(kicad_pcb
	(version 20260206)
	(generator "pcbnew")
	(generator_version "10.0")
	(general
		(thickness 1.6)
		(legacy_teardrops no)
	)
	(paper "A4")
	(layers
		(0 "F.Cu" signal "TOP")
		(4 "In1.Cu" signal "GND")
		(6 "In2.Cu" signal "VCC")
		(8 "In3.Cu" signal "VCC1")
		(10 "In4.Cu" signal "GND1")
		(12 "In5.Cu" signal "IN1")
		(14 "In6.Cu" signal "GND2")
		(16 "In7.Cu" signal "IN2")
		(18 "In8.Cu" signal "GND3")
		(20 "In9.Cu" signal "IN3")
		(22 "In10.Cu" signal "GND4")
		(24 "In11.Cu" signal "IN4")
		(26 "In12.Cu" signal "GND5")
		(28 "In13.Cu" signal "IN5")
		(30 "In14.Cu" signal "GND6")
		(32 "In15.Cu" signal "IN6")
		(34 "In16.Cu" signal "GND7")
		(2 "B.Cu" signal "BOTTOM")
		(9 "F.Adhes" user "F.Adhesive")
		(11 "B.Adhes" user "B.Adhesive")
		(13 "F.Paste" user "Package Geometry/Pastemask Top")
		(15 "B.Paste" user "Package Geometry/Pastemask Bottom")
		(5 "F.SilkS" user "Ref Des/Silkscreen Top")
		(7 "B.SilkS" user "Ref Des/Silkscreen Bottom")
		(1 "F.Mask" user "Board Geometry/Soldermask Top")
		(3 "B.Mask" user "Board Geometry/Soldermask Bottom")
		(17 "Dwgs.User" user "User.Drawings")
		(19 "Cmts.User" user "User.Comments")
		(21 "Eco1.User" user "User.Eco1")
		(23 "Eco2.User" user "User.Eco2")
		(25 "Edge.Cuts" user "Board Geometry/Outline")
		(27 "Margin" user)
		(31 "F.CrtYd" user "Package Geometry/Place Bound Top")
		(29 "B.CrtYd" user "Package Geometry/Place Bound Bottom")
		(35 "F.Fab" user "Ref Des/Assembly Top")
		(33 "B.Fab" user "Ref Des/Assembly Bottom")
	)
	(setup
		(pad_to_mask_clearance 0)
		(allow_soldermask_bridges_in_footprints no)
		(tenting
			(front yes)
			(back yes)
		)
		(covering
			(front no)
			(back no)
		)
		(plugging
			(front no)
			(back no)
		)
		(capping no)
		(filling no)
		(pcbplotparams
			(layerselection 0x00000000_00000000_55555555_5755f5ff)
			(plot_on_all_layers_selection 0x00000000_00000000_00000000_00000000)
			(disableapertmacros no)
			(usegerberextensions no)
			(usegerberattributes yes)
			(usegerberadvancedattributes yes)
			(creategerberjobfile yes)
			(dashed_line_dash_ratio 12)
			(dashed_line_gap_ratio 3)
			(svgprecision 4)
			(plotframeref no)
			(mode 1)
			(useauxorigin no)
			(pdf_front_fp_property_popups yes)
			(pdf_back_fp_property_popups yes)
			(pdf_metadata yes)
			(pdf_single_document no)
			(dxfpolygonmode yes)
			(dxfimperialunits yes)
			(dxfusepcbnewfont yes)
			(psnegative no)
			(psa4output no)
			(plot_black_and_white yes)
			(sketchpadsonfab no)
			(plotpadnumbers no)
			(hidednponfab no)
			(sketchdnponfab yes)
			(crossoutdnponfab yes)
			(subtractmaskfromsilk no)
			(outputformat 1)
			(mirror no)
			(drillshape 1)
			(scaleselection 1)
			(outputdirectory "")
		)
	)
	(gr_poly
		(pts
			(xy 23.88997 -294.221916) (xy 23.89996 -294.221384) (xy 23.918402 -294.21368) (xy 23.925784 -294.20693)
			(xy 24.000206 -294.132762) (xy 24.007548 -294.125946) (xy 24.026012 -294.118205) (xy 24.03602 -294.117776)
			(xy 27.92349 -294.117776) (xy 27.933479 -294.118311) (xy 27.951916 -294.126019) (xy 27.959304 -294.132762)
			(xy 28.033726 -294.20693) (xy 28.041069 -294.213744) (xy 28.059533 -294.221478) (xy 28.06954 -294.221916)
			(xy 36.188904 -294.221916) (xy 36.195923 -294.221726) (xy 36.209451 -294.217986) (xy 36.215574 -294.21455)
			(xy 36.239732 -294.200475) (xy 36.291917 -294.180425) (xy 36.34688 -294.170214) (xy 36.374832 -294.169592)
			(xy 36.40278 -294.170246) (xy 36.457736 -294.180465) (xy 36.509919 -294.200503) (xy 36.53409 -294.21455)
			(xy 36.540203 -294.21801) (xy 36.553738 -294.221747) (xy 36.56076 -294.221916) (xy 37.138864 -294.221916)
			(xy 37.145884 -294.221731) (xy 37.159418 -294.218001) (xy 37.165534 -294.21455) (xy 37.189693 -294.20048)
			(xy 37.241879 -294.18044) (xy 37.296842 -294.17024) (xy 37.324792 -294.169592) (xy 37.352741 -294.170242)
			(xy 37.4077 -294.180455) (xy 37.459888 -294.200487) (xy 37.48405 -294.21455) (xy 37.490162 -294.218015)
			(xy 37.503697 -294.221763) (xy 37.51072 -294.221916) (xy 38.089078 -294.221916) (xy 38.096098 -294.221729)
			(xy 38.10963 -294.217996) (xy 38.115748 -294.21455) (xy 38.139908 -294.200481) (xy 38.192093 -294.180444)
			(xy 38.247056 -294.170246) (xy 38.275006 -294.169592) (xy 38.302955 -294.170243) (xy 38.357913 -294.180459)
			(xy 38.410099 -294.200493) (xy 38.434264 -294.21455) (xy 38.440376 -294.218013) (xy 38.453911 -294.221757)
			(xy 38.460934 -294.221916) (xy 40.938958 -294.221916) (xy 40.945978 -294.221732) (xy 40.959513 -294.218003)
			(xy 40.965628 -294.21455) (xy 40.989787 -294.20048) (xy 41.041973 -294.180439) (xy 41.096935 -294.170237)
			(xy 41.124886 -294.169592) (xy 41.152835 -294.170242) (xy 41.207795 -294.180454) (xy 41.259983 -294.200485)
			(xy 41.284144 -294.21455) (xy 41.290256 -294.218016) (xy 41.30379 -294.221765) (xy 41.310814 -294.221916)
			(xy 41.804336 -294.221916) (xy 41.83761 -294.208962) (xy 41.844468 -294.203374) (xy 41.844722 -294.20312)
			(xy 41.866296 -294.185555) (xy 41.913826 -294.156645) (xy 41.965272 -294.135478) (xy 42.019384 -294.122568)
			(xy 42.074846 -294.11823) (xy 42.130308 -294.122568) (xy 42.18442 -294.135478) (xy 42.235866 -294.156645)
			(xy 42.283396 -294.185555) (xy 42.30497 -294.20312) (xy 42.305224 -294.203374) (xy 42.312082 -294.208962)
			(xy 42.345356 -294.221916) (xy 42.838878 -294.221916) (xy 42.845898 -294.221729) (xy 42.85943 -294.217996)
			(xy 42.865548 -294.21455) (xy 42.889708 -294.200481) (xy 42.941893 -294.180444) (xy 42.996856 -294.170246)
			(xy 43.024806 -294.169592) (xy 43.052755 -294.170243) (xy 43.107713 -294.180459) (xy 43.159899 -294.200493)
			(xy 43.184064 -294.21455) (xy 43.190176 -294.218013) (xy 43.203711 -294.221757) (xy 43.210734 -294.221916)
			(xy 43.788838 -294.221916) (xy 43.795855 -294.221721) (xy 43.809379 -294.217974) (xy 43.815508 -294.21455)
			(xy 43.839667 -294.200478) (xy 43.891852 -294.180434) (xy 43.946815 -294.170228) (xy 43.974766 -294.169592)
			(xy 44.002716 -294.17024) (xy 44.057677 -294.180449) (xy 44.109867 -294.200477) (xy 44.134024 -294.21455)
			(xy 44.140135 -294.218018) (xy 44.15367 -294.221773) (xy 44.160694 -294.221916) (xy 44.739052 -294.221916)
			(xy 44.746069 -294.221719) (xy 44.759591 -294.217969) (xy 44.765722 -294.21455) (xy 44.789881 -294.200479)
			(xy 44.842066 -294.180437) (xy 44.897029 -294.170234) (xy 44.92498 -294.169592) (xy 44.95293 -294.170241)
			(xy 45.00789 -294.180452) (xy 45.060078 -294.200483) (xy 45.084238 -294.21455) (xy 45.090349 -294.218017)
			(xy 45.103884 -294.221767) (xy 45.110908 -294.221916) (xy 45.689012 -294.221916) (xy 45.69603 -294.221725)
			(xy 45.709558 -294.217984) (xy 45.715682 -294.21455) (xy 45.73984 -294.200476) (xy 45.792025 -294.180427)
			(xy 45.846988 -294.170217) (xy 45.87494 -294.169592) (xy 45.902888 -294.170247) (xy 45.957843 -294.180467)
			(xy 46.010025 -294.200506) (xy 46.034198 -294.21455) (xy 46.040311 -294.218009) (xy 46.053846 -294.221743)
			(xy 46.060868 -294.221916) (xy 46.638972 -294.221916) (xy 46.645992 -294.22173) (xy 46.659525 -294.217998)
			(xy 46.665642 -294.21455) (xy 46.689801 -294.200481) (xy 46.741987 -294.180442) (xy 46.79695 -294.170243)
			(xy 46.8249 -294.169592) (xy 46.852849 -294.170243) (xy 46.907807 -294.180457) (xy 46.959994 -294.20049)
			(xy 46.984158 -294.21455) (xy 46.99027 -294.218014) (xy 47.003805 -294.22176) (xy 47.010828 -294.221916)
			(xy 47.588932 -294.221916) (xy 47.59595 -294.221722) (xy 47.609474 -294.217976) (xy 47.615602 -294.21455)
			(xy 47.639761 -294.200478) (xy 47.691946 -294.180432) (xy 47.746909 -294.170226) (xy 47.77486 -294.169592)
			(xy 47.78685 -294.169715) (xy 47.810754 -294.171622) (xy 47.822612 -294.173402) (xy 47.835058 -294.175434)
			(xy 47.857918 -294.167814) (xy 48.251364 -293.774368) (xy 48.258209 -293.76697) (xy 48.265938 -293.748371)
			(xy 48.26635 -293.7383) (xy 48.26635 -290.14039) (xy 48.266776 -290.130322) (xy 48.274499 -290.111725)
			(xy 48.281336 -290.104322) (xy 48.443642 -289.942016) (xy 48.450481 -289.934616) (xy 48.458194 -289.916017)
			(xy 48.458628 -289.905948) (xy 48.458628 -289.881056) (xy 48.455834 -289.869626) (xy 48.45304 -289.864038)
			(xy 48.442478 -289.842372) (xy 48.42755 -289.796545) (xy 48.419989 -289.748945) (xy 48.419512 -289.724846)
			(xy 48.420034 -289.699591) (xy 48.428347 -289.649769) (xy 48.444748 -289.601995) (xy 48.468789 -289.557572)
			(xy 48.499813 -289.517712) (xy 48.536975 -289.483502) (xy 48.579261 -289.455876) (xy 48.625517 -289.435586)
			(xy 48.674482 -289.423186) (xy 48.72482 -289.419015) (xy 48.775158 -289.423186) (xy 48.824123 -289.435586)
			(xy 48.870379 -289.455876) (xy 48.912665 -289.483502) (xy 48.949827 -289.517712) (xy 48.980851 -289.557572)
			(xy 49.004892 -289.601995) (xy 49.021293 -289.649769) (xy 49.029606 -289.699591) (xy 49.030128 -289.724846)
			(xy 49.029457 -289.752996) (xy 49.019098 -289.808337) (xy 49.009554 -289.834828) (xy 49.004982 -289.846766)
			(xy 49.00803 -289.871658) (xy 49.045622 -289.926014) (xy 49.045622 -289.926522) (xy 49.061624 -289.949636)
			(xy 49.064447 -289.953623) (xy 49.071351 -289.960532) (xy 49.07534 -289.963352) (xy 49.077118 -289.964368)
			(xy 49.08348 -289.968341) (xy 49.097816 -289.972721) (xy 49.105312 -289.973004) (xy 49.295304 -289.973004)
			(xy 49.30456 -289.972646) (xy 49.321879 -289.966123) (xy 49.329086 -289.960304) (xy 49.333912 -289.955986)
			(xy 49.353978 -289.926268) (xy 49.384458 -289.881564) (xy 49.390815 -289.871006) (xy 49.393756 -289.846578)
			(xy 49.390046 -289.834828) (xy 49.389792 -289.83432) (xy 49.380372 -289.808066) (xy 49.370148 -289.753239)
			(xy 49.369472 -289.725354) (xy 49.369472 -289.720782) (xy 49.37024 -289.697) (xy 49.378241 -289.650096)
			(xy 49.393422 -289.605002) (xy 49.415416 -289.56281) (xy 49.443691 -289.524541) (xy 49.477561 -289.491123)
			(xy 49.516206 -289.463365) (xy 49.558689 -289.441939) (xy 49.603983 -289.427365) (xy 49.650989 -289.419994)
			(xy 49.67478 -289.419538) (xy 49.698773 -289.419983) (xy 49.746168 -289.427487) (xy 49.791805 -289.442315)
			(xy 49.834561 -289.4641) (xy 49.873382 -289.492306) (xy 49.907311 -289.526238) (xy 49.935514 -289.565061)
			(xy 49.957295 -289.607819) (xy 49.972119 -289.653457) (xy 49.979619 -289.700853) (xy 49.980088 -289.724846)
			(xy 49.979416 -289.752996) (xy 49.969056 -289.808336) (xy 49.959514 -289.834828) (xy 49.954942 -289.846766)
			(xy 49.95799 -289.871658) (xy 49.995582 -289.926014) (xy 49.995582 -289.926522) (xy 50.011584 -289.949636)
			(xy 50.014409 -289.953621) (xy 50.021318 -289.960523) (xy 50.0253 -289.963352) (xy 50.027078 -289.964368)
			(xy 50.033439 -289.968346) (xy 50.047775 -289.972737) (xy 50.055272 -289.973004) (xy 50.245518 -289.973004)
			(xy 50.254773 -289.972643) (xy 50.272088 -289.966117) (xy 50.2793 -289.960304) (xy 50.284126 -289.955986)
			(xy 50.304192 -289.926268) (xy 50.334672 -289.881564) (xy 50.341028 -289.871006) (xy 50.343968 -289.846578)
			(xy 50.34026 -289.834828) (xy 50.340006 -289.83432) (xy 50.330586 -289.808066) (xy 50.320361 -289.753239)
			(xy 50.319686 -289.725354) (xy 50.319686 -289.720782) (xy 50.320454 -289.697) (xy 50.328455 -289.650098)
			(xy 50.343637 -289.605005) (xy 50.365631 -289.562813) (xy 50.393906 -289.524546) (xy 50.427776 -289.491129)
			(xy 50.466421 -289.463372) (xy 50.508904 -289.441948) (xy 50.554198 -289.427376) (xy 50.601204 -289.420007)
			(xy 50.624994 -289.419538) (xy 50.648986 -289.419984) (xy 50.69638 -289.42749) (xy 50.742015 -289.442319)
			(xy 50.784769 -289.464104) (xy 50.823588 -289.492311) (xy 50.857515 -289.526243) (xy 50.885717 -289.565065)
			(xy 50.907497 -289.607822) (xy 50.922319 -289.653459) (xy 50.929819 -289.700854) (xy 50.930302 -289.724846)
			(xy 50.92963 -289.752996) (xy 50.919271 -289.808336) (xy 50.909728 -289.834828) (xy 50.905156 -289.846766)
			(xy 50.908204 -289.871658) (xy 50.945796 -289.926014) (xy 50.945796 -289.926522) (xy 50.961798 -289.949636)
			(xy 50.96462 -289.953624) (xy 50.971522 -289.960536) (xy 50.975514 -289.963352) (xy 50.977292 -289.964368)
			(xy 50.983653 -289.968344) (xy 50.997989 -289.972731) (xy 51.005486 -289.973004) (xy 51.195478 -289.973004)
			(xy 51.204735 -289.97265) (xy 51.22206 -289.966134) (xy 51.22926 -289.960304) (xy 51.234086 -289.955986)
			(xy 51.254152 -289.926268) (xy 51.284632 -289.881564) (xy 51.290992 -289.871007) (xy 51.293934 -289.846577)
			(xy 51.29022 -289.834828) (xy 51.289966 -289.83432) (xy 51.280547 -289.808066) (xy 51.270323 -289.753239)
			(xy 51.269646 -289.725354) (xy 51.269646 -289.720782) (xy 51.270414 -289.696999) (xy 51.278415 -289.650094)
			(xy 51.293596 -289.604998) (xy 51.315589 -289.562804) (xy 51.343864 -289.524533) (xy 51.377733 -289.491113)
			(xy 51.416377 -289.463352) (xy 51.458861 -289.441923) (xy 51.504155 -289.427345) (xy 51.551163 -289.41997)
			(xy 51.574954 -289.419538) (xy 51.598948 -289.419981) (xy 51.646347 -289.427482) (xy 51.691987 -289.442307)
			(xy 51.734747 -289.464091) (xy 51.773571 -289.492296) (xy 51.807504 -289.526229) (xy 51.835709 -289.565053)
			(xy 51.857493 -289.607813) (xy 51.872318 -289.653453) (xy 51.879819 -289.700852) (xy 51.880262 -289.724846)
			(xy 51.879591 -289.752996) (xy 51.869234 -289.808337) (xy 51.859688 -289.834828) (xy 51.855116 -289.846766)
			(xy 51.858164 -289.871658) (xy 51.895756 -289.926014) (xy 51.895756 -289.926522) (xy 51.911758 -289.949636)
			(xy 51.914582 -289.953622) (xy 51.921489 -289.960527) (xy 51.925474 -289.963352) (xy 51.927252 -289.964368)
			(xy 51.933612 -289.968349) (xy 51.947948 -289.972748) (xy 51.955446 -289.973004) (xy 52.145438 -289.973004)
			(xy 52.154698 -289.972657) (xy 52.172033 -289.966152) (xy 52.17922 -289.960304) (xy 52.184046 -289.955986)
			(xy 52.204112 -289.926268) (xy 52.234592 -289.881564) (xy 52.240946 -289.871006) (xy 52.243884 -289.846579)
			(xy 52.24018 -289.834828) (xy 52.239926 -289.83432) (xy 52.230505 -289.808066) (xy 52.22028 -289.753239)
			(xy 52.219606 -289.725354) (xy 52.219606 -289.720782) (xy 52.220374 -289.696998) (xy 52.228374 -289.650091)
			(xy 52.243555 -289.604992) (xy 52.265548 -289.562795) (xy 52.293821 -289.524521) (xy 52.32769 -289.491097)
			(xy 52.366334 -289.463331) (xy 52.408818 -289.441897) (xy 52.454113 -289.427314) (xy 52.501122 -289.419933)
			(xy 52.524914 -289.419538) (xy 52.548905 -289.419985) (xy 52.596296 -289.427494) (xy 52.641929 -289.442324)
			(xy 52.68468 -289.464111) (xy 52.723496 -289.492318) (xy 52.757421 -289.52625) (xy 52.78562 -289.565071)
			(xy 52.807399 -289.607826) (xy 52.82222 -289.653462) (xy 52.829719 -289.700855) (xy 52.830222 -289.724846)
			(xy 52.82955 -289.752996) (xy 52.819192 -289.808336) (xy 52.809648 -289.834828) (xy 52.805076 -289.846766)
			(xy 52.808124 -289.871658) (xy 52.845716 -289.926014) (xy 52.845716 -289.926522) (xy 52.861718 -289.949636)
			(xy 52.86454 -289.953623) (xy 52.871444 -289.960533) (xy 52.875434 -289.963352) (xy 52.877212 -289.964368)
			(xy 52.883574 -289.968341) (xy 52.89791 -289.972723) (xy 52.905406 -289.973004) (xy 53.095398 -289.973004)
			(xy 53.104654 -289.972647) (xy 53.121974 -289.966126) (xy 53.12918 -289.960304) (xy 53.134006 -289.955986)
			(xy 53.154072 -289.926268) (xy 53.184552 -289.881564) (xy 53.19091 -289.871007) (xy 53.193851 -289.846578)
			(xy 53.19014 -289.834828) (xy 53.189886 -289.83432) (xy 53.180466 -289.808066) (xy 53.170242 -289.753239)
			(xy 53.169566 -289.725354) (xy 53.169566 -289.720782) (xy 53.170334 -289.696999) (xy 53.178335 -289.650096)
			(xy 53.193516 -289.605001) (xy 53.21551 -289.562809) (xy 53.243785 -289.52454) (xy 53.277654 -289.491121)
			(xy 53.316299 -289.463362) (xy 53.358783 -289.441935) (xy 53.404077 -289.42736) (xy 53.451083 -289.419989)
			(xy 53.474874 -289.419538) (xy 53.498867 -289.419982) (xy 53.546263 -289.427486) (xy 53.591901 -289.442313)
			(xy 53.634658 -289.464098) (xy 53.673479 -289.492304) (xy 53.707409 -289.526236) (xy 53.735613 -289.565059)
			(xy 53.757395 -289.607817) (xy 53.772219 -289.653456) (xy 53.779719 -289.700853) (xy 53.780182 -289.724846)
			(xy 53.77951 -289.752996) (xy 53.76915 -289.808336) (xy 53.759608 -289.834828) (xy 53.755036 -289.846766)
			(xy 53.758084 -289.871658) (xy 53.795676 -289.926014) (xy 53.795676 -289.926522) (xy 53.811678 -289.949636)
			(xy 53.814503 -289.953621) (xy 53.821411 -289.960524) (xy 53.825394 -289.963352) (xy 53.827172 -289.964368)
			(xy 53.833532 -289.968347) (xy 53.847869 -289.97274) (xy 53.855366 -289.973004) (xy 54.045358 -289.973004)
			(xy 54.054617 -289.972654) (xy 54.071947 -289.966143) (xy 54.07914 -289.960304) (xy 54.083966 -289.955986)
			(xy 54.104032 -289.926268) (xy 54.134512 -289.881564) (xy 54.140874 -289.871008) (xy 54.143817 -289.846577)
			(xy 54.1401 -289.834828) (xy 54.139846 -289.83432) (xy 54.130424 -289.808066) (xy 54.120198 -289.753239)
			(xy 54.119526 -289.725354) (xy 54.119526 -289.720782) (xy 54.120294 -289.696998) (xy 54.128294 -289.650092)
			(xy 54.143475 -289.604995) (xy 54.165469 -289.5628) (xy 54.193742 -289.524527) (xy 54.227612 -289.491105)
			(xy 54.266256 -289.463341) (xy 54.30874 -289.44191) (xy 54.354034 -289.427329) (xy 54.401042 -289.419952)
			(xy 54.424834 -289.419538) (xy 54.448824 -289.419987) (xy 54.496213 -289.427498) (xy 54.541843 -289.44233)
			(xy 54.584591 -289.464118) (xy 54.623404 -289.492325) (xy 54.657327 -289.526257) (xy 54.685524 -289.565077)
			(xy 54.7073 -289.607831) (xy 54.722121 -289.653465) (xy 54.72962 -289.700856) (xy 54.730142 -289.724846)
			(xy 54.729471 -289.752996) (xy 54.719113 -289.808337) (xy 54.709568 -289.834828) (xy 54.704996 -289.846766)
			(xy 54.708044 -289.871658) (xy 54.745636 -289.926014) (xy 54.745636 -289.926522) (xy 54.761638 -289.949636)
			(xy 54.764461 -289.953623) (xy 54.771367 -289.96053) (xy 54.775354 -289.963352) (xy 54.777132 -289.964368)
			(xy 54.783491 -289.968352) (xy 54.797827 -289.972756) (xy 54.805326 -289.973004) (xy 54.995318 -289.973004)
			(xy 55.004573 -289.972643) (xy 55.021888 -289.966117) (xy 55.0291 -289.960304) (xy 55.033926 -289.955986)
			(xy 55.053992 -289.926268) (xy 55.084472 -289.881564) (xy 55.090828 -289.871006) (xy 55.093768 -289.846578)
			(xy 55.09006 -289.834828) (xy 55.089806 -289.83432) (xy 55.080386 -289.808066) (xy 55.070161 -289.753239)
			(xy 55.069486 -289.725354) (xy 55.069486 -289.720782) (xy 55.070254 -289.697) (xy 55.078255 -289.650098)
			(xy 55.093437 -289.605005) (xy 55.115431 -289.562813) (xy 55.143706 -289.524546) (xy 55.177576 -289.491129)
			(xy 55.216221 -289.463372) (xy 55.258704 -289.441948) (xy 55.303998 -289.427376) (xy 55.351004 -289.420007)
			(xy 55.374794 -289.419538) (xy 55.398786 -289.419984) (xy 55.44618 -289.42749) (xy 55.491815 -289.442319)
			(xy 55.534569 -289.464104) (xy 55.573388 -289.492311) (xy 55.607315 -289.526243) (xy 55.635517 -289.565065)
			(xy 55.657297 -289.607822) (xy 55.672119 -289.653459) (xy 55.679619 -289.700854) (xy 55.680102 -289.724846)
			(xy 55.67943 -289.752996) (xy 55.669071 -289.808336) (xy 55.659528 -289.834828) (xy 55.654956 -289.846766)
			(xy 55.658004 -289.871658) (xy 55.695596 -289.926014) (xy 55.695596 -289.926522) (xy 55.711598 -289.949636)
			(xy 55.71442 -289.953624) (xy 55.721322 -289.960536) (xy 55.725314 -289.963352) (xy 55.727092 -289.964368)
			(xy 55.733453 -289.968344) (xy 55.747789 -289.972731) (xy 55.755286 -289.973004) (xy 55.945278 -289.973004)
			(xy 55.954535 -289.97265) (xy 55.97186 -289.966134) (xy 55.97906 -289.960304) (xy 55.983886 -289.955986)
			(xy 56.003952 -289.926268) (xy 56.034432 -289.881564) (xy 56.040792 -289.871007) (xy 56.043734 -289.846577)
			(xy 56.04002 -289.834828) (xy 56.039766 -289.83432) (xy 56.030347 -289.808066) (xy 56.020123 -289.753239)
			(xy 56.019446 -289.725354) (xy 56.019446 -289.720782) (xy 56.020214 -289.696999) (xy 56.028215 -289.650094)
			(xy 56.043396 -289.604998) (xy 56.065389 -289.562804) (xy 56.093664 -289.524533) (xy 56.127533 -289.491113)
			(xy 56.166177 -289.463352) (xy 56.208661 -289.441923) (xy 56.253955 -289.427345) (xy 56.300963 -289.41997)
			(xy 56.324754 -289.419538) (xy 56.348748 -289.419981) (xy 56.396147 -289.427482) (xy 56.441787 -289.442307)
			(xy 56.484547 -289.464091) (xy 56.523371 -289.492296) (xy 56.557304 -289.526229) (xy 56.585509 -289.565053)
			(xy 56.607293 -289.607813) (xy 56.622118 -289.653453) (xy 56.629619 -289.700852) (xy 56.630062 -289.724846)
			(xy 56.629391 -289.752996) (xy 56.619034 -289.808337) (xy 56.609488 -289.834828) (xy 56.604916 -289.846766)
			(xy 56.607964 -289.871658) (xy 56.645556 -289.926014) (xy 56.645556 -289.926522) (xy 56.661558 -289.949636)
			(xy 56.664382 -289.953622) (xy 56.671289 -289.960527) (xy 56.675274 -289.963352) (xy 56.677052 -289.964368)
			(xy 56.683412 -289.968349) (xy 56.697748 -289.972748) (xy 56.705246 -289.973004) (xy 56.895492 -289.973004)
			(xy 56.904748 -289.972648) (xy 56.92207 -289.966128) (xy 56.929274 -289.960304) (xy 56.9341 -289.955986)
			(xy 56.954166 -289.926268) (xy 56.984646 -289.881564) (xy 56.991005 -289.871007) (xy 56.993946 -289.846578)
			(xy 56.990234 -289.834828) (xy 56.98998 -289.83432) (xy 56.98056 -289.808066) (xy 56.970336 -289.753239)
			(xy 56.96966 -289.725354) (xy 56.96966 -289.720782) (xy 56.970428 -289.696999) (xy 56.978429 -289.650095)
			(xy 56.99361 -289.605001) (xy 57.015604 -289.562807) (xy 57.043878 -289.524538) (xy 57.077748 -289.491118)
			(xy 57.116393 -289.463359) (xy 57.158876 -289.441932) (xy 57.20417 -289.427355) (xy 57.251177 -289.419983)
			(xy 57.274968 -289.419538) (xy 57.298961 -289.419982) (xy 57.346358 -289.427485) (xy 57.391997 -289.442311)
			(xy 57.434754 -289.464096) (xy 57.473577 -289.492301) (xy 57.507508 -289.526234) (xy 57.535712 -289.565058)
			(xy 57.557494 -289.607816) (xy 57.572318 -289.653456) (xy 57.579819 -289.700853) (xy 57.580276 -289.724846)
			(xy 57.579604 -289.752996) (xy 57.569244 -289.808336) (xy 57.559702 -289.834828) (xy 57.55513 -289.846766)
			(xy 57.558178 -289.871658) (xy 57.59577 -289.926014) (xy 57.59577 -289.926522) (xy 57.611772 -289.949636)
			(xy 57.614596 -289.953621) (xy 57.621505 -289.960525) (xy 57.625488 -289.963352) (xy 57.627266 -289.964368)
			(xy 57.633626 -289.968347) (xy 57.647962 -289.972742) (xy 57.65546 -289.973004) (xy 57.845452 -289.973004)
			(xy 57.854711 -289.972655) (xy 57.872042 -289.966146) (xy 57.879234 -289.960304) (xy 57.88406 -289.955986)
			(xy 57.904126 -289.926268) (xy 57.934606 -289.881564) (xy 57.940968 -289.871008) (xy 57.943912 -289.846577)
			(xy 57.940194 -289.834828) (xy 57.93994 -289.83432) (xy 57.930519 -289.808066) (xy 57.920293 -289.753239)
			(xy 57.91962 -289.725354) (xy 57.91962 -289.720782) (xy 57.920388 -289.696998) (xy 57.928388 -289.650092)
			(xy 57.943569 -289.604994) (xy 57.965563 -289.562798) (xy 57.993836 -289.524525) (xy 58.027705 -289.491102)
			(xy 58.066349 -289.463338) (xy 58.108833 -289.441906) (xy 58.154128 -289.427324) (xy 58.201136 -289.419946)
			(xy 58.224928 -289.419538) (xy 58.248918 -289.419986) (xy 58.296308 -289.427497) (xy 58.341939 -289.442328)
			(xy 58.384688 -289.464116) (xy 58.423502 -289.492323) (xy 58.457425 -289.526255) (xy 58.485623 -289.565076)
			(xy 58.5074 -289.60783) (xy 58.52222 -289.653464) (xy 58.529719 -289.700855) (xy 58.530236 -289.724846)
			(xy 58.529565 -289.752996) (xy 58.519207 -289.808337) (xy 58.509662 -289.834828) (xy 58.50509 -289.846766)
			(xy 58.508138 -289.871658) (xy 58.54573 -289.926014) (xy 58.54573 -289.926522) (xy 58.561732 -289.949636)
			(xy 58.564555 -289.953623) (xy 58.57146 -289.960531) (xy 58.575448 -289.963352) (xy 58.577226 -289.964368)
			(xy 58.583585 -289.968352) (xy 58.597921 -289.972759) (xy 58.60542 -289.973004) (xy 59.745372 -289.973004)
			(xy 59.75463 -289.972651) (xy 59.771956 -289.966137) (xy 59.779154 -289.960304) (xy 59.78398 -289.955986)
			(xy 59.804046 -289.926268) (xy 59.834526 -289.881564) (xy 59.840887 -289.871007) (xy 59.843829 -289.846577)
			(xy 59.840114 -289.834828) (xy 59.83986 -289.83432) (xy 59.830441 -289.808066) (xy 59.820218 -289.753239)
			(xy 59.81954 -289.725354) (xy 59.81954 -289.720782) (xy 59.820308 -289.696999) (xy 59.828309 -289.650093)
			(xy 59.84349 -289.604998) (xy 59.865483 -289.562803) (xy 59.893757 -289.524532) (xy 59.927627 -289.49111)
			(xy 59.966271 -289.463349) (xy 60.008755 -289.441919) (xy 60.054049 -289.42734) (xy 60.101057 -289.419965)
			(xy 60.124848 -289.419538) (xy 60.148835 -289.420012) (xy 60.196219 -289.427525) (xy 60.241843 -289.442357)
			(xy 60.284586 -289.464144) (xy 60.323394 -289.492349) (xy 60.357312 -289.526277) (xy 60.385506 -289.565094)
			(xy 60.407279 -289.607844) (xy 60.422097 -289.653473) (xy 60.429595 -289.700858) (xy 60.430156 -289.724846)
			(xy 60.429485 -289.752996) (xy 60.419127 -289.808337) (xy 60.409582 -289.834828) (xy 60.40501 -289.846766)
			(xy 60.408058 -289.871658) (xy 60.44565 -289.926014) (xy 60.44565 -289.926522) (xy 60.461652 -289.949636)
			(xy 60.464476 -289.953622) (xy 60.471382 -289.960528) (xy 60.475368 -289.963352) (xy 60.477146 -289.964368)
			(xy 60.483506 -289.96835) (xy 60.497842 -289.97275) (xy 60.50534 -289.973004) (xy 60.695332 -289.973004)
			(xy 60.704593 -289.972658) (xy 60.721928 -289.966154) (xy 60.729114 -289.960304) (xy 60.73394 -289.955986)
			(xy 60.754006 -289.926268) (xy 60.784486 -289.881564) (xy 60.790841 -289.871006) (xy 60.793779 -289.846578)
			(xy 60.790074 -289.834828) (xy 60.78982 -289.83432) (xy 60.780399 -289.808066) (xy 60.770174 -289.753239)
			(xy 60.7695 -289.725354) (xy 60.7695 -289.720782) (xy 60.770268 -289.696998) (xy 60.778268 -289.65009)
			(xy 60.793449 -289.604991) (xy 60.815442 -289.562794) (xy 60.843715 -289.524519) (xy 60.877584 -289.491094)
			(xy 60.916228 -289.463328) (xy 60.958712 -289.441893) (xy 61.004007 -289.427309) (xy 61.051016 -289.419928)
			(xy 61.074808 -289.419538) (xy 61.098799 -289.419985) (xy 61.146191 -289.427493) (xy 61.191825 -289.442323)
			(xy 61.234577 -289.464109) (xy 61.273393 -289.492316) (xy 61.307319 -289.526248) (xy 61.335519 -289.56507)
			(xy 61.357298 -289.607825) (xy 61.37212 -289.653461) (xy 61.379619 -289.700854) (xy 61.380116 -289.724846)
			(xy 61.379444 -289.752996) (xy 61.369086 -289.808336) (xy 61.359542 -289.834828) (xy 61.35497 -289.846766)
			(xy 61.358018 -289.871658) (xy 61.39561 -289.926014) (xy 61.39561 -289.926522) (xy 61.411612 -289.949636)
			(xy 61.414434 -289.953624) (xy 61.421338 -289.960534) (xy 61.425328 -289.963352) (xy 61.427106 -289.964368)
			(xy 61.433467 -289.968342) (xy 61.447804 -289.972726) (xy 61.4553 -289.973004) (xy 61.645292 -289.973004)
			(xy 61.654548 -289.972648) (xy 61.67187 -289.966128) (xy 61.679074 -289.960304) (xy 61.6839 -289.955986)
			(xy 61.703966 -289.926268) (xy 61.734446 -289.881564) (xy 61.740805 -289.871007) (xy 61.743746 -289.846578)
			(xy 61.740034 -289.834828) (xy 61.73978 -289.83432) (xy 61.73036 -289.808066) (xy 61.720136 -289.753239)
			(xy 61.71946 -289.725354) (xy 61.71946 -289.720782) (xy 61.720228 -289.696999) (xy 61.728229 -289.650095)
			(xy 61.74341 -289.605001) (xy 61.765404 -289.562807) (xy 61.793678 -289.524538) (xy 61.827548 -289.491118)
			(xy 61.866193 -289.463359) (xy 61.908676 -289.441932) (xy 61.95397 -289.427355) (xy 62.000977 -289.419983)
			(xy 62.024768 -289.419538) (xy 62.048761 -289.419982) (xy 62.096158 -289.427485) (xy 62.141797 -289.442311)
			(xy 62.184554 -289.464096) (xy 62.223377 -289.492301) (xy 62.257308 -289.526234) (xy 62.285512 -289.565058)
			(xy 62.307294 -289.607816) (xy 62.322118 -289.653456) (xy 62.329619 -289.700853) (xy 62.330076 -289.724846)
			(xy 62.329404 -289.752996) (xy 62.319044 -289.808336) (xy 62.309502 -289.834828) (xy 62.30493 -289.846766)
			(xy 62.307978 -289.871658) (xy 62.34557 -289.926014) (xy 62.34557 -289.926522) (xy 62.361572 -289.949636)
			(xy 62.364396 -289.953621) (xy 62.371305 -289.960525) (xy 62.375288 -289.963352) (xy 62.377066 -289.964368)
			(xy 62.383426 -289.968347) (xy 62.397762 -289.972742) (xy 62.40526 -289.973004) (xy 62.595506 -289.973004)
			(xy 62.604761 -289.972645) (xy 62.62208 -289.966122) (xy 62.629288 -289.960304) (xy 62.634114 -289.955986)
			(xy 62.65418 -289.926268) (xy 62.68466 -289.881564) (xy 62.691017 -289.871006) (xy 62.693957 -289.846578)
			(xy 62.690248 -289.834828) (xy 62.689994 -289.83432) (xy 62.680574 -289.808066) (xy 62.67035 -289.753239)
			(xy 62.669674 -289.725354) (xy 62.669674 -289.720782) (xy 62.670442 -289.697) (xy 62.678443 -289.650096)
			(xy 62.693624 -289.605003) (xy 62.715619 -289.562811) (xy 62.743893 -289.524542) (xy 62.777763 -289.491124)
			(xy 62.816408 -289.463366) (xy 62.858891 -289.441941) (xy 62.904185 -289.427366) (xy 62.951192 -289.419996)
			(xy 62.974982 -289.419538) (xy 62.998975 -289.419983) (xy 63.04637 -289.427488) (xy 63.092007 -289.442315)
			(xy 63.134762 -289.4641) (xy 63.173582 -289.492306) (xy 63.207512 -289.526239) (xy 63.235714 -289.565062)
			(xy 63.257496 -289.607819) (xy 63.272319 -289.653458) (xy 63.279819 -289.700853) (xy 63.28029 -289.724846)
			(xy 63.279618 -289.752996) (xy 63.269258 -289.808336) (xy 63.259716 -289.834828) (xy 63.255144 -289.846766)
			(xy 63.258192 -289.871658) (xy 63.295784 -289.926014) (xy 63.295784 -289.926522) (xy 63.311786 -289.949636)
			(xy 63.314611 -289.95362) (xy 63.32152 -289.960523) (xy 63.325502 -289.963352) (xy 63.32728 -289.964368)
			(xy 63.333641 -289.968346) (xy 63.347977 -289.972736) (xy 63.355474 -289.973004) (xy 63.545466 -289.973004)
			(xy 63.554724 -289.972652) (xy 63.572052 -289.96614) (xy 63.579248 -289.960304) (xy 63.584074 -289.955986)
			(xy 63.60414 -289.926268) (xy 63.63462 -289.881564) (xy 63.640981 -289.871008) (xy 63.643924 -289.846577)
			(xy 63.640208 -289.834828) (xy 63.639954 -289.83432) (xy 63.630532 -289.808066) (xy 63.620306 -289.753239)
			(xy 63.619634 -289.725354) (xy 63.619634 -289.720782) (xy 63.620402 -289.696999) (xy 63.628403 -289.650093)
			(xy 63.643583 -289.604997) (xy 63.665577 -289.562802) (xy 63.693851 -289.52453) (xy 63.72772 -289.491108)
			(xy 63.766365 -289.463346) (xy 63.808848 -289.441915) (xy 63.854143 -289.427335) (xy 63.90115 -289.419959)
			(xy 63.924942 -289.419538) (xy 63.948932 -289.419987) (xy 63.996319 -289.4275) (xy 64.041949 -289.442332)
			(xy 64.084695 -289.464121) (xy 64.123508 -289.492328) (xy 64.157429 -289.526259) (xy 64.185625 -289.56508)
			(xy 64.207401 -289.607833) (xy 64.222221 -289.653466) (xy 64.22972 -289.700856) (xy 64.23025 -289.724846)
			(xy 64.229579 -289.752996) (xy 64.219221 -289.808337) (xy 64.209676 -289.834828) (xy 64.205104 -289.846766)
			(xy 64.208152 -289.871658) (xy 64.245744 -289.926014) (xy 64.245744 -289.926522) (xy 64.261746 -289.949636)
			(xy 64.264569 -289.953622) (xy 64.271476 -289.960529) (xy 64.275462 -289.963352) (xy 64.27724 -289.964368)
			(xy 64.283599 -289.968351) (xy 64.297935 -289.972753) (xy 64.305434 -289.973004) (xy 64.495426 -289.973004)
			(xy 64.50468 -289.972642) (xy 64.521994 -289.966114) (xy 64.529208 -289.960304) (xy 64.534034 -289.955986)
			(xy 64.5541 -289.926268) (xy 64.58458 -289.881564) (xy 64.590935 -289.871006) (xy 64.593874 -289.846578)
			(xy 64.590168 -289.834828) (xy 64.589914 -289.83432) (xy 64.580493 -289.808066) (xy 64.570268 -289.753239)
			(xy 64.569594 -289.725354) (xy 64.569594 -289.720782) (xy 64.570362 -289.696997) (xy 64.578362 -289.650089)
			(xy 64.593543 -289.60499) (xy 64.615536 -289.562793) (xy 64.643809 -289.524517) (xy 64.677677 -289.491092)
			(xy 64.716321 -289.463325) (xy 64.758805 -289.441889) (xy 64.8041 -289.427304) (xy 64.851109 -289.419922)
			(xy 64.874902 -289.419538) (xy 64.898894 -289.419984) (xy 64.946286 -289.427492) (xy 64.991921 -289.442321)
			(xy 65.034673 -289.464107) (xy 65.073491 -289.492314) (xy 65.107418 -289.526246) (xy 65.135618 -289.565068)
			(xy 65.157397 -289.607824) (xy 65.17222 -289.65346) (xy 65.179719 -289.700854) (xy 65.18021 -289.724846)
			(xy 65.179538 -289.752996) (xy 65.16918 -289.808336) (xy 65.159636 -289.834828) (xy 65.155064 -289.846766)
			(xy 65.158112 -289.871658) (xy 65.195704 -289.926014) (xy 65.195704 -289.926522) (xy 65.211706 -289.949636)
			(xy 65.214528 -289.953624) (xy 65.221431 -289.960535) (xy 65.225422 -289.963352) (xy 65.2272 -289.964368)
			(xy 65.233561 -289.968343) (xy 65.247898 -289.972728) (xy 65.255394 -289.973004) (xy 65.445386 -289.973004)
			(xy 65.454643 -289.972649) (xy 65.471966 -289.966131) (xy 65.479168 -289.960304) (xy 65.483994 -289.955986)
			(xy 65.50406 -289.926268) (xy 65.53454 -289.881564) (xy 65.540899 -289.871007) (xy 65.543841 -289.846577)
			(xy 65.540128 -289.834828) (xy 65.539874 -289.83432) (xy 65.530454 -289.808066) (xy 65.520231 -289.753239)
			(xy 65.519554 -289.725354) (xy 65.519554 -289.720782) (xy 65.520322 -289.696999) (xy 65.528323 -289.650095)
			(xy 65.543504 -289.605) (xy 65.565498 -289.562806) (xy 65.593772 -289.524536) (xy 65.627642 -289.491116)
			(xy 65.666286 -289.463356) (xy 65.70877 -289.441928) (xy 65.754064 -289.427351) (xy 65.801071 -289.419978)
			(xy 65.824862 -289.419538) (xy 65.848856 -289.419981) (xy 65.896253 -289.427484) (xy 65.941893 -289.442309)
			(xy 65.984651 -289.464094) (xy 66.023474 -289.492299) (xy 66.057406 -289.526232) (xy 66.085611 -289.565056)
			(xy 66.107394 -289.607814) (xy 66.122218 -289.653455) (xy 66.129719 -289.700852) (xy 66.13017 -289.724846)
			(xy 66.129499 -289.752996) (xy 66.119142 -289.808337) (xy 66.109596 -289.834828) (xy 66.105024 -289.846766)
			(xy 66.108072 -289.871658) (xy 66.145664 -289.926014) (xy 66.145664 -289.926522) (xy 66.161666 -289.949636)
			(xy 66.16449 -289.953621) (xy 66.171398 -289.960526) (xy 66.175382 -289.963352) (xy 66.17716 -289.964368)
			(xy 66.18352 -289.968348) (xy 66.197856 -289.972745) (xy 66.205354 -289.973004) (xy 66.395346 -289.973004)
			(xy 66.404606 -289.972656) (xy 66.421938 -289.966148) (xy 66.429128 -289.960304) (xy 66.433954 -289.955986)
			(xy 66.45402 -289.926268) (xy 66.4845 -289.881564) (xy 66.490853 -289.871005) (xy 66.493791 -289.846579)
			(xy 66.490088 -289.834828) (xy 66.489834 -289.83432) (xy 66.480413 -289.808066) (xy 66.470187 -289.753239)
			(xy 66.469514 -289.725354) (xy 66.469514 -289.720782) (xy 66.470282 -289.696998) (xy 66.478282 -289.650091)
			(xy 66.493463 -289.604994) (xy 66.515456 -289.562797) (xy 66.54373 -289.524524) (xy 66.577599 -289.4911)
			(xy 66.616243 -289.463335) (xy 66.658727 -289.441902) (xy 66.704021 -289.42732) (xy 66.75103 -289.419941)
			(xy 66.774822 -289.419538) (xy 66.798813 -289.419986) (xy 66.846203 -289.427496) (xy 66.891835 -289.442327)
			(xy 66.934584 -289.464114) (xy 66.973399 -289.492321) (xy 67.007323 -289.526253) (xy 67.035522 -289.565074)
			(xy 67.057299 -289.607828) (xy 67.07212 -289.653463) (xy 67.079619 -289.700855) (xy 67.08013 -289.724846)
			(xy 67.079459 -289.752996) (xy 67.0691 -289.808337) (xy 67.059556 -289.834828) (xy 67.054984 -289.846766)
			(xy 67.058032 -289.871658) (xy 67.095624 -289.926014) (xy 67.095624 -289.926522) (xy 67.111626 -289.949636)
			(xy 67.114449 -289.953623) (xy 67.121353 -289.960532) (xy 67.125342 -289.963352) (xy 67.12712 -289.964368)
			(xy 67.133479 -289.968353) (xy 67.147815 -289.972761) (xy 67.155314 -289.973004) (xy 67.345306 -289.973004)
			(xy 67.354561 -289.972645) (xy 67.37188 -289.966122) (xy 67.379088 -289.960304) (xy 67.383914 -289.955986)
			(xy 67.40398 -289.926268) (xy 67.43446 -289.881564) (xy 67.440817 -289.871006) (xy 67.443757 -289.846578)
			(xy 67.440048 -289.834828) (xy 67.439794 -289.83432) (xy 67.430374 -289.808066) (xy 67.42015 -289.753239)
			(xy 67.419474 -289.725354) (xy 67.419474 -289.720782) (xy 67.420242 -289.697) (xy 67.428243 -289.650096)
			(xy 67.443424 -289.605003) (xy 67.465419 -289.562811) (xy 67.493693 -289.524542) (xy 67.527563 -289.491124)
			(xy 67.566208 -289.463366) (xy 67.608691 -289.441941) (xy 67.653985 -289.427366) (xy 67.700992 -289.419996)
			(xy 67.724782 -289.419538) (xy 67.748775 -289.419983) (xy 67.79617 -289.427488) (xy 67.841807 -289.442315)
			(xy 67.884562 -289.4641) (xy 67.923382 -289.492306) (xy 67.957312 -289.526239) (xy 67.985514 -289.565062)
			(xy 68.007296 -289.607819) (xy 68.022119 -289.653458) (xy 68.029619 -289.700853) (xy 68.03009 -289.724846)
			(xy 68.029418 -289.752996) (xy 68.019058 -289.808336) (xy 68.009516 -289.834828) (xy 68.004944 -289.846766)
			(xy 68.007992 -289.871658) (xy 68.045584 -289.926014) (xy 68.045584 -289.926522) (xy 68.061586 -289.949636)
			(xy 68.064411 -289.95362) (xy 68.07132 -289.960523) (xy 68.075302 -289.963352) (xy 68.07708 -289.964368)
			(xy 68.083441 -289.968346) (xy 68.097777 -289.972736) (xy 68.105274 -289.973004) (xy 68.295266 -289.973004)
			(xy 68.304524 -289.972652) (xy 68.321852 -289.96614) (xy 68.329048 -289.960304) (xy 68.333874 -289.955986)
			(xy 68.35394 -289.926268) (xy 68.38442 -289.881564) (xy 68.390781 -289.871008) (xy 68.393724 -289.846577)
			(xy 68.390008 -289.834828) (xy 68.389754 -289.83432) (xy 68.380332 -289.808066) (xy 68.370106 -289.753239)
			(xy 68.369434 -289.725354) (xy 68.369434 -289.720782) (xy 68.370202 -289.696999) (xy 68.378203 -289.650093)
			(xy 68.393383 -289.604997) (xy 68.415377 -289.562802) (xy 68.443651 -289.52453) (xy 68.47752 -289.491108)
			(xy 68.516165 -289.463346) (xy 68.558648 -289.441915) (xy 68.603943 -289.427335) (xy 68.65095 -289.419959)
			(xy 68.674742 -289.419538) (xy 68.698732 -289.419987) (xy 68.746119 -289.4275) (xy 68.791749 -289.442332)
			(xy 68.834495 -289.464121) (xy 68.873308 -289.492328) (xy 68.907229 -289.526259) (xy 68.935425 -289.56508)
			(xy 68.957201 -289.607833) (xy 68.972021 -289.653466) (xy 68.97952 -289.700856) (xy 68.98005 -289.724846)
			(xy 68.979379 -289.752996) (xy 68.969021 -289.808337) (xy 68.959476 -289.834828) (xy 68.954904 -289.846766)
			(xy 68.957952 -289.871658) (xy 68.995544 -289.926014) (xy 68.995544 -289.926522) (xy 69.011546 -289.949636)
			(xy 69.014369 -289.953622) (xy 69.021276 -289.960529) (xy 69.025262 -289.963352) (xy 69.02704 -289.964368)
			(xy 69.033399 -289.968351) (xy 69.047735 -289.972753) (xy 69.055234 -289.973004) (xy 69.24548 -289.973004)
			(xy 69.254737 -289.97265) (xy 69.272062 -289.966134) (xy 69.279262 -289.960304) (xy 69.284088 -289.955986)
			(xy 69.304154 -289.926268) (xy 69.334634 -289.881564) (xy 69.340994 -289.871007) (xy 69.343936 -289.846577)
			(xy 69.340222 -289.834828) (xy 69.339968 -289.83432) (xy 69.330549 -289.808066) (xy 69.320325 -289.753239)
			(xy 69.319648 -289.725354) (xy 69.319648 -289.720782) (xy 69.320416 -289.696999) (xy 69.328417 -289.650094)
			(xy 69.343598 -289.604999) (xy 69.365592 -289.562805) (xy 69.393866 -289.524534) (xy 69.427735 -289.491114)
			(xy 69.46638 -289.463353) (xy 69.508863 -289.441924) (xy 69.554157 -289.427346) (xy 69.601165 -289.419972)
			(xy 69.624956 -289.419538) (xy 69.64895 -289.419981) (xy 69.696348 -289.427482) (xy 69.741989 -289.442308)
			(xy 69.784748 -289.464091) (xy 69.823572 -289.492297) (xy 69.857504 -289.52623) (xy 69.88571 -289.565054)
			(xy 69.907493 -289.607813) (xy 69.922318 -289.653454) (xy 69.929819 -289.700852) (xy 69.930264 -289.724846)
			(xy 69.929593 -289.752996) (xy 69.919236 -289.808337) (xy 69.90969 -289.834828) (xy 69.905118 -289.846766)
			(xy 69.908166 -289.871658) (xy 69.945758 -289.926014) (xy 69.945758 -289.926522) (xy 69.96176 -289.949636)
			(xy 69.964584 -289.953622) (xy 69.971491 -289.960527) (xy 69.975476 -289.963352) (xy 69.977254 -289.964368)
			(xy 69.983614 -289.968349) (xy 69.99795 -289.972747) (xy 70.005448 -289.973004) (xy 70.19544 -289.973004)
			(xy 70.2047 -289.972657) (xy 70.222034 -289.966151) (xy 70.229222 -289.960304) (xy 70.234048 -289.955986)
			(xy 70.254114 -289.926268) (xy 70.284594 -289.881564) (xy 70.290948 -289.871006) (xy 70.293886 -289.846579)
			(xy 70.290182 -289.834828) (xy 70.289928 -289.83432) (xy 70.280507 -289.808066) (xy 70.270281 -289.753239)
			(xy 70.269608 -289.725354) (xy 70.269608 -289.720782) (xy 70.270376 -289.696998) (xy 70.278376 -289.650091)
			(xy 70.293557 -289.604993) (xy 70.31555 -289.562796) (xy 70.343823 -289.524522) (xy 70.377692 -289.491097)
			(xy 70.416336 -289.463332) (xy 70.45882 -289.441898) (xy 70.504115 -289.427315) (xy 70.551124 -289.419935)
			(xy 70.574916 -289.419538) (xy 70.598907 -289.419985) (xy 70.646298 -289.427494) (xy 70.69193 -289.442325)
			(xy 70.734681 -289.464112) (xy 70.773497 -289.492319) (xy 70.807422 -289.52625) (xy 70.835621 -289.565072)
			(xy 70.857399 -289.607827) (xy 70.87222 -289.653463) (xy 70.879719 -289.700855) (xy 70.880224 -289.724846)
			(xy 70.879552 -289.752996) (xy 70.869194 -289.808336) (xy 70.85965 -289.834828) (xy 70.855078 -289.846766)
			(xy 70.858126 -289.871658) (xy 70.895718 -289.926014) (xy 70.895718 -289.926522) (xy 70.91172 -289.949636)
			(xy 70.914542 -289.953623) (xy 70.921447 -289.960533) (xy 70.925436 -289.963352) (xy 70.927214 -289.964368)
			(xy 70.933576 -289.968341) (xy 70.947912 -289.972722) (xy 70.955408 -289.973004) (xy 71.1454 -289.973004)
			(xy 71.154656 -289.972646) (xy 71.171976 -289.966125) (xy 71.179182 -289.960304) (xy 71.184008 -289.955986)
			(xy 71.204074 -289.926268) (xy 71.234554 -289.881564) (xy 71.240912 -289.871007) (xy 71.243852 -289.846578)
			(xy 71.240142 -289.834828) (xy 71.239888 -289.83432) (xy 71.230468 -289.808066) (xy 71.220244 -289.753239)
			(xy 71.219568 -289.725354) (xy 71.219568 -289.720782) (xy 71.220336 -289.697) (xy 71.228337 -289.650096)
			(xy 71.243518 -289.605002) (xy 71.265512 -289.562809) (xy 71.293787 -289.52454) (xy 71.327656 -289.491122)
			(xy 71.366301 -289.463363) (xy 71.408785 -289.441937) (xy 71.454079 -289.427362) (xy 71.501085 -289.419991)
			(xy 71.524876 -289.419538) (xy 71.548869 -289.419982) (xy 71.596265 -289.427486) (xy 71.641903 -289.442313)
			(xy 71.684659 -289.464098) (xy 71.72348 -289.492304) (xy 71.75741 -289.526237) (xy 71.785613 -289.56506)
			(xy 71.807395 -289.607818) (xy 71.822219 -289.653457) (xy 71.829719 -289.700853) (xy 71.830184 -289.724846)
			(xy 71.829512 -289.752996) (xy 71.819152 -289.808336) (xy 71.80961 -289.834828) (xy 71.805038 -289.846766)
			(xy 71.808086 -289.871658) (xy 71.845678 -289.926014) (xy 71.845678 -289.926522) (xy 71.86168 -289.949636)
			(xy 71.864505 -289.953621) (xy 71.871414 -289.960524) (xy 71.875396 -289.963352) (xy 71.877174 -289.964368)
			(xy 71.883534 -289.968346) (xy 71.897871 -289.972739) (xy 71.905368 -289.973004) (xy 72.09536 -289.973004)
			(xy 72.104619 -289.972653) (xy 72.121948 -289.966142) (xy 72.129142 -289.960304) (xy 72.133968 -289.955986)
			(xy 72.154034 -289.926268) (xy 72.184514 -289.881564) (xy 72.190876 -289.871007) (xy 72.193818 -289.846577)
			(xy 72.190102 -289.834828) (xy 72.189848 -289.83432) (xy 72.180426 -289.808066) (xy 72.1702 -289.753239)
			(xy 72.169528 -289.725354) (xy 72.169528 -289.720782) (xy 72.170296 -289.696998) (xy 72.178296 -289.650092)
			(xy 72.193477 -289.604996) (xy 72.215471 -289.5628) (xy 72.243745 -289.524528) (xy 72.277614 -289.491106)
			(xy 72.316258 -289.463343) (xy 72.358742 -289.441911) (xy 72.404036 -289.427331) (xy 72.451044 -289.419954)
			(xy 72.474836 -289.419538) (xy 72.498826 -289.419987) (xy 72.546214 -289.427498) (xy 72.591844 -289.442331)
			(xy 72.634592 -289.464119) (xy 72.673405 -289.492326) (xy 72.707328 -289.526257) (xy 72.735524 -289.565078)
			(xy 72.757301 -289.607832) (xy 72.772121 -289.653465) (xy 72.77962 -289.700856) (xy 72.780144 -289.724846)
			(xy 72.779473 -289.752996) (xy 72.769115 -289.808337) (xy 72.75957 -289.834828) (xy 72.754998 -289.846766)
			(xy 72.758046 -289.871658) (xy 72.795638 -289.926014) (xy 72.795638 -289.926522) (xy 72.81164 -289.949636)
			(xy 72.814463 -289.953622) (xy 72.821369 -289.96053) (xy 72.825356 -289.963352) (xy 72.827134 -289.964368)
			(xy 72.833493 -289.968351) (xy 72.847829 -289.972755) (xy 72.855328 -289.973004) (xy 73.082912 -289.973004)
			(xy 73.092981 -289.972579) (xy 73.111583 -289.964862) (xy 73.11898 -289.958018) (xy 73.159366 -289.917632)
			(xy 73.164192 -289.884612) (xy 73.156064 -289.869626) (xy 73.144589 -289.847233) (xy 73.128307 -289.799628)
			(xy 73.120027 -289.750002) (xy 73.119488 -289.724846) (xy 73.119946 -289.701068) (xy 73.127325 -289.654088)
			(xy 73.141898 -289.60882) (xy 73.16331 -289.566357) (xy 73.191046 -289.527726) (xy 73.224434 -289.493862)
			(xy 73.262668 -289.465582) (xy 73.304823 -289.44357) (xy 73.349881 -289.428358) (xy 73.373234 -289.423856)
			(xy 73.39457 -289.4203) (xy 73.402952 -289.419538) (xy 73.424796 -289.419538) (xy 73.440662 -289.419753)
			(xy 73.472223 -289.423057) (xy 73.487788 -289.426142) (xy 73.498964 -289.428428) (xy 73.521316 -289.423094)
			(xy 73.573386 -289.38093) (xy 73.574148 -289.380168) (xy 73.5965 -289.362388) (xy 73.606152 -289.334702)
			(xy 73.602596 -289.320224) (xy 73.598761 -289.302889) (xy 73.59469 -289.267619) (xy 73.594468 -289.249866)
			(xy 73.59471 -289.232115) (xy 73.598781 -289.196846) (xy 73.602596 -289.179508) (xy 73.606152 -289.16503)
			(xy 73.5965 -289.137344) (xy 73.574148 -289.119564) (xy 73.573386 -289.118802) (xy 73.530206 -289.084004)
			(xy 73.521046 -289.077295) (xy 73.49902 -289.071909) (xy 73.487788 -289.07359) (xy 73.472286 -289.07667)
			(xy 73.440853 -289.07998) (xy 73.42505 -289.080194) (xy 73.402952 -289.080194) (xy 73.39457 -289.079432)
			(xy 73.373234 -289.075876) (xy 73.349867 -289.071418) (xy 73.304792 -289.056222) (xy 73.26262 -289.034217)
			(xy 73.224372 -289.005937) (xy 73.190973 -288.972067) (xy 73.163233 -288.933425) (xy 73.141823 -288.890948)
			(xy 73.127261 -288.845665) (xy 73.1199 -288.79867) (xy 73.119488 -288.774886) (xy 73.11996 -288.750895)
			(xy 73.127467 -288.703505) (xy 73.142296 -288.657873) (xy 73.16408 -288.615122) (xy 73.192284 -288.576305)
			(xy 73.226212 -288.542377) (xy 73.26503 -288.514175) (xy 73.307782 -288.492392) (xy 73.353415 -288.477565)
			(xy 73.400805 -288.470059) (xy 73.424796 -288.469578) (xy 73.425304 -288.469578) (xy 73.448066 -288.469999)
			(xy 73.493084 -288.476758) (xy 73.514966 -288.48304) (xy 73.516998 -288.483802) (xy 73.520554 -288.484564)
			(xy 73.525634 -288.486342) (xy 73.529698 -288.487866) (xy 73.545954 -288.491168) (xy 73.556368 -288.492184)
			(xy 73.55967 -288.492184) (xy 73.569694 -288.49177) (xy 73.588219 -288.484104) (xy 73.602397 -288.46993)
			(xy 73.610067 -288.451408) (xy 73.61047 -288.441384) (xy 73.61047 -288.421572) (xy 73.60539 -288.406332)
			(xy 73.600564 -288.399728) (xy 73.590971 -288.386728) (xy 73.572554 -288.360179) (xy 73.563734 -288.346642)
			(xy 73.546235 -288.318967) (xy 73.514584 -288.261641) (xy 73.500488 -288.232088) (xy 73.494138 -288.218118)
			(xy 73.477628 -288.178494) (xy 73.477374 -288.177732) (xy 73.476358 -288.175446) (xy 73.473868 -288.169862)
			(xy 73.46668 -288.159976) (xy 73.462134 -288.155888) (xy 73.46061 -288.154618) (xy 73.452482 -288.148776)
			(xy 73.424796 -288.130742) (xy 73.410826 -288.12998) (xy 73.386501 -288.12839) (xy 73.338779 -288.118453)
			(xy 73.293242 -288.101062) (xy 73.251045 -288.076658) (xy 73.213261 -288.045862) (xy 73.180848 -288.009454)
			(xy 73.15463 -287.968361) (xy 73.135272 -287.923624) (xy 73.123266 -287.87638) (xy 73.118917 -287.82783)
			(xy 73.122335 -287.779205) (xy 73.133434 -287.73174) (xy 73.151932 -287.686641) (xy 73.177358 -287.645052)
			(xy 73.209067 -287.608031) (xy 73.246255 -287.576516) (xy 73.287976 -287.551309) (xy 73.333172 -287.533049)
			(xy 73.380695 -287.522199) (xy 73.404984 -287.520126) (xy 73.411334 -287.519618) (xy 73.428606 -287.51403)
			(xy 73.436988 -287.510982) (xy 73.457816 -287.496758) (xy 73.462642 -287.490916) (xy 73.475596 -287.475168)
			(xy 73.479406 -287.466786) (xy 73.479914 -287.465516) (xy 73.488088 -287.445485) (xy 73.506001 -287.4061)
			(xy 73.515728 -287.386776) (xy 73.520554 -287.377378) (xy 73.538304 -287.344304) (xy 73.578228 -287.280732)
			(xy 73.60031 -287.250378) (xy 73.605136 -287.244028) (xy 73.610216 -287.22955) (xy 73.61047 -287.22066)
			(xy 73.61047 -287.218882) (xy 73.598786 -287.196784) (xy 73.561956 -287.171892) (xy 73.552047 -287.165942)
			(xy 73.529172 -287.162777) (xy 73.518014 -287.165796) (xy 73.495374 -287.172574) (xy 73.448679 -287.179852)
			(xy 73.42505 -287.180274) (xy 73.420478 -287.180274) (xy 73.39671 -287.179484) (xy 73.34984 -287.171446)
			(xy 73.304784 -287.156239) (xy 73.26263 -287.13423) (xy 73.224398 -287.105951) (xy 73.191013 -287.072086)
			(xy 73.163283 -287.033455) (xy 73.141877 -286.990991) (xy 73.127314 -286.945722) (xy 73.119947 -286.898743)
			(xy 73.119488 -286.874966) (xy 73.119961 -286.850976) (xy 73.127471 -286.803589) (xy 73.142302 -286.757959)
			(xy 73.164087 -286.715211) (xy 73.192291 -286.676396) (xy 73.226219 -286.642471) (xy 73.265036 -286.614271)
			(xy 73.307787 -286.59249) (xy 73.353418 -286.577664) (xy 73.400806 -286.570159) (xy 73.424796 -286.569658)
			(xy 73.425304 -286.569658) (xy 73.448066 -286.570079) (xy 73.493084 -286.576838) (xy 73.514966 -286.58312)
			(xy 73.516998 -286.583882) (xy 73.520554 -286.584644) (xy 73.525634 -286.586422) (xy 73.529698 -286.587946)
			(xy 73.545954 -286.591248) (xy 73.556368 -286.592264) (xy 73.55967 -286.592264) (xy 73.569693 -286.591849)
			(xy 73.588214 -286.584183) (xy 73.602386 -286.570009) (xy 73.61005 -286.551487) (xy 73.61047 -286.541464)
			(xy 73.61047 -286.521398) (xy 73.60539 -286.506158) (xy 73.600564 -286.499554) (xy 73.590971 -286.486554)
			(xy 73.572553 -286.460005) (xy 73.563734 -286.446468) (xy 73.546234 -286.418794) (xy 73.514582 -286.361468)
			(xy 73.500488 -286.331914) (xy 73.494138 -286.317944) (xy 73.477628 -286.27832) (xy 73.477374 -286.277558)
			(xy 73.476358 -286.275272) (xy 73.47387 -286.269687) (xy 73.466686 -286.259797) (xy 73.462134 -286.255714)
			(xy 73.46061 -286.254444) (xy 73.452482 -286.248602) (xy 73.424796 -286.230568) (xy 73.410826 -286.229806)
			(xy 73.386499 -286.228216) (xy 73.338773 -286.218278) (xy 73.293232 -286.200886) (xy 73.251032 -286.17648)
			(xy 73.213244 -286.145681) (xy 73.180828 -286.109271) (xy 73.154607 -286.068174) (xy 73.135248 -286.023434)
			(xy 73.123241 -285.976186) (xy 73.118891 -285.927631) (xy 73.12231 -285.879002) (xy 73.133409 -285.831533)
			(xy 73.151908 -285.78643) (xy 73.177336 -285.744838) (xy 73.209048 -285.707813) (xy 73.246239 -285.676296)
			(xy 73.287963 -285.651086) (xy 73.333163 -285.632824) (xy 73.380689 -285.621974) (xy 73.404984 -285.619952)
			(xy 73.411334 -285.619444) (xy 73.428606 -285.613856) (xy 73.436988 -285.610808) (xy 73.457816 -285.596584)
			(xy 73.462642 -285.590742) (xy 73.475596 -285.574994) (xy 73.479406 -285.566612) (xy 73.479914 -285.565342)
			(xy 73.488087 -285.545311) (xy 73.506 -285.505926) (xy 73.515728 -285.486602) (xy 73.520554 -285.477204)
			(xy 73.538303 -285.444129) (xy 73.578226 -285.380556) (xy 73.60031 -285.350204) (xy 73.605136 -285.343854)
			(xy 73.610216 -285.329376) (xy 73.61047 -285.320486) (xy 73.61047 -285.318708) (xy 73.598786 -285.29661)
			(xy 73.561956 -285.271718) (xy 73.552047 -285.265765) (xy 73.529172 -285.262599) (xy 73.518014 -285.265622)
			(xy 73.495373 -285.2724) (xy 73.448679 -285.279677) (xy 73.42505 -285.2801) (xy 73.420478 -285.2801)
			(xy 73.396709 -285.27931) (xy 73.349838 -285.271272) (xy 73.30478 -285.256066) (xy 73.262624 -285.234057)
			(xy 73.22439 -285.205778) (xy 73.191003 -285.171914) (xy 73.163269 -285.133283) (xy 73.141861 -285.090819)
			(xy 73.127294 -285.04555) (xy 73.119923 -284.99857) (xy 73.119488 -284.974792) (xy 73.119959 -284.950801)
			(xy 73.127466 -284.90341) (xy 73.142294 -284.857777) (xy 73.164078 -284.815025) (xy 73.192282 -284.776207)
			(xy 73.22621 -284.742279) (xy 73.265028 -284.714076) (xy 73.307781 -284.692293) (xy 73.353414 -284.677465)
			(xy 73.400805 -284.669959) (xy 73.424796 -284.669484) (xy 73.425304 -284.669484) (xy 73.448066 -284.669905)
			(xy 73.493084 -284.676665) (xy 73.514966 -284.682946) (xy 73.516998 -284.683708) (xy 73.520554 -284.68447)
			(xy 73.525634 -284.686248) (xy 73.529698 -284.687772) (xy 73.545954 -284.691074) (xy 73.556368 -284.69209)
			(xy 73.55967 -284.69209) (xy 73.569695 -284.691676) (xy 73.58822 -284.684011) (xy 73.602399 -284.669837)
			(xy 73.610072 -284.651314) (xy 73.61047 -284.64129) (xy 73.61047 -284.621478) (xy 73.60539 -284.606238)
			(xy 73.600564 -284.599634) (xy 73.590971 -284.586634) (xy 73.572553 -284.560085) (xy 73.563734 -284.546548)
			(xy 73.546235 -284.518874) (xy 73.514583 -284.461548) (xy 73.500488 -284.431994) (xy 73.494138 -284.418024)
			(xy 73.477628 -284.3784) (xy 73.477374 -284.377638) (xy 73.476358 -284.375352) (xy 73.473868 -284.369768)
			(xy 73.466681 -284.359881) (xy 73.462134 -284.355794) (xy 73.46061 -284.354524) (xy 73.452482 -284.348682)
			(xy 73.424796 -284.330648) (xy 73.410826 -284.329886) (xy 73.3865 -284.328296) (xy 73.338778 -284.318359)
			(xy 73.29324 -284.300967) (xy 73.251042 -284.276563) (xy 73.213257 -284.245766) (xy 73.180843 -284.209358)
			(xy 73.154625 -284.168264) (xy 73.135266 -284.123526) (xy 73.12326 -284.076282) (xy 73.118911 -284.02773)
			(xy 73.122329 -283.979104) (xy 73.133428 -283.931638) (xy 73.151926 -283.886538) (xy 73.177353 -283.844949)
			(xy 73.209063 -283.807927) (xy 73.246251 -283.776411) (xy 73.287973 -283.751203) (xy 73.33317 -283.732943)
			(xy 73.380694 -283.722094) (xy 73.404984 -283.720032) (xy 73.411334 -283.719524) (xy 73.428606 -283.713936)
			(xy 73.436988 -283.710888) (xy 73.457816 -283.696664) (xy 73.462642 -283.690822) (xy 73.475596 -283.675074)
			(xy 73.479406 -283.666692) (xy 73.479914 -283.665422) (xy 73.488088 -283.645391) (xy 73.506001 -283.606006)
			(xy 73.515728 -283.586682) (xy 73.520554 -283.577284) (xy 73.538304 -283.54421) (xy 73.578227 -283.480637)
			(xy 73.60031 -283.450284) (xy 73.605136 -283.443934) (xy 73.610216 -283.429456) (xy 73.61047 -283.420566)
			(xy 73.61047 -283.418788) (xy 73.598786 -283.39669) (xy 73.561956 -283.371798) (xy 73.552047 -283.365847)
			(xy 73.529172 -283.362682) (xy 73.518014 -283.365702) (xy 73.495374 -283.37248) (xy 73.448679 -283.379758)
			(xy 73.42505 -283.38018) (xy 73.420478 -283.38018) (xy 73.39671 -283.37939) (xy 73.34984 -283.371352)
			(xy 73.304783 -283.356145) (xy 73.262628 -283.334136) (xy 73.224396 -283.305857) (xy 73.191011 -283.271993)
			(xy 73.16328 -283.233362) (xy 73.141873 -283.190898) (xy 73.12731 -283.145629) (xy 73.119941 -283.098649)
			(xy 73.119488 -283.074872) (xy 73.119944 -283.051093) (xy 73.12732 -283.00411) (xy 73.14189 -282.958838)
			(xy 73.163301 -282.916372) (xy 73.191036 -282.877738) (xy 73.224425 -282.84387) (xy 73.262659 -282.815587)
			(xy 73.304816 -282.793573) (xy 73.349876 -282.778359) (xy 73.373234 -282.773882) (xy 73.39457 -282.770326)
			(xy 73.402952 -282.769564) (xy 73.42505 -282.769564) (xy 73.440852 -282.769795) (xy 73.472285 -282.773099)
			(xy 73.487788 -282.776168) (xy 73.498989 -282.77789) (xy 73.521001 -282.772619) (xy 73.530206 -282.766008)
			(xy 73.573386 -282.730956) (xy 73.574148 -282.730194) (xy 73.5965 -282.712414) (xy 73.606152 -282.684728)
			(xy 73.602596 -282.67025) (xy 73.59876 -282.652915) (xy 73.594685 -282.617645) (xy 73.594468 -282.599892)
			(xy 73.594715 -282.582141) (xy 73.598793 -282.546875) (xy 73.602596 -282.529534) (xy 73.606152 -282.515056)
			(xy 73.596754 -282.487878) (xy 73.530968 -282.434284) (xy 73.526396 -282.430474) (xy 73.516744 -282.425648)
			(xy 73.498964 -282.42133) (xy 73.487534 -282.423616) (xy 73.471969 -282.426703) (xy 73.440409 -282.430007)
			(xy 73.424542 -282.43022) (xy 73.422256 -282.43022) (xy 73.398456 -282.429589) (xy 73.35148 -282.421854)
			(xy 73.306274 -282.406922) (xy 73.263934 -282.385154) (xy 73.225485 -282.357079) (xy 73.19186 -282.323376)
			(xy 73.163874 -282.284862) (xy 73.142205 -282.242472) (xy 73.127377 -282.197231) (xy 73.119751 -282.150238)
			(xy 73.119234 -282.126436) (xy 73.119234 -282.109418) (xy 73.1012 -282.08351) (xy 73.086214 -282.077922)
			(xy 73.073514 -282.073096) (xy 73.05873 -282.067235) (xy 73.029514 -282.054659) (xy 73.015094 -282.04795)
			(xy 72.979026 -282.030424) (xy 72.978772 -282.03017) (xy 72.973184 -282.027376) (xy 72.962516 -282.024582)
			(xy 72.93864 -282.024582) (xy 72.926194 -282.027376) (xy 72.920098 -282.030424) (xy 72.919844 -282.030678)
			(xy 72.897228 -282.042278) (xy 72.850976 -282.063372) (xy 72.827388 -282.072842) (xy 72.821546 -282.074874)
			(xy 72.812402 -282.081478) (xy 72.805798 -282.08859) (xy 72.801988 -282.093416) (xy 72.789288 -282.11145)
			(xy 72.78497 -282.117546) (xy 72.77989 -282.132278) (xy 72.779636 -282.139644) (xy 72.777838 -282.165423)
			(xy 72.766669 -282.215875) (xy 72.747164 -282.263725) (xy 72.719879 -282.307607) (xy 72.685595 -282.346267)
			(xy 72.645289 -282.378602) (xy 72.600114 -282.403688) (xy 72.55136 -282.420808) (xy 72.500419 -282.429474)
			(xy 72.474582 -282.429966) (xy 72.448763 -282.429433) (xy 72.39786 -282.420762) (xy 72.34914 -282.403653)
			(xy 72.303992 -282.378594) (xy 72.263701 -282.346297) (xy 72.229417 -282.307685) (xy 72.202115 -282.263856)
			(xy 72.182574 -282.21606) (xy 72.17135 -282.165657) (xy 72.169528 -282.139898) (xy 72.168766 -282.12542)
			(xy 72.14108 -282.085034) (xy 72.129396 -282.075636) (xy 72.122284 -282.072842) (xy 72.09889 -282.063355)
			(xy 72.053019 -282.042264) (xy 72.03059 -282.030678) (xy 72.030082 -282.030424) (xy 72.029574 -282.03017)
			(xy 72.023224 -282.026868) (xy 72.011286 -282.024074) (xy 72.005368 -282.022888) (xy 71.993303 -282.023022)
			(xy 71.98741 -282.024328) (xy 71.975726 -282.027376) (xy 71.970646 -282.03017) (xy 71.94931 -282.040838)
			(xy 71.938388 -282.046172) (xy 71.927974 -282.050998) (xy 71.914258 -282.057094) (xy 71.91375 -282.057348)
			(xy 71.84644 -282.086558) (xy 71.82993 -282.11145) (xy 71.82993 -282.12669) (xy 71.829311 -282.150579)
			(xy 71.82156 -282.197733) (xy 71.806557 -282.243102) (xy 71.784669 -282.285581) (xy 71.756432 -282.324131)
			(xy 71.722533 -282.357812) (xy 71.683802 -282.385801) (xy 71.641183 -282.407414) (xy 71.595717 -282.422124)
			(xy 71.548515 -282.429572) (xy 71.524622 -282.429966) (xy 71.500682 -282.429501) (xy 71.453387 -282.422029)
			(xy 71.40784 -282.407265) (xy 71.365156 -282.38557) (xy 71.326382 -282.357478) (xy 71.29247 -282.323676)
			(xy 71.264251 -282.284994) (xy 71.242418 -282.242382) (xy 71.227505 -282.196882) (xy 71.219879 -282.149613)
			(xy 71.219314 -282.125674) (xy 71.218984 -282.11713) (xy 71.213352 -282.100995) (xy 71.202725 -282.087612)
			(xy 71.195692 -282.082748) (xy 71.191374 -282.079954) (xy 71.186294 -282.077922) (xy 71.185786 -282.077668)
			(xy 71.139304 -282.058872) (xy 71.111364 -282.046172) (xy 71.087234 -282.034234) (xy 71.049642 -282.013914)
			(xy 71.029322 -282.02509) (xy 71.004421 -282.038267) (xy 70.953334 -282.062031) (xy 70.927214 -282.072588)
			(xy 70.924674 -282.073604) (xy 70.922134 -282.074874) (xy 70.916946 -282.077804) (xy 70.907969 -282.085632)
			(xy 70.904354 -282.090368) (xy 70.884796 -282.117546) (xy 70.87997 -282.131516) (xy 70.879716 -282.138882)
			(xy 70.87797 -282.164702) (xy 70.866885 -282.215246) (xy 70.847436 -282.263198) (xy 70.82018 -282.307185)
			(xy 70.785899 -282.345945) (xy 70.745572 -282.378371) (xy 70.700356 -282.403533) (xy 70.651544 -282.420711)
			(xy 70.600535 -282.429413) (xy 70.574662 -282.429966) (xy 70.548805 -282.42942) (xy 70.49783 -282.420706)
			(xy 70.44905 -282.403533) (xy 70.403859 -282.378391) (xy 70.363547 -282.345998) (xy 70.329265 -282.30728)
			(xy 70.301991 -282.263342) (xy 70.282506 -282.215439) (xy 70.271366 -282.164939) (xy 70.269608 -282.139136)
			(xy 70.269354 -282.13177) (xy 70.264528 -282.118054) (xy 70.260464 -282.112212) (xy 70.241668 -282.085288)
			(xy 70.229984 -282.07589) (xy 70.222872 -282.073096) (xy 70.198673 -282.063182) (xy 70.151276 -282.041072)
			(xy 70.12813 -282.0289) (xy 70.12686 -282.028392) (xy 70.118732 -282.022296) (xy 70.089522 -282.02001)
			(xy 70.075298 -282.02763) (xy 70.05746 -282.03693) (xy 70.021126 -282.054207) (xy 70.002654 -282.062174)
			(xy 69.997066 -282.06446) (xy 69.994526 -282.06573) (xy 69.977254 -282.072842) (xy 69.970396 -282.075636)
			(xy 69.9643 -282.080462) (xy 69.961573 -282.082756) (xy 69.95673 -282.087984) (xy 69.954648 -282.090876)
			(xy 69.943218 -282.106878) (xy 69.9389 -282.112974) (xy 69.929756 -282.139898) (xy 69.929248 -282.146502)
			(xy 69.926924 -282.17185) (xy 69.914921 -282.221312) (xy 69.894883 -282.2681) (xy 69.867363 -282.310917)
			(xy 69.833125 -282.348578) (xy 69.793116 -282.38004) (xy 69.748443 -282.404432) (xy 69.700344 -282.421078)
			(xy 69.650151 -282.429519) (xy 69.624702 -282.429966) (xy 69.598595 -282.429443) (xy 69.547137 -282.420584)
			(xy 69.497934 -282.403108) (xy 69.452419 -282.377522) (xy 69.411914 -282.344571) (xy 69.377601 -282.305214)
			(xy 69.350477 -282.260598) (xy 69.331331 -282.21202) (xy 69.320722 -282.160895) (xy 69.319394 -282.134818)
			(xy 69.319394 -282.134564) (xy 69.318886 -282.122372) (xy 69.305678 -282.098242) (xy 69.301093 -282.090681)
			(xy 69.287841 -282.078994) (xy 69.27977 -282.075382) (xy 69.279262 -282.075128) (xy 69.26453 -282.069286)
			(xy 69.264022 -282.069286) (xy 69.259958 -282.067508) (xy 69.237935 -282.058294) (xy 69.194734 -282.037966)
			(xy 69.173598 -282.026868) (xy 69.16801 -282.024074) (xy 69.156072 -282.021026) (xy 69.142864 -282.021026)
			(xy 69.130926 -282.024074) (xy 69.125338 -282.026868) (xy 69.098008 -282.041138) (xy 69.041829 -282.066556)
			(xy 69.01307 -282.077668) (xy 69.003592 -282.08173) (xy 68.988682 -282.095947) (xy 68.980529 -282.114867)
			(xy 68.98005 -282.125166) (xy 68.979489 -282.150394) (xy 68.97111 -282.200151) (xy 68.954663 -282.247852)
			(xy 68.930598 -282.292201) (xy 68.899568 -282.331989) (xy 68.862418 -282.366134) (xy 68.82016 -282.393705)
			(xy 68.773944 -282.413953) (xy 68.725027 -282.426327) (xy 68.674742 -282.430489) (xy 68.624457 -282.426327)
			(xy 68.57554 -282.413953) (xy 68.529324 -282.393705) (xy 68.487066 -282.366134) (xy 68.449916 -282.331989)
			(xy 68.418886 -282.292201) (xy 68.394821 -282.247852) (xy 68.378374 -282.200151) (xy 68.369995 -282.150394)
			(xy 68.369434 -282.125166) (xy 68.368962 -282.11486) (xy 68.360845 -282.095916) (xy 68.345903 -282.081719)
			(xy 68.336414 -282.077668) (xy 68.309064 -282.067159) (xy 68.25556 -282.043268) (xy 68.22948 -282.029916)
			(xy 68.223892 -282.027122) (xy 68.211954 -282.024328) (xy 68.206108 -282.02313) (xy 68.194178 -282.02313)
			(xy 68.188332 -282.024328) (xy 68.175886 -282.027122) (xy 68.170298 -282.03017) (xy 68.147508 -282.041986)
			(xy 68.100874 -282.06346) (xy 68.07708 -282.073096) (xy 68.070213 -282.076008) (xy 68.058456 -282.085174)
			(xy 68.053966 -282.09113) (xy 68.034662 -282.118562) (xy 68.03009 -282.132024) (xy 68.029836 -282.13939)
			(xy 68.028189 -282.163839) (xy 68.018081 -282.211784) (xy 68.000448 -282.2575) (xy 67.975741 -282.299815)
			(xy 67.944595 -282.337641) (xy 67.907809 -282.370009) (xy 67.866326 -282.396088) (xy 67.821212 -282.415209)
			(xy 67.773624 -282.426882) (xy 67.724782 -282.430806) (xy 67.67594 -282.426882) (xy 67.628352 -282.415209)
			(xy 67.583238 -282.396088) (xy 67.541755 -282.370009) (xy 67.504969 -282.337641) (xy 67.473823 -282.299815)
			(xy 67.449116 -282.2575) (xy 67.431483 -282.211784) (xy 67.421375 -282.163839) (xy 67.419728 -282.13939)
			(xy 67.419474 -282.132024) (xy 67.414648 -282.118562) (xy 67.395598 -282.091638) (xy 67.392128 -282.086911)
			(xy 67.3834 -282.079084) (xy 67.378326 -282.076144) (xy 67.3735 -282.073604) (xy 67.37096 -282.072588)
			(xy 67.346035 -282.062419) (xy 67.29724 -282.03967) (xy 67.273424 -282.027122) (xy 67.26709 -282.024009)
			(xy 67.253299 -282.021034) (xy 67.246246 -282.02128) (xy 67.235324 -282.022042) (xy 67.209095 -282.036054)
			(xy 67.15521 -282.061219) (xy 67.127628 -282.072334) (xy 67.124072 -282.073604) (xy 67.120516 -282.075636)
			(xy 67.115933 -282.078485) (xy 67.107988 -282.085784) (xy 67.104768 -282.090114) (xy 67.084702 -282.1178)
			(xy 67.08013 -282.13177) (xy 67.079876 -282.13939) (xy 67.078229 -282.163839) (xy 67.068121 -282.211784)
			(xy 67.050488 -282.2575) (xy 67.025781 -282.299815) (xy 66.994635 -282.337641) (xy 66.957849 -282.370009)
			(xy 66.916366 -282.396088) (xy 66.871252 -282.415209) (xy 66.823664 -282.426882) (xy 66.774822 -282.430806)
			(xy 66.72598 -282.426882) (xy 66.678392 -282.415209) (xy 66.633278 -282.396088) (xy 66.591795 -282.370009)
			(xy 66.555009 -282.337641) (xy 66.523863 -282.299815) (xy 66.499156 -282.2575) (xy 66.481523 -282.211784)
			(xy 66.471415 -282.163839) (xy 66.469768 -282.13939) (xy 66.469514 -282.13177) (xy 66.464942 -282.1178)
			(xy 66.444876 -282.090114) (xy 66.441655 -282.085784) (xy 66.433713 -282.078482) (xy 66.429128 -282.075636)
			(xy 66.425572 -282.073604) (xy 66.422016 -282.072334) (xy 66.398229 -282.062753) (xy 66.351595 -282.041407)
			(xy 66.328798 -282.029662) (xy 66.327782 -282.029154) (xy 66.322457 -282.026688) (xy 66.311041 -282.023987)
			(xy 66.305176 -282.02382) (xy 66.289682 -282.02382) (xy 66.27749 -282.026614) (xy 66.253007 -282.039488)
			(xy 66.20281 -282.062741) (xy 66.17716 -282.073096) (xy 66.170295 -282.076011) (xy 66.158541 -282.085179)
			(xy 66.154046 -282.09113) (xy 66.134742 -282.118562) (xy 66.13017 -282.132024) (xy 66.129916 -282.13939)
			(xy 66.128269 -282.163839) (xy 66.118161 -282.211784) (xy 66.100528 -282.2575) (xy 66.075821 -282.299815)
			(xy 66.044675 -282.337641) (xy 66.007889 -282.370009) (xy 65.966406 -282.396088) (xy 65.921292 -282.415209)
			(xy 65.873704 -282.426882) (xy 65.824862 -282.430806) (xy 65.77602 -282.426882) (xy 65.728432 -282.415209)
			(xy 65.683318 -282.396088) (xy 65.641835 -282.370009) (xy 65.605049 -282.337641) (xy 65.573903 -282.299815)
			(xy 65.549196 -282.2575) (xy 65.531563 -282.211784) (xy 65.521455 -282.163839) (xy 65.519808 -282.13939)
			(xy 65.519554 -282.132024) (xy 65.514982 -282.118562) (xy 65.495678 -282.091638) (xy 65.492207 -282.086912)
			(xy 65.483477 -282.079088) (xy 65.478406 -282.076144) (xy 65.47358 -282.073604) (xy 65.47104 -282.072588)
			(xy 65.446114 -282.062421) (xy 65.397317 -282.039676) (xy 65.373504 -282.027122) (xy 65.367169 -282.024012)
			(xy 65.353379 -282.021042) (xy 65.346326 -282.02128) (xy 65.335404 -282.022042) (xy 65.309175 -282.036054)
			(xy 65.255289 -282.061217) (xy 65.227708 -282.072334) (xy 65.224152 -282.073604) (xy 65.220596 -282.075636)
			(xy 65.216014 -282.078486) (xy 65.208072 -282.085787) (xy 65.204848 -282.090114) (xy 65.184782 -282.1178)
			(xy 65.18021 -282.13177) (xy 65.179956 -282.13939) (xy 65.178309 -282.163839) (xy 65.168201 -282.211784)
			(xy 65.150568 -282.2575) (xy 65.125861 -282.299815) (xy 65.094715 -282.337641) (xy 65.057929 -282.370009)
			(xy 65.016446 -282.396088) (xy 64.971332 -282.415209) (xy 64.923744 -282.426882) (xy 64.874902 -282.430806)
			(xy 64.82606 -282.426882) (xy 64.778472 -282.415209) (xy 64.733358 -282.396088) (xy 64.691875 -282.370009)
			(xy 64.655089 -282.337641) (xy 64.623943 -282.299815) (xy 64.599236 -282.2575) (xy 64.581603 -282.211784)
			(xy 64.571495 -282.163839) (xy 64.569848 -282.13939) (xy 64.569594 -282.132024) (xy 64.564768 -282.117546)
			(xy 64.544956 -282.090368) (xy 64.542162 -282.086528) (xy 64.53539 -282.079874) (xy 64.531494 -282.07716)
			(xy 64.525906 -282.073604) (xy 64.52108 -282.071826) (xy 64.497689 -282.062402) (xy 64.451819 -282.041436)
			(xy 64.429386 -282.029916) (xy 64.423798 -282.027122) (xy 64.41186 -282.024328) (xy 64.406014 -282.02313)
			(xy 64.394084 -282.02313) (xy 64.388238 -282.024328) (xy 64.375792 -282.027122) (xy 64.370204 -282.03017)
			(xy 64.356242 -282.03743) (xy 64.327916 -282.051151) (xy 64.313562 -282.057602) (xy 64.304378 -282.062221)
			(xy 64.290406 -282.077276) (xy 64.283446 -282.0966) (xy 64.28359 -282.106878) (xy 64.284098 -282.124912)
			(xy 64.283614 -282.151853) (xy 64.27556 -282.205129) (xy 64.259635 -282.256603) (xy 64.236195 -282.305119)
			(xy 64.205769 -282.349587) (xy 64.169038 -282.389008) (xy 64.126828 -282.422498) (xy 64.080088 -282.449304)
			(xy 64.029867 -282.468823) (xy 64.003682 -282.475178) (xy 63.994284 -282.47721) (xy 63.978536 -282.487878)
			(xy 63.846456 -282.67787) (xy 63.841386 -282.685814) (xy 63.83695 -282.704117) (xy 63.839443 -282.722784)
			(xy 63.843662 -282.73121) (xy 63.850774 -282.74391) (xy 63.87592 -282.758134) (xy 63.89243 -282.757372)
			(xy 63.893954 -282.757372) (xy 63.89624 -282.757118) (xy 63.924434 -282.755848) (xy 63.924942 -282.755848)
			(xy 63.950013 -282.756343) (xy 63.999537 -282.764193) (xy 64.047223 -282.779694) (xy 64.091897 -282.802464)
			(xy 64.132459 -282.831942) (xy 64.16791 -282.867402) (xy 64.197378 -282.907971) (xy 64.220136 -282.952651)
			(xy 64.235625 -283.000341) (xy 64.243463 -283.049866) (xy 64.243461 -283.074872) (xy 64.569098 -283.074872)
			(xy 64.573058 -283.025818) (xy 64.584835 -282.978034) (xy 64.604126 -282.932758) (xy 64.630429 -282.891162)
			(xy 64.663064 -282.854325) (xy 64.701185 -282.8232) (xy 64.743806 -282.798593) (xy 64.789822 -282.781141)
			(xy 64.838041 -282.771297) (xy 64.887216 -282.769316) (xy 64.936071 -282.775248) (xy 64.983342 -282.78894)
			(xy 65.027804 -282.810038) (xy 65.068307 -282.837994) (xy 65.1038 -282.872086) (xy 65.133365 -282.91143)
			(xy 65.156236 -282.955007) (xy 65.17182 -283.001688) (xy 65.179715 -283.050265) (xy 65.18021 -283.074872)
			(xy 65.519058 -283.074872) (xy 65.523018 -283.025818) (xy 65.534795 -282.978034) (xy 65.554086 -282.932758)
			(xy 65.580389 -282.891162) (xy 65.613024 -282.854325) (xy 65.651145 -282.8232) (xy 65.693766 -282.798593)
			(xy 65.739782 -282.781141) (xy 65.788001 -282.771297) (xy 65.837176 -282.769316) (xy 65.886031 -282.775248)
			(xy 65.933302 -282.78894) (xy 65.977764 -282.810038) (xy 66.018267 -282.837994) (xy 66.05376 -282.872086)
			(xy 66.083325 -282.91143) (xy 66.106196 -282.955007) (xy 66.12178 -283.001688) (xy 66.129675 -283.050265)
			(xy 66.13017 -283.074872) (xy 66.469018 -283.074872) (xy 66.472978 -283.025818) (xy 66.484755 -282.978034)
			(xy 66.504046 -282.932758) (xy 66.530349 -282.891162) (xy 66.562984 -282.854325) (xy 66.601105 -282.8232)
			(xy 66.643726 -282.798593) (xy 66.689742 -282.781141) (xy 66.737961 -282.771297) (xy 66.787136 -282.769316)
			(xy 66.835991 -282.775248) (xy 66.883262 -282.78894) (xy 66.927724 -282.810038) (xy 66.968227 -282.837994)
			(xy 67.00372 -282.872086) (xy 67.033285 -282.91143) (xy 67.056156 -282.955007) (xy 67.07174 -283.001688)
			(xy 67.079635 -283.050265) (xy 67.08013 -283.074872) (xy 68.368938 -283.074872) (xy 68.372898 -283.025818)
			(xy 68.384675 -282.978034) (xy 68.403966 -282.932758) (xy 68.430269 -282.891162) (xy 68.462904 -282.854325)
			(xy 68.501025 -282.8232) (xy 68.543646 -282.798593) (xy 68.589662 -282.781141) (xy 68.637881 -282.771297)
			(xy 68.687056 -282.769316) (xy 68.735911 -282.775248) (xy 68.783182 -282.78894) (xy 68.827644 -282.810038)
			(xy 68.868147 -282.837994) (xy 68.90364 -282.872086) (xy 68.933205 -282.91143) (xy 68.956076 -282.955007)
			(xy 68.97166 -283.001688) (xy 68.979555 -283.050265) (xy 68.98005 -283.074872) (xy 69.319152 -283.074872)
			(xy 69.323112 -283.025818) (xy 69.334889 -282.978034) (xy 69.35418 -282.932758) (xy 69.380483 -282.891162)
			(xy 69.413118 -282.854325) (xy 69.451239 -282.8232) (xy 69.49386 -282.798593) (xy 69.539876 -282.781141)
			(xy 69.588095 -282.771297) (xy 69.63727 -282.769316) (xy 69.686125 -282.775248) (xy 69.733396 -282.78894)
			(xy 69.777858 -282.810038) (xy 69.818361 -282.837994) (xy 69.853854 -282.872086) (xy 69.883419 -282.91143)
			(xy 69.90629 -282.955007) (xy 69.921874 -283.001688) (xy 69.929769 -283.050265) (xy 69.930264 -283.074872)
			(xy 70.269112 -283.074872) (xy 70.273072 -283.025818) (xy 70.284849 -282.978034) (xy 70.30414 -282.932758)
			(xy 70.330443 -282.891162) (xy 70.363078 -282.854325) (xy 70.401199 -282.8232) (xy 70.44382 -282.798593)
			(xy 70.489836 -282.781141) (xy 70.538055 -282.771297) (xy 70.58723 -282.769316) (xy 70.636085 -282.775248)
			(xy 70.683356 -282.78894) (xy 70.727818 -282.810038) (xy 70.768321 -282.837994) (xy 70.803814 -282.872086)
			(xy 70.833379 -282.91143) (xy 70.85625 -282.955007) (xy 70.871834 -283.001688) (xy 70.879729 -283.050265)
			(xy 70.880224 -283.074872) (xy 71.219072 -283.074872) (xy 71.223032 -283.025818) (xy 71.234809 -282.978034)
			(xy 71.2541 -282.932758) (xy 71.280403 -282.891162) (xy 71.313038 -282.854325) (xy 71.351159 -282.8232)
			(xy 71.39378 -282.798593) (xy 71.439796 -282.781141) (xy 71.488015 -282.771297) (xy 71.53719 -282.769316)
			(xy 71.586045 -282.775248) (xy 71.633316 -282.78894) (xy 71.677778 -282.810038) (xy 71.718281 -282.837994)
			(xy 71.753774 -282.872086) (xy 71.783339 -282.91143) (xy 71.80621 -282.955007) (xy 71.821794 -283.001688)
			(xy 71.829689 -283.050265) (xy 71.830184 -283.074872) (xy 72.169032 -283.074872) (xy 72.172992 -283.025818)
			(xy 72.184769 -282.978034) (xy 72.20406 -282.932758) (xy 72.230363 -282.891162) (xy 72.262998 -282.854325)
			(xy 72.301119 -282.8232) (xy 72.34374 -282.798593) (xy 72.389756 -282.781141) (xy 72.437975 -282.771297)
			(xy 72.48715 -282.769316) (xy 72.536005 -282.775248) (xy 72.583276 -282.78894) (xy 72.627738 -282.810038)
			(xy 72.668241 -282.837994) (xy 72.703734 -282.872086) (xy 72.733299 -282.91143) (xy 72.75617 -282.955007)
			(xy 72.771754 -283.001688) (xy 72.779649 -283.050265) (xy 72.780144 -283.074872) (xy 72.779649 -283.099479)
			(xy 72.771754 -283.148056) (xy 72.75617 -283.194737) (xy 72.733299 -283.238314) (xy 72.703734 -283.277658)
			(xy 72.668241 -283.31175) (xy 72.627738 -283.339706) (xy 72.583276 -283.360804) (xy 72.536005 -283.374496)
			(xy 72.48715 -283.380428) (xy 72.437975 -283.378447) (xy 72.389756 -283.368603) (xy 72.34374 -283.351151)
			(xy 72.301119 -283.326544) (xy 72.262998 -283.295419) (xy 72.230363 -283.258582) (xy 72.20406 -283.216986)
			(xy 72.184769 -283.17171) (xy 72.172992 -283.123926) (xy 72.169032 -283.074872) (xy 71.830184 -283.074872)
			(xy 71.829689 -283.099479) (xy 71.821794 -283.148056) (xy 71.80621 -283.194737) (xy 71.783339 -283.238314)
			(xy 71.753774 -283.277658) (xy 71.718281 -283.31175) (xy 71.677778 -283.339706) (xy 71.633316 -283.360804)
			(xy 71.586045 -283.374496) (xy 71.53719 -283.380428) (xy 71.488015 -283.378447) (xy 71.439796 -283.368603)
			(xy 71.39378 -283.351151) (xy 71.351159 -283.326544) (xy 71.313038 -283.295419) (xy 71.280403 -283.258582)
			(xy 71.2541 -283.216986) (xy 71.234809 -283.17171) (xy 71.223032 -283.123926) (xy 71.219072 -283.074872)
			(xy 70.880224 -283.074872) (xy 70.879729 -283.099479) (xy 70.871834 -283.148056) (xy 70.85625 -283.194737)
			(xy 70.833379 -283.238314) (xy 70.803814 -283.277658) (xy 70.768321 -283.31175) (xy 70.727818 -283.339706)
			(xy 70.683356 -283.360804) (xy 70.636085 -283.374496) (xy 70.58723 -283.380428) (xy 70.538055 -283.378447)
			(xy 70.489836 -283.368603) (xy 70.44382 -283.351151) (xy 70.401199 -283.326544) (xy 70.363078 -283.295419)
			(xy 70.330443 -283.258582) (xy 70.30414 -283.216986) (xy 70.284849 -283.17171) (xy 70.273072 -283.123926)
			(xy 70.269112 -283.074872) (xy 69.930264 -283.074872) (xy 69.929769 -283.099479) (xy 69.921874 -283.148056)
			(xy 69.90629 -283.194737) (xy 69.883419 -283.238314) (xy 69.853854 -283.277658) (xy 69.818361 -283.31175)
			(xy 69.777858 -283.339706) (xy 69.733396 -283.360804) (xy 69.686125 -283.374496) (xy 69.63727 -283.380428)
			(xy 69.588095 -283.378447) (xy 69.539876 -283.368603) (xy 69.49386 -283.351151) (xy 69.451239 -283.326544)
			(xy 69.413118 -283.295419) (xy 69.380483 -283.258582) (xy 69.35418 -283.216986) (xy 69.334889 -283.17171)
			(xy 69.323112 -283.123926) (xy 69.319152 -283.074872) (xy 68.98005 -283.074872) (xy 68.979555 -283.099479)
			(xy 68.97166 -283.148056) (xy 68.956076 -283.194737) (xy 68.933205 -283.238314) (xy 68.90364 -283.277658)
			(xy 68.868147 -283.31175) (xy 68.827644 -283.339706) (xy 68.783182 -283.360804) (xy 68.735911 -283.374496)
			(xy 68.687056 -283.380428) (xy 68.637881 -283.378447) (xy 68.589662 -283.368603) (xy 68.543646 -283.351151)
			(xy 68.501025 -283.326544) (xy 68.462904 -283.295419) (xy 68.430269 -283.258582) (xy 68.403966 -283.216986)
			(xy 68.384675 -283.17171) (xy 68.372898 -283.123926) (xy 68.368938 -283.074872) (xy 67.08013 -283.074872)
			(xy 67.079635 -283.099479) (xy 67.07174 -283.148056) (xy 67.056156 -283.194737) (xy 67.033285 -283.238314)
			(xy 67.00372 -283.277658) (xy 66.968227 -283.31175) (xy 66.927724 -283.339706) (xy 66.883262 -283.360804)
			(xy 66.835991 -283.374496) (xy 66.787136 -283.380428) (xy 66.737961 -283.378447) (xy 66.689742 -283.368603)
			(xy 66.643726 -283.351151) (xy 66.601105 -283.326544) (xy 66.562984 -283.295419) (xy 66.530349 -283.258582)
			(xy 66.504046 -283.216986) (xy 66.484755 -283.17171) (xy 66.472978 -283.123926) (xy 66.469018 -283.074872)
			(xy 66.13017 -283.074872) (xy 66.129675 -283.099479) (xy 66.12178 -283.148056) (xy 66.106196 -283.194737)
			(xy 66.083325 -283.238314) (xy 66.05376 -283.277658) (xy 66.018267 -283.31175) (xy 65.977764 -283.339706)
			(xy 65.933302 -283.360804) (xy 65.886031 -283.374496) (xy 65.837176 -283.380428) (xy 65.788001 -283.378447)
			(xy 65.739782 -283.368603) (xy 65.693766 -283.351151) (xy 65.651145 -283.326544) (xy 65.613024 -283.295419)
			(xy 65.580389 -283.258582) (xy 65.554086 -283.216986) (xy 65.534795 -283.17171) (xy 65.523018 -283.123926)
			(xy 65.519058 -283.074872) (xy 65.18021 -283.074872) (xy 65.179715 -283.099479) (xy 65.17182 -283.148056)
			(xy 65.156236 -283.194737) (xy 65.133365 -283.238314) (xy 65.1038 -283.277658) (xy 65.068307 -283.31175)
			(xy 65.027804 -283.339706) (xy 64.983342 -283.360804) (xy 64.936071 -283.374496) (xy 64.887216 -283.380428)
			(xy 64.838041 -283.378447) (xy 64.789822 -283.368603) (xy 64.743806 -283.351151) (xy 64.701185 -283.326544)
			(xy 64.663064 -283.295419) (xy 64.630429 -283.258582) (xy 64.604126 -283.216986) (xy 64.584835 -283.17171)
			(xy 64.573058 -283.123926) (xy 64.569098 -283.074872) (xy 64.243461 -283.074872) (xy 64.243458 -283.100008)
			(xy 64.235608 -283.149532) (xy 64.220108 -283.197218) (xy 64.197339 -283.241893) (xy 64.167861 -283.282455)
			(xy 64.132402 -283.317907) (xy 64.091833 -283.347375) (xy 64.047153 -283.370135) (xy 63.999464 -283.385624)
			(xy 63.949938 -283.393463) (xy 63.899796 -283.393458) (xy 63.850272 -283.385609) (xy 63.802586 -283.370109)
			(xy 63.757911 -283.347341) (xy 63.717349 -283.317864) (xy 63.681896 -283.282405) (xy 63.652427 -283.241837)
			(xy 63.629667 -283.197158) (xy 63.614177 -283.149468) (xy 63.606337 -283.099943) (xy 63.605918 -283.074872)
			(xy 63.606277 -283.053455) (xy 63.612045 -283.011012) (xy 63.623461 -282.969729) (xy 63.631572 -282.949904)
			(xy 63.631826 -282.949142) (xy 63.633604 -282.94457) (xy 63.63843 -282.923234) (xy 63.63716 -282.913836)
			(xy 63.633604 -282.88742) (xy 63.6328 -282.882256) (xy 63.629349 -282.872393) (xy 63.626746 -282.867862)
			(xy 63.623488 -282.861952) (xy 63.619886 -282.848952) (xy 63.619634 -282.842208) (xy 63.619634 -282.328112)
			(xy 63.619425 -282.321531) (xy 63.616083 -282.3088) (xy 63.61303 -282.302966) (xy 63.598199 -282.275656)
			(xy 63.577138 -282.217195) (xy 63.566447 -282.155982) (xy 63.565786 -282.124912) (xy 63.566294 -282.106624)
			(xy 63.566391 -282.096318) (xy 63.559367 -282.076963) (xy 63.545302 -282.061925) (xy 63.536068 -282.057348)
			(xy 63.521717 -282.050957) (xy 63.493392 -282.037364) (xy 63.479426 -282.03017) (xy 63.47333 -282.026868)
			(xy 63.4492 -282.021534) (xy 63.437516 -282.024328) (xy 63.426086 -282.027122) (xy 63.420752 -282.029916)
			(xy 63.39455 -282.043342) (xy 63.340792 -282.067361) (xy 63.31331 -282.077922) (xy 63.303832 -282.081982)
			(xy 63.288926 -282.096199) (xy 63.280784 -282.115122) (xy 63.28029 -282.12542) (xy 63.279729 -282.150648)
			(xy 63.27135 -282.200405) (xy 63.254903 -282.248106) (xy 63.230838 -282.292455) (xy 63.199808 -282.332243)
			(xy 63.162658 -282.366388) (xy 63.1204 -282.393959) (xy 63.074184 -282.414207) (xy 63.025267 -282.426581)
			(xy 62.974982 -282.430743) (xy 62.924697 -282.426581) (xy 62.87578 -282.414207) (xy 62.829564 -282.393959)
			(xy 62.787306 -282.366388) (xy 62.750156 -282.332243) (xy 62.719126 -282.292455) (xy 62.695061 -282.248106)
			(xy 62.678614 -282.200405) (xy 62.670235 -282.150648) (xy 62.669674 -282.12542) (xy 62.669213 -282.115106)
			(xy 62.66111 -282.096138) (xy 62.646173 -282.081915) (xy 62.636654 -282.077922) (xy 62.609507 -282.067517)
			(xy 62.556385 -282.043878) (xy 62.530482 -282.030678) (xy 62.527688 -282.029408) (xy 62.517782 -282.025598)
			(xy 62.51448 -282.024836) (xy 62.501018 -282.021534) (xy 62.482476 -282.02382) (xy 62.474348 -282.028138)
			(xy 62.459108 -282.036012) (xy 62.438985 -282.046118) (xy 62.397948 -282.064669) (xy 62.377066 -282.073096)
			(xy 62.376558 -282.073096) (xy 62.376304 -282.07335) (xy 62.369776 -282.076295) (xy 62.35856 -282.08519)
			(xy 62.354206 -282.090876) (xy 62.343792 -282.105354) (xy 62.337188 -282.118054) (xy 62.330076 -282.138628)
			(xy 62.329568 -282.145486) (xy 62.327312 -282.17091) (xy 62.315413 -282.22054) (xy 62.295434 -282.267505)
			(xy 62.26793 -282.310497) (xy 62.233667 -282.348322) (xy 62.193595 -282.37993) (xy 62.148829 -282.404441)
			(xy 62.100612 -282.421174) (xy 62.050286 -282.429664) (xy 62.024768 -282.43022) (xy 62.000829 -282.429751)
			(xy 61.953538 -282.422273) (xy 61.907994 -282.407504) (xy 61.865314 -282.385808) (xy 61.826543 -282.357715)
			(xy 61.792633 -282.323915) (xy 61.764414 -282.285237) (xy 61.742578 -282.242627) (xy 61.727661 -282.197132)
			(xy 61.720029 -282.149865) (xy 61.71946 -282.125928) (xy 61.71946 -282.109418) (xy 61.701426 -282.08351)
			(xy 61.68644 -282.077922) (xy 61.66009 -282.067821) (xy 61.608496 -282.044944) (xy 61.583316 -282.032202)
			(xy 61.582554 -282.031694) (xy 61.572394 -282.026868) (xy 61.560964 -282.024328) (xy 61.555183 -282.02312)
			(xy 61.543377 -282.02312) (xy 61.537596 -282.024328) (xy 61.525912 -282.027122) (xy 61.520324 -282.029916)
			(xy 61.494186 -282.043339) (xy 61.440555 -282.067359) (xy 61.413136 -282.077922) (xy 61.403669 -282.081991)
			(xy 61.388784 -282.096213) (xy 61.380657 -282.115128) (xy 61.380116 -282.12542) (xy 61.379555 -282.150648)
			(xy 61.371176 -282.200405) (xy 61.354729 -282.248106) (xy 61.330664 -282.292455) (xy 61.299634 -282.332243)
			(xy 61.262484 -282.366388) (xy 61.220226 -282.393959) (xy 61.17401 -282.414207) (xy 61.125093 -282.426581)
			(xy 61.074808 -282.430743) (xy 61.024523 -282.426581) (xy 60.975606 -282.414207) (xy 60.92939 -282.393959)
			(xy 60.887132 -282.366388) (xy 60.849982 -282.332243) (xy 60.818952 -282.292455) (xy 60.794887 -282.248106)
			(xy 60.77844 -282.200405) (xy 60.770061 -282.150648) (xy 60.7695 -282.12542) (xy 60.769039 -282.115105)
			(xy 60.760938 -282.096134) (xy 60.746004 -282.081904) (xy 60.73648 -282.077922) (xy 60.709197 -282.067474)
			(xy 60.65582 -282.043709) (xy 60.6298 -282.030424) (xy 60.629546 -282.03017) (xy 60.622942 -282.026868)
			(xy 60.611512 -282.024328) (xy 60.599828 -282.021534) (xy 60.576206 -282.027122) (xy 60.57011 -282.03017)
			(xy 60.569856 -282.030424) (xy 60.55106 -282.039822) (xy 60.529513 -282.050297) (xy 60.48555 -282.069355)
			(xy 60.463176 -282.077922) (xy 60.44819 -282.08351) (xy 60.430156 -282.109418) (xy 60.430156 -282.125928)
			(xy 60.429609 -282.149865) (xy 60.421975 -282.197129) (xy 60.407056 -282.242623) (xy 60.385218 -282.285229)
			(xy 60.356995 -282.323904) (xy 60.323081 -282.357698) (xy 60.284307 -282.385783) (xy 60.241624 -282.407471)
			(xy 60.196078 -282.422229) (xy 60.148787 -282.429695) (xy 60.124848 -282.43022) (xy 60.100879 -282.429755)
			(xy 60.05353 -282.422271) (xy 60.007932 -282.407479) (xy 59.965206 -282.385742) (xy 59.926402 -282.357595)
			(xy 59.892474 -282.32373) (xy 59.864255 -282.284979) (xy 59.842439 -282.242293) (xy 59.827562 -282.196723)
			(xy 59.81999 -282.149388) (xy 59.81954 -282.12542) (xy 59.819078 -282.115108) (xy 59.810972 -282.096145)
			(xy 59.796032 -282.08193) (xy 59.78652 -282.077922) (xy 59.739731 -282.059713) (xy 59.649867 -282.014923)
			(xy 59.565145 -281.961036) (xy 59.525408 -281.930348) (xy 59.51601 -281.924252) (xy 59.49345 -281.91272)
			(xy 59.452178 -281.883339) (xy 59.416322 -281.847548) (xy 59.386865 -281.806329) (xy 59.375294 -281.78379)
			(xy 59.369452 -281.774392) (xy 59.340325 -281.736768) (xy 59.288801 -281.656768) (xy 59.245408 -281.572081)
			(xy 59.227466 -281.528012) (xy 59.224418 -281.520138) (xy 59.219084 -281.513788) (xy 59.214512 -281.5082)
			(xy 59.18835 -281.489658) (xy 59.187842 -281.48915) (xy 59.182 -281.485086) (xy 59.167776 -281.480006)
			(xy 59.154568 -281.479498) (xy 59.149742 -281.47899) (xy 59.148726 -281.478736) (xy 59.1185 -281.474672)
			(xy 59.106054 -281.472386) (xy 59.082178 -281.479752) (xy 59.004962 -281.556968) (xy 58.997596 -281.581098)
			(xy 58.999882 -281.59329) (xy 59.002377 -281.607318) (xy 59.005051 -281.635685) (xy 59.005216 -281.649932)
			(xy 59.004694 -281.675187) (xy 58.996381 -281.725009) (xy 58.97998 -281.772783) (xy 58.955939 -281.817206)
			(xy 58.924915 -281.857066) (xy 58.887753 -281.891276) (xy 58.845467 -281.918902) (xy 58.799211 -281.939192)
			(xy 58.750246 -281.951592) (xy 58.699908 -281.955763) (xy 58.64957 -281.951592) (xy 58.600605 -281.939192)
			(xy 58.554349 -281.918902) (xy 58.512063 -281.891276) (xy 58.474901 -281.857066) (xy 58.443877 -281.817206)
			(xy 58.419836 -281.772783) (xy 58.403435 -281.725009) (xy 58.395122 -281.675187) (xy 58.3946 -281.649932)
			(xy 58.394692 -281.640764) (xy 58.395833 -281.622464) (xy 58.396886 -281.613356) (xy 58.398156 -281.601164)
			(xy 58.390282 -281.578812) (xy 58.313828 -281.50566) (xy 58.291222 -281.498802) (xy 58.27903 -281.500834)
			(xy 58.265479 -281.502975) (xy 58.238138 -281.505267) (xy 58.22442 -281.505406) (xy 58.210898 -281.505286)
			(xy 58.183941 -281.503122) (xy 58.170572 -281.501088) (xy 58.15838 -281.499056) (xy 58.135774 -281.505914)
			(xy 58.059574 -281.579066) (xy 58.0517 -281.601164) (xy 58.05297 -281.613356) (xy 58.054025 -281.622463)
			(xy 58.055171 -281.640764) (xy 58.055256 -281.649932) (xy 58.054768 -281.674757) (xy 58.04673 -281.723752)
			(xy 58.030872 -281.770802) (xy 58.00761 -281.814666) (xy 57.977559 -281.854188) (xy 57.941509 -281.888329)
			(xy 57.900411 -281.916187) (xy 57.855347 -281.937029) (xy 57.807505 -281.950306) (xy 57.758146 -281.955668)
			(xy 57.708569 -281.952974) (xy 57.660081 -281.942295) (xy 57.613959 -281.923912) (xy 57.571419 -281.898309)
			(xy 57.533582 -281.866161) (xy 57.501444 -281.828315) (xy 57.475853 -281.785769) (xy 57.457482 -281.739643)
			(xy 57.446815 -281.691152) (xy 57.444134 -281.641574) (xy 57.449509 -281.592216) (xy 57.462799 -281.544377)
			(xy 57.483653 -281.499319) (xy 57.511522 -281.458228) (xy 57.545671 -281.422188) (xy 57.585202 -281.392147)
			(xy 57.629072 -281.368897) (xy 57.676126 -281.353051) (xy 57.725123 -281.345026) (xy 57.749948 -281.344624)
			(xy 57.758985 -281.34467) (xy 57.777031 -281.345685) (xy 57.786016 -281.346656) (xy 57.798208 -281.34818)
			(xy 57.820306 -281.340306) (xy 57.893204 -281.263852) (xy 57.900316 -281.241246) (xy 57.898284 -281.229054)
			(xy 57.896153 -281.215566) (xy 57.893865 -281.188353) (xy 57.893712 -281.174698) (xy 57.893712 -281.10434)
			(xy 57.893261 -281.093677) (xy 57.88459 -281.074196) (xy 57.876948 -281.066748) (xy 57.812686 -281.008836)
			(xy 57.792366 -281.002232) (xy 57.781698 -281.003502) (xy 57.749948 -281.005026) (xy 57.724686 -281.004537)
			(xy 57.674851 -280.996228) (xy 57.627063 -280.979829) (xy 57.582626 -280.955787) (xy 57.542753 -280.924759)
			(xy 57.508532 -280.88759) (xy 57.480896 -280.845295) (xy 57.460599 -280.799028) (xy 57.448195 -280.750051)
			(xy 57.444022 -280.6997) (xy 57.448195 -280.649349) (xy 57.460599 -280.600372) (xy 57.480896 -280.554105)
			(xy 57.508532 -280.51181) (xy 57.542753 -280.474641) (xy 57.582626 -280.443613) (xy 57.627063 -280.419571)
			(xy 57.674851 -280.403172) (xy 57.724686 -280.394863) (xy 57.749948 -280.39441) (xy 57.781444 -280.395934)
			(xy 57.792366 -280.397204) (xy 57.812432 -280.3906) (xy 57.876694 -280.332688) (xy 57.884197 -280.325141)
			(xy 57.892846 -280.305722) (xy 57.893458 -280.295096) (xy 57.893458 -280.224738) (xy 57.89362 -280.211084)
			(xy 57.895909 -280.183871) (xy 57.89803 -280.170382) (xy 57.899808 -280.158444) (xy 57.89295 -280.135838)
			(xy 57.820052 -280.059638) (xy 57.797954 -280.05151) (xy 57.785762 -280.053034) (xy 57.77684 -280.053998)
			(xy 57.758922 -280.055017) (xy 57.749948 -280.055066) (xy 57.724691 -280.054577) (xy 57.674865 -280.04627)
			(xy 57.627087 -280.029874) (xy 57.582659 -280.005837) (xy 57.542794 -279.974815) (xy 57.508579 -279.937653)
			(xy 57.480948 -279.895367) (xy 57.460655 -279.849109) (xy 57.448254 -279.800141) (xy 57.444082 -279.7498)
			(xy 57.448254 -279.699459) (xy 57.460655 -279.650491) (xy 57.480948 -279.604233) (xy 57.508579 -279.561947)
			(xy 57.542794 -279.524785) (xy 57.582659 -279.493763) (xy 57.627087 -279.469726) (xy 57.674865 -279.45333)
			(xy 57.724691 -279.445023) (xy 57.749948 -279.44445) (xy 57.764131 -279.444634) (xy 57.792371 -279.447303)
			(xy 57.806336 -279.449784) (xy 57.818782 -279.45207) (xy 57.842404 -279.444704) (xy 57.919874 -279.367234)
			(xy 57.92724 -279.343612) (xy 57.924954 -279.331166) (xy 57.92247 -279.317201) (xy 57.919799 -279.288961)
			(xy 57.91962 -279.274778) (xy 57.919808 -279.260596) (xy 57.922483 -279.232357) (xy 57.924954 -279.21839)
			(xy 57.92724 -279.205944) (xy 57.919874 -279.182322) (xy 57.842404 -279.104852) (xy 57.818782 -279.097486)
			(xy 57.806336 -279.099772) (xy 57.792371 -279.102255) (xy 57.764131 -279.104922) (xy 57.749948 -279.105106)
			(xy 57.724688 -279.104617) (xy 57.674856 -279.096309) (xy 57.627071 -279.079911) (xy 57.582637 -279.055871)
			(xy 57.542767 -279.024844) (xy 57.508547 -278.987678) (xy 57.480913 -278.945386) (xy 57.460618 -278.899122)
			(xy 57.448214 -278.850148) (xy 57.444042 -278.7998) (xy 57.448214 -278.749452) (xy 57.460618 -278.700478)
			(xy 57.480913 -278.654214) (xy 57.508547 -278.611922) (xy 57.542767 -278.574756) (xy 57.582637 -278.543729)
			(xy 57.627071 -278.519689) (xy 57.674856 -278.503291) (xy 57.724688 -278.494983) (xy 57.749948 -278.49449)
			(xy 57.764131 -278.494674) (xy 57.792371 -278.497343) (xy 57.806336 -278.499824) (xy 57.818782 -278.50211)
			(xy 57.842404 -278.494744) (xy 57.919874 -278.417274) (xy 57.92724 -278.393652) (xy 57.924954 -278.381206)
			(xy 57.922468 -278.367241) (xy 57.919794 -278.339001) (xy 57.91962 -278.324818) (xy 57.919806 -278.310635)
			(xy 57.922478 -278.282396) (xy 57.924954 -278.26843) (xy 57.92724 -278.255984) (xy 57.919874 -278.232362)
			(xy 57.842404 -278.154892) (xy 57.818782 -278.147526) (xy 57.806336 -278.149812) (xy 57.792371 -278.152295)
			(xy 57.764131 -278.154962) (xy 57.749948 -278.155146) (xy 57.724685 -278.154657) (xy 57.674846 -278.146348)
			(xy 57.627055 -278.129947) (xy 57.582615 -278.105904) (xy 57.54274 -278.074874) (xy 57.508516 -278.037702)
			(xy 57.480878 -277.995405) (xy 57.46058 -277.949134) (xy 57.448175 -277.900154) (xy 57.444002 -277.8498)
			(xy 57.448175 -277.799446) (xy 57.46058 -277.750465) (xy 57.480878 -277.704195) (xy 57.508516 -277.661898)
			(xy 57.54274 -277.624726) (xy 57.582615 -277.593696) (xy 57.627055 -277.569653) (xy 57.674846 -277.553252)
			(xy 57.724685 -277.544943) (xy 57.749948 -277.54453) (xy 57.764131 -277.544714) (xy 57.792371 -277.547383)
			(xy 57.806336 -277.549864) (xy 57.818782 -277.55215) (xy 57.842404 -277.544784) (xy 57.919874 -277.467314)
			(xy 57.92724 -277.443692) (xy 57.924954 -277.431246) (xy 57.92247 -277.417281) (xy 57.919802 -277.389041)
			(xy 57.91962 -277.374858) (xy 57.919804 -277.360675) (xy 57.922472 -277.332435) (xy 57.924954 -277.31847)
			(xy 57.92724 -277.306024) (xy 57.919874 -277.282402) (xy 57.842404 -277.204932) (xy 57.818782 -277.197566)
			(xy 57.806336 -277.199852) (xy 57.792371 -277.202335) (xy 57.764131 -277.205002) (xy 57.749948 -277.205186)
			(xy 57.724689 -277.204697) (xy 57.67486 -277.196389) (xy 57.627079 -277.179993) (xy 57.582648 -277.155954)
			(xy 57.54278 -277.124929) (xy 57.508563 -277.087766) (xy 57.480931 -277.045476) (xy 57.460636 -276.999215)
			(xy 57.448234 -276.950244) (xy 57.444062 -276.8999) (xy 57.448234 -276.849556) (xy 57.460636 -276.800585)
			(xy 57.480931 -276.754324) (xy 57.508563 -276.712034) (xy 57.54278 -276.674871) (xy 57.582648 -276.643846)
			(xy 57.627079 -276.619807) (xy 57.67486 -276.603411) (xy 57.724689 -276.595103) (xy 57.749948 -276.59457)
			(xy 57.764131 -276.594754) (xy 57.792371 -276.597423) (xy 57.806336 -276.599904) (xy 57.818782 -276.60219)
			(xy 57.842404 -276.594824) (xy 57.919874 -276.517354) (xy 57.92724 -276.493732) (xy 57.924954 -276.481286)
			(xy 57.922469 -276.467321) (xy 57.919796 -276.439081) (xy 57.91962 -276.424898) (xy 57.919807 -276.410716)
			(xy 57.922481 -276.382476) (xy 57.924954 -276.36851) (xy 57.92724 -276.356064) (xy 57.919874 -276.332442)
			(xy 57.842404 -276.254972) (xy 57.818782 -276.247606) (xy 57.806336 -276.249892) (xy 57.792371 -276.252375)
			(xy 57.764131 -276.255042) (xy 57.749948 -276.255226) (xy 57.724686 -276.254737) (xy 57.674851 -276.246428)
			(xy 57.627063 -276.230029) (xy 57.582626 -276.205987) (xy 57.542753 -276.174959) (xy 57.508532 -276.13779)
			(xy 57.480896 -276.095495) (xy 57.460599 -276.049228) (xy 57.448195 -276.000251) (xy 57.444022 -275.9499)
			(xy 57.448195 -275.899549) (xy 57.460599 -275.850572) (xy 57.480896 -275.804305) (xy 57.508532 -275.76201)
			(xy 57.542753 -275.724841) (xy 57.582626 -275.693813) (xy 57.627063 -275.669771) (xy 57.674851 -275.653372)
			(xy 57.724686 -275.645063) (xy 57.749948 -275.64461) (xy 57.758985 -275.644656) (xy 57.777031 -275.645671)
			(xy 57.786016 -275.646642) (xy 57.798208 -275.648166) (xy 57.820306 -275.640292) (xy 57.893204 -275.563838)
			(xy 57.900316 -275.541232) (xy 57.898284 -275.52904) (xy 57.896154 -275.515552) (xy 57.893867 -275.488339)
			(xy 57.893712 -275.474684) (xy 57.893712 -275.40458) (xy 57.893249 -275.393923) (xy 57.884563 -275.374459)
			(xy 57.876948 -275.366988) (xy 57.812686 -275.309076) (xy 57.792366 -275.302472) (xy 57.781698 -275.303742)
			(xy 57.749948 -275.305266) (xy 57.724691 -275.304777) (xy 57.674865 -275.29647) (xy 57.627087 -275.280074)
			(xy 57.582659 -275.256037) (xy 57.542794 -275.225015) (xy 57.508579 -275.187853) (xy 57.480948 -275.145567)
			(xy 57.460655 -275.099309) (xy 57.448254 -275.050341) (xy 57.444082 -275) (xy 57.448254 -274.949659)
			(xy 57.460655 -274.900691) (xy 57.480948 -274.854433) (xy 57.508579 -274.812147) (xy 57.542794 -274.774985)
			(xy 57.582659 -274.743963) (xy 57.627087 -274.719926) (xy 57.674865 -274.70353) (xy 57.724691 -274.695223)
			(xy 57.749948 -274.69465) (xy 57.781698 -274.696174) (xy 57.792366 -274.697444) (xy 57.812686 -274.69084)
			(xy 57.876948 -274.632928) (xy 57.884463 -274.625386) (xy 57.893135 -274.605966) (xy 57.893712 -274.595336)
			(xy 57.893712 -274.524724) (xy 57.893754 -274.51537) (xy 57.894769 -274.496689) (xy 57.895744 -274.487386)
			(xy 57.897014 -274.475956) (xy 57.889648 -274.454112) (xy 57.817512 -274.381468) (xy 57.795922 -274.373848)
			(xy 57.784238 -274.374864) (xy 57.749948 -274.376896) (xy 57.724232 -274.376421) (xy 57.673433 -274.368382)
			(xy 57.624517 -274.352495) (xy 57.578689 -274.32915) (xy 57.537078 -274.298923) (xy 57.500708 -274.262559)
			(xy 57.470475 -274.220952) (xy 57.447123 -274.175127) (xy 57.431229 -274.126214) (xy 57.423182 -274.075416)
			(xy 57.423182 -274.023984) (xy 57.431229 -273.973186) (xy 57.447123 -273.924273) (xy 57.470475 -273.878448)
			(xy 57.500708 -273.836841) (xy 57.537078 -273.800476) (xy 57.578689 -273.77025) (xy 57.624517 -273.746905)
			(xy 57.673433 -273.731018) (xy 57.724232 -273.722979) (xy 57.749948 -273.722592) (xy 57.763672 -273.722785)
			(xy 57.791013 -273.725202) (xy 57.804558 -273.727418) (xy 57.816496 -273.729196) (xy 57.839356 -273.722338)
			(xy 57.91581 -273.648678) (xy 57.923684 -273.626072) (xy 57.92216 -273.614134) (xy 57.920965 -273.604336)
			(xy 57.919696 -273.584635) (xy 57.91962 -273.574764) (xy 57.919699 -273.564893) (xy 57.920968 -273.545193)
			(xy 57.92216 -273.535394) (xy 57.923684 -273.523456) (xy 57.91581 -273.50085) (xy 57.839356 -273.42719)
			(xy 57.816496 -273.420332) (xy 57.804558 -273.42211) (xy 57.791011 -273.424312) (xy 57.763671 -273.426729)
			(xy 57.749948 -273.426936) (xy 57.724237 -273.426461) (xy 57.673447 -273.418424) (xy 57.62454 -273.40254)
			(xy 57.578721 -273.379199) (xy 57.537117 -273.348978) (xy 57.500753 -273.31262) (xy 57.470526 -273.27102)
			(xy 57.447179 -273.225204) (xy 57.431287 -273.1763) (xy 57.423242 -273.125511) (xy 57.423242 -273.074089)
			(xy 57.431287 -273.0233) (xy 57.447179 -272.974396) (xy 57.470526 -272.92858) (xy 57.500753 -272.88698)
			(xy 57.537117 -272.850622) (xy 57.578721 -272.820401) (xy 57.62454 -272.79706) (xy 57.673447 -272.781176)
			(xy 57.724237 -272.773139) (xy 57.749948 -272.772632) (xy 57.763672 -272.772825) (xy 57.791013 -272.775242)
			(xy 57.804558 -272.777458) (xy 57.816496 -272.779236) (xy 57.839356 -272.772378) (xy 57.91581 -272.698718)
			(xy 57.923684 -272.676112) (xy 57.92216 -272.664174) (xy 57.920964 -272.654376) (xy 57.919692 -272.634675)
			(xy 57.91962 -272.624804) (xy 57.919795 -272.610558) (xy 57.922463 -272.58219) (xy 57.924954 -272.568162)
			(xy 57.92724 -272.55597) (xy 57.919874 -272.53184) (xy 57.842658 -272.454624) (xy 57.818528 -272.447258)
			(xy 57.806336 -272.449544) (xy 57.792309 -272.452041) (xy 57.763941 -272.454709) (xy 57.749694 -272.454878)
			(xy 57.724441 -272.454356) (xy 57.674625 -272.446042) (xy 57.626857 -272.429643) (xy 57.58244 -272.405604)
			(xy 57.542584 -272.374583) (xy 57.508378 -272.337425) (xy 57.480755 -272.295144) (xy 57.460468 -272.248892)
			(xy 57.44807 -272.199933) (xy 57.443899 -272.1496) (xy 57.44807 -272.099267) (xy 57.460468 -272.050308)
			(xy 57.480755 -272.004056) (xy 57.508378 -271.961775) (xy 57.542584 -271.924617) (xy 57.58244 -271.893596)
			(xy 57.626857 -271.869557) (xy 57.674625 -271.853158) (xy 57.724441 -271.844844) (xy 57.749694 -271.844262)
			(xy 57.776186 -271.844827) (xy 57.828377 -271.853965) (xy 57.87821 -271.871969) (xy 57.92419 -271.898299)
			(xy 57.964939 -271.932165) (xy 57.999235 -271.972552) (xy 58.013092 -271.995138) (xy 58.01995 -272.006822)
			(xy 58.043318 -272.020284) (xy 58.05678 -272.020284) (xy 58.066803 -272.019868) (xy 58.085324 -272.012201)
			(xy 58.099499 -271.998027) (xy 58.107167 -271.979507) (xy 58.10758 -271.969484) (xy 58.10758 -271.841976)
			(xy 58.104278 -271.833086) (xy 58.08802 -271.789827) (xy 58.06264 -271.70096) (xy 58.045583 -271.610128)
			(xy 58.036994 -271.518108) (xy 58.03646 -271.471898) (xy 58.03646 -266.15644) (xy 58.03643 -266.152304)
			(xy 58.03516 -266.14413) (xy 58.03392 -266.140184) (xy 55.218584 -257.822954) (xy 55.21658 -257.817428)
			(xy 55.210426 -257.807417) (xy 55.206392 -257.803142) (xy 51.564032 -254.160782) (xy 51.556634 -254.153937)
			(xy 51.538035 -254.146215) (xy 51.527964 -254.145796) (xy 46.564042 -254.145796) (xy 46.557005 -254.145567)
			(xy 46.543474 -254.14169) (xy 46.537372 -254.138176) (xy 46.531276 -254.13462) (xy 46.524926 -254.132842)
			(xy 46.510956 -254.13081) (xy 1.72085 -254.13081) (xy 1.702054 -254.13843) (xy 1.694942 -254.145796)
			(xy 1.48336 -254.357378) (xy 1.47652 -254.364778) (xy 1.468804 -254.383377) (xy 1.468374 -254.393446)
			(xy 1.468374 -255.732026) (xy 3.944364 -255.732026) (xy 3.948435 -255.676404) (xy 3.960561 -255.621967)
			(xy 3.980484 -255.569876) (xy 4.00778 -255.521241) (xy 4.041866 -255.477098) (xy 4.082015 -255.438389)
			(xy 4.127373 -255.405938) (xy 4.176973 -255.380437) (xy 4.229757 -255.36243) (xy 4.2846 -255.3523)
			(xy 4.340334 -255.350263) (xy 4.395771 -255.356363) (xy 4.449728 -255.370469) (xy 4.501057 -255.392281)
			(xy 4.548663 -255.421335) (xy 4.591531 -255.45701) (xy 4.628748 -255.498547) (xy 4.659521 -255.54506)
			(xy 4.683193 -255.595557) (xy 4.692308 -255.625854) (xy 5.829806 -255.625854) (xy 5.833877 -255.570232)
			(xy 5.846003 -255.515795) (xy 5.865926 -255.463704) (xy 5.893222 -255.415069) (xy 5.927308 -255.370926)
			(xy 5.967457 -255.332217) (xy 6.012815 -255.299766) (xy 6.062415 -255.274265) (xy 6.115199 -255.256258)
			(xy 6.170042 -255.246128) (xy 6.225776 -255.244091) (xy 6.281213 -255.250191) (xy 6.33517 -255.264297)
			(xy 6.386499 -255.286109) (xy 6.434105 -255.315163) (xy 6.476973 -255.350838) (xy 6.51419 -255.392375)
			(xy 6.544963 -255.438888) (xy 6.568635 -255.489385) (xy 6.584703 -255.542792) (xy 6.592823 -255.597968)
			(xy 6.593332 -255.625854) (xy 6.592831 -255.653286) (xy 7.359648 -255.653286) (xy 7.363719 -255.597664)
			(xy 7.375845 -255.543227) (xy 7.395768 -255.491136) (xy 7.423064 -255.442501) (xy 7.45715 -255.398358)
			(xy 7.497299 -255.359649) (xy 7.542657 -255.327198) (xy 7.592257 -255.301697) (xy 7.645041 -255.28369)
			(xy 7.699884 -255.27356) (xy 7.755618 -255.271523) (xy 7.811055 -255.277623) (xy 7.865012 -255.291729)
			(xy 7.916341 -255.313541) (xy 7.963947 -255.342595) (xy 8.006815 -255.37827) (xy 8.044032 -255.419807)
			(xy 8.074805 -255.46632) (xy 8.098477 -255.516817) (xy 8.114545 -255.570224) (xy 8.119741 -255.605534)
			(xy 8.896348 -255.605534) (xy 8.900419 -255.549912) (xy 8.912545 -255.495475) (xy 8.932468 -255.443384)
			(xy 8.959764 -255.394749) (xy 8.99385 -255.350606) (xy 9.033999 -255.311897) (xy 9.079357 -255.279446)
			(xy 9.128957 -255.253945) (xy 9.181741 -255.235938) (xy 9.236584 -255.225808) (xy 9.292318 -255.223771)
			(xy 9.347755 -255.229871) (xy 9.401712 -255.243977) (xy 9.453041 -255.265789) (xy 9.500647 -255.294843)
			(xy 9.543515 -255.330518) (xy 9.580732 -255.372055) (xy 9.611505 -255.418568) (xy 9.635177 -255.469065)
			(xy 9.651245 -255.522472) (xy 9.659365 -255.577648) (xy 9.659874 -255.605534) (xy 9.659365 -255.63342)
			(xy 9.651245 -255.688596) (xy 9.644369 -255.711452) (xy 10.405362 -255.711452) (xy 10.409433 -255.65583)
			(xy 10.421559 -255.601393) (xy 10.441482 -255.549302) (xy 10.468778 -255.500667) (xy 10.502864 -255.456524)
			(xy 10.543013 -255.417815) (xy 10.588371 -255.385364) (xy 10.637971 -255.359863) (xy 10.690755 -255.341856)
			(xy 10.745598 -255.331726) (xy 10.801332 -255.329689) (xy 10.856769 -255.335789) (xy 10.910726 -255.349895)
			(xy 10.962055 -255.371707) (xy 11.009661 -255.400761) (xy 11.052529 -255.436436) (xy 11.089746 -255.477973)
			(xy 11.120519 -255.524486) (xy 11.144191 -255.574983) (xy 11.160259 -255.62839) (xy 11.16396 -255.65354)
			(xy 11.983464 -255.65354) (xy 11.987535 -255.597918) (xy 11.999661 -255.543481) (xy 12.019584 -255.49139)
			(xy 12.04688 -255.442755) (xy 12.080966 -255.398612) (xy 12.121115 -255.359903) (xy 12.166473 -255.327452)
			(xy 12.216073 -255.301951) (xy 12.268857 -255.283944) (xy 12.3237 -255.273814) (xy 12.379434 -255.271777)
			(xy 12.434871 -255.277877) (xy 12.488828 -255.291983) (xy 12.540157 -255.313795) (xy 12.587763 -255.342849)
			(xy 12.630631 -255.378524) (xy 12.667848 -255.420061) (xy 12.698621 -255.466574) (xy 12.722293 -255.517071)
			(xy 12.738361 -255.570478) (xy 12.746481 -255.625654) (xy 12.74699 -255.65354) (xy 12.746481 -255.681426)
			(xy 12.738361 -255.736602) (xy 12.722293 -255.790009) (xy 12.698621 -255.840506) (xy 12.667848 -255.887019)
			(xy 12.64673 -255.910588) (xy 21.87651 -255.910588) (xy 21.880581 -255.854966) (xy 21.892707 -255.800529)
			(xy 21.91263 -255.748438) (xy 21.939926 -255.699803) (xy 21.974012 -255.65566) (xy 22.014161 -255.616951)
			(xy 22.059519 -255.5845) (xy 22.109119 -255.558999) (xy 22.161903 -255.540992) (xy 22.216746 -255.530862)
			(xy 22.27248 -255.528825) (xy 22.327917 -255.534925) (xy 22.381874 -255.549031) (xy 22.433203 -255.570843)
			(xy 22.480809 -255.599897) (xy 22.523677 -255.635572) (xy 22.558963 -255.674954) (xy 22.765453 -255.674954)
			(xy 22.765453 -255.620446) (xy 22.773211 -255.566494) (xy 22.788567 -255.514195) (xy 22.811211 -255.464614)
			(xy 22.84068 -255.41876) (xy 22.876375 -255.377567) (xy 22.91757 -255.341873) (xy 22.963424 -255.312405)
			(xy 23.013006 -255.289763) (xy 23.065306 -255.274408) (xy 23.119258 -255.266653) (xy 23.146512 -255.26619)
			(xy 23.176121 -255.266801) (xy 23.23463 -255.275939) (xy 23.291025 -255.29401) (xy 23.343949 -255.320578)
			(xy 23.392131 -255.355006) (xy 23.434414 -255.396466) (xy 23.469782 -255.443963) (xy 23.484078 -255.469898)
			(xy 23.491605 -255.482931) (xy 23.512833 -255.504246) (xy 23.539345 -255.518463) (xy 23.568845 -255.524353)
			(xy 23.598783 -255.521405) (xy 23.626568 -255.509874) (xy 23.649797 -255.490759) (xy 23.658576 -255.478534)
			(xy 23.673758 -255.456285) (xy 23.709456 -255.415951) (xy 23.750471 -255.381036) (xy 23.795986 -255.352233)
			(xy 23.845098 -255.330115) (xy 23.896832 -255.31512) (xy 23.95016 -255.307547) (xy 23.977092 -255.307084)
			(xy 24.004345 -255.307563) (xy 24.058295 -255.315319) (xy 24.110593 -255.330674) (xy 24.160173 -255.353315)
			(xy 24.206026 -255.382782) (xy 24.247219 -255.418475) (xy 24.282913 -255.459667) (xy 24.312381 -255.50552)
			(xy 24.335024 -255.555099) (xy 24.35038 -255.607397) (xy 24.358137 -255.661347) (xy 24.358137 -255.715853)
			(xy 24.35038 -255.769803) (xy 24.335024 -255.822101) (xy 24.312381 -255.87168) (xy 24.282913 -255.917533)
			(xy 24.247219 -255.958725) (xy 24.206026 -255.994418) (xy 24.160173 -256.023885) (xy 24.110593 -256.046526)
			(xy 24.058295 -256.061881) (xy 24.004345 -256.069637) (xy 23.977092 -256.0701) (xy 23.947483 -256.06949)
			(xy 23.888973 -256.060353) (xy 23.832579 -256.042282) (xy 23.779655 -256.015714) (xy 23.731472 -255.981286)
			(xy 23.68919 -255.939825) (xy 23.653822 -255.892327) (xy 23.639526 -255.866392) (xy 23.631993 -255.853363)
			(xy 23.610765 -255.83205) (xy 23.584256 -255.817834) (xy 23.554757 -255.811945) (xy 23.524821 -255.814892)
			(xy 23.497037 -255.82642) (xy 23.473808 -255.845532) (xy 23.465028 -255.857756) (xy 23.44984 -255.88)
			(xy 23.414143 -255.920335) (xy 23.37313 -255.955251) (xy 23.327616 -255.984055) (xy 23.278504 -256.006174)
			(xy 23.226771 -256.021169) (xy 23.173443 -256.028743) (xy 23.146512 -256.029206) (xy 23.119258 -256.028747)
			(xy 23.065306 -256.020992) (xy 23.013006 -256.005637) (xy 22.963424 -255.982995) (xy 22.91757 -255.953527)
			(xy 22.876375 -255.917833) (xy 22.84068 -255.87664) (xy 22.811211 -255.830786) (xy 22.788567 -255.781205)
			(xy 22.773211 -255.728906) (xy 22.765453 -255.674954) (xy 22.558963 -255.674954) (xy 22.560894 -255.677109)
			(xy 22.591667 -255.723622) (xy 22.615339 -255.774119) (xy 22.631407 -255.827526) (xy 22.639527 -255.882702)
			(xy 22.640036 -255.910588) (xy 22.639527 -255.938474) (xy 22.631407 -255.99365) (xy 22.615339 -256.047057)
			(xy 22.591667 -256.097554) (xy 22.560894 -256.144067) (xy 22.523677 -256.185604) (xy 22.480809 -256.221279)
			(xy 22.433203 -256.250333) (xy 22.381874 -256.272145) (xy 22.327917 -256.286251) (xy 22.27248 -256.292351)
			(xy 22.216746 -256.290314) (xy 22.161903 -256.280184) (xy 22.109119 -256.262177) (xy 22.059519 -256.236676)
			(xy 22.014161 -256.204225) (xy 21.974012 -256.165516) (xy 21.939926 -256.121373) (xy 21.91263 -256.072738)
			(xy 21.892707 -256.020647) (xy 21.880581 -255.96621) (xy 21.87651 -255.910588) (xy 12.64673 -255.910588)
			(xy 12.630631 -255.928556) (xy 12.587763 -255.964231) (xy 12.540157 -255.993285) (xy 12.488828 -256.015097)
			(xy 12.434871 -256.029203) (xy 12.379434 -256.035303) (xy 12.3237 -256.033266) (xy 12.268857 -256.023136)
			(xy 12.216073 -256.005129) (xy 12.166473 -255.979628) (xy 12.121115 -255.947177) (xy 12.080966 -255.908468)
			(xy 12.04688 -255.864325) (xy 12.019584 -255.81569) (xy 11.999661 -255.763599) (xy 11.987535 -255.709162)
			(xy 11.983464 -255.65354) (xy 11.16396 -255.65354) (xy 11.168379 -255.683566) (xy 11.168888 -255.711452)
			(xy 11.168379 -255.739338) (xy 11.160259 -255.794514) (xy 11.144191 -255.847921) (xy 11.120519 -255.898418)
			(xy 11.089746 -255.944931) (xy 11.052529 -255.986468) (xy 11.009661 -256.022143) (xy 10.962055 -256.051197)
			(xy 10.910726 -256.073009) (xy 10.856769 -256.087115) (xy 10.801332 -256.093215) (xy 10.745598 -256.091178)
			(xy 10.690755 -256.081048) (xy 10.637971 -256.063041) (xy 10.588371 -256.03754) (xy 10.543013 -256.005089)
			(xy 10.502864 -255.96638) (xy 10.468778 -255.922237) (xy 10.441482 -255.873602) (xy 10.421559 -255.821511)
			(xy 10.409433 -255.767074) (xy 10.405362 -255.711452) (xy 9.644369 -255.711452) (xy 9.635177 -255.742003)
			(xy 9.611505 -255.7925) (xy 9.580732 -255.839013) (xy 9.543515 -255.88055) (xy 9.500647 -255.916225)
			(xy 9.453041 -255.945279) (xy 9.401712 -255.967091) (xy 9.347755 -255.981197) (xy 9.292318 -255.987297)
			(xy 9.236584 -255.98526) (xy 9.181741 -255.97513) (xy 9.128957 -255.957123) (xy 9.079357 -255.931622)
			(xy 9.033999 -255.899171) (xy 8.99385 -255.860462) (xy 8.959764 -255.816319) (xy 8.932468 -255.767684)
			(xy 8.912545 -255.715593) (xy 8.900419 -255.661156) (xy 8.896348 -255.605534) (xy 8.119741 -255.605534)
			(xy 8.122665 -255.6254) (xy 8.123174 -255.653286) (xy 8.122665 -255.681172) (xy 8.114545 -255.736348)
			(xy 8.098477 -255.789755) (xy 8.074805 -255.840252) (xy 8.044032 -255.886765) (xy 8.006815 -255.928302)
			(xy 7.963947 -255.963977) (xy 7.916341 -255.993031) (xy 7.865012 -256.014843) (xy 7.811055 -256.028949)
			(xy 7.755618 -256.035049) (xy 7.699884 -256.033012) (xy 7.645041 -256.022882) (xy 7.592257 -256.004875)
			(xy 7.542657 -255.979374) (xy 7.497299 -255.946923) (xy 7.45715 -255.908214) (xy 7.423064 -255.864071)
			(xy 7.395768 -255.815436) (xy 7.375845 -255.763345) (xy 7.363719 -255.708908) (xy 7.359648 -255.653286)
			(xy 6.592831 -255.653286) (xy 6.592823 -255.65374) (xy 6.584703 -255.708916) (xy 6.568635 -255.762323)
			(xy 6.544963 -255.81282) (xy 6.51419 -255.859333) (xy 6.476973 -255.90087) (xy 6.434105 -255.936545)
			(xy 6.386499 -255.965599) (xy 6.33517 -255.987411) (xy 6.281213 -256.001517) (xy 6.225776 -256.007617)
			(xy 6.170042 -256.00558) (xy 6.115199 -255.99545) (xy 6.062415 -255.977443) (xy 6.012815 -255.951942)
			(xy 5.967457 -255.919491) (xy 5.927308 -255.880782) (xy 5.893222 -255.836639) (xy 5.865926 -255.788004)
			(xy 5.846003 -255.735913) (xy 5.833877 -255.681476) (xy 5.829806 -255.625854) (xy 4.692308 -255.625854)
			(xy 4.699261 -255.648964) (xy 4.707381 -255.70414) (xy 4.70789 -255.732026) (xy 4.707381 -255.759912)
			(xy 4.699261 -255.815088) (xy 4.683193 -255.868495) (xy 4.659521 -255.918992) (xy 4.628748 -255.965505)
			(xy 4.591531 -256.007042) (xy 4.548663 -256.042717) (xy 4.501057 -256.071771) (xy 4.449728 -256.093583)
			(xy 4.395771 -256.107689) (xy 4.340334 -256.113789) (xy 4.2846 -256.111752) (xy 4.229757 -256.101622)
			(xy 4.176973 -256.083615) (xy 4.127373 -256.058114) (xy 4.082015 -256.025663) (xy 4.041866 -255.986954)
			(xy 4.00778 -255.942811) (xy 3.980484 -255.894176) (xy 3.960561 -255.842085) (xy 3.948435 -255.787648)
			(xy 3.944364 -255.732026) (xy 1.468374 -255.732026) (xy 1.468374 -256.516124) (xy 3.26466 -256.516124)
			(xy 3.268731 -256.460502) (xy 3.280857 -256.406065) (xy 3.30078 -256.353974) (xy 3.328076 -256.305339)
			(xy 3.362162 -256.261196) (xy 3.402311 -256.222487) (xy 3.447669 -256.190036) (xy 3.497269 -256.164535)
			(xy 3.550053 -256.146528) (xy 3.604896 -256.136398) (xy 3.66063 -256.134361) (xy 3.716067 -256.140461)
			(xy 3.770024 -256.154567) (xy 3.821353 -256.176379) (xy 3.868959 -256.205433) (xy 3.911827 -256.241108)
			(xy 3.949044 -256.282645) (xy 3.979817 -256.329158) (xy 4.003489 -256.379655) (xy 4.019557 -256.433062)
			(xy 4.025875 -256.475992) (xy 4.752846 -256.475992) (xy 4.756917 -256.42037) (xy 4.769043 -256.365933)
			(xy 4.788966 -256.313842) (xy 4.816262 -256.265207) (xy 4.850348 -256.221064) (xy 4.890497 -256.182355)
			(xy 4.935855 -256.149904) (xy 4.985455 -256.124403) (xy 5.038239 -256.106396) (xy 5.093082 -256.096266)
			(xy 5.148816 -256.094229) (xy 5.204253 -256.100329) (xy 5.25821 -256.114435) (xy 5.309539 -256.136247)
			(xy 5.357145 -256.165301) (xy 5.400013 -256.200976) (xy 5.43723 -256.242513) (xy 5.468003 -256.289026)
			(xy 5.491675 -256.339523) (xy 5.507743 -256.39293) (xy 5.515863 -256.448106) (xy 5.516372 -256.475992)
			(xy 5.515863 -256.503878) (xy 5.511108 -256.53619) (xy 6.261352 -256.53619) (xy 6.265423 -256.480568)
			(xy 6.277549 -256.426131) (xy 6.297472 -256.37404) (xy 6.324768 -256.325405) (xy 6.358854 -256.281262)
			(xy 6.399003 -256.242553) (xy 6.444361 -256.210102) (xy 6.493961 -256.184601) (xy 6.546745 -256.166594)
			(xy 6.601588 -256.156464) (xy 6.657322 -256.154427) (xy 6.712759 -256.160527) (xy 6.766716 -256.174633)
			(xy 6.818045 -256.196445) (xy 6.865651 -256.225499) (xy 6.908519 -256.261174) (xy 6.945736 -256.302711)
			(xy 6.976509 -256.349224) (xy 7.000181 -256.399721) (xy 7.016249 -256.453128) (xy 7.019614 -256.475992)
			(xy 7.769604 -256.475992) (xy 7.773675 -256.42037) (xy 7.785801 -256.365933) (xy 7.805724 -256.313842)
			(xy 7.83302 -256.265207) (xy 7.867106 -256.221064) (xy 7.907255 -256.182355) (xy 7.952613 -256.149904)
			(xy 8.002213 -256.124403) (xy 8.054997 -256.106396) (xy 8.10984 -256.096266) (xy 8.165574 -256.094229)
			(xy 8.221011 -256.100329) (xy 8.274968 -256.114435) (xy 8.326297 -256.136247) (xy 8.373903 -256.165301)
			(xy 8.416771 -256.200976) (xy 8.453988 -256.242513) (xy 8.484761 -256.289026) (xy 8.508433 -256.339523)
			(xy 8.513192 -256.355342) (xy 9.479024 -256.355342) (xy 9.483095 -256.29972) (xy 9.495221 -256.245283)
			(xy 9.515144 -256.193192) (xy 9.54244 -256.144557) (xy 9.576526 -256.100414) (xy 9.616675 -256.061705)
			(xy 9.662033 -256.029254) (xy 9.711633 -256.003753) (xy 9.764417 -255.985746) (xy 9.81926 -255.975616)
			(xy 9.874994 -255.973579) (xy 9.930431 -255.979679) (xy 9.984388 -255.993785) (xy 10.035717 -256.015597)
			(xy 10.083323 -256.044651) (xy 10.126191 -256.080326) (xy 10.163408 -256.121863) (xy 10.194181 -256.168376)
			(xy 10.217853 -256.218873) (xy 10.233921 -256.27228) (xy 10.242041 -256.327456) (xy 10.24255 -256.355342)
			(xy 10.242041 -256.383228) (xy 10.237286 -256.41554) (xy 11.047728 -256.41554) (xy 11.051799 -256.359918)
			(xy 11.063925 -256.305481) (xy 11.083848 -256.25339) (xy 11.111144 -256.204755) (xy 11.14523 -256.160612)
			(xy 11.185379 -256.121903) (xy 11.230737 -256.089452) (xy 11.280337 -256.063951) (xy 11.333121 -256.045944)
			(xy 11.387964 -256.035814) (xy 11.443698 -256.033777) (xy 11.499135 -256.039877) (xy 11.553092 -256.053983)
			(xy 11.604421 -256.075795) (xy 11.652027 -256.104849) (xy 11.694895 -256.140524) (xy 11.732112 -256.182061)
			(xy 11.762885 -256.228574) (xy 11.786557 -256.279071) (xy 11.802625 -256.332478) (xy 11.810745 -256.387654)
			(xy 11.811254 -256.41554) (xy 11.810888 -256.435606) (xy 12.455396 -256.435606) (xy 12.459467 -256.379984)
			(xy 12.471593 -256.325547) (xy 12.491516 -256.273456) (xy 12.518812 -256.224821) (xy 12.552898 -256.180678)
			(xy 12.593047 -256.141969) (xy 12.638405 -256.109518) (xy 12.688005 -256.084017) (xy 12.740789 -256.06601)
			(xy 12.795632 -256.05588) (xy 12.851366 -256.053843) (xy 12.906803 -256.059943) (xy 12.96076 -256.074049)
			(xy 13.012089 -256.095861) (xy 13.059695 -256.124915) (xy 13.102563 -256.16059) (xy 13.13978 -256.202127)
			(xy 13.170553 -256.24864) (xy 13.194225 -256.299137) (xy 13.210293 -256.352544) (xy 13.218413 -256.40772)
			(xy 13.218922 -256.435606) (xy 13.218413 -256.463492) (xy 13.216039 -256.479621) (xy 25.279328 -256.479621)
			(xy 25.279328 -256.425119) (xy 25.287084 -256.371171) (xy 25.302439 -256.318876) (xy 25.325081 -256.269299)
			(xy 25.354547 -256.223449) (xy 25.390238 -256.182258) (xy 25.431429 -256.146567) (xy 25.477279 -256.117101)
			(xy 25.526856 -256.094459) (xy 25.579151 -256.079104) (xy 25.633099 -256.071348) (xy 25.66035 -256.070862)
			(xy 25.686666 -256.071314) (xy 25.7388 -256.078536) (xy 25.789447 -256.09285) (xy 25.837649 -256.113985)
			(xy 25.882491 -256.14154) (xy 25.923123 -256.174992) (xy 25.941274 -256.194052) (xy 25.94881 -256.201437)
			(xy 25.968079 -256.209972) (xy 25.978612 -256.210562) (xy 26.053288 -256.210562) (xy 26.06384 -256.210051)
			(xy 26.083136 -256.201504) (xy 26.090626 -256.194052) (xy 26.108758 -256.17497) (xy 26.149378 -256.14149)
			(xy 26.194219 -256.113919) (xy 26.242427 -256.09278) (xy 26.293085 -256.078477) (xy 26.34523 -256.071281)
			(xy 26.37155 -256.070862) (xy 26.398801 -256.071348) (xy 26.452749 -256.079104) (xy 26.505044 -256.094459)
			(xy 26.513997 -256.098548) (xy 27.881832 -256.098548) (xy 27.885903 -256.042926) (xy 27.898029 -255.988489)
			(xy 27.917952 -255.936398) (xy 27.945248 -255.887763) (xy 27.979334 -255.84362) (xy 28.019483 -255.804911)
			(xy 28.064841 -255.77246) (xy 28.114441 -255.746959) (xy 28.167225 -255.728952) (xy 28.222068 -255.718822)
			(xy 28.277802 -255.716785) (xy 28.333239 -255.722885) (xy 28.387196 -255.736991) (xy 28.438525 -255.758803)
			(xy 28.486131 -255.787857) (xy 28.528999 -255.823532) (xy 28.566216 -255.865069) (xy 28.596989 -255.911582)
			(xy 28.620661 -255.962079) (xy 28.636729 -256.015486) (xy 28.644849 -256.070662) (xy 28.645358 -256.098548)
			(xy 28.644849 -256.126434) (xy 28.636729 -256.18161) (xy 28.620661 -256.235017) (xy 28.596989 -256.285514)
			(xy 28.566216 -256.332027) (xy 28.528999 -256.373564) (xy 28.526173 -256.375916) (xy 28.769562 -256.375916)
			(xy 28.773633 -256.320294) (xy 28.785759 -256.265857) (xy 28.805682 -256.213766) (xy 28.832978 -256.165131)
			(xy 28.867064 -256.120988) (xy 28.907213 -256.082279) (xy 28.952571 -256.049828) (xy 29.002171 -256.024327)
			(xy 29.054955 -256.00632) (xy 29.109798 -255.99619) (xy 29.165532 -255.994153) (xy 29.220969 -256.000253)
			(xy 29.274926 -256.014359) (xy 29.326255 -256.036171) (xy 29.373861 -256.065225) (xy 29.416729 -256.1009)
			(xy 29.453946 -256.142437) (xy 29.484719 -256.18895) (xy 29.508391 -256.239447) (xy 29.524459 -256.292854)
			(xy 29.532579 -256.34803) (xy 29.533088 -256.375916) (xy 30.245048 -256.375916) (xy 30.249119 -256.320294)
			(xy 30.261245 -256.265857) (xy 30.281168 -256.213766) (xy 30.308464 -256.165131) (xy 30.34255 -256.120988)
			(xy 30.382699 -256.082279) (xy 30.428057 -256.049828) (xy 30.477657 -256.024327) (xy 30.530441 -256.00632)
			(xy 30.585284 -255.99619) (xy 30.641018 -255.994153) (xy 30.696455 -256.000253) (xy 30.750412 -256.014359)
			(xy 30.801741 -256.036171) (xy 30.849347 -256.065225) (xy 30.892215 -256.1009) (xy 30.929432 -256.142437)
			(xy 30.960205 -256.18895) (xy 30.983877 -256.239447) (xy 30.999945 -256.292854) (xy 31.008065 -256.34803)
			(xy 31.008574 -256.375916) (xy 31.134048 -256.375916) (xy 31.138119 -256.320294) (xy 31.150245 -256.265857)
			(xy 31.170168 -256.213766) (xy 31.197464 -256.165131) (xy 31.23155 -256.120988) (xy 31.271699 -256.082279)
			(xy 31.317057 -256.049828) (xy 31.366657 -256.024327) (xy 31.419441 -256.00632) (xy 31.474284 -255.99619)
			(xy 31.530018 -255.994153) (xy 31.585455 -256.000253) (xy 31.639412 -256.014359) (xy 31.690741 -256.036171)
			(xy 31.738347 -256.065225) (xy 31.781215 -256.1009) (xy 31.818432 -256.142437) (xy 31.849205 -256.18895)
			(xy 31.872877 -256.239447) (xy 31.888945 -256.292854) (xy 31.897065 -256.34803) (xy 31.897574 -256.375916)
			(xy 31.897065 -256.403802) (xy 31.888945 -256.458978) (xy 31.872877 -256.512385) (xy 31.849205 -256.562882)
			(xy 31.818432 -256.609395) (xy 31.781215 -256.650932) (xy 31.738347 -256.686607) (xy 31.690741 -256.715661)
			(xy 31.639412 -256.737473) (xy 31.585455 -256.751579) (xy 31.530018 -256.757679) (xy 31.474284 -256.755642)
			(xy 31.419441 -256.745512) (xy 31.366657 -256.727505) (xy 31.317057 -256.702004) (xy 31.271699 -256.669553)
			(xy 31.23155 -256.630844) (xy 31.197464 -256.586701) (xy 31.170168 -256.538066) (xy 31.150245 -256.485975)
			(xy 31.138119 -256.431538) (xy 31.134048 -256.375916) (xy 31.008574 -256.375916) (xy 31.008065 -256.403802)
			(xy 30.999945 -256.458978) (xy 30.983877 -256.512385) (xy 30.960205 -256.562882) (xy 30.929432 -256.609395)
			(xy 30.892215 -256.650932) (xy 30.849347 -256.686607) (xy 30.801741 -256.715661) (xy 30.750412 -256.737473)
			(xy 30.696455 -256.751579) (xy 30.641018 -256.757679) (xy 30.585284 -256.755642) (xy 30.530441 -256.745512)
			(xy 30.477657 -256.727505) (xy 30.428057 -256.702004) (xy 30.382699 -256.669553) (xy 30.34255 -256.630844)
			(xy 30.308464 -256.586701) (xy 30.281168 -256.538066) (xy 30.261245 -256.485975) (xy 30.249119 -256.431538)
			(xy 30.245048 -256.375916) (xy 29.533088 -256.375916) (xy 29.532579 -256.403802) (xy 29.524459 -256.458978)
			(xy 29.508391 -256.512385) (xy 29.484719 -256.562882) (xy 29.453946 -256.609395) (xy 29.416729 -256.650932)
			(xy 29.373861 -256.686607) (xy 29.326255 -256.715661) (xy 29.274926 -256.737473) (xy 29.220969 -256.751579)
			(xy 29.165532 -256.757679) (xy 29.109798 -256.755642) (xy 29.054955 -256.745512) (xy 29.002171 -256.727505)
			(xy 28.952571 -256.702004) (xy 28.907213 -256.669553) (xy 28.867064 -256.630844) (xy 28.832978 -256.586701)
			(xy 28.805682 -256.538066) (xy 28.785759 -256.485975) (xy 28.773633 -256.431538) (xy 28.769562 -256.375916)
			(xy 28.526173 -256.375916) (xy 28.486131 -256.409239) (xy 28.438525 -256.438293) (xy 28.387196 -256.460105)
			(xy 28.333239 -256.474211) (xy 28.277802 -256.480311) (xy 28.222068 -256.478274) (xy 28.167225 -256.468144)
			(xy 28.114441 -256.450137) (xy 28.064841 -256.424636) (xy 28.019483 -256.392185) (xy 27.979334 -256.353476)
			(xy 27.945248 -256.309333) (xy 27.917952 -256.260698) (xy 27.898029 -256.208607) (xy 27.885903 -256.15417)
			(xy 27.881832 -256.098548) (xy 26.513997 -256.098548) (xy 26.554621 -256.117101) (xy 26.600471 -256.146567)
			(xy 26.641662 -256.182258) (xy 26.677353 -256.223449) (xy 26.706819 -256.269299) (xy 26.729461 -256.318876)
			(xy 26.744816 -256.371171) (xy 26.752572 -256.425119) (xy 26.752572 -256.479621) (xy 26.744816 -256.533569)
			(xy 26.729461 -256.585864) (xy 26.706819 -256.635441) (xy 26.677353 -256.681291) (xy 26.641662 -256.722482)
			(xy 26.600471 -256.758173) (xy 26.554621 -256.787639) (xy 26.505044 -256.810281) (xy 26.452749 -256.825636)
			(xy 26.398801 -256.833392) (xy 26.37155 -256.833878) (xy 26.345233 -256.833445) (xy 26.293098 -256.826222)
			(xy 26.242449 -256.811905) (xy 26.194247 -256.790767) (xy 26.149406 -256.763208) (xy 26.108775 -256.72975)
			(xy 26.090626 -256.710688) (xy 26.083098 -256.703294) (xy 26.063823 -256.694766) (xy 26.053288 -256.694178)
			(xy 25.978612 -256.694178) (xy 25.968062 -256.694706) (xy 25.948767 -256.703243) (xy 25.941274 -256.710688)
			(xy 25.92315 -256.729778) (xy 25.882527 -256.763255) (xy 25.837685 -256.790825) (xy 25.789475 -256.811962)
			(xy 25.738816 -256.826264) (xy 25.68667 -256.833459) (xy 25.66035 -256.833878) (xy 25.633099 -256.833392)
			(xy 25.579151 -256.825636) (xy 25.526856 -256.810281) (xy 25.477279 -256.787639) (xy 25.431429 -256.758173)
			(xy 25.390238 -256.722482) (xy 25.354547 -256.681291) (xy 25.325081 -256.635441) (xy 25.302439 -256.585864)
			(xy 25.287084 -256.533569) (xy 25.279328 -256.479621) (xy 13.216039 -256.479621) (xy 13.210293 -256.518668)
			(xy 13.194225 -256.572075) (xy 13.170553 -256.622572) (xy 13.13978 -256.669085) (xy 13.102563 -256.710622)
			(xy 13.059695 -256.746297) (xy 13.012089 -256.775351) (xy 12.96076 -256.797163) (xy 12.906803 -256.811269)
			(xy 12.851366 -256.817369) (xy 12.795632 -256.815332) (xy 12.740789 -256.805202) (xy 12.688005 -256.787195)
			(xy 12.638405 -256.761694) (xy 12.593047 -256.729243) (xy 12.552898 -256.690534) (xy 12.518812 -256.646391)
			(xy 12.491516 -256.597756) (xy 12.471593 -256.545665) (xy 12.459467 -256.491228) (xy 12.455396 -256.435606)
			(xy 11.810888 -256.435606) (xy 11.810745 -256.443426) (xy 11.802625 -256.498602) (xy 11.786557 -256.552009)
			(xy 11.762885 -256.602506) (xy 11.732112 -256.649019) (xy 11.694895 -256.690556) (xy 11.652027 -256.726231)
			(xy 11.604421 -256.755285) (xy 11.553092 -256.777097) (xy 11.499135 -256.791203) (xy 11.443698 -256.797303)
			(xy 11.387964 -256.795266) (xy 11.333121 -256.785136) (xy 11.280337 -256.767129) (xy 11.230737 -256.741628)
			(xy 11.185379 -256.709177) (xy 11.14523 -256.670468) (xy 11.111144 -256.626325) (xy 11.083848 -256.57769)
			(xy 11.063925 -256.525599) (xy 11.051799 -256.471162) (xy 11.047728 -256.41554) (xy 10.237286 -256.41554)
			(xy 10.233921 -256.438404) (xy 10.217853 -256.491811) (xy 10.194181 -256.542308) (xy 10.163408 -256.588821)
			(xy 10.126191 -256.630358) (xy 10.083323 -256.666033) (xy 10.035717 -256.695087) (xy 9.984388 -256.716899)
			(xy 9.930431 -256.731005) (xy 9.874994 -256.737105) (xy 9.81926 -256.735068) (xy 9.764417 -256.724938)
			(xy 9.711633 -256.706931) (xy 9.662033 -256.68143) (xy 9.616675 -256.648979) (xy 9.576526 -256.61027)
			(xy 9.54244 -256.566127) (xy 9.515144 -256.517492) (xy 9.495221 -256.465401) (xy 9.483095 -256.410964)
			(xy 9.479024 -256.355342) (xy 8.513192 -256.355342) (xy 8.524501 -256.39293) (xy 8.532621 -256.448106)
			(xy 8.53313 -256.475992) (xy 8.532621 -256.503878) (xy 8.524501 -256.559054) (xy 8.508433 -256.612461)
			(xy 8.484761 -256.662958) (xy 8.453988 -256.709471) (xy 8.416771 -256.751008) (xy 8.373903 -256.786683)
			(xy 8.326297 -256.815737) (xy 8.274968 -256.837549) (xy 8.221011 -256.851655) (xy 8.165574 -256.857755)
			(xy 8.10984 -256.855718) (xy 8.054997 -256.845588) (xy 8.002213 -256.827581) (xy 7.952613 -256.80208)
			(xy 7.907255 -256.769629) (xy 7.867106 -256.73092) (xy 7.83302 -256.686777) (xy 7.805724 -256.638142)
			(xy 7.785801 -256.586051) (xy 7.773675 -256.531614) (xy 7.769604 -256.475992) (xy 7.019614 -256.475992)
			(xy 7.024369 -256.508304) (xy 7.024878 -256.53619) (xy 7.024369 -256.564076) (xy 7.016249 -256.619252)
			(xy 7.000181 -256.672659) (xy 6.976509 -256.723156) (xy 6.945736 -256.769669) (xy 6.908519 -256.811206)
			(xy 6.865651 -256.846881) (xy 6.818045 -256.875935) (xy 6.766716 -256.897747) (xy 6.712759 -256.911853)
			(xy 6.657322 -256.917953) (xy 6.601588 -256.915916) (xy 6.546745 -256.905786) (xy 6.493961 -256.887779)
			(xy 6.444361 -256.862278) (xy 6.399003 -256.829827) (xy 6.358854 -256.791118) (xy 6.324768 -256.746975)
			(xy 6.297472 -256.69834) (xy 6.277549 -256.646249) (xy 6.265423 -256.591812) (xy 6.261352 -256.53619)
			(xy 5.511108 -256.53619) (xy 5.507743 -256.559054) (xy 5.491675 -256.612461) (xy 5.468003 -256.662958)
			(xy 5.43723 -256.709471) (xy 5.400013 -256.751008) (xy 5.357145 -256.786683) (xy 5.309539 -256.815737)
			(xy 5.25821 -256.837549) (xy 5.204253 -256.851655) (xy 5.148816 -256.857755) (xy 5.093082 -256.855718)
			(xy 5.038239 -256.845588) (xy 4.985455 -256.827581) (xy 4.935855 -256.80208) (xy 4.890497 -256.769629)
			(xy 4.850348 -256.73092) (xy 4.816262 -256.686777) (xy 4.788966 -256.638142) (xy 4.769043 -256.586051)
			(xy 4.756917 -256.531614) (xy 4.752846 -256.475992) (xy 4.025875 -256.475992) (xy 4.027677 -256.488238)
			(xy 4.028186 -256.516124) (xy 4.027677 -256.54401) (xy 4.019557 -256.599186) (xy 4.003489 -256.652593)
			(xy 3.979817 -256.70309) (xy 3.949044 -256.749603) (xy 3.911827 -256.79114) (xy 3.868959 -256.826815)
			(xy 3.821353 -256.855869) (xy 3.770024 -256.877681) (xy 3.716067 -256.891787) (xy 3.66063 -256.897887)
			(xy 3.604896 -256.89585) (xy 3.550053 -256.88572) (xy 3.497269 -256.867713) (xy 3.447669 -256.842212)
			(xy 3.402311 -256.809761) (xy 3.362162 -256.771052) (xy 3.328076 -256.726909) (xy 3.30078 -256.678274)
			(xy 3.280857 -256.626183) (xy 3.268731 -256.571746) (xy 3.26466 -256.516124) (xy 1.468374 -256.516124)
			(xy 1.468374 -256.987548) (xy 27.881832 -256.987548) (xy 27.885903 -256.931926) (xy 27.898029 -256.877489)
			(xy 27.917952 -256.825398) (xy 27.945248 -256.776763) (xy 27.979334 -256.73262) (xy 28.019483 -256.693911)
			(xy 28.064841 -256.66146) (xy 28.114441 -256.635959) (xy 28.167225 -256.617952) (xy 28.222068 -256.607822)
			(xy 28.277802 -256.605785) (xy 28.333239 -256.611885) (xy 28.387196 -256.625991) (xy 28.438525 -256.647803)
			(xy 28.486131 -256.676857) (xy 28.528999 -256.712532) (xy 28.566216 -256.754069) (xy 28.596989 -256.800582)
			(xy 28.620661 -256.851079) (xy 28.636729 -256.904486) (xy 28.644849 -256.959662) (xy 28.645358 -256.987548)
			(xy 28.644849 -257.015434) (xy 28.636729 -257.07061) (xy 28.620661 -257.124017) (xy 28.614145 -257.137916)
			(xy 34.296096 -257.137916) (xy 34.296647 -257.108534) (xy 34.305675 -257.050468) (xy 34.323505 -256.994474)
			(xy 34.349715 -256.941879) (xy 34.383683 -256.893927) (xy 34.424606 -256.851754) (xy 34.447734 -256.833624)
			(xy 34.457132 -256.826258) (xy 34.467546 -256.805684) (xy 34.46907 -256.701798) (xy 34.459164 -256.680716)
			(xy 34.45002 -256.67335) (xy 34.42817 -256.655146) (xy 34.389629 -256.613328) (xy 34.357722 -256.566252)
			(xy 34.333155 -256.514962) (xy 34.316472 -256.460593) (xy 34.308044 -256.404351) (xy 34.307526 -256.375916)
			(xy 34.308012 -256.348665) (xy 34.315768 -256.294717) (xy 34.331123 -256.242422) (xy 34.353765 -256.192845)
			(xy 34.383231 -256.146995) (xy 34.418922 -256.105804) (xy 34.460113 -256.070113) (xy 34.505963 -256.040647)
			(xy 34.55554 -256.018005) (xy 34.607835 -256.00265) (xy 34.661783 -255.994894) (xy 34.716285 -255.994894)
			(xy 34.770233 -256.00265) (xy 34.822528 -256.018005) (xy 34.872105 -256.040647) (xy 34.917955 -256.070113)
			(xy 34.959146 -256.105804) (xy 34.994837 -256.146995) (xy 35.024303 -256.192845) (xy 35.046945 -256.242422)
			(xy 35.0623 -256.294717) (xy 35.070056 -256.348665) (xy 35.070542 -256.375916) (xy 35.069999 -256.405298)
			(xy 35.060967 -256.463364) (xy 35.043134 -256.519357) (xy 35.016923 -256.571952) (xy 34.982954 -256.619904)
			(xy 34.942031 -256.662077) (xy 34.918904 -256.680208) (xy 34.909506 -256.687574) (xy 34.899092 -256.708148)
			(xy 34.897568 -256.812034) (xy 34.907474 -256.833116) (xy 34.916618 -256.840482) (xy 34.938443 -256.858714)
			(xy 34.976984 -256.900528) (xy 35.008893 -256.947598) (xy 35.033464 -256.998883) (xy 35.050153 -257.053245)
			(xy 35.058589 -257.109483) (xy 35.059112 -257.137916) (xy 35.692586 -257.137916) (xy 35.696657 -257.082294)
			(xy 35.708783 -257.027857) (xy 35.728706 -256.975766) (xy 35.756002 -256.927131) (xy 35.790088 -256.882988)
			(xy 35.830237 -256.844279) (xy 35.875595 -256.811828) (xy 35.925195 -256.786327) (xy 35.977979 -256.76832)
			(xy 36.032822 -256.75819) (xy 36.088556 -256.756153) (xy 36.143993 -256.762253) (xy 36.19795 -256.776359)
			(xy 36.249279 -256.798171) (xy 36.296885 -256.827225) (xy 36.339753 -256.8629) (xy 36.37697 -256.904437)
			(xy 36.407743 -256.95095) (xy 36.431415 -257.001447) (xy 36.447483 -257.054854) (xy 36.455603 -257.11003)
			(xy 36.456112 -257.137916) (xy 36.579046 -257.137916) (xy 36.583117 -257.082294) (xy 36.595243 -257.027857)
			(xy 36.615166 -256.975766) (xy 36.642462 -256.927131) (xy 36.676548 -256.882988) (xy 36.716697 -256.844279)
			(xy 36.762055 -256.811828) (xy 36.811655 -256.786327) (xy 36.864439 -256.76832) (xy 36.919282 -256.75819)
			(xy 36.975016 -256.756153) (xy 37.030453 -256.762253) (xy 37.08441 -256.776359) (xy 37.135739 -256.798171)
			(xy 37.183345 -256.827225) (xy 37.226213 -256.8629) (xy 37.26343 -256.904437) (xy 37.294203 -256.95095)
			(xy 37.317875 -257.001447) (xy 37.333943 -257.054854) (xy 37.342063 -257.11003) (xy 37.342572 -257.137916)
			(xy 37.342063 -257.165802) (xy 37.333943 -257.220978) (xy 37.317875 -257.274385) (xy 37.294203 -257.324882)
			(xy 37.26343 -257.371395) (xy 37.226213 -257.412932) (xy 37.183345 -257.448607) (xy 37.135739 -257.477661)
			(xy 37.08441 -257.499473) (xy 37.030453 -257.513579) (xy 36.975016 -257.519679) (xy 36.919282 -257.517642)
			(xy 36.864439 -257.507512) (xy 36.811655 -257.489505) (xy 36.762055 -257.464004) (xy 36.716697 -257.431553)
			(xy 36.676548 -257.392844) (xy 36.642462 -257.348701) (xy 36.615166 -257.300066) (xy 36.595243 -257.247975)
			(xy 36.583117 -257.193538) (xy 36.579046 -257.137916) (xy 36.456112 -257.137916) (xy 36.455603 -257.165802)
			(xy 36.447483 -257.220978) (xy 36.431415 -257.274385) (xy 36.407743 -257.324882) (xy 36.37697 -257.371395)
			(xy 36.339753 -257.412932) (xy 36.296885 -257.448607) (xy 36.249279 -257.477661) (xy 36.19795 -257.499473)
			(xy 36.143993 -257.513579) (xy 36.088556 -257.519679) (xy 36.032822 -257.517642) (xy 35.977979 -257.507512)
			(xy 35.925195 -257.489505) (xy 35.875595 -257.464004) (xy 35.830237 -257.431553) (xy 35.790088 -257.392844)
			(xy 35.756002 -257.348701) (xy 35.728706 -257.300066) (xy 35.708783 -257.247975) (xy 35.696657 -257.193538)
			(xy 35.692586 -257.137916) (xy 35.059112 -257.137916) (xy 35.058626 -257.165167) (xy 35.05087 -257.219115)
			(xy 35.035515 -257.27141) (xy 35.012873 -257.320987) (xy 34.983407 -257.366837) (xy 34.947716 -257.408028)
			(xy 34.906525 -257.443719) (xy 34.860675 -257.473185) (xy 34.811098 -257.495827) (xy 34.758803 -257.511182)
			(xy 34.704855 -257.518938) (xy 34.650353 -257.518938) (xy 34.596405 -257.511182) (xy 34.54411 -257.495827)
			(xy 34.494533 -257.473185) (xy 34.448683 -257.443719) (xy 34.407492 -257.408028) (xy 34.371801 -257.366837)
			(xy 34.342335 -257.320987) (xy 34.319693 -257.27141) (xy 34.304338 -257.219115) (xy 34.296582 -257.165167)
			(xy 34.296096 -257.137916) (xy 28.614145 -257.137916) (xy 28.596989 -257.174514) (xy 28.566216 -257.221027)
			(xy 28.528999 -257.262564) (xy 28.486131 -257.298239) (xy 28.438525 -257.327293) (xy 28.387196 -257.349105)
			(xy 28.333239 -257.363211) (xy 28.277802 -257.369311) (xy 28.222068 -257.367274) (xy 28.167225 -257.357144)
			(xy 28.114441 -257.339137) (xy 28.064841 -257.313636) (xy 28.019483 -257.281185) (xy 27.979334 -257.242476)
			(xy 27.945248 -257.198333) (xy 27.917952 -257.149698) (xy 27.898029 -257.097607) (xy 27.885903 -257.04317)
			(xy 27.881832 -256.987548) (xy 1.468374 -256.987548) (xy 1.468374 -257.60807) (xy 3.22402 -257.60807)
			(xy 3.228091 -257.552448) (xy 3.240217 -257.498011) (xy 3.26014 -257.44592) (xy 3.287436 -257.397285)
			(xy 3.321522 -257.353142) (xy 3.361671 -257.314433) (xy 3.407029 -257.281982) (xy 3.456629 -257.256481)
			(xy 3.509413 -257.238474) (xy 3.564256 -257.228344) (xy 3.61999 -257.226307) (xy 3.675427 -257.232407)
			(xy 3.729384 -257.246513) (xy 3.780713 -257.268325) (xy 3.828319 -257.297379) (xy 3.871187 -257.333054)
			(xy 3.908404 -257.374591) (xy 3.939177 -257.421104) (xy 3.962849 -257.471601) (xy 3.978917 -257.525008)
			(xy 3.987037 -257.580184) (xy 3.987546 -257.60807) (xy 4.74802 -257.60807) (xy 4.752091 -257.552448)
			(xy 4.764217 -257.498011) (xy 4.78414 -257.44592) (xy 4.811436 -257.397285) (xy 4.845522 -257.353142)
			(xy 4.885671 -257.314433) (xy 4.931029 -257.281982) (xy 4.980629 -257.256481) (xy 5.033413 -257.238474)
			(xy 5.088256 -257.228344) (xy 5.14399 -257.226307) (xy 5.199427 -257.232407) (xy 5.253384 -257.246513)
			(xy 5.304713 -257.268325) (xy 5.352319 -257.297379) (xy 5.395187 -257.333054) (xy 5.432404 -257.374591)
			(xy 5.463177 -257.421104) (xy 5.486849 -257.471601) (xy 5.502917 -257.525008) (xy 5.511037 -257.580184)
			(xy 5.511546 -257.60807) (xy 7.03402 -257.60807) (xy 7.038091 -257.552448) (xy 7.050217 -257.498011)
			(xy 7.07014 -257.44592) (xy 7.097436 -257.397285) (xy 7.131522 -257.353142) (xy 7.171671 -257.314433)
			(xy 7.217029 -257.281982) (xy 7.266629 -257.256481) (xy 7.319413 -257.238474) (xy 7.374256 -257.228344)
			(xy 7.42999 -257.226307) (xy 7.485427 -257.232407) (xy 7.539384 -257.246513) (xy 7.590713 -257.268325)
			(xy 7.638319 -257.297379) (xy 7.681187 -257.333054) (xy 7.718404 -257.374591) (xy 7.749177 -257.421104)
			(xy 7.772849 -257.471601) (xy 7.788917 -257.525008) (xy 7.797037 -257.580184) (xy 7.797546 -257.60807)
			(xy 8.55802 -257.60807) (xy 8.562091 -257.552448) (xy 8.574217 -257.498011) (xy 8.59414 -257.44592)
			(xy 8.621436 -257.397285) (xy 8.655522 -257.353142) (xy 8.695671 -257.314433) (xy 8.741029 -257.281982)
			(xy 8.790629 -257.256481) (xy 8.843413 -257.238474) (xy 8.898256 -257.228344) (xy 8.95399 -257.226307)
			(xy 9.009427 -257.232407) (xy 9.063384 -257.246513) (xy 9.114713 -257.268325) (xy 9.162319 -257.297379)
			(xy 9.205187 -257.333054) (xy 9.242404 -257.374591) (xy 9.273177 -257.421104) (xy 9.296849 -257.471601)
			(xy 9.312917 -257.525008) (xy 9.321037 -257.580184) (xy 9.321546 -257.60807) (xy 10.08202 -257.60807)
			(xy 10.086091 -257.552448) (xy 10.098217 -257.498011) (xy 10.11814 -257.44592) (xy 10.145436 -257.397285)
			(xy 10.179522 -257.353142) (xy 10.219671 -257.314433) (xy 10.265029 -257.281982) (xy 10.314629 -257.256481)
			(xy 10.367413 -257.238474) (xy 10.422256 -257.228344) (xy 10.47799 -257.226307) (xy 10.533427 -257.232407)
			(xy 10.587384 -257.246513) (xy 10.638713 -257.268325) (xy 10.686319 -257.297379) (xy 10.729187 -257.333054)
			(xy 10.766404 -257.374591) (xy 10.797177 -257.421104) (xy 10.820849 -257.471601) (xy 10.836917 -257.525008)
			(xy 10.845037 -257.580184) (xy 10.845546 -257.60807) (xy 11.60602 -257.60807) (xy 11.610091 -257.552448)
			(xy 11.622217 -257.498011) (xy 11.64214 -257.44592) (xy 11.669436 -257.397285) (xy 11.703522 -257.353142)
			(xy 11.743671 -257.314433) (xy 11.789029 -257.281982) (xy 11.838629 -257.256481) (xy 11.891413 -257.238474)
			(xy 11.946256 -257.228344) (xy 12.00199 -257.226307) (xy 12.057427 -257.232407) (xy 12.111384 -257.246513)
			(xy 12.162713 -257.268325) (xy 12.210319 -257.297379) (xy 12.253187 -257.333054) (xy 12.290404 -257.374591)
			(xy 12.321177 -257.421104) (xy 12.344849 -257.471601) (xy 12.360917 -257.525008) (xy 12.369037 -257.580184)
			(xy 12.369546 -257.60807) (xy 13.13002 -257.60807) (xy 13.134091 -257.552448) (xy 13.146217 -257.498011)
			(xy 13.16614 -257.44592) (xy 13.193436 -257.397285) (xy 13.227522 -257.353142) (xy 13.267671 -257.314433)
			(xy 13.313029 -257.281982) (xy 13.362629 -257.256481) (xy 13.415413 -257.238474) (xy 13.470256 -257.228344)
			(xy 13.52599 -257.226307) (xy 13.581427 -257.232407) (xy 13.635384 -257.246513) (xy 13.686713 -257.268325)
			(xy 13.734319 -257.297379) (xy 13.777187 -257.333054) (xy 13.814404 -257.374591) (xy 13.845177 -257.421104)
			(xy 13.868849 -257.471601) (xy 13.869635 -257.474212) (xy 21.97176 -257.474212) (xy 21.975831 -257.41859)
			(xy 21.987957 -257.364153) (xy 22.00788 -257.312062) (xy 22.035176 -257.263427) (xy 22.069262 -257.219284)
			(xy 22.109411 -257.180575) (xy 22.154769 -257.148124) (xy 22.204369 -257.122623) (xy 22.257153 -257.104616)
			(xy 22.311996 -257.094486) (xy 22.36773 -257.092449) (xy 22.423167 -257.098549) (xy 22.477124 -257.112655)
			(xy 22.528453 -257.134467) (xy 22.576059 -257.163521) (xy 22.618927 -257.199196) (xy 22.656144 -257.240733)
			(xy 22.686917 -257.287246) (xy 22.710589 -257.337743) (xy 22.726657 -257.39115) (xy 22.734777 -257.446326)
			(xy 22.735286 -257.474212) (xy 22.734777 -257.502098) (xy 22.726657 -257.557274) (xy 22.710589 -257.610681)
			(xy 22.686917 -257.661178) (xy 22.656144 -257.707691) (xy 22.618927 -257.749228) (xy 22.576059 -257.784903)
			(xy 22.528453 -257.813957) (xy 22.477124 -257.835769) (xy 22.423167 -257.849875) (xy 22.36773 -257.855975)
			(xy 22.311996 -257.853938) (xy 22.257153 -257.843808) (xy 22.204369 -257.825801) (xy 22.154769 -257.8003)
			(xy 22.109411 -257.767849) (xy 22.069262 -257.72914) (xy 22.035176 -257.684997) (xy 22.00788 -257.636362)
			(xy 21.987957 -257.584271) (xy 21.975831 -257.529834) (xy 21.97176 -257.474212) (xy 13.869635 -257.474212)
			(xy 13.884917 -257.525008) (xy 13.893037 -257.580184) (xy 13.893546 -257.60807) (xy 13.893037 -257.635956)
			(xy 13.884917 -257.691132) (xy 13.868849 -257.744539) (xy 13.845177 -257.795036) (xy 13.814404 -257.841549)
			(xy 13.777187 -257.883086) (xy 13.734319 -257.918761) (xy 13.686713 -257.947815) (xy 13.635384 -257.969627)
			(xy 13.581427 -257.983733) (xy 13.52599 -257.989833) (xy 13.470256 -257.987796) (xy 13.415413 -257.977666)
			(xy 13.362629 -257.959659) (xy 13.313029 -257.934158) (xy 13.267671 -257.901707) (xy 13.227522 -257.862998)
			(xy 13.193436 -257.818855) (xy 13.16614 -257.77022) (xy 13.146217 -257.718129) (xy 13.134091 -257.663692)
			(xy 13.13002 -257.60807) (xy 12.369546 -257.60807) (xy 12.369037 -257.635956) (xy 12.360917 -257.691132)
			(xy 12.344849 -257.744539) (xy 12.321177 -257.795036) (xy 12.290404 -257.841549) (xy 12.253187 -257.883086)
			(xy 12.210319 -257.918761) (xy 12.162713 -257.947815) (xy 12.111384 -257.969627) (xy 12.057427 -257.983733)
			(xy 12.00199 -257.989833) (xy 11.946256 -257.987796) (xy 11.891413 -257.977666) (xy 11.838629 -257.959659)
			(xy 11.789029 -257.934158) (xy 11.743671 -257.901707) (xy 11.703522 -257.862998) (xy 11.669436 -257.818855)
			(xy 11.64214 -257.77022) (xy 11.622217 -257.718129) (xy 11.610091 -257.663692) (xy 11.60602 -257.60807)
			(xy 10.845546 -257.60807) (xy 10.845037 -257.635956) (xy 10.836917 -257.691132) (xy 10.820849 -257.744539)
			(xy 10.797177 -257.795036) (xy 10.766404 -257.841549) (xy 10.729187 -257.883086) (xy 10.686319 -257.918761)
			(xy 10.638713 -257.947815) (xy 10.587384 -257.969627) (xy 10.533427 -257.983733) (xy 10.47799 -257.989833)
			(xy 10.422256 -257.987796) (xy 10.367413 -257.977666) (xy 10.314629 -257.959659) (xy 10.265029 -257.934158)
			(xy 10.219671 -257.901707) (xy 10.179522 -257.862998) (xy 10.145436 -257.818855) (xy 10.11814 -257.77022)
			(xy 10.098217 -257.718129) (xy 10.086091 -257.663692) (xy 10.08202 -257.60807) (xy 9.321546 -257.60807)
			(xy 9.321037 -257.635956) (xy 9.312917 -257.691132) (xy 9.296849 -257.744539) (xy 9.273177 -257.795036)
			(xy 9.242404 -257.841549) (xy 9.205187 -257.883086) (xy 9.162319 -257.918761) (xy 9.114713 -257.947815)
			(xy 9.063384 -257.969627) (xy 9.009427 -257.983733) (xy 8.95399 -257.989833) (xy 8.898256 -257.987796)
			(xy 8.843413 -257.977666) (xy 8.790629 -257.959659) (xy 8.741029 -257.934158) (xy 8.695671 -257.901707)
			(xy 8.655522 -257.862998) (xy 8.621436 -257.818855) (xy 8.59414 -257.77022) (xy 8.574217 -257.718129)
			(xy 8.562091 -257.663692) (xy 8.55802 -257.60807) (xy 7.797546 -257.60807) (xy 7.797037 -257.635956)
			(xy 7.788917 -257.691132) (xy 7.772849 -257.744539) (xy 7.749177 -257.795036) (xy 7.718404 -257.841549)
			(xy 7.681187 -257.883086) (xy 7.638319 -257.918761) (xy 7.590713 -257.947815) (xy 7.539384 -257.969627)
			(xy 7.485427 -257.983733) (xy 7.42999 -257.989833) (xy 7.374256 -257.987796) (xy 7.319413 -257.977666)
			(xy 7.266629 -257.959659) (xy 7.217029 -257.934158) (xy 7.171671 -257.901707) (xy 7.131522 -257.862998)
			(xy 7.097436 -257.818855) (xy 7.07014 -257.77022) (xy 7.050217 -257.718129) (xy 7.038091 -257.663692)
			(xy 7.03402 -257.60807) (xy 5.511546 -257.60807) (xy 5.511037 -257.635956) (xy 5.502917 -257.691132)
			(xy 5.486849 -257.744539) (xy 5.463177 -257.795036) (xy 5.432404 -257.841549) (xy 5.395187 -257.883086)
			(xy 5.352319 -257.918761) (xy 5.304713 -257.947815) (xy 5.253384 -257.969627) (xy 5.199427 -257.983733)
			(xy 5.14399 -257.989833) (xy 5.088256 -257.987796) (xy 5.033413 -257.977666) (xy 4.980629 -257.959659)
			(xy 4.931029 -257.934158) (xy 4.885671 -257.901707) (xy 4.845522 -257.862998) (xy 4.811436 -257.818855)
			(xy 4.78414 -257.77022) (xy 4.764217 -257.718129) (xy 4.752091 -257.663692) (xy 4.74802 -257.60807)
			(xy 3.987546 -257.60807) (xy 3.987037 -257.635956) (xy 3.978917 -257.691132) (xy 3.962849 -257.744539)
			(xy 3.939177 -257.795036) (xy 3.908404 -257.841549) (xy 3.871187 -257.883086) (xy 3.828319 -257.918761)
			(xy 3.780713 -257.947815) (xy 3.729384 -257.969627) (xy 3.675427 -257.983733) (xy 3.61999 -257.989833)
			(xy 3.564256 -257.987796) (xy 3.509413 -257.977666) (xy 3.456629 -257.959659) (xy 3.407029 -257.934158)
			(xy 3.361671 -257.901707) (xy 3.321522 -257.862998) (xy 3.287436 -257.818855) (xy 3.26014 -257.77022)
			(xy 3.240217 -257.718129) (xy 3.228091 -257.663692) (xy 3.22402 -257.60807) (xy 1.468374 -257.60807)
			(xy 1.468374 -258.510786) (xy 3.22402 -258.510786) (xy 3.228091 -258.455164) (xy 3.240217 -258.400727)
			(xy 3.26014 -258.348636) (xy 3.287436 -258.300001) (xy 3.321522 -258.255858) (xy 3.361671 -258.217149)
			(xy 3.407029 -258.184698) (xy 3.456629 -258.159197) (xy 3.509413 -258.14119) (xy 3.564256 -258.13106)
			(xy 3.61999 -258.129023) (xy 3.675427 -258.135123) (xy 3.729384 -258.149229) (xy 3.780713 -258.171041)
			(xy 3.828319 -258.200095) (xy 3.871187 -258.23577) (xy 3.908404 -258.277307) (xy 3.939177 -258.32382)
			(xy 3.962849 -258.374317) (xy 3.978917 -258.427724) (xy 3.987037 -258.4829) (xy 3.987546 -258.510786)
			(xy 4.74802 -258.510786) (xy 4.752091 -258.455164) (xy 4.764217 -258.400727) (xy 4.78414 -258.348636)
			(xy 4.811436 -258.300001) (xy 4.845522 -258.255858) (xy 4.885671 -258.217149) (xy 4.931029 -258.184698)
			(xy 4.980629 -258.159197) (xy 5.033413 -258.14119) (xy 5.088256 -258.13106) (xy 5.14399 -258.129023)
			(xy 5.199427 -258.135123) (xy 5.253384 -258.149229) (xy 5.304713 -258.171041) (xy 5.352319 -258.200095)
			(xy 5.395187 -258.23577) (xy 5.432404 -258.277307) (xy 5.463177 -258.32382) (xy 5.486849 -258.374317)
			(xy 5.502917 -258.427724) (xy 5.511037 -258.4829) (xy 5.511546 -258.510786) (xy 6.27202 -258.510786)
			(xy 6.276091 -258.455164) (xy 6.288217 -258.400727) (xy 6.30814 -258.348636) (xy 6.335436 -258.300001)
			(xy 6.369522 -258.255858) (xy 6.409671 -258.217149) (xy 6.455029 -258.184698) (xy 6.504629 -258.159197)
			(xy 6.557413 -258.14119) (xy 6.612256 -258.13106) (xy 6.66799 -258.129023) (xy 6.723427 -258.135123)
			(xy 6.777384 -258.149229) (xy 6.828713 -258.171041) (xy 6.876319 -258.200095) (xy 6.919187 -258.23577)
			(xy 6.956404 -258.277307) (xy 6.987177 -258.32382) (xy 7.010849 -258.374317) (xy 7.026917 -258.427724)
			(xy 7.035037 -258.4829) (xy 7.035546 -258.510786) (xy 7.79602 -258.510786) (xy 7.800091 -258.455164)
			(xy 7.812217 -258.400727) (xy 7.83214 -258.348636) (xy 7.859436 -258.300001) (xy 7.893522 -258.255858)
			(xy 7.933671 -258.217149) (xy 7.979029 -258.184698) (xy 8.028629 -258.159197) (xy 8.081413 -258.14119)
			(xy 8.136256 -258.13106) (xy 8.19199 -258.129023) (xy 8.247427 -258.135123) (xy 8.301384 -258.149229)
			(xy 8.352713 -258.171041) (xy 8.400319 -258.200095) (xy 8.443187 -258.23577) (xy 8.480404 -258.277307)
			(xy 8.511177 -258.32382) (xy 8.534849 -258.374317) (xy 8.550917 -258.427724) (xy 8.559037 -258.4829)
			(xy 8.559546 -258.510786) (xy 9.32002 -258.510786) (xy 9.324091 -258.455164) (xy 9.336217 -258.400727)
			(xy 9.35614 -258.348636) (xy 9.383436 -258.300001) (xy 9.417522 -258.255858) (xy 9.457671 -258.217149)
			(xy 9.503029 -258.184698) (xy 9.552629 -258.159197) (xy 9.605413 -258.14119) (xy 9.660256 -258.13106)
			(xy 9.71599 -258.129023) (xy 9.771427 -258.135123) (xy 9.825384 -258.149229) (xy 9.876713 -258.171041)
			(xy 9.924319 -258.200095) (xy 9.967187 -258.23577) (xy 10.004404 -258.277307) (xy 10.035177 -258.32382)
			(xy 10.058849 -258.374317) (xy 10.074917 -258.427724) (xy 10.083037 -258.4829) (xy 10.083546 -258.510786)
			(xy 10.84402 -258.510786) (xy 10.848091 -258.455164) (xy 10.860217 -258.400727) (xy 10.88014 -258.348636)
			(xy 10.907436 -258.300001) (xy 10.941522 -258.255858) (xy 10.981671 -258.217149) (xy 11.027029 -258.184698)
			(xy 11.076629 -258.159197) (xy 11.129413 -258.14119) (xy 11.184256 -258.13106) (xy 11.23999 -258.129023)
			(xy 11.295427 -258.135123) (xy 11.349384 -258.149229) (xy 11.400713 -258.171041) (xy 11.448319 -258.200095)
			(xy 11.491187 -258.23577) (xy 11.528404 -258.277307) (xy 11.559177 -258.32382) (xy 11.582849 -258.374317)
			(xy 11.598917 -258.427724) (xy 11.607037 -258.4829) (xy 11.607546 -258.510786) (xy 11.607037 -258.538672)
			(xy 11.602805 -258.567428) (xy 11.988798 -258.567428) (xy 11.992869 -258.511806) (xy 12.004995 -258.457369)
			(xy 12.024918 -258.405278) (xy 12.052214 -258.356643) (xy 12.0863 -258.3125) (xy 12.126449 -258.273791)
			(xy 12.171807 -258.24134) (xy 12.221407 -258.215839) (xy 12.274191 -258.197832) (xy 12.329034 -258.187702)
			(xy 12.384768 -258.185665) (xy 12.440205 -258.191765) (xy 12.494162 -258.205871) (xy 12.545491 -258.227683)
			(xy 12.593097 -258.256737) (xy 12.635965 -258.292412) (xy 12.673182 -258.333949) (xy 12.703955 -258.380462)
			(xy 12.727627 -258.430959) (xy 12.743695 -258.484366) (xy 12.747583 -258.510786) (xy 13.13002 -258.510786)
			(xy 13.134091 -258.455164) (xy 13.146217 -258.400727) (xy 13.16614 -258.348636) (xy 13.193436 -258.300001)
			(xy 13.227522 -258.255858) (xy 13.267671 -258.217149) (xy 13.313029 -258.184698) (xy 13.362629 -258.159197)
			(xy 13.415413 -258.14119) (xy 13.470256 -258.13106) (xy 13.52599 -258.129023) (xy 13.581427 -258.135123)
			(xy 13.635384 -258.149229) (xy 13.686713 -258.171041) (xy 13.734319 -258.200095) (xy 13.777187 -258.23577)
			(xy 13.814404 -258.277307) (xy 13.845177 -258.32382) (xy 13.868849 -258.374317) (xy 13.884917 -258.427724)
			(xy 13.893037 -258.4829) (xy 13.893546 -258.510786) (xy 13.893037 -258.538672) (xy 13.884917 -258.593848)
			(xy 13.868849 -258.647255) (xy 13.860309 -258.665472) (xy 21.126448 -258.665472) (xy 21.130519 -258.60985)
			(xy 21.142645 -258.555413) (xy 21.162568 -258.503322) (xy 21.189864 -258.454687) (xy 21.22395 -258.410544)
			(xy 21.264099 -258.371835) (xy 21.309457 -258.339384) (xy 21.359057 -258.313883) (xy 21.411841 -258.295876)
			(xy 21.466684 -258.285746) (xy 21.522418 -258.283709) (xy 21.577855 -258.289809) (xy 21.631812 -258.303915)
			(xy 21.683141 -258.325727) (xy 21.730747 -258.354781) (xy 21.773615 -258.390456) (xy 21.810832 -258.431993)
			(xy 21.841605 -258.478506) (xy 21.865277 -258.529003) (xy 21.881345 -258.58241) (xy 21.889465 -258.637586)
			(xy 21.889691 -258.649978) (xy 22.926292 -258.649978) (xy 22.930363 -258.594356) (xy 22.942489 -258.539919)
			(xy 22.962412 -258.487828) (xy 22.989708 -258.439193) (xy 23.023794 -258.39505) (xy 23.063943 -258.356341)
			(xy 23.109301 -258.32389) (xy 23.158901 -258.298389) (xy 23.211685 -258.280382) (xy 23.266528 -258.270252)
			(xy 23.322262 -258.268215) (xy 23.375363 -258.274058) (xy 28.769562 -258.274058) (xy 28.773633 -258.218436)
			(xy 28.785759 -258.163999) (xy 28.805682 -258.111908) (xy 28.832978 -258.063273) (xy 28.867064 -258.01913)
			(xy 28.907213 -257.980421) (xy 28.952571 -257.94797) (xy 29.002171 -257.922469) (xy 29.054955 -257.904462)
			(xy 29.109798 -257.894332) (xy 29.165532 -257.892295) (xy 29.220969 -257.898395) (xy 29.274926 -257.912501)
			(xy 29.326255 -257.934313) (xy 29.373861 -257.963367) (xy 29.416729 -257.999042) (xy 29.453946 -258.040579)
			(xy 29.484719 -258.087092) (xy 29.508391 -258.137589) (xy 29.524459 -258.190996) (xy 29.532579 -258.246172)
			(xy 29.533088 -258.274058) (xy 30.2547 -258.274058) (xy 30.258771 -258.218436) (xy 30.270897 -258.163999)
			(xy 30.29082 -258.111908) (xy 30.318116 -258.063273) (xy 30.352202 -258.01913) (xy 30.392351 -257.980421)
			(xy 30.437709 -257.94797) (xy 30.487309 -257.922469) (xy 30.540093 -257.904462) (xy 30.594936 -257.894332)
			(xy 30.65067 -257.892295) (xy 30.706107 -257.898395) (xy 30.760064 -257.912501) (xy 30.811393 -257.934313)
			(xy 30.858999 -257.963367) (xy 30.901867 -257.999042) (xy 30.939084 -258.040579) (xy 30.969857 -258.087092)
			(xy 30.993529 -258.137589) (xy 31.009597 -258.190996) (xy 31.017717 -258.246172) (xy 31.018226 -258.274058)
			(xy 31.017717 -258.301944) (xy 31.009597 -258.35712) (xy 30.993529 -258.410527) (xy 30.969857 -258.461024)
			(xy 30.939084 -258.507537) (xy 30.901867 -258.549074) (xy 30.858999 -258.584749) (xy 30.811393 -258.613803)
			(xy 30.760064 -258.635615) (xy 30.706107 -258.649721) (xy 30.65067 -258.655821) (xy 30.594936 -258.653784)
			(xy 30.540093 -258.643654) (xy 30.487309 -258.625647) (xy 30.437709 -258.600146) (xy 30.392351 -258.567695)
			(xy 30.352202 -258.528986) (xy 30.318116 -258.484843) (xy 30.29082 -258.436208) (xy 30.270897 -258.384117)
			(xy 30.258771 -258.32968) (xy 30.2547 -258.274058) (xy 29.533088 -258.274058) (xy 29.532579 -258.301944)
			(xy 29.524459 -258.35712) (xy 29.508391 -258.410527) (xy 29.484719 -258.461024) (xy 29.453946 -258.507537)
			(xy 29.416729 -258.549074) (xy 29.373861 -258.584749) (xy 29.326255 -258.613803) (xy 29.274926 -258.635615)
			(xy 29.220969 -258.649721) (xy 29.165532 -258.655821) (xy 29.109798 -258.653784) (xy 29.054955 -258.643654)
			(xy 29.002171 -258.625647) (xy 28.952571 -258.600146) (xy 28.907213 -258.567695) (xy 28.867064 -258.528986)
			(xy 28.832978 -258.484843) (xy 28.805682 -258.436208) (xy 28.785759 -258.384117) (xy 28.773633 -258.32968)
			(xy 28.769562 -258.274058) (xy 23.375363 -258.274058) (xy 23.377699 -258.274315) (xy 23.431656 -258.288421)
			(xy 23.482985 -258.310233) (xy 23.530591 -258.339287) (xy 23.573459 -258.374962) (xy 23.610676 -258.416499)
			(xy 23.641449 -258.463012) (xy 23.665121 -258.513509) (xy 23.681189 -258.566916) (xy 23.689309 -258.622092)
			(xy 23.689818 -258.649978) (xy 23.689309 -258.677864) (xy 23.687357 -258.691126) (xy 24.410668 -258.691126)
			(xy 24.414739 -258.635504) (xy 24.426865 -258.581067) (xy 24.446788 -258.528976) (xy 24.474084 -258.480341)
			(xy 24.50817 -258.436198) (xy 24.548319 -258.397489) (xy 24.593677 -258.365038) (xy 24.643277 -258.339537)
			(xy 24.696061 -258.32153) (xy 24.750904 -258.3114) (xy 24.806638 -258.309363) (xy 24.862075 -258.315463)
			(xy 24.916032 -258.329569) (xy 24.967361 -258.351381) (xy 25.014967 -258.380435) (xy 25.057835 -258.41611)
			(xy 25.095052 -258.457647) (xy 25.125825 -258.50416) (xy 25.149497 -258.554657) (xy 25.165565 -258.608064)
			(xy 25.173685 -258.66324) (xy 25.174194 -258.691126) (xy 25.173685 -258.719012) (xy 25.165565 -258.774188)
			(xy 25.149497 -258.827595) (xy 25.125825 -258.878092) (xy 25.095052 -258.924605) (xy 25.057835 -258.966142)
			(xy 25.014967 -259.001817) (xy 24.967361 -259.030871) (xy 24.916032 -259.052683) (xy 24.862075 -259.066789)
			(xy 24.806638 -259.072889) (xy 24.750904 -259.070852) (xy 24.696061 -259.060722) (xy 24.643277 -259.042715)
			(xy 24.593677 -259.017214) (xy 24.548319 -258.984763) (xy 24.50817 -258.946054) (xy 24.474084 -258.901911)
			(xy 24.446788 -258.853276) (xy 24.426865 -258.801185) (xy 24.414739 -258.746748) (xy 24.410668 -258.691126)
			(xy 23.687357 -258.691126) (xy 23.681189 -258.73304) (xy 23.665121 -258.786447) (xy 23.641449 -258.836944)
			(xy 23.610676 -258.883457) (xy 23.573459 -258.924994) (xy 23.530591 -258.960669) (xy 23.482985 -258.989723)
			(xy 23.431656 -259.011535) (xy 23.377699 -259.025641) (xy 23.322262 -259.031741) (xy 23.266528 -259.029704)
			(xy 23.211685 -259.019574) (xy 23.158901 -259.001567) (xy 23.109301 -258.976066) (xy 23.063943 -258.943615)
			(xy 23.023794 -258.904906) (xy 22.989708 -258.860763) (xy 22.962412 -258.812128) (xy 22.942489 -258.760037)
			(xy 22.930363 -258.7056) (xy 22.926292 -258.649978) (xy 21.889691 -258.649978) (xy 21.889974 -258.665472)
			(xy 21.889465 -258.693358) (xy 21.881345 -258.748534) (xy 21.865277 -258.801941) (xy 21.841605 -258.852438)
			(xy 21.810832 -258.898951) (xy 21.773615 -258.940488) (xy 21.730747 -258.976163) (xy 21.683141 -259.005217)
			(xy 21.631812 -259.027029) (xy 21.577855 -259.041135) (xy 21.522418 -259.047235) (xy 21.466684 -259.045198)
			(xy 21.411841 -259.035068) (xy 21.359057 -259.017061) (xy 21.309457 -258.99156) (xy 21.264099 -258.959109)
			(xy 21.22395 -258.9204) (xy 21.189864 -258.876257) (xy 21.162568 -258.827622) (xy 21.142645 -258.775531)
			(xy 21.130519 -258.721094) (xy 21.126448 -258.665472) (xy 13.860309 -258.665472) (xy 13.845177 -258.697752)
			(xy 13.814404 -258.744265) (xy 13.777187 -258.785802) (xy 13.734319 -258.821477) (xy 13.686713 -258.850531)
			(xy 13.635384 -258.872343) (xy 13.581427 -258.886449) (xy 13.52599 -258.892549) (xy 13.470256 -258.890512)
			(xy 13.415413 -258.880382) (xy 13.362629 -258.862375) (xy 13.313029 -258.836874) (xy 13.267671 -258.804423)
			(xy 13.227522 -258.765714) (xy 13.193436 -258.721571) (xy 13.16614 -258.672936) (xy 13.146217 -258.620845)
			(xy 13.134091 -258.566408) (xy 13.13002 -258.510786) (xy 12.747583 -258.510786) (xy 12.751815 -258.539542)
			(xy 12.752324 -258.567428) (xy 12.751815 -258.595314) (xy 12.743695 -258.65049) (xy 12.727627 -258.703897)
			(xy 12.703955 -258.754394) (xy 12.673182 -258.800907) (xy 12.635965 -258.842444) (xy 12.593097 -258.878119)
			(xy 12.545491 -258.907173) (xy 12.494162 -258.928985) (xy 12.440205 -258.943091) (xy 12.384768 -258.949191)
			(xy 12.329034 -258.947154) (xy 12.274191 -258.937024) (xy 12.221407 -258.919017) (xy 12.171807 -258.893516)
			(xy 12.126449 -258.861065) (xy 12.0863 -258.822356) (xy 12.052214 -258.778213) (xy 12.024918 -258.729578)
			(xy 12.004995 -258.677487) (xy 11.992869 -258.62305) (xy 11.988798 -258.567428) (xy 11.602805 -258.567428)
			(xy 11.598917 -258.593848) (xy 11.582849 -258.647255) (xy 11.559177 -258.697752) (xy 11.528404 -258.744265)
			(xy 11.491187 -258.785802) (xy 11.448319 -258.821477) (xy 11.400713 -258.850531) (xy 11.349384 -258.872343)
			(xy 11.295427 -258.886449) (xy 11.23999 -258.892549) (xy 11.184256 -258.890512) (xy 11.129413 -258.880382)
			(xy 11.076629 -258.862375) (xy 11.027029 -258.836874) (xy 10.981671 -258.804423) (xy 10.941522 -258.765714)
			(xy 10.907436 -258.721571) (xy 10.88014 -258.672936) (xy 10.860217 -258.620845) (xy 10.848091 -258.566408)
			(xy 10.84402 -258.510786) (xy 10.083546 -258.510786) (xy 10.083037 -258.538672) (xy 10.074917 -258.593848)
			(xy 10.058849 -258.647255) (xy 10.035177 -258.697752) (xy 10.004404 -258.744265) (xy 9.967187 -258.785802)
			(xy 9.924319 -258.821477) (xy 9.876713 -258.850531) (xy 9.825384 -258.872343) (xy 9.771427 -258.886449)
			(xy 9.71599 -258.892549) (xy 9.660256 -258.890512) (xy 9.605413 -258.880382) (xy 9.552629 -258.862375)
			(xy 9.503029 -258.836874) (xy 9.457671 -258.804423) (xy 9.417522 -258.765714) (xy 9.383436 -258.721571)
			(xy 9.35614 -258.672936) (xy 9.336217 -258.620845) (xy 9.324091 -258.566408) (xy 9.32002 -258.510786)
			(xy 8.559546 -258.510786) (xy 8.559037 -258.538672) (xy 8.550917 -258.593848) (xy 8.534849 -258.647255)
			(xy 8.511177 -258.697752) (xy 8.480404 -258.744265) (xy 8.443187 -258.785802) (xy 8.400319 -258.821477)
			(xy 8.352713 -258.850531) (xy 8.301384 -258.872343) (xy 8.247427 -258.886449) (xy 8.19199 -258.892549)
			(xy 8.136256 -258.890512) (xy 8.081413 -258.880382) (xy 8.028629 -258.862375) (xy 7.979029 -258.836874)
			(xy 7.933671 -258.804423) (xy 7.893522 -258.765714) (xy 7.859436 -258.721571) (xy 7.83214 -258.672936)
			(xy 7.812217 -258.620845) (xy 7.800091 -258.566408) (xy 7.79602 -258.510786) (xy 7.035546 -258.510786)
			(xy 7.035037 -258.538672) (xy 7.026917 -258.593848) (xy 7.010849 -258.647255) (xy 6.987177 -258.697752)
			(xy 6.956404 -258.744265) (xy 6.919187 -258.785802) (xy 6.876319 -258.821477) (xy 6.828713 -258.850531)
			(xy 6.777384 -258.872343) (xy 6.723427 -258.886449) (xy 6.66799 -258.892549) (xy 6.612256 -258.890512)
			(xy 6.557413 -258.880382) (xy 6.504629 -258.862375) (xy 6.455029 -258.836874) (xy 6.409671 -258.804423)
			(xy 6.369522 -258.765714) (xy 6.335436 -258.721571) (xy 6.30814 -258.672936) (xy 6.288217 -258.620845)
			(xy 6.276091 -258.566408) (xy 6.27202 -258.510786) (xy 5.511546 -258.510786) (xy 5.511037 -258.538672)
			(xy 5.502917 -258.593848) (xy 5.486849 -258.647255) (xy 5.463177 -258.697752) (xy 5.432404 -258.744265)
			(xy 5.395187 -258.785802) (xy 5.352319 -258.821477) (xy 5.304713 -258.850531) (xy 5.253384 -258.872343)
			(xy 5.199427 -258.886449) (xy 5.14399 -258.892549) (xy 5.088256 -258.890512) (xy 5.033413 -258.880382)
			(xy 4.980629 -258.862375) (xy 4.931029 -258.836874) (xy 4.885671 -258.804423) (xy 4.845522 -258.765714)
			(xy 4.811436 -258.721571) (xy 4.78414 -258.672936) (xy 4.764217 -258.620845) (xy 4.752091 -258.566408)
			(xy 4.74802 -258.510786) (xy 3.987546 -258.510786) (xy 3.987037 -258.538672) (xy 3.978917 -258.593848)
			(xy 3.962849 -258.647255) (xy 3.939177 -258.697752) (xy 3.908404 -258.744265) (xy 3.871187 -258.785802)
			(xy 3.828319 -258.821477) (xy 3.780713 -258.850531) (xy 3.729384 -258.872343) (xy 3.675427 -258.886449)
			(xy 3.61999 -258.892549) (xy 3.564256 -258.890512) (xy 3.509413 -258.880382) (xy 3.456629 -258.862375)
			(xy 3.407029 -258.836874) (xy 3.361671 -258.804423) (xy 3.321522 -258.765714) (xy 3.287436 -258.721571)
			(xy 3.26014 -258.672936) (xy 3.240217 -258.620845) (xy 3.228091 -258.566408) (xy 3.22402 -258.510786)
			(xy 1.468374 -258.510786) (xy 1.468374 -259.576316) (xy 30.245048 -259.576316) (xy 30.249119 -259.520694)
			(xy 30.261245 -259.466257) (xy 30.281168 -259.414166) (xy 30.308464 -259.365531) (xy 30.34255 -259.321388)
			(xy 30.382699 -259.282679) (xy 30.428057 -259.250228) (xy 30.477657 -259.224727) (xy 30.530441 -259.20672)
			(xy 30.585284 -259.19659) (xy 30.641018 -259.194553) (xy 30.696455 -259.200653) (xy 30.750412 -259.214759)
			(xy 30.801741 -259.236571) (xy 30.849347 -259.265625) (xy 30.892215 -259.3013) (xy 30.929432 -259.342837)
			(xy 30.960205 -259.38935) (xy 30.983877 -259.439847) (xy 30.999945 -259.493254) (xy 31.008065 -259.54843)
			(xy 31.008574 -259.576316) (xy 31.134048 -259.576316) (xy 31.138119 -259.520694) (xy 31.150245 -259.466257)
			(xy 31.170168 -259.414166) (xy 31.197464 -259.365531) (xy 31.23155 -259.321388) (xy 31.271699 -259.282679)
			(xy 31.317057 -259.250228) (xy 31.366657 -259.224727) (xy 31.419441 -259.20672) (xy 31.474284 -259.19659)
			(xy 31.530018 -259.194553) (xy 31.585455 -259.200653) (xy 31.639412 -259.214759) (xy 31.690741 -259.236571)
			(xy 31.738347 -259.265625) (xy 31.781215 -259.3013) (xy 31.818432 -259.342837) (xy 31.849205 -259.38935)
			(xy 31.872877 -259.439847) (xy 31.888945 -259.493254) (xy 31.897065 -259.54843) (xy 31.897574 -259.576316)
			(xy 31.897065 -259.604202) (xy 31.888945 -259.659378) (xy 31.872877 -259.712785) (xy 31.849205 -259.763282)
			(xy 31.818432 -259.809795) (xy 31.781215 -259.851332) (xy 31.738347 -259.887007) (xy 31.690741 -259.916061)
			(xy 31.639412 -259.937873) (xy 31.585455 -259.951979) (xy 31.530018 -259.958079) (xy 31.474284 -259.956042)
			(xy 31.419441 -259.945912) (xy 31.366657 -259.927905) (xy 31.317057 -259.902404) (xy 31.271699 -259.869953)
			(xy 31.23155 -259.831244) (xy 31.197464 -259.787101) (xy 31.170168 -259.738466) (xy 31.150245 -259.686375)
			(xy 31.138119 -259.631938) (xy 31.134048 -259.576316) (xy 31.008574 -259.576316) (xy 31.008065 -259.604202)
			(xy 30.999945 -259.659378) (xy 30.983877 -259.712785) (xy 30.960205 -259.763282) (xy 30.929432 -259.809795)
			(xy 30.892215 -259.851332) (xy 30.849347 -259.887007) (xy 30.801741 -259.916061) (xy 30.750412 -259.937873)
			(xy 30.696455 -259.951979) (xy 30.641018 -259.958079) (xy 30.585284 -259.956042) (xy 30.530441 -259.945912)
			(xy 30.477657 -259.927905) (xy 30.428057 -259.902404) (xy 30.382699 -259.869953) (xy 30.34255 -259.831244)
			(xy 30.308464 -259.787101) (xy 30.281168 -259.738466) (xy 30.261245 -259.686375) (xy 30.249119 -259.631938)
			(xy 30.245048 -259.576316) (xy 1.468374 -259.576316) (xy 1.468374 -260.740398) (xy 22.04339 -260.740398)
			(xy 22.043956 -260.711756) (xy 22.05252 -260.655116) (xy 22.069455 -260.600392) (xy 22.09438 -260.548815)
			(xy 22.126735 -260.501543) (xy 22.165793 -260.459639) (xy 22.187916 -260.44144) (xy 22.196298 -260.434836)
			(xy 22.206204 -260.415786) (xy 22.212808 -260.31952) (xy 22.205696 -260.299454) (xy 22.198076 -260.29158)
			(xy 22.178306 -260.270146) (xy 22.144874 -260.222374) (xy 22.119096 -260.170073) (xy 22.101571 -260.11446)
			(xy 22.092708 -260.056828) (xy 22.092158 -260.027674) (xy 22.092644 -260.000423) (xy 22.1004 -259.946475)
			(xy 22.115755 -259.89418) (xy 22.138397 -259.844603) (xy 22.167863 -259.798753) (xy 22.203554 -259.757562)
			(xy 22.244745 -259.721871) (xy 22.290595 -259.692405) (xy 22.340172 -259.669763) (xy 22.392467 -259.654408)
			(xy 22.446415 -259.646652) (xy 22.500917 -259.646652) (xy 22.554865 -259.654408) (xy 22.60716 -259.669763)
			(xy 22.656737 -259.692405) (xy 22.702587 -259.721871) (xy 22.743778 -259.757562) (xy 22.779469 -259.798753)
			(xy 22.808935 -259.844603) (xy 22.831577 -259.89418) (xy 22.846932 -259.946475) (xy 22.854688 -260.000423)
			(xy 22.855174 -260.027674) (xy 22.854672 -260.056319) (xy 22.85251 -260.0706) (xy 23.642826 -260.0706)
			(xy 23.646897 -260.014978) (xy 23.659023 -259.960541) (xy 23.678946 -259.90845) (xy 23.706242 -259.859815)
			(xy 23.740328 -259.815672) (xy 23.780477 -259.776963) (xy 23.825835 -259.744512) (xy 23.875435 -259.719011)
			(xy 23.928219 -259.701004) (xy 23.983062 -259.690874) (xy 24.038796 -259.688837) (xy 24.094233 -259.694937)
			(xy 24.14819 -259.709043) (xy 24.199519 -259.730855) (xy 24.247125 -259.759909) (xy 24.289993 -259.795584)
			(xy 24.32721 -259.837121) (xy 24.357983 -259.883634) (xy 24.381655 -259.934131) (xy 24.397723 -259.987538)
			(xy 24.405843 -260.042714) (xy 24.406352 -260.0706) (xy 24.405843 -260.098486) (xy 24.402695 -260.119876)
			(xy 27.661868 -260.119876) (xy 27.665939 -260.064254) (xy 27.678065 -260.009817) (xy 27.697988 -259.957726)
			(xy 27.725284 -259.909091) (xy 27.75937 -259.864948) (xy 27.799519 -259.826239) (xy 27.844877 -259.793788)
			(xy 27.894477 -259.768287) (xy 27.947261 -259.75028) (xy 28.002104 -259.74015) (xy 28.057838 -259.738113)
			(xy 28.113275 -259.744213) (xy 28.167232 -259.758319) (xy 28.218561 -259.780131) (xy 28.266167 -259.809185)
			(xy 28.309035 -259.84486) (xy 28.346252 -259.886397) (xy 28.377025 -259.93291) (xy 28.400697 -259.983407)
			(xy 28.416765 -260.036814) (xy 28.424885 -260.09199) (xy 28.425394 -260.119876) (xy 28.424885 -260.147762)
			(xy 28.416765 -260.202938) (xy 28.400697 -260.256345) (xy 28.377025 -260.306842) (xy 28.356202 -260.338316)
			(xy 34.296096 -260.338316) (xy 34.296647 -260.308934) (xy 34.305675 -260.250868) (xy 34.323505 -260.194874)
			(xy 34.349715 -260.142279) (xy 34.383683 -260.094327) (xy 34.424606 -260.052154) (xy 34.447734 -260.034024)
			(xy 34.457132 -260.026658) (xy 34.467546 -260.006084) (xy 34.46907 -259.902198) (xy 34.459164 -259.881116)
			(xy 34.45002 -259.87375) (xy 34.42817 -259.855546) (xy 34.389629 -259.813728) (xy 34.357722 -259.766652)
			(xy 34.333155 -259.715362) (xy 34.316472 -259.660993) (xy 34.308044 -259.604751) (xy 34.307526 -259.576316)
			(xy 34.308012 -259.549065) (xy 34.315768 -259.495117) (xy 34.331123 -259.442822) (xy 34.353765 -259.393245)
			(xy 34.383231 -259.347395) (xy 34.418922 -259.306204) (xy 34.460113 -259.270513) (xy 34.505963 -259.241047)
			(xy 34.55554 -259.218405) (xy 34.607835 -259.20305) (xy 34.661783 -259.195294) (xy 34.716285 -259.195294)
			(xy 34.770233 -259.20305) (xy 34.822528 -259.218405) (xy 34.872105 -259.241047) (xy 34.917955 -259.270513)
			(xy 34.959146 -259.306204) (xy 34.994837 -259.347395) (xy 35.024303 -259.393245) (xy 35.046945 -259.442822)
			(xy 35.0623 -259.495117) (xy 35.070056 -259.549065) (xy 35.070542 -259.576316) (xy 35.069999 -259.605698)
			(xy 35.060967 -259.663764) (xy 35.043134 -259.719757) (xy 35.016923 -259.772352) (xy 34.982954 -259.820304)
			(xy 34.942031 -259.862477) (xy 34.918904 -259.880608) (xy 34.909506 -259.887974) (xy 34.899092 -259.908548)
			(xy 34.897568 -260.012434) (xy 34.907474 -260.033516) (xy 34.916618 -260.040882) (xy 34.938443 -260.059114)
			(xy 34.976984 -260.100928) (xy 35.008893 -260.147998) (xy 35.033464 -260.199283) (xy 35.050153 -260.253645)
			(xy 35.058589 -260.309883) (xy 35.059112 -260.338316) (xy 35.692586 -260.338316) (xy 35.696657 -260.282694)
			(xy 35.708783 -260.228257) (xy 35.728706 -260.176166) (xy 35.756002 -260.127531) (xy 35.790088 -260.083388)
			(xy 35.830237 -260.044679) (xy 35.875595 -260.012228) (xy 35.925195 -259.986727) (xy 35.977979 -259.96872)
			(xy 36.032822 -259.95859) (xy 36.088556 -259.956553) (xy 36.143993 -259.962653) (xy 36.19795 -259.976759)
			(xy 36.249279 -259.998571) (xy 36.296885 -260.027625) (xy 36.339753 -260.0633) (xy 36.37697 -260.104837)
			(xy 36.407743 -260.15135) (xy 36.431415 -260.201847) (xy 36.447483 -260.255254) (xy 36.455603 -260.31043)
			(xy 36.456112 -260.338316) (xy 36.579046 -260.338316) (xy 36.583117 -260.282694) (xy 36.595243 -260.228257)
			(xy 36.615166 -260.176166) (xy 36.642462 -260.127531) (xy 36.676548 -260.083388) (xy 36.716697 -260.044679)
			(xy 36.762055 -260.012228) (xy 36.811655 -259.986727) (xy 36.864439 -259.96872) (xy 36.919282 -259.95859)
			(xy 36.975016 -259.956553) (xy 37.030453 -259.962653) (xy 37.08441 -259.976759) (xy 37.135739 -259.998571)
			(xy 37.183345 -260.027625) (xy 37.226213 -260.0633) (xy 37.26343 -260.104837) (xy 37.294203 -260.15135)
			(xy 37.317875 -260.201847) (xy 37.333943 -260.255254) (xy 37.342063 -260.31043) (xy 37.342572 -260.338316)
			(xy 37.342063 -260.366202) (xy 37.333943 -260.421378) (xy 37.317875 -260.474785) (xy 37.294203 -260.525282)
			(xy 37.26343 -260.571795) (xy 37.226213 -260.613332) (xy 37.183345 -260.649007) (xy 37.135739 -260.678061)
			(xy 37.08441 -260.699873) (xy 37.030453 -260.713979) (xy 36.975016 -260.720079) (xy 36.919282 -260.718042)
			(xy 36.864439 -260.707912) (xy 36.811655 -260.689905) (xy 36.762055 -260.664404) (xy 36.716697 -260.631953)
			(xy 36.676548 -260.593244) (xy 36.642462 -260.549101) (xy 36.615166 -260.500466) (xy 36.595243 -260.448375)
			(xy 36.583117 -260.393938) (xy 36.579046 -260.338316) (xy 36.456112 -260.338316) (xy 36.455603 -260.366202)
			(xy 36.447483 -260.421378) (xy 36.431415 -260.474785) (xy 36.407743 -260.525282) (xy 36.37697 -260.571795)
			(xy 36.339753 -260.613332) (xy 36.296885 -260.649007) (xy 36.249279 -260.678061) (xy 36.19795 -260.699873)
			(xy 36.143993 -260.713979) (xy 36.088556 -260.720079) (xy 36.032822 -260.718042) (xy 35.977979 -260.707912)
			(xy 35.925195 -260.689905) (xy 35.875595 -260.664404) (xy 35.830237 -260.631953) (xy 35.790088 -260.593244)
			(xy 35.756002 -260.549101) (xy 35.728706 -260.500466) (xy 35.708783 -260.448375) (xy 35.696657 -260.393938)
			(xy 35.692586 -260.338316) (xy 35.059112 -260.338316) (xy 35.058626 -260.365567) (xy 35.05087 -260.419515)
			(xy 35.035515 -260.47181) (xy 35.012873 -260.521387) (xy 34.983407 -260.567237) (xy 34.947716 -260.608428)
			(xy 34.906525 -260.644119) (xy 34.860675 -260.673585) (xy 34.811098 -260.696227) (xy 34.758803 -260.711582)
			(xy 34.704855 -260.719338) (xy 34.650353 -260.719338) (xy 34.596405 -260.711582) (xy 34.54411 -260.696227)
			(xy 34.494533 -260.673585) (xy 34.448683 -260.644119) (xy 34.407492 -260.608428) (xy 34.371801 -260.567237)
			(xy 34.342335 -260.521387) (xy 34.319693 -260.47181) (xy 34.304338 -260.419515) (xy 34.296582 -260.365567)
			(xy 34.296096 -260.338316) (xy 28.356202 -260.338316) (xy 28.346252 -260.353355) (xy 28.309035 -260.394892)
			(xy 28.266167 -260.430567) (xy 28.218561 -260.459621) (xy 28.167232 -260.481433) (xy 28.113275 -260.495539)
			(xy 28.057838 -260.501639) (xy 28.002104 -260.499602) (xy 27.947261 -260.489472) (xy 27.894477 -260.471465)
			(xy 27.844877 -260.445964) (xy 27.799519 -260.413513) (xy 27.75937 -260.374804) (xy 27.725284 -260.330661)
			(xy 27.697988 -260.282026) (xy 27.678065 -260.229935) (xy 27.665939 -260.175498) (xy 27.661868 -260.119876)
			(xy 24.402695 -260.119876) (xy 24.397723 -260.153662) (xy 24.381655 -260.207069) (xy 24.357983 -260.257566)
			(xy 24.32721 -260.304079) (xy 24.289993 -260.345616) (xy 24.247125 -260.381291) (xy 24.199519 -260.410345)
			(xy 24.14819 -260.432157) (xy 24.094233 -260.446263) (xy 24.038796 -260.452363) (xy 23.983062 -260.450326)
			(xy 23.928219 -260.440196) (xy 23.875435 -260.422189) (xy 23.825835 -260.396688) (xy 23.780477 -260.364237)
			(xy 23.740328 -260.325528) (xy 23.706242 -260.281385) (xy 23.678946 -260.23275) (xy 23.659023 -260.180659)
			(xy 23.646897 -260.126222) (xy 23.642826 -260.0706) (xy 22.85251 -260.0706) (xy 22.846097 -260.112963)
			(xy 22.82915 -260.167688) (xy 22.804213 -260.219265) (xy 22.771846 -260.266535) (xy 22.732776 -260.308435)
			(xy 22.710648 -260.326632) (xy 22.702266 -260.333236) (xy 22.69236 -260.352286) (xy 22.685756 -260.448552)
			(xy 22.692868 -260.468618) (xy 22.700488 -260.476492) (xy 22.720239 -260.497943) (xy 22.749139 -260.53923)
			(xy 26.534616 -260.53923) (xy 26.538687 -260.483608) (xy 26.550813 -260.429171) (xy 26.570736 -260.37708)
			(xy 26.598032 -260.328445) (xy 26.632118 -260.284302) (xy 26.672267 -260.245593) (xy 26.717625 -260.213142)
			(xy 26.767225 -260.187641) (xy 26.820009 -260.169634) (xy 26.874852 -260.159504) (xy 26.930586 -260.157467)
			(xy 26.986023 -260.163567) (xy 27.03998 -260.177673) (xy 27.091309 -260.199485) (xy 27.138915 -260.228539)
			(xy 27.181783 -260.264214) (xy 27.219 -260.305751) (xy 27.249773 -260.352264) (xy 27.273445 -260.402761)
			(xy 27.289513 -260.456168) (xy 27.297633 -260.511344) (xy 27.298142 -260.53923) (xy 27.297633 -260.567116)
			(xy 27.289513 -260.622292) (xy 27.273445 -260.675699) (xy 27.249773 -260.726196) (xy 27.219 -260.772709)
			(xy 27.181783 -260.814246) (xy 27.138915 -260.849921) (xy 27.091309 -260.878975) (xy 27.03998 -260.900787)
			(xy 26.986023 -260.914893) (xy 26.930586 -260.920993) (xy 26.874852 -260.918956) (xy 26.820009 -260.908826)
			(xy 26.767225 -260.890819) (xy 26.717625 -260.865318) (xy 26.672267 -260.832867) (xy 26.632118 -260.794158)
			(xy 26.598032 -260.750015) (xy 26.570736 -260.70138) (xy 26.550813 -260.649289) (xy 26.538687 -260.594852)
			(xy 26.534616 -260.53923) (xy 22.749139 -260.53923) (xy 22.753675 -260.54571) (xy 22.779457 -260.598007)
			(xy 22.796986 -260.653616) (xy 22.805854 -260.711245) (xy 22.806406 -260.740398) (xy 22.80592 -260.767649)
			(xy 22.798164 -260.821597) (xy 22.782809 -260.873892) (xy 22.760167 -260.923469) (xy 22.730701 -260.969319)
			(xy 22.69501 -261.01051) (xy 22.653819 -261.046201) (xy 22.607969 -261.075667) (xy 22.558392 -261.098309)
			(xy 22.506097 -261.113664) (xy 22.452149 -261.12142) (xy 22.397647 -261.12142) (xy 22.343699 -261.113664)
			(xy 22.291404 -261.098309) (xy 22.241827 -261.075667) (xy 22.195977 -261.046201) (xy 22.154786 -261.01051)
			(xy 22.119095 -260.969319) (xy 22.089629 -260.923469) (xy 22.066987 -260.873892) (xy 22.051632 -260.821597)
			(xy 22.043876 -260.767649) (xy 22.04339 -260.740398) (xy 1.468374 -260.740398) (xy 1.468374 -261.764272)
			(xy 24.31872 -261.764272) (xy 24.322791 -261.70865) (xy 24.334917 -261.654213) (xy 24.35484 -261.602122)
			(xy 24.382136 -261.553487) (xy 24.416222 -261.509344) (xy 24.456371 -261.470635) (xy 24.501729 -261.438184)
			(xy 24.551329 -261.412683) (xy 24.604113 -261.394676) (xy 24.658956 -261.384546) (xy 24.71469 -261.382509)
			(xy 24.770127 -261.388609) (xy 24.824084 -261.402715) (xy 24.875413 -261.424527) (xy 24.923019 -261.453581)
			(xy 24.965887 -261.489256) (xy 25.003104 -261.530793) (xy 25.033877 -261.577306) (xy 25.057549 -261.627803)
			(xy 25.073617 -261.68121) (xy 25.081737 -261.736386) (xy 25.082246 -261.764272) (xy 25.081737 -261.792158)
			(xy 25.077941 -261.817951) (xy 25.519366 -261.817951) (xy 25.519366 -261.763449) (xy 25.527122 -261.709501)
			(xy 25.542477 -261.657206) (xy 25.565117 -261.607629) (xy 25.594582 -261.561778) (xy 25.630273 -261.520587)
			(xy 25.671462 -261.484894) (xy 25.717311 -261.455427) (xy 25.766888 -261.432784) (xy 25.819182 -261.417426)
			(xy 25.873129 -261.409667) (xy 25.90038 -261.40918) (xy 25.929298 -261.409682) (xy 25.986471 -261.41841)
			(xy 26.041672 -261.435669) (xy 26.093634 -261.461064) (xy 26.141167 -261.494012) (xy 26.183182 -261.533758)
			(xy 26.20137 -261.556246) (xy 26.208941 -261.564997) (xy 26.229693 -261.575185) (xy 26.241248 -261.575804)
			(xy 26.321512 -261.575804) (xy 26.33308 -261.575239) (xy 26.353851 -261.56504) (xy 26.36139 -261.556246)
			(xy 26.378143 -261.535463) (xy 26.416497 -261.498333) (xy 26.459651 -261.466911) (xy 26.506765 -261.441812)
			(xy 26.556917 -261.423526) (xy 26.609128 -261.412409) (xy 26.66238 -261.408679) (xy 26.715632 -261.412409)
			(xy 26.767843 -261.423526) (xy 26.817995 -261.441812) (xy 26.865109 -261.466911) (xy 26.908263 -261.498333)
			(xy 26.946617 -261.535463) (xy 26.96337 -261.556246) (xy 26.970941 -261.564997) (xy 26.991693 -261.575185)
			(xy 27.003248 -261.575804) (xy 27.083512 -261.575804) (xy 27.09508 -261.575239) (xy 27.115851 -261.56504)
			(xy 27.12339 -261.556246) (xy 27.140143 -261.535463) (xy 27.178497 -261.498333) (xy 27.221651 -261.466911)
			(xy 27.268765 -261.441812) (xy 27.318917 -261.423526) (xy 27.371128 -261.412409) (xy 27.42438 -261.408679)
			(xy 27.477632 -261.412409) (xy 27.529843 -261.423526) (xy 27.579995 -261.441812) (xy 27.627109 -261.466911)
			(xy 27.670263 -261.498333) (xy 27.708617 -261.535463) (xy 27.72537 -261.556246) (xy 27.732941 -261.564997)
			(xy 27.753693 -261.575185) (xy 27.765248 -261.575804) (xy 27.845512 -261.575804) (xy 27.85708 -261.575239)
			(xy 27.877851 -261.56504) (xy 27.88539 -261.556246) (xy 27.903573 -261.533756) (xy 27.945596 -261.494024)
			(xy 27.993133 -261.461087) (xy 28.045096 -261.4357) (xy 28.100294 -261.418445) (xy 28.157464 -261.409716)
			(xy 28.18638 -261.40918) (xy 28.213633 -261.409666) (xy 28.267584 -261.41742) (xy 28.319883 -261.432774)
			(xy 28.369464 -261.455415) (xy 28.399098 -261.474458) (xy 28.769562 -261.474458) (xy 28.773633 -261.418836)
			(xy 28.785759 -261.364399) (xy 28.805682 -261.312308) (xy 28.832978 -261.263673) (xy 28.867064 -261.21953)
			(xy 28.907213 -261.180821) (xy 28.952571 -261.14837) (xy 29.002171 -261.122869) (xy 29.054955 -261.104862)
			(xy 29.109798 -261.094732) (xy 29.165532 -261.092695) (xy 29.220969 -261.098795) (xy 29.274926 -261.112901)
			(xy 29.326255 -261.134713) (xy 29.373861 -261.163767) (xy 29.416729 -261.199442) (xy 29.453946 -261.240979)
			(xy 29.484719 -261.287492) (xy 29.508391 -261.337989) (xy 29.524459 -261.391396) (xy 29.532579 -261.446572)
			(xy 29.533088 -261.474458) (xy 30.2547 -261.474458) (xy 30.258771 -261.418836) (xy 30.270897 -261.364399)
			(xy 30.29082 -261.312308) (xy 30.318116 -261.263673) (xy 30.352202 -261.21953) (xy 30.392351 -261.180821)
			(xy 30.437709 -261.14837) (xy 30.487309 -261.122869) (xy 30.540093 -261.104862) (xy 30.594936 -261.094732)
			(xy 30.65067 -261.092695) (xy 30.706107 -261.098795) (xy 30.760064 -261.112901) (xy 30.811393 -261.134713)
			(xy 30.858999 -261.163767) (xy 30.901867 -261.199442) (xy 30.939084 -261.240979) (xy 30.969857 -261.287492)
			(xy 30.993529 -261.337989) (xy 31.009597 -261.391396) (xy 31.017717 -261.446572) (xy 31.018226 -261.474458)
			(xy 31.017717 -261.502344) (xy 31.009597 -261.55752) (xy 30.993529 -261.610927) (xy 30.969857 -261.661424)
			(xy 30.939084 -261.707937) (xy 30.901867 -261.749474) (xy 30.858999 -261.785149) (xy 30.811393 -261.814203)
			(xy 30.760064 -261.836015) (xy 30.706107 -261.850121) (xy 30.65067 -261.856221) (xy 30.594936 -261.854184)
			(xy 30.540093 -261.844054) (xy 30.487309 -261.826047) (xy 30.437709 -261.800546) (xy 30.392351 -261.768095)
			(xy 30.352202 -261.729386) (xy 30.318116 -261.685243) (xy 30.29082 -261.636608) (xy 30.270897 -261.584517)
			(xy 30.258771 -261.53008) (xy 30.2547 -261.474458) (xy 29.533088 -261.474458) (xy 29.532579 -261.502344)
			(xy 29.524459 -261.55752) (xy 29.508391 -261.610927) (xy 29.484719 -261.661424) (xy 29.453946 -261.707937)
			(xy 29.416729 -261.749474) (xy 29.373861 -261.785149) (xy 29.326255 -261.814203) (xy 29.274926 -261.836015)
			(xy 29.220969 -261.850121) (xy 29.165532 -261.856221) (xy 29.109798 -261.854184) (xy 29.054955 -261.844054)
			(xy 29.002171 -261.826047) (xy 28.952571 -261.800546) (xy 28.907213 -261.768095) (xy 28.867064 -261.729386)
			(xy 28.832978 -261.685243) (xy 28.805682 -261.636608) (xy 28.785759 -261.584517) (xy 28.773633 -261.53008)
			(xy 28.769562 -261.474458) (xy 28.399098 -261.474458) (xy 28.415318 -261.484881) (xy 28.456512 -261.520574)
			(xy 28.492207 -261.561766) (xy 28.521676 -261.607618) (xy 28.544319 -261.657198) (xy 28.559675 -261.709496)
			(xy 28.567433 -261.763447) (xy 28.567433 -261.817953) (xy 28.559675 -261.871904) (xy 28.544319 -261.924202)
			(xy 28.521676 -261.973782) (xy 28.492207 -262.019634) (xy 28.456512 -262.060826) (xy 28.415318 -262.096519)
			(xy 28.369464 -262.125985) (xy 28.319883 -262.148626) (xy 28.267584 -262.16398) (xy 28.213633 -262.171734)
			(xy 28.18638 -262.172196) (xy 28.157465 -262.171622) (xy 28.100296 -262.162905) (xy 28.045099 -262.145658)
			(xy 27.993137 -262.120277) (xy 27.945601 -262.087343) (xy 27.903582 -262.047611) (xy 27.88539 -262.02513)
			(xy 27.87784 -262.016356) (xy 27.857072 -262.006182) (xy 27.845512 -262.005572) (xy 27.765248 -262.005572)
			(xy 27.75368 -262.006145) (xy 27.732907 -262.016335) (xy 27.72537 -262.02513) (xy 27.708617 -262.045913)
			(xy 27.670263 -262.083043) (xy 27.627109 -262.114465) (xy 27.579995 -262.139564) (xy 27.529843 -262.15785)
			(xy 27.477632 -262.168967) (xy 27.42438 -262.172697) (xy 27.371128 -262.168967) (xy 27.318917 -262.15785)
			(xy 27.268765 -262.139564) (xy 27.221651 -262.114465) (xy 27.178497 -262.083043) (xy 27.140143 -262.045913)
			(xy 27.12339 -262.02513) (xy 27.11584 -262.016356) (xy 27.095072 -262.006182) (xy 27.083512 -262.005572)
			(xy 27.003248 -262.005572) (xy 26.99168 -262.006145) (xy 26.970907 -262.016335) (xy 26.96337 -262.02513)
			(xy 26.946617 -262.045913) (xy 26.908263 -262.083043) (xy 26.865109 -262.114465) (xy 26.817995 -262.139564)
			(xy 26.767843 -262.15785) (xy 26.715632 -262.168967) (xy 26.66238 -262.172697) (xy 26.609128 -262.168967)
			(xy 26.556917 -262.15785) (xy 26.506765 -262.139564) (xy 26.459651 -262.114465) (xy 26.416497 -262.083043)
			(xy 26.378143 -262.045913) (xy 26.36139 -262.02513) (xy 26.35384 -262.016356) (xy 26.333072 -262.006182)
			(xy 26.321512 -262.005572) (xy 26.241248 -262.005572) (xy 26.22968 -262.006145) (xy 26.208907 -262.016335)
			(xy 26.20137 -262.02513) (xy 26.183204 -262.047634) (xy 26.141178 -262.087367) (xy 26.093637 -262.120302)
			(xy 26.041672 -262.145687) (xy 25.98647 -262.162939) (xy 25.929297 -262.171663) (xy 25.90038 -262.172196)
			(xy 25.873129 -262.171733) (xy 25.819182 -262.163974) (xy 25.766888 -262.148616) (xy 25.717311 -262.125973)
			(xy 25.671462 -262.096506) (xy 25.630273 -262.060813) (xy 25.594582 -262.019622) (xy 25.565117 -261.973771)
			(xy 25.542477 -261.924194) (xy 25.527122 -261.871899) (xy 25.519366 -261.817951) (xy 25.077941 -261.817951)
			(xy 25.073617 -261.847334) (xy 25.057549 -261.900741) (xy 25.033877 -261.951238) (xy 25.003104 -261.997751)
			(xy 24.965887 -262.039288) (xy 24.923019 -262.074963) (xy 24.875413 -262.104017) (xy 24.824084 -262.125829)
			(xy 24.770127 -262.139935) (xy 24.71469 -262.146035) (xy 24.658956 -262.143998) (xy 24.604113 -262.133868)
			(xy 24.551329 -262.115861) (xy 24.501729 -262.09036) (xy 24.456371 -262.057909) (xy 24.416222 -262.0192)
			(xy 24.382136 -261.975057) (xy 24.35484 -261.926422) (xy 24.334917 -261.874331) (xy 24.322791 -261.819894)
			(xy 24.31872 -261.764272) (xy 1.468374 -261.764272) (xy 1.468374 -262.519668) (xy 22.592282 -262.519668)
			(xy 22.596353 -262.464046) (xy 22.608479 -262.409609) (xy 22.628402 -262.357518) (xy 22.655698 -262.308883)
			(xy 22.689784 -262.26474) (xy 22.729933 -262.226031) (xy 22.775291 -262.19358) (xy 22.824891 -262.168079)
			(xy 22.877675 -262.150072) (xy 22.932518 -262.139942) (xy 22.988252 -262.137905) (xy 23.043689 -262.144005)
			(xy 23.097646 -262.158111) (xy 23.148975 -262.179923) (xy 23.196581 -262.208977) (xy 23.239449 -262.244652)
			(xy 23.276666 -262.286189) (xy 23.307439 -262.332702) (xy 23.331111 -262.383199) (xy 23.347179 -262.436606)
			(xy 23.355299 -262.491782) (xy 23.355808 -262.519668) (xy 23.355299 -262.547554) (xy 23.347179 -262.60273)
			(xy 23.331111 -262.656137) (xy 23.307439 -262.706634) (xy 23.276666 -262.753147) (xy 23.239449 -262.794684)
			(xy 23.196581 -262.830359) (xy 23.148975 -262.859413) (xy 23.097646 -262.881225) (xy 23.043689 -262.895331)
			(xy 22.988252 -262.901431) (xy 22.932518 -262.899394) (xy 22.877675 -262.889264) (xy 22.824891 -262.871257)
			(xy 22.775291 -262.845756) (xy 22.729933 -262.813305) (xy 22.689784 -262.774596) (xy 22.655698 -262.730453)
			(xy 22.628402 -262.681818) (xy 22.608479 -262.629727) (xy 22.596353 -262.57529) (xy 22.592282 -262.519668)
			(xy 1.468374 -262.519668) (xy 1.468374 -262.912352) (xy 25.168858 -262.912352) (xy 25.172929 -262.85673)
			(xy 25.185055 -262.802293) (xy 25.204978 -262.750202) (xy 25.232274 -262.701567) (xy 25.26636 -262.657424)
			(xy 25.306509 -262.618715) (xy 25.351867 -262.586264) (xy 25.401467 -262.560763) (xy 25.454251 -262.542756)
			(xy 25.509094 -262.532626) (xy 25.564828 -262.530589) (xy 25.620265 -262.536689) (xy 25.674222 -262.550795)
			(xy 25.725551 -262.572607) (xy 25.773157 -262.601661) (xy 25.816025 -262.637336) (xy 25.853242 -262.678873)
			(xy 25.884015 -262.725386) (xy 25.907687 -262.775883) (xy 25.923755 -262.82929) (xy 25.931875 -262.884466)
			(xy 25.932384 -262.912352) (xy 25.931875 -262.940238) (xy 25.923755 -262.995414) (xy 25.907687 -263.048821)
			(xy 25.884015 -263.099318) (xy 25.853242 -263.145831) (xy 25.816025 -263.187368) (xy 25.773157 -263.223043)
			(xy 25.725551 -263.252097) (xy 25.674222 -263.273909) (xy 25.620265 -263.288015) (xy 25.564828 -263.294115)
			(xy 25.509094 -263.292078) (xy 25.454251 -263.281948) (xy 25.401467 -263.263941) (xy 25.351867 -263.23844)
			(xy 25.306509 -263.205989) (xy 25.26636 -263.16728) (xy 25.232274 -263.123137) (xy 25.204978 -263.074502)
			(xy 25.185055 -263.022411) (xy 25.172929 -262.967974) (xy 25.168858 -262.912352) (xy 1.468374 -262.912352)
			(xy 1.468374 -264.017506) (xy 36.356542 -264.017506) (xy 36.360613 -263.961884) (xy 36.372739 -263.907447)
			(xy 36.392662 -263.855356) (xy 36.419958 -263.806721) (xy 36.454044 -263.762578) (xy 36.494193 -263.723869)
			(xy 36.539551 -263.691418) (xy 36.589151 -263.665917) (xy 36.641935 -263.64791) (xy 36.696778 -263.63778)
			(xy 36.752512 -263.635743) (xy 36.807949 -263.641843) (xy 36.861906 -263.655949) (xy 36.913235 -263.677761)
			(xy 36.960841 -263.706815) (xy 37.003709 -263.74249) (xy 37.040926 -263.784027) (xy 37.071699 -263.83054)
			(xy 37.095371 -263.881037) (xy 37.111439 -263.934444) (xy 37.119559 -263.98962) (xy 37.120068 -264.017506)
			(xy 37.119559 -264.045392) (xy 37.111439 -264.100568) (xy 37.095371 -264.153975) (xy 37.078854 -264.18921)
			(xy 37.95979 -264.18921) (xy 37.963861 -264.133588) (xy 37.975987 -264.079151) (xy 37.99591 -264.02706)
			(xy 38.023206 -263.978425) (xy 38.057292 -263.934282) (xy 38.097441 -263.895573) (xy 38.142799 -263.863122)
			(xy 38.192399 -263.837621) (xy 38.245183 -263.819614) (xy 38.300026 -263.809484) (xy 38.35576 -263.807447)
			(xy 38.411197 -263.813547) (xy 38.465154 -263.827653) (xy 38.516483 -263.849465) (xy 38.564089 -263.878519)
			(xy 38.606957 -263.914194) (xy 38.644174 -263.955731) (xy 38.674947 -264.002244) (xy 38.698619 -264.052741)
			(xy 38.714687 -264.106148) (xy 38.722807 -264.161324) (xy 38.723316 -264.18921) (xy 38.722807 -264.217096)
			(xy 38.714687 -264.272272) (xy 38.698619 -264.325679) (xy 38.674947 -264.376176) (xy 38.644174 -264.422689)
			(xy 38.606957 -264.464226) (xy 38.564089 -264.499901) (xy 38.516483 -264.528955) (xy 38.507265 -264.532872)
			(xy 41.281094 -264.532872) (xy 41.285165 -264.47725) (xy 41.297291 -264.422813) (xy 41.317214 -264.370722)
			(xy 41.34451 -264.322087) (xy 41.378596 -264.277944) (xy 41.418745 -264.239235) (xy 41.464103 -264.206784)
			(xy 41.513703 -264.181283) (xy 41.566487 -264.163276) (xy 41.62133 -264.153146) (xy 41.677064 -264.151109)
			(xy 41.732501 -264.157209) (xy 41.786458 -264.171315) (xy 41.837787 -264.193127) (xy 41.885393 -264.222181)
			(xy 41.928261 -264.257856) (xy 41.965478 -264.299393) (xy 41.996251 -264.345906) (xy 42.019923 -264.396403)
			(xy 42.035991 -264.44981) (xy 42.044111 -264.504986) (xy 42.04462 -264.532872) (xy 42.044111 -264.560758)
			(xy 42.035991 -264.615934) (xy 42.019923 -264.669341) (xy 41.996251 -264.719838) (xy 41.965478 -264.766351)
			(xy 41.928261 -264.807888) (xy 41.885393 -264.843563) (xy 41.837787 -264.872617) (xy 41.786458 -264.894429)
			(xy 41.732501 -264.908535) (xy 41.677064 -264.914635) (xy 41.62133 -264.912598) (xy 41.566487 -264.902468)
			(xy 41.513703 -264.884461) (xy 41.464103 -264.85896) (xy 41.418745 -264.826509) (xy 41.378596 -264.7878)
			(xy 41.34451 -264.743657) (xy 41.317214 -264.695022) (xy 41.297291 -264.642931) (xy 41.285165 -264.588494)
			(xy 41.281094 -264.532872) (xy 38.507265 -264.532872) (xy 38.465154 -264.550767) (xy 38.411197 -264.564873)
			(xy 38.35576 -264.570973) (xy 38.300026 -264.568936) (xy 38.245183 -264.558806) (xy 38.192399 -264.540799)
			(xy 38.142799 -264.515298) (xy 38.097441 -264.482847) (xy 38.057292 -264.444138) (xy 38.023206 -264.399995)
			(xy 37.99591 -264.35136) (xy 37.975987 -264.299269) (xy 37.963861 -264.244832) (xy 37.95979 -264.18921)
			(xy 37.078854 -264.18921) (xy 37.071699 -264.204472) (xy 37.040926 -264.250985) (xy 37.003709 -264.292522)
			(xy 36.960841 -264.328197) (xy 36.913235 -264.357251) (xy 36.861906 -264.379063) (xy 36.807949 -264.393169)
			(xy 36.752512 -264.399269) (xy 36.696778 -264.397232) (xy 36.641935 -264.387102) (xy 36.589151 -264.369095)
			(xy 36.539551 -264.343594) (xy 36.494193 -264.311143) (xy 36.454044 -264.272434) (xy 36.419958 -264.228291)
			(xy 36.392662 -264.179656) (xy 36.372739 -264.127565) (xy 36.360613 -264.073128) (xy 36.356542 -264.017506)
			(xy 1.468374 -264.017506) (xy 1.468374 -265.16457) (xy 40.46296 -265.16457) (xy 40.467031 -265.108948)
			(xy 40.479157 -265.054511) (xy 40.49908 -265.00242) (xy 40.526376 -264.953785) (xy 40.560462 -264.909642)
			(xy 40.600611 -264.870933) (xy 40.645969 -264.838482) (xy 40.695569 -264.812981) (xy 40.748353 -264.794974)
			(xy 40.803196 -264.784844) (xy 40.85893 -264.782807) (xy 40.914367 -264.788907) (xy 40.968324 -264.803013)
			(xy 41.019653 -264.824825) (xy 41.067259 -264.853879) (xy 41.110127 -264.889554) (xy 41.147344 -264.931091)
			(xy 41.178117 -264.977604) (xy 41.201789 -265.028101) (xy 41.217857 -265.081508) (xy 41.225977 -265.136684)
			(xy 41.226486 -265.16457) (xy 41.225977 -265.192456) (xy 41.217857 -265.247632) (xy 41.201789 -265.301039)
			(xy 41.178117 -265.351536) (xy 41.147344 -265.398049) (xy 41.110127 -265.439586) (xy 41.067259 -265.475261)
			(xy 41.019653 -265.504315) (xy 40.968324 -265.526127) (xy 40.914367 -265.540233) (xy 40.85893 -265.546333)
			(xy 40.803196 -265.544296) (xy 40.748353 -265.534166) (xy 40.695569 -265.516159) (xy 40.645969 -265.490658)
			(xy 40.600611 -265.458207) (xy 40.560462 -265.419498) (xy 40.526376 -265.375355) (xy 40.49908 -265.32672)
			(xy 40.479157 -265.274629) (xy 40.467031 -265.220192) (xy 40.46296 -265.16457) (xy 1.468374 -265.16457)
			(xy 1.468374 -265.804904) (xy 37.345618 -265.804904) (xy 37.349689 -265.749282) (xy 37.361815 -265.694845)
			(xy 37.381738 -265.642754) (xy 37.409034 -265.594119) (xy 37.44312 -265.549976) (xy 37.483269 -265.511267)
			(xy 37.528627 -265.478816) (xy 37.578227 -265.453315) (xy 37.631011 -265.435308) (xy 37.685854 -265.425178)
			(xy 37.741588 -265.423141) (xy 37.797025 -265.429241) (xy 37.850982 -265.443347) (xy 37.902311 -265.465159)
			(xy 37.949917 -265.494213) (xy 37.992785 -265.529888) (xy 38.030002 -265.571425) (xy 38.060775 -265.617938)
			(xy 38.084447 -265.668435) (xy 38.100515 -265.721842) (xy 38.108635 -265.777018) (xy 38.109144 -265.804904)
			(xy 38.108635 -265.83279) (xy 38.100515 -265.887966) (xy 38.084447 -265.941373) (xy 38.060775 -265.99187)
			(xy 38.030002 -266.038383) (xy 37.992785 -266.07992) (xy 37.949917 -266.115595) (xy 37.902311 -266.144649)
			(xy 37.850982 -266.166461) (xy 37.797025 -266.180567) (xy 37.741588 -266.186667) (xy 37.685854 -266.18463)
			(xy 37.631011 -266.1745) (xy 37.578227 -266.156493) (xy 37.528627 -266.130992) (xy 37.483269 -266.098541)
			(xy 37.44312 -266.059832) (xy 37.409034 -266.015689) (xy 37.381738 -265.967054) (xy 37.361815 -265.914963)
			(xy 37.349689 -265.860526) (xy 37.345618 -265.804904) (xy 1.468374 -265.804904) (xy 1.468374 -267.500608)
			(xy 17.210784 -267.500608) (xy 17.214855 -267.444986) (xy 17.226981 -267.390549) (xy 17.246904 -267.338458)
			(xy 17.2742 -267.289823) (xy 17.308286 -267.24568) (xy 17.348435 -267.206971) (xy 17.393793 -267.17452)
			(xy 17.443393 -267.149019) (xy 17.496177 -267.131012) (xy 17.55102 -267.120882) (xy 17.606754 -267.118845)
			(xy 17.662191 -267.124945) (xy 17.716148 -267.139051) (xy 17.767477 -267.160863) (xy 17.815083 -267.189917)
			(xy 17.857951 -267.225592) (xy 17.895168 -267.267129) (xy 17.925941 -267.313642) (xy 17.949613 -267.364139)
			(xy 17.965681 -267.417546) (xy 17.973801 -267.472722) (xy 17.97431 -267.500608) (xy 17.973801 -267.528494)
			(xy 17.965681 -267.58367) (xy 17.949613 -267.637077) (xy 17.925941 -267.687574) (xy 17.895168 -267.734087)
			(xy 17.857951 -267.775624) (xy 17.815083 -267.811299) (xy 17.767477 -267.840353) (xy 17.716148 -267.862165)
			(xy 17.662191 -267.876271) (xy 17.606754 -267.882371) (xy 17.55102 -267.880334) (xy 17.496177 -267.870204)
			(xy 17.443393 -267.852197) (xy 17.393793 -267.826696) (xy 17.348435 -267.794245) (xy 17.308286 -267.755536)
			(xy 17.2742 -267.711393) (xy 17.246904 -267.662758) (xy 17.226981 -267.610667) (xy 17.214855 -267.55623)
			(xy 17.210784 -267.500608) (xy 1.468374 -267.500608) (xy 1.468374 -270.100806) (xy 17.238724 -270.100806)
			(xy 17.242795 -270.045184) (xy 17.254921 -269.990747) (xy 17.274844 -269.938656) (xy 17.30214 -269.890021)
			(xy 17.336226 -269.845878) (xy 17.376375 -269.807169) (xy 17.421733 -269.774718) (xy 17.471333 -269.749217)
			(xy 17.524117 -269.73121) (xy 17.57896 -269.72108) (xy 17.634694 -269.719043) (xy 17.690131 -269.725143)
			(xy 17.744088 -269.739249) (xy 17.795417 -269.761061) (xy 17.843023 -269.790115) (xy 17.885891 -269.82579)
			(xy 17.923108 -269.867327) (xy 17.953881 -269.91384) (xy 17.977553 -269.964337) (xy 17.993621 -270.017744)
			(xy 18.001741 -270.07292) (xy 18.00225 -270.100806) (xy 18.001741 -270.128692) (xy 17.993621 -270.183868)
			(xy 17.977553 -270.237275) (xy 17.953881 -270.287772) (xy 17.923108 -270.334285) (xy 17.885891 -270.375822)
			(xy 17.843023 -270.411497) (xy 17.795417 -270.440551) (xy 17.744088 -270.462363) (xy 17.690131 -270.476469)
			(xy 17.634694 -270.482569) (xy 17.57896 -270.480532) (xy 17.524117 -270.470402) (xy 17.471333 -270.452395)
			(xy 17.421733 -270.426894) (xy 17.376375 -270.394443) (xy 17.336226 -270.355734) (xy 17.30214 -270.311591)
			(xy 17.274844 -270.262956) (xy 17.254921 -270.210865) (xy 17.242795 -270.156428) (xy 17.238724 -270.100806)
			(xy 1.468374 -270.100806) (xy 1.468374 -270.107918) (xy 1.468816 -270.117707) (xy 1.476125 -270.135868)
			(xy 1.482598 -270.143224) (xy 1.538478 -270.201136) (xy 1.556004 -270.209264) (xy 1.566164 -270.209518)
			(xy 1.593973 -270.211099) (xy 1.648727 -270.22132) (xy 1.701412 -270.239394) (xy 1.750909 -270.264936)
			(xy 1.796167 -270.297404) (xy 1.836223 -270.336107) (xy 1.870225 -270.380223) (xy 1.897451 -270.428815)
			(xy 1.917322 -270.480849) (xy 1.929417 -270.535219) (xy 1.933477 -270.59077) (xy 1.929417 -270.646321)
			(xy 1.917322 -270.700691) (xy 1.897451 -270.752725) (xy 1.870225 -270.801317) (xy 1.836222 -270.845433)
			(xy 1.796167 -270.884136) (xy 1.750909 -270.916604) (xy 1.701412 -270.942146) (xy 1.648727 -270.96022)
			(xy 1.593973 -270.970441) (xy 1.566164 -270.972026) (xy 1.556004 -270.97228) (xy 1.538478 -270.980408)
			(xy 1.482598 -271.03832) (xy 1.476118 -271.045673) (xy 1.468803 -271.063835) (xy 1.468374 -271.073626)
			(xy 1.468374 -271.184624) (xy 17.47469 -271.184624) (xy 17.478761 -271.129002) (xy 17.490887 -271.074565)
			(xy 17.51081 -271.022474) (xy 17.538106 -270.973839) (xy 17.572192 -270.929696) (xy 17.612341 -270.890987)
			(xy 17.657699 -270.858536) (xy 17.707299 -270.833035) (xy 17.760083 -270.815028) (xy 17.814926 -270.804898)
			(xy 17.87066 -270.802861) (xy 17.926097 -270.808961) (xy 17.980054 -270.823067) (xy 18.031383 -270.844879)
			(xy 18.078989 -270.873933) (xy 18.11018 -270.89989) (xy 24.898611 -270.89989) (xy 24.902617 -270.704835)
			(xy 24.914627 -270.510109) (xy 24.934622 -270.31604) (xy 24.962567 -270.122956) (xy 24.998416 -269.931181)
			(xy 25.042108 -269.741041) (xy 25.093569 -269.552854) (xy 25.152713 -269.366939) (xy 25.21944 -269.183608)
			(xy 25.293637 -269.003172) (xy 25.375179 -268.825934) (xy 25.46393 -268.652193) (xy 25.559738 -268.482242)
			(xy 25.662443 -268.316368) (xy 25.771871 -268.15485) (xy 25.887838 -267.997961) (xy 26.010149 -267.845966)
			(xy 26.138596 -267.69912) (xy 26.272964 -267.557671) (xy 26.413026 -267.421858) (xy 26.558545 -267.291909)
			(xy 26.709277 -267.168045) (xy 26.864967 -267.050473) (xy 27.025353 -266.939393) (xy 27.190164 -266.83499)
			(xy 27.359122 -266.737442) (xy 27.531943 -266.646913) (xy 27.708335 -266.563555) (xy 27.888 -266.487509)
			(xy 28.070635 -266.418904) (xy 28.255934 -266.357854) (xy 28.443582 -266.304464) (xy 28.633264 -266.258822)
			(xy 28.824661 -266.221006) (xy 29.017448 -266.19108) (xy 29.211301 -266.169094) (xy 29.405894 -266.155085)
			(xy 29.600897 -266.149077) (xy 29.795983 -266.15108) (xy 29.990822 -266.161091) (xy 30.185086 -266.179092)
			(xy 30.378447 -266.205054) (xy 30.57058 -266.238932) (xy 30.761159 -266.280669) (xy 30.949864 -266.330196)
			(xy 31.136377 -266.387428) (xy 31.320383 -266.452269) (xy 31.48472 -266.517882) (xy 40.39692 -266.517882)
			(xy 40.400991 -266.46226) (xy 40.413117 -266.407823) (xy 40.43304 -266.355732) (xy 40.460336 -266.307097)
			(xy 40.494422 -266.262954) (xy 40.534571 -266.224245) (xy 40.579929 -266.191794) (xy 40.629529 -266.166293)
			(xy 40.682313 -266.148286) (xy 40.737156 -266.138156) (xy 40.79289 -266.136119) (xy 40.848327 -266.142219)
			(xy 40.902284 -266.156325) (xy 40.953613 -266.178137) (xy 41.001219 -266.207191) (xy 41.044087 -266.242866)
			(xy 41.081304 -266.284403) (xy 41.112077 -266.330916) (xy 41.135749 -266.381413) (xy 41.151817 -266.43482)
			(xy 41.159937 -266.489996) (xy 41.160446 -266.517882) (xy 41.159937 -266.545768) (xy 41.151817 -266.600944)
			(xy 41.135749 -266.654351) (xy 41.112077 -266.704848) (xy 41.081304 -266.751361) (xy 41.044087 -266.792898)
			(xy 41.001219 -266.828573) (xy 40.953613 -266.857627) (xy 40.902284 -266.879439) (xy 40.848327 -266.893545)
			(xy 40.79289 -266.899645) (xy 40.737156 -266.897608) (xy 40.682313 -266.887478) (xy 40.629529 -266.869471)
			(xy 40.579929 -266.84397) (xy 40.534571 -266.811519) (xy 40.494422 -266.77281) (xy 40.460336 -266.728667)
			(xy 40.43304 -266.680032) (xy 40.413117 -266.627941) (xy 40.400991 -266.573504) (xy 40.39692 -266.517882)
			(xy 31.48472 -266.517882) (xy 31.501571 -266.52461) (xy 31.679637 -266.604328) (xy 31.85428 -266.69129)
			(xy 32.025206 -266.785349) (xy 32.192125 -266.886345) (xy 32.308409 -266.963398) (xy 38.656004 -266.963398)
			(xy 38.660075 -266.907776) (xy 38.672201 -266.853339) (xy 38.692124 -266.801248) (xy 38.71942 -266.752613)
			(xy 38.753506 -266.70847) (xy 38.793655 -266.669761) (xy 38.839013 -266.63731) (xy 38.888613 -266.611809)
			(xy 38.941397 -266.593802) (xy 38.99624 -266.583672) (xy 39.051974 -266.581635) (xy 39.107411 -266.587735)
			(xy 39.161368 -266.601841) (xy 39.212697 -266.623653) (xy 39.260303 -266.652707) (xy 39.303171 -266.688382)
			(xy 39.340388 -266.729919) (xy 39.371161 -266.776432) (xy 39.394833 -266.826929) (xy 39.410901 -266.880336)
			(xy 39.419021 -266.935512) (xy 39.41953 -266.963398) (xy 39.419021 -266.991284) (xy 39.410901 -267.04646)
			(xy 39.394833 -267.099867) (xy 39.371161 -267.150364) (xy 39.340388 -267.196877) (xy 39.303171 -267.238414)
			(xy 39.260303 -267.274089) (xy 39.212697 -267.303143) (xy 39.161368 -267.324955) (xy 39.107411 -267.339061)
			(xy 39.051974 -267.345161) (xy 38.99624 -267.343124) (xy 38.941397 -267.332994) (xy 38.888613 -267.314987)
			(xy 38.839013 -267.289486) (xy 38.793655 -267.257035) (xy 38.753506 -267.218326) (xy 38.71942 -267.174183)
			(xy 38.692124 -267.125548) (xy 38.672201 -267.073457) (xy 38.660075 -267.01902) (xy 38.656004 -266.963398)
			(xy 32.308409 -266.963398) (xy 32.354758 -266.99411) (xy 32.512829 -267.10846) (xy 32.666072 -267.229203)
			(xy 32.814229 -267.356137) (xy 32.95705 -267.489045) (xy 33.045174 -267.578078) (xy 36.853112 -267.578078)
			(xy 36.857183 -267.522456) (xy 36.869309 -267.468019) (xy 36.889232 -267.415928) (xy 36.916528 -267.367293)
			(xy 36.950614 -267.32315) (xy 36.990763 -267.284441) (xy 37.036121 -267.25199) (xy 37.085721 -267.226489)
			(xy 37.138505 -267.208482) (xy 37.193348 -267.198352) (xy 37.249082 -267.196315) (xy 37.304519 -267.202415)
			(xy 37.358476 -267.216521) (xy 37.409805 -267.238333) (xy 37.457411 -267.267387) (xy 37.500279 -267.303062)
			(xy 37.537496 -267.344599) (xy 37.568269 -267.391112) (xy 37.591941 -267.441609) (xy 37.608009 -267.495016)
			(xy 37.616129 -267.550192) (xy 37.616638 -267.578078) (xy 37.616156 -267.604494) (xy 40.41775 -267.604494)
			(xy 40.418236 -267.577243) (xy 40.425992 -267.523295) (xy 40.441347 -267.471) (xy 40.463989 -267.421423)
			(xy 40.493455 -267.375573) (xy 40.529146 -267.334382) (xy 40.570337 -267.298691) (xy 40.616187 -267.269225)
			(xy 40.665764 -267.246583) (xy 40.718059 -267.231228) (xy 40.772007 -267.223472) (xy 40.826509 -267.223472)
			(xy 40.880457 -267.231228) (xy 40.932752 -267.246583) (xy 40.982329 -267.269225) (xy 41.028179 -267.298691)
			(xy 41.06937 -267.334382) (xy 41.105061 -267.375573) (xy 41.134527 -267.421423) (xy 41.157169 -267.471)
			(xy 41.172524 -267.523295) (xy 41.18028 -267.577243) (xy 41.180766 -267.604494) (xy 41.180261 -267.632763)
			(xy 41.17193 -267.688683) (xy 41.155434 -267.74276) (xy 41.131135 -267.79381) (xy 41.099566 -267.840712)
			(xy 41.061418 -267.88244) (xy 41.039796 -267.900658) (xy 41.029673 -267.909485) (xy 41.013976 -267.931265)
			(xy 41.004494 -267.956382) (xy 41.001881 -267.983101) (xy 41.006318 -268.009579) (xy 41.017498 -268.033987)
			(xy 41.034649 -268.05464) (xy 41.045384 -268.06271) (xy 41.066526 -268.078075) (xy 41.104806 -268.113657)
			(xy 41.13787 -268.154133) (xy 41.165096 -268.198745) (xy 41.185977 -268.246657) (xy 41.200119 -268.29697)
			(xy 41.207259 -268.348744) (xy 41.20769 -268.374876) (xy 41.207204 -268.402127) (xy 41.199448 -268.456075)
			(xy 41.184093 -268.50837) (xy 41.161451 -268.557947) (xy 41.131985 -268.603797) (xy 41.096294 -268.644988)
			(xy 41.055103 -268.680679) (xy 41.009253 -268.710145) (xy 40.959676 -268.732787) (xy 40.907381 -268.748142)
			(xy 40.853433 -268.755898) (xy 40.798931 -268.755898) (xy 40.744983 -268.748142) (xy 40.692688 -268.732787)
			(xy 40.643111 -268.710145) (xy 40.597261 -268.680679) (xy 40.55607 -268.644988) (xy 40.520379 -268.603797)
			(xy 40.490913 -268.557947) (xy 40.468271 -268.50837) (xy 40.452916 -268.456075) (xy 40.44516 -268.402127)
			(xy 40.444674 -268.374876) (xy 40.445179 -268.346607) (xy 40.453513 -268.290688) (xy 40.470011 -268.236612)
			(xy 40.49431 -268.185563) (xy 40.525878 -268.13866) (xy 40.564023 -268.096931) (xy 40.585644 -268.078712)
			(xy 40.595805 -268.069923) (xy 40.611512 -268.048137) (xy 40.620998 -268.02301) (xy 40.623608 -267.99628)
			(xy 40.619163 -267.969793) (xy 40.607969 -267.945379) (xy 40.5908 -267.924726) (xy 40.580056 -267.91666)
			(xy 40.558934 -267.90127) (xy 40.520655 -267.86569) (xy 40.487592 -267.825217) (xy 40.460364 -267.78061)
			(xy 40.439481 -267.732703) (xy 40.425333 -267.682394) (xy 40.418186 -267.630624) (xy 40.41775 -267.604494)
			(xy 37.616156 -267.604494) (xy 37.616129 -267.605964) (xy 37.608009 -267.66114) (xy 37.591941 -267.714547)
			(xy 37.568269 -267.765044) (xy 37.537496 -267.811557) (xy 37.500279 -267.853094) (xy 37.457411 -267.888769)
			(xy 37.409805 -267.917823) (xy 37.358476 -267.939635) (xy 37.304519 -267.953741) (xy 37.249082 -267.959841)
			(xy 37.193348 -267.957804) (xy 37.138505 -267.947674) (xy 37.085721 -267.929667) (xy 37.036121 -267.904166)
			(xy 36.990763 -267.871715) (xy 36.950614 -267.833006) (xy 36.916528 -267.788863) (xy 36.889232 -267.740228)
			(xy 36.869309 -267.688137) (xy 36.857183 -267.6337) (xy 36.853112 -267.578078) (xy 33.045174 -267.578078)
			(xy 33.094294 -267.627705) (xy 33.22573 -267.771883) (xy 33.351135 -267.921336) (xy 33.470299 -268.07581)
			(xy 33.58302 -268.235047) (xy 33.689109 -268.398778) (xy 33.788387 -268.566725) (xy 33.880685 -268.738608)
			(xy 33.96585 -268.914134) (xy 34.043736 -269.093009) (xy 34.114213 -269.274931) (xy 34.177161 -269.459593)
			(xy 34.232476 -269.646683) (xy 34.280062 -269.835887) (xy 34.319841 -270.026884) (xy 34.351745 -270.219354)
			(xy 34.37572 -270.412972) (xy 34.386802 -270.547592) (xy 39.118284 -270.547592) (xy 39.122355 -270.49197)
			(xy 39.134481 -270.437533) (xy 39.154404 -270.385442) (xy 39.1817 -270.336807) (xy 39.215786 -270.292664)
			(xy 39.255935 -270.253955) (xy 39.301293 -270.221504) (xy 39.350893 -270.196003) (xy 39.403677 -270.177996)
			(xy 39.45852 -270.167866) (xy 39.514254 -270.165829) (xy 39.569691 -270.171929) (xy 39.623648 -270.186035)
			(xy 39.674977 -270.207847) (xy 39.722583 -270.236901) (xy 39.765451 -270.272576) (xy 39.802668 -270.314113)
			(xy 39.833441 -270.360626) (xy 39.857113 -270.411123) (xy 39.873181 -270.46453) (xy 39.881301 -270.519706)
			(xy 39.88181 -270.547592) (xy 39.881301 -270.575478) (xy 39.873181 -270.630654) (xy 39.862636 -270.665702)
			(xy 40.061894 -270.665702) (xy 40.065965 -270.61008) (xy 40.078091 -270.555643) (xy 40.098014 -270.503552)
			(xy 40.12531 -270.454917) (xy 40.159396 -270.410774) (xy 40.199545 -270.372065) (xy 40.244903 -270.339614)
			(xy 40.294503 -270.314113) (xy 40.347287 -270.296106) (xy 40.40213 -270.285976) (xy 40.457864 -270.283939)
			(xy 40.513301 -270.290039) (xy 40.567258 -270.304145) (xy 40.618587 -270.325957) (xy 40.666193 -270.355011)
			(xy 40.709061 -270.390686) (xy 40.746278 -270.432223) (xy 40.777051 -270.478736) (xy 40.800723 -270.529233)
			(xy 40.816791 -270.58264) (xy 40.821811 -270.616753) (xy 41.069457 -270.616753) (xy 41.069457 -270.562247)
			(xy 41.077215 -270.508295) (xy 41.092571 -270.455996) (xy 41.115215 -270.406415) (xy 41.144684 -270.360562)
			(xy 41.180379 -270.319369) (xy 41.221573 -270.283675) (xy 41.267428 -270.254208) (xy 41.317009 -270.231566)
			(xy 41.369308 -270.216212) (xy 41.423261 -270.208456) (xy 41.450514 -270.207994) (xy 41.477463 -270.208482)
			(xy 41.530822 -270.216082) (xy 41.582581 -270.231115) (xy 41.631709 -270.253282) (xy 41.67723 -270.28214)
			(xy 41.718237 -270.317117) (xy 41.753914 -270.357517) (xy 41.783551 -270.402534) (xy 41.806559 -270.451274)
			(xy 41.82248 -270.502767) (xy 41.827196 -270.529304) (xy 41.83003 -270.54387) (xy 41.84297 -270.570561)
			(xy 41.863029 -270.592413) (xy 41.888517 -270.607585) (xy 41.917289 -270.6148) (xy 41.94692 -270.613449)
			(xy 41.974916 -270.603647) (xy 41.987216 -270.595344) (xy 42.01183 -270.57815) (xy 42.065325 -270.550893)
			(xy 42.122429 -270.532353) (xy 42.181732 -270.522987) (xy 42.211752 -270.522446) (xy 42.239004 -270.522998)
			(xy 42.292953 -270.530748) (xy 42.345251 -270.546098) (xy 42.394831 -270.568735) (xy 42.440685 -270.598199)
			(xy 42.481878 -270.633888) (xy 42.517573 -270.675077) (xy 42.547041 -270.720927) (xy 42.569685 -270.770504)
			(xy 42.585041 -270.8228) (xy 42.592799 -270.876748) (xy 42.592799 -270.931252) (xy 42.585041 -270.9852)
			(xy 42.569685 -271.037496) (xy 42.547041 -271.087073) (xy 42.517573 -271.132923) (xy 42.481878 -271.174112)
			(xy 42.440685 -271.209801) (xy 42.394831 -271.239265) (xy 42.345251 -271.261902) (xy 42.292953 -271.277252)
			(xy 42.239004 -271.285002) (xy 42.211752 -271.285462) (xy 42.184803 -271.28495) (xy 42.131443 -271.277358)
			(xy 42.079683 -271.262331) (xy 42.030553 -271.24017) (xy 41.98503 -271.211314) (xy 41.944022 -271.176339)
			(xy 41.908345 -271.135941) (xy 41.878708 -271.090923) (xy 41.855702 -271.042183) (xy 41.839784 -270.990689)
			(xy 41.83507 -270.964152) (xy 41.832258 -270.949578) (xy 41.819324 -270.922875) (xy 41.799264 -270.901013)
			(xy 41.773768 -270.885836) (xy 41.744988 -270.878623) (xy 41.715348 -270.879983) (xy 41.687349 -270.8898)
			(xy 41.67505 -270.898112) (xy 41.650442 -270.915315) (xy 41.596946 -270.942571) (xy 41.53984 -270.96111)
			(xy 41.480534 -270.970472) (xy 41.450514 -270.97101) (xy 41.423261 -270.970544) (xy 41.369308 -270.962788)
			(xy 41.317009 -270.947434) (xy 41.267428 -270.924792) (xy 41.221573 -270.895325) (xy 41.180379 -270.859631)
			(xy 41.144684 -270.818438) (xy 41.115215 -270.772585) (xy 41.092571 -270.723004) (xy 41.077215 -270.670705)
			(xy 41.069457 -270.616753) (xy 40.821811 -270.616753) (xy 40.824911 -270.637816) (xy 40.82542 -270.665702)
			(xy 40.824911 -270.693588) (xy 40.816791 -270.748764) (xy 40.800723 -270.802171) (xy 40.777051 -270.852668)
			(xy 40.746278 -270.899181) (xy 40.709061 -270.940718) (xy 40.666193 -270.976393) (xy 40.618587 -271.005447)
			(xy 40.567258 -271.027259) (xy 40.513301 -271.041365) (xy 40.457864 -271.047465) (xy 40.40213 -271.045428)
			(xy 40.347287 -271.035298) (xy 40.294503 -271.017291) (xy 40.244903 -270.99179) (xy 40.199545 -270.959339)
			(xy 40.159396 -270.92063) (xy 40.12531 -270.876487) (xy 40.098014 -270.827852) (xy 40.078091 -270.775761)
			(xy 40.065965 -270.721324) (xy 40.061894 -270.665702) (xy 39.862636 -270.665702) (xy 39.857113 -270.684061)
			(xy 39.833441 -270.734558) (xy 39.802668 -270.781071) (xy 39.765451 -270.822608) (xy 39.722583 -270.858283)
			(xy 39.674977 -270.887337) (xy 39.623648 -270.909149) (xy 39.569691 -270.923255) (xy 39.514254 -270.929355)
			(xy 39.45852 -270.927318) (xy 39.403677 -270.917188) (xy 39.350893 -270.899181) (xy 39.301293 -270.87368)
			(xy 39.255935 -270.841229) (xy 39.215786 -270.80252) (xy 39.1817 -270.758377) (xy 39.154404 -270.709742)
			(xy 39.134481 -270.657651) (xy 39.122355 -270.603214) (xy 39.118284 -270.547592) (xy 34.386802 -270.547592)
			(xy 34.391726 -270.60741) (xy 34.399735 -270.802342) (xy 34.400236 -270.89989) (xy 34.399735 -270.997438)
			(xy 34.391726 -271.19237) (xy 34.37572 -271.386808) (xy 34.351745 -271.580426) (xy 34.319841 -271.772896)
			(xy 34.280062 -271.963893) (xy 34.233363 -272.14957) (xy 44.143688 -272.14957) (xy 44.147648 -272.100516)
			(xy 44.159425 -272.052732) (xy 44.178716 -272.007456) (xy 44.205019 -271.96586) (xy 44.237654 -271.929023)
			(xy 44.275775 -271.897898) (xy 44.318396 -271.873291) (xy 44.364412 -271.855839) (xy 44.412631 -271.845995)
			(xy 44.461806 -271.844014) (xy 44.510661 -271.849946) (xy 44.557932 -271.863638) (xy 44.602394 -271.884736)
			(xy 44.642897 -271.912692) (xy 44.67839 -271.946784) (xy 44.707955 -271.986128) (xy 44.730826 -272.029705)
			(xy 44.74641 -272.076386) (xy 44.754305 -272.124963) (xy 44.7548 -272.14957) (xy 46.043862 -272.14957)
			(xy 46.047822 -272.100516) (xy 46.059599 -272.052732) (xy 46.07889 -272.007456) (xy 46.105193 -271.96586)
			(xy 46.137828 -271.929023) (xy 46.175949 -271.897898) (xy 46.21857 -271.873291) (xy 46.264586 -271.855839)
			(xy 46.312805 -271.845995) (xy 46.36198 -271.844014) (xy 46.410835 -271.849946) (xy 46.458106 -271.863638)
			(xy 46.502568 -271.884736) (xy 46.543071 -271.912692) (xy 46.578564 -271.946784) (xy 46.608129 -271.986128)
			(xy 46.631 -272.029705) (xy 46.646584 -272.076386) (xy 46.654479 -272.124963) (xy 46.654974 -272.14957)
			(xy 47.943782 -272.14957) (xy 47.947742 -272.100516) (xy 47.959519 -272.052732) (xy 47.97881 -272.007456)
			(xy 48.005113 -271.96586) (xy 48.037748 -271.929023) (xy 48.075869 -271.897898) (xy 48.11849 -271.873291)
			(xy 48.164506 -271.855839) (xy 48.212725 -271.845995) (xy 48.2619 -271.844014) (xy 48.310755 -271.849946)
			(xy 48.358026 -271.863638) (xy 48.402488 -271.884736) (xy 48.442991 -271.912692) (xy 48.478484 -271.946784)
			(xy 48.508049 -271.986128) (xy 48.53092 -272.029705) (xy 48.546504 -272.076386) (xy 48.554399 -272.124963)
			(xy 48.554894 -272.14957) (xy 49.843702 -272.14957) (xy 49.847662 -272.100516) (xy 49.859439 -272.052732)
			(xy 49.87873 -272.007456) (xy 49.905033 -271.96586) (xy 49.937668 -271.929023) (xy 49.975789 -271.897898)
			(xy 50.01841 -271.873291) (xy 50.064426 -271.855839) (xy 50.112645 -271.845995) (xy 50.16182 -271.844014)
			(xy 50.210675 -271.849946) (xy 50.257946 -271.863638) (xy 50.302408 -271.884736) (xy 50.342911 -271.912692)
			(xy 50.378404 -271.946784) (xy 50.407969 -271.986128) (xy 50.43084 -272.029705) (xy 50.446424 -272.076386)
			(xy 50.454319 -272.124963) (xy 50.454814 -272.14957) (xy 51.743876 -272.14957) (xy 51.747836 -272.100516)
			(xy 51.759613 -272.052732) (xy 51.778904 -272.007456) (xy 51.805207 -271.96586) (xy 51.837842 -271.929023)
			(xy 51.875963 -271.897898) (xy 51.918584 -271.873291) (xy 51.9646 -271.855839) (xy 52.012819 -271.845995)
			(xy 52.061994 -271.844014) (xy 52.110849 -271.849946) (xy 52.15812 -271.863638) (xy 52.202582 -271.884736)
			(xy 52.243085 -271.912692) (xy 52.278578 -271.946784) (xy 52.308143 -271.986128) (xy 52.331014 -272.029705)
			(xy 52.346598 -272.076386) (xy 52.354493 -272.124963) (xy 52.354988 -272.14957) (xy 53.643796 -272.14957)
			(xy 53.647756 -272.100516) (xy 53.659533 -272.052732) (xy 53.678824 -272.007456) (xy 53.705127 -271.96586)
			(xy 53.737762 -271.929023) (xy 53.775883 -271.897898) (xy 53.818504 -271.873291) (xy 53.86452 -271.855839)
			(xy 53.912739 -271.845995) (xy 53.961914 -271.844014) (xy 54.010769 -271.849946) (xy 54.05804 -271.863638)
			(xy 54.102502 -271.884736) (xy 54.143005 -271.912692) (xy 54.178498 -271.946784) (xy 54.208063 -271.986128)
			(xy 54.230934 -272.029705) (xy 54.246518 -272.076386) (xy 54.254413 -272.124963) (xy 54.254908 -272.14957)
			(xy 55.543716 -272.14957) (xy 55.547676 -272.100516) (xy 55.559453 -272.052732) (xy 55.578744 -272.007456)
			(xy 55.605047 -271.96586) (xy 55.637682 -271.929023) (xy 55.675803 -271.897898) (xy 55.718424 -271.873291)
			(xy 55.76444 -271.855839) (xy 55.812659 -271.845995) (xy 55.861834 -271.844014) (xy 55.910689 -271.849946)
			(xy 55.95796 -271.863638) (xy 56.002422 -271.884736) (xy 56.042925 -271.912692) (xy 56.078418 -271.946784)
			(xy 56.107983 -271.986128) (xy 56.130854 -272.029705) (xy 56.146438 -272.076386) (xy 56.154333 -272.124963)
			(xy 56.154828 -272.14957) (xy 56.154333 -272.174177) (xy 56.146438 -272.222754) (xy 56.130854 -272.269435)
			(xy 56.107983 -272.313012) (xy 56.078418 -272.352356) (xy 56.042925 -272.386448) (xy 56.002422 -272.414404)
			(xy 55.95796 -272.435502) (xy 55.910689 -272.449194) (xy 55.861834 -272.455126) (xy 55.812659 -272.453145)
			(xy 55.76444 -272.443301) (xy 55.718424 -272.425849) (xy 55.675803 -272.401242) (xy 55.637682 -272.370117)
			(xy 55.605047 -272.33328) (xy 55.578744 -272.291684) (xy 55.559453 -272.246408) (xy 55.547676 -272.198624)
			(xy 55.543716 -272.14957) (xy 54.254908 -272.14957) (xy 54.254413 -272.174177) (xy 54.246518 -272.222754)
			(xy 54.230934 -272.269435) (xy 54.208063 -272.313012) (xy 54.178498 -272.352356) (xy 54.143005 -272.386448)
			(xy 54.102502 -272.414404) (xy 54.05804 -272.435502) (xy 54.010769 -272.449194) (xy 53.961914 -272.455126)
			(xy 53.912739 -272.453145) (xy 53.86452 -272.443301) (xy 53.818504 -272.425849) (xy 53.775883 -272.401242)
			(xy 53.737762 -272.370117) (xy 53.705127 -272.33328) (xy 53.678824 -272.291684) (xy 53.659533 -272.246408)
			(xy 53.647756 -272.198624) (xy 53.643796 -272.14957) (xy 52.354988 -272.14957) (xy 52.354493 -272.174177)
			(xy 52.346598 -272.222754) (xy 52.331014 -272.269435) (xy 52.308143 -272.313012) (xy 52.278578 -272.352356)
			(xy 52.243085 -272.386448) (xy 52.202582 -272.414404) (xy 52.15812 -272.435502) (xy 52.110849 -272.449194)
			(xy 52.061994 -272.455126) (xy 52.012819 -272.453145) (xy 51.9646 -272.443301) (xy 51.918584 -272.425849)
			(xy 51.875963 -272.401242) (xy 51.837842 -272.370117) (xy 51.805207 -272.33328) (xy 51.778904 -272.291684)
			(xy 51.759613 -272.246408) (xy 51.747836 -272.198624) (xy 51.743876 -272.14957) (xy 50.454814 -272.14957)
			(xy 50.454319 -272.174177) (xy 50.446424 -272.222754) (xy 50.43084 -272.269435) (xy 50.407969 -272.313012)
			(xy 50.378404 -272.352356) (xy 50.342911 -272.386448) (xy 50.302408 -272.414404) (xy 50.257946 -272.435502)
			(xy 50.210675 -272.449194) (xy 50.16182 -272.455126) (xy 50.112645 -272.453145) (xy 50.064426 -272.443301)
			(xy 50.01841 -272.425849) (xy 49.975789 -272.401242) (xy 49.937668 -272.370117) (xy 49.905033 -272.33328)
			(xy 49.87873 -272.291684) (xy 49.859439 -272.246408) (xy 49.847662 -272.198624) (xy 49.843702 -272.14957)
			(xy 48.554894 -272.14957) (xy 48.554399 -272.174177) (xy 48.546504 -272.222754) (xy 48.53092 -272.269435)
			(xy 48.508049 -272.313012) (xy 48.478484 -272.352356) (xy 48.442991 -272.386448) (xy 48.402488 -272.414404)
			(xy 48.358026 -272.435502) (xy 48.310755 -272.449194) (xy 48.2619 -272.455126) (xy 48.212725 -272.453145)
			(xy 48.164506 -272.443301) (xy 48.11849 -272.425849) (xy 48.075869 -272.401242) (xy 48.037748 -272.370117)
			(xy 48.005113 -272.33328) (xy 47.97881 -272.291684) (xy 47.959519 -272.246408) (xy 47.947742 -272.198624)
			(xy 47.943782 -272.14957) (xy 46.654974 -272.14957) (xy 46.654479 -272.174177) (xy 46.646584 -272.222754)
			(xy 46.631 -272.269435) (xy 46.608129 -272.313012) (xy 46.578564 -272.352356) (xy 46.543071 -272.386448)
			(xy 46.502568 -272.414404) (xy 46.458106 -272.435502) (xy 46.410835 -272.449194) (xy 46.36198 -272.455126)
			(xy 46.312805 -272.453145) (xy 46.264586 -272.443301) (xy 46.21857 -272.425849) (xy 46.175949 -272.401242)
			(xy 46.137828 -272.370117) (xy 46.105193 -272.33328) (xy 46.07889 -272.291684) (xy 46.059599 -272.246408)
			(xy 46.047822 -272.198624) (xy 46.043862 -272.14957) (xy 44.7548 -272.14957) (xy 44.754305 -272.174177)
			(xy 44.74641 -272.222754) (xy 44.730826 -272.269435) (xy 44.707955 -272.313012) (xy 44.67839 -272.352356)
			(xy 44.642897 -272.386448) (xy 44.602394 -272.414404) (xy 44.557932 -272.435502) (xy 44.510661 -272.449194)
			(xy 44.461806 -272.455126) (xy 44.412631 -272.453145) (xy 44.364412 -272.443301) (xy 44.318396 -272.425849)
			(xy 44.275775 -272.401242) (xy 44.237654 -272.370117) (xy 44.205019 -272.33328) (xy 44.178716 -272.291684)
			(xy 44.159425 -272.246408) (xy 44.147648 -272.198624) (xy 44.143688 -272.14957) (xy 34.233363 -272.14957)
			(xy 34.232476 -272.153097) (xy 34.177161 -272.340187) (xy 34.114213 -272.524849) (xy 34.07549 -272.624804)
			(xy 37.969202 -272.624804) (xy 37.973162 -272.57575) (xy 37.984939 -272.527966) (xy 38.00423 -272.48269)
			(xy 38.030533 -272.441094) (xy 38.063168 -272.404257) (xy 38.101289 -272.373132) (xy 38.14391 -272.348525)
			(xy 38.189926 -272.331073) (xy 38.238145 -272.321229) (xy 38.28732 -272.319248) (xy 38.336175 -272.32518)
			(xy 38.383446 -272.338872) (xy 38.427908 -272.35997) (xy 38.468411 -272.387926) (xy 38.503904 -272.422018)
			(xy 38.533469 -272.461362) (xy 38.55634 -272.504939) (xy 38.571924 -272.55162) (xy 38.579819 -272.600197)
			(xy 38.580314 -272.624804) (xy 38.919162 -272.624804) (xy 38.923122 -272.57575) (xy 38.934899 -272.527966)
			(xy 38.95419 -272.48269) (xy 38.980493 -272.441094) (xy 39.013128 -272.404257) (xy 39.051249 -272.373132)
			(xy 39.09387 -272.348525) (xy 39.139886 -272.331073) (xy 39.188105 -272.321229) (xy 39.23728 -272.319248)
			(xy 39.286135 -272.32518) (xy 39.333406 -272.338872) (xy 39.377868 -272.35997) (xy 39.418371 -272.387926)
			(xy 39.453864 -272.422018) (xy 39.483429 -272.461362) (xy 39.5063 -272.504939) (xy 39.521884 -272.55162)
			(xy 39.529779 -272.600197) (xy 39.530274 -272.624804) (xy 39.869122 -272.624804) (xy 39.873082 -272.57575)
			(xy 39.884859 -272.527966) (xy 39.90415 -272.48269) (xy 39.930453 -272.441094) (xy 39.963088 -272.404257)
			(xy 40.001209 -272.373132) (xy 40.04383 -272.348525) (xy 40.089846 -272.331073) (xy 40.138065 -272.321229)
			(xy 40.18724 -272.319248) (xy 40.236095 -272.32518) (xy 40.283366 -272.338872) (xy 40.327828 -272.35997)
			(xy 40.368331 -272.387926) (xy 40.403824 -272.422018) (xy 40.433389 -272.461362) (xy 40.45626 -272.504939)
			(xy 40.471844 -272.55162) (xy 40.479739 -272.600197) (xy 40.480234 -272.624804) (xy 40.819082 -272.624804)
			(xy 40.823042 -272.57575) (xy 40.834819 -272.527966) (xy 40.85411 -272.48269) (xy 40.880413 -272.441094)
			(xy 40.913048 -272.404257) (xy 40.951169 -272.373132) (xy 40.99379 -272.348525) (xy 41.039806 -272.331073)
			(xy 41.088025 -272.321229) (xy 41.1372 -272.319248) (xy 41.186055 -272.32518) (xy 41.233326 -272.338872)
			(xy 41.277788 -272.35997) (xy 41.318291 -272.387926) (xy 41.353784 -272.422018) (xy 41.383349 -272.461362)
			(xy 41.40622 -272.504939) (xy 41.421804 -272.55162) (xy 41.429699 -272.600197) (xy 41.430194 -272.624804)
			(xy 41.769042 -272.624804) (xy 41.773002 -272.57575) (xy 41.784779 -272.527966) (xy 41.80407 -272.48269)
			(xy 41.830373 -272.441094) (xy 41.863008 -272.404257) (xy 41.901129 -272.373132) (xy 41.94375 -272.348525)
			(xy 41.989766 -272.331073) (xy 42.037985 -272.321229) (xy 42.08716 -272.319248) (xy 42.136015 -272.32518)
			(xy 42.183286 -272.338872) (xy 42.227748 -272.35997) (xy 42.268251 -272.387926) (xy 42.303744 -272.422018)
			(xy 42.333309 -272.461362) (xy 42.35618 -272.504939) (xy 42.371764 -272.55162) (xy 42.379659 -272.600197)
			(xy 42.380154 -272.624804) (xy 42.379659 -272.649411) (xy 42.371764 -272.697988) (xy 42.35618 -272.744669)
			(xy 42.333309 -272.788246) (xy 42.303744 -272.82759) (xy 42.268251 -272.861682) (xy 42.227748 -272.889638)
			(xy 42.183286 -272.910736) (xy 42.136015 -272.924428) (xy 42.08716 -272.93036) (xy 42.037985 -272.928379)
			(xy 41.989766 -272.918535) (xy 41.94375 -272.901083) (xy 41.901129 -272.876476) (xy 41.863008 -272.845351)
			(xy 41.830373 -272.808514) (xy 41.80407 -272.766918) (xy 41.784779 -272.721642) (xy 41.773002 -272.673858)
			(xy 41.769042 -272.624804) (xy 41.430194 -272.624804) (xy 41.429699 -272.649411) (xy 41.421804 -272.697988)
			(xy 41.40622 -272.744669) (xy 41.383349 -272.788246) (xy 41.353784 -272.82759) (xy 41.318291 -272.861682)
			(xy 41.277788 -272.889638) (xy 41.233326 -272.910736) (xy 41.186055 -272.924428) (xy 41.1372 -272.93036)
			(xy 41.088025 -272.928379) (xy 41.039806 -272.918535) (xy 40.99379 -272.901083) (xy 40.951169 -272.876476)
			(xy 40.913048 -272.845351) (xy 40.880413 -272.808514) (xy 40.85411 -272.766918) (xy 40.834819 -272.721642)
			(xy 40.823042 -272.673858) (xy 40.819082 -272.624804) (xy 40.480234 -272.624804) (xy 40.479739 -272.649411)
			(xy 40.471844 -272.697988) (xy 40.45626 -272.744669) (xy 40.433389 -272.788246) (xy 40.403824 -272.82759)
			(xy 40.368331 -272.861682) (xy 40.327828 -272.889638) (xy 40.283366 -272.910736) (xy 40.236095 -272.924428)
			(xy 40.18724 -272.93036) (xy 40.138065 -272.928379) (xy 40.089846 -272.918535) (xy 40.04383 -272.901083)
			(xy 40.001209 -272.876476) (xy 39.963088 -272.845351) (xy 39.930453 -272.808514) (xy 39.90415 -272.766918)
			(xy 39.884859 -272.721642) (xy 39.873082 -272.673858) (xy 39.869122 -272.624804) (xy 39.530274 -272.624804)
			(xy 39.529779 -272.649411) (xy 39.521884 -272.697988) (xy 39.5063 -272.744669) (xy 39.483429 -272.788246)
			(xy 39.453864 -272.82759) (xy 39.418371 -272.861682) (xy 39.377868 -272.889638) (xy 39.333406 -272.910736)
			(xy 39.286135 -272.924428) (xy 39.23728 -272.93036) (xy 39.188105 -272.928379) (xy 39.139886 -272.918535)
			(xy 39.09387 -272.901083) (xy 39.051249 -272.876476) (xy 39.013128 -272.845351) (xy 38.980493 -272.808514)
			(xy 38.95419 -272.766918) (xy 38.934899 -272.721642) (xy 38.923122 -272.673858) (xy 38.919162 -272.624804)
			(xy 38.580314 -272.624804) (xy 38.579819 -272.649411) (xy 38.571924 -272.697988) (xy 38.55634 -272.744669)
			(xy 38.533469 -272.788246) (xy 38.503904 -272.82759) (xy 38.468411 -272.861682) (xy 38.427908 -272.889638)
			(xy 38.383446 -272.910736) (xy 38.336175 -272.924428) (xy 38.28732 -272.93036) (xy 38.238145 -272.928379)
			(xy 38.189926 -272.918535) (xy 38.14391 -272.901083) (xy 38.101289 -272.876476) (xy 38.063168 -272.845351)
			(xy 38.030533 -272.808514) (xy 38.00423 -272.766918) (xy 37.984939 -272.721642) (xy 37.973162 -272.673858)
			(xy 37.969202 -272.624804) (xy 34.07549 -272.624804) (xy 34.043736 -272.706771) (xy 33.96585 -272.885646)
			(xy 33.880685 -273.061172) (xy 33.859951 -273.099784) (xy 43.193982 -273.099784) (xy 43.197942 -273.05073)
			(xy 43.209719 -273.002946) (xy 43.22901 -272.95767) (xy 43.255313 -272.916074) (xy 43.287948 -272.879237)
			(xy 43.326069 -272.848112) (xy 43.36869 -272.823505) (xy 43.414706 -272.806053) (xy 43.462925 -272.796209)
			(xy 43.5121 -272.794228) (xy 43.560955 -272.80016) (xy 43.608226 -272.813852) (xy 43.652688 -272.83495)
			(xy 43.693191 -272.862906) (xy 43.728684 -272.896998) (xy 43.758249 -272.936342) (xy 43.78112 -272.979919)
			(xy 43.796704 -273.0266) (xy 43.804599 -273.075177) (xy 43.805094 -273.099784) (xy 43.804599 -273.124391)
			(xy 43.80442 -273.125492) (xy 44.123098 -273.125492) (xy 44.123098 -273.074076) (xy 44.131141 -273.023294)
			(xy 44.147029 -272.974395) (xy 44.170372 -272.928583) (xy 44.200593 -272.886987) (xy 44.236949 -272.850631)
			(xy 44.278545 -272.82041) (xy 44.324357 -272.797067) (xy 44.373256 -272.781179) (xy 44.424038 -272.773136)
			(xy 44.475454 -272.773136) (xy 44.526236 -272.781179) (xy 44.575135 -272.797067) (xy 44.620947 -272.82041)
			(xy 44.662543 -272.850631) (xy 44.698899 -272.886987) (xy 44.72912 -272.928583) (xy 44.752463 -272.974395)
			(xy 44.768351 -273.023294) (xy 44.776394 -273.074076) (xy 44.776898 -273.099784) (xy 45.094156 -273.099784)
			(xy 45.098116 -273.05073) (xy 45.109893 -273.002946) (xy 45.129184 -272.95767) (xy 45.155487 -272.916074)
			(xy 45.188122 -272.879237) (xy 45.226243 -272.848112) (xy 45.268864 -272.823505) (xy 45.31488 -272.806053)
			(xy 45.363099 -272.796209) (xy 45.412274 -272.794228) (xy 45.461129 -272.80016) (xy 45.5084 -272.813852)
			(xy 45.552862 -272.83495) (xy 45.593365 -272.862906) (xy 45.628858 -272.896998) (xy 45.658423 -272.936342)
			(xy 45.681294 -272.979919) (xy 45.696878 -273.0266) (xy 45.704773 -273.075177) (xy 45.705268 -273.099784)
			(xy 45.704773 -273.124391) (xy 45.704594 -273.125492) (xy 46.023272 -273.125492) (xy 46.023272 -273.074076)
			(xy 46.031315 -273.023294) (xy 46.047203 -272.974395) (xy 46.070546 -272.928583) (xy 46.100767 -272.886987)
			(xy 46.137123 -272.850631) (xy 46.178719 -272.82041) (xy 46.224531 -272.797067) (xy 46.27343 -272.781179)
			(xy 46.324212 -272.773136) (xy 46.375628 -272.773136) (xy 46.42641 -272.781179) (xy 46.475309 -272.797067)
			(xy 46.521121 -272.82041) (xy 46.562717 -272.850631) (xy 46.599073 -272.886987) (xy 46.629294 -272.928583)
			(xy 46.652637 -272.974395) (xy 46.668525 -273.023294) (xy 46.676568 -273.074076) (xy 46.677072 -273.099784)
			(xy 46.994076 -273.099784) (xy 46.998036 -273.05073) (xy 47.009813 -273.002946) (xy 47.029104 -272.95767)
			(xy 47.055407 -272.916074) (xy 47.088042 -272.879237) (xy 47.126163 -272.848112) (xy 47.168784 -272.823505)
			(xy 47.2148 -272.806053) (xy 47.263019 -272.796209) (xy 47.312194 -272.794228) (xy 47.361049 -272.80016)
			(xy 47.40832 -272.813852) (xy 47.452782 -272.83495) (xy 47.493285 -272.862906) (xy 47.528778 -272.896998)
			(xy 47.558343 -272.936342) (xy 47.581214 -272.979919) (xy 47.596798 -273.0266) (xy 47.604693 -273.075177)
			(xy 47.605188 -273.099784) (xy 47.604693 -273.124391) (xy 47.604514 -273.125492) (xy 47.923192 -273.125492)
			(xy 47.923192 -273.074076) (xy 47.931235 -273.023294) (xy 47.947123 -272.974395) (xy 47.970466 -272.928583)
			(xy 48.000687 -272.886987) (xy 48.037043 -272.850631) (xy 48.078639 -272.82041) (xy 48.124451 -272.797067)
			(xy 48.17335 -272.781179) (xy 48.224132 -272.773136) (xy 48.275548 -272.773136) (xy 48.32633 -272.781179)
			(xy 48.375229 -272.797067) (xy 48.421041 -272.82041) (xy 48.462637 -272.850631) (xy 48.498993 -272.886987)
			(xy 48.529214 -272.928583) (xy 48.552557 -272.974395) (xy 48.568445 -273.023294) (xy 48.576488 -273.074076)
			(xy 48.576992 -273.099784) (xy 48.893996 -273.099784) (xy 48.897956 -273.05073) (xy 48.909733 -273.002946)
			(xy 48.929024 -272.95767) (xy 48.955327 -272.916074) (xy 48.987962 -272.879237) (xy 49.026083 -272.848112)
			(xy 49.068704 -272.823505) (xy 49.11472 -272.806053) (xy 49.162939 -272.796209) (xy 49.212114 -272.794228)
			(xy 49.260969 -272.80016) (xy 49.30824 -272.813852) (xy 49.352702 -272.83495) (xy 49.393205 -272.862906)
			(xy 49.428698 -272.896998) (xy 49.458263 -272.936342) (xy 49.481134 -272.979919) (xy 49.496718 -273.0266)
			(xy 49.504613 -273.075177) (xy 49.505108 -273.099784) (xy 49.504613 -273.124391) (xy 49.504434 -273.125492)
			(xy 49.823112 -273.125492) (xy 49.823112 -273.074076) (xy 49.831155 -273.023294) (xy 49.847043 -272.974395)
			(xy 49.870386 -272.928583) (xy 49.900607 -272.886987) (xy 49.936963 -272.850631) (xy 49.978559 -272.82041)
			(xy 50.024371 -272.797067) (xy 50.07327 -272.781179) (xy 50.124052 -272.773136) (xy 50.175468 -272.773136)
			(xy 50.22625 -272.781179) (xy 50.275149 -272.797067) (xy 50.320961 -272.82041) (xy 50.362557 -272.850631)
			(xy 50.398913 -272.886987) (xy 50.429134 -272.928583) (xy 50.452477 -272.974395) (xy 50.468365 -273.023294)
			(xy 50.476408 -273.074076) (xy 50.476912 -273.099784) (xy 50.79417 -273.099784) (xy 50.79813 -273.05073)
			(xy 50.809907 -273.002946) (xy 50.829198 -272.95767) (xy 50.855501 -272.916074) (xy 50.888136 -272.879237)
			(xy 50.926257 -272.848112) (xy 50.968878 -272.823505) (xy 51.014894 -272.806053) (xy 51.063113 -272.796209)
			(xy 51.112288 -272.794228) (xy 51.161143 -272.80016) (xy 51.208414 -272.813852) (xy 51.252876 -272.83495)
			(xy 51.293379 -272.862906) (xy 51.328872 -272.896998) (xy 51.358437 -272.936342) (xy 51.381308 -272.979919)
			(xy 51.396892 -273.0266) (xy 51.404787 -273.075177) (xy 51.405282 -273.099784) (xy 51.404787 -273.124391)
			(xy 51.404608 -273.125492) (xy 51.723286 -273.125492) (xy 51.723286 -273.074076) (xy 51.731329 -273.023294)
			(xy 51.747217 -272.974395) (xy 51.77056 -272.928583) (xy 51.800781 -272.886987) (xy 51.837137 -272.850631)
			(xy 51.878733 -272.82041) (xy 51.924545 -272.797067) (xy 51.973444 -272.781179) (xy 52.024226 -272.773136)
			(xy 52.075642 -272.773136) (xy 52.126424 -272.781179) (xy 52.175323 -272.797067) (xy 52.221135 -272.82041)
			(xy 52.262731 -272.850631) (xy 52.299087 -272.886987) (xy 52.329308 -272.928583) (xy 52.352651 -272.974395)
			(xy 52.368539 -273.023294) (xy 52.376582 -273.074076) (xy 52.377086 -273.099784) (xy 52.69409 -273.099784)
			(xy 52.69805 -273.05073) (xy 52.709827 -273.002946) (xy 52.729118 -272.95767) (xy 52.755421 -272.916074)
			(xy 52.788056 -272.879237) (xy 52.826177 -272.848112) (xy 52.868798 -272.823505) (xy 52.914814 -272.806053)
			(xy 52.963033 -272.796209) (xy 53.012208 -272.794228) (xy 53.061063 -272.80016) (xy 53.108334 -272.813852)
			(xy 53.152796 -272.83495) (xy 53.193299 -272.862906) (xy 53.228792 -272.896998) (xy 53.258357 -272.936342)
			(xy 53.281228 -272.979919) (xy 53.296812 -273.0266) (xy 53.304707 -273.075177) (xy 53.305202 -273.099784)
			(xy 53.304707 -273.124391) (xy 53.304528 -273.125492) (xy 53.623206 -273.125492) (xy 53.623206 -273.074076)
			(xy 53.631249 -273.023294) (xy 53.647137 -272.974395) (xy 53.67048 -272.928583) (xy 53.700701 -272.886987)
			(xy 53.737057 -272.850631) (xy 53.778653 -272.82041) (xy 53.824465 -272.797067) (xy 53.873364 -272.781179)
			(xy 53.924146 -272.773136) (xy 53.975562 -272.773136) (xy 54.026344 -272.781179) (xy 54.075243 -272.797067)
			(xy 54.121055 -272.82041) (xy 54.162651 -272.850631) (xy 54.199007 -272.886987) (xy 54.229228 -272.928583)
			(xy 54.252571 -272.974395) (xy 54.268459 -273.023294) (xy 54.276502 -273.074076) (xy 54.277006 -273.099784)
			(xy 54.59401 -273.099784) (xy 54.59797 -273.05073) (xy 54.609747 -273.002946) (xy 54.629038 -272.95767)
			(xy 54.655341 -272.916074) (xy 54.687976 -272.879237) (xy 54.726097 -272.848112) (xy 54.768718 -272.823505)
			(xy 54.814734 -272.806053) (xy 54.862953 -272.796209) (xy 54.912128 -272.794228) (xy 54.960983 -272.80016)
			(xy 55.008254 -272.813852) (xy 55.052716 -272.83495) (xy 55.093219 -272.862906) (xy 55.128712 -272.896998)
			(xy 55.158277 -272.936342) (xy 55.181148 -272.979919) (xy 55.196732 -273.0266) (xy 55.204627 -273.075177)
			(xy 55.205122 -273.099784) (xy 55.204627 -273.124391) (xy 55.204448 -273.125492) (xy 55.523126 -273.125492)
			(xy 55.523126 -273.074076) (xy 55.531169 -273.023294) (xy 55.547057 -272.974395) (xy 55.5704 -272.928583)
			(xy 55.600621 -272.886987) (xy 55.636977 -272.850631) (xy 55.678573 -272.82041) (xy 55.724385 -272.797067)
			(xy 55.773284 -272.781179) (xy 55.824066 -272.773136) (xy 55.875482 -272.773136) (xy 55.926264 -272.781179)
			(xy 55.975163 -272.797067) (xy 56.020975 -272.82041) (xy 56.062571 -272.850631) (xy 56.098927 -272.886987)
			(xy 56.129148 -272.928583) (xy 56.152491 -272.974395) (xy 56.168379 -273.023294) (xy 56.176422 -273.074076)
			(xy 56.176926 -273.099784) (xy 56.494184 -273.099784) (xy 56.498144 -273.05073) (xy 56.509921 -273.002946)
			(xy 56.529212 -272.95767) (xy 56.555515 -272.916074) (xy 56.58815 -272.879237) (xy 56.626271 -272.848112)
			(xy 56.668892 -272.823505) (xy 56.714908 -272.806053) (xy 56.763127 -272.796209) (xy 56.812302 -272.794228)
			(xy 56.861157 -272.80016) (xy 56.908428 -272.813852) (xy 56.95289 -272.83495) (xy 56.993393 -272.862906)
			(xy 57.028886 -272.896998) (xy 57.058451 -272.936342) (xy 57.081322 -272.979919) (xy 57.096906 -273.0266)
			(xy 57.104801 -273.075177) (xy 57.105296 -273.099784) (xy 57.104801 -273.124391) (xy 57.096906 -273.172968)
			(xy 57.081322 -273.219649) (xy 57.058451 -273.263226) (xy 57.028886 -273.30257) (xy 56.993393 -273.336662)
			(xy 56.95289 -273.364618) (xy 56.908428 -273.385716) (xy 56.861157 -273.399408) (xy 56.812302 -273.40534)
			(xy 56.763127 -273.403359) (xy 56.714908 -273.393515) (xy 56.668892 -273.376063) (xy 56.626271 -273.351456)
			(xy 56.58815 -273.320331) (xy 56.555515 -273.283494) (xy 56.529212 -273.241898) (xy 56.509921 -273.196622)
			(xy 56.498144 -273.148838) (xy 56.494184 -273.099784) (xy 56.176926 -273.099784) (xy 56.176422 -273.125492)
			(xy 56.168379 -273.176274) (xy 56.152491 -273.225173) (xy 56.129148 -273.270985) (xy 56.098927 -273.312581)
			(xy 56.062571 -273.348937) (xy 56.020975 -273.379158) (xy 55.975163 -273.402501) (xy 55.926264 -273.418389)
			(xy 55.875482 -273.426432) (xy 55.824066 -273.426432) (xy 55.773284 -273.418389) (xy 55.724385 -273.402501)
			(xy 55.678573 -273.379158) (xy 55.636977 -273.348937) (xy 55.600621 -273.312581) (xy 55.5704 -273.270985)
			(xy 55.547057 -273.225173) (xy 55.531169 -273.176274) (xy 55.523126 -273.125492) (xy 55.204448 -273.125492)
			(xy 55.196732 -273.172968) (xy 55.181148 -273.219649) (xy 55.158277 -273.263226) (xy 55.128712 -273.30257)
			(xy 55.093219 -273.336662) (xy 55.052716 -273.364618) (xy 55.008254 -273.385716) (xy 54.960983 -273.399408)
			(xy 54.912128 -273.40534) (xy 54.862953 -273.403359) (xy 54.814734 -273.393515) (xy 54.768718 -273.376063)
			(xy 54.726097 -273.351456) (xy 54.687976 -273.320331) (xy 54.655341 -273.283494) (xy 54.629038 -273.241898)
			(xy 54.609747 -273.196622) (xy 54.59797 -273.148838) (xy 54.59401 -273.099784) (xy 54.277006 -273.099784)
			(xy 54.276502 -273.125492) (xy 54.268459 -273.176274) (xy 54.252571 -273.225173) (xy 54.229228 -273.270985)
			(xy 54.199007 -273.312581) (xy 54.162651 -273.348937) (xy 54.121055 -273.379158) (xy 54.075243 -273.402501)
			(xy 54.026344 -273.418389) (xy 53.975562 -273.426432) (xy 53.924146 -273.426432) (xy 53.873364 -273.418389)
			(xy 53.824465 -273.402501) (xy 53.778653 -273.379158) (xy 53.737057 -273.348937) (xy 53.700701 -273.312581)
			(xy 53.67048 -273.270985) (xy 53.647137 -273.225173) (xy 53.631249 -273.176274) (xy 53.623206 -273.125492)
			(xy 53.304528 -273.125492) (xy 53.296812 -273.172968) (xy 53.281228 -273.219649) (xy 53.258357 -273.263226)
			(xy 53.228792 -273.30257) (xy 53.193299 -273.336662) (xy 53.152796 -273.364618) (xy 53.108334 -273.385716)
			(xy 53.061063 -273.399408) (xy 53.012208 -273.40534) (xy 52.963033 -273.403359) (xy 52.914814 -273.393515)
			(xy 52.868798 -273.376063) (xy 52.826177 -273.351456) (xy 52.788056 -273.320331) (xy 52.755421 -273.283494)
			(xy 52.729118 -273.241898) (xy 52.709827 -273.196622) (xy 52.69805 -273.148838) (xy 52.69409 -273.099784)
			(xy 52.377086 -273.099784) (xy 52.376582 -273.125492) (xy 52.368539 -273.176274) (xy 52.352651 -273.225173)
			(xy 52.329308 -273.270985) (xy 52.299087 -273.312581) (xy 52.262731 -273.348937) (xy 52.221135 -273.379158)
			(xy 52.175323 -273.402501) (xy 52.126424 -273.418389) (xy 52.075642 -273.426432) (xy 52.024226 -273.426432)
			(xy 51.973444 -273.418389) (xy 51.924545 -273.402501) (xy 51.878733 -273.379158) (xy 51.837137 -273.348937)
			(xy 51.800781 -273.312581) (xy 51.77056 -273.270985) (xy 51.747217 -273.225173) (xy 51.731329 -273.176274)
			(xy 51.723286 -273.125492) (xy 51.404608 -273.125492) (xy 51.396892 -273.172968) (xy 51.381308 -273.219649)
			(xy 51.358437 -273.263226) (xy 51.328872 -273.30257) (xy 51.293379 -273.336662) (xy 51.252876 -273.364618)
			(xy 51.208414 -273.385716) (xy 51.161143 -273.399408) (xy 51.112288 -273.40534) (xy 51.063113 -273.403359)
			(xy 51.014894 -273.393515) (xy 50.968878 -273.376063) (xy 50.926257 -273.351456) (xy 50.888136 -273.320331)
			(xy 50.855501 -273.283494) (xy 50.829198 -273.241898) (xy 50.809907 -273.196622) (xy 50.79813 -273.148838)
			(xy 50.79417 -273.099784) (xy 50.476912 -273.099784) (xy 50.476408 -273.125492) (xy 50.468365 -273.176274)
			(xy 50.452477 -273.225173) (xy 50.429134 -273.270985) (xy 50.398913 -273.312581) (xy 50.362557 -273.348937)
			(xy 50.320961 -273.379158) (xy 50.275149 -273.402501) (xy 50.22625 -273.418389) (xy 50.175468 -273.426432)
			(xy 50.124052 -273.426432) (xy 50.07327 -273.418389) (xy 50.024371 -273.402501) (xy 49.978559 -273.379158)
			(xy 49.936963 -273.348937) (xy 49.900607 -273.312581) (xy 49.870386 -273.270985) (xy 49.847043 -273.225173)
			(xy 49.831155 -273.176274) (xy 49.823112 -273.125492) (xy 49.504434 -273.125492) (xy 49.496718 -273.172968)
			(xy 49.481134 -273.219649) (xy 49.458263 -273.263226) (xy 49.428698 -273.30257) (xy 49.393205 -273.336662)
			(xy 49.352702 -273.364618) (xy 49.30824 -273.385716) (xy 49.260969 -273.399408) (xy 49.212114 -273.40534)
			(xy 49.162939 -273.403359) (xy 49.11472 -273.393515) (xy 49.068704 -273.376063) (xy 49.026083 -273.351456)
			(xy 48.987962 -273.320331) (xy 48.955327 -273.283494) (xy 48.929024 -273.241898) (xy 48.909733 -273.196622)
			(xy 48.897956 -273.148838) (xy 48.893996 -273.099784) (xy 48.576992 -273.099784) (xy 48.576488 -273.125492)
			(xy 48.568445 -273.176274) (xy 48.552557 -273.225173) (xy 48.529214 -273.270985) (xy 48.498993 -273.312581)
			(xy 48.462637 -273.348937) (xy 48.421041 -273.379158) (xy 48.375229 -273.402501) (xy 48.32633 -273.418389)
			(xy 48.275548 -273.426432) (xy 48.224132 -273.426432) (xy 48.17335 -273.418389) (xy 48.124451 -273.402501)
			(xy 48.078639 -273.379158) (xy 48.037043 -273.348937) (xy 48.000687 -273.312581) (xy 47.970466 -273.270985)
			(xy 47.947123 -273.225173) (xy 47.931235 -273.176274) (xy 47.923192 -273.125492) (xy 47.604514 -273.125492)
			(xy 47.596798 -273.172968) (xy 47.581214 -273.219649) (xy 47.558343 -273.263226) (xy 47.528778 -273.30257)
			(xy 47.493285 -273.336662) (xy 47.452782 -273.364618) (xy 47.40832 -273.385716) (xy 47.361049 -273.399408)
			(xy 47.312194 -273.40534) (xy 47.263019 -273.403359) (xy 47.2148 -273.393515) (xy 47.168784 -273.376063)
			(xy 47.126163 -273.351456) (xy 47.088042 -273.320331) (xy 47.055407 -273.283494) (xy 47.029104 -273.241898)
			(xy 47.009813 -273.196622) (xy 46.998036 -273.148838) (xy 46.994076 -273.099784) (xy 46.677072 -273.099784)
			(xy 46.676568 -273.125492) (xy 46.668525 -273.176274) (xy 46.652637 -273.225173) (xy 46.629294 -273.270985)
			(xy 46.599073 -273.312581) (xy 46.562717 -273.348937) (xy 46.521121 -273.379158) (xy 46.475309 -273.402501)
			(xy 46.42641 -273.418389) (xy 46.375628 -273.426432) (xy 46.324212 -273.426432) (xy 46.27343 -273.418389)
			(xy 46.224531 -273.402501) (xy 46.178719 -273.379158) (xy 46.137123 -273.348937) (xy 46.100767 -273.312581)
			(xy 46.070546 -273.270985) (xy 46.047203 -273.225173) (xy 46.031315 -273.176274) (xy 46.023272 -273.125492)
			(xy 45.704594 -273.125492) (xy 45.696878 -273.172968) (xy 45.681294 -273.219649) (xy 45.658423 -273.263226)
			(xy 45.628858 -273.30257) (xy 45.593365 -273.336662) (xy 45.552862 -273.364618) (xy 45.5084 -273.385716)
			(xy 45.461129 -273.399408) (xy 45.412274 -273.40534) (xy 45.363099 -273.403359) (xy 45.31488 -273.393515)
			(xy 45.268864 -273.376063) (xy 45.226243 -273.351456) (xy 45.188122 -273.320331) (xy 45.155487 -273.283494)
			(xy 45.129184 -273.241898) (xy 45.109893 -273.196622) (xy 45.098116 -273.148838) (xy 45.094156 -273.099784)
			(xy 44.776898 -273.099784) (xy 44.776394 -273.125492) (xy 44.768351 -273.176274) (xy 44.752463 -273.225173)
			(xy 44.72912 -273.270985) (xy 44.698899 -273.312581) (xy 44.662543 -273.348937) (xy 44.620947 -273.379158)
			(xy 44.575135 -273.402501) (xy 44.526236 -273.418389) (xy 44.475454 -273.426432) (xy 44.424038 -273.426432)
			(xy 44.373256 -273.418389) (xy 44.324357 -273.402501) (xy 44.278545 -273.379158) (xy 44.236949 -273.348937)
			(xy 44.200593 -273.312581) (xy 44.170372 -273.270985) (xy 44.147029 -273.225173) (xy 44.131141 -273.176274)
			(xy 44.123098 -273.125492) (xy 43.80442 -273.125492) (xy 43.796704 -273.172968) (xy 43.78112 -273.219649)
			(xy 43.758249 -273.263226) (xy 43.728684 -273.30257) (xy 43.693191 -273.336662) (xy 43.652688 -273.364618)
			(xy 43.608226 -273.385716) (xy 43.560955 -273.399408) (xy 43.5121 -273.40534) (xy 43.462925 -273.403359)
			(xy 43.414706 -273.393515) (xy 43.36869 -273.376063) (xy 43.326069 -273.351456) (xy 43.287948 -273.320331)
			(xy 43.255313 -273.283494) (xy 43.22901 -273.241898) (xy 43.209719 -273.196622) (xy 43.197942 -273.148838)
			(xy 43.193982 -273.099784) (xy 33.859951 -273.099784) (xy 33.788387 -273.233055) (xy 33.689109 -273.401002)
			(xy 33.58302 -273.564733) (xy 33.575919 -273.574764) (xy 37.018988 -273.574764) (xy 37.022948 -273.52571)
			(xy 37.034725 -273.477926) (xy 37.054016 -273.43265) (xy 37.080319 -273.391054) (xy 37.112954 -273.354217)
			(xy 37.151075 -273.323092) (xy 37.193696 -273.298485) (xy 37.239712 -273.281033) (xy 37.287931 -273.271189)
			(xy 37.337106 -273.269208) (xy 37.385961 -273.27514) (xy 37.433232 -273.288832) (xy 37.477694 -273.30993)
			(xy 37.518197 -273.337886) (xy 37.55369 -273.371978) (xy 37.583255 -273.411322) (xy 37.606126 -273.454899)
			(xy 37.62171 -273.50158) (xy 37.629605 -273.550157) (xy 37.6301 -273.574764) (xy 37.968948 -273.574764)
			(xy 37.972908 -273.52571) (xy 37.984685 -273.477926) (xy 38.003976 -273.43265) (xy 38.030279 -273.391054)
			(xy 38.062914 -273.354217) (xy 38.101035 -273.323092) (xy 38.143656 -273.298485) (xy 38.189672 -273.281033)
			(xy 38.237891 -273.271189) (xy 38.287066 -273.269208) (xy 38.335921 -273.27514) (xy 38.383192 -273.288832)
			(xy 38.427654 -273.30993) (xy 38.468157 -273.337886) (xy 38.50365 -273.371978) (xy 38.533215 -273.411322)
			(xy 38.556086 -273.454899) (xy 38.57167 -273.50158) (xy 38.579565 -273.550157) (xy 38.58006 -273.574764)
			(xy 38.919162 -273.574764) (xy 38.923122 -273.52571) (xy 38.934899 -273.477926) (xy 38.95419 -273.43265)
			(xy 38.980493 -273.391054) (xy 39.013128 -273.354217) (xy 39.051249 -273.323092) (xy 39.09387 -273.298485)
			(xy 39.139886 -273.281033) (xy 39.188105 -273.271189) (xy 39.23728 -273.269208) (xy 39.286135 -273.27514)
			(xy 39.333406 -273.288832) (xy 39.377868 -273.30993) (xy 39.418371 -273.337886) (xy 39.453864 -273.371978)
			(xy 39.483429 -273.411322) (xy 39.5063 -273.454899) (xy 39.521884 -273.50158) (xy 39.529779 -273.550157)
			(xy 39.530274 -273.574764) (xy 39.869122 -273.574764) (xy 39.873082 -273.52571) (xy 39.884859 -273.477926)
			(xy 39.90415 -273.43265) (xy 39.930453 -273.391054) (xy 39.963088 -273.354217) (xy 40.001209 -273.323092)
			(xy 40.04383 -273.298485) (xy 40.089846 -273.281033) (xy 40.138065 -273.271189) (xy 40.18724 -273.269208)
			(xy 40.236095 -273.27514) (xy 40.283366 -273.288832) (xy 40.327828 -273.30993) (xy 40.368331 -273.337886)
			(xy 40.403824 -273.371978) (xy 40.433389 -273.411322) (xy 40.45626 -273.454899) (xy 40.471844 -273.50158)
			(xy 40.479739 -273.550157) (xy 40.480234 -273.574764) (xy 40.819082 -273.574764) (xy 40.823042 -273.52571)
			(xy 40.834819 -273.477926) (xy 40.85411 -273.43265) (xy 40.880413 -273.391054) (xy 40.913048 -273.354217)
			(xy 40.951169 -273.323092) (xy 40.99379 -273.298485) (xy 41.039806 -273.281033) (xy 41.088025 -273.271189)
			(xy 41.1372 -273.269208) (xy 41.186055 -273.27514) (xy 41.233326 -273.288832) (xy 41.277788 -273.30993)
			(xy 41.318291 -273.337886) (xy 41.353784 -273.371978) (xy 41.383349 -273.411322) (xy 41.40622 -273.454899)
			(xy 41.421804 -273.50158) (xy 41.429699 -273.550157) (xy 41.430194 -273.574764) (xy 41.769042 -273.574764)
			(xy 41.773002 -273.52571) (xy 41.784779 -273.477926) (xy 41.80407 -273.43265) (xy 41.830373 -273.391054)
			(xy 41.863008 -273.354217) (xy 41.901129 -273.323092) (xy 41.94375 -273.298485) (xy 41.989766 -273.281033)
			(xy 42.037985 -273.271189) (xy 42.08716 -273.269208) (xy 42.136015 -273.27514) (xy 42.183286 -273.288832)
			(xy 42.227748 -273.30993) (xy 42.268251 -273.337886) (xy 42.303744 -273.371978) (xy 42.333309 -273.411322)
			(xy 42.35618 -273.454899) (xy 42.371764 -273.50158) (xy 42.379659 -273.550157) (xy 42.380154 -273.574764)
			(xy 42.379659 -273.599371) (xy 42.371764 -273.647948) (xy 42.35618 -273.694629) (xy 42.333309 -273.738206)
			(xy 42.303744 -273.77755) (xy 42.268251 -273.811642) (xy 42.227748 -273.839598) (xy 42.183286 -273.860696)
			(xy 42.136015 -273.874388) (xy 42.08716 -273.88032) (xy 42.037985 -273.878339) (xy 41.989766 -273.868495)
			(xy 41.94375 -273.851043) (xy 41.901129 -273.826436) (xy 41.863008 -273.795311) (xy 41.830373 -273.758474)
			(xy 41.80407 -273.716878) (xy 41.784779 -273.671602) (xy 41.773002 -273.623818) (xy 41.769042 -273.574764)
			(xy 41.430194 -273.574764) (xy 41.429699 -273.599371) (xy 41.421804 -273.647948) (xy 41.40622 -273.694629)
			(xy 41.383349 -273.738206) (xy 41.353784 -273.77755) (xy 41.318291 -273.811642) (xy 41.277788 -273.839598)
			(xy 41.233326 -273.860696) (xy 41.186055 -273.874388) (xy 41.1372 -273.88032) (xy 41.088025 -273.878339)
			(xy 41.039806 -273.868495) (xy 40.99379 -273.851043) (xy 40.951169 -273.826436) (xy 40.913048 -273.795311)
			(xy 40.880413 -273.758474) (xy 40.85411 -273.716878) (xy 40.834819 -273.671602) (xy 40.823042 -273.623818)
			(xy 40.819082 -273.574764) (xy 40.480234 -273.574764) (xy 40.479739 -273.599371) (xy 40.471844 -273.647948)
			(xy 40.45626 -273.694629) (xy 40.433389 -273.738206) (xy 40.403824 -273.77755) (xy 40.368331 -273.811642)
			(xy 40.327828 -273.839598) (xy 40.283366 -273.860696) (xy 40.236095 -273.874388) (xy 40.18724 -273.88032)
			(xy 40.138065 -273.878339) (xy 40.089846 -273.868495) (xy 40.04383 -273.851043) (xy 40.001209 -273.826436)
			(xy 39.963088 -273.795311) (xy 39.930453 -273.758474) (xy 39.90415 -273.716878) (xy 39.884859 -273.671602)
			(xy 39.873082 -273.623818) (xy 39.869122 -273.574764) (xy 39.530274 -273.574764) (xy 39.529779 -273.599371)
			(xy 39.521884 -273.647948) (xy 39.5063 -273.694629) (xy 39.483429 -273.738206) (xy 39.453864 -273.77755)
			(xy 39.418371 -273.811642) (xy 39.377868 -273.839598) (xy 39.333406 -273.860696) (xy 39.286135 -273.874388)
			(xy 39.23728 -273.88032) (xy 39.188105 -273.878339) (xy 39.139886 -273.868495) (xy 39.09387 -273.851043)
			(xy 39.051249 -273.826436) (xy 39.013128 -273.795311) (xy 38.980493 -273.758474) (xy 38.95419 -273.716878)
			(xy 38.934899 -273.671602) (xy 38.923122 -273.623818) (xy 38.919162 -273.574764) (xy 38.58006 -273.574764)
			(xy 38.579565 -273.599371) (xy 38.57167 -273.647948) (xy 38.556086 -273.694629) (xy 38.533215 -273.738206)
			(xy 38.50365 -273.77755) (xy 38.468157 -273.811642) (xy 38.427654 -273.839598) (xy 38.383192 -273.860696)
			(xy 38.335921 -273.874388) (xy 38.287066 -273.88032) (xy 38.237891 -273.878339) (xy 38.189672 -273.868495)
			(xy 38.143656 -273.851043) (xy 38.101035 -273.826436) (xy 38.062914 -273.795311) (xy 38.030279 -273.758474)
			(xy 38.003976 -273.716878) (xy 37.984685 -273.671602) (xy 37.972908 -273.623818) (xy 37.968948 -273.574764)
			(xy 37.6301 -273.574764) (xy 37.629605 -273.599371) (xy 37.62171 -273.647948) (xy 37.606126 -273.694629)
			(xy 37.583255 -273.738206) (xy 37.55369 -273.77755) (xy 37.518197 -273.811642) (xy 37.477694 -273.839598)
			(xy 37.433232 -273.860696) (xy 37.385961 -273.874388) (xy 37.337106 -273.88032) (xy 37.287931 -273.878339)
			(xy 37.239712 -273.868495) (xy 37.193696 -273.851043) (xy 37.151075 -273.826436) (xy 37.112954 -273.795311)
			(xy 37.080319 -273.758474) (xy 37.054016 -273.716878) (xy 37.034725 -273.671602) (xy 37.022948 -273.623818)
			(xy 37.018988 -273.574764) (xy 33.575919 -273.574764) (xy 33.470299 -273.72397) (xy 33.351135 -273.878444)
			(xy 33.22573 -274.027897) (xy 33.094294 -274.172075) (xy 32.95705 -274.310735) (xy 32.814229 -274.443643)
			(xy 32.719591 -274.524724) (xy 37.018988 -274.524724) (xy 37.022948 -274.47567) (xy 37.034725 -274.427886)
			(xy 37.054016 -274.38261) (xy 37.080319 -274.341014) (xy 37.112954 -274.304177) (xy 37.151075 -274.273052)
			(xy 37.193696 -274.248445) (xy 37.239712 -274.230993) (xy 37.287931 -274.221149) (xy 37.337106 -274.219168)
			(xy 37.385961 -274.2251) (xy 37.433232 -274.238792) (xy 37.477694 -274.25989) (xy 37.518197 -274.287846)
			(xy 37.55369 -274.321938) (xy 37.583255 -274.361282) (xy 37.606126 -274.404859) (xy 37.62171 -274.45154)
			(xy 37.629605 -274.500117) (xy 37.6301 -274.524724) (xy 37.630095 -274.524978) (xy 37.969202 -274.524978)
			(xy 37.973162 -274.475924) (xy 37.984939 -274.42814) (xy 38.00423 -274.382864) (xy 38.030533 -274.341268)
			(xy 38.063168 -274.304431) (xy 38.101289 -274.273306) (xy 38.14391 -274.248699) (xy 38.189926 -274.231247)
			(xy 38.238145 -274.221403) (xy 38.28732 -274.219422) (xy 38.336175 -274.225354) (xy 38.383446 -274.239046)
			(xy 38.427908 -274.260144) (xy 38.468411 -274.2881) (xy 38.503904 -274.322192) (xy 38.533469 -274.361536)
			(xy 38.55634 -274.405113) (xy 38.571924 -274.451794) (xy 38.579819 -274.500371) (xy 38.580314 -274.524978)
			(xy 38.919162 -274.524978) (xy 38.923122 -274.475924) (xy 38.934899 -274.42814) (xy 38.95419 -274.382864)
			(xy 38.980493 -274.341268) (xy 39.013128 -274.304431) (xy 39.051249 -274.273306) (xy 39.09387 -274.248699)
			(xy 39.139886 -274.231247) (xy 39.188105 -274.221403) (xy 39.23728 -274.219422) (xy 39.286135 -274.225354)
			(xy 39.333406 -274.239046) (xy 39.377868 -274.260144) (xy 39.418371 -274.2881) (xy 39.453864 -274.322192)
			(xy 39.483429 -274.361536) (xy 39.5063 -274.405113) (xy 39.521884 -274.451794) (xy 39.529779 -274.500371)
			(xy 39.530274 -274.524978) (xy 39.869122 -274.524978) (xy 39.873082 -274.475924) (xy 39.884859 -274.42814)
			(xy 39.90415 -274.382864) (xy 39.930453 -274.341268) (xy 39.963088 -274.304431) (xy 40.001209 -274.273306)
			(xy 40.04383 -274.248699) (xy 40.089846 -274.231247) (xy 40.138065 -274.221403) (xy 40.18724 -274.219422)
			(xy 40.236095 -274.225354) (xy 40.283366 -274.239046) (xy 40.327828 -274.260144) (xy 40.368331 -274.2881)
			(xy 40.403824 -274.322192) (xy 40.433389 -274.361536) (xy 40.45626 -274.405113) (xy 40.471844 -274.451794)
			(xy 40.479739 -274.500371) (xy 40.480234 -274.524978) (xy 40.819082 -274.524978) (xy 40.823042 -274.475924)
			(xy 40.834819 -274.42814) (xy 40.85411 -274.382864) (xy 40.880413 -274.341268) (xy 40.913048 -274.304431)
			(xy 40.951169 -274.273306) (xy 40.99379 -274.248699) (xy 41.039806 -274.231247) (xy 41.088025 -274.221403)
			(xy 41.1372 -274.219422) (xy 41.186055 -274.225354) (xy 41.233326 -274.239046) (xy 41.277788 -274.260144)
			(xy 41.318291 -274.2881) (xy 41.353784 -274.322192) (xy 41.383349 -274.361536) (xy 41.40622 -274.405113)
			(xy 41.421804 -274.451794) (xy 41.429699 -274.500371) (xy 41.430194 -274.524978) (xy 41.769042 -274.524978)
			(xy 41.773002 -274.475924) (xy 41.784779 -274.42814) (xy 41.80407 -274.382864) (xy 41.830373 -274.341268)
			(xy 41.863008 -274.304431) (xy 41.901129 -274.273306) (xy 41.94375 -274.248699) (xy 41.989766 -274.231247)
			(xy 42.037985 -274.221403) (xy 42.08716 -274.219422) (xy 42.136015 -274.225354) (xy 42.183286 -274.239046)
			(xy 42.227748 -274.260144) (xy 42.268251 -274.2881) (xy 42.303744 -274.322192) (xy 42.333309 -274.361536)
			(xy 42.35618 -274.405113) (xy 42.371764 -274.451794) (xy 42.379659 -274.500371) (xy 42.379988 -274.516721)
			(xy 42.719059 -274.516721) (xy 42.724426 -274.467366) (xy 42.737708 -274.419529) (xy 42.758554 -274.374471)
			(xy 42.786415 -274.333379) (xy 42.820556 -274.297337) (xy 42.86008 -274.267292) (xy 42.903943 -274.244038)
			(xy 42.950991 -274.228187) (xy 42.999983 -274.220156) (xy 43.024806 -274.21967) (xy 43.038989 -274.219846)
			(xy 43.067229 -274.222519) (xy 43.081194 -274.225004) (xy 43.095159 -274.227177) (xy 43.123293 -274.224599)
			(xy 43.149643 -274.214409) (xy 43.172192 -274.197387) (xy 43.189212 -274.174838) (xy 43.1994 -274.148487)
			(xy 43.201977 -274.120353) (xy 43.199812 -274.106386) (xy 43.197327 -274.092357) (xy 43.194655 -274.06399)
			(xy 43.194478 -274.049744) (xy 43.19493 -274.024918) (xy 43.202956 -273.975921) (xy 43.218803 -273.928867)
			(xy 43.242055 -273.884996) (xy 43.272098 -273.845466) (xy 43.30814 -273.811317) (xy 43.349233 -273.783449)
			(xy 43.394293 -273.762597) (xy 43.442133 -273.74931) (xy 43.491492 -273.743937) (xy 43.54107 -273.746621)
			(xy 43.589561 -273.757291) (xy 43.635687 -273.775666) (xy 43.678232 -273.801261) (xy 43.716076 -273.833403)
			(xy 43.748221 -273.871243) (xy 43.77382 -273.913786) (xy 43.7922 -273.95991) (xy 43.802874 -274.0084)
			(xy 43.805563 -274.057978) (xy 43.803663 -274.075452) (xy 44.123098 -274.075452) (xy 44.123098 -274.024036)
			(xy 44.131141 -273.973254) (xy 44.147029 -273.924355) (xy 44.170372 -273.878543) (xy 44.200593 -273.836947)
			(xy 44.236949 -273.800591) (xy 44.278545 -273.77037) (xy 44.324357 -273.747027) (xy 44.373256 -273.731139)
			(xy 44.424038 -273.723096) (xy 44.475454 -273.723096) (xy 44.526236 -273.731139) (xy 44.575135 -273.747027)
			(xy 44.620947 -273.77037) (xy 44.662543 -273.800591) (xy 44.698899 -273.836947) (xy 44.72912 -273.878543)
			(xy 44.752463 -273.924355) (xy 44.768351 -273.973254) (xy 44.776394 -274.024036) (xy 44.776898 -274.049744)
			(xy 45.094156 -274.049744) (xy 45.098116 -274.00069) (xy 45.109893 -273.952906) (xy 45.129184 -273.90763)
			(xy 45.155487 -273.866034) (xy 45.188122 -273.829197) (xy 45.226243 -273.798072) (xy 45.268864 -273.773465)
			(xy 45.31488 -273.756013) (xy 45.363099 -273.746169) (xy 45.412274 -273.744188) (xy 45.461129 -273.75012)
			(xy 45.5084 -273.763812) (xy 45.552862 -273.78491) (xy 45.593365 -273.812866) (xy 45.628858 -273.846958)
			(xy 45.658423 -273.886302) (xy 45.681294 -273.929879) (xy 45.696878 -273.97656) (xy 45.704773 -274.025137)
			(xy 45.705268 -274.049744) (xy 45.704773 -274.074351) (xy 45.704594 -274.075452) (xy 46.023272 -274.075452)
			(xy 46.023272 -274.024036) (xy 46.031315 -273.973254) (xy 46.047203 -273.924355) (xy 46.070546 -273.878543)
			(xy 46.100767 -273.836947) (xy 46.137123 -273.800591) (xy 46.178719 -273.77037) (xy 46.224531 -273.747027)
			(xy 46.27343 -273.731139) (xy 46.324212 -273.723096) (xy 46.375628 -273.723096) (xy 46.42641 -273.731139)
			(xy 46.475309 -273.747027) (xy 46.521121 -273.77037) (xy 46.562717 -273.800591) (xy 46.599073 -273.836947)
			(xy 46.629294 -273.878543) (xy 46.652637 -273.924355) (xy 46.668525 -273.973254) (xy 46.676568 -274.024036)
			(xy 46.677072 -274.049744) (xy 46.994076 -274.049744) (xy 46.998036 -274.00069) (xy 47.009813 -273.952906)
			(xy 47.029104 -273.90763) (xy 47.055407 -273.866034) (xy 47.088042 -273.829197) (xy 47.126163 -273.798072)
			(xy 47.168784 -273.773465) (xy 47.2148 -273.756013) (xy 47.263019 -273.746169) (xy 47.312194 -273.744188)
			(xy 47.361049 -273.75012) (xy 47.40832 -273.763812) (xy 47.452782 -273.78491) (xy 47.493285 -273.812866)
			(xy 47.528778 -273.846958) (xy 47.558343 -273.886302) (xy 47.581214 -273.929879) (xy 47.596798 -273.97656)
			(xy 47.604693 -274.025137) (xy 47.605188 -274.049744) (xy 47.604693 -274.074351) (xy 47.604514 -274.075452)
			(xy 47.923192 -274.075452) (xy 47.923192 -274.024036) (xy 47.931235 -273.973254) (xy 47.947123 -273.924355)
			(xy 47.970466 -273.878543) (xy 48.000687 -273.836947) (xy 48.037043 -273.800591) (xy 48.078639 -273.77037)
			(xy 48.124451 -273.747027) (xy 48.17335 -273.731139) (xy 48.224132 -273.723096) (xy 48.275548 -273.723096)
			(xy 48.32633 -273.731139) (xy 48.375229 -273.747027) (xy 48.421041 -273.77037) (xy 48.462637 -273.800591)
			(xy 48.498993 -273.836947) (xy 48.529214 -273.878543) (xy 48.552557 -273.924355) (xy 48.568445 -273.973254)
			(xy 48.576488 -274.024036) (xy 48.576992 -274.049744) (xy 48.893996 -274.049744) (xy 48.897956 -274.00069)
			(xy 48.909733 -273.952906) (xy 48.929024 -273.90763) (xy 48.955327 -273.866034) (xy 48.987962 -273.829197)
			(xy 49.026083 -273.798072) (xy 49.068704 -273.773465) (xy 49.11472 -273.756013) (xy 49.162939 -273.746169)
			(xy 49.212114 -273.744188) (xy 49.260969 -273.75012) (xy 49.30824 -273.763812) (xy 49.352702 -273.78491)
			(xy 49.393205 -273.812866) (xy 49.428698 -273.846958) (xy 49.458263 -273.886302) (xy 49.481134 -273.929879)
			(xy 49.496718 -273.97656) (xy 49.504613 -274.025137) (xy 49.505108 -274.049744) (xy 49.504613 -274.074351)
			(xy 49.504434 -274.075452) (xy 49.823112 -274.075452) (xy 49.823112 -274.024036) (xy 49.831155 -273.973254)
			(xy 49.847043 -273.924355) (xy 49.870386 -273.878543) (xy 49.900607 -273.836947) (xy 49.936963 -273.800591)
			(xy 49.978559 -273.77037) (xy 50.024371 -273.747027) (xy 50.07327 -273.731139) (xy 50.124052 -273.723096)
			(xy 50.175468 -273.723096) (xy 50.22625 -273.731139) (xy 50.275149 -273.747027) (xy 50.320961 -273.77037)
			(xy 50.362557 -273.800591) (xy 50.398913 -273.836947) (xy 50.429134 -273.878543) (xy 50.452477 -273.924355)
			(xy 50.468365 -273.973254) (xy 50.476408 -274.024036) (xy 50.476912 -274.049744) (xy 50.79417 -274.049744)
			(xy 50.79813 -274.00069) (xy 50.809907 -273.952906) (xy 50.829198 -273.90763) (xy 50.855501 -273.866034)
			(xy 50.888136 -273.829197) (xy 50.926257 -273.798072) (xy 50.968878 -273.773465) (xy 51.014894 -273.756013)
			(xy 51.063113 -273.746169) (xy 51.112288 -273.744188) (xy 51.161143 -273.75012) (xy 51.208414 -273.763812)
			(xy 51.252876 -273.78491) (xy 51.293379 -273.812866) (xy 51.328872 -273.846958) (xy 51.358437 -273.886302)
			(xy 51.381308 -273.929879) (xy 51.396892 -273.97656) (xy 51.404787 -274.025137) (xy 51.405282 -274.049744)
			(xy 51.404787 -274.074351) (xy 51.404608 -274.075452) (xy 51.723286 -274.075452) (xy 51.723286 -274.024036)
			(xy 51.731329 -273.973254) (xy 51.747217 -273.924355) (xy 51.77056 -273.878543) (xy 51.800781 -273.836947)
			(xy 51.837137 -273.800591) (xy 51.878733 -273.77037) (xy 51.924545 -273.747027) (xy 51.973444 -273.731139)
			(xy 52.024226 -273.723096) (xy 52.075642 -273.723096) (xy 52.126424 -273.731139) (xy 52.175323 -273.747027)
			(xy 52.221135 -273.77037) (xy 52.262731 -273.800591) (xy 52.299087 -273.836947) (xy 52.329308 -273.878543)
			(xy 52.352651 -273.924355) (xy 52.368539 -273.973254) (xy 52.376582 -274.024036) (xy 52.377086 -274.049744)
			(xy 52.69409 -274.049744) (xy 52.69805 -274.00069) (xy 52.709827 -273.952906) (xy 52.729118 -273.90763)
			(xy 52.755421 -273.866034) (xy 52.788056 -273.829197) (xy 52.826177 -273.798072) (xy 52.868798 -273.773465)
			(xy 52.914814 -273.756013) (xy 52.963033 -273.746169) (xy 53.012208 -273.744188) (xy 53.061063 -273.75012)
			(xy 53.108334 -273.763812) (xy 53.152796 -273.78491) (xy 53.193299 -273.812866) (xy 53.228792 -273.846958)
			(xy 53.258357 -273.886302) (xy 53.281228 -273.929879) (xy 53.296812 -273.97656) (xy 53.304707 -274.025137)
			(xy 53.305202 -274.049744) (xy 53.304707 -274.074351) (xy 53.304528 -274.075452) (xy 53.623206 -274.075452)
			(xy 53.623206 -274.024036) (xy 53.631249 -273.973254) (xy 53.647137 -273.924355) (xy 53.67048 -273.878543)
			(xy 53.700701 -273.836947) (xy 53.737057 -273.800591) (xy 53.778653 -273.77037) (xy 53.824465 -273.747027)
			(xy 53.873364 -273.731139) (xy 53.924146 -273.723096) (xy 53.975562 -273.723096) (xy 54.026344 -273.731139)
			(xy 54.075243 -273.747027) (xy 54.121055 -273.77037) (xy 54.162651 -273.800591) (xy 54.199007 -273.836947)
			(xy 54.229228 -273.878543) (xy 54.252571 -273.924355) (xy 54.268459 -273.973254) (xy 54.276502 -274.024036)
			(xy 54.277006 -274.049744) (xy 54.59401 -274.049744) (xy 54.59797 -274.00069) (xy 54.609747 -273.952906)
			(xy 54.629038 -273.90763) (xy 54.655341 -273.866034) (xy 54.687976 -273.829197) (xy 54.726097 -273.798072)
			(xy 54.768718 -273.773465) (xy 54.814734 -273.756013) (xy 54.862953 -273.746169) (xy 54.912128 -273.744188)
			(xy 54.960983 -273.75012) (xy 55.008254 -273.763812) (xy 55.052716 -273.78491) (xy 55.093219 -273.812866)
			(xy 55.128712 -273.846958) (xy 55.158277 -273.886302) (xy 55.181148 -273.929879) (xy 55.196732 -273.97656)
			(xy 55.204627 -274.025137) (xy 55.205122 -274.049744) (xy 55.204627 -274.074351) (xy 55.204448 -274.075452)
			(xy 55.523126 -274.075452) (xy 55.523126 -274.024036) (xy 55.531169 -273.973254) (xy 55.547057 -273.924355)
			(xy 55.5704 -273.878543) (xy 55.600621 -273.836947) (xy 55.636977 -273.800591) (xy 55.678573 -273.77037)
			(xy 55.724385 -273.747027) (xy 55.773284 -273.731139) (xy 55.824066 -273.723096) (xy 55.875482 -273.723096)
			(xy 55.926264 -273.731139) (xy 55.975163 -273.747027) (xy 56.020975 -273.77037) (xy 56.062571 -273.800591)
			(xy 56.098927 -273.836947) (xy 56.129148 -273.878543) (xy 56.152491 -273.924355) (xy 56.168379 -273.973254)
			(xy 56.176422 -274.024036) (xy 56.176926 -274.049744) (xy 56.494184 -274.049744) (xy 56.498144 -274.00069)
			(xy 56.509921 -273.952906) (xy 56.529212 -273.90763) (xy 56.555515 -273.866034) (xy 56.58815 -273.829197)
			(xy 56.626271 -273.798072) (xy 56.668892 -273.773465) (xy 56.714908 -273.756013) (xy 56.763127 -273.746169)
			(xy 56.812302 -273.744188) (xy 56.861157 -273.75012) (xy 56.908428 -273.763812) (xy 56.95289 -273.78491)
			(xy 56.993393 -273.812866) (xy 57.028886 -273.846958) (xy 57.058451 -273.886302) (xy 57.081322 -273.929879)
			(xy 57.096906 -273.97656) (xy 57.104801 -274.025137) (xy 57.105296 -274.049744) (xy 57.104801 -274.074351)
			(xy 57.096906 -274.122928) (xy 57.081322 -274.169609) (xy 57.058451 -274.213186) (xy 57.028886 -274.25253)
			(xy 56.993393 -274.286622) (xy 56.95289 -274.314578) (xy 56.908428 -274.335676) (xy 56.861157 -274.349368)
			(xy 56.812302 -274.3553) (xy 56.763127 -274.353319) (xy 56.714908 -274.343475) (xy 56.668892 -274.326023)
			(xy 56.626271 -274.301416) (xy 56.58815 -274.270291) (xy 56.555515 -274.233454) (xy 56.529212 -274.191858)
			(xy 56.509921 -274.146582) (xy 56.498144 -274.098798) (xy 56.494184 -274.049744) (xy 56.176926 -274.049744)
			(xy 56.176422 -274.075452) (xy 56.168379 -274.126234) (xy 56.152491 -274.175133) (xy 56.129148 -274.220945)
			(xy 56.098927 -274.262541) (xy 56.062571 -274.298897) (xy 56.020975 -274.329118) (xy 55.975163 -274.352461)
			(xy 55.926264 -274.368349) (xy 55.875482 -274.376392) (xy 55.824066 -274.376392) (xy 55.773284 -274.368349)
			(xy 55.724385 -274.352461) (xy 55.678573 -274.329118) (xy 55.636977 -274.298897) (xy 55.600621 -274.262541)
			(xy 55.5704 -274.220945) (xy 55.547057 -274.175133) (xy 55.531169 -274.126234) (xy 55.523126 -274.075452)
			(xy 55.204448 -274.075452) (xy 55.196732 -274.122928) (xy 55.181148 -274.169609) (xy 55.158277 -274.213186)
			(xy 55.128712 -274.25253) (xy 55.093219 -274.286622) (xy 55.052716 -274.314578) (xy 55.008254 -274.335676)
			(xy 54.960983 -274.349368) (xy 54.912128 -274.3553) (xy 54.862953 -274.353319) (xy 54.814734 -274.343475)
			(xy 54.768718 -274.326023) (xy 54.726097 -274.301416) (xy 54.687976 -274.270291) (xy 54.655341 -274.233454)
			(xy 54.629038 -274.191858) (xy 54.609747 -274.146582) (xy 54.59797 -274.098798) (xy 54.59401 -274.049744)
			(xy 54.277006 -274.049744) (xy 54.276502 -274.075452) (xy 54.268459 -274.126234) (xy 54.252571 -274.175133)
			(xy 54.229228 -274.220945) (xy 54.199007 -274.262541) (xy 54.162651 -274.298897) (xy 54.121055 -274.329118)
			(xy 54.075243 -274.352461) (xy 54.026344 -274.368349) (xy 53.975562 -274.376392) (xy 53.924146 -274.376392)
			(xy 53.873364 -274.368349) (xy 53.824465 -274.352461) (xy 53.778653 -274.329118) (xy 53.737057 -274.298897)
			(xy 53.700701 -274.262541) (xy 53.67048 -274.220945) (xy 53.647137 -274.175133) (xy 53.631249 -274.126234)
			(xy 53.623206 -274.075452) (xy 53.304528 -274.075452) (xy 53.296812 -274.122928) (xy 53.281228 -274.169609)
			(xy 53.258357 -274.213186) (xy 53.228792 -274.25253) (xy 53.193299 -274.286622) (xy 53.152796 -274.314578)
			(xy 53.108334 -274.335676) (xy 53.061063 -274.349368) (xy 53.012208 -274.3553) (xy 52.963033 -274.353319)
			(xy 52.914814 -274.343475) (xy 52.868798 -274.326023) (xy 52.826177 -274.301416) (xy 52.788056 -274.270291)
			(xy 52.755421 -274.233454) (xy 52.729118 -274.191858) (xy 52.709827 -274.146582) (xy 52.69805 -274.098798)
			(xy 52.69409 -274.049744) (xy 52.377086 -274.049744) (xy 52.376582 -274.075452) (xy 52.368539 -274.126234)
			(xy 52.352651 -274.175133) (xy 52.329308 -274.220945) (xy 52.299087 -274.262541) (xy 52.262731 -274.298897)
			(xy 52.221135 -274.329118) (xy 52.175323 -274.352461) (xy 52.126424 -274.368349) (xy 52.075642 -274.376392)
			(xy 52.024226 -274.376392) (xy 51.973444 -274.368349) (xy 51.924545 -274.352461) (xy 51.878733 -274.329118)
			(xy 51.837137 -274.298897) (xy 51.800781 -274.262541) (xy 51.77056 -274.220945) (xy 51.747217 -274.175133)
			(xy 51.731329 -274.126234) (xy 51.723286 -274.075452) (xy 51.404608 -274.075452) (xy 51.396892 -274.122928)
			(xy 51.381308 -274.169609) (xy 51.358437 -274.213186) (xy 51.328872 -274.25253) (xy 51.293379 -274.286622)
			(xy 51.252876 -274.314578) (xy 51.208414 -274.335676) (xy 51.161143 -274.349368) (xy 51.112288 -274.3553)
			(xy 51.063113 -274.353319) (xy 51.014894 -274.343475) (xy 50.968878 -274.326023) (xy 50.926257 -274.301416)
			(xy 50.888136 -274.270291) (xy 50.855501 -274.233454) (xy 50.829198 -274.191858) (xy 50.809907 -274.146582)
			(xy 50.79813 -274.098798) (xy 50.79417 -274.049744) (xy 50.476912 -274.049744) (xy 50.476408 -274.075452)
			(xy 50.468365 -274.126234) (xy 50.452477 -274.175133) (xy 50.429134 -274.220945) (xy 50.398913 -274.262541)
			(xy 50.362557 -274.298897) (xy 50.320961 -274.329118) (xy 50.275149 -274.352461) (xy 50.22625 -274.368349)
			(xy 50.175468 -274.376392) (xy 50.124052 -274.376392) (xy 50.07327 -274.368349) (xy 50.024371 -274.352461)
			(xy 49.978559 -274.329118) (xy 49.936963 -274.298897) (xy 49.900607 -274.262541) (xy 49.870386 -274.220945)
			(xy 49.847043 -274.175133) (xy 49.831155 -274.126234) (xy 49.823112 -274.075452) (xy 49.504434 -274.075452)
			(xy 49.496718 -274.122928) (xy 49.481134 -274.169609) (xy 49.458263 -274.213186) (xy 49.428698 -274.25253)
			(xy 49.393205 -274.286622) (xy 49.352702 -274.314578) (xy 49.30824 -274.335676) (xy 49.260969 -274.349368)
			(xy 49.212114 -274.3553) (xy 49.162939 -274.353319) (xy 49.11472 -274.343475) (xy 49.068704 -274.326023)
			(xy 49.026083 -274.301416) (xy 48.987962 -274.270291) (xy 48.955327 -274.233454) (xy 48.929024 -274.191858)
			(xy 48.909733 -274.146582) (xy 48.897956 -274.098798) (xy 48.893996 -274.049744) (xy 48.576992 -274.049744)
			(xy 48.576488 -274.075452) (xy 48.568445 -274.126234) (xy 48.552557 -274.175133) (xy 48.529214 -274.220945)
			(xy 48.498993 -274.262541) (xy 48.462637 -274.298897) (xy 48.421041 -274.329118) (xy 48.375229 -274.352461)
			(xy 48.32633 -274.368349) (xy 48.275548 -274.376392) (xy 48.224132 -274.376392) (xy 48.17335 -274.368349)
			(xy 48.124451 -274.352461) (xy 48.078639 -274.329118) (xy 48.037043 -274.298897) (xy 48.000687 -274.262541)
			(xy 47.970466 -274.220945) (xy 47.947123 -274.175133) (xy 47.931235 -274.126234) (xy 47.923192 -274.075452)
			(xy 47.604514 -274.075452) (xy 47.596798 -274.122928) (xy 47.581214 -274.169609) (xy 47.558343 -274.213186)
			(xy 47.528778 -274.25253) (xy 47.493285 -274.286622) (xy 47.452782 -274.314578) (xy 47.40832 -274.335676)
			(xy 47.361049 -274.349368) (xy 47.312194 -274.3553) (xy 47.263019 -274.353319) (xy 47.2148 -274.343475)
			(xy 47.168784 -274.326023) (xy 47.126163 -274.301416) (xy 47.088042 -274.270291) (xy 47.055407 -274.233454)
			(xy 47.029104 -274.191858) (xy 47.009813 -274.146582) (xy 46.998036 -274.098798) (xy 46.994076 -274.049744)
			(xy 46.677072 -274.049744) (xy 46.676568 -274.075452) (xy 46.668525 -274.126234) (xy 46.652637 -274.175133)
			(xy 46.629294 -274.220945) (xy 46.599073 -274.262541) (xy 46.562717 -274.298897) (xy 46.521121 -274.329118)
			(xy 46.475309 -274.352461) (xy 46.42641 -274.368349) (xy 46.375628 -274.376392) (xy 46.324212 -274.376392)
			(xy 46.27343 -274.368349) (xy 46.224531 -274.352461) (xy 46.178719 -274.329118) (xy 46.137123 -274.298897)
			(xy 46.100767 -274.262541) (xy 46.070546 -274.220945) (xy 46.047203 -274.175133) (xy 46.031315 -274.126234)
			(xy 46.023272 -274.075452) (xy 45.704594 -274.075452) (xy 45.696878 -274.122928) (xy 45.681294 -274.169609)
			(xy 45.658423 -274.213186) (xy 45.628858 -274.25253) (xy 45.593365 -274.286622) (xy 45.552862 -274.314578)
			(xy 45.5084 -274.335676) (xy 45.461129 -274.349368) (xy 45.412274 -274.3553) (xy 45.363099 -274.353319)
			(xy 45.31488 -274.343475) (xy 45.268864 -274.326023) (xy 45.226243 -274.301416) (xy 45.188122 -274.270291)
			(xy 45.155487 -274.233454) (xy 45.129184 -274.191858) (xy 45.109893 -274.146582) (xy 45.098116 -274.098798)
			(xy 45.094156 -274.049744) (xy 44.776898 -274.049744) (xy 44.776394 -274.075452) (xy 44.768351 -274.126234)
			(xy 44.752463 -274.175133) (xy 44.72912 -274.220945) (xy 44.698899 -274.262541) (xy 44.662543 -274.298897)
			(xy 44.620947 -274.329118) (xy 44.575135 -274.352461) (xy 44.526236 -274.368349) (xy 44.475454 -274.376392)
			(xy 44.424038 -274.376392) (xy 44.373256 -274.368349) (xy 44.324357 -274.352461) (xy 44.278545 -274.329118)
			(xy 44.236949 -274.298897) (xy 44.200593 -274.262541) (xy 44.170372 -274.220945) (xy 44.147029 -274.175133)
			(xy 44.131141 -274.126234) (xy 44.123098 -274.075452) (xy 43.803663 -274.075452) (xy 43.800196 -274.107338)
			(xy 43.786913 -274.155179) (xy 43.766065 -274.200241) (xy 43.738202 -274.241336) (xy 43.704056 -274.277382)
			(xy 43.664529 -274.307429) (xy 43.620661 -274.330685) (xy 43.573609 -274.346537) (xy 43.524611 -274.354568)
			(xy 43.499786 -274.355052) (xy 43.485603 -274.354877) (xy 43.457363 -274.352204) (xy 43.443398 -274.349718)
			(xy 43.429436 -274.34751) (xy 43.401297 -274.350091) (xy 43.374942 -274.360285) (xy 43.352391 -274.377312)
			(xy 43.33537 -274.399869) (xy 43.325184 -274.426227) (xy 43.322612 -274.454367) (xy 43.32478 -274.468336)
			(xy 43.327268 -274.482364) (xy 43.329938 -274.510732) (xy 43.330114 -274.524978) (xy 43.329646 -274.549801)
			(xy 43.321617 -274.598794) (xy 43.305768 -274.645842) (xy 43.282516 -274.689707) (xy 43.252474 -274.729232)
			(xy 43.216433 -274.763375) (xy 43.175343 -274.791238) (xy 43.130286 -274.812087) (xy 43.08245 -274.825371)
			(xy 43.033095 -274.83074) (xy 42.983522 -274.828055) (xy 42.935036 -274.817384) (xy 42.888915 -274.79901)
			(xy 42.846374 -274.773416) (xy 42.808535 -274.741276) (xy 42.776394 -274.703439) (xy 42.750797 -274.6609)
			(xy 42.732421 -274.61478) (xy 42.721747 -274.566294) (xy 42.719059 -274.516721) (xy 42.379988 -274.516721)
			(xy 42.380154 -274.524978) (xy 42.379659 -274.549585) (xy 42.371764 -274.598162) (xy 42.35618 -274.644843)
			(xy 42.333309 -274.68842) (xy 42.303744 -274.727764) (xy 42.268251 -274.761856) (xy 42.227748 -274.789812)
			(xy 42.183286 -274.81091) (xy 42.136015 -274.824602) (xy 42.08716 -274.830534) (xy 42.037985 -274.828553)
			(xy 41.989766 -274.818709) (xy 41.94375 -274.801257) (xy 41.901129 -274.77665) (xy 41.863008 -274.745525)
			(xy 41.830373 -274.708688) (xy 41.80407 -274.667092) (xy 41.784779 -274.621816) (xy 41.773002 -274.574032)
			(xy 41.769042 -274.524978) (xy 41.430194 -274.524978) (xy 41.429699 -274.549585) (xy 41.421804 -274.598162)
			(xy 41.40622 -274.644843) (xy 41.383349 -274.68842) (xy 41.353784 -274.727764) (xy 41.318291 -274.761856)
			(xy 41.277788 -274.789812) (xy 41.233326 -274.81091) (xy 41.186055 -274.824602) (xy 41.1372 -274.830534)
			(xy 41.088025 -274.828553) (xy 41.039806 -274.818709) (xy 40.99379 -274.801257) (xy 40.951169 -274.77665)
			(xy 40.913048 -274.745525) (xy 40.880413 -274.708688) (xy 40.85411 -274.667092) (xy 40.834819 -274.621816)
			(xy 40.823042 -274.574032) (xy 40.819082 -274.524978) (xy 40.480234 -274.524978) (xy 40.479739 -274.549585)
			(xy 40.471844 -274.598162) (xy 40.45626 -274.644843) (xy 40.433389 -274.68842) (xy 40.403824 -274.727764)
			(xy 40.368331 -274.761856) (xy 40.327828 -274.789812) (xy 40.283366 -274.81091) (xy 40.236095 -274.824602)
			(xy 40.18724 -274.830534) (xy 40.138065 -274.828553) (xy 40.089846 -274.818709) (xy 40.04383 -274.801257)
			(xy 40.001209 -274.77665) (xy 39.963088 -274.745525) (xy 39.930453 -274.708688) (xy 39.90415 -274.667092)
			(xy 39.884859 -274.621816) (xy 39.873082 -274.574032) (xy 39.869122 -274.524978) (xy 39.530274 -274.524978)
			(xy 39.529779 -274.549585) (xy 39.521884 -274.598162) (xy 39.5063 -274.644843) (xy 39.483429 -274.68842)
			(xy 39.453864 -274.727764) (xy 39.418371 -274.761856) (xy 39.377868 -274.789812) (xy 39.333406 -274.81091)
			(xy 39.286135 -274.824602) (xy 39.23728 -274.830534) (xy 39.188105 -274.828553) (xy 39.139886 -274.818709)
			(xy 39.09387 -274.801257) (xy 39.051249 -274.77665) (xy 39.013128 -274.745525) (xy 38.980493 -274.708688)
			(xy 38.95419 -274.667092) (xy 38.934899 -274.621816) (xy 38.923122 -274.574032) (xy 38.919162 -274.524978)
			(xy 38.580314 -274.524978) (xy 38.579819 -274.549585) (xy 38.571924 -274.598162) (xy 38.55634 -274.644843)
			(xy 38.533469 -274.68842) (xy 38.503904 -274.727764) (xy 38.468411 -274.761856) (xy 38.427908 -274.789812)
			(xy 38.383446 -274.81091) (xy 38.336175 -274.824602) (xy 38.28732 -274.830534) (xy 38.238145 -274.828553)
			(xy 38.189926 -274.818709) (xy 38.14391 -274.801257) (xy 38.101289 -274.77665) (xy 38.063168 -274.745525)
			(xy 38.030533 -274.708688) (xy 38.00423 -274.667092) (xy 37.984939 -274.621816) (xy 37.973162 -274.574032)
			(xy 37.969202 -274.524978) (xy 37.630095 -274.524978) (xy 37.629605 -274.549331) (xy 37.62171 -274.597908)
			(xy 37.606126 -274.644589) (xy 37.583255 -274.688166) (xy 37.55369 -274.72751) (xy 37.518197 -274.761602)
			(xy 37.477694 -274.789558) (xy 37.433232 -274.810656) (xy 37.385961 -274.824348) (xy 37.337106 -274.83028)
			(xy 37.287931 -274.828299) (xy 37.239712 -274.818455) (xy 37.193696 -274.801003) (xy 37.151075 -274.776396)
			(xy 37.112954 -274.745271) (xy 37.080319 -274.708434) (xy 37.054016 -274.666838) (xy 37.034725 -274.621562)
			(xy 37.022948 -274.573778) (xy 37.018988 -274.524724) (xy 32.719591 -274.524724) (xy 32.666072 -274.570577)
			(xy 32.512829 -274.69132) (xy 32.354758 -274.80567) (xy 32.192125 -274.913435) (xy 32.049126 -274.999958)
			(xy 44.143942 -274.999958) (xy 44.147902 -274.950904) (xy 44.159679 -274.90312) (xy 44.17897 -274.857844)
			(xy 44.205273 -274.816248) (xy 44.237908 -274.779411) (xy 44.276029 -274.748286) (xy 44.31865 -274.723679)
			(xy 44.364666 -274.706227) (xy 44.412885 -274.696383) (xy 44.46206 -274.694402) (xy 44.510915 -274.700334)
			(xy 44.558186 -274.714026) (xy 44.602648 -274.735124) (xy 44.643151 -274.76308) (xy 44.678644 -274.797172)
			(xy 44.708209 -274.836516) (xy 44.73108 -274.880093) (xy 44.746664 -274.926774) (xy 44.754559 -274.975351)
			(xy 44.755054 -274.999958) (xy 44.754559 -275.024565) (xy 44.75438 -275.025666) (xy 45.073312 -275.025666)
			(xy 45.073312 -274.97425) (xy 45.081355 -274.923468) (xy 45.097243 -274.874569) (xy 45.120586 -274.828757)
			(xy 45.150807 -274.787161) (xy 45.187163 -274.750805) (xy 45.228759 -274.720584) (xy 45.274571 -274.697241)
			(xy 45.32347 -274.681353) (xy 45.374252 -274.67331) (xy 45.425668 -274.67331) (xy 45.47645 -274.681353)
			(xy 45.525349 -274.697241) (xy 45.571161 -274.720584) (xy 45.612757 -274.750805) (xy 45.649113 -274.787161)
			(xy 45.679334 -274.828757) (xy 45.702677 -274.874569) (xy 45.718565 -274.923468) (xy 45.726608 -274.97425)
			(xy 45.727112 -274.999958) (xy 46.044116 -274.999958) (xy 46.048076 -274.950904) (xy 46.059853 -274.90312)
			(xy 46.079144 -274.857844) (xy 46.105447 -274.816248) (xy 46.138082 -274.779411) (xy 46.176203 -274.748286)
			(xy 46.218824 -274.723679) (xy 46.26484 -274.706227) (xy 46.313059 -274.696383) (xy 46.362234 -274.694402)
			(xy 46.411089 -274.700334) (xy 46.45836 -274.714026) (xy 46.502822 -274.735124) (xy 46.543325 -274.76308)
			(xy 46.578818 -274.797172) (xy 46.608383 -274.836516) (xy 46.631254 -274.880093) (xy 46.646838 -274.926774)
			(xy 46.654733 -274.975351) (xy 46.655228 -274.999958) (xy 46.654733 -275.024565) (xy 46.654554 -275.025666)
			(xy 46.973232 -275.025666) (xy 46.973232 -274.97425) (xy 46.981275 -274.923468) (xy 46.997163 -274.874569)
			(xy 47.020506 -274.828757) (xy 47.050727 -274.787161) (xy 47.087083 -274.750805) (xy 47.128679 -274.720584)
			(xy 47.174491 -274.697241) (xy 47.22339 -274.681353) (xy 47.274172 -274.67331) (xy 47.325588 -274.67331)
			(xy 47.37637 -274.681353) (xy 47.425269 -274.697241) (xy 47.471081 -274.720584) (xy 47.512677 -274.750805)
			(xy 47.549033 -274.787161) (xy 47.579254 -274.828757) (xy 47.602597 -274.874569) (xy 47.618485 -274.923468)
			(xy 47.626528 -274.97425) (xy 47.627032 -274.999958) (xy 47.944036 -274.999958) (xy 47.947996 -274.950904)
			(xy 47.959773 -274.90312) (xy 47.979064 -274.857844) (xy 48.005367 -274.816248) (xy 48.038002 -274.779411)
			(xy 48.076123 -274.748286) (xy 48.118744 -274.723679) (xy 48.16476 -274.706227) (xy 48.212979 -274.696383)
			(xy 48.262154 -274.694402) (xy 48.311009 -274.700334) (xy 48.35828 -274.714026) (xy 48.402742 -274.735124)
			(xy 48.443245 -274.76308) (xy 48.478738 -274.797172) (xy 48.508303 -274.836516) (xy 48.531174 -274.880093)
			(xy 48.546758 -274.926774) (xy 48.554653 -274.975351) (xy 48.555148 -274.999958) (xy 48.554653 -275.024565)
			(xy 48.554474 -275.025666) (xy 48.873152 -275.025666) (xy 48.873152 -274.97425) (xy 48.881195 -274.923468)
			(xy 48.897083 -274.874569) (xy 48.920426 -274.828757) (xy 48.950647 -274.787161) (xy 48.987003 -274.750805)
			(xy 49.028599 -274.720584) (xy 49.074411 -274.697241) (xy 49.12331 -274.681353) (xy 49.174092 -274.67331)
			(xy 49.225508 -274.67331) (xy 49.27629 -274.681353) (xy 49.325189 -274.697241) (xy 49.371001 -274.720584)
			(xy 49.412597 -274.750805) (xy 49.448953 -274.787161) (xy 49.479174 -274.828757) (xy 49.502517 -274.874569)
			(xy 49.518405 -274.923468) (xy 49.526448 -274.97425) (xy 49.526952 -274.999958) (xy 49.843956 -274.999958)
			(xy 49.847916 -274.950904) (xy 49.859693 -274.90312) (xy 49.878984 -274.857844) (xy 49.905287 -274.816248)
			(xy 49.937922 -274.779411) (xy 49.976043 -274.748286) (xy 50.018664 -274.723679) (xy 50.06468 -274.706227)
			(xy 50.112899 -274.696383) (xy 50.162074 -274.694402) (xy 50.210929 -274.700334) (xy 50.2582 -274.714026)
			(xy 50.302662 -274.735124) (xy 50.343165 -274.76308) (xy 50.378658 -274.797172) (xy 50.408223 -274.836516)
			(xy 50.431094 -274.880093) (xy 50.446678 -274.926774) (xy 50.454573 -274.975351) (xy 50.455068 -274.999958)
			(xy 50.454573 -275.024565) (xy 50.454394 -275.025666) (xy 50.773326 -275.025666) (xy 50.773326 -274.97425)
			(xy 50.781369 -274.923468) (xy 50.797257 -274.874569) (xy 50.8206 -274.828757) (xy 50.850821 -274.787161)
			(xy 50.887177 -274.750805) (xy 50.928773 -274.720584) (xy 50.974585 -274.697241) (xy 51.023484 -274.681353)
			(xy 51.074266 -274.67331) (xy 51.125682 -274.67331) (xy 51.176464 -274.681353) (xy 51.225363 -274.697241)
			(xy 51.271175 -274.720584) (xy 51.312771 -274.750805) (xy 51.349127 -274.787161) (xy 51.379348 -274.828757)
			(xy 51.402691 -274.874569) (xy 51.418579 -274.923468) (xy 51.426622 -274.97425) (xy 51.427126 -274.999958)
			(xy 51.74413 -274.999958) (xy 51.74809 -274.950904) (xy 51.759867 -274.90312) (xy 51.779158 -274.857844)
			(xy 51.805461 -274.816248) (xy 51.838096 -274.779411) (xy 51.876217 -274.748286) (xy 51.918838 -274.723679)
			(xy 51.964854 -274.706227) (xy 52.013073 -274.696383) (xy 52.062248 -274.694402) (xy 52.111103 -274.700334)
			(xy 52.158374 -274.714026) (xy 52.202836 -274.735124) (xy 52.243339 -274.76308) (xy 52.278832 -274.797172)
			(xy 52.308397 -274.836516) (xy 52.331268 -274.880093) (xy 52.346852 -274.926774) (xy 52.354747 -274.975351)
			(xy 52.355242 -274.999958) (xy 52.354747 -275.024565) (xy 52.354568 -275.025666) (xy 52.673246 -275.025666)
			(xy 52.673246 -274.97425) (xy 52.681289 -274.923468) (xy 52.697177 -274.874569) (xy 52.72052 -274.828757)
			(xy 52.750741 -274.787161) (xy 52.787097 -274.750805) (xy 52.828693 -274.720584) (xy 52.874505 -274.697241)
			(xy 52.923404 -274.681353) (xy 52.974186 -274.67331) (xy 53.025602 -274.67331) (xy 53.076384 -274.681353)
			(xy 53.125283 -274.697241) (xy 53.171095 -274.720584) (xy 53.212691 -274.750805) (xy 53.249047 -274.787161)
			(xy 53.279268 -274.828757) (xy 53.302611 -274.874569) (xy 53.318499 -274.923468) (xy 53.326542 -274.97425)
			(xy 53.327046 -274.999958) (xy 53.64405 -274.999958) (xy 53.64801 -274.950904) (xy 53.659787 -274.90312)
			(xy 53.679078 -274.857844) (xy 53.705381 -274.816248) (xy 53.738016 -274.779411) (xy 53.776137 -274.748286)
			(xy 53.818758 -274.723679) (xy 53.864774 -274.706227) (xy 53.912993 -274.696383) (xy 53.962168 -274.694402)
			(xy 54.011023 -274.700334) (xy 54.058294 -274.714026) (xy 54.102756 -274.735124) (xy 54.143259 -274.76308)
			(xy 54.178752 -274.797172) (xy 54.208317 -274.836516) (xy 54.231188 -274.880093) (xy 54.246772 -274.926774)
			(xy 54.254667 -274.975351) (xy 54.255162 -274.999958) (xy 54.254667 -275.024565) (xy 54.254488 -275.025666)
			(xy 54.573166 -275.025666) (xy 54.573166 -274.97425) (xy 54.581209 -274.923468) (xy 54.597097 -274.874569)
			(xy 54.62044 -274.828757) (xy 54.650661 -274.787161) (xy 54.687017 -274.750805) (xy 54.728613 -274.720584)
			(xy 54.774425 -274.697241) (xy 54.823324 -274.681353) (xy 54.874106 -274.67331) (xy 54.925522 -274.67331)
			(xy 54.976304 -274.681353) (xy 55.025203 -274.697241) (xy 55.071015 -274.720584) (xy 55.112611 -274.750805)
			(xy 55.148967 -274.787161) (xy 55.179188 -274.828757) (xy 55.202531 -274.874569) (xy 55.218419 -274.923468)
			(xy 55.226462 -274.97425) (xy 55.226966 -274.999958) (xy 55.54397 -274.999958) (xy 55.54793 -274.950904)
			(xy 55.559707 -274.90312) (xy 55.578998 -274.857844) (xy 55.605301 -274.816248) (xy 55.637936 -274.779411)
			(xy 55.676057 -274.748286) (xy 55.718678 -274.723679) (xy 55.764694 -274.706227) (xy 55.812913 -274.696383)
			(xy 55.862088 -274.694402) (xy 55.910943 -274.700334) (xy 55.958214 -274.714026) (xy 56.002676 -274.735124)
			(xy 56.043179 -274.76308) (xy 56.078672 -274.797172) (xy 56.108237 -274.836516) (xy 56.131108 -274.880093)
			(xy 56.146692 -274.926774) (xy 56.154587 -274.975351) (xy 56.155082 -274.999958) (xy 56.154587 -275.024565)
			(xy 56.154408 -275.025666) (xy 56.47334 -275.025666) (xy 56.47334 -274.97425) (xy 56.481383 -274.923468)
			(xy 56.497271 -274.874569) (xy 56.520614 -274.828757) (xy 56.550835 -274.787161) (xy 56.587191 -274.750805)
			(xy 56.628787 -274.720584) (xy 56.674599 -274.697241) (xy 56.723498 -274.681353) (xy 56.77428 -274.67331)
			(xy 56.825696 -274.67331) (xy 56.876478 -274.681353) (xy 56.925377 -274.697241) (xy 56.971189 -274.720584)
			(xy 57.012785 -274.750805) (xy 57.049141 -274.787161) (xy 57.079362 -274.828757) (xy 57.102705 -274.874569)
			(xy 57.118593 -274.923468) (xy 57.126636 -274.97425) (xy 57.12714 -274.999958) (xy 57.126636 -275.025666)
			(xy 57.118593 -275.076448) (xy 57.102705 -275.125347) (xy 57.079362 -275.171159) (xy 57.049141 -275.212755)
			(xy 57.012785 -275.249111) (xy 56.971189 -275.279332) (xy 56.925377 -275.302675) (xy 56.876478 -275.318563)
			(xy 56.825696 -275.326606) (xy 56.77428 -275.326606) (xy 56.723498 -275.318563) (xy 56.674599 -275.302675)
			(xy 56.628787 -275.279332) (xy 56.587191 -275.249111) (xy 56.550835 -275.212755) (xy 56.520614 -275.171159)
			(xy 56.497271 -275.125347) (xy 56.481383 -275.076448) (xy 56.47334 -275.025666) (xy 56.154408 -275.025666)
			(xy 56.146692 -275.073142) (xy 56.131108 -275.119823) (xy 56.108237 -275.1634) (xy 56.078672 -275.202744)
			(xy 56.043179 -275.236836) (xy 56.002676 -275.264792) (xy 55.958214 -275.28589) (xy 55.910943 -275.299582)
			(xy 55.862088 -275.305514) (xy 55.812913 -275.303533) (xy 55.764694 -275.293689) (xy 55.718678 -275.276237)
			(xy 55.676057 -275.25163) (xy 55.637936 -275.220505) (xy 55.605301 -275.183668) (xy 55.578998 -275.142072)
			(xy 55.559707 -275.096796) (xy 55.54793 -275.049012) (xy 55.54397 -274.999958) (xy 55.226966 -274.999958)
			(xy 55.226462 -275.025666) (xy 55.218419 -275.076448) (xy 55.202531 -275.125347) (xy 55.179188 -275.171159)
			(xy 55.148967 -275.212755) (xy 55.112611 -275.249111) (xy 55.071015 -275.279332) (xy 55.025203 -275.302675)
			(xy 54.976304 -275.318563) (xy 54.925522 -275.326606) (xy 54.874106 -275.326606) (xy 54.823324 -275.318563)
			(xy 54.774425 -275.302675) (xy 54.728613 -275.279332) (xy 54.687017 -275.249111) (xy 54.650661 -275.212755)
			(xy 54.62044 -275.171159) (xy 54.597097 -275.125347) (xy 54.581209 -275.076448) (xy 54.573166 -275.025666)
			(xy 54.254488 -275.025666) (xy 54.246772 -275.073142) (xy 54.231188 -275.119823) (xy 54.208317 -275.1634)
			(xy 54.178752 -275.202744) (xy 54.143259 -275.236836) (xy 54.102756 -275.264792) (xy 54.058294 -275.28589)
			(xy 54.011023 -275.299582) (xy 53.962168 -275.305514) (xy 53.912993 -275.303533) (xy 53.864774 -275.293689)
			(xy 53.818758 -275.276237) (xy 53.776137 -275.25163) (xy 53.738016 -275.220505) (xy 53.705381 -275.183668)
			(xy 53.679078 -275.142072) (xy 53.659787 -275.096796) (xy 53.64801 -275.049012) (xy 53.64405 -274.999958)
			(xy 53.327046 -274.999958) (xy 53.326542 -275.025666) (xy 53.318499 -275.076448) (xy 53.302611 -275.125347)
			(xy 53.279268 -275.171159) (xy 53.249047 -275.212755) (xy 53.212691 -275.249111) (xy 53.171095 -275.279332)
			(xy 53.125283 -275.302675) (xy 53.076384 -275.318563) (xy 53.025602 -275.326606) (xy 52.974186 -275.326606)
			(xy 52.923404 -275.318563) (xy 52.874505 -275.302675) (xy 52.828693 -275.279332) (xy 52.787097 -275.249111)
			(xy 52.750741 -275.212755) (xy 52.72052 -275.171159) (xy 52.697177 -275.125347) (xy 52.681289 -275.076448)
			(xy 52.673246 -275.025666) (xy 52.354568 -275.025666) (xy 52.346852 -275.073142) (xy 52.331268 -275.119823)
			(xy 52.308397 -275.1634) (xy 52.278832 -275.202744) (xy 52.243339 -275.236836) (xy 52.202836 -275.264792)
			(xy 52.158374 -275.28589) (xy 52.111103 -275.299582) (xy 52.062248 -275.305514) (xy 52.013073 -275.303533)
			(xy 51.964854 -275.293689) (xy 51.918838 -275.276237) (xy 51.876217 -275.25163) (xy 51.838096 -275.220505)
			(xy 51.805461 -275.183668) (xy 51.779158 -275.142072) (xy 51.759867 -275.096796) (xy 51.74809 -275.049012)
			(xy 51.74413 -274.999958) (xy 51.427126 -274.999958) (xy 51.426622 -275.025666) (xy 51.418579 -275.076448)
			(xy 51.402691 -275.125347) (xy 51.379348 -275.171159) (xy 51.349127 -275.212755) (xy 51.312771 -275.249111)
			(xy 51.271175 -275.279332) (xy 51.225363 -275.302675) (xy 51.176464 -275.318563) (xy 51.125682 -275.326606)
			(xy 51.074266 -275.326606) (xy 51.023484 -275.318563) (xy 50.974585 -275.302675) (xy 50.928773 -275.279332)
			(xy 50.887177 -275.249111) (xy 50.850821 -275.212755) (xy 50.8206 -275.171159) (xy 50.797257 -275.125347)
			(xy 50.781369 -275.076448) (xy 50.773326 -275.025666) (xy 50.454394 -275.025666) (xy 50.446678 -275.073142)
			(xy 50.431094 -275.119823) (xy 50.408223 -275.1634) (xy 50.378658 -275.202744) (xy 50.343165 -275.236836)
			(xy 50.302662 -275.264792) (xy 50.2582 -275.28589) (xy 50.210929 -275.299582) (xy 50.162074 -275.305514)
			(xy 50.112899 -275.303533) (xy 50.06468 -275.293689) (xy 50.018664 -275.276237) (xy 49.976043 -275.25163)
			(xy 49.937922 -275.220505) (xy 49.905287 -275.183668) (xy 49.878984 -275.142072) (xy 49.859693 -275.096796)
			(xy 49.847916 -275.049012) (xy 49.843956 -274.999958) (xy 49.526952 -274.999958) (xy 49.526448 -275.025666)
			(xy 49.518405 -275.076448) (xy 49.502517 -275.125347) (xy 49.479174 -275.171159) (xy 49.448953 -275.212755)
			(xy 49.412597 -275.249111) (xy 49.371001 -275.279332) (xy 49.325189 -275.302675) (xy 49.27629 -275.318563)
			(xy 49.225508 -275.326606) (xy 49.174092 -275.326606) (xy 49.12331 -275.318563) (xy 49.074411 -275.302675)
			(xy 49.028599 -275.279332) (xy 48.987003 -275.249111) (xy 48.950647 -275.212755) (xy 48.920426 -275.171159)
			(xy 48.897083 -275.125347) (xy 48.881195 -275.076448) (xy 48.873152 -275.025666) (xy 48.554474 -275.025666)
			(xy 48.546758 -275.073142) (xy 48.531174 -275.119823) (xy 48.508303 -275.1634) (xy 48.478738 -275.202744)
			(xy 48.443245 -275.236836) (xy 48.402742 -275.264792) (xy 48.35828 -275.28589) (xy 48.311009 -275.299582)
			(xy 48.262154 -275.305514) (xy 48.212979 -275.303533) (xy 48.16476 -275.293689) (xy 48.118744 -275.276237)
			(xy 48.076123 -275.25163) (xy 48.038002 -275.220505) (xy 48.005367 -275.183668) (xy 47.979064 -275.142072)
			(xy 47.959773 -275.096796) (xy 47.947996 -275.049012) (xy 47.944036 -274.999958) (xy 47.627032 -274.999958)
			(xy 47.626528 -275.025666) (xy 47.618485 -275.076448) (xy 47.602597 -275.125347) (xy 47.579254 -275.171159)
			(xy 47.549033 -275.212755) (xy 47.512677 -275.249111) (xy 47.471081 -275.279332) (xy 47.425269 -275.302675)
			(xy 47.37637 -275.318563) (xy 47.325588 -275.326606) (xy 47.274172 -275.326606) (xy 47.22339 -275.318563)
			(xy 47.174491 -275.302675) (xy 47.128679 -275.279332) (xy 47.087083 -275.249111) (xy 47.050727 -275.212755)
			(xy 47.020506 -275.171159) (xy 46.997163 -275.125347) (xy 46.981275 -275.076448) (xy 46.973232 -275.025666)
			(xy 46.654554 -275.025666) (xy 46.646838 -275.073142) (xy 46.631254 -275.119823) (xy 46.608383 -275.1634)
			(xy 46.578818 -275.202744) (xy 46.543325 -275.236836) (xy 46.502822 -275.264792) (xy 46.45836 -275.28589)
			(xy 46.411089 -275.299582) (xy 46.362234 -275.305514) (xy 46.313059 -275.303533) (xy 46.26484 -275.293689)
			(xy 46.218824 -275.276237) (xy 46.176203 -275.25163) (xy 46.138082 -275.220505) (xy 46.105447 -275.183668)
			(xy 46.079144 -275.142072) (xy 46.059853 -275.096796) (xy 46.048076 -275.049012) (xy 46.044116 -274.999958)
			(xy 45.727112 -274.999958) (xy 45.726608 -275.025666) (xy 45.718565 -275.076448) (xy 45.702677 -275.125347)
			(xy 45.679334 -275.171159) (xy 45.649113 -275.212755) (xy 45.612757 -275.249111) (xy 45.571161 -275.279332)
			(xy 45.525349 -275.302675) (xy 45.47645 -275.318563) (xy 45.425668 -275.326606) (xy 45.374252 -275.326606)
			(xy 45.32347 -275.318563) (xy 45.274571 -275.302675) (xy 45.228759 -275.279332) (xy 45.187163 -275.249111)
			(xy 45.150807 -275.212755) (xy 45.120586 -275.171159) (xy 45.097243 -275.125347) (xy 45.081355 -275.076448)
			(xy 45.073312 -275.025666) (xy 44.75438 -275.025666) (xy 44.746664 -275.073142) (xy 44.73108 -275.119823)
			(xy 44.708209 -275.1634) (xy 44.678644 -275.202744) (xy 44.643151 -275.236836) (xy 44.602648 -275.264792)
			(xy 44.558186 -275.28589) (xy 44.510915 -275.299582) (xy 44.46206 -275.305514) (xy 44.412885 -275.303533)
			(xy 44.364666 -275.293689) (xy 44.31865 -275.276237) (xy 44.276029 -275.25163) (xy 44.237908 -275.220505)
			(xy 44.205273 -275.183668) (xy 44.17897 -275.142072) (xy 44.159679 -275.096796) (xy 44.147902 -275.049012)
			(xy 44.143942 -274.999958) (xy 32.049126 -274.999958) (xy 32.025206 -275.014431) (xy 31.85428 -275.10849)
			(xy 31.679637 -275.195452) (xy 31.501571 -275.27517) (xy 31.320383 -275.347511) (xy 31.136377 -275.412352)
			(xy 30.949864 -275.469584) (xy 30.929464 -275.474938) (xy 36.069028 -275.474938) (xy 36.072988 -275.425884)
			(xy 36.084765 -275.3781) (xy 36.104056 -275.332824) (xy 36.130359 -275.291228) (xy 36.162994 -275.254391)
			(xy 36.201115 -275.223266) (xy 36.243736 -275.198659) (xy 36.289752 -275.181207) (xy 36.337971 -275.171363)
			(xy 36.387146 -275.169382) (xy 36.436001 -275.175314) (xy 36.483272 -275.189006) (xy 36.527734 -275.210104)
			(xy 36.568237 -275.23806) (xy 36.60373 -275.272152) (xy 36.633295 -275.311496) (xy 36.656166 -275.355073)
			(xy 36.67175 -275.401754) (xy 36.679645 -275.450331) (xy 36.68014 -275.474938) (xy 37.018988 -275.474938)
			(xy 37.022948 -275.425884) (xy 37.034725 -275.3781) (xy 37.054016 -275.332824) (xy 37.080319 -275.291228)
			(xy 37.112954 -275.254391) (xy 37.151075 -275.223266) (xy 37.193696 -275.198659) (xy 37.239712 -275.181207)
			(xy 37.287931 -275.171363) (xy 37.337106 -275.169382) (xy 37.385961 -275.175314) (xy 37.433232 -275.189006)
			(xy 37.477694 -275.210104) (xy 37.518197 -275.23806) (xy 37.55369 -275.272152) (xy 37.583255 -275.311496)
			(xy 37.606126 -275.355073) (xy 37.62171 -275.401754) (xy 37.629605 -275.450331) (xy 37.6301 -275.474938)
			(xy 37.969202 -275.474938) (xy 37.973162 -275.425884) (xy 37.984939 -275.3781) (xy 38.00423 -275.332824)
			(xy 38.030533 -275.291228) (xy 38.063168 -275.254391) (xy 38.101289 -275.223266) (xy 38.14391 -275.198659)
			(xy 38.189926 -275.181207) (xy 38.238145 -275.171363) (xy 38.28732 -275.169382) (xy 38.336175 -275.175314)
			(xy 38.383446 -275.189006) (xy 38.427908 -275.210104) (xy 38.468411 -275.23806) (xy 38.503904 -275.272152)
			(xy 38.533469 -275.311496) (xy 38.55634 -275.355073) (xy 38.571924 -275.401754) (xy 38.579819 -275.450331)
			(xy 38.580314 -275.474938) (xy 38.919162 -275.474938) (xy 38.923122 -275.425884) (xy 38.934899 -275.3781)
			(xy 38.95419 -275.332824) (xy 38.980493 -275.291228) (xy 39.013128 -275.254391) (xy 39.051249 -275.223266)
			(xy 39.09387 -275.198659) (xy 39.139886 -275.181207) (xy 39.188105 -275.171363) (xy 39.23728 -275.169382)
			(xy 39.286135 -275.175314) (xy 39.333406 -275.189006) (xy 39.377868 -275.210104) (xy 39.418371 -275.23806)
			(xy 39.453864 -275.272152) (xy 39.483429 -275.311496) (xy 39.5063 -275.355073) (xy 39.521884 -275.401754)
			(xy 39.529779 -275.450331) (xy 39.530274 -275.474938) (xy 39.869122 -275.474938) (xy 39.873082 -275.425884)
			(xy 39.884859 -275.3781) (xy 39.90415 -275.332824) (xy 39.930453 -275.291228) (xy 39.963088 -275.254391)
			(xy 40.001209 -275.223266) (xy 40.04383 -275.198659) (xy 40.089846 -275.181207) (xy 40.138065 -275.171363)
			(xy 40.18724 -275.169382) (xy 40.236095 -275.175314) (xy 40.283366 -275.189006) (xy 40.327828 -275.210104)
			(xy 40.368331 -275.23806) (xy 40.403824 -275.272152) (xy 40.433389 -275.311496) (xy 40.45626 -275.355073)
			(xy 40.471844 -275.401754) (xy 40.479739 -275.450331) (xy 40.480234 -275.474938) (xy 40.819082 -275.474938)
			(xy 40.823042 -275.425884) (xy 40.834819 -275.3781) (xy 40.85411 -275.332824) (xy 40.880413 -275.291228)
			(xy 40.913048 -275.254391) (xy 40.951169 -275.223266) (xy 40.99379 -275.198659) (xy 41.039806 -275.181207)
			(xy 41.088025 -275.171363) (xy 41.1372 -275.169382) (xy 41.186055 -275.175314) (xy 41.233326 -275.189006)
			(xy 41.277788 -275.210104) (xy 41.318291 -275.23806) (xy 41.353784 -275.272152) (xy 41.383349 -275.311496)
			(xy 41.40622 -275.355073) (xy 41.421804 -275.401754) (xy 41.429699 -275.450331) (xy 41.430194 -275.474938)
			(xy 41.769042 -275.474938) (xy 41.773002 -275.425884) (xy 41.784779 -275.3781) (xy 41.80407 -275.332824)
			(xy 41.830373 -275.291228) (xy 41.863008 -275.254391) (xy 41.901129 -275.223266) (xy 41.94375 -275.198659)
			(xy 41.989766 -275.181207) (xy 42.037985 -275.171363) (xy 42.08716 -275.169382) (xy 42.136015 -275.175314)
			(xy 42.183286 -275.189006) (xy 42.227748 -275.210104) (xy 42.268251 -275.23806) (xy 42.303744 -275.272152)
			(xy 42.333309 -275.311496) (xy 42.35618 -275.355073) (xy 42.371764 -275.401754) (xy 42.379659 -275.450331)
			(xy 42.380154 -275.474938) (xy 42.719002 -275.474938) (xy 42.722962 -275.425884) (xy 42.734739 -275.3781)
			(xy 42.75403 -275.332824) (xy 42.780333 -275.291228) (xy 42.812968 -275.254391) (xy 42.851089 -275.223266)
			(xy 42.89371 -275.198659) (xy 42.939726 -275.181207) (xy 42.987945 -275.171363) (xy 43.03712 -275.169382)
			(xy 43.085975 -275.175314) (xy 43.133246 -275.189006) (xy 43.177708 -275.210104) (xy 43.218211 -275.23806)
			(xy 43.253704 -275.272152) (xy 43.283269 -275.311496) (xy 43.30614 -275.355073) (xy 43.321724 -275.401754)
			(xy 43.329619 -275.450331) (xy 43.330114 -275.474938) (xy 43.329619 -275.499545) (xy 43.321724 -275.548122)
			(xy 43.30614 -275.594803) (xy 43.283269 -275.63838) (xy 43.253704 -275.677724) (xy 43.218211 -275.711816)
			(xy 43.177708 -275.739772) (xy 43.133246 -275.76087) (xy 43.085975 -275.774562) (xy 43.03712 -275.780494)
			(xy 42.987945 -275.778513) (xy 42.939726 -275.768669) (xy 42.89371 -275.751217) (xy 42.851089 -275.72661)
			(xy 42.812968 -275.695485) (xy 42.780333 -275.658648) (xy 42.75403 -275.617052) (xy 42.734739 -275.571776)
			(xy 42.722962 -275.523992) (xy 42.719002 -275.474938) (xy 42.380154 -275.474938) (xy 42.379659 -275.499545)
			(xy 42.371764 -275.548122) (xy 42.35618 -275.594803) (xy 42.333309 -275.63838) (xy 42.303744 -275.677724)
			(xy 42.268251 -275.711816) (xy 42.227748 -275.739772) (xy 42.183286 -275.76087) (xy 42.136015 -275.774562)
			(xy 42.08716 -275.780494) (xy 42.037985 -275.778513) (xy 41.989766 -275.768669) (xy 41.94375 -275.751217)
			(xy 41.901129 -275.72661) (xy 41.863008 -275.695485) (xy 41.830373 -275.658648) (xy 41.80407 -275.617052)
			(xy 41.784779 -275.571776) (xy 41.773002 -275.523992) (xy 41.769042 -275.474938) (xy 41.430194 -275.474938)
			(xy 41.429699 -275.499545) (xy 41.421804 -275.548122) (xy 41.40622 -275.594803) (xy 41.383349 -275.63838)
			(xy 41.353784 -275.677724) (xy 41.318291 -275.711816) (xy 41.277788 -275.739772) (xy 41.233326 -275.76087)
			(xy 41.186055 -275.774562) (xy 41.1372 -275.780494) (xy 41.088025 -275.778513) (xy 41.039806 -275.768669)
			(xy 40.99379 -275.751217) (xy 40.951169 -275.72661) (xy 40.913048 -275.695485) (xy 40.880413 -275.658648)
			(xy 40.85411 -275.617052) (xy 40.834819 -275.571776) (xy 40.823042 -275.523992) (xy 40.819082 -275.474938)
			(xy 40.480234 -275.474938) (xy 40.479739 -275.499545) (xy 40.471844 -275.548122) (xy 40.45626 -275.594803)
			(xy 40.433389 -275.63838) (xy 40.403824 -275.677724) (xy 40.368331 -275.711816) (xy 40.327828 -275.739772)
			(xy 40.283366 -275.76087) (xy 40.236095 -275.774562) (xy 40.18724 -275.780494) (xy 40.138065 -275.778513)
			(xy 40.089846 -275.768669) (xy 40.04383 -275.751217) (xy 40.001209 -275.72661) (xy 39.963088 -275.695485)
			(xy 39.930453 -275.658648) (xy 39.90415 -275.617052) (xy 39.884859 -275.571776) (xy 39.873082 -275.523992)
			(xy 39.869122 -275.474938) (xy 39.530274 -275.474938) (xy 39.529779 -275.499545) (xy 39.521884 -275.548122)
			(xy 39.5063 -275.594803) (xy 39.483429 -275.63838) (xy 39.453864 -275.677724) (xy 39.418371 -275.711816)
			(xy 39.377868 -275.739772) (xy 39.333406 -275.76087) (xy 39.286135 -275.774562) (xy 39.23728 -275.780494)
			(xy 39.188105 -275.778513) (xy 39.139886 -275.768669) (xy 39.09387 -275.751217) (xy 39.051249 -275.72661)
			(xy 39.013128 -275.695485) (xy 38.980493 -275.658648) (xy 38.95419 -275.617052) (xy 38.934899 -275.571776)
			(xy 38.923122 -275.523992) (xy 38.919162 -275.474938) (xy 38.580314 -275.474938) (xy 38.579819 -275.499545)
			(xy 38.571924 -275.548122) (xy 38.55634 -275.594803) (xy 38.533469 -275.63838) (xy 38.503904 -275.677724)
			(xy 38.468411 -275.711816) (xy 38.427908 -275.739772) (xy 38.383446 -275.76087) (xy 38.336175 -275.774562)
			(xy 38.28732 -275.780494) (xy 38.238145 -275.778513) (xy 38.189926 -275.768669) (xy 38.14391 -275.751217)
			(xy 38.101289 -275.72661) (xy 38.063168 -275.695485) (xy 38.030533 -275.658648) (xy 38.00423 -275.617052)
			(xy 37.984939 -275.571776) (xy 37.973162 -275.523992) (xy 37.969202 -275.474938) (xy 37.6301 -275.474938)
			(xy 37.629605 -275.499545) (xy 37.62171 -275.548122) (xy 37.606126 -275.594803) (xy 37.583255 -275.63838)
			(xy 37.55369 -275.677724) (xy 37.518197 -275.711816) (xy 37.477694 -275.739772) (xy 37.433232 -275.76087)
			(xy 37.385961 -275.774562) (xy 37.337106 -275.780494) (xy 37.287931 -275.778513) (xy 37.239712 -275.768669)
			(xy 37.193696 -275.751217) (xy 37.151075 -275.72661) (xy 37.112954 -275.695485) (xy 37.080319 -275.658648)
			(xy 37.054016 -275.617052) (xy 37.034725 -275.571776) (xy 37.022948 -275.523992) (xy 37.018988 -275.474938)
			(xy 36.68014 -275.474938) (xy 36.679645 -275.499545) (xy 36.67175 -275.548122) (xy 36.656166 -275.594803)
			(xy 36.633295 -275.63838) (xy 36.60373 -275.677724) (xy 36.568237 -275.711816) (xy 36.527734 -275.739772)
			(xy 36.483272 -275.76087) (xy 36.436001 -275.774562) (xy 36.387146 -275.780494) (xy 36.337971 -275.778513)
			(xy 36.289752 -275.768669) (xy 36.243736 -275.751217) (xy 36.201115 -275.72661) (xy 36.162994 -275.695485)
			(xy 36.130359 -275.658648) (xy 36.104056 -275.617052) (xy 36.084765 -275.571776) (xy 36.072988 -275.523992)
			(xy 36.069028 -275.474938) (xy 30.929464 -275.474938) (xy 30.761159 -275.519111) (xy 30.57058 -275.560848)
			(xy 30.378447 -275.594726) (xy 30.185086 -275.620688) (xy 29.990822 -275.638689) (xy 29.795983 -275.6487)
			(xy 29.600897 -275.650703) (xy 29.405894 -275.644695) (xy 29.211301 -275.630686) (xy 29.017448 -275.6087)
			(xy 28.824661 -275.578774) (xy 28.633264 -275.540958) (xy 28.443582 -275.495316) (xy 28.255934 -275.441926)
			(xy 28.070635 -275.380876) (xy 27.888 -275.312271) (xy 27.708335 -275.236225) (xy 27.531943 -275.152867)
			(xy 27.359122 -275.062338) (xy 27.190164 -274.96479) (xy 27.025353 -274.860387) (xy 26.864967 -274.749307)
			(xy 26.709277 -274.631735) (xy 26.558545 -274.507871) (xy 26.413026 -274.377922) (xy 26.272964 -274.242109)
			(xy 26.138596 -274.10066) (xy 26.010149 -273.953814) (xy 25.887838 -273.801819) (xy 25.771871 -273.64493)
			(xy 25.662443 -273.483412) (xy 25.559738 -273.317538) (xy 25.46393 -273.147587) (xy 25.375179 -272.973846)
			(xy 25.293637 -272.796608) (xy 25.21944 -272.616172) (xy 25.152713 -272.432841) (xy 25.093569 -272.246926)
			(xy 25.042108 -272.058739) (xy 24.998416 -271.868599) (xy 24.962567 -271.676824) (xy 24.934622 -271.48374)
			(xy 24.914627 -271.289671) (xy 24.902617 -271.094945) (xy 24.898611 -270.89989) (xy 18.11018 -270.89989)
			(xy 18.121857 -270.909608) (xy 18.159074 -270.951145) (xy 18.189847 -270.997658) (xy 18.213519 -271.048155)
			(xy 18.229587 -271.101562) (xy 18.237707 -271.156738) (xy 18.238216 -271.184624) (xy 18.237707 -271.21251)
			(xy 18.229587 -271.267686) (xy 18.213519 -271.321093) (xy 18.189847 -271.37159) (xy 18.159074 -271.418103)
			(xy 18.121857 -271.45964) (xy 18.078989 -271.495315) (xy 18.031383 -271.524369) (xy 17.980054 -271.546181)
			(xy 17.926097 -271.560287) (xy 17.87066 -271.566387) (xy 17.814926 -271.56435) (xy 17.760083 -271.55422)
			(xy 17.707299 -271.536213) (xy 17.657699 -271.510712) (xy 17.612341 -271.478261) (xy 17.572192 -271.439552)
			(xy 17.538106 -271.395409) (xy 17.51081 -271.346774) (xy 17.490887 -271.294683) (xy 17.478761 -271.240246)
			(xy 17.47469 -271.184624) (xy 1.468374 -271.184624) (xy 1.468374 -271.45234) (xy 1.46882 -271.462127)
			(xy 1.476135 -271.480283) (xy 1.482598 -271.487646) (xy 1.538478 -271.545558) (xy 1.556004 -271.553686)
			(xy 1.566164 -271.55394) (xy 1.593974 -271.555521) (xy 1.648727 -271.565742) (xy 1.701413 -271.583815)
			(xy 1.750911 -271.609357) (xy 1.796169 -271.641825) (xy 1.836225 -271.680529) (xy 1.870228 -271.724646)
			(xy 1.897454 -271.773237) (xy 1.917326 -271.825272) (xy 1.929421 -271.879643) (xy 1.933481 -271.935194)
			(xy 1.929421 -271.990745) (xy 1.917326 -272.045116) (xy 1.897454 -272.097151) (xy 1.870228 -272.145742)
			(xy 1.836225 -272.189859) (xy 1.796169 -272.228563) (xy 1.750911 -272.261031) (xy 1.701413 -272.286573)
			(xy 1.648727 -272.304646) (xy 1.593974 -272.314867) (xy 1.566164 -272.316448) (xy 1.556004 -272.316702)
			(xy 1.538478 -272.32483) (xy 1.518136 -272.345912) (xy 11.635738 -272.345912) (xy 11.639809 -272.29029)
			(xy 11.651935 -272.235853) (xy 11.671858 -272.183762) (xy 11.699154 -272.135127) (xy 11.73324 -272.090984)
			(xy 11.773389 -272.052275) (xy 11.818747 -272.019824) (xy 11.868347 -271.994323) (xy 11.921131 -271.976316)
			(xy 11.975974 -271.966186) (xy 12.031708 -271.964149) (xy 12.087145 -271.970249) (xy 12.141102 -271.984355)
			(xy 12.192431 -272.006167) (xy 12.240037 -272.035221) (xy 12.282905 -272.070896) (xy 12.320122 -272.112433)
			(xy 12.350895 -272.158946) (xy 12.374567 -272.209443) (xy 12.390635 -272.26285) (xy 12.398755 -272.318026)
			(xy 12.399264 -272.345912) (xy 12.398755 -272.373798) (xy 12.390635 -272.428974) (xy 12.374894 -272.481294)
			(xy 13.765528 -272.481294) (xy 13.769599 -272.425672) (xy 13.781725 -272.371235) (xy 13.801648 -272.319144)
			(xy 13.828944 -272.270509) (xy 13.86303 -272.226366) (xy 13.903179 -272.187657) (xy 13.948537 -272.155206)
			(xy 13.998137 -272.129705) (xy 14.050921 -272.111698) (xy 14.105764 -272.101568) (xy 14.161498 -272.099531)
			(xy 14.216935 -272.105631) (xy 14.270892 -272.119737) (xy 14.322221 -272.141549) (xy 14.369827 -272.170603)
			(xy 14.405901 -272.200624) (xy 17.412968 -272.200624) (xy 17.417039 -272.145002) (xy 17.429165 -272.090565)
			(xy 17.449088 -272.038474) (xy 17.476384 -271.989839) (xy 17.51047 -271.945696) (xy 17.550619 -271.906987)
			(xy 17.595977 -271.874536) (xy 17.645577 -271.849035) (xy 17.698361 -271.831028) (xy 17.753204 -271.820898)
			(xy 17.808938 -271.818861) (xy 17.864375 -271.824961) (xy 17.918332 -271.839067) (xy 17.969661 -271.860879)
			(xy 18.017267 -271.889933) (xy 18.060135 -271.925608) (xy 18.097352 -271.967145) (xy 18.128125 -272.013658)
			(xy 18.151797 -272.064155) (xy 18.167865 -272.117562) (xy 18.175985 -272.172738) (xy 18.176494 -272.200624)
			(xy 18.175985 -272.22851) (xy 18.167865 -272.283686) (xy 18.151797 -272.337093) (xy 18.128125 -272.38759)
			(xy 18.097352 -272.434103) (xy 18.060135 -272.47564) (xy 18.017267 -272.511315) (xy 17.969661 -272.540369)
			(xy 17.918332 -272.562181) (xy 17.864375 -272.576287) (xy 17.808938 -272.582387) (xy 17.753204 -272.58035)
			(xy 17.698361 -272.57022) (xy 17.645577 -272.552213) (xy 17.595977 -272.526712) (xy 17.550619 -272.494261)
			(xy 17.51047 -272.455552) (xy 17.476384 -272.411409) (xy 17.449088 -272.362774) (xy 17.429165 -272.310683)
			(xy 17.417039 -272.256246) (xy 17.412968 -272.200624) (xy 14.405901 -272.200624) (xy 14.412695 -272.206278)
			(xy 14.449912 -272.247815) (xy 14.480685 -272.294328) (xy 14.504357 -272.344825) (xy 14.520425 -272.398232)
			(xy 14.528545 -272.453408) (xy 14.529054 -272.481294) (xy 14.528545 -272.50918) (xy 14.520425 -272.564356)
			(xy 14.504357 -272.617763) (xy 14.480685 -272.66826) (xy 14.449912 -272.714773) (xy 14.412695 -272.75631)
			(xy 14.369827 -272.791985) (xy 14.322221 -272.821039) (xy 14.270892 -272.842851) (xy 14.216935 -272.856957)
			(xy 14.161498 -272.863057) (xy 14.105764 -272.86102) (xy 14.050921 -272.85089) (xy 13.998137 -272.832883)
			(xy 13.948537 -272.807382) (xy 13.903179 -272.774931) (xy 13.86303 -272.736222) (xy 13.828944 -272.692079)
			(xy 13.801648 -272.643444) (xy 13.781725 -272.591353) (xy 13.769599 -272.536916) (xy 13.765528 -272.481294)
			(xy 12.374894 -272.481294) (xy 12.374567 -272.482381) (xy 12.350895 -272.532878) (xy 12.320122 -272.579391)
			(xy 12.282905 -272.620928) (xy 12.240037 -272.656603) (xy 12.192431 -272.685657) (xy 12.141102 -272.707469)
			(xy 12.087145 -272.721575) (xy 12.031708 -272.727675) (xy 11.975974 -272.725638) (xy 11.921131 -272.715508)
			(xy 11.868347 -272.697501) (xy 11.818747 -272.672) (xy 11.773389 -272.639549) (xy 11.73324 -272.60084)
			(xy 11.699154 -272.556697) (xy 11.671858 -272.508062) (xy 11.651935 -272.455971) (xy 11.639809 -272.401534)
			(xy 11.635738 -272.345912) (xy 1.518136 -272.345912) (xy 1.482598 -272.382742) (xy 1.476122 -272.390096)
			(xy 1.468814 -272.408258) (xy 1.468374 -272.418048) (xy 1.468374 -272.818606) (xy 1.468848 -272.828574)
			(xy 1.476418 -272.847016) (xy 1.483106 -272.85442) (xy 1.54051 -272.912332) (xy 1.554079 -272.918174)
			(xy 15.261334 -272.918174) (xy 15.265405 -272.862552) (xy 15.277531 -272.808115) (xy 15.297454 -272.756024)
			(xy 15.32475 -272.707389) (xy 15.358836 -272.663246) (xy 15.398985 -272.624537) (xy 15.444343 -272.592086)
			(xy 15.493943 -272.566585) (xy 15.546727 -272.548578) (xy 15.60157 -272.538448) (xy 15.657304 -272.536411)
			(xy 15.712741 -272.542511) (xy 15.766698 -272.556617) (xy 15.818027 -272.578429) (xy 15.865633 -272.607483)
			(xy 15.908501 -272.643158) (xy 15.945718 -272.684695) (xy 15.976491 -272.731208) (xy 16.000163 -272.781705)
			(xy 16.016231 -272.835112) (xy 16.024351 -272.890288) (xy 16.02486 -272.918174) (xy 16.024351 -272.94606)
			(xy 16.016231 -273.001236) (xy 16.000163 -273.054643) (xy 15.976491 -273.10514) (xy 15.945718 -273.151653)
			(xy 15.908501 -273.19319) (xy 15.880342 -273.216624) (xy 17.412968 -273.216624) (xy 17.417039 -273.161002)
			(xy 17.429165 -273.106565) (xy 17.449088 -273.054474) (xy 17.476384 -273.005839) (xy 17.51047 -272.961696)
			(xy 17.550619 -272.922987) (xy 17.595977 -272.890536) (xy 17.645577 -272.865035) (xy 17.698361 -272.847028)
			(xy 17.753204 -272.836898) (xy 17.808938 -272.834861) (xy 17.864375 -272.840961) (xy 17.918332 -272.855067)
			(xy 17.969661 -272.876879) (xy 18.017267 -272.905933) (xy 18.060135 -272.941608) (xy 18.097352 -272.983145)
			(xy 18.128125 -273.029658) (xy 18.151797 -273.080155) (xy 18.167865 -273.133562) (xy 18.175985 -273.188738)
			(xy 18.176494 -273.216624) (xy 18.175985 -273.24451) (xy 18.167865 -273.299686) (xy 18.151797 -273.353093)
			(xy 18.128125 -273.40359) (xy 18.097352 -273.450103) (xy 18.060135 -273.49164) (xy 18.017267 -273.527315)
			(xy 17.969661 -273.556369) (xy 17.918332 -273.578181) (xy 17.864375 -273.592287) (xy 17.808938 -273.598387)
			(xy 17.753204 -273.59635) (xy 17.698361 -273.58622) (xy 17.645577 -273.568213) (xy 17.595977 -273.542712)
			(xy 17.550619 -273.510261) (xy 17.51047 -273.471552) (xy 17.476384 -273.427409) (xy 17.449088 -273.378774)
			(xy 17.429165 -273.326683) (xy 17.417039 -273.272246) (xy 17.412968 -273.216624) (xy 15.880342 -273.216624)
			(xy 15.865633 -273.228865) (xy 15.818027 -273.257919) (xy 15.766698 -273.279731) (xy 15.712741 -273.293837)
			(xy 15.657304 -273.299937) (xy 15.60157 -273.2979) (xy 15.546727 -273.28777) (xy 15.493943 -273.269763)
			(xy 15.444343 -273.244262) (xy 15.398985 -273.211811) (xy 15.358836 -273.173102) (xy 15.32475 -273.128959)
			(xy 15.297454 -273.080324) (xy 15.277531 -273.028233) (xy 15.265405 -272.973796) (xy 15.261334 -272.918174)
			(xy 1.554079 -272.918174) (xy 1.558798 -272.920206) (xy 1.568958 -272.920206) (xy 1.59602 -272.920967)
			(xy 1.649528 -272.92919) (xy 1.701337 -272.944894) (xy 1.750406 -272.967764) (xy 1.795749 -272.997341)
			(xy 1.836456 -273.03303) (xy 1.871709 -273.074114) (xy 1.900801 -273.11977) (xy 1.923147 -273.16908)
			(xy 1.938298 -273.221053) (xy 1.945951 -273.274646) (xy 1.945951 -273.328782) (xy 1.938298 -273.382375)
			(xy 1.923147 -273.434348) (xy 1.900801 -273.483658) (xy 1.871709 -273.529314) (xy 1.836456 -273.570398)
			(xy 1.795749 -273.606087) (xy 1.750406 -273.635664) (xy 1.701337 -273.658534) (xy 1.649528 -273.674238)
			(xy 1.59602 -273.682461) (xy 1.568958 -273.683222) (xy 1.558798 -273.683222) (xy 1.54051 -273.691096)
			(xy 1.483106 -273.749008) (xy 1.476422 -273.756418) (xy 1.468842 -273.774854) (xy 1.468374 -273.784822)
			(xy 1.468374 -274.082256) (xy 10.07567 -274.082256) (xy 10.079741 -274.026634) (xy 10.091867 -273.972197)
			(xy 10.11179 -273.920106) (xy 10.139086 -273.871471) (xy 10.173172 -273.827328) (xy 10.213321 -273.788619)
			(xy 10.258679 -273.756168) (xy 10.308279 -273.730667) (xy 10.361063 -273.71266) (xy 10.415906 -273.70253)
			(xy 10.47164 -273.700493) (xy 10.527077 -273.706593) (xy 10.581034 -273.720699) (xy 10.632363 -273.742511)
			(xy 10.679969 -273.771565) (xy 10.722837 -273.80724) (xy 10.760054 -273.848777) (xy 10.790827 -273.89529)
			(xy 10.814499 -273.945787) (xy 10.830567 -273.999194) (xy 10.838687 -274.05437) (xy 10.839196 -274.082256)
			(xy 10.838687 -274.110142) (xy 10.830567 -274.165318) (xy 10.814499 -274.218725) (xy 10.807983 -274.232624)
			(xy 15.393668 -274.232624) (xy 15.397739 -274.177002) (xy 15.409865 -274.122565) (xy 15.429788 -274.070474)
			(xy 15.457084 -274.021839) (xy 15.49117 -273.977696) (xy 15.531319 -273.938987) (xy 15.576677 -273.906536)
			(xy 15.626277 -273.881035) (xy 15.679061 -273.863028) (xy 15.733904 -273.852898) (xy 15.789638 -273.850861)
			(xy 15.845075 -273.856961) (xy 15.899032 -273.871067) (xy 15.950361 -273.892879) (xy 15.997967 -273.921933)
			(xy 16.040835 -273.957608) (xy 16.078052 -273.999145) (xy 16.108825 -274.045658) (xy 16.132497 -274.096155)
			(xy 16.148565 -274.149562) (xy 16.156685 -274.204738) (xy 16.157194 -274.232624) (xy 17.412968 -274.232624)
			(xy 17.417039 -274.177002) (xy 17.429165 -274.122565) (xy 17.449088 -274.070474) (xy 17.476384 -274.021839)
			(xy 17.51047 -273.977696) (xy 17.550619 -273.938987) (xy 17.595977 -273.906536) (xy 17.645577 -273.881035)
			(xy 17.698361 -273.863028) (xy 17.753204 -273.852898) (xy 17.808938 -273.850861) (xy 17.864375 -273.856961)
			(xy 17.918332 -273.871067) (xy 17.969661 -273.892879) (xy 18.017267 -273.921933) (xy 18.060135 -273.957608)
			(xy 18.097352 -273.999145) (xy 18.128125 -274.045658) (xy 18.151797 -274.096155) (xy 18.167865 -274.149562)
			(xy 18.175985 -274.204738) (xy 18.176494 -274.232624) (xy 18.175985 -274.26051) (xy 18.167865 -274.315686)
			(xy 18.151797 -274.369093) (xy 18.128125 -274.41959) (xy 18.097352 -274.466103) (xy 18.060135 -274.50764)
			(xy 18.017267 -274.543315) (xy 17.969661 -274.572369) (xy 17.918332 -274.594181) (xy 17.864375 -274.608287)
			(xy 17.808938 -274.614387) (xy 17.753204 -274.61235) (xy 17.698361 -274.60222) (xy 17.645577 -274.584213)
			(xy 17.595977 -274.558712) (xy 17.550619 -274.526261) (xy 17.51047 -274.487552) (xy 17.476384 -274.443409)
			(xy 17.449088 -274.394774) (xy 17.429165 -274.342683) (xy 17.417039 -274.288246) (xy 17.412968 -274.232624)
			(xy 16.157194 -274.232624) (xy 16.156685 -274.26051) (xy 16.148565 -274.315686) (xy 16.132497 -274.369093)
			(xy 16.108825 -274.41959) (xy 16.078052 -274.466103) (xy 16.040835 -274.50764) (xy 15.997967 -274.543315)
			(xy 15.950361 -274.572369) (xy 15.899032 -274.594181) (xy 15.845075 -274.608287) (xy 15.789638 -274.614387)
			(xy 15.733904 -274.61235) (xy 15.679061 -274.60222) (xy 15.626277 -274.584213) (xy 15.576677 -274.558712)
			(xy 15.531319 -274.526261) (xy 15.49117 -274.487552) (xy 15.457084 -274.443409) (xy 15.429788 -274.394774)
			(xy 15.409865 -274.342683) (xy 15.397739 -274.288246) (xy 15.393668 -274.232624) (xy 10.807983 -274.232624)
			(xy 10.790827 -274.269222) (xy 10.760054 -274.315735) (xy 10.722837 -274.357272) (xy 10.679969 -274.392947)
			(xy 10.632363 -274.422001) (xy 10.581034 -274.443813) (xy 10.527077 -274.457919) (xy 10.47164 -274.464019)
			(xy 10.415906 -274.461982) (xy 10.361063 -274.451852) (xy 10.308279 -274.433845) (xy 10.258679 -274.408344)
			(xy 10.213321 -274.375893) (xy 10.173172 -274.337184) (xy 10.139086 -274.293041) (xy 10.11179 -274.244406)
			(xy 10.091867 -274.192315) (xy 10.079741 -274.137878) (xy 10.07567 -274.082256) (xy 1.468374 -274.082256)
			(xy 1.468374 -274.169378) (xy 1.468787 -274.178988) (xy 1.475832 -274.196871) (xy 1.48209 -274.204176)
			(xy 1.536192 -274.262088) (xy 1.55321 -274.270216) (xy 1.563116 -274.270724) (xy 1.590358 -274.273029)
			(xy 1.643821 -274.284451) (xy 1.695107 -274.303385) (xy 1.743166 -274.329444) (xy 1.787015 -274.362095)
			(xy 1.825756 -274.400669) (xy 1.858595 -274.444376) (xy 1.884861 -274.492323) (xy 1.904017 -274.543527)
			(xy 1.915669 -274.59694) (xy 1.91958 -274.65147) (xy 1.915669 -274.706) (xy 1.904017 -274.759413)
			(xy 1.884861 -274.810617) (xy 1.858595 -274.858564) (xy 1.825756 -274.902271) (xy 1.80137 -274.926552)
			(xy 12.410946 -274.926552) (xy 12.415017 -274.87093) (xy 12.427143 -274.816493) (xy 12.447066 -274.764402)
			(xy 12.474362 -274.715767) (xy 12.508448 -274.671624) (xy 12.548597 -274.632915) (xy 12.593955 -274.600464)
			(xy 12.643555 -274.574963) (xy 12.696339 -274.556956) (xy 12.751182 -274.546826) (xy 12.806916 -274.544789)
			(xy 12.862353 -274.550889) (xy 12.91631 -274.564995) (xy 12.967639 -274.586807) (xy 13.015245 -274.615861)
			(xy 13.058113 -274.651536) (xy 13.09533 -274.693073) (xy 13.126103 -274.739586) (xy 13.149775 -274.790083)
			(xy 13.165843 -274.84349) (xy 13.173963 -274.898666) (xy 13.174263 -274.915122) (xy 13.600428 -274.915122)
			(xy 13.604499 -274.8595) (xy 13.616625 -274.805063) (xy 13.636548 -274.752972) (xy 13.663844 -274.704337)
			(xy 13.69793 -274.660194) (xy 13.738079 -274.621485) (xy 13.783437 -274.589034) (xy 13.833037 -274.563533)
			(xy 13.885821 -274.545526) (xy 13.940664 -274.535396) (xy 13.996398 -274.533359) (xy 14.051835 -274.539459)
			(xy 14.105792 -274.553565) (xy 14.157121 -274.575377) (xy 14.204727 -274.604431) (xy 14.247595 -274.640106)
			(xy 14.284812 -274.681643) (xy 14.315585 -274.728156) (xy 14.339257 -274.778653) (xy 14.355325 -274.83206)
			(xy 14.363445 -274.887236) (xy 14.363954 -274.915122) (xy 14.363445 -274.943008) (xy 14.355325 -274.998184)
			(xy 14.339257 -275.051591) (xy 14.315585 -275.102088) (xy 14.284812 -275.148601) (xy 14.247595 -275.190138)
			(xy 14.204727 -275.225813) (xy 14.157121 -275.254867) (xy 14.105792 -275.276679) (xy 14.051835 -275.290785)
			(xy 13.996398 -275.296885) (xy 13.940664 -275.294848) (xy 13.885821 -275.284718) (xy 13.833037 -275.266711)
			(xy 13.783437 -275.24121) (xy 13.738079 -275.208759) (xy 13.69793 -275.17005) (xy 13.663844 -275.125907)
			(xy 13.636548 -275.077272) (xy 13.616625 -275.025181) (xy 13.604499 -274.970744) (xy 13.600428 -274.915122)
			(xy 13.174263 -274.915122) (xy 13.174472 -274.926552) (xy 13.173963 -274.954438) (xy 13.165843 -275.009614)
			(xy 13.149775 -275.063021) (xy 13.126103 -275.113518) (xy 13.09533 -275.160031) (xy 13.058113 -275.201568)
			(xy 13.015245 -275.237243) (xy 12.967639 -275.266297) (xy 12.91631 -275.288109) (xy 12.862353 -275.302215)
			(xy 12.806916 -275.308315) (xy 12.751182 -275.306278) (xy 12.696339 -275.296148) (xy 12.643555 -275.278141)
			(xy 12.593955 -275.25264) (xy 12.548597 -275.220189) (xy 12.508448 -275.18148) (xy 12.474362 -275.137337)
			(xy 12.447066 -275.088702) (xy 12.427143 -275.036611) (xy 12.415017 -274.982174) (xy 12.410946 -274.926552)
			(xy 1.80137 -274.926552) (xy 1.787015 -274.940845) (xy 1.743166 -274.973496) (xy 1.695107 -274.999555)
			(xy 1.643821 -275.018489) (xy 1.590358 -275.029911) (xy 1.563116 -275.032216) (xy 1.55321 -275.032724)
			(xy 1.536192 -275.040852) (xy 1.48209 -275.098764) (xy 1.475795 -275.10605) (xy 1.46872 -275.123941)
			(xy 1.468374 -275.133562) (xy 1.468374 -275.500592) (xy 1.46879 -275.510201) (xy 1.475838 -275.528081)
			(xy 1.48209 -275.53539) (xy 1.536192 -275.593302) (xy 1.553464 -275.60143) (xy 1.563116 -275.601938)
			(xy 1.590382 -275.60421) (xy 1.643902 -275.615576) (xy 1.695249 -275.63447) (xy 1.743371 -275.660504)
			(xy 1.787282 -275.693145) (xy 1.82608 -275.731722) (xy 1.858971 -275.775446) (xy 1.885279 -275.823419)
			(xy 1.904466 -275.874657) (xy 1.916138 -275.928111) (xy 1.917466 -275.946616) (xy 10.886692 -275.946616)
			(xy 10.890763 -275.890994) (xy 10.902889 -275.836557) (xy 10.922812 -275.784466) (xy 10.950108 -275.735831)
			(xy 10.984194 -275.691688) (xy 11.024343 -275.652979) (xy 11.069701 -275.620528) (xy 11.119301 -275.595027)
			(xy 11.172085 -275.57702) (xy 11.226928 -275.56689) (xy 11.282662 -275.564853) (xy 11.338099 -275.570953)
			(xy 11.392056 -275.585059) (xy 11.443385 -275.606871) (xy 11.490991 -275.635925) (xy 11.533859 -275.6716)
			(xy 11.571076 -275.713137) (xy 11.601849 -275.75965) (xy 11.625521 -275.810147) (xy 11.641589 -275.863554)
			(xy 11.649709 -275.91873) (xy 11.650218 -275.946616) (xy 11.649709 -275.974502) (xy 11.641589 -276.029678)
			(xy 11.625521 -276.083085) (xy 11.620791 -276.093174) (xy 12.410946 -276.093174) (xy 12.415017 -276.037552)
			(xy 12.427143 -275.983115) (xy 12.447066 -275.931024) (xy 12.474362 -275.882389) (xy 12.508448 -275.838246)
			(xy 12.548597 -275.799537) (xy 12.593955 -275.767086) (xy 12.643555 -275.741585) (xy 12.696339 -275.723578)
			(xy 12.751182 -275.713448) (xy 12.806916 -275.711411) (xy 12.862353 -275.717511) (xy 12.91631 -275.731617)
			(xy 12.967639 -275.753429) (xy 13.015245 -275.782483) (xy 13.058113 -275.818158) (xy 13.09533 -275.859695)
			(xy 13.126103 -275.906208) (xy 13.149775 -275.956705) (xy 13.165843 -276.010112) (xy 13.173963 -276.065288)
			(xy 13.174268 -276.081998) (xy 13.588998 -276.081998) (xy 13.593069 -276.026376) (xy 13.605195 -275.971939)
			(xy 13.625118 -275.919848) (xy 13.652414 -275.871213) (xy 13.6865 -275.82707) (xy 13.726649 -275.788361)
			(xy 13.772007 -275.75591) (xy 13.821607 -275.730409) (xy 13.874391 -275.712402) (xy 13.929234 -275.702272)
			(xy 13.984968 -275.700235) (xy 14.040405 -275.706335) (xy 14.094362 -275.720441) (xy 14.145691 -275.742253)
			(xy 14.193297 -275.771307) (xy 14.236165 -275.806982) (xy 14.273382 -275.848519) (xy 14.304155 -275.895032)
			(xy 14.327827 -275.945529) (xy 14.343895 -275.998936) (xy 14.352015 -276.054112) (xy 14.352524 -276.081998)
			(xy 14.352015 -276.109884) (xy 14.343895 -276.16506) (xy 14.327827 -276.218467) (xy 14.30619 -276.264624)
			(xy 15.394178 -276.264624) (xy 15.394684 -276.235706) (xy 15.403411 -276.178533) (xy 15.42067 -276.123333)
			(xy 15.446064 -276.07137) (xy 15.479011 -276.023837) (xy 15.518756 -275.981822) (xy 15.541244 -275.963634)
			(xy 15.549993 -275.95606) (xy 15.560182 -275.93531) (xy 15.560802 -275.923756) (xy 15.560802 -275.843492)
			(xy 15.560235 -275.831924) (xy 15.550038 -275.811153) (xy 15.541244 -275.803614) (xy 15.518776 -275.785404)
			(xy 15.479038 -275.743389) (xy 15.446096 -275.695859) (xy 15.420705 -275.643901) (xy 15.403445 -275.588706)
			(xy 15.394714 -275.531539) (xy 15.394178 -275.502624) (xy 15.394664 -275.475373) (xy 15.40242 -275.421425)
			(xy 15.417775 -275.36913) (xy 15.440417 -275.319553) (xy 15.469883 -275.273703) (xy 15.505574 -275.232512)
			(xy 15.546765 -275.196821) (xy 15.592615 -275.167355) (xy 15.642192 -275.144713) (xy 15.694487 -275.129358)
			(xy 15.748435 -275.121602) (xy 15.802937 -275.121602) (xy 15.856885 -275.129358) (xy 15.90918 -275.144713)
			(xy 15.958757 -275.167355) (xy 16.004607 -275.196821) (xy 16.045798 -275.232512) (xy 16.081489 -275.273703)
			(xy 16.110955 -275.319553) (xy 16.133597 -275.36913) (xy 16.148952 -275.421425) (xy 16.156708 -275.475373)
			(xy 16.157194 -275.502624) (xy 16.156624 -275.531539) (xy 16.147906 -275.588708) (xy 16.130658 -275.643906)
			(xy 16.105276 -275.695868) (xy 16.072342 -275.743403) (xy 16.03261 -275.785422) (xy 16.010128 -275.803614)
			(xy 16.001352 -275.811162) (xy 15.991179 -275.831932) (xy 15.99057 -275.843492) (xy 15.99057 -275.923756)
			(xy 15.991142 -275.935324) (xy 15.998302 -275.949918) (xy 44.143942 -275.949918) (xy 44.147902 -275.900864)
			(xy 44.159679 -275.85308) (xy 44.17897 -275.807804) (xy 44.205273 -275.766208) (xy 44.237908 -275.729371)
			(xy 44.276029 -275.698246) (xy 44.31865 -275.673639) (xy 44.364666 -275.656187) (xy 44.412885 -275.646343)
			(xy 44.46206 -275.644362) (xy 44.510915 -275.650294) (xy 44.558186 -275.663986) (xy 44.602648 -275.685084)
			(xy 44.643151 -275.71304) (xy 44.678644 -275.747132) (xy 44.708209 -275.786476) (xy 44.73108 -275.830053)
			(xy 44.746664 -275.876734) (xy 44.754559 -275.925311) (xy 44.755054 -275.949918) (xy 44.754559 -275.974525)
			(xy 44.75438 -275.975626) (xy 45.073312 -275.975626) (xy 45.073312 -275.92421) (xy 45.081355 -275.873428)
			(xy 45.097243 -275.824529) (xy 45.120586 -275.778717) (xy 45.150807 -275.737121) (xy 45.187163 -275.700765)
			(xy 45.228759 -275.670544) (xy 45.274571 -275.647201) (xy 45.32347 -275.631313) (xy 45.374252 -275.62327)
			(xy 45.425668 -275.62327) (xy 45.47645 -275.631313) (xy 45.525349 -275.647201) (xy 45.571161 -275.670544)
			(xy 45.612757 -275.700765) (xy 45.649113 -275.737121) (xy 45.679334 -275.778717) (xy 45.702677 -275.824529)
			(xy 45.718565 -275.873428) (xy 45.726608 -275.92421) (xy 45.727112 -275.949918) (xy 46.044116 -275.949918)
			(xy 46.048076 -275.900864) (xy 46.059853 -275.85308) (xy 46.079144 -275.807804) (xy 46.105447 -275.766208)
			(xy 46.138082 -275.729371) (xy 46.176203 -275.698246) (xy 46.218824 -275.673639) (xy 46.26484 -275.656187)
			(xy 46.313059 -275.646343) (xy 46.362234 -275.644362) (xy 46.411089 -275.650294) (xy 46.45836 -275.663986)
			(xy 46.502822 -275.685084) (xy 46.543325 -275.71304) (xy 46.578818 -275.747132) (xy 46.608383 -275.786476)
			(xy 46.631254 -275.830053) (xy 46.646838 -275.876734) (xy 46.654733 -275.925311) (xy 46.655228 -275.949918)
			(xy 46.654733 -275.974525) (xy 46.654554 -275.975626) (xy 46.973232 -275.975626) (xy 46.973232 -275.92421)
			(xy 46.981275 -275.873428) (xy 46.997163 -275.824529) (xy 47.020506 -275.778717) (xy 47.050727 -275.737121)
			(xy 47.087083 -275.700765) (xy 47.128679 -275.670544) (xy 47.174491 -275.647201) (xy 47.22339 -275.631313)
			(xy 47.274172 -275.62327) (xy 47.325588 -275.62327) (xy 47.37637 -275.631313) (xy 47.425269 -275.647201)
			(xy 47.471081 -275.670544) (xy 47.512677 -275.700765) (xy 47.549033 -275.737121) (xy 47.579254 -275.778717)
			(xy 47.602597 -275.824529) (xy 47.618485 -275.873428) (xy 47.626528 -275.92421) (xy 47.627032 -275.949918)
			(xy 47.944036 -275.949918) (xy 47.947996 -275.900864) (xy 47.959773 -275.85308) (xy 47.979064 -275.807804)
			(xy 48.005367 -275.766208) (xy 48.038002 -275.729371) (xy 48.076123 -275.698246) (xy 48.118744 -275.673639)
			(xy 48.16476 -275.656187) (xy 48.212979 -275.646343) (xy 48.262154 -275.644362) (xy 48.311009 -275.650294)
			(xy 48.35828 -275.663986) (xy 48.402742 -275.685084) (xy 48.443245 -275.71304) (xy 48.478738 -275.747132)
			(xy 48.508303 -275.786476) (xy 48.531174 -275.830053) (xy 48.546758 -275.876734) (xy 48.554653 -275.925311)
			(xy 48.555148 -275.949918) (xy 48.554653 -275.974525) (xy 48.554474 -275.975626) (xy 48.873152 -275.975626)
			(xy 48.873152 -275.92421) (xy 48.881195 -275.873428) (xy 48.897083 -275.824529) (xy 48.920426 -275.778717)
			(xy 48.950647 -275.737121) (xy 48.987003 -275.700765) (xy 49.028599 -275.670544) (xy 49.074411 -275.647201)
			(xy 49.12331 -275.631313) (xy 49.174092 -275.62327) (xy 49.225508 -275.62327) (xy 49.27629 -275.631313)
			(xy 49.325189 -275.647201) (xy 49.371001 -275.670544) (xy 49.412597 -275.700765) (xy 49.448953 -275.737121)
			(xy 49.479174 -275.778717) (xy 49.502517 -275.824529) (xy 49.518405 -275.873428) (xy 49.526448 -275.92421)
			(xy 49.526952 -275.949918) (xy 49.843956 -275.949918) (xy 49.847916 -275.900864) (xy 49.859693 -275.85308)
			(xy 49.878984 -275.807804) (xy 49.905287 -275.766208) (xy 49.937922 -275.729371) (xy 49.976043 -275.698246)
			(xy 50.018664 -275.673639) (xy 50.06468 -275.656187) (xy 50.112899 -275.646343) (xy 50.162074 -275.644362)
			(xy 50.210929 -275.650294) (xy 50.2582 -275.663986) (xy 50.302662 -275.685084) (xy 50.343165 -275.71304)
			(xy 50.378658 -275.747132) (xy 50.408223 -275.786476) (xy 50.431094 -275.830053) (xy 50.446678 -275.876734)
			(xy 50.454573 -275.925311) (xy 50.455068 -275.949918) (xy 50.454573 -275.974525) (xy 50.454394 -275.975626)
			(xy 50.773326 -275.975626) (xy 50.773326 -275.92421) (xy 50.781369 -275.873428) (xy 50.797257 -275.824529)
			(xy 50.8206 -275.778717) (xy 50.850821 -275.737121) (xy 50.887177 -275.700765) (xy 50.928773 -275.670544)
			(xy 50.974585 -275.647201) (xy 51.023484 -275.631313) (xy 51.074266 -275.62327) (xy 51.125682 -275.62327)
			(xy 51.176464 -275.631313) (xy 51.225363 -275.647201) (xy 51.271175 -275.670544) (xy 51.312771 -275.700765)
			(xy 51.349127 -275.737121) (xy 51.379348 -275.778717) (xy 51.402691 -275.824529) (xy 51.418579 -275.873428)
			(xy 51.426622 -275.92421) (xy 51.427126 -275.949918) (xy 51.74413 -275.949918) (xy 51.74809 -275.900864)
			(xy 51.759867 -275.85308) (xy 51.779158 -275.807804) (xy 51.805461 -275.766208) (xy 51.838096 -275.729371)
			(xy 51.876217 -275.698246) (xy 51.918838 -275.673639) (xy 51.964854 -275.656187) (xy 52.013073 -275.646343)
			(xy 52.062248 -275.644362) (xy 52.111103 -275.650294) (xy 52.158374 -275.663986) (xy 52.202836 -275.685084)
			(xy 52.243339 -275.71304) (xy 52.278832 -275.747132) (xy 52.308397 -275.786476) (xy 52.331268 -275.830053)
			(xy 52.346852 -275.876734) (xy 52.354747 -275.925311) (xy 52.355242 -275.949918) (xy 52.354747 -275.974525)
			(xy 52.354568 -275.975626) (xy 52.673246 -275.975626) (xy 52.673246 -275.92421) (xy 52.681289 -275.873428)
			(xy 52.697177 -275.824529) (xy 52.72052 -275.778717) (xy 52.750741 -275.737121) (xy 52.787097 -275.700765)
			(xy 52.828693 -275.670544) (xy 52.874505 -275.647201) (xy 52.923404 -275.631313) (xy 52.974186 -275.62327)
			(xy 53.025602 -275.62327) (xy 53.076384 -275.631313) (xy 53.125283 -275.647201) (xy 53.171095 -275.670544)
			(xy 53.212691 -275.700765) (xy 53.249047 -275.737121) (xy 53.279268 -275.778717) (xy 53.302611 -275.824529)
			(xy 53.318499 -275.873428) (xy 53.326542 -275.92421) (xy 53.327046 -275.949918) (xy 53.64405 -275.949918)
			(xy 53.64801 -275.900864) (xy 53.659787 -275.85308) (xy 53.679078 -275.807804) (xy 53.705381 -275.766208)
			(xy 53.738016 -275.729371) (xy 53.776137 -275.698246) (xy 53.818758 -275.673639) (xy 53.864774 -275.656187)
			(xy 53.912993 -275.646343) (xy 53.962168 -275.644362) (xy 54.011023 -275.650294) (xy 54.058294 -275.663986)
			(xy 54.102756 -275.685084) (xy 54.143259 -275.71304) (xy 54.178752 -275.747132) (xy 54.208317 -275.786476)
			(xy 54.231188 -275.830053) (xy 54.246772 -275.876734) (xy 54.254667 -275.925311) (xy 54.255162 -275.949918)
			(xy 54.254667 -275.974525) (xy 54.254488 -275.975626) (xy 54.573166 -275.975626) (xy 54.573166 -275.92421)
			(xy 54.581209 -275.873428) (xy 54.597097 -275.824529) (xy 54.62044 -275.778717) (xy 54.650661 -275.737121)
			(xy 54.687017 -275.700765) (xy 54.728613 -275.670544) (xy 54.774425 -275.647201) (xy 54.823324 -275.631313)
			(xy 54.874106 -275.62327) (xy 54.925522 -275.62327) (xy 54.976304 -275.631313) (xy 55.025203 -275.647201)
			(xy 55.071015 -275.670544) (xy 55.112611 -275.700765) (xy 55.148967 -275.737121) (xy 55.179188 -275.778717)
			(xy 55.202531 -275.824529) (xy 55.218419 -275.873428) (xy 55.226462 -275.92421) (xy 55.226966 -275.949918)
			(xy 55.54397 -275.949918) (xy 55.54793 -275.900864) (xy 55.559707 -275.85308) (xy 55.578998 -275.807804)
			(xy 55.605301 -275.766208) (xy 55.637936 -275.729371) (xy 55.676057 -275.698246) (xy 55.718678 -275.673639)
			(xy 55.764694 -275.656187) (xy 55.812913 -275.646343) (xy 55.862088 -275.644362) (xy 55.910943 -275.650294)
			(xy 55.958214 -275.663986) (xy 56.002676 -275.685084) (xy 56.043179 -275.71304) (xy 56.078672 -275.747132)
			(xy 56.108237 -275.786476) (xy 56.131108 -275.830053) (xy 56.146692 -275.876734) (xy 56.154587 -275.925311)
			(xy 56.155082 -275.949918) (xy 56.154587 -275.974525) (xy 56.154408 -275.975626) (xy 56.47334 -275.975626)
			(xy 56.47334 -275.92421) (xy 56.481383 -275.873428) (xy 56.497271 -275.824529) (xy 56.520614 -275.778717)
			(xy 56.550835 -275.737121) (xy 56.587191 -275.700765) (xy 56.628787 -275.670544) (xy 56.674599 -275.647201)
			(xy 56.723498 -275.631313) (xy 56.77428 -275.62327) (xy 56.825696 -275.62327) (xy 56.876478 -275.631313)
			(xy 56.925377 -275.647201) (xy 56.971189 -275.670544) (xy 57.012785 -275.700765) (xy 57.049141 -275.737121)
			(xy 57.079362 -275.778717) (xy 57.102705 -275.824529) (xy 57.118593 -275.873428) (xy 57.126636 -275.92421)
			(xy 57.12714 -275.949918) (xy 57.126636 -275.975626) (xy 57.118593 -276.026408) (xy 57.102705 -276.075307)
			(xy 57.079362 -276.121119) (xy 57.049141 -276.162715) (xy 57.012785 -276.199071) (xy 56.971189 -276.229292)
			(xy 56.925377 -276.252635) (xy 56.876478 -276.268523) (xy 56.825696 -276.276566) (xy 56.77428 -276.276566)
			(xy 56.723498 -276.268523) (xy 56.674599 -276.252635) (xy 56.628787 -276.229292) (xy 56.587191 -276.199071)
			(xy 56.550835 -276.162715) (xy 56.520614 -276.121119) (xy 56.497271 -276.075307) (xy 56.481383 -276.026408)
			(xy 56.47334 -275.975626) (xy 56.154408 -275.975626) (xy 56.146692 -276.023102) (xy 56.131108 -276.069783)
			(xy 56.108237 -276.11336) (xy 56.078672 -276.152704) (xy 56.043179 -276.186796) (xy 56.002676 -276.214752)
			(xy 55.958214 -276.23585) (xy 55.910943 -276.249542) (xy 55.862088 -276.255474) (xy 55.812913 -276.253493)
			(xy 55.764694 -276.243649) (xy 55.718678 -276.226197) (xy 55.676057 -276.20159) (xy 55.637936 -276.170465)
			(xy 55.605301 -276.133628) (xy 55.578998 -276.092032) (xy 55.559707 -276.046756) (xy 55.54793 -275.998972)
			(xy 55.54397 -275.949918) (xy 55.226966 -275.949918) (xy 55.226462 -275.975626) (xy 55.218419 -276.026408)
			(xy 55.202531 -276.075307) (xy 55.179188 -276.121119) (xy 55.148967 -276.162715) (xy 55.112611 -276.199071)
			(xy 55.071015 -276.229292) (xy 55.025203 -276.252635) (xy 54.976304 -276.268523) (xy 54.925522 -276.276566)
			(xy 54.874106 -276.276566) (xy 54.823324 -276.268523) (xy 54.774425 -276.252635) (xy 54.728613 -276.229292)
			(xy 54.687017 -276.199071) (xy 54.650661 -276.162715) (xy 54.62044 -276.121119) (xy 54.597097 -276.075307)
			(xy 54.581209 -276.026408) (xy 54.573166 -275.975626) (xy 54.254488 -275.975626) (xy 54.246772 -276.023102)
			(xy 54.231188 -276.069783) (xy 54.208317 -276.11336) (xy 54.178752 -276.152704) (xy 54.143259 -276.186796)
			(xy 54.102756 -276.214752) (xy 54.058294 -276.23585) (xy 54.011023 -276.249542) (xy 53.962168 -276.255474)
			(xy 53.912993 -276.253493) (xy 53.864774 -276.243649) (xy 53.818758 -276.226197) (xy 53.776137 -276.20159)
			(xy 53.738016 -276.170465) (xy 53.705381 -276.133628) (xy 53.679078 -276.092032) (xy 53.659787 -276.046756)
			(xy 53.64801 -275.998972) (xy 53.64405 -275.949918) (xy 53.327046 -275.949918) (xy 53.326542 -275.975626)
			(xy 53.318499 -276.026408) (xy 53.302611 -276.075307) (xy 53.279268 -276.121119) (xy 53.249047 -276.162715)
			(xy 53.212691 -276.199071) (xy 53.171095 -276.229292) (xy 53.125283 -276.252635) (xy 53.076384 -276.268523)
			(xy 53.025602 -276.276566) (xy 52.974186 -276.276566) (xy 52.923404 -276.268523) (xy 52.874505 -276.252635)
			(xy 52.828693 -276.229292) (xy 52.787097 -276.199071) (xy 52.750741 -276.162715) (xy 52.72052 -276.121119)
			(xy 52.697177 -276.075307) (xy 52.681289 -276.026408) (xy 52.673246 -275.975626) (xy 52.354568 -275.975626)
			(xy 52.346852 -276.023102) (xy 52.331268 -276.069783) (xy 52.308397 -276.11336) (xy 52.278832 -276.152704)
			(xy 52.243339 -276.186796) (xy 52.202836 -276.214752) (xy 52.158374 -276.23585) (xy 52.111103 -276.249542)
			(xy 52.062248 -276.255474) (xy 52.013073 -276.253493) (xy 51.964854 -276.243649) (xy 51.918838 -276.226197)
			(xy 51.876217 -276.20159) (xy 51.838096 -276.170465) (xy 51.805461 -276.133628) (xy 51.779158 -276.092032)
			(xy 51.759867 -276.046756) (xy 51.74809 -275.998972) (xy 51.74413 -275.949918) (xy 51.427126 -275.949918)
			(xy 51.426622 -275.975626) (xy 51.418579 -276.026408) (xy 51.402691 -276.075307) (xy 51.379348 -276.121119)
			(xy 51.349127 -276.162715) (xy 51.312771 -276.199071) (xy 51.271175 -276.229292) (xy 51.225363 -276.252635)
			(xy 51.176464 -276.268523) (xy 51.125682 -276.276566) (xy 51.074266 -276.276566) (xy 51.023484 -276.268523)
			(xy 50.974585 -276.252635) (xy 50.928773 -276.229292) (xy 50.887177 -276.199071) (xy 50.850821 -276.162715)
			(xy 50.8206 -276.121119) (xy 50.797257 -276.075307) (xy 50.781369 -276.026408) (xy 50.773326 -275.975626)
			(xy 50.454394 -275.975626) (xy 50.446678 -276.023102) (xy 50.431094 -276.069783) (xy 50.408223 -276.11336)
			(xy 50.378658 -276.152704) (xy 50.343165 -276.186796) (xy 50.302662 -276.214752) (xy 50.2582 -276.23585)
			(xy 50.210929 -276.249542) (xy 50.162074 -276.255474) (xy 50.112899 -276.253493) (xy 50.06468 -276.243649)
			(xy 50.018664 -276.226197) (xy 49.976043 -276.20159) (xy 49.937922 -276.170465) (xy 49.905287 -276.133628)
			(xy 49.878984 -276.092032) (xy 49.859693 -276.046756) (xy 49.847916 -275.998972) (xy 49.843956 -275.949918)
			(xy 49.526952 -275.949918) (xy 49.526448 -275.975626) (xy 49.518405 -276.026408) (xy 49.502517 -276.075307)
			(xy 49.479174 -276.121119) (xy 49.448953 -276.162715) (xy 49.412597 -276.199071) (xy 49.371001 -276.229292)
			(xy 49.325189 -276.252635) (xy 49.27629 -276.268523) (xy 49.225508 -276.276566) (xy 49.174092 -276.276566)
			(xy 49.12331 -276.268523) (xy 49.074411 -276.252635) (xy 49.028599 -276.229292) (xy 48.987003 -276.199071)
			(xy 48.950647 -276.162715) (xy 48.920426 -276.121119) (xy 48.897083 -276.075307) (xy 48.881195 -276.026408)
			(xy 48.873152 -275.975626) (xy 48.554474 -275.975626) (xy 48.546758 -276.023102) (xy 48.531174 -276.069783)
			(xy 48.508303 -276.11336) (xy 48.478738 -276.152704) (xy 48.443245 -276.186796) (xy 48.402742 -276.214752)
			(xy 48.35828 -276.23585) (xy 48.311009 -276.249542) (xy 48.262154 -276.255474) (xy 48.212979 -276.253493)
			(xy 48.16476 -276.243649) (xy 48.118744 -276.226197) (xy 48.076123 -276.20159) (xy 48.038002 -276.170465)
			(xy 48.005367 -276.133628) (xy 47.979064 -276.092032) (xy 47.959773 -276.046756) (xy 47.947996 -275.998972)
			(xy 47.944036 -275.949918) (xy 47.627032 -275.949918) (xy 47.626528 -275.975626) (xy 47.618485 -276.026408)
			(xy 47.602597 -276.075307) (xy 47.579254 -276.121119) (xy 47.549033 -276.162715) (xy 47.512677 -276.199071)
			(xy 47.471081 -276.229292) (xy 47.425269 -276.252635) (xy 47.37637 -276.268523) (xy 47.325588 -276.276566)
			(xy 47.274172 -276.276566) (xy 47.22339 -276.268523) (xy 47.174491 -276.252635) (xy 47.128679 -276.229292)
			(xy 47.087083 -276.199071) (xy 47.050727 -276.162715) (xy 47.020506 -276.121119) (xy 46.997163 -276.075307)
			(xy 46.981275 -276.026408) (xy 46.973232 -275.975626) (xy 46.654554 -275.975626) (xy 46.646838 -276.023102)
			(xy 46.631254 -276.069783) (xy 46.608383 -276.11336) (xy 46.578818 -276.152704) (xy 46.543325 -276.186796)
			(xy 46.502822 -276.214752) (xy 46.45836 -276.23585) (xy 46.411089 -276.249542) (xy 46.362234 -276.255474)
			(xy 46.313059 -276.253493) (xy 46.26484 -276.243649) (xy 46.218824 -276.226197) (xy 46.176203 -276.20159)
			(xy 46.138082 -276.170465) (xy 46.105447 -276.133628) (xy 46.079144 -276.092032) (xy 46.059853 -276.046756)
			(xy 46.048076 -275.998972) (xy 46.044116 -275.949918) (xy 45.727112 -275.949918) (xy 45.726608 -275.975626)
			(xy 45.718565 -276.026408) (xy 45.702677 -276.075307) (xy 45.679334 -276.121119) (xy 45.649113 -276.162715)
			(xy 45.612757 -276.199071) (xy 45.571161 -276.229292) (xy 45.525349 -276.252635) (xy 45.47645 -276.268523)
			(xy 45.425668 -276.276566) (xy 45.374252 -276.276566) (xy 45.32347 -276.268523) (xy 45.274571 -276.252635)
			(xy 45.228759 -276.229292) (xy 45.187163 -276.199071) (xy 45.150807 -276.162715) (xy 45.120586 -276.121119)
			(xy 45.097243 -276.075307) (xy 45.081355 -276.026408) (xy 45.073312 -275.975626) (xy 44.75438 -275.975626)
			(xy 44.746664 -276.023102) (xy 44.73108 -276.069783) (xy 44.708209 -276.11336) (xy 44.678644 -276.152704)
			(xy 44.643151 -276.186796) (xy 44.602648 -276.214752) (xy 44.558186 -276.23585) (xy 44.510915 -276.249542)
			(xy 44.46206 -276.255474) (xy 44.412885 -276.253493) (xy 44.364666 -276.243649) (xy 44.31865 -276.226197)
			(xy 44.276029 -276.20159) (xy 44.237908 -276.170465) (xy 44.205273 -276.133628) (xy 44.17897 -276.092032)
			(xy 44.159679 -276.046756) (xy 44.147902 -275.998972) (xy 44.143942 -275.949918) (xy 15.998302 -275.949918)
			(xy 16.001333 -275.956097) (xy 16.010128 -275.963634) (xy 16.032634 -275.981799) (xy 16.072366 -276.023825)
			(xy 16.105302 -276.071365) (xy 16.130686 -276.123332) (xy 16.147938 -276.178534) (xy 16.156662 -276.235707)
			(xy 16.157194 -276.264624) (xy 16.156708 -276.291875) (xy 16.148952 -276.345823) (xy 16.133597 -276.398118)
			(xy 16.121366 -276.424898) (xy 36.069028 -276.424898) (xy 36.072988 -276.375844) (xy 36.084765 -276.32806)
			(xy 36.104056 -276.282784) (xy 36.130359 -276.241188) (xy 36.162994 -276.204351) (xy 36.201115 -276.173226)
			(xy 36.243736 -276.148619) (xy 36.289752 -276.131167) (xy 36.337971 -276.121323) (xy 36.387146 -276.119342)
			(xy 36.436001 -276.125274) (xy 36.483272 -276.138966) (xy 36.527734 -276.160064) (xy 36.568237 -276.18802)
			(xy 36.60373 -276.222112) (xy 36.633295 -276.261456) (xy 36.656166 -276.305033) (xy 36.67175 -276.351714)
			(xy 36.679645 -276.400291) (xy 36.68014 -276.424898) (xy 37.018988 -276.424898) (xy 37.022948 -276.375844)
			(xy 37.034725 -276.32806) (xy 37.054016 -276.282784) (xy 37.080319 -276.241188) (xy 37.112954 -276.204351)
			(xy 37.151075 -276.173226) (xy 37.193696 -276.148619) (xy 37.239712 -276.131167) (xy 37.287931 -276.121323)
			(xy 37.337106 -276.119342) (xy 37.385961 -276.125274) (xy 37.433232 -276.138966) (xy 37.477694 -276.160064)
			(xy 37.518197 -276.18802) (xy 37.55369 -276.222112) (xy 37.583255 -276.261456) (xy 37.606126 -276.305033)
			(xy 37.62171 -276.351714) (xy 37.629605 -276.400291) (xy 37.6301 -276.424898) (xy 37.969202 -276.424898)
			(xy 37.973162 -276.375844) (xy 37.984939 -276.32806) (xy 38.00423 -276.282784) (xy 38.030533 -276.241188)
			(xy 38.063168 -276.204351) (xy 38.101289 -276.173226) (xy 38.14391 -276.148619) (xy 38.189926 -276.131167)
			(xy 38.238145 -276.121323) (xy 38.28732 -276.119342) (xy 38.336175 -276.125274) (xy 38.383446 -276.138966)
			(xy 38.427908 -276.160064) (xy 38.468411 -276.18802) (xy 38.503904 -276.222112) (xy 38.533469 -276.261456)
			(xy 38.55634 -276.305033) (xy 38.571924 -276.351714) (xy 38.579819 -276.400291) (xy 38.580314 -276.424898)
			(xy 38.919162 -276.424898) (xy 38.923122 -276.375844) (xy 38.934899 -276.32806) (xy 38.95419 -276.282784)
			(xy 38.980493 -276.241188) (xy 39.013128 -276.204351) (xy 39.051249 -276.173226) (xy 39.09387 -276.148619)
			(xy 39.139886 -276.131167) (xy 39.188105 -276.121323) (xy 39.23728 -276.119342) (xy 39.286135 -276.125274)
			(xy 39.333406 -276.138966) (xy 39.377868 -276.160064) (xy 39.418371 -276.18802) (xy 39.453864 -276.222112)
			(xy 39.483429 -276.261456) (xy 39.5063 -276.305033) (xy 39.521884 -276.351714) (xy 39.529779 -276.400291)
			(xy 39.530274 -276.424898) (xy 39.869122 -276.424898) (xy 39.873082 -276.375844) (xy 39.884859 -276.32806)
			(xy 39.90415 -276.282784) (xy 39.930453 -276.241188) (xy 39.963088 -276.204351) (xy 40.001209 -276.173226)
			(xy 40.04383 -276.148619) (xy 40.089846 -276.131167) (xy 40.138065 -276.121323) (xy 40.18724 -276.119342)
			(xy 40.236095 -276.125274) (xy 40.283366 -276.138966) (xy 40.327828 -276.160064) (xy 40.368331 -276.18802)
			(xy 40.403824 -276.222112) (xy 40.433389 -276.261456) (xy 40.45626 -276.305033) (xy 40.471844 -276.351714)
			(xy 40.479739 -276.400291) (xy 40.480234 -276.424898) (xy 40.819082 -276.424898) (xy 40.823042 -276.375844)
			(xy 40.834819 -276.32806) (xy 40.85411 -276.282784) (xy 40.880413 -276.241188) (xy 40.913048 -276.204351)
			(xy 40.951169 -276.173226) (xy 40.99379 -276.148619) (xy 41.039806 -276.131167) (xy 41.088025 -276.121323)
			(xy 41.1372 -276.119342) (xy 41.186055 -276.125274) (xy 41.233326 -276.138966) (xy 41.277788 -276.160064)
			(xy 41.318291 -276.18802) (xy 41.353784 -276.222112) (xy 41.383349 -276.261456) (xy 41.40622 -276.305033)
			(xy 41.421804 -276.351714) (xy 41.429699 -276.400291) (xy 41.430194 -276.424898) (xy 41.769042 -276.424898)
			(xy 41.773002 -276.375844) (xy 41.784779 -276.32806) (xy 41.80407 -276.282784) (xy 41.830373 -276.241188)
			(xy 41.863008 -276.204351) (xy 41.901129 -276.173226) (xy 41.94375 -276.148619) (xy 41.989766 -276.131167)
			(xy 42.037985 -276.121323) (xy 42.08716 -276.119342) (xy 42.136015 -276.125274) (xy 42.183286 -276.138966)
			(xy 42.227748 -276.160064) (xy 42.268251 -276.18802) (xy 42.303744 -276.222112) (xy 42.333309 -276.261456)
			(xy 42.35618 -276.305033) (xy 42.371764 -276.351714) (xy 42.379659 -276.400291) (xy 42.380154 -276.424898)
			(xy 42.379659 -276.449505) (xy 42.371764 -276.498082) (xy 42.35618 -276.544763) (xy 42.333309 -276.58834)
			(xy 42.303744 -276.627684) (xy 42.268251 -276.661776) (xy 42.227748 -276.689732) (xy 42.183286 -276.71083)
			(xy 42.136015 -276.724522) (xy 42.08716 -276.730454) (xy 42.037985 -276.728473) (xy 41.989766 -276.718629)
			(xy 41.94375 -276.701177) (xy 41.901129 -276.67657) (xy 41.863008 -276.645445) (xy 41.830373 -276.608608)
			(xy 41.80407 -276.567012) (xy 41.784779 -276.521736) (xy 41.773002 -276.473952) (xy 41.769042 -276.424898)
			(xy 41.430194 -276.424898) (xy 41.429699 -276.449505) (xy 41.421804 -276.498082) (xy 41.40622 -276.544763)
			(xy 41.383349 -276.58834) (xy 41.353784 -276.627684) (xy 41.318291 -276.661776) (xy 41.277788 -276.689732)
			(xy 41.233326 -276.71083) (xy 41.186055 -276.724522) (xy 41.1372 -276.730454) (xy 41.088025 -276.728473)
			(xy 41.039806 -276.718629) (xy 40.99379 -276.701177) (xy 40.951169 -276.67657) (xy 40.913048 -276.645445)
			(xy 40.880413 -276.608608) (xy 40.85411 -276.567012) (xy 40.834819 -276.521736) (xy 40.823042 -276.473952)
			(xy 40.819082 -276.424898) (xy 40.480234 -276.424898) (xy 40.479739 -276.449505) (xy 40.471844 -276.498082)
			(xy 40.45626 -276.544763) (xy 40.433389 -276.58834) (xy 40.403824 -276.627684) (xy 40.368331 -276.661776)
			(xy 40.327828 -276.689732) (xy 40.283366 -276.71083) (xy 40.236095 -276.724522) (xy 40.18724 -276.730454)
			(xy 40.138065 -276.728473) (xy 40.089846 -276.718629) (xy 40.04383 -276.701177) (xy 40.001209 -276.67657)
			(xy 39.963088 -276.645445) (xy 39.930453 -276.608608) (xy 39.90415 -276.567012) (xy 39.884859 -276.521736)
			(xy 39.873082 -276.473952) (xy 39.869122 -276.424898) (xy 39.530274 -276.424898) (xy 39.529779 -276.449505)
			(xy 39.521884 -276.498082) (xy 39.5063 -276.544763) (xy 39.483429 -276.58834) (xy 39.453864 -276.627684)
			(xy 39.418371 -276.661776) (xy 39.377868 -276.689732) (xy 39.333406 -276.71083) (xy 39.286135 -276.724522)
			(xy 39.23728 -276.730454) (xy 39.188105 -276.728473) (xy 39.139886 -276.718629) (xy 39.09387 -276.701177)
			(xy 39.051249 -276.67657) (xy 39.013128 -276.645445) (xy 38.980493 -276.608608) (xy 38.95419 -276.567012)
			(xy 38.934899 -276.521736) (xy 38.923122 -276.473952) (xy 38.919162 -276.424898) (xy 38.580314 -276.424898)
			(xy 38.579819 -276.449505) (xy 38.571924 -276.498082) (xy 38.55634 -276.544763) (xy 38.533469 -276.58834)
			(xy 38.503904 -276.627684) (xy 38.468411 -276.661776) (xy 38.427908 -276.689732) (xy 38.383446 -276.71083)
			(xy 38.336175 -276.724522) (xy 38.28732 -276.730454) (xy 38.238145 -276.728473) (xy 38.189926 -276.718629)
			(xy 38.14391 -276.701177) (xy 38.101289 -276.67657) (xy 38.063168 -276.645445) (xy 38.030533 -276.608608)
			(xy 38.00423 -276.567012) (xy 37.984939 -276.521736) (xy 37.973162 -276.473952) (xy 37.969202 -276.424898)
			(xy 37.6301 -276.424898) (xy 37.629605 -276.449505) (xy 37.62171 -276.498082) (xy 37.606126 -276.544763)
			(xy 37.583255 -276.58834) (xy 37.55369 -276.627684) (xy 37.518197 -276.661776) (xy 37.477694 -276.689732)
			(xy 37.433232 -276.71083) (xy 37.385961 -276.724522) (xy 37.337106 -276.730454) (xy 37.287931 -276.728473)
			(xy 37.239712 -276.718629) (xy 37.193696 -276.701177) (xy 37.151075 -276.67657) (xy 37.112954 -276.645445)
			(xy 37.080319 -276.608608) (xy 37.054016 -276.567012) (xy 37.034725 -276.521736) (xy 37.022948 -276.473952)
			(xy 37.018988 -276.424898) (xy 36.68014 -276.424898) (xy 36.679645 -276.449505) (xy 36.67175 -276.498082)
			(xy 36.656166 -276.544763) (xy 36.633295 -276.58834) (xy 36.60373 -276.627684) (xy 36.568237 -276.661776)
			(xy 36.527734 -276.689732) (xy 36.483272 -276.71083) (xy 36.436001 -276.724522) (xy 36.387146 -276.730454)
			(xy 36.337971 -276.728473) (xy 36.289752 -276.718629) (xy 36.243736 -276.701177) (xy 36.201115 -276.67657)
			(xy 36.162994 -276.645445) (xy 36.130359 -276.608608) (xy 36.104056 -276.567012) (xy 36.084765 -276.521736)
			(xy 36.072988 -276.473952) (xy 36.069028 -276.424898) (xy 16.121366 -276.424898) (xy 16.110955 -276.447695)
			(xy 16.081489 -276.493545) (xy 16.045798 -276.534736) (xy 16.004607 -276.570427) (xy 15.958757 -276.599893)
			(xy 15.90918 -276.622535) (xy 15.856885 -276.63789) (xy 15.802937 -276.645646) (xy 15.748435 -276.645646)
			(xy 15.694487 -276.63789) (xy 15.642192 -276.622535) (xy 15.592615 -276.599893) (xy 15.546765 -276.570427)
			(xy 15.505574 -276.534736) (xy 15.469883 -276.493545) (xy 15.440417 -276.447695) (xy 15.417775 -276.398118)
			(xy 15.40242 -276.345823) (xy 15.394664 -276.291875) (xy 15.394178 -276.264624) (xy 14.30619 -276.264624)
			(xy 14.304155 -276.268964) (xy 14.273382 -276.315477) (xy 14.236165 -276.357014) (xy 14.193297 -276.392689)
			(xy 14.145691 -276.421743) (xy 14.094362 -276.443555) (xy 14.040405 -276.457661) (xy 13.984968 -276.463761)
			(xy 13.929234 -276.461724) (xy 13.874391 -276.451594) (xy 13.821607 -276.433587) (xy 13.772007 -276.408086)
			(xy 13.726649 -276.375635) (xy 13.6865 -276.336926) (xy 13.652414 -276.292783) (xy 13.625118 -276.244148)
			(xy 13.605195 -276.192057) (xy 13.593069 -276.13762) (xy 13.588998 -276.081998) (xy 13.174268 -276.081998)
			(xy 13.174472 -276.093174) (xy 13.173963 -276.12106) (xy 13.165843 -276.176236) (xy 13.149775 -276.229643)
			(xy 13.126103 -276.28014) (xy 13.09533 -276.326653) (xy 13.058113 -276.36819) (xy 13.015245 -276.403865)
			(xy 12.967639 -276.432919) (xy 12.91631 -276.454731) (xy 12.862353 -276.468837) (xy 12.806916 -276.474937)
			(xy 12.751182 -276.4729) (xy 12.696339 -276.46277) (xy 12.643555 -276.444763) (xy 12.593955 -276.419262)
			(xy 12.548597 -276.386811) (xy 12.508448 -276.348102) (xy 12.474362 -276.303959) (xy 12.447066 -276.255324)
			(xy 12.427143 -276.203233) (xy 12.415017 -276.148796) (xy 12.410946 -276.093174) (xy 11.620791 -276.093174)
			(xy 11.601849 -276.133582) (xy 11.571076 -276.180095) (xy 11.533859 -276.221632) (xy 11.490991 -276.257307)
			(xy 11.443385 -276.286361) (xy 11.392056 -276.308173) (xy 11.338099 -276.322279) (xy 11.282662 -276.328379)
			(xy 11.226928 -276.326342) (xy 11.172085 -276.316212) (xy 11.119301 -276.298205) (xy 11.069701 -276.272704)
			(xy 11.024343 -276.240253) (xy 10.984194 -276.201544) (xy 10.950108 -276.157401) (xy 10.922812 -276.108766)
			(xy 10.902889 -276.056675) (xy 10.890763 -276.002238) (xy 10.886692 -275.946616) (xy 1.917466 -275.946616)
			(xy 1.920055 -275.982684) (xy 1.916138 -276.037257) (xy 1.904466 -276.090711) (xy 1.885279 -276.141949)
			(xy 1.858971 -276.189922) (xy 1.82608 -276.233646) (xy 1.787282 -276.272223) (xy 1.743371 -276.304864)
			(xy 1.695249 -276.330898) (xy 1.643902 -276.349792) (xy 1.590382 -276.361158) (xy 1.563116 -276.36343)
			(xy 1.553464 -276.363938) (xy 1.536192 -276.372066) (xy 1.48209 -276.429978) (xy 1.475797 -276.437265)
			(xy 1.468727 -276.455156) (xy 1.468374 -276.464776) (xy 1.468374 -276.789134) (xy 9.320782 -276.789134)
			(xy 9.324853 -276.733512) (xy 9.336979 -276.679075) (xy 9.356902 -276.626984) (xy 9.384198 -276.578349)
			(xy 9.418284 -276.534206) (xy 9.458433 -276.495497) (xy 9.503791 -276.463046) (xy 9.553391 -276.437545)
			(xy 9.606175 -276.419538) (xy 9.661018 -276.409408) (xy 9.716752 -276.407371) (xy 9.772189 -276.413471)
			(xy 9.826146 -276.427577) (xy 9.877475 -276.449389) (xy 9.925081 -276.478443) (xy 9.967949 -276.514118)
			(xy 10.005166 -276.555655) (xy 10.035939 -276.602168) (xy 10.059611 -276.652665) (xy 10.075679 -276.706072)
			(xy 10.083799 -276.761248) (xy 10.084308 -276.789134) (xy 10.083799 -276.81702) (xy 10.075679 -276.872196)
			(xy 10.059611 -276.925603) (xy 10.035939 -276.9761) (xy 10.005166 -277.022613) (xy 9.967949 -277.06415)
			(xy 9.925081 -277.099825) (xy 9.877475 -277.128879) (xy 9.826146 -277.150691) (xy 9.772189 -277.164797)
			(xy 9.716752 -277.170897) (xy 9.661018 -277.16886) (xy 9.606175 -277.15873) (xy 9.553391 -277.140723)
			(xy 9.503791 -277.115222) (xy 9.458433 -277.082771) (xy 9.418284 -277.044062) (xy 9.384198 -276.999919)
			(xy 9.356902 -276.951284) (xy 9.336979 -276.899193) (xy 9.324853 -276.844756) (xy 9.320782 -276.789134)
			(xy 1.468374 -276.789134) (xy 1.468374 -276.876764) (xy 1.468785 -276.886375) (xy 1.475826 -276.904262)
			(xy 1.48209 -276.911562) (xy 1.536446 -276.969474) (xy 1.553464 -276.977602) (xy 1.56337 -276.97811)
			(xy 1.592037 -276.980469) (xy 1.648235 -276.992719) (xy 1.701958 -277.013268) (xy 1.751986 -277.041649)
			(xy 1.797186 -277.07722) (xy 1.836534 -277.119173) (xy 1.869137 -277.166559) (xy 1.894257 -277.218302)
			(xy 1.911324 -277.273229) (xy 1.912446 -277.280624) (xy 15.393668 -277.280624) (xy 15.397739 -277.225002)
			(xy 15.409865 -277.170565) (xy 15.429788 -277.118474) (xy 15.457084 -277.069839) (xy 15.49117 -277.025696)
			(xy 15.531319 -276.986987) (xy 15.576677 -276.954536) (xy 15.626277 -276.929035) (xy 15.679061 -276.911028)
			(xy 15.733904 -276.900898) (xy 15.789638 -276.898861) (xy 15.798881 -276.899878) (xy 43.193982 -276.899878)
			(xy 43.197942 -276.850824) (xy 43.209719 -276.80304) (xy 43.22901 -276.757764) (xy 43.255313 -276.716168)
			(xy 43.287948 -276.679331) (xy 43.326069 -276.648206) (xy 43.36869 -276.623599) (xy 43.414706 -276.606147)
			(xy 43.462925 -276.596303) (xy 43.5121 -276.594322) (xy 43.560955 -276.600254) (xy 43.608226 -276.613946)
			(xy 43.652688 -276.635044) (xy 43.693191 -276.663) (xy 43.728684 -276.697092) (xy 43.758249 -276.736436)
			(xy 43.78112 -276.780013) (xy 43.796704 -276.826694) (xy 43.804599 -276.875271) (xy 43.805094 -276.899878)
			(xy 44.143942 -276.899878) (xy 44.147902 -276.850824) (xy 44.159679 -276.80304) (xy 44.17897 -276.757764)
			(xy 44.205273 -276.716168) (xy 44.237908 -276.679331) (xy 44.276029 -276.648206) (xy 44.31865 -276.623599)
			(xy 44.364666 -276.606147) (xy 44.412885 -276.596303) (xy 44.46206 -276.594322) (xy 44.510915 -276.600254)
			(xy 44.558186 -276.613946) (xy 44.602648 -276.635044) (xy 44.643151 -276.663) (xy 44.678644 -276.697092)
			(xy 44.708209 -276.736436) (xy 44.73108 -276.780013) (xy 44.746664 -276.826694) (xy 44.754559 -276.875271)
			(xy 44.755054 -276.899878) (xy 45.094156 -276.899878) (xy 45.098116 -276.850824) (xy 45.109893 -276.80304)
			(xy 45.129184 -276.757764) (xy 45.155487 -276.716168) (xy 45.188122 -276.679331) (xy 45.226243 -276.648206)
			(xy 45.268864 -276.623599) (xy 45.31488 -276.606147) (xy 45.363099 -276.596303) (xy 45.412274 -276.594322)
			(xy 45.461129 -276.600254) (xy 45.5084 -276.613946) (xy 45.552862 -276.635044) (xy 45.593365 -276.663)
			(xy 45.628858 -276.697092) (xy 45.658423 -276.736436) (xy 45.681294 -276.780013) (xy 45.696878 -276.826694)
			(xy 45.704773 -276.875271) (xy 45.705268 -276.899878) (xy 46.044116 -276.899878) (xy 46.048076 -276.850824)
			(xy 46.059853 -276.80304) (xy 46.079144 -276.757764) (xy 46.105447 -276.716168) (xy 46.138082 -276.679331)
			(xy 46.176203 -276.648206) (xy 46.218824 -276.623599) (xy 46.26484 -276.606147) (xy 46.313059 -276.596303)
			(xy 46.362234 -276.594322) (xy 46.411089 -276.600254) (xy 46.45836 -276.613946) (xy 46.502822 -276.635044)
			(xy 46.543325 -276.663) (xy 46.578818 -276.697092) (xy 46.608383 -276.736436) (xy 46.631254 -276.780013)
			(xy 46.646838 -276.826694) (xy 46.654733 -276.875271) (xy 46.655228 -276.899878) (xy 46.994076 -276.899878)
			(xy 46.998036 -276.850824) (xy 47.009813 -276.80304) (xy 47.029104 -276.757764) (xy 47.055407 -276.716168)
			(xy 47.088042 -276.679331) (xy 47.126163 -276.648206) (xy 47.168784 -276.623599) (xy 47.2148 -276.606147)
			(xy 47.263019 -276.596303) (xy 47.312194 -276.594322) (xy 47.361049 -276.600254) (xy 47.40832 -276.613946)
			(xy 47.452782 -276.635044) (xy 47.493285 -276.663) (xy 47.528778 -276.697092) (xy 47.558343 -276.736436)
			(xy 47.581214 -276.780013) (xy 47.596798 -276.826694) (xy 47.604693 -276.875271) (xy 47.605188 -276.899878)
			(xy 47.944036 -276.899878) (xy 47.947996 -276.850824) (xy 47.959773 -276.80304) (xy 47.979064 -276.757764)
			(xy 48.005367 -276.716168) (xy 48.038002 -276.679331) (xy 48.076123 -276.648206) (xy 48.118744 -276.623599)
			(xy 48.16476 -276.606147) (xy 48.212979 -276.596303) (xy 48.262154 -276.594322) (xy 48.311009 -276.600254)
			(xy 48.35828 -276.613946) (xy 48.402742 -276.635044) (xy 48.443245 -276.663) (xy 48.478738 -276.697092)
			(xy 48.508303 -276.736436) (xy 48.531174 -276.780013) (xy 48.546758 -276.826694) (xy 48.554653 -276.875271)
			(xy 48.555148 -276.899878) (xy 48.893996 -276.899878) (xy 48.897956 -276.850824) (xy 48.909733 -276.80304)
			(xy 48.929024 -276.757764) (xy 48.955327 -276.716168) (xy 48.987962 -276.679331) (xy 49.026083 -276.648206)
			(xy 49.068704 -276.623599) (xy 49.11472 -276.606147) (xy 49.162939 -276.596303) (xy 49.212114 -276.594322)
			(xy 49.260969 -276.600254) (xy 49.30824 -276.613946) (xy 49.352702 -276.635044) (xy 49.393205 -276.663)
			(xy 49.428698 -276.697092) (xy 49.458263 -276.736436) (xy 49.481134 -276.780013) (xy 49.496718 -276.826694)
			(xy 49.504613 -276.875271) (xy 49.505108 -276.899878) (xy 49.843956 -276.899878) (xy 49.847916 -276.850824)
			(xy 49.859693 -276.80304) (xy 49.878984 -276.757764) (xy 49.905287 -276.716168) (xy 49.937922 -276.679331)
			(xy 49.976043 -276.648206) (xy 50.018664 -276.623599) (xy 50.06468 -276.606147) (xy 50.112899 -276.596303)
			(xy 50.162074 -276.594322) (xy 50.210929 -276.600254) (xy 50.2582 -276.613946) (xy 50.302662 -276.635044)
			(xy 50.343165 -276.663) (xy 50.378658 -276.697092) (xy 50.408223 -276.736436) (xy 50.431094 -276.780013)
			(xy 50.446678 -276.826694) (xy 50.454573 -276.875271) (xy 50.455068 -276.899878) (xy 50.79417 -276.899878)
			(xy 50.79813 -276.850824) (xy 50.809907 -276.80304) (xy 50.829198 -276.757764) (xy 50.855501 -276.716168)
			(xy 50.888136 -276.679331) (xy 50.926257 -276.648206) (xy 50.968878 -276.623599) (xy 51.014894 -276.606147)
			(xy 51.063113 -276.596303) (xy 51.112288 -276.594322) (xy 51.161143 -276.600254) (xy 51.208414 -276.613946)
			(xy 51.252876 -276.635044) (xy 51.293379 -276.663) (xy 51.328872 -276.697092) (xy 51.358437 -276.736436)
			(xy 51.381308 -276.780013) (xy 51.396892 -276.826694) (xy 51.404787 -276.875271) (xy 51.405282 -276.899878)
			(xy 51.74413 -276.899878) (xy 51.74809 -276.850824) (xy 51.759867 -276.80304) (xy 51.779158 -276.757764)
			(xy 51.805461 -276.716168) (xy 51.838096 -276.679331) (xy 51.876217 -276.648206) (xy 51.918838 -276.623599)
			(xy 51.964854 -276.606147) (xy 52.013073 -276.596303) (xy 52.062248 -276.594322) (xy 52.111103 -276.600254)
			(xy 52.158374 -276.613946) (xy 52.202836 -276.635044) (xy 52.243339 -276.663) (xy 52.278832 -276.697092)
			(xy 52.308397 -276.736436) (xy 52.331268 -276.780013) (xy 52.346852 -276.826694) (xy 52.354747 -276.875271)
			(xy 52.355242 -276.899878) (xy 52.69409 -276.899878) (xy 52.69805 -276.850824) (xy 52.709827 -276.80304)
			(xy 52.729118 -276.757764) (xy 52.755421 -276.716168) (xy 52.788056 -276.679331) (xy 52.826177 -276.648206)
			(xy 52.868798 -276.623599) (xy 52.914814 -276.606147) (xy 52.963033 -276.596303) (xy 53.012208 -276.594322)
			(xy 53.061063 -276.600254) (xy 53.108334 -276.613946) (xy 53.152796 -276.635044) (xy 53.193299 -276.663)
			(xy 53.228792 -276.697092) (xy 53.258357 -276.736436) (xy 53.281228 -276.780013) (xy 53.296812 -276.826694)
			(xy 53.304707 -276.875271) (xy 53.305202 -276.899878) (xy 53.64405 -276.899878) (xy 53.64801 -276.850824)
			(xy 53.659787 -276.80304) (xy 53.679078 -276.757764) (xy 53.705381 -276.716168) (xy 53.738016 -276.679331)
			(xy 53.776137 -276.648206) (xy 53.818758 -276.623599) (xy 53.864774 -276.606147) (xy 53.912993 -276.596303)
			(xy 53.962168 -276.594322) (xy 54.011023 -276.600254) (xy 54.058294 -276.613946) (xy 54.102756 -276.635044)
			(xy 54.143259 -276.663) (xy 54.178752 -276.697092) (xy 54.208317 -276.736436) (xy 54.231188 -276.780013)
			(xy 54.246772 -276.826694) (xy 54.254667 -276.875271) (xy 54.255162 -276.899878) (xy 54.59401 -276.899878)
			(xy 54.59797 -276.850824) (xy 54.609747 -276.80304) (xy 54.629038 -276.757764) (xy 54.655341 -276.716168)
			(xy 54.687976 -276.679331) (xy 54.726097 -276.648206) (xy 54.768718 -276.623599) (xy 54.814734 -276.606147)
			(xy 54.862953 -276.596303) (xy 54.912128 -276.594322) (xy 54.960983 -276.600254) (xy 55.008254 -276.613946)
			(xy 55.052716 -276.635044) (xy 55.093219 -276.663) (xy 55.128712 -276.697092) (xy 55.158277 -276.736436)
			(xy 55.181148 -276.780013) (xy 55.196732 -276.826694) (xy 55.204627 -276.875271) (xy 55.205122 -276.899878)
			(xy 55.54397 -276.899878) (xy 55.54793 -276.850824) (xy 55.559707 -276.80304) (xy 55.578998 -276.757764)
			(xy 55.605301 -276.716168) (xy 55.637936 -276.679331) (xy 55.676057 -276.648206) (xy 55.718678 -276.623599)
			(xy 55.764694 -276.606147) (xy 55.812913 -276.596303) (xy 55.862088 -276.594322) (xy 55.910943 -276.600254)
			(xy 55.958214 -276.613946) (xy 56.002676 -276.635044) (xy 56.043179 -276.663) (xy 56.078672 -276.697092)
			(xy 56.108237 -276.736436) (xy 56.131108 -276.780013) (xy 56.146692 -276.826694) (xy 56.154587 -276.875271)
			(xy 56.155082 -276.899878) (xy 56.494184 -276.899878) (xy 56.498144 -276.850824) (xy 56.509921 -276.80304)
			(xy 56.529212 -276.757764) (xy 56.555515 -276.716168) (xy 56.58815 -276.679331) (xy 56.626271 -276.648206)
			(xy 56.668892 -276.623599) (xy 56.714908 -276.606147) (xy 56.763127 -276.596303) (xy 56.812302 -276.594322)
			(xy 56.861157 -276.600254) (xy 56.908428 -276.613946) (xy 56.95289 -276.635044) (xy 56.993393 -276.663)
			(xy 57.028886 -276.697092) (xy 57.058451 -276.736436) (xy 57.081322 -276.780013) (xy 57.096906 -276.826694)
			(xy 57.104801 -276.875271) (xy 57.105296 -276.899878) (xy 57.104801 -276.924485) (xy 57.096906 -276.973062)
			(xy 57.081322 -277.019743) (xy 57.058451 -277.06332) (xy 57.028886 -277.102664) (xy 56.993393 -277.136756)
			(xy 56.95289 -277.164712) (xy 56.908428 -277.18581) (xy 56.861157 -277.199502) (xy 56.812302 -277.205434)
			(xy 56.763127 -277.203453) (xy 56.714908 -277.193609) (xy 56.668892 -277.176157) (xy 56.626271 -277.15155)
			(xy 56.58815 -277.120425) (xy 56.555515 -277.083588) (xy 56.529212 -277.041992) (xy 56.509921 -276.996716)
			(xy 56.498144 -276.948932) (xy 56.494184 -276.899878) (xy 56.155082 -276.899878) (xy 56.154587 -276.924485)
			(xy 56.146692 -276.973062) (xy 56.131108 -277.019743) (xy 56.108237 -277.06332) (xy 56.078672 -277.102664)
			(xy 56.043179 -277.136756) (xy 56.002676 -277.164712) (xy 55.958214 -277.18581) (xy 55.910943 -277.199502)
			(xy 55.862088 -277.205434) (xy 55.812913 -277.203453) (xy 55.764694 -277.193609) (xy 55.718678 -277.176157)
			(xy 55.676057 -277.15155) (xy 55.637936 -277.120425) (xy 55.605301 -277.083588) (xy 55.578998 -277.041992)
			(xy 55.559707 -276.996716) (xy 55.54793 -276.948932) (xy 55.54397 -276.899878) (xy 55.205122 -276.899878)
			(xy 55.204627 -276.924485) (xy 55.196732 -276.973062) (xy 55.181148 -277.019743) (xy 55.158277 -277.06332)
			(xy 55.128712 -277.102664) (xy 55.093219 -277.136756) (xy 55.052716 -277.164712) (xy 55.008254 -277.18581)
			(xy 54.960983 -277.199502) (xy 54.912128 -277.205434) (xy 54.862953 -277.203453) (xy 54.814734 -277.193609)
			(xy 54.768718 -277.176157) (xy 54.726097 -277.15155) (xy 54.687976 -277.120425) (xy 54.655341 -277.083588)
			(xy 54.629038 -277.041992) (xy 54.609747 -276.996716) (xy 54.59797 -276.948932) (xy 54.59401 -276.899878)
			(xy 54.255162 -276.899878) (xy 54.254667 -276.924485) (xy 54.246772 -276.973062) (xy 54.231188 -277.019743)
			(xy 54.208317 -277.06332) (xy 54.178752 -277.102664) (xy 54.143259 -277.136756) (xy 54.102756 -277.164712)
			(xy 54.058294 -277.18581) (xy 54.011023 -277.199502) (xy 53.962168 -277.205434) (xy 53.912993 -277.203453)
			(xy 53.864774 -277.193609) (xy 53.818758 -277.176157) (xy 53.776137 -277.15155) (xy 53.738016 -277.120425)
			(xy 53.705381 -277.083588) (xy 53.679078 -277.041992) (xy 53.659787 -276.996716) (xy 53.64801 -276.948932)
			(xy 53.64405 -276.899878) (xy 53.305202 -276.899878) (xy 53.304707 -276.924485) (xy 53.296812 -276.973062)
			(xy 53.281228 -277.019743) (xy 53.258357 -277.06332) (xy 53.228792 -277.102664) (xy 53.193299 -277.136756)
			(xy 53.152796 -277.164712) (xy 53.108334 -277.18581) (xy 53.061063 -277.199502) (xy 53.012208 -277.205434)
			(xy 52.963033 -277.203453) (xy 52.914814 -277.193609) (xy 52.868798 -277.176157) (xy 52.826177 -277.15155)
			(xy 52.788056 -277.120425) (xy 52.755421 -277.083588) (xy 52.729118 -277.041992) (xy 52.709827 -276.996716)
			(xy 52.69805 -276.948932) (xy 52.69409 -276.899878) (xy 52.355242 -276.899878) (xy 52.354747 -276.924485)
			(xy 52.346852 -276.973062) (xy 52.331268 -277.019743) (xy 52.308397 -277.06332) (xy 52.278832 -277.102664)
			(xy 52.243339 -277.136756) (xy 52.202836 -277.164712) (xy 52.158374 -277.18581) (xy 52.111103 -277.199502)
			(xy 52.062248 -277.205434) (xy 52.013073 -277.203453) (xy 51.964854 -277.193609) (xy 51.918838 -277.176157)
			(xy 51.876217 -277.15155) (xy 51.838096 -277.120425) (xy 51.805461 -277.083588) (xy 51.779158 -277.041992)
			(xy 51.759867 -276.996716) (xy 51.74809 -276.948932) (xy 51.74413 -276.899878) (xy 51.405282 -276.899878)
			(xy 51.404787 -276.924485) (xy 51.396892 -276.973062) (xy 51.381308 -277.019743) (xy 51.358437 -277.06332)
			(xy 51.328872 -277.102664) (xy 51.293379 -277.136756) (xy 51.252876 -277.164712) (xy 51.208414 -277.18581)
			(xy 51.161143 -277.199502) (xy 51.112288 -277.205434) (xy 51.063113 -277.203453) (xy 51.014894 -277.193609)
			(xy 50.968878 -277.176157) (xy 50.926257 -277.15155) (xy 50.888136 -277.120425) (xy 50.855501 -277.083588)
			(xy 50.829198 -277.041992) (xy 50.809907 -276.996716) (xy 50.79813 -276.948932) (xy 50.79417 -276.899878)
			(xy 50.455068 -276.899878) (xy 50.454573 -276.924485) (xy 50.446678 -276.973062) (xy 50.431094 -277.019743)
			(xy 50.408223 -277.06332) (xy 50.378658 -277.102664) (xy 50.343165 -277.136756) (xy 50.302662 -277.164712)
			(xy 50.2582 -277.18581) (xy 50.210929 -277.199502) (xy 50.162074 -277.205434) (xy 50.112899 -277.203453)
			(xy 50.06468 -277.193609) (xy 50.018664 -277.176157) (xy 49.976043 -277.15155) (xy 49.937922 -277.120425)
			(xy 49.905287 -277.083588) (xy 49.878984 -277.041992) (xy 49.859693 -276.996716) (xy 49.847916 -276.948932)
			(xy 49.843956 -276.899878) (xy 49.505108 -276.899878) (xy 49.504613 -276.924485) (xy 49.496718 -276.973062)
			(xy 49.481134 -277.019743) (xy 49.458263 -277.06332) (xy 49.428698 -277.102664) (xy 49.393205 -277.136756)
			(xy 49.352702 -277.164712) (xy 49.30824 -277.18581) (xy 49.260969 -277.199502) (xy 49.212114 -277.205434)
			(xy 49.162939 -277.203453) (xy 49.11472 -277.193609) (xy 49.068704 -277.176157) (xy 49.026083 -277.15155)
			(xy 48.987962 -277.120425) (xy 48.955327 -277.083588) (xy 48.929024 -277.041992) (xy 48.909733 -276.996716)
			(xy 48.897956 -276.948932) (xy 48.893996 -276.899878) (xy 48.555148 -276.899878) (xy 48.554653 -276.924485)
			(xy 48.546758 -276.973062) (xy 48.531174 -277.019743) (xy 48.508303 -277.06332) (xy 48.478738 -277.102664)
			(xy 48.443245 -277.136756) (xy 48.402742 -277.164712) (xy 48.35828 -277.18581) (xy 48.311009 -277.199502)
			(xy 48.262154 -277.205434) (xy 48.212979 -277.203453) (xy 48.16476 -277.193609) (xy 48.118744 -277.176157)
			(xy 48.076123 -277.15155) (xy 48.038002 -277.120425) (xy 48.005367 -277.083588) (xy 47.979064 -277.041992)
			(xy 47.959773 -276.996716) (xy 47.947996 -276.948932) (xy 47.944036 -276.899878) (xy 47.605188 -276.899878)
			(xy 47.604693 -276.924485) (xy 47.596798 -276.973062) (xy 47.581214 -277.019743) (xy 47.558343 -277.06332)
			(xy 47.528778 -277.102664) (xy 47.493285 -277.136756) (xy 47.452782 -277.164712) (xy 47.40832 -277.18581)
			(xy 47.361049 -277.199502) (xy 47.312194 -277.205434) (xy 47.263019 -277.203453) (xy 47.2148 -277.193609)
			(xy 47.168784 -277.176157) (xy 47.126163 -277.15155) (xy 47.088042 -277.120425) (xy 47.055407 -277.083588)
			(xy 47.029104 -277.041992) (xy 47.009813 -276.996716) (xy 46.998036 -276.948932) (xy 46.994076 -276.899878)
			(xy 46.655228 -276.899878) (xy 46.654733 -276.924485) (xy 46.646838 -276.973062) (xy 46.631254 -277.019743)
			(xy 46.608383 -277.06332) (xy 46.578818 -277.102664) (xy 46.543325 -277.136756) (xy 46.502822 -277.164712)
			(xy 46.45836 -277.18581) (xy 46.411089 -277.199502) (xy 46.362234 -277.205434) (xy 46.313059 -277.203453)
			(xy 46.26484 -277.193609) (xy 46.218824 -277.176157) (xy 46.176203 -277.15155) (xy 46.138082 -277.120425)
			(xy 46.105447 -277.083588) (xy 46.079144 -277.041992) (xy 46.059853 -276.996716) (xy 46.048076 -276.948932)
			(xy 46.044116 -276.899878) (xy 45.705268 -276.899878) (xy 45.704773 -276.924485) (xy 45.696878 -276.973062)
			(xy 45.681294 -277.019743) (xy 45.658423 -277.06332) (xy 45.628858 -277.102664) (xy 45.593365 -277.136756)
			(xy 45.552862 -277.164712) (xy 45.5084 -277.18581) (xy 45.461129 -277.199502) (xy 45.412274 -277.205434)
			(xy 45.363099 -277.203453) (xy 45.31488 -277.193609) (xy 45.268864 -277.176157) (xy 45.226243 -277.15155)
			(xy 45.188122 -277.120425) (xy 45.155487 -277.083588) (xy 45.129184 -277.041992) (xy 45.109893 -276.996716)
			(xy 45.098116 -276.948932) (xy 45.094156 -276.899878) (xy 44.755054 -276.899878) (xy 44.754559 -276.924485)
			(xy 44.746664 -276.973062) (xy 44.73108 -277.019743) (xy 44.708209 -277.06332) (xy 44.678644 -277.102664)
			(xy 44.643151 -277.136756) (xy 44.602648 -277.164712) (xy 44.558186 -277.18581) (xy 44.510915 -277.199502)
			(xy 44.46206 -277.205434) (xy 44.412885 -277.203453) (xy 44.364666 -277.193609) (xy 44.31865 -277.176157)
			(xy 44.276029 -277.15155) (xy 44.237908 -277.120425) (xy 44.205273 -277.083588) (xy 44.17897 -277.041992)
			(xy 44.159679 -276.996716) (xy 44.147902 -276.948932) (xy 44.143942 -276.899878) (xy 43.805094 -276.899878)
			(xy 43.804599 -276.924485) (xy 43.796704 -276.973062) (xy 43.78112 -277.019743) (xy 43.758249 -277.06332)
			(xy 43.728684 -277.102664) (xy 43.693191 -277.136756) (xy 43.652688 -277.164712) (xy 43.608226 -277.18581)
			(xy 43.560955 -277.199502) (xy 43.5121 -277.205434) (xy 43.462925 -277.203453) (xy 43.414706 -277.193609)
			(xy 43.36869 -277.176157) (xy 43.326069 -277.15155) (xy 43.287948 -277.120425) (xy 43.255313 -277.083588)
			(xy 43.22901 -277.041992) (xy 43.209719 -276.996716) (xy 43.197942 -276.948932) (xy 43.193982 -276.899878)
			(xy 15.798881 -276.899878) (xy 15.845075 -276.904961) (xy 15.899032 -276.919067) (xy 15.950361 -276.940879)
			(xy 15.997967 -276.969933) (xy 16.040835 -277.005608) (xy 16.078052 -277.047145) (xy 16.108825 -277.093658)
			(xy 16.132497 -277.144155) (xy 16.148565 -277.197562) (xy 16.156685 -277.252738) (xy 16.157194 -277.280624)
			(xy 16.156685 -277.30851) (xy 16.148565 -277.363686) (xy 16.145204 -277.374858) (xy 36.069028 -277.374858)
			(xy 36.072988 -277.325804) (xy 36.084765 -277.27802) (xy 36.104056 -277.232744) (xy 36.130359 -277.191148)
			(xy 36.162994 -277.154311) (xy 36.201115 -277.123186) (xy 36.243736 -277.098579) (xy 36.289752 -277.081127)
			(xy 36.337971 -277.071283) (xy 36.387146 -277.069302) (xy 36.436001 -277.075234) (xy 36.483272 -277.088926)
			(xy 36.527734 -277.110024) (xy 36.568237 -277.13798) (xy 36.60373 -277.172072) (xy 36.633295 -277.211416)
			(xy 36.656166 -277.254993) (xy 36.67175 -277.301674) (xy 36.679645 -277.350251) (xy 36.68014 -277.374858)
			(xy 37.018988 -277.374858) (xy 37.022948 -277.325804) (xy 37.034725 -277.27802) (xy 37.054016 -277.232744)
			(xy 37.080319 -277.191148) (xy 37.112954 -277.154311) (xy 37.151075 -277.123186) (xy 37.193696 -277.098579)
			(xy 37.239712 -277.081127) (xy 37.287931 -277.071283) (xy 37.337106 -277.069302) (xy 37.385961 -277.075234)
			(xy 37.433232 -277.088926) (xy 37.477694 -277.110024) (xy 37.518197 -277.13798) (xy 37.55369 -277.172072)
			(xy 37.583255 -277.211416) (xy 37.606126 -277.254993) (xy 37.62171 -277.301674) (xy 37.629605 -277.350251)
			(xy 37.6301 -277.374858) (xy 37.969202 -277.374858) (xy 37.973162 -277.325804) (xy 37.984939 -277.27802)
			(xy 38.00423 -277.232744) (xy 38.030533 -277.191148) (xy 38.063168 -277.154311) (xy 38.101289 -277.123186)
			(xy 38.14391 -277.098579) (xy 38.189926 -277.081127) (xy 38.238145 -277.071283) (xy 38.28732 -277.069302)
			(xy 38.336175 -277.075234) (xy 38.383446 -277.088926) (xy 38.427908 -277.110024) (xy 38.468411 -277.13798)
			(xy 38.503904 -277.172072) (xy 38.533469 -277.211416) (xy 38.55634 -277.254993) (xy 38.571924 -277.301674)
			(xy 38.579819 -277.350251) (xy 38.580314 -277.374858) (xy 38.919162 -277.374858) (xy 38.923122 -277.325804)
			(xy 38.934899 -277.27802) (xy 38.95419 -277.232744) (xy 38.980493 -277.191148) (xy 39.013128 -277.154311)
			(xy 39.051249 -277.123186) (xy 39.09387 -277.098579) (xy 39.139886 -277.081127) (xy 39.188105 -277.071283)
			(xy 39.23728 -277.069302) (xy 39.286135 -277.075234) (xy 39.333406 -277.088926) (xy 39.377868 -277.110024)
			(xy 39.418371 -277.13798) (xy 39.453864 -277.172072) (xy 39.483429 -277.211416) (xy 39.5063 -277.254993)
			(xy 39.521884 -277.301674) (xy 39.529779 -277.350251) (xy 39.530274 -277.374858) (xy 39.869122 -277.374858)
			(xy 39.873082 -277.325804) (xy 39.884859 -277.27802) (xy 39.90415 -277.232744) (xy 39.930453 -277.191148)
			(xy 39.963088 -277.154311) (xy 40.001209 -277.123186) (xy 40.04383 -277.098579) (xy 40.089846 -277.081127)
			(xy 40.138065 -277.071283) (xy 40.18724 -277.069302) (xy 40.236095 -277.075234) (xy 40.283366 -277.088926)
			(xy 40.327828 -277.110024) (xy 40.368331 -277.13798) (xy 40.403824 -277.172072) (xy 40.433389 -277.211416)
			(xy 40.45626 -277.254993) (xy 40.471844 -277.301674) (xy 40.479739 -277.350251) (xy 40.480234 -277.374858)
			(xy 40.819082 -277.374858) (xy 40.823042 -277.325804) (xy 40.834819 -277.27802) (xy 40.85411 -277.232744)
			(xy 40.880413 -277.191148) (xy 40.913048 -277.154311) (xy 40.951169 -277.123186) (xy 40.99379 -277.098579)
			(xy 41.039806 -277.081127) (xy 41.088025 -277.071283) (xy 41.1372 -277.069302) (xy 41.186055 -277.075234)
			(xy 41.233326 -277.088926) (xy 41.277788 -277.110024) (xy 41.318291 -277.13798) (xy 41.353784 -277.172072)
			(xy 41.383349 -277.211416) (xy 41.40622 -277.254993) (xy 41.421804 -277.301674) (xy 41.429699 -277.350251)
			(xy 41.430194 -277.374858) (xy 41.769042 -277.374858) (xy 41.773002 -277.325804) (xy 41.784779 -277.27802)
			(xy 41.80407 -277.232744) (xy 41.830373 -277.191148) (xy 41.863008 -277.154311) (xy 41.901129 -277.123186)
			(xy 41.94375 -277.098579) (xy 41.989766 -277.081127) (xy 42.037985 -277.071283) (xy 42.08716 -277.069302)
			(xy 42.136015 -277.075234) (xy 42.183286 -277.088926) (xy 42.227748 -277.110024) (xy 42.268251 -277.13798)
			(xy 42.303744 -277.172072) (xy 42.333309 -277.211416) (xy 42.35618 -277.254993) (xy 42.371764 -277.301674)
			(xy 42.379659 -277.350251) (xy 42.380154 -277.374858) (xy 42.379659 -277.399465) (xy 42.371764 -277.448042)
			(xy 42.35618 -277.494723) (xy 42.333309 -277.5383) (xy 42.303744 -277.577644) (xy 42.268251 -277.611736)
			(xy 42.227748 -277.639692) (xy 42.183286 -277.66079) (xy 42.136015 -277.674482) (xy 42.08716 -277.680414)
			(xy 42.037985 -277.678433) (xy 41.989766 -277.668589) (xy 41.94375 -277.651137) (xy 41.901129 -277.62653)
			(xy 41.863008 -277.595405) (xy 41.830373 -277.558568) (xy 41.80407 -277.516972) (xy 41.784779 -277.471696)
			(xy 41.773002 -277.423912) (xy 41.769042 -277.374858) (xy 41.430194 -277.374858) (xy 41.429699 -277.399465)
			(xy 41.421804 -277.448042) (xy 41.40622 -277.494723) (xy 41.383349 -277.5383) (xy 41.353784 -277.577644)
			(xy 41.318291 -277.611736) (xy 41.277788 -277.639692) (xy 41.233326 -277.66079) (xy 41.186055 -277.674482)
			(xy 41.1372 -277.680414) (xy 41.088025 -277.678433) (xy 41.039806 -277.668589) (xy 40.99379 -277.651137)
			(xy 40.951169 -277.62653) (xy 40.913048 -277.595405) (xy 40.880413 -277.558568) (xy 40.85411 -277.516972)
			(xy 40.834819 -277.471696) (xy 40.823042 -277.423912) (xy 40.819082 -277.374858) (xy 40.480234 -277.374858)
			(xy 40.479739 -277.399465) (xy 40.471844 -277.448042) (xy 40.45626 -277.494723) (xy 40.433389 -277.5383)
			(xy 40.403824 -277.577644) (xy 40.368331 -277.611736) (xy 40.327828 -277.639692) (xy 40.283366 -277.66079)
			(xy 40.236095 -277.674482) (xy 40.18724 -277.680414) (xy 40.138065 -277.678433) (xy 40.089846 -277.668589)
			(xy 40.04383 -277.651137) (xy 40.001209 -277.62653) (xy 39.963088 -277.595405) (xy 39.930453 -277.558568)
			(xy 39.90415 -277.516972) (xy 39.884859 -277.471696) (xy 39.873082 -277.423912) (xy 39.869122 -277.374858)
			(xy 39.530274 -277.374858) (xy 39.529779 -277.399465) (xy 39.521884 -277.448042) (xy 39.5063 -277.494723)
			(xy 39.483429 -277.5383) (xy 39.453864 -277.577644) (xy 39.418371 -277.611736) (xy 39.377868 -277.639692)
			(xy 39.333406 -277.66079) (xy 39.286135 -277.674482) (xy 39.23728 -277.680414) (xy 39.188105 -277.678433)
			(xy 39.139886 -277.668589) (xy 39.09387 -277.651137) (xy 39.051249 -277.62653) (xy 39.013128 -277.595405)
			(xy 38.980493 -277.558568) (xy 38.95419 -277.516972) (xy 38.934899 -277.471696) (xy 38.923122 -277.423912)
			(xy 38.919162 -277.374858) (xy 38.580314 -277.374858) (xy 38.579819 -277.399465) (xy 38.571924 -277.448042)
			(xy 38.55634 -277.494723) (xy 38.533469 -277.5383) (xy 38.503904 -277.577644) (xy 38.468411 -277.611736)
			(xy 38.427908 -277.639692) (xy 38.383446 -277.66079) (xy 38.336175 -277.674482) (xy 38.28732 -277.680414)
			(xy 38.238145 -277.678433) (xy 38.189926 -277.668589) (xy 38.14391 -277.651137) (xy 38.101289 -277.62653)
			(xy 38.063168 -277.595405) (xy 38.030533 -277.558568) (xy 38.00423 -277.516972) (xy 37.984939 -277.471696)
			(xy 37.973162 -277.423912) (xy 37.969202 -277.374858) (xy 37.6301 -277.374858) (xy 37.629605 -277.399465)
			(xy 37.62171 -277.448042) (xy 37.606126 -277.494723) (xy 37.583255 -277.5383) (xy 37.55369 -277.577644)
			(xy 37.518197 -277.611736) (xy 37.477694 -277.639692) (xy 37.433232 -277.66079) (xy 37.385961 -277.674482)
			(xy 37.337106 -277.680414) (xy 37.287931 -277.678433) (xy 37.239712 -277.668589) (xy 37.193696 -277.651137)
			(xy 37.151075 -277.62653) (xy 37.112954 -277.595405) (xy 37.080319 -277.558568) (xy 37.054016 -277.516972)
			(xy 37.034725 -277.471696) (xy 37.022948 -277.423912) (xy 37.018988 -277.374858) (xy 36.68014 -277.374858)
			(xy 36.679645 -277.399465) (xy 36.67175 -277.448042) (xy 36.656166 -277.494723) (xy 36.633295 -277.5383)
			(xy 36.60373 -277.577644) (xy 36.568237 -277.611736) (xy 36.527734 -277.639692) (xy 36.483272 -277.66079)
			(xy 36.436001 -277.674482) (xy 36.387146 -277.680414) (xy 36.337971 -277.678433) (xy 36.289752 -277.668589)
			(xy 36.243736 -277.651137) (xy 36.201115 -277.62653) (xy 36.162994 -277.595405) (xy 36.130359 -277.558568)
			(xy 36.104056 -277.516972) (xy 36.084765 -277.471696) (xy 36.072988 -277.423912) (xy 36.069028 -277.374858)
			(xy 16.145204 -277.374858) (xy 16.132497 -277.417093) (xy 16.108825 -277.46759) (xy 16.078052 -277.514103)
			(xy 16.040835 -277.55564) (xy 15.997967 -277.591315) (xy 15.950361 -277.620369) (xy 15.899032 -277.642181)
			(xy 15.845075 -277.656287) (xy 15.789638 -277.662387) (xy 15.733904 -277.66035) (xy 15.679061 -277.65022)
			(xy 15.626277 -277.632213) (xy 15.576677 -277.606712) (xy 15.531319 -277.574261) (xy 15.49117 -277.535552)
			(xy 15.457084 -277.491409) (xy 15.429788 -277.442774) (xy 15.409865 -277.390683) (xy 15.397739 -277.336246)
			(xy 15.393668 -277.280624) (xy 1.912446 -277.280624) (xy 1.919951 -277.330097) (xy 1.920494 -277.358856)
			(xy 1.919971 -277.387615) (xy 1.911335 -277.44448) (xy 1.894261 -277.499406) (xy 1.869136 -277.551146)
			(xy 1.83653 -277.598529) (xy 1.797181 -277.64048) (xy 1.751981 -277.67605) (xy 1.701954 -277.704433)
			(xy 1.648233 -277.724984) (xy 1.592036 -277.73724) (xy 1.56337 -277.739602) (xy 1.553464 -277.74011)
			(xy 1.536446 -277.748238) (xy 1.48209 -277.80615) (xy 1.475808 -277.81344) (xy 1.475478 -277.814278)
			(xy 9.324846 -277.814278) (xy 9.328917 -277.758656) (xy 9.341043 -277.704219) (xy 9.360966 -277.652128)
			(xy 9.388262 -277.603493) (xy 9.422348 -277.55935) (xy 9.462497 -277.520641) (xy 9.507855 -277.48819)
			(xy 9.557455 -277.462689) (xy 9.610239 -277.444682) (xy 9.665082 -277.434552) (xy 9.720816 -277.432515)
			(xy 9.776253 -277.438615) (xy 9.83021 -277.452721) (xy 9.881539 -277.474533) (xy 9.929145 -277.503587)
			(xy 9.972013 -277.539262) (xy 10.00923 -277.580799) (xy 10.040003 -277.627312) (xy 10.063675 -277.677809)
			(xy 10.079743 -277.731216) (xy 10.087863 -277.786392) (xy 10.088372 -277.814278) (xy 11.344146 -277.814278)
			(xy 11.348217 -277.758656) (xy 11.360343 -277.704219) (xy 11.380266 -277.652128) (xy 11.407562 -277.603493)
			(xy 11.441648 -277.55935) (xy 11.481797 -277.520641) (xy 11.527155 -277.48819) (xy 11.576755 -277.462689)
			(xy 11.629539 -277.444682) (xy 11.684382 -277.434552) (xy 11.740116 -277.432515) (xy 11.795553 -277.438615)
			(xy 11.84951 -277.452721) (xy 11.900839 -277.474533) (xy 11.948445 -277.503587) (xy 11.991313 -277.539262)
			(xy 12.02853 -277.580799) (xy 12.059303 -277.627312) (xy 12.082975 -277.677809) (xy 12.099043 -277.731216)
			(xy 12.107163 -277.786392) (xy 12.107672 -277.814278) (xy 12.107163 -277.842164) (xy 12.106034 -277.849838)
			(xy 43.193982 -277.849838) (xy 43.197942 -277.800784) (xy 43.209719 -277.753) (xy 43.22901 -277.707724)
			(xy 43.255313 -277.666128) (xy 43.287948 -277.629291) (xy 43.326069 -277.598166) (xy 43.36869 -277.573559)
			(xy 43.414706 -277.556107) (xy 43.462925 -277.546263) (xy 43.5121 -277.544282) (xy 43.560955 -277.550214)
			(xy 43.608226 -277.563906) (xy 43.652688 -277.585004) (xy 43.693191 -277.61296) (xy 43.728684 -277.647052)
			(xy 43.758249 -277.686396) (xy 43.78112 -277.729973) (xy 43.796704 -277.776654) (xy 43.804599 -277.825231)
			(xy 43.805094 -277.849838) (xy 44.143942 -277.849838) (xy 44.147902 -277.800784) (xy 44.159679 -277.753)
			(xy 44.17897 -277.707724) (xy 44.205273 -277.666128) (xy 44.237908 -277.629291) (xy 44.276029 -277.598166)
			(xy 44.31865 -277.573559) (xy 44.364666 -277.556107) (xy 44.412885 -277.546263) (xy 44.46206 -277.544282)
			(xy 44.510915 -277.550214) (xy 44.558186 -277.563906) (xy 44.602648 -277.585004) (xy 44.643151 -277.61296)
			(xy 44.678644 -277.647052) (xy 44.708209 -277.686396) (xy 44.73108 -277.729973) (xy 44.746664 -277.776654)
			(xy 44.754559 -277.825231) (xy 44.755054 -277.849838) (xy 45.094156 -277.849838) (xy 45.098116 -277.800784)
			(xy 45.109893 -277.753) (xy 45.129184 -277.707724) (xy 45.155487 -277.666128) (xy 45.188122 -277.629291)
			(xy 45.226243 -277.598166) (xy 45.268864 -277.573559) (xy 45.31488 -277.556107) (xy 45.363099 -277.546263)
			(xy 45.412274 -277.544282) (xy 45.461129 -277.550214) (xy 45.5084 -277.563906) (xy 45.552862 -277.585004)
			(xy 45.593365 -277.61296) (xy 45.628858 -277.647052) (xy 45.658423 -277.686396) (xy 45.681294 -277.729973)
			(xy 45.696878 -277.776654) (xy 45.704773 -277.825231) (xy 45.705268 -277.849838) (xy 46.044116 -277.849838)
			(xy 46.048076 -277.800784) (xy 46.059853 -277.753) (xy 46.079144 -277.707724) (xy 46.105447 -277.666128)
			(xy 46.138082 -277.629291) (xy 46.176203 -277.598166) (xy 46.218824 -277.573559) (xy 46.26484 -277.556107)
			(xy 46.313059 -277.546263) (xy 46.362234 -277.544282) (xy 46.411089 -277.550214) (xy 46.45836 -277.563906)
			(xy 46.502822 -277.585004) (xy 46.543325 -277.61296) (xy 46.578818 -277.647052) (xy 46.608383 -277.686396)
			(xy 46.631254 -277.729973) (xy 46.646838 -277.776654) (xy 46.654733 -277.825231) (xy 46.655228 -277.849838)
			(xy 46.994076 -277.849838) (xy 46.998036 -277.800784) (xy 47.009813 -277.753) (xy 47.029104 -277.707724)
			(xy 47.055407 -277.666128) (xy 47.088042 -277.629291) (xy 47.126163 -277.598166) (xy 47.168784 -277.573559)
			(xy 47.2148 -277.556107) (xy 47.263019 -277.546263) (xy 47.312194 -277.544282) (xy 47.361049 -277.550214)
			(xy 47.40832 -277.563906) (xy 47.452782 -277.585004) (xy 47.493285 -277.61296) (xy 47.528778 -277.647052)
			(xy 47.558343 -277.686396) (xy 47.581214 -277.729973) (xy 47.596798 -277.776654) (xy 47.604693 -277.825231)
			(xy 47.605188 -277.849838) (xy 47.944036 -277.849838) (xy 47.947996 -277.800784) (xy 47.959773 -277.753)
			(xy 47.979064 -277.707724) (xy 48.005367 -277.666128) (xy 48.038002 -277.629291) (xy 48.076123 -277.598166)
			(xy 48.118744 -277.573559) (xy 48.16476 -277.556107) (xy 48.212979 -277.546263) (xy 48.262154 -277.544282)
			(xy 48.311009 -277.550214) (xy 48.35828 -277.563906) (xy 48.402742 -277.585004) (xy 48.443245 -277.61296)
			(xy 48.478738 -277.647052) (xy 48.508303 -277.686396) (xy 48.531174 -277.729973) (xy 48.546758 -277.776654)
			(xy 48.554653 -277.825231) (xy 48.555148 -277.849838) (xy 48.893996 -277.849838) (xy 48.897956 -277.800784)
			(xy 48.909733 -277.753) (xy 48.929024 -277.707724) (xy 48.955327 -277.666128) (xy 48.987962 -277.629291)
			(xy 49.026083 -277.598166) (xy 49.068704 -277.573559) (xy 49.11472 -277.556107) (xy 49.162939 -277.546263)
			(xy 49.212114 -277.544282) (xy 49.260969 -277.550214) (xy 49.30824 -277.563906) (xy 49.352702 -277.585004)
			(xy 49.393205 -277.61296) (xy 49.428698 -277.647052) (xy 49.458263 -277.686396) (xy 49.481134 -277.729973)
			(xy 49.496718 -277.776654) (xy 49.504613 -277.825231) (xy 49.505108 -277.849838) (xy 49.843956 -277.849838)
			(xy 49.847916 -277.800784) (xy 49.859693 -277.753) (xy 49.878984 -277.707724) (xy 49.905287 -277.666128)
			(xy 49.937922 -277.629291) (xy 49.976043 -277.598166) (xy 50.018664 -277.573559) (xy 50.06468 -277.556107)
			(xy 50.112899 -277.546263) (xy 50.162074 -277.544282) (xy 50.210929 -277.550214) (xy 50.2582 -277.563906)
			(xy 50.302662 -277.585004) (xy 50.343165 -277.61296) (xy 50.378658 -277.647052) (xy 50.408223 -277.686396)
			(xy 50.431094 -277.729973) (xy 50.446678 -277.776654) (xy 50.454573 -277.825231) (xy 50.455068 -277.849838)
			(xy 50.79417 -277.849838) (xy 50.79813 -277.800784) (xy 50.809907 -277.753) (xy 50.829198 -277.707724)
			(xy 50.855501 -277.666128) (xy 50.888136 -277.629291) (xy 50.926257 -277.598166) (xy 50.968878 -277.573559)
			(xy 51.014894 -277.556107) (xy 51.063113 -277.546263) (xy 51.112288 -277.544282) (xy 51.161143 -277.550214)
			(xy 51.208414 -277.563906) (xy 51.252876 -277.585004) (xy 51.293379 -277.61296) (xy 51.328872 -277.647052)
			(xy 51.358437 -277.686396) (xy 51.381308 -277.729973) (xy 51.396892 -277.776654) (xy 51.404787 -277.825231)
			(xy 51.405282 -277.849838) (xy 51.74413 -277.849838) (xy 51.74809 -277.800784) (xy 51.759867 -277.753)
			(xy 51.779158 -277.707724) (xy 51.805461 -277.666128) (xy 51.838096 -277.629291) (xy 51.876217 -277.598166)
			(xy 51.918838 -277.573559) (xy 51.964854 -277.556107) (xy 52.013073 -277.546263) (xy 52.062248 -277.544282)
			(xy 52.111103 -277.550214) (xy 52.158374 -277.563906) (xy 52.202836 -277.585004) (xy 52.243339 -277.61296)
			(xy 52.278832 -277.647052) (xy 52.308397 -277.686396) (xy 52.331268 -277.729973) (xy 52.346852 -277.776654)
			(xy 52.354747 -277.825231) (xy 52.355242 -277.849838) (xy 52.69409 -277.849838) (xy 52.69805 -277.800784)
			(xy 52.709827 -277.753) (xy 52.729118 -277.707724) (xy 52.755421 -277.666128) (xy 52.788056 -277.629291)
			(xy 52.826177 -277.598166) (xy 52.868798 -277.573559) (xy 52.914814 -277.556107) (xy 52.963033 -277.546263)
			(xy 53.012208 -277.544282) (xy 53.061063 -277.550214) (xy 53.108334 -277.563906) (xy 53.152796 -277.585004)
			(xy 53.193299 -277.61296) (xy 53.228792 -277.647052) (xy 53.258357 -277.686396) (xy 53.281228 -277.729973)
			(xy 53.296812 -277.776654) (xy 53.304707 -277.825231) (xy 53.305202 -277.849838) (xy 53.64405 -277.849838)
			(xy 53.64801 -277.800784) (xy 53.659787 -277.753) (xy 53.679078 -277.707724) (xy 53.705381 -277.666128)
			(xy 53.738016 -277.629291) (xy 53.776137 -277.598166) (xy 53.818758 -277.573559) (xy 53.864774 -277.556107)
			(xy 53.912993 -277.546263) (xy 53.962168 -277.544282) (xy 54.011023 -277.550214) (xy 54.058294 -277.563906)
			(xy 54.102756 -277.585004) (xy 54.143259 -277.61296) (xy 54.178752 -277.647052) (xy 54.208317 -277.686396)
			(xy 54.231188 -277.729973) (xy 54.246772 -277.776654) (xy 54.254667 -277.825231) (xy 54.255162 -277.849838)
			(xy 54.59401 -277.849838) (xy 54.59797 -277.800784) (xy 54.609747 -277.753) (xy 54.629038 -277.707724)
			(xy 54.655341 -277.666128) (xy 54.687976 -277.629291) (xy 54.726097 -277.598166) (xy 54.768718 -277.573559)
			(xy 54.814734 -277.556107) (xy 54.862953 -277.546263) (xy 54.912128 -277.544282) (xy 54.960983 -277.550214)
			(xy 55.008254 -277.563906) (xy 55.052716 -277.585004) (xy 55.093219 -277.61296) (xy 55.128712 -277.647052)
			(xy 55.158277 -277.686396) (xy 55.181148 -277.729973) (xy 55.196732 -277.776654) (xy 55.204627 -277.825231)
			(xy 55.205122 -277.849838) (xy 55.54397 -277.849838) (xy 55.54793 -277.800784) (xy 55.559707 -277.753)
			(xy 55.578998 -277.707724) (xy 55.605301 -277.666128) (xy 55.637936 -277.629291) (xy 55.676057 -277.598166)
			(xy 55.718678 -277.573559) (xy 55.764694 -277.556107) (xy 55.812913 -277.546263) (xy 55.862088 -277.544282)
			(xy 55.910943 -277.550214) (xy 55.958214 -277.563906) (xy 56.002676 -277.585004) (xy 56.043179 -277.61296)
			(xy 56.078672 -277.647052) (xy 56.108237 -277.686396) (xy 56.131108 -277.729973) (xy 56.146692 -277.776654)
			(xy 56.154587 -277.825231) (xy 56.155082 -277.849838) (xy 56.494184 -277.849838) (xy 56.498144 -277.800784)
			(xy 56.509921 -277.753) (xy 56.529212 -277.707724) (xy 56.555515 -277.666128) (xy 56.58815 -277.629291)
			(xy 56.626271 -277.598166) (xy 56.668892 -277.573559) (xy 56.714908 -277.556107) (xy 56.763127 -277.546263)
			(xy 56.812302 -277.544282) (xy 56.861157 -277.550214) (xy 56.908428 -277.563906) (xy 56.95289 -277.585004)
			(xy 56.993393 -277.61296) (xy 57.028886 -277.647052) (xy 57.058451 -277.686396) (xy 57.081322 -277.729973)
			(xy 57.096906 -277.776654) (xy 57.104801 -277.825231) (xy 57.105296 -277.849838) (xy 57.104801 -277.874445)
			(xy 57.096906 -277.923022) (xy 57.081322 -277.969703) (xy 57.058451 -278.01328) (xy 57.028886 -278.052624)
			(xy 56.993393 -278.086716) (xy 56.95289 -278.114672) (xy 56.908428 -278.13577) (xy 56.861157 -278.149462)
			(xy 56.812302 -278.155394) (xy 56.763127 -278.153413) (xy 56.714908 -278.143569) (xy 56.668892 -278.126117)
			(xy 56.626271 -278.10151) (xy 56.58815 -278.070385) (xy 56.555515 -278.033548) (xy 56.529212 -277.991952)
			(xy 56.509921 -277.946676) (xy 56.498144 -277.898892) (xy 56.494184 -277.849838) (xy 56.155082 -277.849838)
			(xy 56.154587 -277.874445) (xy 56.146692 -277.923022) (xy 56.131108 -277.969703) (xy 56.108237 -278.01328)
			(xy 56.078672 -278.052624) (xy 56.043179 -278.086716) (xy 56.002676 -278.114672) (xy 55.958214 -278.13577)
			(xy 55.910943 -278.149462) (xy 55.862088 -278.155394) (xy 55.812913 -278.153413) (xy 55.764694 -278.143569)
			(xy 55.718678 -278.126117) (xy 55.676057 -278.10151) (xy 55.637936 -278.070385) (xy 55.605301 -278.033548)
			(xy 55.578998 -277.991952) (xy 55.559707 -277.946676) (xy 55.54793 -277.898892) (xy 55.54397 -277.849838)
			(xy 55.205122 -277.849838) (xy 55.204627 -277.874445) (xy 55.196732 -277.923022) (xy 55.181148 -277.969703)
			(xy 55.158277 -278.01328) (xy 55.128712 -278.052624) (xy 55.093219 -278.086716) (xy 55.052716 -278.114672)
			(xy 55.008254 -278.13577) (xy 54.960983 -278.149462) (xy 54.912128 -278.155394) (xy 54.862953 -278.153413)
			(xy 54.814734 -278.143569) (xy 54.768718 -278.126117) (xy 54.726097 -278.10151) (xy 54.687976 -278.070385)
			(xy 54.655341 -278.033548) (xy 54.629038 -277.991952) (xy 54.609747 -277.946676) (xy 54.59797 -277.898892)
			(xy 54.59401 -277.849838) (xy 54.255162 -277.849838) (xy 54.254667 -277.874445) (xy 54.246772 -277.923022)
			(xy 54.231188 -277.969703) (xy 54.208317 -278.01328) (xy 54.178752 -278.052624) (xy 54.143259 -278.086716)
			(xy 54.102756 -278.114672) (xy 54.058294 -278.13577) (xy 54.011023 -278.149462) (xy 53.962168 -278.155394)
			(xy 53.912993 -278.153413) (xy 53.864774 -278.143569) (xy 53.818758 -278.126117) (xy 53.776137 -278.10151)
			(xy 53.738016 -278.070385) (xy 53.705381 -278.033548) (xy 53.679078 -277.991952) (xy 53.659787 -277.946676)
			(xy 53.64801 -277.898892) (xy 53.64405 -277.849838) (xy 53.305202 -277.849838) (xy 53.304707 -277.874445)
			(xy 53.296812 -277.923022) (xy 53.281228 -277.969703) (xy 53.258357 -278.01328) (xy 53.228792 -278.052624)
			(xy 53.193299 -278.086716) (xy 53.152796 -278.114672) (xy 53.108334 -278.13577) (xy 53.061063 -278.149462)
			(xy 53.012208 -278.155394) (xy 52.963033 -278.153413) (xy 52.914814 -278.143569) (xy 52.868798 -278.126117)
			(xy 52.826177 -278.10151) (xy 52.788056 -278.070385) (xy 52.755421 -278.033548) (xy 52.729118 -277.991952)
			(xy 52.709827 -277.946676) (xy 52.69805 -277.898892) (xy 52.69409 -277.849838) (xy 52.355242 -277.849838)
			(xy 52.354747 -277.874445) (xy 52.346852 -277.923022) (xy 52.331268 -277.969703) (xy 52.308397 -278.01328)
			(xy 52.278832 -278.052624) (xy 52.243339 -278.086716) (xy 52.202836 -278.114672) (xy 52.158374 -278.13577)
			(xy 52.111103 -278.149462) (xy 52.062248 -278.155394) (xy 52.013073 -278.153413) (xy 51.964854 -278.143569)
			(xy 51.918838 -278.126117) (xy 51.876217 -278.10151) (xy 51.838096 -278.070385) (xy 51.805461 -278.033548)
			(xy 51.779158 -277.991952) (xy 51.759867 -277.946676) (xy 51.74809 -277.898892) (xy 51.74413 -277.849838)
			(xy 51.405282 -277.849838) (xy 51.404787 -277.874445) (xy 51.396892 -277.923022) (xy 51.381308 -277.969703)
			(xy 51.358437 -278.01328) (xy 51.328872 -278.052624) (xy 51.293379 -278.086716) (xy 51.252876 -278.114672)
			(xy 51.208414 -278.13577) (xy 51.161143 -278.149462) (xy 51.112288 -278.155394) (xy 51.063113 -278.153413)
			(xy 51.014894 -278.143569) (xy 50.968878 -278.126117) (xy 50.926257 -278.10151) (xy 50.888136 -278.070385)
			(xy 50.855501 -278.033548) (xy 50.829198 -277.991952) (xy 50.809907 -277.946676) (xy 50.79813 -277.898892)
			(xy 50.79417 -277.849838) (xy 50.455068 -277.849838) (xy 50.454573 -277.874445) (xy 50.446678 -277.923022)
			(xy 50.431094 -277.969703) (xy 50.408223 -278.01328) (xy 50.378658 -278.052624) (xy 50.343165 -278.086716)
			(xy 50.302662 -278.114672) (xy 50.2582 -278.13577) (xy 50.210929 -278.149462) (xy 50.162074 -278.155394)
			(xy 50.112899 -278.153413) (xy 50.06468 -278.143569) (xy 50.018664 -278.126117) (xy 49.976043 -278.10151)
			(xy 49.937922 -278.070385) (xy 49.905287 -278.033548) (xy 49.878984 -277.991952) (xy 49.859693 -277.946676)
			(xy 49.847916 -277.898892) (xy 49.843956 -277.849838) (xy 49.505108 -277.849838) (xy 49.504613 -277.874445)
			(xy 49.496718 -277.923022) (xy 49.481134 -277.969703) (xy 49.458263 -278.01328) (xy 49.428698 -278.052624)
			(xy 49.393205 -278.086716) (xy 49.352702 -278.114672) (xy 49.30824 -278.13577) (xy 49.260969 -278.149462)
			(xy 49.212114 -278.155394) (xy 49.162939 -278.153413) (xy 49.11472 -278.143569) (xy 49.068704 -278.126117)
			(xy 49.026083 -278.10151) (xy 48.987962 -278.070385) (xy 48.955327 -278.033548) (xy 48.929024 -277.991952)
			(xy 48.909733 -277.946676) (xy 48.897956 -277.898892) (xy 48.893996 -277.849838) (xy 48.555148 -277.849838)
			(xy 48.554653 -277.874445) (xy 48.546758 -277.923022) (xy 48.531174 -277.969703) (xy 48.508303 -278.01328)
			(xy 48.478738 -278.052624) (xy 48.443245 -278.086716) (xy 48.402742 -278.114672) (xy 48.35828 -278.13577)
			(xy 48.311009 -278.149462) (xy 48.262154 -278.155394) (xy 48.212979 -278.153413) (xy 48.16476 -278.143569)
			(xy 48.118744 -278.126117) (xy 48.076123 -278.10151) (xy 48.038002 -278.070385) (xy 48.005367 -278.033548)
			(xy 47.979064 -277.991952) (xy 47.959773 -277.946676) (xy 47.947996 -277.898892) (xy 47.944036 -277.849838)
			(xy 47.605188 -277.849838) (xy 47.604693 -277.874445) (xy 47.596798 -277.923022) (xy 47.581214 -277.969703)
			(xy 47.558343 -278.01328) (xy 47.528778 -278.052624) (xy 47.493285 -278.086716) (xy 47.452782 -278.114672)
			(xy 47.40832 -278.13577) (xy 47.361049 -278.149462) (xy 47.312194 -278.155394) (xy 47.263019 -278.153413)
			(xy 47.2148 -278.143569) (xy 47.168784 -278.126117) (xy 47.126163 -278.10151) (xy 47.088042 -278.070385)
			(xy 47.055407 -278.033548) (xy 47.029104 -277.991952) (xy 47.009813 -277.946676) (xy 46.998036 -277.898892)
			(xy 46.994076 -277.849838) (xy 46.655228 -277.849838) (xy 46.654733 -277.874445) (xy 46.646838 -277.923022)
			(xy 46.631254 -277.969703) (xy 46.608383 -278.01328) (xy 46.578818 -278.052624) (xy 46.543325 -278.086716)
			(xy 46.502822 -278.114672) (xy 46.45836 -278.13577) (xy 46.411089 -278.149462) (xy 46.362234 -278.155394)
			(xy 46.313059 -278.153413) (xy 46.26484 -278.143569) (xy 46.218824 -278.126117) (xy 46.176203 -278.10151)
			(xy 46.138082 -278.070385) (xy 46.105447 -278.033548) (xy 46.079144 -277.991952) (xy 46.059853 -277.946676)
			(xy 46.048076 -277.898892) (xy 46.044116 -277.849838) (xy 45.705268 -277.849838) (xy 45.704773 -277.874445)
			(xy 45.696878 -277.923022) (xy 45.681294 -277.969703) (xy 45.658423 -278.01328) (xy 45.628858 -278.052624)
			(xy 45.593365 -278.086716) (xy 45.552862 -278.114672) (xy 45.5084 -278.13577) (xy 45.461129 -278.149462)
			(xy 45.412274 -278.155394) (xy 45.363099 -278.153413) (xy 45.31488 -278.143569) (xy 45.268864 -278.126117)
			(xy 45.226243 -278.10151) (xy 45.188122 -278.070385) (xy 45.155487 -278.033548) (xy 45.129184 -277.991952)
			(xy 45.109893 -277.946676) (xy 45.098116 -277.898892) (xy 45.094156 -277.849838) (xy 44.755054 -277.849838)
			(xy 44.754559 -277.874445) (xy 44.746664 -277.923022) (xy 44.73108 -277.969703) (xy 44.708209 -278.01328)
			(xy 44.678644 -278.052624) (xy 44.643151 -278.086716) (xy 44.602648 -278.114672) (xy 44.558186 -278.13577)
			(xy 44.510915 -278.149462) (xy 44.46206 -278.155394) (xy 44.412885 -278.153413) (xy 44.364666 -278.143569)
			(xy 44.31865 -278.126117) (xy 44.276029 -278.10151) (xy 44.237908 -278.070385) (xy 44.205273 -278.033548)
			(xy 44.17897 -277.991952) (xy 44.159679 -277.946676) (xy 44.147902 -277.898892) (xy 44.143942 -277.849838)
			(xy 43.805094 -277.849838) (xy 43.804599 -277.874445) (xy 43.796704 -277.923022) (xy 43.78112 -277.969703)
			(xy 43.758249 -278.01328) (xy 43.728684 -278.052624) (xy 43.693191 -278.086716) (xy 43.652688 -278.114672)
			(xy 43.608226 -278.13577) (xy 43.560955 -278.149462) (xy 43.5121 -278.155394) (xy 43.462925 -278.153413)
			(xy 43.414706 -278.143569) (xy 43.36869 -278.126117) (xy 43.326069 -278.10151) (xy 43.287948 -278.070385)
			(xy 43.255313 -278.033548) (xy 43.22901 -277.991952) (xy 43.209719 -277.946676) (xy 43.197942 -277.898892)
			(xy 43.193982 -277.849838) (xy 12.106034 -277.849838) (xy 12.099043 -277.89734) (xy 12.082975 -277.950747)
			(xy 12.059303 -278.001244) (xy 12.02853 -278.047757) (xy 11.991313 -278.089294) (xy 11.948445 -278.124969)
			(xy 11.900839 -278.154023) (xy 11.84951 -278.175835) (xy 11.795553 -278.189941) (xy 11.740116 -278.196041)
			(xy 11.684382 -278.194004) (xy 11.629539 -278.183874) (xy 11.576755 -278.165867) (xy 11.527155 -278.140366)
			(xy 11.481797 -278.107915) (xy 11.441648 -278.069206) (xy 11.407562 -278.025063) (xy 11.380266 -277.976428)
			(xy 11.360343 -277.924337) (xy 11.348217 -277.8699) (xy 11.344146 -277.814278) (xy 10.088372 -277.814278)
			(xy 10.087863 -277.842164) (xy 10.079743 -277.89734) (xy 10.063675 -277.950747) (xy 10.040003 -278.001244)
			(xy 10.00923 -278.047757) (xy 9.972013 -278.089294) (xy 9.929145 -278.124969) (xy 9.881539 -278.154023)
			(xy 9.83021 -278.175835) (xy 9.776253 -278.189941) (xy 9.720816 -278.196041) (xy 9.665082 -278.194004)
			(xy 9.610239 -278.183874) (xy 9.557455 -278.165867) (xy 9.507855 -278.140366) (xy 9.462497 -278.107915)
			(xy 9.422348 -278.069206) (xy 9.388262 -278.025063) (xy 9.360966 -277.976428) (xy 9.341043 -277.924337)
			(xy 9.328917 -277.8699) (xy 9.324846 -277.814278) (xy 1.475478 -277.814278) (xy 1.468764 -277.831332)
			(xy 1.468374 -277.840948) (xy 1.468374 -278.301704) (xy 19.362418 -278.301704) (xy 19.366489 -278.246082)
			(xy 19.378615 -278.191645) (xy 19.398538 -278.139554) (xy 19.425834 -278.090919) (xy 19.45992 -278.046776)
			(xy 19.500069 -278.008067) (xy 19.545427 -277.975616) (xy 19.595027 -277.950115) (xy 19.647811 -277.932108)
			(xy 19.702654 -277.921978) (xy 19.758388 -277.919941) (xy 19.813825 -277.926041) (xy 19.867782 -277.940147)
			(xy 19.919111 -277.961959) (xy 19.966717 -277.991013) (xy 20.009585 -278.026688) (xy 20.046802 -278.068225)
			(xy 20.077575 -278.114738) (xy 20.101247 -278.165235) (xy 20.117315 -278.218642) (xy 20.125435 -278.273818)
			(xy 20.125944 -278.301704) (xy 20.125435 -278.32959) (xy 20.117315 -278.384766) (xy 20.101247 -278.438173)
			(xy 20.098899 -278.443182) (xy 25.719276 -278.443182) (xy 25.723347 -278.38756) (xy 25.735473 -278.333123)
			(xy 25.755396 -278.281032) (xy 25.782692 -278.232397) (xy 25.816778 -278.188254) (xy 25.856927 -278.149545)
			(xy 25.902285 -278.117094) (xy 25.951885 -278.091593) (xy 26.004669 -278.073586) (xy 26.059512 -278.063456)
			(xy 26.115246 -278.061419) (xy 26.170683 -278.067519) (xy 26.22464 -278.081625) (xy 26.275969 -278.103437)
			(xy 26.323575 -278.132491) (xy 26.366443 -278.168166) (xy 26.40366 -278.209703) (xy 26.434433 -278.256216)
			(xy 26.458105 -278.306713) (xy 26.463552 -278.324818) (xy 36.069028 -278.324818) (xy 36.072988 -278.275764)
			(xy 36.084765 -278.22798) (xy 36.104056 -278.182704) (xy 36.130359 -278.141108) (xy 36.162994 -278.104271)
			(xy 36.201115 -278.073146) (xy 36.243736 -278.048539) (xy 36.289752 -278.031087) (xy 36.337971 -278.021243)
			(xy 36.387146 -278.019262) (xy 36.436001 -278.025194) (xy 36.483272 -278.038886) (xy 36.527734 -278.059984)
			(xy 36.568237 -278.08794) (xy 36.60373 -278.122032) (xy 36.633295 -278.161376) (xy 36.656166 -278.204953)
			(xy 36.67175 -278.251634) (xy 36.679645 -278.300211) (xy 36.68014 -278.324818) (xy 37.018988 -278.324818)
			(xy 37.022948 -278.275764) (xy 37.034725 -278.22798) (xy 37.054016 -278.182704) (xy 37.080319 -278.141108)
			(xy 37.112954 -278.104271) (xy 37.151075 -278.073146) (xy 37.193696 -278.048539) (xy 37.239712 -278.031087)
			(xy 37.287931 -278.021243) (xy 37.337106 -278.019262) (xy 37.385961 -278.025194) (xy 37.433232 -278.038886)
			(xy 37.477694 -278.059984) (xy 37.518197 -278.08794) (xy 37.55369 -278.122032) (xy 37.583255 -278.161376)
			(xy 37.606126 -278.204953) (xy 37.62171 -278.251634) (xy 37.629605 -278.300211) (xy 37.6301 -278.324818)
			(xy 37.969202 -278.324818) (xy 37.973162 -278.275764) (xy 37.984939 -278.22798) (xy 38.00423 -278.182704)
			(xy 38.030533 -278.141108) (xy 38.063168 -278.104271) (xy 38.101289 -278.073146) (xy 38.14391 -278.048539)
			(xy 38.189926 -278.031087) (xy 38.238145 -278.021243) (xy 38.28732 -278.019262) (xy 38.336175 -278.025194)
			(xy 38.383446 -278.038886) (xy 38.427908 -278.059984) (xy 38.468411 -278.08794) (xy 38.503904 -278.122032)
			(xy 38.533469 -278.161376) (xy 38.55634 -278.204953) (xy 38.571924 -278.251634) (xy 38.579819 -278.300211)
			(xy 38.580314 -278.324818) (xy 38.919162 -278.324818) (xy 38.923122 -278.275764) (xy 38.934899 -278.22798)
			(xy 38.95419 -278.182704) (xy 38.980493 -278.141108) (xy 39.013128 -278.104271) (xy 39.051249 -278.073146)
			(xy 39.09387 -278.048539) (xy 39.139886 -278.031087) (xy 39.188105 -278.021243) (xy 39.23728 -278.019262)
			(xy 39.286135 -278.025194) (xy 39.333406 -278.038886) (xy 39.377868 -278.059984) (xy 39.418371 -278.08794)
			(xy 39.453864 -278.122032) (xy 39.483429 -278.161376) (xy 39.5063 -278.204953) (xy 39.521884 -278.251634)
			(xy 39.529779 -278.300211) (xy 39.530274 -278.324818) (xy 39.869122 -278.324818) (xy 39.873082 -278.275764)
			(xy 39.884859 -278.22798) (xy 39.90415 -278.182704) (xy 39.930453 -278.141108) (xy 39.963088 -278.104271)
			(xy 40.001209 -278.073146) (xy 40.04383 -278.048539) (xy 40.089846 -278.031087) (xy 40.138065 -278.021243)
			(xy 40.18724 -278.019262) (xy 40.236095 -278.025194) (xy 40.283366 -278.038886) (xy 40.327828 -278.059984)
			(xy 40.368331 -278.08794) (xy 40.403824 -278.122032) (xy 40.433389 -278.161376) (xy 40.45626 -278.204953)
			(xy 40.471844 -278.251634) (xy 40.479739 -278.300211) (xy 40.480234 -278.324818) (xy 40.819082 -278.324818)
			(xy 40.823042 -278.275764) (xy 40.834819 -278.22798) (xy 40.85411 -278.182704) (xy 40.880413 -278.141108)
			(xy 40.913048 -278.104271) (xy 40.951169 -278.073146) (xy 40.99379 -278.048539) (xy 41.039806 -278.031087)
			(xy 41.088025 -278.021243) (xy 41.1372 -278.019262) (xy 41.186055 -278.025194) (xy 41.233326 -278.038886)
			(xy 41.277788 -278.059984) (xy 41.318291 -278.08794) (xy 41.353784 -278.122032) (xy 41.383349 -278.161376)
			(xy 41.40622 -278.204953) (xy 41.421804 -278.251634) (xy 41.429699 -278.300211) (xy 41.430194 -278.324818)
			(xy 41.769042 -278.324818) (xy 41.773002 -278.275764) (xy 41.784779 -278.22798) (xy 41.80407 -278.182704)
			(xy 41.830373 -278.141108) (xy 41.863008 -278.104271) (xy 41.901129 -278.073146) (xy 41.94375 -278.048539)
			(xy 41.989766 -278.031087) (xy 42.037985 -278.021243) (xy 42.08716 -278.019262) (xy 42.136015 -278.025194)
			(xy 42.183286 -278.038886) (xy 42.227748 -278.059984) (xy 42.268251 -278.08794) (xy 42.303744 -278.122032)
			(xy 42.333309 -278.161376) (xy 42.35618 -278.204953) (xy 42.371764 -278.251634) (xy 42.379659 -278.300211)
			(xy 42.380154 -278.324818) (xy 42.379659 -278.349425) (xy 42.371764 -278.398002) (xy 42.35618 -278.444683)
			(xy 42.333309 -278.48826) (xy 42.303744 -278.527604) (xy 42.268251 -278.561696) (xy 42.227748 -278.589652)
			(xy 42.183286 -278.61075) (xy 42.136015 -278.624442) (xy 42.08716 -278.630374) (xy 42.037985 -278.628393)
			(xy 41.989766 -278.618549) (xy 41.94375 -278.601097) (xy 41.901129 -278.57649) (xy 41.863008 -278.545365)
			(xy 41.830373 -278.508528) (xy 41.80407 -278.466932) (xy 41.784779 -278.421656) (xy 41.773002 -278.373872)
			(xy 41.769042 -278.324818) (xy 41.430194 -278.324818) (xy 41.429699 -278.349425) (xy 41.421804 -278.398002)
			(xy 41.40622 -278.444683) (xy 41.383349 -278.48826) (xy 41.353784 -278.527604) (xy 41.318291 -278.561696)
			(xy 41.277788 -278.589652) (xy 41.233326 -278.61075) (xy 41.186055 -278.624442) (xy 41.1372 -278.630374)
			(xy 41.088025 -278.628393) (xy 41.039806 -278.618549) (xy 40.99379 -278.601097) (xy 40.951169 -278.57649)
			(xy 40.913048 -278.545365) (xy 40.880413 -278.508528) (xy 40.85411 -278.466932) (xy 40.834819 -278.421656)
			(xy 40.823042 -278.373872) (xy 40.819082 -278.324818) (xy 40.480234 -278.324818) (xy 40.479739 -278.349425)
			(xy 40.471844 -278.398002) (xy 40.45626 -278.444683) (xy 40.433389 -278.48826) (xy 40.403824 -278.527604)
			(xy 40.368331 -278.561696) (xy 40.327828 -278.589652) (xy 40.283366 -278.61075) (xy 40.236095 -278.624442)
			(xy 40.18724 -278.630374) (xy 40.138065 -278.628393) (xy 40.089846 -278.618549) (xy 40.04383 -278.601097)
			(xy 40.001209 -278.57649) (xy 39.963088 -278.545365) (xy 39.930453 -278.508528) (xy 39.90415 -278.466932)
			(xy 39.884859 -278.421656) (xy 39.873082 -278.373872) (xy 39.869122 -278.324818) (xy 39.530274 -278.324818)
			(xy 39.529779 -278.349425) (xy 39.521884 -278.398002) (xy 39.5063 -278.444683) (xy 39.483429 -278.48826)
			(xy 39.453864 -278.527604) (xy 39.418371 -278.561696) (xy 39.377868 -278.589652) (xy 39.333406 -278.61075)
			(xy 39.286135 -278.624442) (xy 39.23728 -278.630374) (xy 39.188105 -278.628393) (xy 39.139886 -278.618549)
			(xy 39.09387 -278.601097) (xy 39.051249 -278.57649) (xy 39.013128 -278.545365) (xy 38.980493 -278.508528)
			(xy 38.95419 -278.466932) (xy 38.934899 -278.421656) (xy 38.923122 -278.373872) (xy 38.919162 -278.324818)
			(xy 38.580314 -278.324818) (xy 38.579819 -278.349425) (xy 38.571924 -278.398002) (xy 38.55634 -278.444683)
			(xy 38.533469 -278.48826) (xy 38.503904 -278.527604) (xy 38.468411 -278.561696) (xy 38.427908 -278.589652)
			(xy 38.383446 -278.61075) (xy 38.336175 -278.624442) (xy 38.28732 -278.630374) (xy 38.238145 -278.628393)
			(xy 38.189926 -278.618549) (xy 38.14391 -278.601097) (xy 38.101289 -278.57649) (xy 38.063168 -278.545365)
			(xy 38.030533 -278.508528) (xy 38.00423 -278.466932) (xy 37.984939 -278.421656) (xy 37.973162 -278.373872)
			(xy 37.969202 -278.324818) (xy 37.6301 -278.324818) (xy 37.629605 -278.349425) (xy 37.62171 -278.398002)
			(xy 37.606126 -278.444683) (xy 37.583255 -278.48826) (xy 37.55369 -278.527604) (xy 37.518197 -278.561696)
			(xy 37.477694 -278.589652) (xy 37.433232 -278.61075) (xy 37.385961 -278.624442) (xy 37.337106 -278.630374)
			(xy 37.287931 -278.628393) (xy 37.239712 -278.618549) (xy 37.193696 -278.601097) (xy 37.151075 -278.57649)
			(xy 37.112954 -278.545365) (xy 37.080319 -278.508528) (xy 37.054016 -278.466932) (xy 37.034725 -278.421656)
			(xy 37.022948 -278.373872) (xy 37.018988 -278.324818) (xy 36.68014 -278.324818) (xy 36.679645 -278.349425)
			(xy 36.67175 -278.398002) (xy 36.656166 -278.444683) (xy 36.633295 -278.48826) (xy 36.60373 -278.527604)
			(xy 36.568237 -278.561696) (xy 36.527734 -278.589652) (xy 36.483272 -278.61075) (xy 36.436001 -278.624442)
			(xy 36.387146 -278.630374) (xy 36.337971 -278.628393) (xy 36.289752 -278.618549) (xy 36.243736 -278.601097)
			(xy 36.201115 -278.57649) (xy 36.162994 -278.545365) (xy 36.130359 -278.508528) (xy 36.104056 -278.466932)
			(xy 36.084765 -278.421656) (xy 36.072988 -278.373872) (xy 36.069028 -278.324818) (xy 26.463552 -278.324818)
			(xy 26.474173 -278.36012) (xy 26.482293 -278.415296) (xy 26.482802 -278.443182) (xy 26.482293 -278.471068)
			(xy 26.474173 -278.526244) (xy 26.458105 -278.579651) (xy 26.434433 -278.630148) (xy 26.40366 -278.676661)
			(xy 26.366443 -278.718198) (xy 26.323575 -278.753873) (xy 26.318245 -278.757126) (xy 33.547048 -278.757126)
			(xy 33.551119 -278.701504) (xy 33.563245 -278.647067) (xy 33.583168 -278.594976) (xy 33.610464 -278.546341)
			(xy 33.64455 -278.502198) (xy 33.684699 -278.463489) (xy 33.730057 -278.431038) (xy 33.779657 -278.405537)
			(xy 33.832441 -278.38753) (xy 33.887284 -278.3774) (xy 33.943018 -278.375363) (xy 33.998455 -278.381463)
			(xy 34.052412 -278.395569) (xy 34.103741 -278.417381) (xy 34.151347 -278.446435) (xy 34.194215 -278.48211)
			(xy 34.231432 -278.523647) (xy 34.262205 -278.57016) (xy 34.285877 -278.620657) (xy 34.301945 -278.674064)
			(xy 34.310065 -278.72924) (xy 34.310574 -278.757126) (xy 34.310065 -278.785012) (xy 34.307889 -278.799798)
			(xy 43.193982 -278.799798) (xy 43.197942 -278.750744) (xy 43.209719 -278.70296) (xy 43.22901 -278.657684)
			(xy 43.255313 -278.616088) (xy 43.287948 -278.579251) (xy 43.326069 -278.548126) (xy 43.36869 -278.523519)
			(xy 43.414706 -278.506067) (xy 43.462925 -278.496223) (xy 43.5121 -278.494242) (xy 43.560955 -278.500174)
			(xy 43.608226 -278.513866) (xy 43.652688 -278.534964) (xy 43.693191 -278.56292) (xy 43.728684 -278.597012)
			(xy 43.758249 -278.636356) (xy 43.78112 -278.679933) (xy 43.796704 -278.726614) (xy 43.804599 -278.775191)
			(xy 43.805094 -278.799798) (xy 44.143942 -278.799798) (xy 44.147902 -278.750744) (xy 44.159679 -278.70296)
			(xy 44.17897 -278.657684) (xy 44.205273 -278.616088) (xy 44.237908 -278.579251) (xy 44.276029 -278.548126)
			(xy 44.31865 -278.523519) (xy 44.364666 -278.506067) (xy 44.412885 -278.496223) (xy 44.46206 -278.494242)
			(xy 44.510915 -278.500174) (xy 44.558186 -278.513866) (xy 44.602648 -278.534964) (xy 44.643151 -278.56292)
			(xy 44.678644 -278.597012) (xy 44.708209 -278.636356) (xy 44.73108 -278.679933) (xy 44.746664 -278.726614)
			(xy 44.754559 -278.775191) (xy 44.755054 -278.799798) (xy 45.094156 -278.799798) (xy 45.098116 -278.750744)
			(xy 45.109893 -278.70296) (xy 45.129184 -278.657684) (xy 45.155487 -278.616088) (xy 45.188122 -278.579251)
			(xy 45.226243 -278.548126) (xy 45.268864 -278.523519) (xy 45.31488 -278.506067) (xy 45.363099 -278.496223)
			(xy 45.412274 -278.494242) (xy 45.461129 -278.500174) (xy 45.5084 -278.513866) (xy 45.552862 -278.534964)
			(xy 45.593365 -278.56292) (xy 45.628858 -278.597012) (xy 45.658423 -278.636356) (xy 45.681294 -278.679933)
			(xy 45.696878 -278.726614) (xy 45.704773 -278.775191) (xy 45.705268 -278.799798) (xy 46.044116 -278.799798)
			(xy 46.048076 -278.750744) (xy 46.059853 -278.70296) (xy 46.079144 -278.657684) (xy 46.105447 -278.616088)
			(xy 46.138082 -278.579251) (xy 46.176203 -278.548126) (xy 46.218824 -278.523519) (xy 46.26484 -278.506067)
			(xy 46.313059 -278.496223) (xy 46.362234 -278.494242) (xy 46.411089 -278.500174) (xy 46.45836 -278.513866)
			(xy 46.502822 -278.534964) (xy 46.543325 -278.56292) (xy 46.578818 -278.597012) (xy 46.608383 -278.636356)
			(xy 46.631254 -278.679933) (xy 46.646838 -278.726614) (xy 46.654733 -278.775191) (xy 46.655228 -278.799798)
			(xy 46.994076 -278.799798) (xy 46.998036 -278.750744) (xy 47.009813 -278.70296) (xy 47.029104 -278.657684)
			(xy 47.055407 -278.616088) (xy 47.088042 -278.579251) (xy 47.126163 -278.548126) (xy 47.168784 -278.523519)
			(xy 47.2148 -278.506067) (xy 47.263019 -278.496223) (xy 47.312194 -278.494242) (xy 47.361049 -278.500174)
			(xy 47.40832 -278.513866) (xy 47.452782 -278.534964) (xy 47.493285 -278.56292) (xy 47.528778 -278.597012)
			(xy 47.558343 -278.636356) (xy 47.581214 -278.679933) (xy 47.596798 -278.726614) (xy 47.604693 -278.775191)
			(xy 47.605188 -278.799798) (xy 47.944036 -278.799798) (xy 47.947996 -278.750744) (xy 47.959773 -278.70296)
			(xy 47.979064 -278.657684) (xy 48.005367 -278.616088) (xy 48.038002 -278.579251) (xy 48.076123 -278.548126)
			(xy 48.118744 -278.523519) (xy 48.16476 -278.506067) (xy 48.212979 -278.496223) (xy 48.262154 -278.494242)
			(xy 48.311009 -278.500174) (xy 48.35828 -278.513866) (xy 48.402742 -278.534964) (xy 48.443245 -278.56292)
			(xy 48.478738 -278.597012) (xy 48.508303 -278.636356) (xy 48.531174 -278.679933) (xy 48.546758 -278.726614)
			(xy 48.554653 -278.775191) (xy 48.555148 -278.799798) (xy 48.893996 -278.799798) (xy 48.897956 -278.750744)
			(xy 48.909733 -278.70296) (xy 48.929024 -278.657684) (xy 48.955327 -278.616088) (xy 48.987962 -278.579251)
			(xy 49.026083 -278.548126) (xy 49.068704 -278.523519) (xy 49.11472 -278.506067) (xy 49.162939 -278.496223)
			(xy 49.212114 -278.494242) (xy 49.260969 -278.500174) (xy 49.30824 -278.513866) (xy 49.352702 -278.534964)
			(xy 49.393205 -278.56292) (xy 49.428698 -278.597012) (xy 49.458263 -278.636356) (xy 49.481134 -278.679933)
			(xy 49.496718 -278.726614) (xy 49.504613 -278.775191) (xy 49.505108 -278.799798) (xy 49.843956 -278.799798)
			(xy 49.847916 -278.750744) (xy 49.859693 -278.70296) (xy 49.878984 -278.657684) (xy 49.905287 -278.616088)
			(xy 49.937922 -278.579251) (xy 49.976043 -278.548126) (xy 50.018664 -278.523519) (xy 50.06468 -278.506067)
			(xy 50.112899 -278.496223) (xy 50.162074 -278.494242) (xy 50.210929 -278.500174) (xy 50.2582 -278.513866)
			(xy 50.302662 -278.534964) (xy 50.343165 -278.56292) (xy 50.378658 -278.597012) (xy 50.408223 -278.636356)
			(xy 50.431094 -278.679933) (xy 50.446678 -278.726614) (xy 50.454573 -278.775191) (xy 50.455068 -278.799798)
			(xy 50.79417 -278.799798) (xy 50.79813 -278.750744) (xy 50.809907 -278.70296) (xy 50.829198 -278.657684)
			(xy 50.855501 -278.616088) (xy 50.888136 -278.579251) (xy 50.926257 -278.548126) (xy 50.968878 -278.523519)
			(xy 51.014894 -278.506067) (xy 51.063113 -278.496223) (xy 51.112288 -278.494242) (xy 51.161143 -278.500174)
			(xy 51.208414 -278.513866) (xy 51.252876 -278.534964) (xy 51.293379 -278.56292) (xy 51.328872 -278.597012)
			(xy 51.358437 -278.636356) (xy 51.381308 -278.679933) (xy 51.396892 -278.726614) (xy 51.404787 -278.775191)
			(xy 51.405282 -278.799798) (xy 51.74413 -278.799798) (xy 51.74809 -278.750744) (xy 51.759867 -278.70296)
			(xy 51.779158 -278.657684) (xy 51.805461 -278.616088) (xy 51.838096 -278.579251) (xy 51.876217 -278.548126)
			(xy 51.918838 -278.523519) (xy 51.964854 -278.506067) (xy 52.013073 -278.496223) (xy 52.062248 -278.494242)
			(xy 52.111103 -278.500174) (xy 52.158374 -278.513866) (xy 52.202836 -278.534964) (xy 52.243339 -278.56292)
			(xy 52.278832 -278.597012) (xy 52.308397 -278.636356) (xy 52.331268 -278.679933) (xy 52.346852 -278.726614)
			(xy 52.354747 -278.775191) (xy 52.355242 -278.799798) (xy 52.69409 -278.799798) (xy 52.69805 -278.750744)
			(xy 52.709827 -278.70296) (xy 52.729118 -278.657684) (xy 52.755421 -278.616088) (xy 52.788056 -278.579251)
			(xy 52.826177 -278.548126) (xy 52.868798 -278.523519) (xy 52.914814 -278.506067) (xy 52.963033 -278.496223)
			(xy 53.012208 -278.494242) (xy 53.061063 -278.500174) (xy 53.108334 -278.513866) (xy 53.152796 -278.534964)
			(xy 53.193299 -278.56292) (xy 53.228792 -278.597012) (xy 53.258357 -278.636356) (xy 53.281228 -278.679933)
			(xy 53.296812 -278.726614) (xy 53.304707 -278.775191) (xy 53.305202 -278.799798) (xy 53.64405 -278.799798)
			(xy 53.64801 -278.750744) (xy 53.659787 -278.70296) (xy 53.679078 -278.657684) (xy 53.705381 -278.616088)
			(xy 53.738016 -278.579251) (xy 53.776137 -278.548126) (xy 53.818758 -278.523519) (xy 53.864774 -278.506067)
			(xy 53.912993 -278.496223) (xy 53.962168 -278.494242) (xy 54.011023 -278.500174) (xy 54.058294 -278.513866)
			(xy 54.102756 -278.534964) (xy 54.143259 -278.56292) (xy 54.178752 -278.597012) (xy 54.208317 -278.636356)
			(xy 54.231188 -278.679933) (xy 54.246772 -278.726614) (xy 54.254667 -278.775191) (xy 54.255162 -278.799798)
			(xy 54.59401 -278.799798) (xy 54.59797 -278.750744) (xy 54.609747 -278.70296) (xy 54.629038 -278.657684)
			(xy 54.655341 -278.616088) (xy 54.687976 -278.579251) (xy 54.726097 -278.548126) (xy 54.768718 -278.523519)
			(xy 54.814734 -278.506067) (xy 54.862953 -278.496223) (xy 54.912128 -278.494242) (xy 54.960983 -278.500174)
			(xy 55.008254 -278.513866) (xy 55.052716 -278.534964) (xy 55.093219 -278.56292) (xy 55.128712 -278.597012)
			(xy 55.158277 -278.636356) (xy 55.181148 -278.679933) (xy 55.196732 -278.726614) (xy 55.204627 -278.775191)
			(xy 55.205122 -278.799798) (xy 55.54397 -278.799798) (xy 55.54793 -278.750744) (xy 55.559707 -278.70296)
			(xy 55.578998 -278.657684) (xy 55.605301 -278.616088) (xy 55.637936 -278.579251) (xy 55.676057 -278.548126)
			(xy 55.718678 -278.523519) (xy 55.764694 -278.506067) (xy 55.812913 -278.496223) (xy 55.862088 -278.494242)
			(xy 55.910943 -278.500174) (xy 55.958214 -278.513866) (xy 56.002676 -278.534964) (xy 56.043179 -278.56292)
			(xy 56.078672 -278.597012) (xy 56.108237 -278.636356) (xy 56.131108 -278.679933) (xy 56.146692 -278.726614)
			(xy 56.154587 -278.775191) (xy 56.155082 -278.799798) (xy 56.494184 -278.799798) (xy 56.498144 -278.750744)
			(xy 56.509921 -278.70296) (xy 56.529212 -278.657684) (xy 56.555515 -278.616088) (xy 56.58815 -278.579251)
			(xy 56.626271 -278.548126) (xy 56.668892 -278.523519) (xy 56.714908 -278.506067) (xy 56.763127 -278.496223)
			(xy 56.812302 -278.494242) (xy 56.861157 -278.500174) (xy 56.908428 -278.513866) (xy 56.95289 -278.534964)
			(xy 56.993393 -278.56292) (xy 57.028886 -278.597012) (xy 57.058451 -278.636356) (xy 57.081322 -278.679933)
			(xy 57.096906 -278.726614) (xy 57.104801 -278.775191) (xy 57.105296 -278.799798) (xy 57.104801 -278.824405)
			(xy 57.096906 -278.872982) (xy 57.081322 -278.919663) (xy 57.058451 -278.96324) (xy 57.028886 -279.002584)
			(xy 56.993393 -279.036676) (xy 56.95289 -279.064632) (xy 56.908428 -279.08573) (xy 56.861157 -279.099422)
			(xy 56.812302 -279.105354) (xy 56.763127 -279.103373) (xy 56.714908 -279.093529) (xy 56.668892 -279.076077)
			(xy 56.626271 -279.05147) (xy 56.58815 -279.020345) (xy 56.555515 -278.983508) (xy 56.529212 -278.941912)
			(xy 56.509921 -278.896636) (xy 56.498144 -278.848852) (xy 56.494184 -278.799798) (xy 56.155082 -278.799798)
			(xy 56.154587 -278.824405) (xy 56.146692 -278.872982) (xy 56.131108 -278.919663) (xy 56.108237 -278.96324)
			(xy 56.078672 -279.002584) (xy 56.043179 -279.036676) (xy 56.002676 -279.064632) (xy 55.958214 -279.08573)
			(xy 55.910943 -279.099422) (xy 55.862088 -279.105354) (xy 55.812913 -279.103373) (xy 55.764694 -279.093529)
			(xy 55.718678 -279.076077) (xy 55.676057 -279.05147) (xy 55.637936 -279.020345) (xy 55.605301 -278.983508)
			(xy 55.578998 -278.941912) (xy 55.559707 -278.896636) (xy 55.54793 -278.848852) (xy 55.54397 -278.799798)
			(xy 55.205122 -278.799798) (xy 55.204627 -278.824405) (xy 55.196732 -278.872982) (xy 55.181148 -278.919663)
			(xy 55.158277 -278.96324) (xy 55.128712 -279.002584) (xy 55.093219 -279.036676) (xy 55.052716 -279.064632)
			(xy 55.008254 -279.08573) (xy 54.960983 -279.099422) (xy 54.912128 -279.105354) (xy 54.862953 -279.103373)
			(xy 54.814734 -279.093529) (xy 54.768718 -279.076077) (xy 54.726097 -279.05147) (xy 54.687976 -279.020345)
			(xy 54.655341 -278.983508) (xy 54.629038 -278.941912) (xy 54.609747 -278.896636) (xy 54.59797 -278.848852)
			(xy 54.59401 -278.799798) (xy 54.255162 -278.799798) (xy 54.254667 -278.824405) (xy 54.246772 -278.872982)
			(xy 54.231188 -278.919663) (xy 54.208317 -278.96324) (xy 54.178752 -279.002584) (xy 54.143259 -279.036676)
			(xy 54.102756 -279.064632) (xy 54.058294 -279.08573) (xy 54.011023 -279.099422) (xy 53.962168 -279.105354)
			(xy 53.912993 -279.103373) (xy 53.864774 -279.093529) (xy 53.818758 -279.076077) (xy 53.776137 -279.05147)
			(xy 53.738016 -279.020345) (xy 53.705381 -278.983508) (xy 53.679078 -278.941912) (xy 53.659787 -278.896636)
			(xy 53.64801 -278.848852) (xy 53.64405 -278.799798) (xy 53.305202 -278.799798) (xy 53.304707 -278.824405)
			(xy 53.296812 -278.872982) (xy 53.281228 -278.919663) (xy 53.258357 -278.96324) (xy 53.228792 -279.002584)
			(xy 53.193299 -279.036676) (xy 53.152796 -279.064632) (xy 53.108334 -279.08573) (xy 53.061063 -279.099422)
			(xy 53.012208 -279.105354) (xy 52.963033 -279.103373) (xy 52.914814 -279.093529) (xy 52.868798 -279.076077)
			(xy 52.826177 -279.05147) (xy 52.788056 -279.020345) (xy 52.755421 -278.983508) (xy 52.729118 -278.941912)
			(xy 52.709827 -278.896636) (xy 52.69805 -278.848852) (xy 52.69409 -278.799798) (xy 52.355242 -278.799798)
			(xy 52.354747 -278.824405) (xy 52.346852 -278.872982) (xy 52.331268 -278.919663) (xy 52.308397 -278.96324)
			(xy 52.278832 -279.002584) (xy 52.243339 -279.036676) (xy 52.202836 -279.064632) (xy 52.158374 -279.08573)
			(xy 52.111103 -279.099422) (xy 52.062248 -279.105354) (xy 52.013073 -279.103373) (xy 51.964854 -279.093529)
			(xy 51.918838 -279.076077) (xy 51.876217 -279.05147) (xy 51.838096 -279.020345) (xy 51.805461 -278.983508)
			(xy 51.779158 -278.941912) (xy 51.759867 -278.896636) (xy 51.74809 -278.848852) (xy 51.74413 -278.799798)
			(xy 51.405282 -278.799798) (xy 51.404787 -278.824405) (xy 51.396892 -278.872982) (xy 51.381308 -278.919663)
			(xy 51.358437 -278.96324) (xy 51.328872 -279.002584) (xy 51.293379 -279.036676) (xy 51.252876 -279.064632)
			(xy 51.208414 -279.08573) (xy 51.161143 -279.099422) (xy 51.112288 -279.105354) (xy 51.063113 -279.103373)
			(xy 51.014894 -279.093529) (xy 50.968878 -279.076077) (xy 50.926257 -279.05147) (xy 50.888136 -279.020345)
			(xy 50.855501 -278.983508) (xy 50.829198 -278.941912) (xy 50.809907 -278.896636) (xy 50.79813 -278.848852)
			(xy 50.79417 -278.799798) (xy 50.455068 -278.799798) (xy 50.454573 -278.824405) (xy 50.446678 -278.872982)
			(xy 50.431094 -278.919663) (xy 50.408223 -278.96324) (xy 50.378658 -279.002584) (xy 50.343165 -279.036676)
			(xy 50.302662 -279.064632) (xy 50.2582 -279.08573) (xy 50.210929 -279.099422) (xy 50.162074 -279.105354)
			(xy 50.112899 -279.103373) (xy 50.06468 -279.093529) (xy 50.018664 -279.076077) (xy 49.976043 -279.05147)
			(xy 49.937922 -279.020345) (xy 49.905287 -278.983508) (xy 49.878984 -278.941912) (xy 49.859693 -278.896636)
			(xy 49.847916 -278.848852) (xy 49.843956 -278.799798) (xy 49.505108 -278.799798) (xy 49.504613 -278.824405)
			(xy 49.496718 -278.872982) (xy 49.481134 -278.919663) (xy 49.458263 -278.96324) (xy 49.428698 -279.002584)
			(xy 49.393205 -279.036676) (xy 49.352702 -279.064632) (xy 49.30824 -279.08573) (xy 49.260969 -279.099422)
			(xy 49.212114 -279.105354) (xy 49.162939 -279.103373) (xy 49.11472 -279.093529) (xy 49.068704 -279.076077)
			(xy 49.026083 -279.05147) (xy 48.987962 -279.020345) (xy 48.955327 -278.983508) (xy 48.929024 -278.941912)
			(xy 48.909733 -278.896636) (xy 48.897956 -278.848852) (xy 48.893996 -278.799798) (xy 48.555148 -278.799798)
			(xy 48.554653 -278.824405) (xy 48.546758 -278.872982) (xy 48.531174 -278.919663) (xy 48.508303 -278.96324)
			(xy 48.478738 -279.002584) (xy 48.443245 -279.036676) (xy 48.402742 -279.064632) (xy 48.35828 -279.08573)
			(xy 48.311009 -279.099422) (xy 48.262154 -279.105354) (xy 48.212979 -279.103373) (xy 48.16476 -279.093529)
			(xy 48.118744 -279.076077) (xy 48.076123 -279.05147) (xy 48.038002 -279.020345) (xy 48.005367 -278.983508)
			(xy 47.979064 -278.941912) (xy 47.959773 -278.896636) (xy 47.947996 -278.848852) (xy 47.944036 -278.799798)
			(xy 47.605188 -278.799798) (xy 47.604693 -278.824405) (xy 47.596798 -278.872982) (xy 47.581214 -278.919663)
			(xy 47.558343 -278.96324) (xy 47.528778 -279.002584) (xy 47.493285 -279.036676) (xy 47.452782 -279.064632)
			(xy 47.40832 -279.08573) (xy 47.361049 -279.099422) (xy 47.312194 -279.105354) (xy 47.263019 -279.103373)
			(xy 47.2148 -279.093529) (xy 47.168784 -279.076077) (xy 47.126163 -279.05147) (xy 47.088042 -279.020345)
			(xy 47.055407 -278.983508) (xy 47.029104 -278.941912) (xy 47.009813 -278.896636) (xy 46.998036 -278.848852)
			(xy 46.994076 -278.799798) (xy 46.655228 -278.799798) (xy 46.654733 -278.824405) (xy 46.646838 -278.872982)
			(xy 46.631254 -278.919663) (xy 46.608383 -278.96324) (xy 46.578818 -279.002584) (xy 46.543325 -279.036676)
			(xy 46.502822 -279.064632) (xy 46.45836 -279.08573) (xy 46.411089 -279.099422) (xy 46.362234 -279.105354)
			(xy 46.313059 -279.103373) (xy 46.26484 -279.093529) (xy 46.218824 -279.076077) (xy 46.176203 -279.05147)
			(xy 46.138082 -279.020345) (xy 46.105447 -278.983508) (xy 46.079144 -278.941912) (xy 46.059853 -278.896636)
			(xy 46.048076 -278.848852) (xy 46.044116 -278.799798) (xy 45.705268 -278.799798) (xy 45.704773 -278.824405)
			(xy 45.696878 -278.872982) (xy 45.681294 -278.919663) (xy 45.658423 -278.96324) (xy 45.628858 -279.002584)
			(xy 45.593365 -279.036676) (xy 45.552862 -279.064632) (xy 45.5084 -279.08573) (xy 45.461129 -279.099422)
			(xy 45.412274 -279.105354) (xy 45.363099 -279.103373) (xy 45.31488 -279.093529) (xy 45.268864 -279.076077)
			(xy 45.226243 -279.05147) (xy 45.188122 -279.020345) (xy 45.155487 -278.983508) (xy 45.129184 -278.941912)
			(xy 45.109893 -278.896636) (xy 45.098116 -278.848852) (xy 45.094156 -278.799798) (xy 44.755054 -278.799798)
			(xy 44.754559 -278.824405) (xy 44.746664 -278.872982) (xy 44.73108 -278.919663) (xy 44.708209 -278.96324)
			(xy 44.678644 -279.002584) (xy 44.643151 -279.036676) (xy 44.602648 -279.064632) (xy 44.558186 -279.08573)
			(xy 44.510915 -279.099422) (xy 44.46206 -279.105354) (xy 44.412885 -279.103373) (xy 44.364666 -279.093529)
			(xy 44.31865 -279.076077) (xy 44.276029 -279.05147) (xy 44.237908 -279.020345) (xy 44.205273 -278.983508)
			(xy 44.17897 -278.941912) (xy 44.159679 -278.896636) (xy 44.147902 -278.848852) (xy 44.143942 -278.799798)
			(xy 43.805094 -278.799798) (xy 43.804599 -278.824405) (xy 43.796704 -278.872982) (xy 43.78112 -278.919663)
			(xy 43.758249 -278.96324) (xy 43.728684 -279.002584) (xy 43.693191 -279.036676) (xy 43.652688 -279.064632)
			(xy 43.608226 -279.08573) (xy 43.560955 -279.099422) (xy 43.5121 -279.105354) (xy 43.462925 -279.103373)
			(xy 43.414706 -279.093529) (xy 43.36869 -279.076077) (xy 43.326069 -279.05147) (xy 43.287948 -279.020345)
			(xy 43.255313 -278.983508) (xy 43.22901 -278.941912) (xy 43.209719 -278.896636) (xy 43.197942 -278.848852)
			(xy 43.193982 -278.799798) (xy 34.307889 -278.799798) (xy 34.301945 -278.840188) (xy 34.285877 -278.893595)
			(xy 34.262205 -278.944092) (xy 34.231432 -278.990605) (xy 34.194215 -279.032142) (xy 34.151347 -279.067817)
			(xy 34.103741 -279.096871) (xy 34.052412 -279.118683) (xy 33.998455 -279.132789) (xy 33.943018 -279.138889)
			(xy 33.887284 -279.136852) (xy 33.832441 -279.126722) (xy 33.779657 -279.108715) (xy 33.730057 -279.083214)
			(xy 33.684699 -279.050763) (xy 33.64455 -279.012054) (xy 33.610464 -278.967911) (xy 33.583168 -278.919276)
			(xy 33.563245 -278.867185) (xy 33.551119 -278.812748) (xy 33.547048 -278.757126) (xy 26.318245 -278.757126)
			(xy 26.275969 -278.782927) (xy 26.22464 -278.804739) (xy 26.170683 -278.818845) (xy 26.115246 -278.824945)
			(xy 26.059512 -278.822908) (xy 26.004669 -278.812778) (xy 25.951885 -278.794771) (xy 25.902285 -278.76927)
			(xy 25.856927 -278.736819) (xy 25.816778 -278.69811) (xy 25.782692 -278.653967) (xy 25.755396 -278.605332)
			(xy 25.735473 -278.553241) (xy 25.723347 -278.498804) (xy 25.719276 -278.443182) (xy 20.098899 -278.443182)
			(xy 20.077575 -278.48867) (xy 20.046802 -278.535183) (xy 20.009585 -278.57672) (xy 19.966717 -278.612395)
			(xy 19.919111 -278.641449) (xy 19.867782 -278.663261) (xy 19.813825 -278.677367) (xy 19.758388 -278.683467)
			(xy 19.702654 -278.68143) (xy 19.647811 -278.6713) (xy 19.595027 -278.653293) (xy 19.545427 -278.627792)
			(xy 19.500069 -278.595341) (xy 19.45992 -278.556632) (xy 19.425834 -278.512489) (xy 19.398538 -278.463854)
			(xy 19.378615 -278.411763) (xy 19.366489 -278.357326) (xy 19.362418 -278.301704) (xy 1.468374 -278.301704)
			(xy 1.468374 -279.73909) (xy 5.034026 -279.73909) (xy 5.034518 -279.710836) (xy 5.042855 -279.654948)
			(xy 5.059345 -279.6009) (xy 5.083626 -279.549876) (xy 5.115169 -279.502992) (xy 5.133848 -279.481788)
			(xy 5.140452 -279.474676) (xy 5.14731 -279.45715) (xy 5.14731 -279.369266) (xy 5.140452 -279.35174)
			(xy 5.133848 -279.344628) (xy 5.115176 -279.32342) (xy 5.083639 -279.276534) (xy 5.059362 -279.22551)
			(xy 5.042875 -279.171465) (xy 5.034539 -279.115578) (xy 5.034026 -279.087326) (xy 5.03448 -279.060072)
			(xy 5.042234 -279.006119) (xy 5.057588 -278.953819) (xy 5.08023 -278.904237) (xy 5.109699 -278.858382)
			(xy 5.145394 -278.817188) (xy 5.186588 -278.781494) (xy 5.232444 -278.752026) (xy 5.282027 -278.729386)
			(xy 5.334327 -278.714032) (xy 5.38828 -278.706279) (xy 5.415534 -278.705818) (xy 5.444273 -278.706343)
			(xy 5.501099 -278.714969) (xy 5.555989 -278.73202) (xy 5.6077 -278.75711) (xy 5.655064 -278.789673)
			(xy 5.676392 -278.808942) (xy 5.683504 -278.815546) (xy 5.70103 -278.822658) (xy 5.790438 -278.822658)
			(xy 5.807964 -278.815546) (xy 5.815076 -278.808942) (xy 5.836403 -278.789672) (xy 5.883766 -278.757107)
			(xy 5.935477 -278.732016) (xy 5.990368 -278.714966) (xy 6.047195 -278.706344) (xy 6.104673 -278.706344)
			(xy 6.1615 -278.714966) (xy 6.216391 -278.732016) (xy 6.268102 -278.757107) (xy 6.315465 -278.789672)
			(xy 6.336792 -278.808942) (xy 6.343904 -278.815546) (xy 6.36143 -278.822658) (xy 6.450838 -278.822658)
			(xy 6.468364 -278.815546) (xy 6.475476 -278.808942) (xy 6.496803 -278.789672) (xy 6.544166 -278.757107)
			(xy 6.595877 -278.732016) (xy 6.650768 -278.714966) (xy 6.707595 -278.706344) (xy 6.765073 -278.706344)
			(xy 6.8219 -278.714966) (xy 6.876791 -278.732016) (xy 6.928502 -278.757107) (xy 6.975865 -278.789672)
			(xy 6.997192 -278.808942) (xy 7.004304 -278.815546) (xy 7.02183 -278.822658) (xy 7.111238 -278.822658)
			(xy 7.128764 -278.815546) (xy 7.135876 -278.808942) (xy 7.15719 -278.789656) (xy 7.204555 -278.757092)
			(xy 7.25627 -278.732002) (xy 7.311164 -278.714955) (xy 7.367994 -278.706336) (xy 7.396734 -278.705818)
			(xy 7.423987 -278.706246) (xy 7.477938 -278.714008) (xy 7.530236 -278.729369) (xy 7.579815 -278.752016)
			(xy 7.625666 -278.781488) (xy 7.666857 -278.817186) (xy 7.702548 -278.858382) (xy 7.732013 -278.904238)
			(xy 7.754652 -278.95382) (xy 7.770005 -279.00612) (xy 7.777758 -279.060073) (xy 7.778242 -279.087326)
			(xy 7.777767 -279.11558) (xy 7.769428 -279.17147) (xy 7.752934 -279.225518) (xy 7.729489 -279.274778)
			(xy 36.069028 -279.274778) (xy 36.072988 -279.225724) (xy 36.084765 -279.17794) (xy 36.104056 -279.132664)
			(xy 36.130359 -279.091068) (xy 36.162994 -279.054231) (xy 36.201115 -279.023106) (xy 36.243736 -278.998499)
			(xy 36.289752 -278.981047) (xy 36.337971 -278.971203) (xy 36.387146 -278.969222) (xy 36.436001 -278.975154)
			(xy 36.483272 -278.988846) (xy 36.527734 -279.009944) (xy 36.568237 -279.0379) (xy 36.60373 -279.071992)
			(xy 36.633295 -279.111336) (xy 36.656166 -279.154913) (xy 36.67175 -279.201594) (xy 36.679645 -279.250171)
			(xy 36.68014 -279.274778) (xy 37.018988 -279.274778) (xy 37.022948 -279.225724) (xy 37.034725 -279.17794)
			(xy 37.054016 -279.132664) (xy 37.080319 -279.091068) (xy 37.112954 -279.054231) (xy 37.151075 -279.023106)
			(xy 37.193696 -278.998499) (xy 37.239712 -278.981047) (xy 37.287931 -278.971203) (xy 37.337106 -278.969222)
			(xy 37.385961 -278.975154) (xy 37.433232 -278.988846) (xy 37.477694 -279.009944) (xy 37.518197 -279.0379)
			(xy 37.55369 -279.071992) (xy 37.583255 -279.111336) (xy 37.606126 -279.154913) (xy 37.62171 -279.201594)
			(xy 37.629605 -279.250171) (xy 37.6301 -279.274778) (xy 37.969202 -279.274778) (xy 37.973162 -279.225724)
			(xy 37.984939 -279.17794) (xy 38.00423 -279.132664) (xy 38.030533 -279.091068) (xy 38.063168 -279.054231)
			(xy 38.101289 -279.023106) (xy 38.14391 -278.998499) (xy 38.189926 -278.981047) (xy 38.238145 -278.971203)
			(xy 38.28732 -278.969222) (xy 38.336175 -278.975154) (xy 38.383446 -278.988846) (xy 38.427908 -279.009944)
			(xy 38.468411 -279.0379) (xy 38.503904 -279.071992) (xy 38.533469 -279.111336) (xy 38.55634 -279.154913)
			(xy 38.571924 -279.201594) (xy 38.579819 -279.250171) (xy 38.580314 -279.274778) (xy 38.919162 -279.274778)
			(xy 38.923122 -279.225724) (xy 38.934899 -279.17794) (xy 38.95419 -279.132664) (xy 38.980493 -279.091068)
			(xy 39.013128 -279.054231) (xy 39.051249 -279.023106) (xy 39.09387 -278.998499) (xy 39.139886 -278.981047)
			(xy 39.188105 -278.971203) (xy 39.23728 -278.969222) (xy 39.286135 -278.975154) (xy 39.333406 -278.988846)
			(xy 39.377868 -279.009944) (xy 39.418371 -279.0379) (xy 39.453864 -279.071992) (xy 39.483429 -279.111336)
			(xy 39.5063 -279.154913) (xy 39.521884 -279.201594) (xy 39.529779 -279.250171) (xy 39.530274 -279.274778)
			(xy 39.869122 -279.274778) (xy 39.873082 -279.225724) (xy 39.884859 -279.17794) (xy 39.90415 -279.132664)
			(xy 39.930453 -279.091068) (xy 39.963088 -279.054231) (xy 40.001209 -279.023106) (xy 40.04383 -278.998499)
			(xy 40.089846 -278.981047) (xy 40.138065 -278.971203) (xy 40.18724 -278.969222) (xy 40.236095 -278.975154)
			(xy 40.283366 -278.988846) (xy 40.327828 -279.009944) (xy 40.368331 -279.0379) (xy 40.403824 -279.071992)
			(xy 40.433389 -279.111336) (xy 40.45626 -279.154913) (xy 40.471844 -279.201594) (xy 40.479739 -279.250171)
			(xy 40.480234 -279.274778) (xy 40.819082 -279.274778) (xy 40.823042 -279.225724) (xy 40.834819 -279.17794)
			(xy 40.85411 -279.132664) (xy 40.880413 -279.091068) (xy 40.913048 -279.054231) (xy 40.951169 -279.023106)
			(xy 40.99379 -278.998499) (xy 41.039806 -278.981047) (xy 41.088025 -278.971203) (xy 41.1372 -278.969222)
			(xy 41.186055 -278.975154) (xy 41.233326 -278.988846) (xy 41.277788 -279.009944) (xy 41.318291 -279.0379)
			(xy 41.353784 -279.071992) (xy 41.383349 -279.111336) (xy 41.40622 -279.154913) (xy 41.421804 -279.201594)
			(xy 41.429699 -279.250171) (xy 41.430194 -279.274778) (xy 41.769042 -279.274778) (xy 41.773002 -279.225724)
			(xy 41.784779 -279.17794) (xy 41.80407 -279.132664) (xy 41.830373 -279.091068) (xy 41.863008 -279.054231)
			(xy 41.901129 -279.023106) (xy 41.94375 -278.998499) (xy 41.989766 -278.981047) (xy 42.037985 -278.971203)
			(xy 42.08716 -278.969222) (xy 42.136015 -278.975154) (xy 42.183286 -278.988846) (xy 42.227748 -279.009944)
			(xy 42.268251 -279.0379) (xy 42.303744 -279.071992) (xy 42.333309 -279.111336) (xy 42.35618 -279.154913)
			(xy 42.371764 -279.201594) (xy 42.379659 -279.250171) (xy 42.380154 -279.274778) (xy 42.379659 -279.299385)
			(xy 42.371764 -279.347962) (xy 42.35618 -279.394643) (xy 42.333309 -279.43822) (xy 42.303744 -279.477564)
			(xy 42.268251 -279.511656) (xy 42.227748 -279.539612) (xy 42.183286 -279.56071) (xy 42.136015 -279.574402)
			(xy 42.08716 -279.580334) (xy 42.037985 -279.578353) (xy 41.989766 -279.568509) (xy 41.94375 -279.551057)
			(xy 41.901129 -279.52645) (xy 41.863008 -279.495325) (xy 41.830373 -279.458488) (xy 41.80407 -279.416892)
			(xy 41.784779 -279.371616) (xy 41.773002 -279.323832) (xy 41.769042 -279.274778) (xy 41.430194 -279.274778)
			(xy 41.429699 -279.299385) (xy 41.421804 -279.347962) (xy 41.40622 -279.394643) (xy 41.383349 -279.43822)
			(xy 41.353784 -279.477564) (xy 41.318291 -279.511656) (xy 41.277788 -279.539612) (xy 41.233326 -279.56071)
			(xy 41.186055 -279.574402) (xy 41.1372 -279.580334) (xy 41.088025 -279.578353) (xy 41.039806 -279.568509)
			(xy 40.99379 -279.551057) (xy 40.951169 -279.52645) (xy 40.913048 -279.495325) (xy 40.880413 -279.458488)
			(xy 40.85411 -279.416892) (xy 40.834819 -279.371616) (xy 40.823042 -279.323832) (xy 40.819082 -279.274778)
			(xy 40.480234 -279.274778) (xy 40.479739 -279.299385) (xy 40.471844 -279.347962) (xy 40.45626 -279.394643)
			(xy 40.433389 -279.43822) (xy 40.403824 -279.477564) (xy 40.368331 -279.511656) (xy 40.327828 -279.539612)
			(xy 40.283366 -279.56071) (xy 40.236095 -279.574402) (xy 40.18724 -279.580334) (xy 40.138065 -279.578353)
			(xy 40.089846 -279.568509) (xy 40.04383 -279.551057) (xy 40.001209 -279.52645) (xy 39.963088 -279.495325)
			(xy 39.930453 -279.458488) (xy 39.90415 -279.416892) (xy 39.884859 -279.371616) (xy 39.873082 -279.323832)
			(xy 39.869122 -279.274778) (xy 39.530274 -279.274778) (xy 39.529779 -279.299385) (xy 39.521884 -279.347962)
			(xy 39.5063 -279.394643) (xy 39.483429 -279.43822) (xy 39.453864 -279.477564) (xy 39.418371 -279.511656)
			(xy 39.377868 -279.539612) (xy 39.333406 -279.56071) (xy 39.286135 -279.574402) (xy 39.23728 -279.580334)
			(xy 39.188105 -279.578353) (xy 39.139886 -279.568509) (xy 39.09387 -279.551057) (xy 39.051249 -279.52645)
			(xy 39.013128 -279.495325) (xy 38.980493 -279.458488) (xy 38.95419 -279.416892) (xy 38.934899 -279.371616)
			(xy 38.923122 -279.323832) (xy 38.919162 -279.274778) (xy 38.580314 -279.274778) (xy 38.579819 -279.299385)
			(xy 38.571924 -279.347962) (xy 38.55634 -279.394643) (xy 38.533469 -279.43822) (xy 38.503904 -279.477564)
			(xy 38.468411 -279.511656) (xy 38.427908 -279.539612) (xy 38.383446 -279.56071) (xy 38.336175 -279.574402)
			(xy 38.28732 -279.580334) (xy 38.238145 -279.578353) (xy 38.189926 -279.568509) (xy 38.14391 -279.551057)
			(xy 38.101289 -279.52645) (xy 38.063168 -279.495325) (xy 38.030533 -279.458488) (xy 38.00423 -279.416892)
			(xy 37.984939 -279.371616) (xy 37.973162 -279.323832) (xy 37.969202 -279.274778) (xy 37.6301 -279.274778)
			(xy 37.629605 -279.299385) (xy 37.62171 -279.347962) (xy 37.606126 -279.394643) (xy 37.583255 -279.43822)
			(xy 37.55369 -279.477564) (xy 37.518197 -279.511656) (xy 37.477694 -279.539612) (xy 37.433232 -279.56071)
			(xy 37.385961 -279.574402) (xy 37.337106 -279.580334) (xy 37.287931 -279.578353) (xy 37.239712 -279.568509)
			(xy 37.193696 -279.551057) (xy 37.151075 -279.52645) (xy 37.112954 -279.495325) (xy 37.080319 -279.458488)
			(xy 37.054016 -279.416892) (xy 37.034725 -279.371616) (xy 37.022948 -279.323832) (xy 37.018988 -279.274778)
			(xy 36.68014 -279.274778) (xy 36.679645 -279.299385) (xy 36.67175 -279.347962) (xy 36.656166 -279.394643)
			(xy 36.633295 -279.43822) (xy 36.60373 -279.477564) (xy 36.568237 -279.511656) (xy 36.527734 -279.539612)
			(xy 36.483272 -279.56071) (xy 36.436001 -279.574402) (xy 36.387146 -279.580334) (xy 36.337971 -279.578353)
			(xy 36.289752 -279.568509) (xy 36.243736 -279.551057) (xy 36.201115 -279.52645) (xy 36.162994 -279.495325)
			(xy 36.130359 -279.458488) (xy 36.104056 -279.416892) (xy 36.084765 -279.371616) (xy 36.072988 -279.323832)
			(xy 36.069028 -279.274778) (xy 7.729489 -279.274778) (xy 7.728649 -279.276542) (xy 7.697102 -279.323425)
			(xy 7.67842 -279.344628) (xy 7.671816 -279.35174) (xy 7.664958 -279.369266) (xy 7.664958 -279.45715)
			(xy 7.671816 -279.474676) (xy 7.67842 -279.481788) (xy 7.697095 -279.502995) (xy 7.728632 -279.54988)
			(xy 7.752909 -279.600904) (xy 7.769395 -279.654951) (xy 7.77773 -279.710837) (xy 7.778242 -279.73909)
			(xy 7.777713 -279.766339) (xy 7.769958 -279.820284) (xy 7.754606 -279.872576) (xy 7.731969 -279.92215)
			(xy 7.726209 -279.931114) (xy 25.811478 -279.931114) (xy 25.815549 -279.875492) (xy 25.827675 -279.821055)
			(xy 25.847598 -279.768964) (xy 25.874894 -279.720329) (xy 25.90898 -279.676186) (xy 25.949129 -279.637477)
			(xy 25.994487 -279.605026) (xy 26.044087 -279.579525) (xy 26.096871 -279.561518) (xy 26.151714 -279.551388)
			(xy 26.207448 -279.549351) (xy 26.262885 -279.555451) (xy 26.316842 -279.569557) (xy 26.368171 -279.591369)
			(xy 26.415777 -279.620423) (xy 26.458645 -279.656098) (xy 26.495862 -279.697635) (xy 26.526635 -279.744148)
			(xy 26.550307 -279.794645) (xy 26.566375 -279.848052) (xy 26.574495 -279.903228) (xy 26.575004 -279.931114)
			(xy 27.286964 -279.931114) (xy 27.291035 -279.875492) (xy 27.303161 -279.821055) (xy 27.323084 -279.768964)
			(xy 27.35038 -279.720329) (xy 27.384466 -279.676186) (xy 27.424615 -279.637477) (xy 27.469973 -279.605026)
			(xy 27.519573 -279.579525) (xy 27.572357 -279.561518) (xy 27.6272 -279.551388) (xy 27.682934 -279.549351)
			(xy 27.738371 -279.555451) (xy 27.792328 -279.569557) (xy 27.843657 -279.591369) (xy 27.891263 -279.620423)
			(xy 27.934131 -279.656098) (xy 27.971348 -279.697635) (xy 28.002121 -279.744148) (xy 28.025793 -279.794645)
			(xy 28.041861 -279.848052) (xy 28.049981 -279.903228) (xy 28.05049 -279.931114) (xy 28.175964 -279.931114)
			(xy 28.180035 -279.875492) (xy 28.192161 -279.821055) (xy 28.212084 -279.768964) (xy 28.23938 -279.720329)
			(xy 28.273466 -279.676186) (xy 28.313615 -279.637477) (xy 28.358973 -279.605026) (xy 28.408573 -279.579525)
			(xy 28.461357 -279.561518) (xy 28.5162 -279.551388) (xy 28.571934 -279.549351) (xy 28.627371 -279.555451)
			(xy 28.681328 -279.569557) (xy 28.732657 -279.591369) (xy 28.780263 -279.620423) (xy 28.823131 -279.656098)
			(xy 28.860348 -279.697635) (xy 28.891121 -279.744148) (xy 28.914793 -279.794645) (xy 28.930861 -279.848052)
			(xy 28.938981 -279.903228) (xy 28.93949 -279.931114) (xy 28.938981 -279.959) (xy 28.930861 -280.014176)
			(xy 28.914793 -280.067583) (xy 28.891121 -280.11808) (xy 28.860348 -280.164593) (xy 28.823131 -280.20613)
			(xy 28.780263 -280.241805) (xy 28.732657 -280.270859) (xy 28.681328 -280.292671) (xy 28.627371 -280.306777)
			(xy 28.571934 -280.312877) (xy 28.5162 -280.31084) (xy 28.461357 -280.30071) (xy 28.408573 -280.282703)
			(xy 28.358973 -280.257202) (xy 28.313615 -280.224751) (xy 28.273466 -280.186042) (xy 28.23938 -280.141899)
			(xy 28.212084 -280.093264) (xy 28.192161 -280.041173) (xy 28.180035 -279.986736) (xy 28.175964 -279.931114)
			(xy 28.05049 -279.931114) (xy 28.049981 -279.959) (xy 28.041861 -280.014176) (xy 28.025793 -280.067583)
			(xy 28.002121 -280.11808) (xy 27.971348 -280.164593) (xy 27.934131 -280.20613) (xy 27.891263 -280.241805)
			(xy 27.843657 -280.270859) (xy 27.792328 -280.292671) (xy 27.738371 -280.306777) (xy 27.682934 -280.312877)
			(xy 27.6272 -280.31084) (xy 27.572357 -280.30071) (xy 27.519573 -280.282703) (xy 27.469973 -280.257202)
			(xy 27.424615 -280.224751) (xy 27.384466 -280.186042) (xy 27.35038 -280.141899) (xy 27.323084 -280.093264)
			(xy 27.303161 -280.041173) (xy 27.291035 -279.986736) (xy 27.286964 -279.931114) (xy 26.575004 -279.931114)
			(xy 26.574495 -279.959) (xy 26.566375 -280.014176) (xy 26.550307 -280.067583) (xy 26.526635 -280.11808)
			(xy 26.495862 -280.164593) (xy 26.458645 -280.20613) (xy 26.415777 -280.241805) (xy 26.368171 -280.270859)
			(xy 26.316842 -280.292671) (xy 26.262885 -280.306777) (xy 26.207448 -280.312877) (xy 26.151714 -280.31084)
			(xy 26.096871 -280.30071) (xy 26.044087 -280.282703) (xy 25.994487 -280.257202) (xy 25.949129 -280.224751)
			(xy 25.90898 -280.186042) (xy 25.874894 -280.141899) (xy 25.847598 -280.093264) (xy 25.827675 -280.041173)
			(xy 25.815549 -279.986736) (xy 25.811478 -279.931114) (xy 7.726209 -279.931114) (xy 7.702507 -279.967999)
			(xy 7.66682 -280.009189) (xy 7.625634 -280.04488) (xy 7.579789 -280.074348) (xy 7.530217 -280.096991)
			(xy 7.477927 -280.112349) (xy 7.423983 -280.120109) (xy 7.396734 -280.120598) (xy 7.367994 -280.120115)
			(xy 7.311164 -280.111483) (xy 7.256273 -280.094423) (xy 7.204562 -280.069322) (xy 7.157201 -280.036749)
			(xy 7.135876 -280.017474) (xy 7.128764 -280.01087) (xy 7.111238 -280.003758) (xy 7.02183 -280.003758)
			(xy 7.004304 -280.01087) (xy 6.997192 -280.017474) (xy 6.975865 -280.036744) (xy 6.928502 -280.069309)
			(xy 6.876791 -280.0944) (xy 6.8219 -280.11145) (xy 6.765073 -280.120072) (xy 6.707595 -280.120072)
			(xy 6.650768 -280.11145) (xy 6.595877 -280.0944) (xy 6.544166 -280.069309) (xy 6.496803 -280.036744)
			(xy 6.475476 -280.017474) (xy 6.468364 -280.01087) (xy 6.450838 -280.003758) (xy 6.36143 -280.003758)
			(xy 6.343904 -280.01087) (xy 6.336792 -280.017474) (xy 6.315465 -280.036744) (xy 6.268102 -280.069309)
			(xy 6.216391 -280.0944) (xy 6.1615 -280.11145) (xy 6.104673 -280.120072) (xy 6.047195 -280.120072)
			(xy 5.990368 -280.11145) (xy 5.935477 -280.0944) (xy 5.883766 -280.069309) (xy 5.836403 -280.036744)
			(xy 5.815076 -280.017474) (xy 5.807964 -280.01087) (xy 5.790438 -280.003758) (xy 5.70103 -280.003758)
			(xy 5.683504 -280.01087) (xy 5.676392 -280.017474) (xy 5.655053 -280.036731) (xy 5.607694 -280.069298)
			(xy 5.555985 -280.094393) (xy 5.501097 -280.111447) (xy 5.444272 -280.120075) (xy 5.415534 -280.120598)
			(xy 5.388282 -280.120113) (xy 5.334331 -280.11236) (xy 5.282033 -280.097008) (xy 5.232452 -280.074369)
			(xy 5.186598 -280.044904) (xy 5.145405 -280.009212) (xy 5.109711 -279.968021) (xy 5.080243 -279.922169)
			(xy 5.0576 -279.87259) (xy 5.042245 -279.820293) (xy 5.034489 -279.766342) (xy 5.034026 -279.73909)
			(xy 1.468374 -279.73909) (xy 1.468374 -280.722651) (xy 9.692378 -280.722651) (xy 9.692378 -280.668149)
			(xy 9.700134 -280.614203) (xy 9.715488 -280.561909) (xy 9.738128 -280.512333) (xy 9.767593 -280.466483)
			(xy 9.803283 -280.425293) (xy 9.844472 -280.389602) (xy 9.890321 -280.360135) (xy 9.939896 -280.337493)
			(xy 9.992189 -280.322137) (xy 10.046135 -280.314379) (xy 10.073386 -280.313892) (xy 10.102124 -280.314426)
			(xy 10.158951 -280.323047) (xy 10.213842 -280.340094) (xy 10.265554 -280.365184) (xy 10.312917 -280.397746)
			(xy 10.334244 -280.417016) (xy 10.341356 -280.42362) (xy 10.358882 -280.430732) (xy 10.44829 -280.430732)
			(xy 10.465816 -280.42362) (xy 10.472928 -280.417016) (xy 10.494255 -280.397746) (xy 10.541618 -280.365181)
			(xy 10.593329 -280.34009) (xy 10.64822 -280.32304) (xy 10.705047 -280.314418) (xy 10.762525 -280.314418)
			(xy 10.819352 -280.32304) (xy 10.874243 -280.34009) (xy 10.925954 -280.365181) (xy 10.973317 -280.397746)
			(xy 10.994644 -280.417016) (xy 11.001756 -280.42362) (xy 11.019282 -280.430732) (xy 11.10869 -280.430732)
			(xy 11.126216 -280.42362) (xy 11.133328 -280.417016) (xy 11.154658 -280.397748) (xy 11.202019 -280.365182)
			(xy 11.25373 -280.34009) (xy 11.30862 -280.323038) (xy 11.365447 -280.314414) (xy 11.394186 -280.313892)
			(xy 11.42431 -280.31446) (xy 11.483807 -280.32394) (xy 11.541075 -280.342651) (xy 11.594692 -280.370128)
			(xy 11.643326 -280.405688) (xy 11.66495 -280.426668) (xy 11.672062 -280.434034) (xy 11.690858 -280.441654)
			(xy 11.783314 -280.441654) (xy 11.80211 -280.434034) (xy 11.809222 -280.426668) (xy 11.83087 -280.405712)
			(xy 11.879491 -280.370138) (xy 11.933102 -280.342652) (xy 11.990367 -280.323939) (xy 12.049863 -280.314463)
			(xy 12.079986 -280.313892) (xy 12.10724 -280.314354) (xy 12.161192 -280.32211) (xy 12.213491 -280.337465)
			(xy 12.263073 -280.360106) (xy 12.308928 -280.389574) (xy 12.350123 -280.425268) (xy 12.385818 -280.466461)
			(xy 12.415287 -280.512314) (xy 12.437931 -280.561895) (xy 12.453287 -280.614194) (xy 12.461045 -280.668147)
			(xy 12.461045 -280.72265) (xy 13.939778 -280.72265) (xy 13.939778 -280.66815) (xy 13.947534 -280.614204)
			(xy 13.962887 -280.561912) (xy 13.985527 -280.512336) (xy 14.01499 -280.466487) (xy 14.050679 -280.425298)
			(xy 14.091866 -280.389606) (xy 14.137713 -280.360139) (xy 14.187287 -280.337496) (xy 14.239579 -280.322139)
			(xy 14.293524 -280.31438) (xy 14.320774 -280.313892) (xy 14.349512 -280.314434) (xy 14.406339 -280.323052)
			(xy 14.461229 -280.340098) (xy 14.512941 -280.365186) (xy 14.560305 -280.397747) (xy 14.581632 -280.417016)
			(xy 14.588744 -280.42362) (xy 14.60627 -280.430732) (xy 14.695678 -280.430732) (xy 14.713204 -280.42362)
			(xy 14.720316 -280.417016) (xy 14.741643 -280.397746) (xy 14.789006 -280.365181) (xy 14.840717 -280.34009)
			(xy 14.895608 -280.32304) (xy 14.952435 -280.314418) (xy 15.009913 -280.314418) (xy 15.06674 -280.32304)
			(xy 15.121631 -280.34009) (xy 15.173342 -280.365181) (xy 15.220705 -280.397746) (xy 15.242032 -280.417016)
			(xy 15.249144 -280.42362) (xy 15.26667 -280.430732) (xy 15.356078 -280.430732) (xy 15.373604 -280.42362)
			(xy 15.380716 -280.417016) (xy 15.40205 -280.397754) (xy 15.449411 -280.365187) (xy 15.501121 -280.340094)
			(xy 15.55601 -280.323041) (xy 15.612836 -280.314415) (xy 15.641574 -280.313892) (xy 15.671697 -280.314467)
			(xy 15.731194 -280.323945) (xy 15.788462 -280.342655) (xy 15.84208 -280.37013) (xy 15.890713 -280.405689)
			(xy 15.912338 -280.426668) (xy 15.91945 -280.434034) (xy 15.938246 -280.441654) (xy 16.030702 -280.441654)
			(xy 16.049498 -280.434034) (xy 16.05661 -280.426668) (xy 16.078219 -280.40567) (xy 16.126851 -280.370101)
			(xy 16.180471 -280.342623) (xy 16.237745 -280.32392) (xy 16.297248 -280.314456) (xy 16.327374 -280.313892)
			(xy 16.354628 -280.314354) (xy 16.408582 -280.322108) (xy 16.460883 -280.337461) (xy 16.510466 -280.360102)
			(xy 16.556323 -280.38957) (xy 16.597518 -280.425263) (xy 16.633215 -280.466457) (xy 16.662685 -280.512311)
			(xy 16.68533 -280.561893) (xy 16.700687 -280.614193) (xy 16.708445 -280.668146) (xy 16.708445 -280.693114)
			(xy 31.338012 -280.693114) (xy 31.338555 -280.663732) (xy 31.347584 -280.605665) (xy 31.365415 -280.54967)
			(xy 31.391626 -280.497075) (xy 31.425597 -280.449124) (xy 31.466521 -280.406952) (xy 31.48965 -280.388822)
			(xy 31.499048 -280.381456) (xy 31.509462 -280.360882) (xy 31.510986 -280.256996) (xy 31.50108 -280.235914)
			(xy 31.491936 -280.228548) (xy 31.470088 -280.210342) (xy 31.431546 -280.168524) (xy 31.399638 -280.121449)
			(xy 31.375071 -280.070159) (xy 31.358388 -280.015791) (xy 31.34996 -279.959549) (xy 31.349442 -279.931114)
			(xy 31.349928 -279.903863) (xy 31.357684 -279.849915) (xy 31.373039 -279.79762) (xy 31.395681 -279.748043)
			(xy 31.425147 -279.702193) (xy 31.460838 -279.661002) (xy 31.502029 -279.625311) (xy 31.547879 -279.595845)
			(xy 31.597456 -279.573203) (xy 31.649751 -279.557848) (xy 31.703699 -279.550092) (xy 31.758201 -279.550092)
			(xy 31.812149 -279.557848) (xy 31.864444 -279.573203) (xy 31.914021 -279.595845) (xy 31.959871 -279.625311)
			(xy 32.001062 -279.661002) (xy 32.036753 -279.702193) (xy 32.066219 -279.748043) (xy 32.067002 -279.749758)
			(xy 44.143942 -279.749758) (xy 44.147902 -279.700704) (xy 44.159679 -279.65292) (xy 44.17897 -279.607644)
			(xy 44.205273 -279.566048) (xy 44.237908 -279.529211) (xy 44.276029 -279.498086) (xy 44.31865 -279.473479)
			(xy 44.364666 -279.456027) (xy 44.412885 -279.446183) (xy 44.46206 -279.444202) (xy 44.510915 -279.450134)
			(xy 44.558186 -279.463826) (xy 44.602648 -279.484924) (xy 44.643151 -279.51288) (xy 44.678644 -279.546972)
			(xy 44.708209 -279.586316) (xy 44.73108 -279.629893) (xy 44.746664 -279.676574) (xy 44.754559 -279.725151)
			(xy 44.755049 -279.749504) (xy 45.094156 -279.749504) (xy 45.098116 -279.70045) (xy 45.109893 -279.652666)
			(xy 45.129184 -279.60739) (xy 45.155487 -279.565794) (xy 45.188122 -279.528957) (xy 45.226243 -279.497832)
			(xy 45.268864 -279.473225) (xy 45.31488 -279.455773) (xy 45.363099 -279.445929) (xy 45.412274 -279.443948)
			(xy 45.461129 -279.44988) (xy 45.5084 -279.463572) (xy 45.552862 -279.48467) (xy 45.593365 -279.512626)
			(xy 45.628858 -279.546718) (xy 45.658423 -279.586062) (xy 45.681294 -279.629639) (xy 45.696878 -279.67632)
			(xy 45.704773 -279.724897) (xy 45.705268 -279.749504) (xy 45.705263 -279.749758) (xy 46.044116 -279.749758)
			(xy 46.048076 -279.700704) (xy 46.059853 -279.65292) (xy 46.079144 -279.607644) (xy 46.105447 -279.566048)
			(xy 46.138082 -279.529211) (xy 46.176203 -279.498086) (xy 46.218824 -279.473479) (xy 46.26484 -279.456027)
			(xy 46.313059 -279.446183) (xy 46.362234 -279.444202) (xy 46.411089 -279.450134) (xy 46.45836 -279.463826)
			(xy 46.502822 -279.484924) (xy 46.543325 -279.51288) (xy 46.578818 -279.546972) (xy 46.608383 -279.586316)
			(xy 46.631254 -279.629893) (xy 46.646838 -279.676574) (xy 46.654733 -279.725151) (xy 46.655223 -279.749504)
			(xy 46.994076 -279.749504) (xy 46.998036 -279.70045) (xy 47.009813 -279.652666) (xy 47.029104 -279.60739)
			(xy 47.055407 -279.565794) (xy 47.088042 -279.528957) (xy 47.126163 -279.497832) (xy 47.168784 -279.473225)
			(xy 47.2148 -279.455773) (xy 47.263019 -279.445929) (xy 47.312194 -279.443948) (xy 47.361049 -279.44988)
			(xy 47.40832 -279.463572) (xy 47.452782 -279.48467) (xy 47.493285 -279.512626) (xy 47.528778 -279.546718)
			(xy 47.558343 -279.586062) (xy 47.581214 -279.629639) (xy 47.596798 -279.67632) (xy 47.604693 -279.724897)
			(xy 47.605188 -279.749504) (xy 47.605183 -279.749758) (xy 47.944036 -279.749758) (xy 47.947996 -279.700704)
			(xy 47.959773 -279.65292) (xy 47.979064 -279.607644) (xy 48.005367 -279.566048) (xy 48.038002 -279.529211)
			(xy 48.076123 -279.498086) (xy 48.118744 -279.473479) (xy 48.16476 -279.456027) (xy 48.212979 -279.446183)
			(xy 48.262154 -279.444202) (xy 48.311009 -279.450134) (xy 48.35828 -279.463826) (xy 48.402742 -279.484924)
			(xy 48.443245 -279.51288) (xy 48.478738 -279.546972) (xy 48.508303 -279.586316) (xy 48.531174 -279.629893)
			(xy 48.546758 -279.676574) (xy 48.554653 -279.725151) (xy 48.555143 -279.749504) (xy 48.893996 -279.749504)
			(xy 48.897956 -279.70045) (xy 48.909733 -279.652666) (xy 48.929024 -279.60739) (xy 48.955327 -279.565794)
			(xy 48.987962 -279.528957) (xy 49.026083 -279.497832) (xy 49.068704 -279.473225) (xy 49.11472 -279.455773)
			(xy 49.162939 -279.445929) (xy 49.212114 -279.443948) (xy 49.260969 -279.44988) (xy 49.30824 -279.463572)
			(xy 49.352702 -279.48467) (xy 49.393205 -279.512626) (xy 49.428698 -279.546718) (xy 49.458263 -279.586062)
			(xy 49.481134 -279.629639) (xy 49.496718 -279.67632) (xy 49.504613 -279.724897) (xy 49.505108 -279.749504)
			(xy 49.505103 -279.749758) (xy 49.843956 -279.749758) (xy 49.847916 -279.700704) (xy 49.859693 -279.65292)
			(xy 49.878984 -279.607644) (xy 49.905287 -279.566048) (xy 49.937922 -279.529211) (xy 49.976043 -279.498086)
			(xy 50.018664 -279.473479) (xy 50.06468 -279.456027) (xy 50.112899 -279.446183) (xy 50.162074 -279.444202)
			(xy 50.210929 -279.450134) (xy 50.2582 -279.463826) (xy 50.302662 -279.484924) (xy 50.343165 -279.51288)
			(xy 50.378658 -279.546972) (xy 50.408223 -279.586316) (xy 50.431094 -279.629893) (xy 50.446678 -279.676574)
			(xy 50.454573 -279.725151) (xy 50.455063 -279.749504) (xy 50.79417 -279.749504) (xy 50.79813 -279.70045)
			(xy 50.809907 -279.652666) (xy 50.829198 -279.60739) (xy 50.855501 -279.565794) (xy 50.888136 -279.528957)
			(xy 50.926257 -279.497832) (xy 50.968878 -279.473225) (xy 51.014894 -279.455773) (xy 51.063113 -279.445929)
			(xy 51.112288 -279.443948) (xy 51.161143 -279.44988) (xy 51.208414 -279.463572) (xy 51.252876 -279.48467)
			(xy 51.293379 -279.512626) (xy 51.328872 -279.546718) (xy 51.358437 -279.586062) (xy 51.381308 -279.629639)
			(xy 51.396892 -279.67632) (xy 51.404787 -279.724897) (xy 51.405282 -279.749504) (xy 51.405277 -279.749758)
			(xy 51.74413 -279.749758) (xy 51.74809 -279.700704) (xy 51.759867 -279.65292) (xy 51.779158 -279.607644)
			(xy 51.805461 -279.566048) (xy 51.838096 -279.529211) (xy 51.876217 -279.498086) (xy 51.918838 -279.473479)
			(xy 51.964854 -279.456027) (xy 52.013073 -279.446183) (xy 52.062248 -279.444202) (xy 52.111103 -279.450134)
			(xy 52.158374 -279.463826) (xy 52.202836 -279.484924) (xy 52.243339 -279.51288) (xy 52.278832 -279.546972)
			(xy 52.308397 -279.586316) (xy 52.331268 -279.629893) (xy 52.346852 -279.676574) (xy 52.354747 -279.725151)
			(xy 52.355237 -279.749504) (xy 52.69409 -279.749504) (xy 52.69805 -279.70045) (xy 52.709827 -279.652666)
			(xy 52.729118 -279.60739) (xy 52.755421 -279.565794) (xy 52.788056 -279.528957) (xy 52.826177 -279.497832)
			(xy 52.868798 -279.473225) (xy 52.914814 -279.455773) (xy 52.963033 -279.445929) (xy 53.012208 -279.443948)
			(xy 53.061063 -279.44988) (xy 53.108334 -279.463572) (xy 53.152796 -279.48467) (xy 53.193299 -279.512626)
			(xy 53.228792 -279.546718) (xy 53.258357 -279.586062) (xy 53.281228 -279.629639) (xy 53.296812 -279.67632)
			(xy 53.304707 -279.724897) (xy 53.305202 -279.749504) (xy 53.305197 -279.749758) (xy 53.64405 -279.749758)
			(xy 53.64801 -279.700704) (xy 53.659787 -279.65292) (xy 53.679078 -279.607644) (xy 53.705381 -279.566048)
			(xy 53.738016 -279.529211) (xy 53.776137 -279.498086) (xy 53.818758 -279.473479) (xy 53.864774 -279.456027)
			(xy 53.912993 -279.446183) (xy 53.962168 -279.444202) (xy 54.011023 -279.450134) (xy 54.058294 -279.463826)
			(xy 54.102756 -279.484924) (xy 54.143259 -279.51288) (xy 54.178752 -279.546972) (xy 54.208317 -279.586316)
			(xy 54.231188 -279.629893) (xy 54.246772 -279.676574) (xy 54.254667 -279.725151) (xy 54.255157 -279.749504)
			(xy 54.59401 -279.749504) (xy 54.59797 -279.70045) (xy 54.609747 -279.652666) (xy 54.629038 -279.60739)
			(xy 54.655341 -279.565794) (xy 54.687976 -279.528957) (xy 54.726097 -279.497832) (xy 54.768718 -279.473225)
			(xy 54.814734 -279.455773) (xy 54.862953 -279.445929) (xy 54.912128 -279.443948) (xy 54.960983 -279.44988)
			(xy 55.008254 -279.463572) (xy 55.052716 -279.48467) (xy 55.093219 -279.512626) (xy 55.128712 -279.546718)
			(xy 55.158277 -279.586062) (xy 55.181148 -279.629639) (xy 55.196732 -279.67632) (xy 55.204627 -279.724897)
			(xy 55.205122 -279.749504) (xy 55.205117 -279.749758) (xy 55.54397 -279.749758) (xy 55.54793 -279.700704)
			(xy 55.559707 -279.65292) (xy 55.578998 -279.607644) (xy 55.605301 -279.566048) (xy 55.637936 -279.529211)
			(xy 55.676057 -279.498086) (xy 55.718678 -279.473479) (xy 55.764694 -279.456027) (xy 55.812913 -279.446183)
			(xy 55.862088 -279.444202) (xy 55.910943 -279.450134) (xy 55.958214 -279.463826) (xy 56.002676 -279.484924)
			(xy 56.043179 -279.51288) (xy 56.078672 -279.546972) (xy 56.108237 -279.586316) (xy 56.131108 -279.629893)
			(xy 56.146692 -279.676574) (xy 56.154587 -279.725151) (xy 56.155077 -279.749504) (xy 56.49393 -279.749504)
			(xy 56.49789 -279.70045) (xy 56.509667 -279.652666) (xy 56.528958 -279.60739) (xy 56.555261 -279.565794)
			(xy 56.587896 -279.528957) (xy 56.626017 -279.497832) (xy 56.668638 -279.473225) (xy 56.714654 -279.455773)
			(xy 56.762873 -279.445929) (xy 56.812048 -279.443948) (xy 56.860903 -279.44988) (xy 56.908174 -279.463572)
			(xy 56.952636 -279.48467) (xy 56.993139 -279.512626) (xy 57.028632 -279.546718) (xy 57.058197 -279.586062)
			(xy 57.081068 -279.629639) (xy 57.096652 -279.67632) (xy 57.104547 -279.724897) (xy 57.105042 -279.749504)
			(xy 57.104547 -279.774111) (xy 57.096652 -279.822688) (xy 57.081068 -279.869369) (xy 57.058197 -279.912946)
			(xy 57.028632 -279.95229) (xy 56.993139 -279.986382) (xy 56.952636 -280.014338) (xy 56.908174 -280.035436)
			(xy 56.860903 -280.049128) (xy 56.812048 -280.05506) (xy 56.762873 -280.053079) (xy 56.714654 -280.043235)
			(xy 56.668638 -280.025783) (xy 56.626017 -280.001176) (xy 56.587896 -279.970051) (xy 56.555261 -279.933214)
			(xy 56.528958 -279.891618) (xy 56.509667 -279.846342) (xy 56.49789 -279.798558) (xy 56.49393 -279.749504)
			(xy 56.155077 -279.749504) (xy 56.155082 -279.749758) (xy 56.154587 -279.774365) (xy 56.146692 -279.822942)
			(xy 56.131108 -279.869623) (xy 56.108237 -279.9132) (xy 56.078672 -279.952544) (xy 56.043179 -279.986636)
			(xy 56.002676 -280.014592) (xy 55.958214 -280.03569) (xy 55.910943 -280.049382) (xy 55.862088 -280.055314)
			(xy 55.812913 -280.053333) (xy 55.764694 -280.043489) (xy 55.718678 -280.026037) (xy 55.676057 -280.00143)
			(xy 55.637936 -279.970305) (xy 55.605301 -279.933468) (xy 55.578998 -279.891872) (xy 55.559707 -279.846596)
			(xy 55.54793 -279.798812) (xy 55.54397 -279.749758) (xy 55.205117 -279.749758) (xy 55.204627 -279.774111)
			(xy 55.196732 -279.822688) (xy 55.181148 -279.869369) (xy 55.158277 -279.912946) (xy 55.128712 -279.95229)
			(xy 55.093219 -279.986382) (xy 55.052716 -280.014338) (xy 55.008254 -280.035436) (xy 54.960983 -280.049128)
			(xy 54.912128 -280.05506) (xy 54.862953 -280.053079) (xy 54.814734 -280.043235) (xy 54.768718 -280.025783)
			(xy 54.726097 -280.001176) (xy 54.687976 -279.970051) (xy 54.655341 -279.933214) (xy 54.629038 -279.891618)
			(xy 54.609747 -279.846342) (xy 54.59797 -279.798558) (xy 54.59401 -279.749504) (xy 54.255157 -279.749504)
			(xy 54.255162 -279.749758) (xy 54.254667 -279.774365) (xy 54.246772 -279.822942) (xy 54.231188 -279.869623)
			(xy 54.208317 -279.9132) (xy 54.178752 -279.952544) (xy 54.143259 -279.986636) (xy 54.102756 -280.014592)
			(xy 54.058294 -280.03569) (xy 54.011023 -280.049382) (xy 53.962168 -280.055314) (xy 53.912993 -280.053333)
			(xy 53.864774 -280.043489) (xy 53.818758 -280.026037) (xy 53.776137 -280.00143) (xy 53.738016 -279.970305)
			(xy 53.705381 -279.933468) (xy 53.679078 -279.891872) (xy 53.659787 -279.846596) (xy 53.64801 -279.798812)
			(xy 53.64405 -279.749758) (xy 53.305197 -279.749758) (xy 53.304707 -279.774111) (xy 53.296812 -279.822688)
			(xy 53.281228 -279.869369) (xy 53.258357 -279.912946) (xy 53.228792 -279.95229) (xy 53.193299 -279.986382)
			(xy 53.152796 -280.014338) (xy 53.108334 -280.035436) (xy 53.061063 -280.049128) (xy 53.012208 -280.05506)
			(xy 52.963033 -280.053079) (xy 52.914814 -280.043235) (xy 52.868798 -280.025783) (xy 52.826177 -280.001176)
			(xy 52.788056 -279.970051) (xy 52.755421 -279.933214) (xy 52.729118 -279.891618) (xy 52.709827 -279.846342)
			(xy 52.69805 -279.798558) (xy 52.69409 -279.749504) (xy 52.355237 -279.749504) (xy 52.355242 -279.749758)
			(xy 52.354747 -279.774365) (xy 52.346852 -279.822942) (xy 52.331268 -279.869623) (xy 52.308397 -279.9132)
			(xy 52.278832 -279.952544) (xy 52.243339 -279.986636) (xy 52.202836 -280.014592) (xy 52.158374 -280.03569)
			(xy 52.111103 -280.049382) (xy 52.062248 -280.055314) (xy 52.013073 -280.053333) (xy 51.964854 -280.043489)
			(xy 51.918838 -280.026037) (xy 51.876217 -280.00143) (xy 51.838096 -279.970305) (xy 51.805461 -279.933468)
			(xy 51.779158 -279.891872) (xy 51.759867 -279.846596) (xy 51.74809 -279.798812) (xy 51.74413 -279.749758)
			(xy 51.405277 -279.749758) (xy 51.404787 -279.774111) (xy 51.396892 -279.822688) (xy 51.381308 -279.869369)
			(xy 51.358437 -279.912946) (xy 51.328872 -279.95229) (xy 51.293379 -279.986382) (xy 51.252876 -280.014338)
			(xy 51.208414 -280.035436) (xy 51.161143 -280.049128) (xy 51.112288 -280.05506) (xy 51.063113 -280.053079)
			(xy 51.014894 -280.043235) (xy 50.968878 -280.025783) (xy 50.926257 -280.001176) (xy 50.888136 -279.970051)
			(xy 50.855501 -279.933214) (xy 50.829198 -279.891618) (xy 50.809907 -279.846342) (xy 50.79813 -279.798558)
			(xy 50.79417 -279.749504) (xy 50.455063 -279.749504) (xy 50.455068 -279.749758) (xy 50.454573 -279.774365)
			(xy 50.446678 -279.822942) (xy 50.431094 -279.869623) (xy 50.408223 -279.9132) (xy 50.378658 -279.952544)
			(xy 50.343165 -279.986636) (xy 50.302662 -280.014592) (xy 50.2582 -280.03569) (xy 50.210929 -280.049382)
			(xy 50.162074 -280.055314) (xy 50.112899 -280.053333) (xy 50.06468 -280.043489) (xy 50.018664 -280.026037)
			(xy 49.976043 -280.00143) (xy 49.937922 -279.970305) (xy 49.905287 -279.933468) (xy 49.878984 -279.891872)
			(xy 49.859693 -279.846596) (xy 49.847916 -279.798812) (xy 49.843956 -279.749758) (xy 49.505103 -279.749758)
			(xy 49.504613 -279.774111) (xy 49.496718 -279.822688) (xy 49.481134 -279.869369) (xy 49.458263 -279.912946)
			(xy 49.428698 -279.95229) (xy 49.393205 -279.986382) (xy 49.352702 -280.014338) (xy 49.30824 -280.035436)
			(xy 49.260969 -280.049128) (xy 49.212114 -280.05506) (xy 49.162939 -280.053079) (xy 49.11472 -280.043235)
			(xy 49.068704 -280.025783) (xy 49.026083 -280.001176) (xy 48.987962 -279.970051) (xy 48.955327 -279.933214)
			(xy 48.929024 -279.891618) (xy 48.909733 -279.846342) (xy 48.897956 -279.798558) (xy 48.893996 -279.749504)
			(xy 48.555143 -279.749504) (xy 48.555148 -279.749758) (xy 48.554653 -279.774365) (xy 48.546758 -279.822942)
			(xy 48.531174 -279.869623) (xy 48.508303 -279.9132) (xy 48.478738 -279.952544) (xy 48.443245 -279.986636)
			(xy 48.402742 -280.014592) (xy 48.35828 -280.03569) (xy 48.311009 -280.049382) (xy 48.262154 -280.055314)
			(xy 48.212979 -280.053333) (xy 48.16476 -280.043489) (xy 48.118744 -280.026037) (xy 48.076123 -280.00143)
			(xy 48.038002 -279.970305) (xy 48.005367 -279.933468) (xy 47.979064 -279.891872) (xy 47.959773 -279.846596)
			(xy 47.947996 -279.798812) (xy 47.944036 -279.749758) (xy 47.605183 -279.749758) (xy 47.604693 -279.774111)
			(xy 47.596798 -279.822688) (xy 47.581214 -279.869369) (xy 47.558343 -279.912946) (xy 47.528778 -279.95229)
			(xy 47.493285 -279.986382) (xy 47.452782 -280.014338) (xy 47.40832 -280.035436) (xy 47.361049 -280.049128)
			(xy 47.312194 -280.05506) (xy 47.263019 -280.053079) (xy 47.2148 -280.043235) (xy 47.168784 -280.025783)
			(xy 47.126163 -280.001176) (xy 47.088042 -279.970051) (xy 47.055407 -279.933214) (xy 47.029104 -279.891618)
			(xy 47.009813 -279.846342) (xy 46.998036 -279.798558) (xy 46.994076 -279.749504) (xy 46.655223 -279.749504)
			(xy 46.655228 -279.749758) (xy 46.654733 -279.774365) (xy 46.646838 -279.822942) (xy 46.631254 -279.869623)
			(xy 46.608383 -279.9132) (xy 46.578818 -279.952544) (xy 46.543325 -279.986636) (xy 46.502822 -280.014592)
			(xy 46.45836 -280.03569) (xy 46.411089 -280.049382) (xy 46.362234 -280.055314) (xy 46.313059 -280.053333)
			(xy 46.26484 -280.043489) (xy 46.218824 -280.026037) (xy 46.176203 -280.00143) (xy 46.138082 -279.970305)
			(xy 46.105447 -279.933468) (xy 46.079144 -279.891872) (xy 46.059853 -279.846596) (xy 46.048076 -279.798812)
			(xy 46.044116 -279.749758) (xy 45.705263 -279.749758) (xy 45.704773 -279.774111) (xy 45.696878 -279.822688)
			(xy 45.681294 -279.869369) (xy 45.658423 -279.912946) (xy 45.628858 -279.95229) (xy 45.593365 -279.986382)
			(xy 45.552862 -280.014338) (xy 45.5084 -280.035436) (xy 45.461129 -280.049128) (xy 45.412274 -280.05506)
			(xy 45.363099 -280.053079) (xy 45.31488 -280.043235) (xy 45.268864 -280.025783) (xy 45.226243 -280.001176)
			(xy 45.188122 -279.970051) (xy 45.155487 -279.933214) (xy 45.129184 -279.891618) (xy 45.109893 -279.846342)
			(xy 45.098116 -279.798558) (xy 45.094156 -279.749504) (xy 44.755049 -279.749504) (xy 44.755054 -279.749758)
			(xy 44.754559 -279.774365) (xy 44.746664 -279.822942) (xy 44.73108 -279.869623) (xy 44.708209 -279.9132)
			(xy 44.678644 -279.952544) (xy 44.643151 -279.986636) (xy 44.602648 -280.014592) (xy 44.558186 -280.03569)
			(xy 44.510915 -280.049382) (xy 44.46206 -280.055314) (xy 44.412885 -280.053333) (xy 44.364666 -280.043489)
			(xy 44.31865 -280.026037) (xy 44.276029 -280.00143) (xy 44.237908 -279.970305) (xy 44.205273 -279.933468)
			(xy 44.17897 -279.891872) (xy 44.159679 -279.846596) (xy 44.147902 -279.798812) (xy 44.143942 -279.749758)
			(xy 32.067002 -279.749758) (xy 32.088861 -279.79762) (xy 32.104216 -279.849915) (xy 32.111972 -279.903863)
			(xy 32.112458 -279.931114) (xy 32.111907 -279.960496) (xy 32.102876 -280.018561) (xy 32.085044 -280.074554)
			(xy 32.058835 -280.127149) (xy 32.024867 -280.1751) (xy 31.983946 -280.217274) (xy 31.974426 -280.224738)
			(xy 36.069028 -280.224738) (xy 36.072988 -280.175684) (xy 36.084765 -280.1279) (xy 36.104056 -280.082624)
			(xy 36.130359 -280.041028) (xy 36.162994 -280.004191) (xy 36.201115 -279.973066) (xy 36.243736 -279.948459)
			(xy 36.289752 -279.931007) (xy 36.337971 -279.921163) (xy 36.387146 -279.919182) (xy 36.436001 -279.925114)
			(xy 36.483272 -279.938806) (xy 36.527734 -279.959904) (xy 36.568237 -279.98786) (xy 36.60373 -280.021952)
			(xy 36.633295 -280.061296) (xy 36.656166 -280.104873) (xy 36.67175 -280.151554) (xy 36.679645 -280.200131)
			(xy 36.68014 -280.224738) (xy 37.018988 -280.224738) (xy 37.022948 -280.175684) (xy 37.034725 -280.1279)
			(xy 37.054016 -280.082624) (xy 37.080319 -280.041028) (xy 37.112954 -280.004191) (xy 37.151075 -279.973066)
			(xy 37.193696 -279.948459) (xy 37.239712 -279.931007) (xy 37.287931 -279.921163) (xy 37.337106 -279.919182)
			(xy 37.385961 -279.925114) (xy 37.433232 -279.938806) (xy 37.477694 -279.959904) (xy 37.518197 -279.98786)
			(xy 37.55369 -280.021952) (xy 37.583255 -280.061296) (xy 37.606126 -280.104873) (xy 37.62171 -280.151554)
			(xy 37.629605 -280.200131) (xy 37.6301 -280.224738) (xy 37.969202 -280.224738) (xy 37.973162 -280.175684)
			(xy 37.984939 -280.1279) (xy 38.00423 -280.082624) (xy 38.030533 -280.041028) (xy 38.063168 -280.004191)
			(xy 38.101289 -279.973066) (xy 38.14391 -279.948459) (xy 38.189926 -279.931007) (xy 38.238145 -279.921163)
			(xy 38.28732 -279.919182) (xy 38.336175 -279.925114) (xy 38.383446 -279.938806) (xy 38.427908 -279.959904)
			(xy 38.468411 -279.98786) (xy 38.503904 -280.021952) (xy 38.533469 -280.061296) (xy 38.55634 -280.104873)
			(xy 38.571924 -280.151554) (xy 38.579819 -280.200131) (xy 38.580314 -280.224738) (xy 38.919162 -280.224738)
			(xy 38.923122 -280.175684) (xy 38.934899 -280.1279) (xy 38.95419 -280.082624) (xy 38.980493 -280.041028)
			(xy 39.013128 -280.004191) (xy 39.051249 -279.973066) (xy 39.09387 -279.948459) (xy 39.139886 -279.931007)
			(xy 39.188105 -279.921163) (xy 39.23728 -279.919182) (xy 39.286135 -279.925114) (xy 39.333406 -279.938806)
			(xy 39.377868 -279.959904) (xy 39.418371 -279.98786) (xy 39.453864 -280.021952) (xy 39.483429 -280.061296)
			(xy 39.5063 -280.104873) (xy 39.521884 -280.151554) (xy 39.529779 -280.200131) (xy 39.530274 -280.224738)
			(xy 39.869122 -280.224738) (xy 39.873082 -280.175684) (xy 39.884859 -280.1279) (xy 39.90415 -280.082624)
			(xy 39.930453 -280.041028) (xy 39.963088 -280.004191) (xy 40.001209 -279.973066) (xy 40.04383 -279.948459)
			(xy 40.089846 -279.931007) (xy 40.138065 -279.921163) (xy 40.18724 -279.919182) (xy 40.236095 -279.925114)
			(xy 40.283366 -279.938806) (xy 40.327828 -279.959904) (xy 40.368331 -279.98786) (xy 40.403824 -280.021952)
			(xy 40.433389 -280.061296) (xy 40.45626 -280.104873) (xy 40.471844 -280.151554) (xy 40.479739 -280.200131)
			(xy 40.480234 -280.224738) (xy 40.819082 -280.224738) (xy 40.823042 -280.175684) (xy 40.834819 -280.1279)
			(xy 40.85411 -280.082624) (xy 40.880413 -280.041028) (xy 40.913048 -280.004191) (xy 40.951169 -279.973066)
			(xy 40.99379 -279.948459) (xy 41.039806 -279.931007) (xy 41.088025 -279.921163) (xy 41.1372 -279.919182)
			(xy 41.186055 -279.925114) (xy 41.233326 -279.938806) (xy 41.277788 -279.959904) (xy 41.318291 -279.98786)
			(xy 41.353784 -280.021952) (xy 41.383349 -280.061296) (xy 41.40622 -280.104873) (xy 41.421804 -280.151554)
			(xy 41.429699 -280.200131) (xy 41.430194 -280.224738) (xy 41.769042 -280.224738) (xy 41.773002 -280.175684)
			(xy 41.784779 -280.1279) (xy 41.80407 -280.082624) (xy 41.830373 -280.041028) (xy 41.863008 -280.004191)
			(xy 41.901129 -279.973066) (xy 41.94375 -279.948459) (xy 41.989766 -279.931007) (xy 42.037985 -279.921163)
			(xy 42.08716 -279.919182) (xy 42.136015 -279.925114) (xy 42.183286 -279.938806) (xy 42.227748 -279.959904)
			(xy 42.268251 -279.98786) (xy 42.303744 -280.021952) (xy 42.333309 -280.061296) (xy 42.35618 -280.104873)
			(xy 42.371764 -280.151554) (xy 42.379659 -280.200131) (xy 42.380154 -280.224738) (xy 42.719002 -280.224738)
			(xy 42.722962 -280.175684) (xy 42.734739 -280.1279) (xy 42.75403 -280.082624) (xy 42.780333 -280.041028)
			(xy 42.812968 -280.004191) (xy 42.851089 -279.973066) (xy 42.89371 -279.948459) (xy 42.939726 -279.931007)
			(xy 42.987945 -279.921163) (xy 43.03712 -279.919182) (xy 43.085975 -279.925114) (xy 43.133246 -279.938806)
			(xy 43.177708 -279.959904) (xy 43.218211 -279.98786) (xy 43.253704 -280.021952) (xy 43.283269 -280.061296)
			(xy 43.30614 -280.104873) (xy 43.321724 -280.151554) (xy 43.329619 -280.200131) (xy 43.330114 -280.224738)
			(xy 43.329619 -280.249345) (xy 43.321724 -280.297922) (xy 43.30614 -280.344603) (xy 43.283269 -280.38818)
			(xy 43.253704 -280.427524) (xy 43.218211 -280.461616) (xy 43.177708 -280.489572) (xy 43.133246 -280.51067)
			(xy 43.085975 -280.524362) (xy 43.03712 -280.530294) (xy 42.987945 -280.528313) (xy 42.939726 -280.518469)
			(xy 42.89371 -280.501017) (xy 42.851089 -280.47641) (xy 42.812968 -280.445285) (xy 42.780333 -280.408448)
			(xy 42.75403 -280.366852) (xy 42.734739 -280.321576) (xy 42.722962 -280.273792) (xy 42.719002 -280.224738)
			(xy 42.380154 -280.224738) (xy 42.379659 -280.249345) (xy 42.371764 -280.297922) (xy 42.35618 -280.344603)
			(xy 42.333309 -280.38818) (xy 42.303744 -280.427524) (xy 42.268251 -280.461616) (xy 42.227748 -280.489572)
			(xy 42.183286 -280.51067) (xy 42.136015 -280.524362) (xy 42.08716 -280.530294) (xy 42.037985 -280.528313)
			(xy 41.989766 -280.518469) (xy 41.94375 -280.501017) (xy 41.901129 -280.47641) (xy 41.863008 -280.445285)
			(xy 41.830373 -280.408448) (xy 41.80407 -280.366852) (xy 41.784779 -280.321576) (xy 41.773002 -280.273792)
			(xy 41.769042 -280.224738) (xy 41.430194 -280.224738) (xy 41.429699 -280.249345) (xy 41.421804 -280.297922)
			(xy 41.40622 -280.344603) (xy 41.383349 -280.38818) (xy 41.353784 -280.427524) (xy 41.318291 -280.461616)
			(xy 41.277788 -280.489572) (xy 41.233326 -280.51067) (xy 41.186055 -280.524362) (xy 41.1372 -280.530294)
			(xy 41.088025 -280.528313) (xy 41.039806 -280.518469) (xy 40.99379 -280.501017) (xy 40.951169 -280.47641)
			(xy 40.913048 -280.445285) (xy 40.880413 -280.408448) (xy 40.85411 -280.366852) (xy 40.834819 -280.321576)
			(xy 40.823042 -280.273792) (xy 40.819082 -280.224738) (xy 40.480234 -280.224738) (xy 40.479739 -280.249345)
			(xy 40.471844 -280.297922) (xy 40.45626 -280.344603) (xy 40.433389 -280.38818) (xy 40.403824 -280.427524)
			(xy 40.368331 -280.461616) (xy 40.327828 -280.489572) (xy 40.283366 -280.51067) (xy 40.236095 -280.524362)
			(xy 40.18724 -280.530294) (xy 40.138065 -280.528313) (xy 40.089846 -280.518469) (xy 40.04383 -280.501017)
			(xy 40.001209 -280.47641) (xy 39.963088 -280.445285) (xy 39.930453 -280.408448) (xy 39.90415 -280.366852)
			(xy 39.884859 -280.321576) (xy 39.873082 -280.273792) (xy 39.869122 -280.224738) (xy 39.530274 -280.224738)
			(xy 39.529779 -280.249345) (xy 39.521884 -280.297922) (xy 39.5063 -280.344603) (xy 39.483429 -280.38818)
			(xy 39.453864 -280.427524) (xy 39.418371 -280.461616) (xy 39.377868 -280.489572) (xy 39.333406 -280.51067)
			(xy 39.286135 -280.524362) (xy 39.23728 -280.530294) (xy 39.188105 -280.528313) (xy 39.139886 -280.518469)
			(xy 39.09387 -280.501017) (xy 39.051249 -280.47641) (xy 39.013128 -280.445285) (xy 38.980493 -280.408448)
			(xy 38.95419 -280.366852) (xy 38.934899 -280.321576) (xy 38.923122 -280.273792) (xy 38.919162 -280.224738)
			(xy 38.580314 -280.224738) (xy 38.579819 -280.249345) (xy 38.571924 -280.297922) (xy 38.55634 -280.344603)
			(xy 38.533469 -280.38818) (xy 38.503904 -280.427524) (xy 38.468411 -280.461616) (xy 38.427908 -280.489572)
			(xy 38.383446 -280.51067) (xy 38.336175 -280.524362) (xy 38.28732 -280.530294) (xy 38.238145 -280.528313)
			(xy 38.189926 -280.518469) (xy 38.14391 -280.501017) (xy 38.101289 -280.47641) (xy 38.063168 -280.445285)
			(xy 38.030533 -280.408448) (xy 38.00423 -280.366852) (xy 37.984939 -280.321576) (xy 37.973162 -280.273792)
			(xy 37.969202 -280.224738) (xy 37.6301 -280.224738) (xy 37.629605 -280.249345) (xy 37.62171 -280.297922)
			(xy 37.606126 -280.344603) (xy 37.583255 -280.38818) (xy 37.55369 -280.427524) (xy 37.518197 -280.461616)
			(xy 37.477694 -280.489572) (xy 37.433232 -280.51067) (xy 37.385961 -280.524362) (xy 37.337106 -280.530294)
			(xy 37.287931 -280.528313) (xy 37.239712 -280.518469) (xy 37.193696 -280.501017) (xy 37.151075 -280.47641)
			(xy 37.112954 -280.445285) (xy 37.080319 -280.408448) (xy 37.054016 -280.366852) (xy 37.034725 -280.321576)
			(xy 37.022948 -280.273792) (xy 37.018988 -280.224738) (xy 36.68014 -280.224738) (xy 36.679645 -280.249345)
			(xy 36.67175 -280.297922) (xy 36.656166 -280.344603) (xy 36.633295 -280.38818) (xy 36.60373 -280.427524)
			(xy 36.568237 -280.461616) (xy 36.527734 -280.489572) (xy 36.483272 -280.51067) (xy 36.436001 -280.524362)
			(xy 36.387146 -280.530294) (xy 36.337971 -280.528313) (xy 36.289752 -280.518469) (xy 36.243736 -280.501017)
			(xy 36.201115 -280.47641) (xy 36.162994 -280.445285) (xy 36.130359 -280.408448) (xy 36.104056 -280.366852)
			(xy 36.084765 -280.321576) (xy 36.072988 -280.273792) (xy 36.069028 -280.224738) (xy 31.974426 -280.224738)
			(xy 31.96082 -280.235406) (xy 31.951422 -280.242772) (xy 31.941008 -280.263346) (xy 31.939484 -280.367232)
			(xy 31.94939 -280.388314) (xy 31.958534 -280.39568) (xy 31.980362 -280.413909) (xy 32.018902 -280.455724)
			(xy 32.05081 -280.502795) (xy 32.07538 -280.55408) (xy 32.092068 -280.608443) (xy 32.100505 -280.664681)
			(xy 32.101028 -280.693114) (xy 32.734502 -280.693114) (xy 32.738573 -280.637492) (xy 32.750699 -280.583055)
			(xy 32.770622 -280.530964) (xy 32.797918 -280.482329) (xy 32.832004 -280.438186) (xy 32.872153 -280.399477)
			(xy 32.917511 -280.367026) (xy 32.967111 -280.341525) (xy 33.019895 -280.323518) (xy 33.074738 -280.313388)
			(xy 33.130472 -280.311351) (xy 33.185909 -280.317451) (xy 33.239866 -280.331557) (xy 33.291195 -280.353369)
			(xy 33.338801 -280.382423) (xy 33.381669 -280.418098) (xy 33.418886 -280.459635) (xy 33.449659 -280.506148)
			(xy 33.473331 -280.556645) (xy 33.489399 -280.610052) (xy 33.497519 -280.665228) (xy 33.498028 -280.693114)
			(xy 33.620962 -280.693114) (xy 33.625033 -280.637492) (xy 33.637159 -280.583055) (xy 33.657082 -280.530964)
			(xy 33.684378 -280.482329) (xy 33.718464 -280.438186) (xy 33.758613 -280.399477) (xy 33.803971 -280.367026)
			(xy 33.853571 -280.341525) (xy 33.906355 -280.323518) (xy 33.961198 -280.313388) (xy 34.016932 -280.311351)
			(xy 34.072369 -280.317451) (xy 34.126326 -280.331557) (xy 34.177655 -280.353369) (xy 34.225261 -280.382423)
			(xy 34.268129 -280.418098) (xy 34.305346 -280.459635) (xy 34.336119 -280.506148) (xy 34.359791 -280.556645)
			(xy 34.375859 -280.610052) (xy 34.383979 -280.665228) (xy 34.384488 -280.693114) (xy 34.384367 -280.699718)
			(xy 44.143942 -280.699718) (xy 44.147902 -280.650664) (xy 44.159679 -280.60288) (xy 44.17897 -280.557604)
			(xy 44.205273 -280.516008) (xy 44.237908 -280.479171) (xy 44.276029 -280.448046) (xy 44.31865 -280.423439)
			(xy 44.364666 -280.405987) (xy 44.412885 -280.396143) (xy 44.46206 -280.394162) (xy 44.510915 -280.400094)
			(xy 44.558186 -280.413786) (xy 44.602648 -280.434884) (xy 44.643151 -280.46284) (xy 44.678644 -280.496932)
			(xy 44.708209 -280.536276) (xy 44.73108 -280.579853) (xy 44.746664 -280.626534) (xy 44.754559 -280.675111)
			(xy 44.755054 -280.699718) (xy 45.094156 -280.699718) (xy 45.098116 -280.650664) (xy 45.109893 -280.60288)
			(xy 45.129184 -280.557604) (xy 45.155487 -280.516008) (xy 45.188122 -280.479171) (xy 45.226243 -280.448046)
			(xy 45.268864 -280.423439) (xy 45.31488 -280.405987) (xy 45.363099 -280.396143) (xy 45.412274 -280.394162)
			(xy 45.461129 -280.400094) (xy 45.5084 -280.413786) (xy 45.552862 -280.434884) (xy 45.593365 -280.46284)
			(xy 45.628858 -280.496932) (xy 45.658423 -280.536276) (xy 45.681294 -280.579853) (xy 45.696878 -280.626534)
			(xy 45.704773 -280.675111) (xy 45.705268 -280.699718) (xy 46.044116 -280.699718) (xy 46.048076 -280.650664)
			(xy 46.059853 -280.60288) (xy 46.079144 -280.557604) (xy 46.105447 -280.516008) (xy 46.138082 -280.479171)
			(xy 46.176203 -280.448046) (xy 46.218824 -280.423439) (xy 46.26484 -280.405987) (xy 46.313059 -280.396143)
			(xy 46.362234 -280.394162) (xy 46.411089 -280.400094) (xy 46.45836 -280.413786) (xy 46.502822 -280.434884)
			(xy 46.543325 -280.46284) (xy 46.578818 -280.496932) (xy 46.608383 -280.536276) (xy 46.631254 -280.579853)
			(xy 46.646838 -280.626534) (xy 46.654733 -280.675111) (xy 46.655228 -280.699718) (xy 46.994076 -280.699718)
			(xy 46.998036 -280.650664) (xy 47.009813 -280.60288) (xy 47.029104 -280.557604) (xy 47.055407 -280.516008)
			(xy 47.088042 -280.479171) (xy 47.126163 -280.448046) (xy 47.168784 -280.423439) (xy 47.2148 -280.405987)
			(xy 47.263019 -280.396143) (xy 47.312194 -280.394162) (xy 47.361049 -280.400094) (xy 47.40832 -280.413786)
			(xy 47.452782 -280.434884) (xy 47.493285 -280.46284) (xy 47.528778 -280.496932) (xy 47.558343 -280.536276)
			(xy 47.581214 -280.579853) (xy 47.596798 -280.626534) (xy 47.604693 -280.675111) (xy 47.605188 -280.699718)
			(xy 47.944036 -280.699718) (xy 47.947996 -280.650664) (xy 47.959773 -280.60288) (xy 47.979064 -280.557604)
			(xy 48.005367 -280.516008) (xy 48.038002 -280.479171) (xy 48.076123 -280.448046) (xy 48.118744 -280.423439)
			(xy 48.16476 -280.405987) (xy 48.212979 -280.396143) (xy 48.262154 -280.394162) (xy 48.311009 -280.400094)
			(xy 48.35828 -280.413786) (xy 48.402742 -280.434884) (xy 48.443245 -280.46284) (xy 48.478738 -280.496932)
			(xy 48.508303 -280.536276) (xy 48.531174 -280.579853) (xy 48.546758 -280.626534) (xy 48.554653 -280.675111)
			(xy 48.555148 -280.699718) (xy 48.893996 -280.699718) (xy 48.897956 -280.650664) (xy 48.909733 -280.60288)
			(xy 48.929024 -280.557604) (xy 48.955327 -280.516008) (xy 48.987962 -280.479171) (xy 49.026083 -280.448046)
			(xy 49.068704 -280.423439) (xy 49.11472 -280.405987) (xy 49.162939 -280.396143) (xy 49.212114 -280.394162)
			(xy 49.260969 -280.400094) (xy 49.30824 -280.413786) (xy 49.352702 -280.434884) (xy 49.393205 -280.46284)
			(xy 49.428698 -280.496932) (xy 49.458263 -280.536276) (xy 49.481134 -280.579853) (xy 49.496718 -280.626534)
			(xy 49.504613 -280.675111) (xy 49.505108 -280.699718) (xy 49.843956 -280.699718) (xy 49.847916 -280.650664)
			(xy 49.859693 -280.60288) (xy 49.878984 -280.557604) (xy 49.905287 -280.516008) (xy 49.937922 -280.479171)
			(xy 49.976043 -280.448046) (xy 50.018664 -280.423439) (xy 50.06468 -280.405987) (xy 50.112899 -280.396143)
			(xy 50.162074 -280.394162) (xy 50.210929 -280.400094) (xy 50.2582 -280.413786) (xy 50.302662 -280.434884)
			(xy 50.343165 -280.46284) (xy 50.378658 -280.496932) (xy 50.408223 -280.536276) (xy 50.431094 -280.579853)
			(xy 50.446678 -280.626534) (xy 50.454573 -280.675111) (xy 50.455068 -280.699718) (xy 50.79417 -280.699718)
			(xy 50.79813 -280.650664) (xy 50.809907 -280.60288) (xy 50.829198 -280.557604) (xy 50.855501 -280.516008)
			(xy 50.888136 -280.479171) (xy 50.926257 -280.448046) (xy 50.968878 -280.423439) (xy 51.014894 -280.405987)
			(xy 51.063113 -280.396143) (xy 51.112288 -280.394162) (xy 51.161143 -280.400094) (xy 51.208414 -280.413786)
			(xy 51.252876 -280.434884) (xy 51.293379 -280.46284) (xy 51.328872 -280.496932) (xy 51.358437 -280.536276)
			(xy 51.381308 -280.579853) (xy 51.396892 -280.626534) (xy 51.404787 -280.675111) (xy 51.405282 -280.699718)
			(xy 51.74413 -280.699718) (xy 51.74809 -280.650664) (xy 51.759867 -280.60288) (xy 51.779158 -280.557604)
			(xy 51.805461 -280.516008) (xy 51.838096 -280.479171) (xy 51.876217 -280.448046) (xy 51.918838 -280.423439)
			(xy 51.964854 -280.405987) (xy 52.013073 -280.396143) (xy 52.062248 -280.394162) (xy 52.111103 -280.400094)
			(xy 52.158374 -280.413786) (xy 52.202836 -280.434884) (xy 52.243339 -280.46284) (xy 52.278832 -280.496932)
			(xy 52.308397 -280.536276) (xy 52.331268 -280.579853) (xy 52.346852 -280.626534) (xy 52.354747 -280.675111)
			(xy 52.355242 -280.699718) (xy 52.69409 -280.699718) (xy 52.69805 -280.650664) (xy 52.709827 -280.60288)
			(xy 52.729118 -280.557604) (xy 52.755421 -280.516008) (xy 52.788056 -280.479171) (xy 52.826177 -280.448046)
			(xy 52.868798 -280.423439) (xy 52.914814 -280.405987) (xy 52.963033 -280.396143) (xy 53.012208 -280.394162)
			(xy 53.061063 -280.400094) (xy 53.108334 -280.413786) (xy 53.152796 -280.434884) (xy 53.193299 -280.46284)
			(xy 53.228792 -280.496932) (xy 53.258357 -280.536276) (xy 53.281228 -280.579853) (xy 53.296812 -280.626534)
			(xy 53.304707 -280.675111) (xy 53.305202 -280.699718) (xy 53.64405 -280.699718) (xy 53.64801 -280.650664)
			(xy 53.659787 -280.60288) (xy 53.679078 -280.557604) (xy 53.705381 -280.516008) (xy 53.738016 -280.479171)
			(xy 53.776137 -280.448046) (xy 53.818758 -280.423439) (xy 53.864774 -280.405987) (xy 53.912993 -280.396143)
			(xy 53.962168 -280.394162) (xy 54.011023 -280.400094) (xy 54.058294 -280.413786) (xy 54.102756 -280.434884)
			(xy 54.143259 -280.46284) (xy 54.178752 -280.496932) (xy 54.208317 -280.536276) (xy 54.231188 -280.579853)
			(xy 54.246772 -280.626534) (xy 54.254667 -280.675111) (xy 54.255162 -280.699718) (xy 54.59401 -280.699718)
			(xy 54.59797 -280.650664) (xy 54.609747 -280.60288) (xy 54.629038 -280.557604) (xy 54.655341 -280.516008)
			(xy 54.687976 -280.479171) (xy 54.726097 -280.448046) (xy 54.768718 -280.423439) (xy 54.814734 -280.405987)
			(xy 54.862953 -280.396143) (xy 54.912128 -280.394162) (xy 54.960983 -280.400094) (xy 55.008254 -280.413786)
			(xy 55.052716 -280.434884) (xy 55.093219 -280.46284) (xy 55.128712 -280.496932) (xy 55.158277 -280.536276)
			(xy 55.181148 -280.579853) (xy 55.196732 -280.626534) (xy 55.204627 -280.675111) (xy 55.205122 -280.699718)
			(xy 55.54397 -280.699718) (xy 55.54793 -280.650664) (xy 55.559707 -280.60288) (xy 55.578998 -280.557604)
			(xy 55.605301 -280.516008) (xy 55.637936 -280.479171) (xy 55.676057 -280.448046) (xy 55.718678 -280.423439)
			(xy 55.764694 -280.405987) (xy 55.812913 -280.396143) (xy 55.862088 -280.394162) (xy 55.910943 -280.400094)
			(xy 55.958214 -280.413786) (xy 56.002676 -280.434884) (xy 56.043179 -280.46284) (xy 56.078672 -280.496932)
			(xy 56.108237 -280.536276) (xy 56.131108 -280.579853) (xy 56.146692 -280.626534) (xy 56.154587 -280.675111)
			(xy 56.155082 -280.699718) (xy 56.49393 -280.699718) (xy 56.49789 -280.650664) (xy 56.509667 -280.60288)
			(xy 56.528958 -280.557604) (xy 56.555261 -280.516008) (xy 56.587896 -280.479171) (xy 56.626017 -280.448046)
			(xy 56.668638 -280.423439) (xy 56.714654 -280.405987) (xy 56.762873 -280.396143) (xy 56.812048 -280.394162)
			(xy 56.860903 -280.400094) (xy 56.908174 -280.413786) (xy 56.952636 -280.434884) (xy 56.993139 -280.46284)
			(xy 57.028632 -280.496932) (xy 57.058197 -280.536276) (xy 57.081068 -280.579853) (xy 57.096652 -280.626534)
			(xy 57.104547 -280.675111) (xy 57.105042 -280.699718) (xy 57.104547 -280.724325) (xy 57.096652 -280.772902)
			(xy 57.081068 -280.819583) (xy 57.058197 -280.86316) (xy 57.028632 -280.902504) (xy 56.993139 -280.936596)
			(xy 56.952636 -280.964552) (xy 56.908174 -280.98565) (xy 56.860903 -280.999342) (xy 56.812048 -281.005274)
			(xy 56.762873 -281.003293) (xy 56.714654 -280.993449) (xy 56.668638 -280.975997) (xy 56.626017 -280.95139)
			(xy 56.587896 -280.920265) (xy 56.555261 -280.883428) (xy 56.528958 -280.841832) (xy 56.509667 -280.796556)
			(xy 56.49789 -280.748772) (xy 56.49393 -280.699718) (xy 56.155082 -280.699718) (xy 56.154587 -280.724325)
			(xy 56.146692 -280.772902) (xy 56.131108 -280.819583) (xy 56.108237 -280.86316) (xy 56.078672 -280.902504)
			(xy 56.043179 -280.936596) (xy 56.002676 -280.964552) (xy 55.958214 -280.98565) (xy 55.910943 -280.999342)
			(xy 55.862088 -281.005274) (xy 55.812913 -281.003293) (xy 55.764694 -280.993449) (xy 55.718678 -280.975997)
			(xy 55.676057 -280.95139) (xy 55.637936 -280.920265) (xy 55.605301 -280.883428) (xy 55.578998 -280.841832)
			(xy 55.559707 -280.796556) (xy 55.54793 -280.748772) (xy 55.54397 -280.699718) (xy 55.205122 -280.699718)
			(xy 55.204627 -280.724325) (xy 55.196732 -280.772902) (xy 55.181148 -280.819583) (xy 55.158277 -280.86316)
			(xy 55.128712 -280.902504) (xy 55.093219 -280.936596) (xy 55.052716 -280.964552) (xy 55.008254 -280.98565)
			(xy 54.960983 -280.999342) (xy 54.912128 -281.005274) (xy 54.862953 -281.003293) (xy 54.814734 -280.993449)
			(xy 54.768718 -280.975997) (xy 54.726097 -280.95139) (xy 54.687976 -280.920265) (xy 54.655341 -280.883428)
			(xy 54.629038 -280.841832) (xy 54.609747 -280.796556) (xy 54.59797 -280.748772) (xy 54.59401 -280.699718)
			(xy 54.255162 -280.699718) (xy 54.254667 -280.724325) (xy 54.246772 -280.772902) (xy 54.231188 -280.819583)
			(xy 54.208317 -280.86316) (xy 54.178752 -280.902504) (xy 54.143259 -280.936596) (xy 54.102756 -280.964552)
			(xy 54.058294 -280.98565) (xy 54.011023 -280.999342) (xy 53.962168 -281.005274) (xy 53.912993 -281.003293)
			(xy 53.864774 -280.993449) (xy 53.818758 -280.975997) (xy 53.776137 -280.95139) (xy 53.738016 -280.920265)
			(xy 53.705381 -280.883428) (xy 53.679078 -280.841832) (xy 53.659787 -280.796556) (xy 53.64801 -280.748772)
			(xy 53.64405 -280.699718) (xy 53.305202 -280.699718) (xy 53.304707 -280.724325) (xy 53.296812 -280.772902)
			(xy 53.281228 -280.819583) (xy 53.258357 -280.86316) (xy 53.228792 -280.902504) (xy 53.193299 -280.936596)
			(xy 53.152796 -280.964552) (xy 53.108334 -280.98565) (xy 53.061063 -280.999342) (xy 53.012208 -281.005274)
			(xy 52.963033 -281.003293) (xy 52.914814 -280.993449) (xy 52.868798 -280.975997) (xy 52.826177 -280.95139)
			(xy 52.788056 -280.920265) (xy 52.755421 -280.883428) (xy 52.729118 -280.841832) (xy 52.709827 -280.796556)
			(xy 52.69805 -280.748772) (xy 52.69409 -280.699718) (xy 52.355242 -280.699718) (xy 52.354747 -280.724325)
			(xy 52.346852 -280.772902) (xy 52.331268 -280.819583) (xy 52.308397 -280.86316) (xy 52.278832 -280.902504)
			(xy 52.243339 -280.936596) (xy 52.202836 -280.964552) (xy 52.158374 -280.98565) (xy 52.111103 -280.999342)
			(xy 52.062248 -281.005274) (xy 52.013073 -281.003293) (xy 51.964854 -280.993449) (xy 51.918838 -280.975997)
			(xy 51.876217 -280.95139) (xy 51.838096 -280.920265) (xy 51.805461 -280.883428) (xy 51.779158 -280.841832)
			(xy 51.759867 -280.796556) (xy 51.74809 -280.748772) (xy 51.74413 -280.699718) (xy 51.405282 -280.699718)
			(xy 51.404787 -280.724325) (xy 51.396892 -280.772902) (xy 51.381308 -280.819583) (xy 51.358437 -280.86316)
			(xy 51.328872 -280.902504) (xy 51.293379 -280.936596) (xy 51.252876 -280.964552) (xy 51.208414 -280.98565)
			(xy 51.161143 -280.999342) (xy 51.112288 -281.005274) (xy 51.063113 -281.003293) (xy 51.014894 -280.993449)
			(xy 50.968878 -280.975997) (xy 50.926257 -280.95139) (xy 50.888136 -280.920265) (xy 50.855501 -280.883428)
			(xy 50.829198 -280.841832) (xy 50.809907 -280.796556) (xy 50.79813 -280.748772) (xy 50.79417 -280.699718)
			(xy 50.455068 -280.699718) (xy 50.454573 -280.724325) (xy 50.446678 -280.772902) (xy 50.431094 -280.819583)
			(xy 50.408223 -280.86316) (xy 50.378658 -280.902504) (xy 50.343165 -280.936596) (xy 50.302662 -280.964552)
			(xy 50.2582 -280.98565) (xy 50.210929 -280.999342) (xy 50.162074 -281.005274) (xy 50.112899 -281.003293)
			(xy 50.06468 -280.993449) (xy 50.018664 -280.975997) (xy 49.976043 -280.95139) (xy 49.937922 -280.920265)
			(xy 49.905287 -280.883428) (xy 49.878984 -280.841832) (xy 49.859693 -280.796556) (xy 49.847916 -280.748772)
			(xy 49.843956 -280.699718) (xy 49.505108 -280.699718) (xy 49.504613 -280.724325) (xy 49.496718 -280.772902)
			(xy 49.481134 -280.819583) (xy 49.458263 -280.86316) (xy 49.428698 -280.902504) (xy 49.393205 -280.936596)
			(xy 49.352702 -280.964552) (xy 49.30824 -280.98565) (xy 49.260969 -280.999342) (xy 49.212114 -281.005274)
			(xy 49.162939 -281.003293) (xy 49.11472 -280.993449) (xy 49.068704 -280.975997) (xy 49.026083 -280.95139)
			(xy 48.987962 -280.920265) (xy 48.955327 -280.883428) (xy 48.929024 -280.841832) (xy 48.909733 -280.796556)
			(xy 48.897956 -280.748772) (xy 48.893996 -280.699718) (xy 48.555148 -280.699718) (xy 48.554653 -280.724325)
			(xy 48.546758 -280.772902) (xy 48.531174 -280.819583) (xy 48.508303 -280.86316) (xy 48.478738 -280.902504)
			(xy 48.443245 -280.936596) (xy 48.402742 -280.964552) (xy 48.35828 -280.98565) (xy 48.311009 -280.999342)
			(xy 48.262154 -281.005274) (xy 48.212979 -281.003293) (xy 48.16476 -280.993449) (xy 48.118744 -280.975997)
			(xy 48.076123 -280.95139) (xy 48.038002 -280.920265) (xy 48.005367 -280.883428) (xy 47.979064 -280.841832)
			(xy 47.959773 -280.796556) (xy 47.947996 -280.748772) (xy 47.944036 -280.699718) (xy 47.605188 -280.699718)
			(xy 47.604693 -280.724325) (xy 47.596798 -280.772902) (xy 47.581214 -280.819583) (xy 47.558343 -280.86316)
			(xy 47.528778 -280.902504) (xy 47.493285 -280.936596) (xy 47.452782 -280.964552) (xy 47.40832 -280.98565)
			(xy 47.361049 -280.999342) (xy 47.312194 -281.005274) (xy 47.263019 -281.003293) (xy 47.2148 -280.993449)
			(xy 47.168784 -280.975997) (xy 47.126163 -280.95139) (xy 47.088042 -280.920265) (xy 47.055407 -280.883428)
			(xy 47.029104 -280.841832) (xy 47.009813 -280.796556) (xy 46.998036 -280.748772) (xy 46.994076 -280.699718)
			(xy 46.655228 -280.699718) (xy 46.654733 -280.724325) (xy 46.646838 -280.772902) (xy 46.631254 -280.819583)
			(xy 46.608383 -280.86316) (xy 46.578818 -280.902504) (xy 46.543325 -280.936596) (xy 46.502822 -280.964552)
			(xy 46.45836 -280.98565) (xy 46.411089 -280.999342) (xy 46.362234 -281.005274) (xy 46.313059 -281.003293)
			(xy 46.26484 -280.993449) (xy 46.218824 -280.975997) (xy 46.176203 -280.95139) (xy 46.138082 -280.920265)
			(xy 46.105447 -280.883428) (xy 46.079144 -280.841832) (xy 46.059853 -280.796556) (xy 46.048076 -280.748772)
			(xy 46.044116 -280.699718) (xy 45.705268 -280.699718) (xy 45.704773 -280.724325) (xy 45.696878 -280.772902)
			(xy 45.681294 -280.819583) (xy 45.658423 -280.86316) (xy 45.628858 -280.902504) (xy 45.593365 -280.936596)
			(xy 45.552862 -280.964552) (xy 45.5084 -280.98565) (xy 45.461129 -280.999342) (xy 45.412274 -281.005274)
			(xy 45.363099 -281.003293) (xy 45.31488 -280.993449) (xy 45.268864 -280.975997) (xy 45.226243 -280.95139)
			(xy 45.188122 -280.920265) (xy 45.155487 -280.883428) (xy 45.129184 -280.841832) (xy 45.109893 -280.796556)
			(xy 45.098116 -280.748772) (xy 45.094156 -280.699718) (xy 44.755054 -280.699718) (xy 44.754559 -280.724325)
			(xy 44.746664 -280.772902) (xy 44.73108 -280.819583) (xy 44.708209 -280.86316) (xy 44.678644 -280.902504)
			(xy 44.643151 -280.936596) (xy 44.602648 -280.964552) (xy 44.558186 -280.98565) (xy 44.510915 -280.999342)
			(xy 44.46206 -281.005274) (xy 44.412885 -281.003293) (xy 44.364666 -280.993449) (xy 44.31865 -280.975997)
			(xy 44.276029 -280.95139) (xy 44.237908 -280.920265) (xy 44.205273 -280.883428) (xy 44.17897 -280.841832)
			(xy 44.159679 -280.796556) (xy 44.147902 -280.748772) (xy 44.143942 -280.699718) (xy 34.384367 -280.699718)
			(xy 34.383979 -280.721) (xy 34.375859 -280.776176) (xy 34.359791 -280.829583) (xy 34.336119 -280.88008)
			(xy 34.305346 -280.926593) (xy 34.268129 -280.96813) (xy 34.225261 -281.003805) (xy 34.177655 -281.032859)
			(xy 34.126326 -281.054671) (xy 34.072369 -281.068777) (xy 34.016932 -281.074877) (xy 33.961198 -281.07284)
			(xy 33.906355 -281.06271) (xy 33.853571 -281.044703) (xy 33.803971 -281.019202) (xy 33.758613 -280.986751)
			(xy 33.718464 -280.948042) (xy 33.684378 -280.903899) (xy 33.657082 -280.855264) (xy 33.637159 -280.803173)
			(xy 33.625033 -280.748736) (xy 33.620962 -280.693114) (xy 33.498028 -280.693114) (xy 33.497519 -280.721)
			(xy 33.489399 -280.776176) (xy 33.473331 -280.829583) (xy 33.449659 -280.88008) (xy 33.418886 -280.926593)
			(xy 33.381669 -280.96813) (xy 33.338801 -281.003805) (xy 33.291195 -281.032859) (xy 33.239866 -281.054671)
			(xy 33.185909 -281.068777) (xy 33.130472 -281.074877) (xy 33.074738 -281.07284) (xy 33.019895 -281.06271)
			(xy 32.967111 -281.044703) (xy 32.917511 -281.019202) (xy 32.872153 -280.986751) (xy 32.832004 -280.948042)
			(xy 32.797918 -280.903899) (xy 32.770622 -280.855264) (xy 32.750699 -280.803173) (xy 32.738573 -280.748736)
			(xy 32.734502 -280.693114) (xy 32.101028 -280.693114) (xy 32.100542 -280.720365) (xy 32.092786 -280.774313)
			(xy 32.077431 -280.826608) (xy 32.054789 -280.876185) (xy 32.025323 -280.922035) (xy 31.989632 -280.963226)
			(xy 31.948441 -280.998917) (xy 31.902591 -281.028383) (xy 31.853014 -281.051025) (xy 31.800719 -281.06638)
			(xy 31.746771 -281.074136) (xy 31.692269 -281.074136) (xy 31.638321 -281.06638) (xy 31.586026 -281.051025)
			(xy 31.536449 -281.028383) (xy 31.490599 -280.998917) (xy 31.449408 -280.963226) (xy 31.413717 -280.922035)
			(xy 31.384251 -280.876185) (xy 31.361609 -280.826608) (xy 31.346254 -280.774313) (xy 31.338498 -280.720365)
			(xy 31.338012 -280.693114) (xy 16.708445 -280.693114) (xy 16.708445 -280.722654) (xy 16.700687 -280.776607)
			(xy 16.68533 -280.828907) (xy 16.662685 -280.878489) (xy 16.633215 -280.924343) (xy 16.597518 -280.965537)
			(xy 16.556323 -281.00123) (xy 16.510466 -281.030698) (xy 16.460883 -281.053339) (xy 16.408582 -281.068692)
			(xy 16.354628 -281.076446) (xy 16.327374 -281.076908) (xy 16.297249 -281.076366) (xy 16.237751 -281.06688)
			(xy 16.180482 -281.048163) (xy 16.126866 -281.02068) (xy 16.078233 -280.985115) (xy 16.05661 -280.964132)
			(xy 16.049498 -280.956766) (xy 16.030702 -280.949146) (xy 15.938246 -280.949146) (xy 15.91945 -280.956766)
			(xy 15.912338 -280.964132) (xy 15.890708 -280.985107) (xy 15.842082 -281.020678) (xy 15.788467 -281.048161)
			(xy 15.731197 -281.06687) (xy 15.671698 -281.07634) (xy 15.641574 -281.076908) (xy 15.612835 -281.076398)
			(xy 15.556007 -281.067772) (xy 15.501116 -281.050718) (xy 15.449404 -281.025624) (xy 15.402042 -280.993056)
			(xy 15.380716 -280.973784) (xy 15.373604 -280.96718) (xy 15.356078 -280.960068) (xy 15.26667 -280.960068)
			(xy 15.249144 -280.96718) (xy 15.242032 -280.973784) (xy 15.220705 -280.993054) (xy 15.173342 -281.025619)
			(xy 15.121631 -281.05071) (xy 15.06674 -281.06776) (xy 15.009913 -281.076382) (xy 14.952435 -281.076382)
			(xy 14.895608 -281.06776) (xy 14.840717 -281.05071) (xy 14.789006 -281.025619) (xy 14.741643 -280.993054)
			(xy 14.720316 -280.973784) (xy 14.713204 -280.96718) (xy 14.695678 -280.960068) (xy 14.60627 -280.960068)
			(xy 14.588744 -280.96718) (xy 14.581632 -280.973784) (xy 14.560319 -280.993071) (xy 14.512953 -281.025634)
			(xy 14.461237 -281.050723) (xy 14.406344 -281.06777) (xy 14.349514 -281.076389) (xy 14.320774 -281.076908)
			(xy 14.293524 -281.07642) (xy 14.239579 -281.068661) (xy 14.187287 -281.053304) (xy 14.137713 -281.030661)
			(xy 14.091866 -281.001194) (xy 14.050679 -280.965502) (xy 14.01499 -280.924313) (xy 13.985527 -280.878464)
			(xy 13.962887 -280.828888) (xy 13.947534 -280.776596) (xy 13.939778 -280.72265) (xy 12.461045 -280.72265)
			(xy 12.461045 -280.722653) (xy 12.453287 -280.776606) (xy 12.437931 -280.828905) (xy 12.415287 -280.878486)
			(xy 12.385818 -280.924339) (xy 12.350123 -280.965532) (xy 12.308928 -281.001226) (xy 12.263073 -281.030694)
			(xy 12.213491 -281.053335) (xy 12.161192 -281.06869) (xy 12.10724 -281.076446) (xy 12.079986 -281.076908)
			(xy 12.049862 -281.076358) (xy 11.990364 -281.066874) (xy 11.933095 -281.048159) (xy 11.879478 -281.020678)
			(xy 11.830845 -280.985114) (xy 11.809222 -280.964132) (xy 11.80211 -280.956766) (xy 11.783314 -280.949146)
			(xy 11.690858 -280.949146) (xy 11.672062 -280.956766) (xy 11.66495 -280.964132) (xy 11.643315 -280.985101)
			(xy 11.59469 -281.020673) (xy 11.541076 -281.048157) (xy 11.483808 -281.066867) (xy 11.42431 -281.076339)
			(xy 11.394186 -281.076908) (xy 11.365447 -281.076391) (xy 11.308619 -281.067766) (xy 11.253729 -281.050715)
			(xy 11.202017 -281.025622) (xy 11.154655 -280.993055) (xy 11.133328 -280.973784) (xy 11.126216 -280.96718)
			(xy 11.10869 -280.960068) (xy 11.019282 -280.960068) (xy 11.001756 -280.96718) (xy 10.994644 -280.973784)
			(xy 10.973317 -280.993054) (xy 10.925954 -281.025619) (xy 10.874243 -281.05071) (xy 10.819352 -281.06776)
			(xy 10.762525 -281.076382) (xy 10.705047 -281.076382) (xy 10.64822 -281.06776) (xy 10.593329 -281.05071)
			(xy 10.541618 -281.025619) (xy 10.494255 -280.993054) (xy 10.472928 -280.973784) (xy 10.465816 -280.96718)
			(xy 10.44829 -280.960068) (xy 10.358882 -280.960068) (xy 10.341356 -280.96718) (xy 10.334244 -280.973784)
			(xy 10.312926 -280.993065) (xy 10.265561 -281.025629) (xy 10.213847 -281.050719) (xy 10.158955 -281.067767)
			(xy 10.102126 -281.076388) (xy 10.073386 -281.076908) (xy 10.046135 -281.076421) (xy 9.992189 -281.068663)
			(xy 9.939896 -281.053307) (xy 9.890321 -281.030665) (xy 9.844472 -281.001198) (xy 9.803283 -280.965507)
			(xy 9.767593 -280.924317) (xy 9.738128 -280.878467) (xy 9.715488 -280.828891) (xy 9.700134 -280.776597)
			(xy 9.692378 -280.722651) (xy 1.468374 -280.722651) (xy 1.468374 -281.174952) (xy 36.069028 -281.174952)
			(xy 36.072988 -281.125898) (xy 36.084765 -281.078114) (xy 36.104056 -281.032838) (xy 36.130359 -280.991242)
			(xy 36.162994 -280.954405) (xy 36.201115 -280.92328) (xy 36.243736 -280.898673) (xy 36.289752 -280.881221)
			(xy 36.337971 -280.871377) (xy 36.387146 -280.869396) (xy 36.436001 -280.875328) (xy 36.483272 -280.88902)
			(xy 36.527734 -280.910118) (xy 36.568237 -280.938074) (xy 36.60373 -280.972166) (xy 36.633295 -281.01151)
			(xy 36.656166 -281.055087) (xy 36.67175 -281.101768) (xy 36.679645 -281.150345) (xy 36.68014 -281.174952)
			(xy 37.018988 -281.174952) (xy 37.022948 -281.125898) (xy 37.034725 -281.078114) (xy 37.054016 -281.032838)
			(xy 37.080319 -280.991242) (xy 37.112954 -280.954405) (xy 37.151075 -280.92328) (xy 37.193696 -280.898673)
			(xy 37.239712 -280.881221) (xy 37.287931 -280.871377) (xy 37.337106 -280.869396) (xy 37.385961 -280.875328)
			(xy 37.433232 -280.88902) (xy 37.477694 -280.910118) (xy 37.518197 -280.938074) (xy 37.55369 -280.972166)
			(xy 37.583255 -281.01151) (xy 37.606126 -281.055087) (xy 37.62171 -281.101768) (xy 37.629605 -281.150345)
			(xy 37.6301 -281.174952) (xy 37.969202 -281.174952) (xy 37.973162 -281.125898) (xy 37.984939 -281.078114)
			(xy 38.00423 -281.032838) (xy 38.030533 -280.991242) (xy 38.063168 -280.954405) (xy 38.101289 -280.92328)
			(xy 38.14391 -280.898673) (xy 38.189926 -280.881221) (xy 38.238145 -280.871377) (xy 38.28732 -280.869396)
			(xy 38.336175 -280.875328) (xy 38.383446 -280.88902) (xy 38.427908 -280.910118) (xy 38.468411 -280.938074)
			(xy 38.503904 -280.972166) (xy 38.533469 -281.01151) (xy 38.55634 -281.055087) (xy 38.571924 -281.101768)
			(xy 38.579819 -281.150345) (xy 38.580314 -281.174952) (xy 38.919162 -281.174952) (xy 38.923122 -281.125898)
			(xy 38.934899 -281.078114) (xy 38.95419 -281.032838) (xy 38.980493 -280.991242) (xy 39.013128 -280.954405)
			(xy 39.051249 -280.92328) (xy 39.09387 -280.898673) (xy 39.139886 -280.881221) (xy 39.188105 -280.871377)
			(xy 39.23728 -280.869396) (xy 39.286135 -280.875328) (xy 39.333406 -280.88902) (xy 39.377868 -280.910118)
			(xy 39.418371 -280.938074) (xy 39.453864 -280.972166) (xy 39.483429 -281.01151) (xy 39.5063 -281.055087)
			(xy 39.521884 -281.101768) (xy 39.529779 -281.150345) (xy 39.530274 -281.174952) (xy 39.869122 -281.174952)
			(xy 39.873082 -281.125898) (xy 39.884859 -281.078114) (xy 39.90415 -281.032838) (xy 39.930453 -280.991242)
			(xy 39.963088 -280.954405) (xy 40.001209 -280.92328) (xy 40.04383 -280.898673) (xy 40.089846 -280.881221)
			(xy 40.138065 -280.871377) (xy 40.18724 -280.869396) (xy 40.236095 -280.875328) (xy 40.283366 -280.88902)
			(xy 40.327828 -280.910118) (xy 40.368331 -280.938074) (xy 40.403824 -280.972166) (xy 40.433389 -281.01151)
			(xy 40.45626 -281.055087) (xy 40.471844 -281.101768) (xy 40.479739 -281.150345) (xy 40.480234 -281.174952)
			(xy 40.819082 -281.174952) (xy 40.823042 -281.125898) (xy 40.834819 -281.078114) (xy 40.85411 -281.032838)
			(xy 40.880413 -280.991242) (xy 40.913048 -280.954405) (xy 40.951169 -280.92328) (xy 40.99379 -280.898673)
			(xy 41.039806 -280.881221) (xy 41.088025 -280.871377) (xy 41.1372 -280.869396) (xy 41.186055 -280.875328)
			(xy 41.233326 -280.88902) (xy 41.277788 -280.910118) (xy 41.318291 -280.938074) (xy 41.353784 -280.972166)
			(xy 41.383349 -281.01151) (xy 41.40622 -281.055087) (xy 41.421804 -281.101768) (xy 41.429699 -281.150345)
			(xy 41.430194 -281.174952) (xy 41.769042 -281.174952) (xy 41.773002 -281.125898) (xy 41.784779 -281.078114)
			(xy 41.80407 -281.032838) (xy 41.830373 -280.991242) (xy 41.863008 -280.954405) (xy 41.901129 -280.92328)
			(xy 41.94375 -280.898673) (xy 41.989766 -280.881221) (xy 42.037985 -280.871377) (xy 42.08716 -280.869396)
			(xy 42.136015 -280.875328) (xy 42.183286 -280.88902) (xy 42.227748 -280.910118) (xy 42.268251 -280.938074)
			(xy 42.303744 -280.972166) (xy 42.333309 -281.01151) (xy 42.35618 -281.055087) (xy 42.371764 -281.101768)
			(xy 42.379659 -281.150345) (xy 42.380154 -281.174952) (xy 42.719002 -281.174952) (xy 42.722962 -281.125898)
			(xy 42.734739 -281.078114) (xy 42.75403 -281.032838) (xy 42.780333 -280.991242) (xy 42.812968 -280.954405)
			(xy 42.851089 -280.92328) (xy 42.89371 -280.898673) (xy 42.939726 -280.881221) (xy 42.987945 -280.871377)
			(xy 43.03712 -280.869396) (xy 43.085975 -280.875328) (xy 43.133246 -280.88902) (xy 43.177708 -280.910118)
			(xy 43.218211 -280.938074) (xy 43.253704 -280.972166) (xy 43.283269 -281.01151) (xy 43.30614 -281.055087)
			(xy 43.321724 -281.101768) (xy 43.329619 -281.150345) (xy 43.330114 -281.174952) (xy 43.329619 -281.199559)
			(xy 43.321724 -281.248136) (xy 43.30614 -281.294817) (xy 43.283269 -281.338394) (xy 43.253704 -281.377738)
			(xy 43.218211 -281.41183) (xy 43.177708 -281.439786) (xy 43.133246 -281.460884) (xy 43.085975 -281.474576)
			(xy 43.03712 -281.480508) (xy 42.987945 -281.478527) (xy 42.939726 -281.468683) (xy 42.89371 -281.451231)
			(xy 42.851089 -281.426624) (xy 42.812968 -281.395499) (xy 42.780333 -281.358662) (xy 42.75403 -281.317066)
			(xy 42.734739 -281.27179) (xy 42.722962 -281.224006) (xy 42.719002 -281.174952) (xy 42.380154 -281.174952)
			(xy 42.379659 -281.199559) (xy 42.371764 -281.248136) (xy 42.35618 -281.294817) (xy 42.333309 -281.338394)
			(xy 42.303744 -281.377738) (xy 42.268251 -281.41183) (xy 42.227748 -281.439786) (xy 42.183286 -281.460884)
			(xy 42.136015 -281.474576) (xy 42.08716 -281.480508) (xy 42.037985 -281.478527) (xy 41.989766 -281.468683)
			(xy 41.94375 -281.451231) (xy 41.901129 -281.426624) (xy 41.863008 -281.395499) (xy 41.830373 -281.358662)
			(xy 41.80407 -281.317066) (xy 41.784779 -281.27179) (xy 41.773002 -281.224006) (xy 41.769042 -281.174952)
			(xy 41.430194 -281.174952) (xy 41.429699 -281.199559) (xy 41.421804 -281.248136) (xy 41.40622 -281.294817)
			(xy 41.383349 -281.338394) (xy 41.353784 -281.377738) (xy 41.318291 -281.41183) (xy 41.277788 -281.439786)
			(xy 41.233326 -281.460884) (xy 41.186055 -281.474576) (xy 41.1372 -281.480508) (xy 41.088025 -281.478527)
			(xy 41.039806 -281.468683) (xy 40.99379 -281.451231) (xy 40.951169 -281.426624) (xy 40.913048 -281.395499)
			(xy 40.880413 -281.358662) (xy 40.85411 -281.317066) (xy 40.834819 -281.27179) (xy 40.823042 -281.224006)
			(xy 40.819082 -281.174952) (xy 40.480234 -281.174952) (xy 40.479739 -281.199559) (xy 40.471844 -281.248136)
			(xy 40.45626 -281.294817) (xy 40.433389 -281.338394) (xy 40.403824 -281.377738) (xy 40.368331 -281.41183)
			(xy 40.327828 -281.439786) (xy 40.283366 -281.460884) (xy 40.236095 -281.474576) (xy 40.18724 -281.480508)
			(xy 40.138065 -281.478527) (xy 40.089846 -281.468683) (xy 40.04383 -281.451231) (xy 40.001209 -281.426624)
			(xy 39.963088 -281.395499) (xy 39.930453 -281.358662) (xy 39.90415 -281.317066) (xy 39.884859 -281.27179)
			(xy 39.873082 -281.224006) (xy 39.869122 -281.174952) (xy 39.530274 -281.174952) (xy 39.529779 -281.199559)
			(xy 39.521884 -281.248136) (xy 39.5063 -281.294817) (xy 39.483429 -281.338394) (xy 39.453864 -281.377738)
			(xy 39.418371 -281.41183) (xy 39.377868 -281.439786) (xy 39.333406 -281.460884) (xy 39.286135 -281.474576)
			(xy 39.23728 -281.480508) (xy 39.188105 -281.478527) (xy 39.139886 -281.468683) (xy 39.09387 -281.451231)
			(xy 39.051249 -281.426624) (xy 39.013128 -281.395499) (xy 38.980493 -281.358662) (xy 38.95419 -281.317066)
			(xy 38.934899 -281.27179) (xy 38.923122 -281.224006) (xy 38.919162 -281.174952) (xy 38.580314 -281.174952)
			(xy 38.579819 -281.199559) (xy 38.571924 -281.248136) (xy 38.55634 -281.294817) (xy 38.533469 -281.338394)
			(xy 38.503904 -281.377738) (xy 38.468411 -281.41183) (xy 38.427908 -281.439786) (xy 38.383446 -281.460884)
			(xy 38.336175 -281.474576) (xy 38.28732 -281.480508) (xy 38.238145 -281.478527) (xy 38.189926 -281.468683)
			(xy 38.14391 -281.451231) (xy 38.101289 -281.426624) (xy 38.063168 -281.395499) (xy 38.030533 -281.358662)
			(xy 38.00423 -281.317066) (xy 37.984939 -281.27179) (xy 37.973162 -281.224006) (xy 37.969202 -281.174952)
			(xy 37.6301 -281.174952) (xy 37.629605 -281.199559) (xy 37.62171 -281.248136) (xy 37.606126 -281.294817)
			(xy 37.583255 -281.338394) (xy 37.55369 -281.377738) (xy 37.518197 -281.41183) (xy 37.477694 -281.439786)
			(xy 37.433232 -281.460884) (xy 37.385961 -281.474576) (xy 37.337106 -281.480508) (xy 37.287931 -281.478527)
			(xy 37.239712 -281.468683) (xy 37.193696 -281.451231) (xy 37.151075 -281.426624) (xy 37.112954 -281.395499)
			(xy 37.080319 -281.358662) (xy 37.054016 -281.317066) (xy 37.034725 -281.27179) (xy 37.022948 -281.224006)
			(xy 37.018988 -281.174952) (xy 36.68014 -281.174952) (xy 36.679645 -281.199559) (xy 36.67175 -281.248136)
			(xy 36.656166 -281.294817) (xy 36.633295 -281.338394) (xy 36.60373 -281.377738) (xy 36.568237 -281.41183)
			(xy 36.527734 -281.439786) (xy 36.483272 -281.460884) (xy 36.436001 -281.474576) (xy 36.387146 -281.480508)
			(xy 36.337971 -281.478527) (xy 36.289752 -281.468683) (xy 36.243736 -281.451231) (xy 36.201115 -281.426624)
			(xy 36.162994 -281.395499) (xy 36.130359 -281.358662) (xy 36.104056 -281.317066) (xy 36.084765 -281.27179)
			(xy 36.072988 -281.224006) (xy 36.069028 -281.174952) (xy 1.468374 -281.174952) (xy 1.468374 -281.829256)
			(xy 25.811478 -281.829256) (xy 25.815549 -281.773634) (xy 25.827675 -281.719197) (xy 25.847598 -281.667106)
			(xy 25.874894 -281.618471) (xy 25.90898 -281.574328) (xy 25.949129 -281.535619) (xy 25.994487 -281.503168)
			(xy 26.044087 -281.477667) (xy 26.096871 -281.45966) (xy 26.151714 -281.44953) (xy 26.207448 -281.447493)
			(xy 26.262885 -281.453593) (xy 26.316842 -281.467699) (xy 26.368171 -281.489511) (xy 26.415777 -281.518565)
			(xy 26.458645 -281.55424) (xy 26.495862 -281.595777) (xy 26.526635 -281.64229) (xy 26.550307 -281.692787)
			(xy 26.566375 -281.746194) (xy 26.574495 -281.80137) (xy 26.575004 -281.829256) (xy 27.296616 -281.829256)
			(xy 27.300687 -281.773634) (xy 27.312813 -281.719197) (xy 27.332736 -281.667106) (xy 27.360032 -281.618471)
			(xy 27.394118 -281.574328) (xy 27.434267 -281.535619) (xy 27.479625 -281.503168) (xy 27.529225 -281.477667)
			(xy 27.582009 -281.45966) (xy 27.636852 -281.44953) (xy 27.692586 -281.447493) (xy 27.748023 -281.453593)
			(xy 27.80198 -281.467699) (xy 27.853309 -281.489511) (xy 27.900915 -281.518565) (xy 27.943783 -281.55424)
			(xy 27.981 -281.595777) (xy 28.011773 -281.64229) (xy 28.035445 -281.692787) (xy 28.051513 -281.746194)
			(xy 28.059633 -281.80137) (xy 28.060142 -281.829256) (xy 28.059633 -281.857142) (xy 28.051513 -281.912318)
			(xy 28.035445 -281.965725) (xy 28.011773 -282.016222) (xy 27.981 -282.062735) (xy 27.943783 -282.104272)
			(xy 27.918981 -282.124912) (xy 36.069028 -282.124912) (xy 36.072988 -282.075858) (xy 36.084765 -282.028074)
			(xy 36.104056 -281.982798) (xy 36.130359 -281.941202) (xy 36.162994 -281.904365) (xy 36.201115 -281.87324)
			(xy 36.243736 -281.848633) (xy 36.289752 -281.831181) (xy 36.337971 -281.821337) (xy 36.387146 -281.819356)
			(xy 36.436001 -281.825288) (xy 36.483272 -281.83898) (xy 36.527734 -281.860078) (xy 36.568237 -281.888034)
			(xy 36.60373 -281.922126) (xy 36.633295 -281.96147) (xy 36.656166 -282.005047) (xy 36.67175 -282.051728)
			(xy 36.679645 -282.100305) (xy 36.68014 -282.124912) (xy 37.018988 -282.124912) (xy 37.022948 -282.075858)
			(xy 37.034725 -282.028074) (xy 37.054016 -281.982798) (xy 37.080319 -281.941202) (xy 37.112954 -281.904365)
			(xy 37.151075 -281.87324) (xy 37.193696 -281.848633) (xy 37.239712 -281.831181) (xy 37.287931 -281.821337)
			(xy 37.337106 -281.819356) (xy 37.385961 -281.825288) (xy 37.433232 -281.83898) (xy 37.477694 -281.860078)
			(xy 37.518197 -281.888034) (xy 37.55369 -281.922126) (xy 37.583255 -281.96147) (xy 37.606126 -282.005047)
			(xy 37.62171 -282.051728) (xy 37.629605 -282.100305) (xy 37.6301 -282.124912) (xy 37.969202 -282.124912)
			(xy 37.973162 -282.075858) (xy 37.984939 -282.028074) (xy 38.00423 -281.982798) (xy 38.030533 -281.941202)
			(xy 38.063168 -281.904365) (xy 38.101289 -281.87324) (xy 38.14391 -281.848633) (xy 38.189926 -281.831181)
			(xy 38.238145 -281.821337) (xy 38.28732 -281.819356) (xy 38.336175 -281.825288) (xy 38.383446 -281.83898)
			(xy 38.427908 -281.860078) (xy 38.468411 -281.888034) (xy 38.503904 -281.922126) (xy 38.533469 -281.96147)
			(xy 38.55634 -282.005047) (xy 38.571924 -282.051728) (xy 38.579819 -282.100305) (xy 38.580314 -282.124912)
			(xy 38.919162 -282.124912) (xy 38.923122 -282.075858) (xy 38.934899 -282.028074) (xy 38.95419 -281.982798)
			(xy 38.980493 -281.941202) (xy 39.013128 -281.904365) (xy 39.051249 -281.87324) (xy 39.09387 -281.848633)
			(xy 39.139886 -281.831181) (xy 39.188105 -281.821337) (xy 39.23728 -281.819356) (xy 39.286135 -281.825288)
			(xy 39.333406 -281.83898) (xy 39.377868 -281.860078) (xy 39.418371 -281.888034) (xy 39.453864 -281.922126)
			(xy 39.483429 -281.96147) (xy 39.5063 -282.005047) (xy 39.521884 -282.051728) (xy 39.529779 -282.100305)
			(xy 39.530274 -282.124912) (xy 39.869122 -282.124912) (xy 39.873082 -282.075858) (xy 39.884859 -282.028074)
			(xy 39.90415 -281.982798) (xy 39.930453 -281.941202) (xy 39.963088 -281.904365) (xy 40.001209 -281.87324)
			(xy 40.04383 -281.848633) (xy 40.089846 -281.831181) (xy 40.138065 -281.821337) (xy 40.18724 -281.819356)
			(xy 40.236095 -281.825288) (xy 40.283366 -281.83898) (xy 40.327828 -281.860078) (xy 40.368331 -281.888034)
			(xy 40.403824 -281.922126) (xy 40.433389 -281.96147) (xy 40.45626 -282.005047) (xy 40.471844 -282.051728)
			(xy 40.479739 -282.100305) (xy 40.480234 -282.124912) (xy 40.819082 -282.124912) (xy 40.823042 -282.075858)
			(xy 40.834819 -282.028074) (xy 40.85411 -281.982798) (xy 40.880413 -281.941202) (xy 40.913048 -281.904365)
			(xy 40.951169 -281.87324) (xy 40.99379 -281.848633) (xy 41.039806 -281.831181) (xy 41.088025 -281.821337)
			(xy 41.1372 -281.819356) (xy 41.186055 -281.825288) (xy 41.233326 -281.83898) (xy 41.277788 -281.860078)
			(xy 41.318291 -281.888034) (xy 41.353784 -281.922126) (xy 41.383349 -281.96147) (xy 41.40622 -282.005047)
			(xy 41.421804 -282.051728) (xy 41.429699 -282.100305) (xy 41.430194 -282.124912) (xy 41.769042 -282.124912)
			(xy 41.773002 -282.075858) (xy 41.784779 -282.028074) (xy 41.80407 -281.982798) (xy 41.830373 -281.941202)
			(xy 41.863008 -281.904365) (xy 41.901129 -281.87324) (xy 41.94375 -281.848633) (xy 41.989766 -281.831181)
			(xy 42.037985 -281.821337) (xy 42.08716 -281.819356) (xy 42.136015 -281.825288) (xy 42.183286 -281.83898)
			(xy 42.227748 -281.860078) (xy 42.268251 -281.888034) (xy 42.303744 -281.922126) (xy 42.333309 -281.96147)
			(xy 42.35618 -282.005047) (xy 42.371764 -282.051728) (xy 42.379659 -282.100305) (xy 42.380154 -282.124912)
			(xy 42.719002 -282.124912) (xy 42.722962 -282.075858) (xy 42.734739 -282.028074) (xy 42.75403 -281.982798)
			(xy 42.780333 -281.941202) (xy 42.812968 -281.904365) (xy 42.851089 -281.87324) (xy 42.89371 -281.848633)
			(xy 42.939726 -281.831181) (xy 42.987945 -281.821337) (xy 43.03712 -281.819356) (xy 43.085975 -281.825288)
			(xy 43.133246 -281.83898) (xy 43.177708 -281.860078) (xy 43.218211 -281.888034) (xy 43.253704 -281.922126)
			(xy 43.283269 -281.96147) (xy 43.30614 -282.005047) (xy 43.321724 -282.051728) (xy 43.329619 -282.100305)
			(xy 43.329948 -282.116638) (xy 43.669093 -282.116638) (xy 43.674456 -282.06729) (xy 43.687733 -282.01946)
			(xy 43.708572 -281.974408) (xy 43.736425 -281.933321) (xy 43.770558 -281.897281) (xy 43.810072 -281.867238)
			(xy 43.853925 -281.843983) (xy 43.900964 -281.828128) (xy 43.949947 -281.820093) (xy 43.974766 -281.819604)
			(xy 43.988949 -281.819785) (xy 44.017189 -281.822454) (xy 44.031154 -281.824938) (xy 44.045114 -281.827133)
			(xy 44.073246 -281.824541) (xy 44.099592 -281.814343) (xy 44.122137 -281.797318) (xy 44.139156 -281.774768)
			(xy 44.149347 -281.74842) (xy 44.151931 -281.720287) (xy 44.149772 -281.70632) (xy 44.147288 -281.692355)
			(xy 44.144621 -281.664115) (xy 44.144438 -281.649932) (xy 44.144843 -281.625109) (xy 44.15287 -281.576115)
			(xy 44.168717 -281.529066) (xy 44.191967 -281.4852) (xy 44.222007 -281.445674) (xy 44.258047 -281.411528)
			(xy 44.299135 -281.383662) (xy 44.344191 -281.362811) (xy 44.392026 -281.349524) (xy 44.441381 -281.34415)
			(xy 44.490955 -281.346832) (xy 44.539442 -281.357499) (xy 44.585564 -281.375869) (xy 44.628107 -281.401459)
			(xy 44.66595 -281.433595) (xy 44.698095 -281.471429) (xy 44.723696 -281.513966) (xy 44.742078 -281.560084)
			(xy 44.752757 -281.608568) (xy 44.755006 -281.649932) (xy 45.094156 -281.649932) (xy 45.098116 -281.600878)
			(xy 45.109893 -281.553094) (xy 45.129184 -281.507818) (xy 45.155487 -281.466222) (xy 45.188122 -281.429385)
			(xy 45.226243 -281.39826) (xy 45.268864 -281.373653) (xy 45.31488 -281.356201) (xy 45.363099 -281.346357)
			(xy 45.412274 -281.344376) (xy 45.461129 -281.350308) (xy 45.5084 -281.364) (xy 45.552862 -281.385098)
			(xy 45.593365 -281.413054) (xy 45.628858 -281.447146) (xy 45.658423 -281.48649) (xy 45.681294 -281.530067)
			(xy 45.696878 -281.576748) (xy 45.704773 -281.625325) (xy 45.705268 -281.649932) (xy 46.044116 -281.649932)
			(xy 46.048076 -281.600878) (xy 46.059853 -281.553094) (xy 46.079144 -281.507818) (xy 46.105447 -281.466222)
			(xy 46.138082 -281.429385) (xy 46.176203 -281.39826) (xy 46.218824 -281.373653) (xy 46.26484 -281.356201)
			(xy 46.313059 -281.346357) (xy 46.362234 -281.344376) (xy 46.411089 -281.350308) (xy 46.45836 -281.364)
			(xy 46.502822 -281.385098) (xy 46.543325 -281.413054) (xy 46.578818 -281.447146) (xy 46.608383 -281.48649)
			(xy 46.631254 -281.530067) (xy 46.646838 -281.576748) (xy 46.654733 -281.625325) (xy 46.655228 -281.649932)
			(xy 46.994076 -281.649932) (xy 46.998036 -281.600878) (xy 47.009813 -281.553094) (xy 47.029104 -281.507818)
			(xy 47.055407 -281.466222) (xy 47.088042 -281.429385) (xy 47.126163 -281.39826) (xy 47.168784 -281.373653)
			(xy 47.2148 -281.356201) (xy 47.263019 -281.346357) (xy 47.312194 -281.344376) (xy 47.361049 -281.350308)
			(xy 47.40832 -281.364) (xy 47.452782 -281.385098) (xy 47.493285 -281.413054) (xy 47.528778 -281.447146)
			(xy 47.558343 -281.48649) (xy 47.581214 -281.530067) (xy 47.596798 -281.576748) (xy 47.604693 -281.625325)
			(xy 47.605188 -281.649932) (xy 47.944036 -281.649932) (xy 47.947996 -281.600878) (xy 47.959773 -281.553094)
			(xy 47.979064 -281.507818) (xy 48.005367 -281.466222) (xy 48.038002 -281.429385) (xy 48.076123 -281.39826)
			(xy 48.118744 -281.373653) (xy 48.16476 -281.356201) (xy 48.212979 -281.346357) (xy 48.262154 -281.344376)
			(xy 48.311009 -281.350308) (xy 48.35828 -281.364) (xy 48.402742 -281.385098) (xy 48.443245 -281.413054)
			(xy 48.478738 -281.447146) (xy 48.508303 -281.48649) (xy 48.531174 -281.530067) (xy 48.546758 -281.576748)
			(xy 48.554653 -281.625325) (xy 48.555148 -281.649932) (xy 48.893996 -281.649932) (xy 48.897956 -281.600878)
			(xy 48.909733 -281.553094) (xy 48.929024 -281.507818) (xy 48.955327 -281.466222) (xy 48.987962 -281.429385)
			(xy 49.026083 -281.39826) (xy 49.068704 -281.373653) (xy 49.11472 -281.356201) (xy 49.162939 -281.346357)
			(xy 49.212114 -281.344376) (xy 49.260969 -281.350308) (xy 49.30824 -281.364) (xy 49.352702 -281.385098)
			(xy 49.393205 -281.413054) (xy 49.428698 -281.447146) (xy 49.458263 -281.48649) (xy 49.481134 -281.530067)
			(xy 49.496718 -281.576748) (xy 49.504613 -281.625325) (xy 49.505108 -281.649932) (xy 49.843956 -281.649932)
			(xy 49.847916 -281.600878) (xy 49.859693 -281.553094) (xy 49.878984 -281.507818) (xy 49.905287 -281.466222)
			(xy 49.937922 -281.429385) (xy 49.976043 -281.39826) (xy 50.018664 -281.373653) (xy 50.06468 -281.356201)
			(xy 50.112899 -281.346357) (xy 50.162074 -281.344376) (xy 50.210929 -281.350308) (xy 50.2582 -281.364)
			(xy 50.302662 -281.385098) (xy 50.343165 -281.413054) (xy 50.378658 -281.447146) (xy 50.408223 -281.48649)
			(xy 50.431094 -281.530067) (xy 50.446678 -281.576748) (xy 50.454573 -281.625325) (xy 50.455068 -281.649932)
			(xy 50.79417 -281.649932) (xy 50.79813 -281.600878) (xy 50.809907 -281.553094) (xy 50.829198 -281.507818)
			(xy 50.855501 -281.466222) (xy 50.888136 -281.429385) (xy 50.926257 -281.39826) (xy 50.968878 -281.373653)
			(xy 51.014894 -281.356201) (xy 51.063113 -281.346357) (xy 51.112288 -281.344376) (xy 51.161143 -281.350308)
			(xy 51.208414 -281.364) (xy 51.252876 -281.385098) (xy 51.293379 -281.413054) (xy 51.328872 -281.447146)
			(xy 51.358437 -281.48649) (xy 51.381308 -281.530067) (xy 51.396892 -281.576748) (xy 51.404787 -281.625325)
			(xy 51.405282 -281.649932) (xy 51.74413 -281.649932) (xy 51.74809 -281.600878) (xy 51.759867 -281.553094)
			(xy 51.779158 -281.507818) (xy 51.805461 -281.466222) (xy 51.838096 -281.429385) (xy 51.876217 -281.39826)
			(xy 51.918838 -281.373653) (xy 51.964854 -281.356201) (xy 52.013073 -281.346357) (xy 52.062248 -281.344376)
			(xy 52.111103 -281.350308) (xy 52.158374 -281.364) (xy 52.202836 -281.385098) (xy 52.243339 -281.413054)
			(xy 52.278832 -281.447146) (xy 52.308397 -281.48649) (xy 52.331268 -281.530067) (xy 52.346852 -281.576748)
			(xy 52.354747 -281.625325) (xy 52.355242 -281.649932) (xy 52.69409 -281.649932) (xy 52.69805 -281.600878)
			(xy 52.709827 -281.553094) (xy 52.729118 -281.507818) (xy 52.755421 -281.466222) (xy 52.788056 -281.429385)
			(xy 52.826177 -281.39826) (xy 52.868798 -281.373653) (xy 52.914814 -281.356201) (xy 52.963033 -281.346357)
			(xy 53.012208 -281.344376) (xy 53.061063 -281.350308) (xy 53.108334 -281.364) (xy 53.152796 -281.385098)
			(xy 53.193299 -281.413054) (xy 53.228792 -281.447146) (xy 53.258357 -281.48649) (xy 53.281228 -281.530067)
			(xy 53.296812 -281.576748) (xy 53.304707 -281.625325) (xy 53.305202 -281.649932) (xy 53.305037 -281.658139)
			(xy 53.644226 -281.658139) (xy 53.64692 -281.608578) (xy 53.657596 -281.560106) (xy 53.675973 -281.514)
			(xy 53.701568 -281.471475) (xy 53.733705 -281.43365) (xy 53.771538 -281.401522) (xy 53.81407 -281.375939)
			(xy 53.860181 -281.357573) (xy 53.908656 -281.346909) (xy 53.958217 -281.344228) (xy 54.007559 -281.3496)
			(xy 54.055382 -281.362884) (xy 54.100426 -281.38373) (xy 54.141504 -281.411589) (xy 54.177534 -281.445726)
			(xy 54.207567 -281.485242) (xy 54.230811 -281.529097) (xy 54.246654 -281.576134) (xy 54.254679 -281.625115)
			(xy 54.255162 -281.649932) (xy 54.254991 -281.664115) (xy 54.252315 -281.692355) (xy 54.249828 -281.70632)
			(xy 54.247542 -281.718766) (xy 54.254908 -281.742388) (xy 54.332378 -281.819858) (xy 54.356 -281.827224)
			(xy 54.368446 -281.824938) (xy 54.382412 -281.82246) (xy 54.410651 -281.819789) (xy 54.424834 -281.819604)
			(xy 54.439017 -281.819776) (xy 54.467257 -281.822451) (xy 54.481222 -281.824938) (xy 54.493668 -281.827224)
			(xy 54.51729 -281.819858) (xy 54.59476 -281.742388) (xy 54.602126 -281.718766) (xy 54.59984 -281.70632)
			(xy 54.597357 -281.692355) (xy 54.594689 -281.664115) (xy 54.594506 -281.649932) (xy 54.594943 -281.625108)
			(xy 54.60297 -281.576114) (xy 54.618818 -281.529064) (xy 54.642069 -281.485197) (xy 54.672111 -281.44567)
			(xy 54.708151 -281.411524) (xy 54.749242 -281.383659) (xy 54.794299 -281.362808) (xy 54.842135 -281.349522)
			(xy 54.891491 -281.34415) (xy 54.941066 -281.346834) (xy 54.989554 -281.357502) (xy 55.035677 -281.375875)
			(xy 55.07822 -281.401468) (xy 55.116062 -281.433606) (xy 55.148205 -281.471443) (xy 55.173804 -281.513982)
			(xy 55.192184 -281.560102) (xy 55.20286 -281.608588) (xy 55.205104 -281.649932) (xy 55.54397 -281.649932)
			(xy 55.54793 -281.600878) (xy 55.559707 -281.553094) (xy 55.578998 -281.507818) (xy 55.605301 -281.466222)
			(xy 55.637936 -281.429385) (xy 55.676057 -281.39826) (xy 55.718678 -281.373653) (xy 55.764694 -281.356201)
			(xy 55.812913 -281.346357) (xy 55.862088 -281.344376) (xy 55.910943 -281.350308) (xy 55.958214 -281.364)
			(xy 56.002676 -281.385098) (xy 56.043179 -281.413054) (xy 56.078672 -281.447146) (xy 56.108237 -281.48649)
			(xy 56.131108 -281.530067) (xy 56.146692 -281.576748) (xy 56.154587 -281.625325) (xy 56.155082 -281.649932)
			(xy 56.494184 -281.649932) (xy 56.498144 -281.600878) (xy 56.509921 -281.553094) (xy 56.529212 -281.507818)
			(xy 56.555515 -281.466222) (xy 56.58815 -281.429385) (xy 56.626271 -281.39826) (xy 56.668892 -281.373653)
			(xy 56.714908 -281.356201) (xy 56.763127 -281.346357) (xy 56.812302 -281.344376) (xy 56.861157 -281.350308)
			(xy 56.908428 -281.364) (xy 56.95289 -281.385098) (xy 56.993393 -281.413054) (xy 57.028886 -281.447146)
			(xy 57.058451 -281.48649) (xy 57.081322 -281.530067) (xy 57.096906 -281.576748) (xy 57.104801 -281.625325)
			(xy 57.105296 -281.649932) (xy 57.104801 -281.674539) (xy 57.096906 -281.723116) (xy 57.081322 -281.769797)
			(xy 57.058451 -281.813374) (xy 57.028886 -281.852718) (xy 56.993393 -281.88681) (xy 56.95289 -281.914766)
			(xy 56.908428 -281.935864) (xy 56.861157 -281.949556) (xy 56.812302 -281.955488) (xy 56.763127 -281.953507)
			(xy 56.714908 -281.943663) (xy 56.668892 -281.926211) (xy 56.626271 -281.901604) (xy 56.58815 -281.870479)
			(xy 56.555515 -281.833642) (xy 56.529212 -281.792046) (xy 56.509921 -281.74677) (xy 56.498144 -281.698986)
			(xy 56.494184 -281.649932) (xy 56.155082 -281.649932) (xy 56.154587 -281.674539) (xy 56.146692 -281.723116)
			(xy 56.131108 -281.769797) (xy 56.108237 -281.813374) (xy 56.078672 -281.852718) (xy 56.043179 -281.88681)
			(xy 56.002676 -281.914766) (xy 55.958214 -281.935864) (xy 55.910943 -281.949556) (xy 55.862088 -281.955488)
			(xy 55.812913 -281.953507) (xy 55.764694 -281.943663) (xy 55.718678 -281.926211) (xy 55.676057 -281.901604)
			(xy 55.637936 -281.870479) (xy 55.605301 -281.833642) (xy 55.578998 -281.792046) (xy 55.559707 -281.74677)
			(xy 55.54793 -281.698986) (xy 55.54397 -281.649932) (xy 55.205104 -281.649932) (xy 55.205551 -281.658163)
			(xy 55.200187 -281.707519) (xy 55.186908 -281.755358) (xy 55.166064 -281.800418) (xy 55.138205 -281.841513)
			(xy 55.104064 -281.877558) (xy 55.064542 -281.907606) (xy 55.020679 -281.930864) (xy 54.973631 -281.946718)
			(xy 54.924638 -281.954753) (xy 54.899814 -281.95524) (xy 54.885631 -281.955061) (xy 54.857391 -281.95239)
			(xy 54.843426 -281.949906) (xy 54.83098 -281.94762) (xy 54.807358 -281.954986) (xy 54.729888 -282.032456)
			(xy 54.722522 -282.056078) (xy 54.724808 -282.068524) (xy 54.727284 -282.08249) (xy 54.729956 -282.110729)
			(xy 54.730142 -282.124912) (xy 54.72962 -282.150167) (xy 54.721307 -282.199989) (xy 54.704906 -282.247763)
			(xy 54.680865 -282.292186) (xy 54.649841 -282.332046) (xy 54.612679 -282.366256) (xy 54.570393 -282.393882)
			(xy 54.524137 -282.414172) (xy 54.475172 -282.426572) (xy 54.424834 -282.430743) (xy 54.374496 -282.426572)
			(xy 54.325531 -282.414172) (xy 54.279275 -282.393882) (xy 54.236989 -282.366256) (xy 54.199827 -282.332046)
			(xy 54.168803 -282.292186) (xy 54.144762 -282.247763) (xy 54.128361 -282.199989) (xy 54.120048 -282.150167)
			(xy 54.119526 -282.124912) (xy 54.119704 -282.110729) (xy 54.122375 -282.082489) (xy 54.12486 -282.068524)
			(xy 54.127146 -282.056078) (xy 54.11978 -282.032456) (xy 54.04231 -281.954986) (xy 54.018688 -281.94762)
			(xy 54.006242 -281.949906) (xy 53.992277 -281.952387) (xy 53.964037 -281.955056) (xy 53.949854 -281.95524)
			(xy 53.925037 -281.954673) (xy 53.876058 -281.946635) (xy 53.829025 -281.93078) (xy 53.785177 -281.907525)
			(xy 53.745668 -281.877482) (xy 53.71154 -281.841444) (xy 53.683692 -281.800358) (xy 53.662857 -281.755309)
			(xy 53.649586 -281.707483) (xy 53.644226 -281.658139) (xy 53.305037 -281.658139) (xy 53.304707 -281.674539)
			(xy 53.296812 -281.723116) (xy 53.281228 -281.769797) (xy 53.258357 -281.813374) (xy 53.228792 -281.852718)
			(xy 53.193299 -281.88681) (xy 53.152796 -281.914766) (xy 53.108334 -281.935864) (xy 53.061063 -281.949556)
			(xy 53.012208 -281.955488) (xy 52.963033 -281.953507) (xy 52.914814 -281.943663) (xy 52.868798 -281.926211)
			(xy 52.826177 -281.901604) (xy 52.788056 -281.870479) (xy 52.755421 -281.833642) (xy 52.729118 -281.792046)
			(xy 52.709827 -281.74677) (xy 52.69805 -281.698986) (xy 52.69409 -281.649932) (xy 52.355242 -281.649932)
			(xy 52.354747 -281.674539) (xy 52.346852 -281.723116) (xy 52.331268 -281.769797) (xy 52.308397 -281.813374)
			(xy 52.278832 -281.852718) (xy 52.243339 -281.88681) (xy 52.202836 -281.914766) (xy 52.158374 -281.935864)
			(xy 52.111103 -281.949556) (xy 52.062248 -281.955488) (xy 52.013073 -281.953507) (xy 51.964854 -281.943663)
			(xy 51.918838 -281.926211) (xy 51.876217 -281.901604) (xy 51.838096 -281.870479) (xy 51.805461 -281.833642)
			(xy 51.779158 -281.792046) (xy 51.759867 -281.74677) (xy 51.74809 -281.698986) (xy 51.74413 -281.649932)
			(xy 51.405282 -281.649932) (xy 51.404787 -281.674539) (xy 51.396892 -281.723116) (xy 51.381308 -281.769797)
			(xy 51.358437 -281.813374) (xy 51.328872 -281.852718) (xy 51.293379 -281.88681) (xy 51.252876 -281.914766)
			(xy 51.208414 -281.935864) (xy 51.161143 -281.949556) (xy 51.112288 -281.955488) (xy 51.063113 -281.953507)
			(xy 51.014894 -281.943663) (xy 50.968878 -281.926211) (xy 50.926257 -281.901604) (xy 50.888136 -281.870479)
			(xy 50.855501 -281.833642) (xy 50.829198 -281.792046) (xy 50.809907 -281.74677) (xy 50.79813 -281.698986)
			(xy 50.79417 -281.649932) (xy 50.455068 -281.649932) (xy 50.454573 -281.674539) (xy 50.446678 -281.723116)
			(xy 50.431094 -281.769797) (xy 50.408223 -281.813374) (xy 50.378658 -281.852718) (xy 50.343165 -281.88681)
			(xy 50.302662 -281.914766) (xy 50.2582 -281.935864) (xy 50.210929 -281.949556) (xy 50.162074 -281.955488)
			(xy 50.112899 -281.953507) (xy 50.06468 -281.943663) (xy 50.018664 -281.926211) (xy 49.976043 -281.901604)
			(xy 49.937922 -281.870479) (xy 49.905287 -281.833642) (xy 49.878984 -281.792046) (xy 49.859693 -281.74677)
			(xy 49.847916 -281.698986) (xy 49.843956 -281.649932) (xy 49.505108 -281.649932) (xy 49.504613 -281.674539)
			(xy 49.496718 -281.723116) (xy 49.481134 -281.769797) (xy 49.458263 -281.813374) (xy 49.428698 -281.852718)
			(xy 49.393205 -281.88681) (xy 49.352702 -281.914766) (xy 49.30824 -281.935864) (xy 49.260969 -281.949556)
			(xy 49.212114 -281.955488) (xy 49.162939 -281.953507) (xy 49.11472 -281.943663) (xy 49.068704 -281.926211)
			(xy 49.026083 -281.901604) (xy 48.987962 -281.870479) (xy 48.955327 -281.833642) (xy 48.929024 -281.792046)
			(xy 48.909733 -281.74677) (xy 48.897956 -281.698986) (xy 48.893996 -281.649932) (xy 48.555148 -281.649932)
			(xy 48.554653 -281.674539) (xy 48.546758 -281.723116) (xy 48.531174 -281.769797) (xy 48.508303 -281.813374)
			(xy 48.478738 -281.852718) (xy 48.443245 -281.88681) (xy 48.402742 -281.914766) (xy 48.35828 -281.935864)
			(xy 48.311009 -281.949556) (xy 48.262154 -281.955488) (xy 48.212979 -281.953507) (xy 48.16476 -281.943663)
			(xy 48.118744 -281.926211) (xy 48.076123 -281.901604) (xy 48.038002 -281.870479) (xy 48.005367 -281.833642)
			(xy 47.979064 -281.792046) (xy 47.959773 -281.74677) (xy 47.947996 -281.698986) (xy 47.944036 -281.649932)
			(xy 47.605188 -281.649932) (xy 47.604693 -281.674539) (xy 47.596798 -281.723116) (xy 47.581214 -281.769797)
			(xy 47.558343 -281.813374) (xy 47.528778 -281.852718) (xy 47.493285 -281.88681) (xy 47.452782 -281.914766)
			(xy 47.40832 -281.935864) (xy 47.361049 -281.949556) (xy 47.312194 -281.955488) (xy 47.263019 -281.953507)
			(xy 47.2148 -281.943663) (xy 47.168784 -281.926211) (xy 47.126163 -281.901604) (xy 47.088042 -281.870479)
			(xy 47.055407 -281.833642) (xy 47.029104 -281.792046) (xy 47.009813 -281.74677) (xy 46.998036 -281.698986)
			(xy 46.994076 -281.649932) (xy 46.655228 -281.649932) (xy 46.654733 -281.674539) (xy 46.646838 -281.723116)
			(xy 46.631254 -281.769797) (xy 46.608383 -281.813374) (xy 46.578818 -281.852718) (xy 46.543325 -281.88681)
			(xy 46.502822 -281.914766) (xy 46.45836 -281.935864) (xy 46.411089 -281.949556) (xy 46.362234 -281.955488)
			(xy 46.313059 -281.953507) (xy 46.26484 -281.943663) (xy 46.218824 -281.926211) (xy 46.176203 -281.901604)
			(xy 46.138082 -281.870479) (xy 46.105447 -281.833642) (xy 46.079144 -281.792046) (xy 46.059853 -281.74677)
			(xy 46.048076 -281.698986) (xy 46.044116 -281.649932) (xy 45.705268 -281.649932) (xy 45.704773 -281.674539)
			(xy 45.696878 -281.723116) (xy 45.681294 -281.769797) (xy 45.658423 -281.813374) (xy 45.628858 -281.852718)
			(xy 45.593365 -281.88681) (xy 45.552862 -281.914766) (xy 45.5084 -281.935864) (xy 45.461129 -281.949556)
			(xy 45.412274 -281.955488) (xy 45.363099 -281.953507) (xy 45.31488 -281.943663) (xy 45.268864 -281.926211)
			(xy 45.226243 -281.901604) (xy 45.188122 -281.870479) (xy 45.155487 -281.833642) (xy 45.129184 -281.792046)
			(xy 45.109893 -281.74677) (xy 45.098116 -281.698986) (xy 45.094156 -281.649932) (xy 44.755006 -281.649932)
			(xy 44.755452 -281.658141) (xy 44.750091 -281.707497) (xy 44.736816 -281.755336) (xy 44.715976 -281.800397)
			(xy 44.688121 -281.841492) (xy 44.653984 -281.87754) (xy 44.614465 -281.907591) (xy 44.570606 -281.930852)
			(xy 44.52356 -281.946711) (xy 44.474569 -281.95475) (xy 44.449746 -281.95524) (xy 44.435563 -281.955056)
			(xy 44.407323 -281.952389) (xy 44.393358 -281.949906) (xy 44.379401 -281.947672) (xy 44.35126 -281.950261)
			(xy 44.324907 -281.960462) (xy 44.302357 -281.977494) (xy 44.285336 -282.000053) (xy 44.275149 -282.026412)
			(xy 44.272574 -282.054554) (xy 44.27474 -282.068524) (xy 44.277215 -282.08249) (xy 44.279888 -282.11073)
			(xy 44.280074 -282.124912) (xy 44.279609 -282.149731) (xy 44.271577 -282.198715) (xy 44.255726 -282.245754)
			(xy 44.232474 -282.28961) (xy 44.202434 -282.329126) (xy 44.166396 -282.363261) (xy 44.125311 -282.391117)
			(xy 44.08026 -282.41196) (xy 44.032432 -282.42524) (xy 43.983084 -282.430607) (xy 43.933519 -282.42792)
			(xy 43.885041 -282.41725) (xy 43.838928 -282.398878) (xy 43.796395 -282.373288) (xy 43.758561 -282.341154)
			(xy 43.726425 -282.303323) (xy 43.700832 -282.260792) (xy 43.682456 -282.21468) (xy 43.671783 -282.166203)
			(xy 43.669093 -282.116638) (xy 43.329948 -282.116638) (xy 43.330114 -282.124912) (xy 43.329619 -282.149519)
			(xy 43.321724 -282.198096) (xy 43.30614 -282.244777) (xy 43.283269 -282.288354) (xy 43.253704 -282.327698)
			(xy 43.218211 -282.36179) (xy 43.177708 -282.389746) (xy 43.133246 -282.410844) (xy 43.085975 -282.424536)
			(xy 43.03712 -282.430468) (xy 42.987945 -282.428487) (xy 42.939726 -282.418643) (xy 42.89371 -282.401191)
			(xy 42.851089 -282.376584) (xy 42.812968 -282.345459) (xy 42.780333 -282.308622) (xy 42.75403 -282.267026)
			(xy 42.734739 -282.22175) (xy 42.722962 -282.173966) (xy 42.719002 -282.124912) (xy 42.380154 -282.124912)
			(xy 42.379659 -282.149519) (xy 42.371764 -282.198096) (xy 42.35618 -282.244777) (xy 42.333309 -282.288354)
			(xy 42.303744 -282.327698) (xy 42.268251 -282.36179) (xy 42.227748 -282.389746) (xy 42.183286 -282.410844)
			(xy 42.136015 -282.424536) (xy 42.08716 -282.430468) (xy 42.037985 -282.428487) (xy 41.989766 -282.418643)
			(xy 41.94375 -282.401191) (xy 41.901129 -282.376584) (xy 41.863008 -282.345459) (xy 41.830373 -282.308622)
			(xy 41.80407 -282.267026) (xy 41.784779 -282.22175) (xy 41.773002 -282.173966) (xy 41.769042 -282.124912)
			(xy 41.430194 -282.124912) (xy 41.429699 -282.149519) (xy 41.421804 -282.198096) (xy 41.40622 -282.244777)
			(xy 41.383349 -282.288354) (xy 41.353784 -282.327698) (xy 41.318291 -282.36179) (xy 41.277788 -282.389746)
			(xy 41.233326 -282.410844) (xy 41.186055 -282.424536) (xy 41.1372 -282.430468) (xy 41.088025 -282.428487)
			(xy 41.039806 -282.418643) (xy 40.99379 -282.401191) (xy 40.951169 -282.376584) (xy 40.913048 -282.345459)
			(xy 40.880413 -282.308622) (xy 40.85411 -282.267026) (xy 40.834819 -282.22175) (xy 40.823042 -282.173966)
			(xy 40.819082 -282.124912) (xy 40.480234 -282.124912) (xy 40.479739 -282.149519) (xy 40.471844 -282.198096)
			(xy 40.45626 -282.244777) (xy 40.433389 -282.288354) (xy 40.403824 -282.327698) (xy 40.368331 -282.36179)
			(xy 40.327828 -282.389746) (xy 40.283366 -282.410844) (xy 40.236095 -282.424536) (xy 40.18724 -282.430468)
			(xy 40.138065 -282.428487) (xy 40.089846 -282.418643) (xy 40.04383 -282.401191) (xy 40.001209 -282.376584)
			(xy 39.963088 -282.345459) (xy 39.930453 -282.308622) (xy 39.90415 -282.267026) (xy 39.884859 -282.22175)
			(xy 39.873082 -282.173966) (xy 39.869122 -282.124912) (xy 39.530274 -282.124912) (xy 39.529779 -282.149519)
			(xy 39.521884 -282.198096) (xy 39.5063 -282.244777) (xy 39.483429 -282.288354) (xy 39.453864 -282.327698)
			(xy 39.418371 -282.36179) (xy 39.377868 -282.389746) (xy 39.333406 -282.410844) (xy 39.286135 -282.424536)
			(xy 39.23728 -282.430468) (xy 39.188105 -282.428487) (xy 39.139886 -282.418643) (xy 39.09387 -282.401191)
			(xy 39.051249 -282.376584) (xy 39.013128 -282.345459) (xy 38.980493 -282.308622) (xy 38.95419 -282.267026)
			(xy 38.934899 -282.22175) (xy 38.923122 -282.173966) (xy 38.919162 -282.124912) (xy 38.580314 -282.124912)
			(xy 38.579819 -282.149519) (xy 38.571924 -282.198096) (xy 38.55634 -282.244777) (xy 38.533469 -282.288354)
			(xy 38.503904 -282.327698) (xy 38.468411 -282.36179) (xy 38.427908 -282.389746) (xy 38.383446 -282.410844)
			(xy 38.336175 -282.424536) (xy 38.28732 -282.430468) (xy 38.238145 -282.428487) (xy 38.189926 -282.418643)
			(xy 38.14391 -282.401191) (xy 38.101289 -282.376584) (xy 38.063168 -282.345459) (xy 38.030533 -282.308622)
			(xy 38.00423 -282.267026) (xy 37.984939 -282.22175) (xy 37.973162 -282.173966) (xy 37.969202 -282.124912)
			(xy 37.6301 -282.124912) (xy 37.629605 -282.149519) (xy 37.62171 -282.198096) (xy 37.606126 -282.244777)
			(xy 37.583255 -282.288354) (xy 37.55369 -282.327698) (xy 37.518197 -282.36179) (xy 37.477694 -282.389746)
			(xy 37.433232 -282.410844) (xy 37.385961 -282.424536) (xy 37.337106 -282.430468) (xy 37.287931 -282.428487)
			(xy 37.239712 -282.418643) (xy 37.193696 -282.401191) (xy 37.151075 -282.376584) (xy 37.112954 -282.345459)
			(xy 37.080319 -282.308622) (xy 37.054016 -282.267026) (xy 37.034725 -282.22175) (xy 37.022948 -282.173966)
			(xy 37.018988 -282.124912) (xy 36.68014 -282.124912) (xy 36.679645 -282.149519) (xy 36.67175 -282.198096)
			(xy 36.656166 -282.244777) (xy 36.633295 -282.288354) (xy 36.60373 -282.327698) (xy 36.568237 -282.36179)
			(xy 36.527734 -282.389746) (xy 36.483272 -282.410844) (xy 36.436001 -282.424536) (xy 36.387146 -282.430468)
			(xy 36.337971 -282.428487) (xy 36.289752 -282.418643) (xy 36.243736 -282.401191) (xy 36.201115 -282.376584)
			(xy 36.162994 -282.345459) (xy 36.130359 -282.308622) (xy 36.104056 -282.267026) (xy 36.084765 -282.22175)
			(xy 36.072988 -282.173966) (xy 36.069028 -282.124912) (xy 27.918981 -282.124912) (xy 27.900915 -282.139947)
			(xy 27.853309 -282.169001) (xy 27.80198 -282.190813) (xy 27.748023 -282.204919) (xy 27.692586 -282.211019)
			(xy 27.636852 -282.208982) (xy 27.582009 -282.198852) (xy 27.529225 -282.180845) (xy 27.479625 -282.155344)
			(xy 27.434267 -282.122893) (xy 27.394118 -282.084184) (xy 27.360032 -282.040041) (xy 27.332736 -281.991406)
			(xy 27.312813 -281.939315) (xy 27.300687 -281.884878) (xy 27.296616 -281.829256) (xy 26.575004 -281.829256)
			(xy 26.574495 -281.857142) (xy 26.566375 -281.912318) (xy 26.550307 -281.965725) (xy 26.526635 -282.016222)
			(xy 26.495862 -282.062735) (xy 26.458645 -282.104272) (xy 26.415777 -282.139947) (xy 26.368171 -282.169001)
			(xy 26.316842 -282.190813) (xy 26.262885 -282.204919) (xy 26.207448 -282.211019) (xy 26.151714 -282.208982)
			(xy 26.096871 -282.198852) (xy 26.044087 -282.180845) (xy 25.994487 -282.155344) (xy 25.949129 -282.122893)
			(xy 25.90898 -282.084184) (xy 25.874894 -282.040041) (xy 25.847598 -281.991406) (xy 25.827675 -281.939315)
			(xy 25.815549 -281.884878) (xy 25.811478 -281.829256) (xy 1.468374 -281.829256) (xy 1.468374 -282.382031)
			(xy 1.86739 -282.382031) (xy 1.86739 -282.327529) (xy 1.875146 -282.273582) (xy 1.890501 -282.221287)
			(xy 1.913142 -282.171711) (xy 1.942608 -282.12586) (xy 1.978299 -282.084671) (xy 2.019489 -282.048979)
			(xy 2.065339 -282.019513) (xy 2.114916 -281.996872) (xy 2.16721 -281.981517) (xy 2.221157 -281.97376)
			(xy 2.248408 -281.973274) (xy 2.277147 -281.9738) (xy 2.333974 -281.982423) (xy 2.388864 -281.999473)
			(xy 2.440576 -282.024564) (xy 2.487939 -282.057128) (xy 2.509266 -282.076398) (xy 2.516378 -282.083002)
			(xy 2.533904 -282.090114) (xy 2.623312 -282.090114) (xy 2.640838 -282.083002) (xy 2.64795 -282.076398)
			(xy 2.669283 -282.057134) (xy 2.716642 -282.024564) (xy 2.768352 -281.99947) (xy 2.823242 -281.982418)
			(xy 2.880069 -281.973795) (xy 2.908808 -281.973274) (xy 2.938932 -281.973833) (xy 2.998429 -281.983316)
			(xy 3.055698 -282.002029) (xy 3.109314 -282.029508) (xy 3.157948 -282.065069) (xy 3.179572 -282.08605)
			(xy 3.186684 -282.093416) (xy 3.20548 -282.101036) (xy 3.297936 -282.101036) (xy 3.316732 -282.093416)
			(xy 3.323844 -282.08605) (xy 3.345479 -282.06508) (xy 3.394104 -282.029509) (xy 3.447718 -282.002026)
			(xy 3.504986 -281.983315) (xy 3.564484 -281.973843) (xy 3.594608 -281.973274) (xy 3.621979 -281.973717)
			(xy 3.67616 -281.981538) (xy 3.728664 -281.997031) (xy 3.778411 -282.019879) (xy 3.824376 -282.049609)
			(xy 3.845306 -282.067254) (xy 3.852418 -282.07335) (xy 3.869436 -282.0797) (xy 3.95478 -282.0797)
			(xy 3.971798 -282.07335) (xy 3.97891 -282.067254) (xy 3.999834 -282.049605) (xy 4.045808 -282.019893)
			(xy 4.095558 -281.997058) (xy 4.148061 -281.981569) (xy 4.202238 -281.973745) (xy 4.229608 -281.973274)
			(xy 4.256861 -281.973733) (xy 4.310813 -281.98149) (xy 4.363111 -281.996846) (xy 4.412691 -282.019488)
			(xy 4.458545 -282.048957) (xy 4.499738 -282.08465) (xy 4.535432 -282.125843) (xy 4.564901 -282.171697)
			(xy 4.587543 -282.221277) (xy 4.6029 -282.273576) (xy 4.610657 -282.327527) (xy 4.610657 -282.382031)
			(xy 5.88618 -282.382031) (xy 5.88618 -282.327529) (xy 5.893936 -282.273582) (xy 5.909291 -282.221288)
			(xy 5.931932 -282.171711) (xy 5.961397 -282.125861) (xy 5.997088 -282.084671) (xy 6.038278 -282.04898)
			(xy 6.084128 -282.019514) (xy 6.133704 -281.996872) (xy 6.185998 -281.981517) (xy 6.239945 -281.97376)
			(xy 6.267196 -281.973274) (xy 6.295934 -281.973807) (xy 6.352761 -281.982428) (xy 6.407651 -281.999477)
			(xy 6.459363 -282.024566) (xy 6.506727 -282.057129) (xy 6.528054 -282.076398) (xy 6.535166 -282.083002)
			(xy 6.552692 -282.090114) (xy 6.6421 -282.090114) (xy 6.659626 -282.083002) (xy 6.666738 -282.076398)
			(xy 6.688065 -282.057128) (xy 6.735428 -282.024563) (xy 6.787139 -281.999472) (xy 6.84203 -281.982422)
			(xy 6.898857 -281.9738) (xy 6.956335 -281.9738) (xy 7.013162 -281.982422) (xy 7.068053 -281.999472)
			(xy 7.119764 -282.024563) (xy 7.167127 -282.057128) (xy 7.188454 -282.076398) (xy 7.195566 -282.083002)
			(xy 7.213092 -282.090114) (xy 7.3025 -282.090114) (xy 7.320026 -282.083002) (xy 7.327138 -282.076398)
			(xy 7.348476 -282.05714) (xy 7.395834 -282.024569) (xy 7.447543 -281.999474) (xy 7.502431 -281.98242)
			(xy 7.559258 -281.973796) (xy 7.587996 -281.973274) (xy 7.61812 -281.97384) (xy 7.677617 -281.983321)
			(xy 7.734885 -282.002033) (xy 7.788502 -282.02951) (xy 7.837136 -282.06507) (xy 7.85876 -282.08605)
			(xy 7.865872 -282.093416) (xy 7.884668 -282.101036) (xy 7.977124 -282.101036) (xy 7.99592 -282.093416)
			(xy 8.003032 -282.08605) (xy 8.024672 -282.065086) (xy 8.073296 -282.029514) (xy 8.126908 -282.00203)
			(xy 8.184175 -281.983318) (xy 8.243673 -281.973844) (xy 8.273796 -281.973274) (xy 8.301049 -281.973733)
			(xy 8.355001 -281.98149) (xy 8.407299 -281.996845) (xy 8.45688 -282.019488) (xy 8.502734 -282.048956)
			(xy 8.543928 -282.08465) (xy 8.579622 -282.125843) (xy 8.60909 -282.171696) (xy 8.631733 -282.221277)
			(xy 8.64709 -282.273575) (xy 8.654847 -282.327527) (xy 8.654847 -282.382033) (xy 8.64709 -282.435985)
			(xy 8.631733 -282.488283) (xy 8.60909 -282.537864) (xy 8.579622 -282.583717) (xy 8.543928 -282.62491)
			(xy 8.502734 -282.660604) (xy 8.45688 -282.690072) (xy 8.407299 -282.712715) (xy 8.355001 -282.72807)
			(xy 8.301049 -282.735827) (xy 8.273796 -282.73629) (xy 8.243672 -282.735739) (xy 8.184174 -282.726256)
			(xy 8.126905 -282.707541) (xy 8.073288 -282.68006) (xy 8.024656 -282.644496) (xy 8.003032 -282.623514)
			(xy 7.99592 -282.616148) (xy 7.977124 -282.608528) (xy 7.884668 -282.608528) (xy 7.865872 -282.616148)
			(xy 7.85876 -282.623514) (xy 7.837134 -282.644493) (xy 7.788505 -282.680061) (xy 7.734889 -282.707541)
			(xy 7.677619 -282.726249) (xy 7.61812 -282.735721) (xy 7.587996 -282.73629) (xy 7.559257 -282.735771)
			(xy 7.502429 -282.727148) (xy 7.447538 -282.710097) (xy 7.395827 -282.685004) (xy 7.348464 -282.652437)
			(xy 7.327138 -282.633166) (xy 7.320026 -282.626562) (xy 7.3025 -282.61945) (xy 7.213092 -282.61945)
			(xy 7.195566 -282.626562) (xy 7.188454 -282.633166) (xy 7.167127 -282.652436) (xy 7.119764 -282.685001)
			(xy 7.068053 -282.710092) (xy 7.013162 -282.727142) (xy 6.956335 -282.735764) (xy 6.898857 -282.735764)
			(xy 6.84203 -282.727142) (xy 6.787139 -282.710092) (xy 6.735428 -282.685001) (xy 6.688065 -282.652436)
			(xy 6.666738 -282.633166) (xy 6.659626 -282.626562) (xy 6.6421 -282.61945) (xy 6.552692 -282.61945)
			(xy 6.535166 -282.626562) (xy 6.528054 -282.633166) (xy 6.506729 -282.652439) (xy 6.459366 -282.685005)
			(xy 6.407654 -282.710097) (xy 6.352763 -282.727147) (xy 6.295935 -282.735769) (xy 6.267196 -282.73629)
			(xy 6.239945 -282.7358) (xy 6.185998 -282.728043) (xy 6.133704 -282.712688) (xy 6.084128 -282.690046)
			(xy 6.038278 -282.66058) (xy 5.997088 -282.624889) (xy 5.961397 -282.583699) (xy 5.931932 -282.537849)
			(xy 5.909291 -282.488272) (xy 5.893936 -282.435978) (xy 5.88618 -282.382031) (xy 4.610657 -282.382031)
			(xy 4.610657 -282.382033) (xy 4.6029 -282.435984) (xy 4.587543 -282.488283) (xy 4.564901 -282.537863)
			(xy 4.535432 -282.583717) (xy 4.499738 -282.62491) (xy 4.458545 -282.660603) (xy 4.412691 -282.690072)
			(xy 4.363111 -282.712714) (xy 4.310813 -282.72807) (xy 4.256861 -282.735827) (xy 4.229608 -282.73629)
			(xy 4.202238 -282.735822) (xy 4.148059 -282.728005) (xy 4.095556 -282.712516) (xy 4.045809 -282.689675)
			(xy 3.999842 -282.659951) (xy 3.97891 -282.64231) (xy 3.971798 -282.636214) (xy 3.95478 -282.629864)
			(xy 3.869436 -282.629864) (xy 3.852418 -282.636214) (xy 3.845306 -282.64231) (xy 3.824384 -282.659961)
			(xy 3.778408 -282.689671) (xy 3.728658 -282.712504) (xy 3.676155 -282.727993) (xy 3.621978 -282.735818)
			(xy 3.594608 -282.73629) (xy 3.564484 -282.735731) (xy 3.504986 -282.72625) (xy 3.447717 -282.707537)
			(xy 3.394101 -282.680058) (xy 3.345468 -282.644495) (xy 3.323844 -282.623514) (xy 3.316732 -282.616148)
			(xy 3.297936 -282.608528) (xy 3.20548 -282.608528) (xy 3.186684 -282.616148) (xy 3.179572 -282.623514)
			(xy 3.157941 -282.644487) (xy 3.109313 -282.680056) (xy 3.055699 -282.707537) (xy 2.99843 -282.726247)
			(xy 2.938932 -282.73572) (xy 2.908808 -282.73629) (xy 2.880069 -282.735764) (xy 2.823242 -282.727142)
			(xy 2.768351 -282.710093) (xy 2.716639 -282.685002) (xy 2.669277 -282.652437) (xy 2.64795 -282.633166)
			(xy 2.640838 -282.626562) (xy 2.623312 -282.61945) (xy 2.533904 -282.61945) (xy 2.516378 -282.626562)
			(xy 2.509266 -282.633166) (xy 2.487936 -282.652434) (xy 2.440575 -282.685) (xy 2.388864 -282.710093)
			(xy 2.333974 -282.727145) (xy 2.277147 -282.735768) (xy 2.248408 -282.73629) (xy 2.221157 -282.7358)
			(xy 2.16721 -282.728043) (xy 2.114916 -282.712688) (xy 2.065339 -282.690047) (xy 2.019489 -282.660581)
			(xy 1.978299 -282.624889) (xy 1.942608 -282.5837) (xy 1.913142 -282.537849) (xy 1.890501 -282.488273)
			(xy 1.875146 -282.435978) (xy 1.86739 -282.382031) (xy 1.468374 -282.382031) (xy 1.468374 -283.186451)
			(xy 9.692378 -283.186451) (xy 9.692378 -283.131949) (xy 9.700134 -283.078003) (xy 9.715488 -283.025709)
			(xy 9.738128 -282.976133) (xy 9.767593 -282.930283) (xy 9.803283 -282.889093) (xy 9.844472 -282.853402)
			(xy 9.890321 -282.823935) (xy 9.939896 -282.801293) (xy 9.992189 -282.785937) (xy 10.046135 -282.778179)
			(xy 10.073386 -282.777692) (xy 10.102124 -282.778226) (xy 10.158951 -282.786847) (xy 10.213842 -282.803894)
			(xy 10.265554 -282.828984) (xy 10.312917 -282.861546) (xy 10.334244 -282.880816) (xy 10.341356 -282.88742)
			(xy 10.358882 -282.894532) (xy 10.44829 -282.894532) (xy 10.465816 -282.88742) (xy 10.472928 -282.880816)
			(xy 10.494255 -282.861546) (xy 10.541618 -282.828981) (xy 10.593329 -282.80389) (xy 10.64822 -282.78684)
			(xy 10.705047 -282.778218) (xy 10.762525 -282.778218) (xy 10.819352 -282.78684) (xy 10.874243 -282.80389)
			(xy 10.925954 -282.828981) (xy 10.973317 -282.861546) (xy 10.994644 -282.880816) (xy 11.001756 -282.88742)
			(xy 11.019282 -282.894532) (xy 11.10869 -282.894532) (xy 11.126216 -282.88742) (xy 11.133328 -282.880816)
			(xy 11.154658 -282.861548) (xy 11.202019 -282.828982) (xy 11.25373 -282.80389) (xy 11.30862 -282.786838)
			(xy 11.365447 -282.778214) (xy 11.394186 -282.777692) (xy 11.42431 -282.77826) (xy 11.483807 -282.78774)
			(xy 11.541075 -282.806451) (xy 11.594692 -282.833928) (xy 11.643326 -282.869488) (xy 11.66495 -282.890468)
			(xy 11.672062 -282.897834) (xy 11.690858 -282.905454) (xy 11.783314 -282.905454) (xy 11.80211 -282.897834)
			(xy 11.809222 -282.890468) (xy 11.83087 -282.869512) (xy 11.879491 -282.833938) (xy 11.933102 -282.806452)
			(xy 11.990367 -282.787739) (xy 12.049863 -282.778263) (xy 12.079986 -282.777692) (xy 12.10724 -282.778154)
			(xy 12.161192 -282.78591) (xy 12.213491 -282.801265) (xy 12.263073 -282.823906) (xy 12.308928 -282.853374)
			(xy 12.350123 -282.889068) (xy 12.385818 -282.930261) (xy 12.415287 -282.976114) (xy 12.437931 -283.025695)
			(xy 12.453287 -283.077994) (xy 12.461045 -283.131947) (xy 12.461045 -283.18645) (xy 13.965178 -283.18645)
			(xy 13.965178 -283.13195) (xy 13.972934 -283.078004) (xy 13.988287 -283.025712) (xy 14.010927 -282.976136)
			(xy 14.04039 -282.930287) (xy 14.076079 -282.889098) (xy 14.117266 -282.853406) (xy 14.163113 -282.823939)
			(xy 14.212687 -282.801296) (xy 14.264979 -282.785939) (xy 14.318924 -282.77818) (xy 14.346174 -282.777692)
			(xy 14.374912 -282.778234) (xy 14.431739 -282.786852) (xy 14.486629 -282.803898) (xy 14.538341 -282.828986)
			(xy 14.585705 -282.861547) (xy 14.607032 -282.880816) (xy 14.614144 -282.88742) (xy 14.63167 -282.894532)
			(xy 14.721078 -282.894532) (xy 14.738604 -282.88742) (xy 14.745716 -282.880816) (xy 14.767043 -282.861546)
			(xy 14.814406 -282.828981) (xy 14.866117 -282.80389) (xy 14.921008 -282.78684) (xy 14.977835 -282.778218)
			(xy 15.035313 -282.778218) (xy 15.09214 -282.78684) (xy 15.147031 -282.80389) (xy 15.198742 -282.828981)
			(xy 15.246105 -282.861546) (xy 15.267432 -282.880816) (xy 15.274544 -282.88742) (xy 15.29207 -282.894532)
			(xy 15.381478 -282.894532) (xy 15.399004 -282.88742) (xy 15.406116 -282.880816) (xy 15.42745 -282.861554)
			(xy 15.474811 -282.828987) (xy 15.526521 -282.803894) (xy 15.58141 -282.786841) (xy 15.638236 -282.778215)
			(xy 15.666974 -282.777692) (xy 15.697097 -282.778267) (xy 15.756594 -282.787745) (xy 15.813862 -282.806455)
			(xy 15.86748 -282.83393) (xy 15.916113 -282.869489) (xy 15.937738 -282.890468) (xy 15.94485 -282.897834)
			(xy 15.963646 -282.905454) (xy 16.056102 -282.905454) (xy 16.074898 -282.897834) (xy 16.08201 -282.890468)
			(xy 16.103619 -282.86947) (xy 16.152251 -282.833901) (xy 16.205871 -282.806423) (xy 16.263145 -282.78772)
			(xy 16.322648 -282.778256) (xy 16.352774 -282.777692) (xy 16.380028 -282.778154) (xy 16.433982 -282.785908)
			(xy 16.486283 -282.801261) (xy 16.535866 -282.823902) (xy 16.581723 -282.85337) (xy 16.622918 -282.889063)
			(xy 16.658615 -282.930257) (xy 16.688085 -282.976111) (xy 16.71073 -283.025693) (xy 16.726087 -283.077993)
			(xy 16.733783 -283.131514) (xy 25.811478 -283.131514) (xy 25.815549 -283.075892) (xy 25.827675 -283.021455)
			(xy 25.847598 -282.969364) (xy 25.874894 -282.920729) (xy 25.90898 -282.876586) (xy 25.949129 -282.837877)
			(xy 25.994487 -282.805426) (xy 26.044087 -282.779925) (xy 26.096871 -282.761918) (xy 26.151714 -282.751788)
			(xy 26.207448 -282.749751) (xy 26.262885 -282.755851) (xy 26.316842 -282.769957) (xy 26.368171 -282.791769)
			(xy 26.415777 -282.820823) (xy 26.458645 -282.856498) (xy 26.495862 -282.898035) (xy 26.526635 -282.944548)
			(xy 26.550307 -282.995045) (xy 26.566375 -283.048452) (xy 26.574495 -283.103628) (xy 26.575004 -283.131514)
			(xy 27.286964 -283.131514) (xy 27.291035 -283.075892) (xy 27.303161 -283.021455) (xy 27.323084 -282.969364)
			(xy 27.35038 -282.920729) (xy 27.384466 -282.876586) (xy 27.424615 -282.837877) (xy 27.469973 -282.805426)
			(xy 27.519573 -282.779925) (xy 27.572357 -282.761918) (xy 27.6272 -282.751788) (xy 27.682934 -282.749751)
			(xy 27.738371 -282.755851) (xy 27.792328 -282.769957) (xy 27.843657 -282.791769) (xy 27.891263 -282.820823)
			(xy 27.934131 -282.856498) (xy 27.971348 -282.898035) (xy 28.002121 -282.944548) (xy 28.025793 -282.995045)
			(xy 28.041861 -283.048452) (xy 28.049981 -283.103628) (xy 28.05049 -283.131514) (xy 28.175964 -283.131514)
			(xy 28.180035 -283.075892) (xy 28.192161 -283.021455) (xy 28.212084 -282.969364) (xy 28.23938 -282.920729)
			(xy 28.273466 -282.876586) (xy 28.313615 -282.837877) (xy 28.358973 -282.805426) (xy 28.408573 -282.779925)
			(xy 28.461357 -282.761918) (xy 28.5162 -282.751788) (xy 28.571934 -282.749751) (xy 28.627371 -282.755851)
			(xy 28.681328 -282.769957) (xy 28.732657 -282.791769) (xy 28.780263 -282.820823) (xy 28.823131 -282.856498)
			(xy 28.860348 -282.898035) (xy 28.891121 -282.944548) (xy 28.914793 -282.995045) (xy 28.930861 -283.048452)
			(xy 28.938981 -283.103628) (xy 28.93949 -283.131514) (xy 28.938981 -283.1594) (xy 28.930861 -283.214576)
			(xy 28.914793 -283.267983) (xy 28.891121 -283.31848) (xy 28.860348 -283.364993) (xy 28.823131 -283.40653)
			(xy 28.780263 -283.442205) (xy 28.732657 -283.471259) (xy 28.681328 -283.493071) (xy 28.627371 -283.507177)
			(xy 28.571934 -283.513277) (xy 28.5162 -283.51124) (xy 28.461357 -283.50111) (xy 28.408573 -283.483103)
			(xy 28.358973 -283.457602) (xy 28.313615 -283.425151) (xy 28.273466 -283.386442) (xy 28.23938 -283.342299)
			(xy 28.212084 -283.293664) (xy 28.192161 -283.241573) (xy 28.180035 -283.187136) (xy 28.175964 -283.131514)
			(xy 28.05049 -283.131514) (xy 28.049981 -283.1594) (xy 28.041861 -283.214576) (xy 28.025793 -283.267983)
			(xy 28.002121 -283.31848) (xy 27.971348 -283.364993) (xy 27.934131 -283.40653) (xy 27.891263 -283.442205)
			(xy 27.843657 -283.471259) (xy 27.792328 -283.493071) (xy 27.738371 -283.507177) (xy 27.682934 -283.513277)
			(xy 27.6272 -283.51124) (xy 27.572357 -283.50111) (xy 27.519573 -283.483103) (xy 27.469973 -283.457602)
			(xy 27.424615 -283.425151) (xy 27.384466 -283.386442) (xy 27.35038 -283.342299) (xy 27.323084 -283.293664)
			(xy 27.303161 -283.241573) (xy 27.291035 -283.187136) (xy 27.286964 -283.131514) (xy 26.575004 -283.131514)
			(xy 26.574495 -283.1594) (xy 26.566375 -283.214576) (xy 26.550307 -283.267983) (xy 26.526635 -283.31848)
			(xy 26.495862 -283.364993) (xy 26.458645 -283.40653) (xy 26.415777 -283.442205) (xy 26.368171 -283.471259)
			(xy 26.316842 -283.493071) (xy 26.262885 -283.507177) (xy 26.207448 -283.513277) (xy 26.151714 -283.51124)
			(xy 26.096871 -283.50111) (xy 26.044087 -283.483103) (xy 25.994487 -283.457602) (xy 25.949129 -283.425151)
			(xy 25.90898 -283.386442) (xy 25.874894 -283.342299) (xy 25.847598 -283.293664) (xy 25.827675 -283.241573)
			(xy 25.815549 -283.187136) (xy 25.811478 -283.131514) (xy 16.733783 -283.131514) (xy 16.733845 -283.131946)
			(xy 16.733845 -283.186454) (xy 16.726087 -283.240407) (xy 16.71073 -283.292707) (xy 16.688085 -283.342289)
			(xy 16.658615 -283.388143) (xy 16.622918 -283.429337) (xy 16.581723 -283.46503) (xy 16.535866 -283.494498)
			(xy 16.486283 -283.517139) (xy 16.433982 -283.532492) (xy 16.380028 -283.540246) (xy 16.352774 -283.540708)
			(xy 16.322649 -283.540166) (xy 16.263151 -283.53068) (xy 16.205882 -283.511963) (xy 16.152266 -283.48448)
			(xy 16.103633 -283.448915) (xy 16.08201 -283.427932) (xy 16.074898 -283.420566) (xy 16.056102 -283.412946)
			(xy 15.963646 -283.412946) (xy 15.94485 -283.420566) (xy 15.937738 -283.427932) (xy 15.916108 -283.448907)
			(xy 15.867482 -283.484478) (xy 15.813867 -283.511961) (xy 15.756597 -283.53067) (xy 15.697098 -283.54014)
			(xy 15.666974 -283.540708) (xy 15.638235 -283.540198) (xy 15.581407 -283.531572) (xy 15.526516 -283.514518)
			(xy 15.474804 -283.489424) (xy 15.427442 -283.456856) (xy 15.406116 -283.437584) (xy 15.399004 -283.43098)
			(xy 15.381478 -283.423868) (xy 15.29207 -283.423868) (xy 15.274544 -283.43098) (xy 15.267432 -283.437584)
			(xy 15.246105 -283.456854) (xy 15.198742 -283.489419) (xy 15.147031 -283.51451) (xy 15.09214 -283.53156)
			(xy 15.035313 -283.540182) (xy 14.977835 -283.540182) (xy 14.921008 -283.53156) (xy 14.866117 -283.51451)
			(xy 14.814406 -283.489419) (xy 14.767043 -283.456854) (xy 14.745716 -283.437584) (xy 14.738604 -283.43098)
			(xy 14.721078 -283.423868) (xy 14.63167 -283.423868) (xy 14.614144 -283.43098) (xy 14.607032 -283.437584)
			(xy 14.585719 -283.456871) (xy 14.538353 -283.489434) (xy 14.486637 -283.514523) (xy 14.431744 -283.53157)
			(xy 14.374914 -283.540189) (xy 14.346174 -283.540708) (xy 14.318924 -283.54022) (xy 14.264979 -283.532461)
			(xy 14.212687 -283.517104) (xy 14.163113 -283.494461) (xy 14.117266 -283.464994) (xy 14.076079 -283.429302)
			(xy 14.04039 -283.388113) (xy 14.010927 -283.342264) (xy 13.988287 -283.292688) (xy 13.972934 -283.240396)
			(xy 13.965178 -283.18645) (xy 12.461045 -283.18645) (xy 12.461045 -283.186453) (xy 12.453287 -283.240406)
			(xy 12.437931 -283.292705) (xy 12.415287 -283.342286) (xy 12.385818 -283.388139) (xy 12.350123 -283.429332)
			(xy 12.308928 -283.465026) (xy 12.263073 -283.494494) (xy 12.213491 -283.517135) (xy 12.161192 -283.53249)
			(xy 12.10724 -283.540246) (xy 12.079986 -283.540708) (xy 12.049862 -283.540158) (xy 11.990364 -283.530674)
			(xy 11.933095 -283.511959) (xy 11.879478 -283.484478) (xy 11.830845 -283.448914) (xy 11.809222 -283.427932)
			(xy 11.80211 -283.420566) (xy 11.783314 -283.412946) (xy 11.690858 -283.412946) (xy 11.672062 -283.420566)
			(xy 11.66495 -283.427932) (xy 11.643315 -283.448901) (xy 11.59469 -283.484473) (xy 11.541076 -283.511957)
			(xy 11.483808 -283.530667) (xy 11.42431 -283.540139) (xy 11.394186 -283.540708) (xy 11.365447 -283.540191)
			(xy 11.308619 -283.531566) (xy 11.253729 -283.514515) (xy 11.202017 -283.489422) (xy 11.154655 -283.456855)
			(xy 11.133328 -283.437584) (xy 11.126216 -283.43098) (xy 11.10869 -283.423868) (xy 11.019282 -283.423868)
			(xy 11.001756 -283.43098) (xy 10.994644 -283.437584) (xy 10.973317 -283.456854) (xy 10.925954 -283.489419)
			(xy 10.874243 -283.51451) (xy 10.819352 -283.53156) (xy 10.762525 -283.540182) (xy 10.705047 -283.540182)
			(xy 10.64822 -283.53156) (xy 10.593329 -283.51451) (xy 10.541618 -283.489419) (xy 10.494255 -283.456854)
			(xy 10.472928 -283.437584) (xy 10.465816 -283.43098) (xy 10.44829 -283.423868) (xy 10.358882 -283.423868)
			(xy 10.341356 -283.43098) (xy 10.334244 -283.437584) (xy 10.312926 -283.456865) (xy 10.265561 -283.489429)
			(xy 10.213847 -283.514519) (xy 10.158955 -283.531567) (xy 10.102126 -283.540188) (xy 10.073386 -283.540708)
			(xy 10.046135 -283.540221) (xy 9.992189 -283.532463) (xy 9.939896 -283.517107) (xy 9.890321 -283.494465)
			(xy 9.844472 -283.464998) (xy 9.803283 -283.429307) (xy 9.767593 -283.388117) (xy 9.738128 -283.342267)
			(xy 9.715488 -283.292691) (xy 9.700134 -283.240397) (xy 9.692378 -283.186451) (xy 1.468374 -283.186451)
			(xy 1.468374 -283.893514) (xy 31.338012 -283.893514) (xy 31.338555 -283.864132) (xy 31.347584 -283.806065)
			(xy 31.365415 -283.75007) (xy 31.391626 -283.697475) (xy 31.425597 -283.649524) (xy 31.466521 -283.607352)
			(xy 31.48965 -283.589222) (xy 31.499048 -283.581856) (xy 31.509462 -283.561282) (xy 31.510986 -283.457396)
			(xy 31.50108 -283.436314) (xy 31.491936 -283.428948) (xy 31.470088 -283.410742) (xy 31.431546 -283.368924)
			(xy 31.399638 -283.321849) (xy 31.375071 -283.270559) (xy 31.358388 -283.216191) (xy 31.34996 -283.159949)
			(xy 31.349442 -283.131514) (xy 31.349928 -283.104263) (xy 31.357684 -283.050315) (xy 31.373039 -282.99802)
			(xy 31.395681 -282.948443) (xy 31.425147 -282.902593) (xy 31.460838 -282.861402) (xy 31.502029 -282.825711)
			(xy 31.547879 -282.796245) (xy 31.597456 -282.773603) (xy 31.649751 -282.758248) (xy 31.703699 -282.750492)
			(xy 31.758201 -282.750492) (xy 31.812149 -282.758248) (xy 31.864444 -282.773603) (xy 31.914021 -282.796245)
			(xy 31.959871 -282.825711) (xy 32.001062 -282.861402) (xy 32.036753 -282.902593) (xy 32.066219 -282.948443)
			(xy 32.088861 -282.99802) (xy 32.104216 -283.050315) (xy 32.107747 -283.074872) (xy 36.069028 -283.074872)
			(xy 36.072988 -283.025818) (xy 36.084765 -282.978034) (xy 36.104056 -282.932758) (xy 36.130359 -282.891162)
			(xy 36.162994 -282.854325) (xy 36.201115 -282.8232) (xy 36.243736 -282.798593) (xy 36.289752 -282.781141)
			(xy 36.337971 -282.771297) (xy 36.387146 -282.769316) (xy 36.436001 -282.775248) (xy 36.483272 -282.78894)
			(xy 36.527734 -282.810038) (xy 36.568237 -282.837994) (xy 36.60373 -282.872086) (xy 36.633295 -282.91143)
			(xy 36.656166 -282.955007) (xy 36.67175 -283.001688) (xy 36.679645 -283.050265) (xy 36.68014 -283.074872)
			(xy 37.018988 -283.074872) (xy 37.022948 -283.025818) (xy 37.034725 -282.978034) (xy 37.054016 -282.932758)
			(xy 37.080319 -282.891162) (xy 37.112954 -282.854325) (xy 37.151075 -282.8232) (xy 37.193696 -282.798593)
			(xy 37.239712 -282.781141) (xy 37.287931 -282.771297) (xy 37.337106 -282.769316) (xy 37.385961 -282.775248)
			(xy 37.433232 -282.78894) (xy 37.477694 -282.810038) (xy 37.518197 -282.837994) (xy 37.55369 -282.872086)
			(xy 37.583255 -282.91143) (xy 37.606126 -282.955007) (xy 37.62171 -283.001688) (xy 37.629605 -283.050265)
			(xy 37.6301 -283.074872) (xy 37.969202 -283.074872) (xy 37.973162 -283.025818) (xy 37.984939 -282.978034)
			(xy 38.00423 -282.932758) (xy 38.030533 -282.891162) (xy 38.063168 -282.854325) (xy 38.101289 -282.8232)
			(xy 38.14391 -282.798593) (xy 38.189926 -282.781141) (xy 38.238145 -282.771297) (xy 38.28732 -282.769316)
			(xy 38.336175 -282.775248) (xy 38.383446 -282.78894) (xy 38.427908 -282.810038) (xy 38.468411 -282.837994)
			(xy 38.503904 -282.872086) (xy 38.533469 -282.91143) (xy 38.55634 -282.955007) (xy 38.571924 -283.001688)
			(xy 38.579819 -283.050265) (xy 38.580314 -283.074872) (xy 38.919162 -283.074872) (xy 38.923122 -283.025818)
			(xy 38.934899 -282.978034) (xy 38.95419 -282.932758) (xy 38.980493 -282.891162) (xy 39.013128 -282.854325)
			(xy 39.051249 -282.8232) (xy 39.09387 -282.798593) (xy 39.139886 -282.781141) (xy 39.188105 -282.771297)
			(xy 39.23728 -282.769316) (xy 39.286135 -282.775248) (xy 39.333406 -282.78894) (xy 39.377868 -282.810038)
			(xy 39.418371 -282.837994) (xy 39.453864 -282.872086) (xy 39.483429 -282.91143) (xy 39.5063 -282.955007)
			(xy 39.521884 -283.001688) (xy 39.529779 -283.050265) (xy 39.530274 -283.074872) (xy 39.869122 -283.074872)
			(xy 39.873082 -283.025818) (xy 39.884859 -282.978034) (xy 39.90415 -282.932758) (xy 39.930453 -282.891162)
			(xy 39.963088 -282.854325) (xy 40.001209 -282.8232) (xy 40.04383 -282.798593) (xy 40.089846 -282.781141)
			(xy 40.138065 -282.771297) (xy 40.18724 -282.769316) (xy 40.236095 -282.775248) (xy 40.283366 -282.78894)
			(xy 40.327828 -282.810038) (xy 40.368331 -282.837994) (xy 40.403824 -282.872086) (xy 40.433389 -282.91143)
			(xy 40.45626 -282.955007) (xy 40.471844 -283.001688) (xy 40.479739 -283.050265) (xy 40.480234 -283.074872)
			(xy 40.819082 -283.074872) (xy 40.823042 -283.025818) (xy 40.834819 -282.978034) (xy 40.85411 -282.932758)
			(xy 40.880413 -282.891162) (xy 40.913048 -282.854325) (xy 40.951169 -282.8232) (xy 40.99379 -282.798593)
			(xy 41.039806 -282.781141) (xy 41.088025 -282.771297) (xy 41.1372 -282.769316) (xy 41.186055 -282.775248)
			(xy 41.233326 -282.78894) (xy 41.277788 -282.810038) (xy 41.318291 -282.837994) (xy 41.353784 -282.872086)
			(xy 41.383349 -282.91143) (xy 41.40622 -282.955007) (xy 41.421804 -283.001688) (xy 41.429699 -283.050265)
			(xy 41.430194 -283.074872) (xy 41.769042 -283.074872) (xy 41.773002 -283.025818) (xy 41.784779 -282.978034)
			(xy 41.80407 -282.932758) (xy 41.830373 -282.891162) (xy 41.863008 -282.854325) (xy 41.901129 -282.8232)
			(xy 41.94375 -282.798593) (xy 41.989766 -282.781141) (xy 42.037985 -282.771297) (xy 42.08716 -282.769316)
			(xy 42.136015 -282.775248) (xy 42.183286 -282.78894) (xy 42.227748 -282.810038) (xy 42.268251 -282.837994)
			(xy 42.303744 -282.872086) (xy 42.333309 -282.91143) (xy 42.35618 -282.955007) (xy 42.371764 -283.001688)
			(xy 42.379659 -283.050265) (xy 42.379988 -283.06664) (xy 44.619253 -283.06664) (xy 44.624617 -283.017284)
			(xy 44.637895 -282.969446) (xy 44.658738 -282.924387) (xy 44.686596 -282.883293) (xy 44.720735 -282.847248)
			(xy 44.760256 -282.8172) (xy 44.804118 -282.793942) (xy 44.851165 -282.778087) (xy 44.900157 -282.770052)
			(xy 44.92498 -282.769564) (xy 44.939163 -282.769744) (xy 44.967403 -282.772414) (xy 44.981368 -282.774898)
			(xy 44.993814 -282.777184) (xy 45.017436 -282.769818) (xy 45.094906 -282.692348) (xy 45.102272 -282.668726)
			(xy 45.099986 -282.65628) (xy 45.097511 -282.642314) (xy 45.094838 -282.614074) (xy 45.094652 -282.599892)
			(xy 45.095174 -282.574637) (xy 45.103487 -282.524815) (xy 45.119888 -282.477041) (xy 45.143929 -282.432618)
			(xy 45.174953 -282.392758) (xy 45.212115 -282.358548) (xy 45.254401 -282.330922) (xy 45.300657 -282.310632)
			(xy 45.349622 -282.298232) (xy 45.39996 -282.294061) (xy 45.450298 -282.298232) (xy 45.499263 -282.310632)
			(xy 45.545519 -282.330922) (xy 45.587805 -282.358548) (xy 45.624967 -282.392758) (xy 45.655991 -282.432618)
			(xy 45.680032 -282.477041) (xy 45.696433 -282.524815) (xy 45.704746 -282.574637) (xy 45.705268 -282.599892)
			(xy 45.705091 -282.614075) (xy 45.702419 -282.642315) (xy 45.699934 -282.65628) (xy 45.697648 -282.668726)
			(xy 45.705014 -282.692348) (xy 45.782484 -282.769818) (xy 45.806106 -282.777184) (xy 45.818552 -282.774898)
			(xy 45.832517 -282.772418) (xy 45.860757 -282.769749) (xy 45.87494 -282.769564) (xy 45.889123 -282.769736)
			(xy 45.917363 -282.772411) (xy 45.931328 -282.774898) (xy 45.943774 -282.777184) (xy 45.967396 -282.769818)
			(xy 46.044866 -282.692348) (xy 46.052232 -282.668726) (xy 46.049946 -282.65628) (xy 46.047471 -282.642314)
			(xy 46.044798 -282.614074) (xy 46.044612 -282.599892) (xy 46.045134 -282.574637) (xy 46.053447 -282.524815)
			(xy 46.069848 -282.477041) (xy 46.093889 -282.432618) (xy 46.124913 -282.392758) (xy 46.162075 -282.358548)
			(xy 46.204361 -282.330922) (xy 46.250617 -282.310632) (xy 46.299582 -282.298232) (xy 46.34992 -282.294061)
			(xy 46.400258 -282.298232) (xy 46.449223 -282.310632) (xy 46.495479 -282.330922) (xy 46.537765 -282.358548)
			(xy 46.574927 -282.392758) (xy 46.605951 -282.432618) (xy 46.629992 -282.477041) (xy 46.646393 -282.524815)
			(xy 46.654706 -282.574637) (xy 46.655228 -282.599892) (xy 46.65505 -282.614075) (xy 46.652379 -282.642315)
			(xy 46.649894 -282.65628) (xy 46.647608 -282.668726) (xy 46.654974 -282.692348) (xy 46.732444 -282.769818)
			(xy 46.756066 -282.777184) (xy 46.768512 -282.774898) (xy 46.782478 -282.772424) (xy 46.810718 -282.769751)
			(xy 46.8249 -282.769564) (xy 46.849721 -282.770078) (xy 46.89871 -282.778109) (xy 46.945754 -282.793961)
			(xy 46.989614 -282.817214) (xy 47.029133 -282.847257) (xy 47.063272 -282.883298) (xy 47.09113 -282.924387)
			(xy 47.111974 -282.969442) (xy 47.125253 -283.017276) (xy 47.130619 -283.066627) (xy 47.130172 -283.074872)
			(xy 47.469056 -283.074872) (xy 47.473016 -283.025818) (xy 47.484793 -282.978034) (xy 47.504084 -282.932758)
			(xy 47.530387 -282.891162) (xy 47.563022 -282.854325) (xy 47.601143 -282.8232) (xy 47.643764 -282.798593)
			(xy 47.68978 -282.781141) (xy 47.737999 -282.771297) (xy 47.787174 -282.769316) (xy 47.836029 -282.775248)
			(xy 47.8833 -282.78894) (xy 47.927762 -282.810038) (xy 47.968265 -282.837994) (xy 48.003758 -282.872086)
			(xy 48.033323 -282.91143) (xy 48.056194 -282.955007) (xy 48.071778 -283.001688) (xy 48.079673 -283.050265)
			(xy 48.080168 -283.074872) (xy 48.419016 -283.074872) (xy 48.422976 -283.025818) (xy 48.434753 -282.978034)
			(xy 48.454044 -282.932758) (xy 48.480347 -282.891162) (xy 48.512982 -282.854325) (xy 48.551103 -282.8232)
			(xy 48.593724 -282.798593) (xy 48.63974 -282.781141) (xy 48.687959 -282.771297) (xy 48.737134 -282.769316)
			(xy 48.785989 -282.775248) (xy 48.83326 -282.78894) (xy 48.877722 -282.810038) (xy 48.918225 -282.837994)
			(xy 48.953718 -282.872086) (xy 48.983283 -282.91143) (xy 49.006154 -282.955007) (xy 49.021738 -283.001688)
			(xy 49.029633 -283.050265) (xy 49.030128 -283.074872) (xy 49.368976 -283.074872) (xy 49.372936 -283.025818)
			(xy 49.384713 -282.978034) (xy 49.404004 -282.932758) (xy 49.430307 -282.891162) (xy 49.462942 -282.854325)
			(xy 49.501063 -282.8232) (xy 49.543684 -282.798593) (xy 49.5897 -282.781141) (xy 49.637919 -282.771297)
			(xy 49.687094 -282.769316) (xy 49.735949 -282.775248) (xy 49.78322 -282.78894) (xy 49.827682 -282.810038)
			(xy 49.868185 -282.837994) (xy 49.903678 -282.872086) (xy 49.933243 -282.91143) (xy 49.956114 -282.955007)
			(xy 49.971698 -283.001688) (xy 49.979593 -283.050265) (xy 49.980088 -283.074872) (xy 50.31919 -283.074872)
			(xy 50.32315 -283.025818) (xy 50.334927 -282.978034) (xy 50.354218 -282.932758) (xy 50.380521 -282.891162)
			(xy 50.413156 -282.854325) (xy 50.451277 -282.8232) (xy 50.493898 -282.798593) (xy 50.539914 -282.781141)
			(xy 50.588133 -282.771297) (xy 50.637308 -282.769316) (xy 50.686163 -282.775248) (xy 50.733434 -282.78894)
			(xy 50.777896 -282.810038) (xy 50.818399 -282.837994) (xy 50.853892 -282.872086) (xy 50.883457 -282.91143)
			(xy 50.906328 -282.955007) (xy 50.921912 -283.001688) (xy 50.929807 -283.050265) (xy 50.930302 -283.074872)
			(xy 51.26915 -283.074872) (xy 51.27311 -283.025818) (xy 51.284887 -282.978034) (xy 51.304178 -282.932758)
			(xy 51.330481 -282.891162) (xy 51.363116 -282.854325) (xy 51.401237 -282.8232) (xy 51.443858 -282.798593)
			(xy 51.489874 -282.781141) (xy 51.538093 -282.771297) (xy 51.587268 -282.769316) (xy 51.636123 -282.775248)
			(xy 51.683394 -282.78894) (xy 51.727856 -282.810038) (xy 51.768359 -282.837994) (xy 51.803852 -282.872086)
			(xy 51.833417 -282.91143) (xy 51.856288 -282.955007) (xy 51.871872 -283.001688) (xy 51.879767 -283.050265)
			(xy 51.880262 -283.074872) (xy 52.21911 -283.074872) (xy 52.22307 -283.025818) (xy 52.234847 -282.978034)
			(xy 52.254138 -282.932758) (xy 52.280441 -282.891162) (xy 52.313076 -282.854325) (xy 52.351197 -282.8232)
			(xy 52.393818 -282.798593) (xy 52.439834 -282.781141) (xy 52.488053 -282.771297) (xy 52.537228 -282.769316)
			(xy 52.586083 -282.775248) (xy 52.633354 -282.78894) (xy 52.677816 -282.810038) (xy 52.718319 -282.837994)
			(xy 52.753812 -282.872086) (xy 52.783377 -282.91143) (xy 52.806248 -282.955007) (xy 52.821832 -283.001688)
			(xy 52.829727 -283.050265) (xy 52.830222 -283.074872) (xy 53.16907 -283.074872) (xy 53.17303 -283.025818)
			(xy 53.184807 -282.978034) (xy 53.204098 -282.932758) (xy 53.230401 -282.891162) (xy 53.263036 -282.854325)
			(xy 53.301157 -282.8232) (xy 53.343778 -282.798593) (xy 53.389794 -282.781141) (xy 53.438013 -282.771297)
			(xy 53.487188 -282.769316) (xy 53.536043 -282.775248) (xy 53.583314 -282.78894) (xy 53.627776 -282.810038)
			(xy 53.668279 -282.837994) (xy 53.703772 -282.872086) (xy 53.733337 -282.91143) (xy 53.756208 -282.955007)
			(xy 53.771792 -283.001688) (xy 53.779687 -283.050265) (xy 53.780182 -283.074872) (xy 54.11903 -283.074872)
			(xy 54.12299 -283.025818) (xy 54.134767 -282.978034) (xy 54.154058 -282.932758) (xy 54.180361 -282.891162)
			(xy 54.212996 -282.854325) (xy 54.251117 -282.8232) (xy 54.293738 -282.798593) (xy 54.339754 -282.781141)
			(xy 54.387973 -282.771297) (xy 54.437148 -282.769316) (xy 54.486003 -282.775248) (xy 54.533274 -282.78894)
			(xy 54.577736 -282.810038) (xy 54.618239 -282.837994) (xy 54.653732 -282.872086) (xy 54.683297 -282.91143)
			(xy 54.706168 -282.955007) (xy 54.721752 -283.001688) (xy 54.729647 -283.050265) (xy 54.730142 -283.074872)
			(xy 55.06899 -283.074872) (xy 55.07295 -283.025818) (xy 55.084727 -282.978034) (xy 55.104018 -282.932758)
			(xy 55.130321 -282.891162) (xy 55.162956 -282.854325) (xy 55.201077 -282.8232) (xy 55.243698 -282.798593)
			(xy 55.289714 -282.781141) (xy 55.337933 -282.771297) (xy 55.387108 -282.769316) (xy 55.435963 -282.775248)
			(xy 55.483234 -282.78894) (xy 55.527696 -282.810038) (xy 55.568199 -282.837994) (xy 55.603692 -282.872086)
			(xy 55.633257 -282.91143) (xy 55.656128 -282.955007) (xy 55.671712 -283.001688) (xy 55.679607 -283.050265)
			(xy 55.680102 -283.074872) (xy 56.019204 -283.074872) (xy 56.023164 -283.025818) (xy 56.034941 -282.978034)
			(xy 56.054232 -282.932758) (xy 56.080535 -282.891162) (xy 56.11317 -282.854325) (xy 56.151291 -282.8232)
			(xy 56.193912 -282.798593) (xy 56.239928 -282.781141) (xy 56.288147 -282.771297) (xy 56.337322 -282.769316)
			(xy 56.386177 -282.775248) (xy 56.433448 -282.78894) (xy 56.47791 -282.810038) (xy 56.518413 -282.837994)
			(xy 56.553906 -282.872086) (xy 56.583471 -282.91143) (xy 56.606342 -282.955007) (xy 56.621926 -283.001688)
			(xy 56.629821 -283.050265) (xy 56.630316 -283.074872) (xy 56.969164 -283.074872) (xy 56.973124 -283.025818)
			(xy 56.984901 -282.978034) (xy 57.004192 -282.932758) (xy 57.030495 -282.891162) (xy 57.06313 -282.854325)
			(xy 57.101251 -282.8232) (xy 57.143872 -282.798593) (xy 57.189888 -282.781141) (xy 57.238107 -282.771297)
			(xy 57.287282 -282.769316) (xy 57.336137 -282.775248) (xy 57.383408 -282.78894) (xy 57.42787 -282.810038)
			(xy 57.468373 -282.837994) (xy 57.503866 -282.872086) (xy 57.533431 -282.91143) (xy 57.556302 -282.955007)
			(xy 57.571886 -283.001688) (xy 57.579781 -283.050265) (xy 57.580276 -283.074872) (xy 57.919124 -283.074872)
			(xy 57.923084 -283.025818) (xy 57.934861 -282.978034) (xy 57.954152 -282.932758) (xy 57.980455 -282.891162)
			(xy 58.01309 -282.854325) (xy 58.051211 -282.8232) (xy 58.093832 -282.798593) (xy 58.139848 -282.781141)
			(xy 58.188067 -282.771297) (xy 58.237242 -282.769316) (xy 58.286097 -282.775248) (xy 58.333368 -282.78894)
			(xy 58.37783 -282.810038) (xy 58.418333 -282.837994) (xy 58.453826 -282.872086) (xy 58.483391 -282.91143)
			(xy 58.506262 -282.955007) (xy 58.521846 -283.001688) (xy 58.529741 -283.050265) (xy 58.530236 -283.074872)
			(xy 59.819044 -283.074872) (xy 59.823004 -283.025818) (xy 59.834781 -282.978034) (xy 59.854072 -282.932758)
			(xy 59.880375 -282.891162) (xy 59.91301 -282.854325) (xy 59.951131 -282.8232) (xy 59.993752 -282.798593)
			(xy 60.039768 -282.781141) (xy 60.087987 -282.771297) (xy 60.137162 -282.769316) (xy 60.186017 -282.775248)
			(xy 60.233288 -282.78894) (xy 60.27775 -282.810038) (xy 60.318253 -282.837994) (xy 60.353746 -282.872086)
			(xy 60.383311 -282.91143) (xy 60.406182 -282.955007) (xy 60.421766 -283.001688) (xy 60.429661 -283.050265)
			(xy 60.430156 -283.074872) (xy 60.769004 -283.074872) (xy 60.772964 -283.025818) (xy 60.784741 -282.978034)
			(xy 60.804032 -282.932758) (xy 60.830335 -282.891162) (xy 60.86297 -282.854325) (xy 60.901091 -282.8232)
			(xy 60.943712 -282.798593) (xy 60.989728 -282.781141) (xy 61.037947 -282.771297) (xy 61.087122 -282.769316)
			(xy 61.135977 -282.775248) (xy 61.183248 -282.78894) (xy 61.22771 -282.810038) (xy 61.268213 -282.837994)
			(xy 61.303706 -282.872086) (xy 61.333271 -282.91143) (xy 61.356142 -282.955007) (xy 61.371726 -283.001688)
			(xy 61.379621 -283.050265) (xy 61.380116 -283.074872) (xy 61.718964 -283.074872) (xy 61.722924 -283.025818)
			(xy 61.734701 -282.978034) (xy 61.753992 -282.932758) (xy 61.780295 -282.891162) (xy 61.81293 -282.854325)
			(xy 61.851051 -282.8232) (xy 61.893672 -282.798593) (xy 61.939688 -282.781141) (xy 61.987907 -282.771297)
			(xy 62.037082 -282.769316) (xy 62.085937 -282.775248) (xy 62.133208 -282.78894) (xy 62.17767 -282.810038)
			(xy 62.218173 -282.837994) (xy 62.253666 -282.872086) (xy 62.283231 -282.91143) (xy 62.306102 -282.955007)
			(xy 62.321686 -283.001688) (xy 62.329581 -283.050265) (xy 62.330076 -283.074872) (xy 62.669178 -283.074872)
			(xy 62.673138 -283.025818) (xy 62.684915 -282.978034) (xy 62.704206 -282.932758) (xy 62.730509 -282.891162)
			(xy 62.763144 -282.854325) (xy 62.801265 -282.8232) (xy 62.843886 -282.798593) (xy 62.889902 -282.781141)
			(xy 62.938121 -282.771297) (xy 62.987296 -282.769316) (xy 63.036151 -282.775248) (xy 63.083422 -282.78894)
			(xy 63.127884 -282.810038) (xy 63.168387 -282.837994) (xy 63.20388 -282.872086) (xy 63.233445 -282.91143)
			(xy 63.256316 -282.955007) (xy 63.2719 -283.001688) (xy 63.279795 -283.050265) (xy 63.28029 -283.074872)
			(xy 63.279795 -283.099479) (xy 63.2719 -283.148056) (xy 63.256316 -283.194737) (xy 63.233445 -283.238314)
			(xy 63.20388 -283.277658) (xy 63.168387 -283.31175) (xy 63.127884 -283.339706) (xy 63.083422 -283.360804)
			(xy 63.036151 -283.374496) (xy 62.987296 -283.380428) (xy 62.938121 -283.378447) (xy 62.889902 -283.368603)
			(xy 62.843886 -283.351151) (xy 62.801265 -283.326544) (xy 62.763144 -283.295419) (xy 62.730509 -283.258582)
			(xy 62.704206 -283.216986) (xy 62.684915 -283.17171) (xy 62.673138 -283.123926) (xy 62.669178 -283.074872)
			(xy 62.330076 -283.074872) (xy 62.329581 -283.099479) (xy 62.321686 -283.148056) (xy 62.306102 -283.194737)
			(xy 62.283231 -283.238314) (xy 62.253666 -283.277658) (xy 62.218173 -283.31175) (xy 62.17767 -283.339706)
			(xy 62.133208 -283.360804) (xy 62.085937 -283.374496) (xy 62.037082 -283.380428) (xy 61.987907 -283.378447)
			(xy 61.939688 -283.368603) (xy 61.893672 -283.351151) (xy 61.851051 -283.326544) (xy 61.81293 -283.295419)
			(xy 61.780295 -283.258582) (xy 61.753992 -283.216986) (xy 61.734701 -283.17171) (xy 61.722924 -283.123926)
			(xy 61.718964 -283.074872) (xy 61.380116 -283.074872) (xy 61.379621 -283.099479) (xy 61.371726 -283.148056)
			(xy 61.356142 -283.194737) (xy 61.333271 -283.238314) (xy 61.303706 -283.277658) (xy 61.268213 -283.31175)
			(xy 61.22771 -283.339706) (xy 61.183248 -283.360804) (xy 61.135977 -283.374496) (xy 61.087122 -283.380428)
			(xy 61.037947 -283.378447) (xy 60.989728 -283.368603) (xy 60.943712 -283.351151) (xy 60.901091 -283.326544)
			(xy 60.86297 -283.295419) (xy 60.830335 -283.258582) (xy 60.804032 -283.216986) (xy 60.784741 -283.17171)
			(xy 60.772964 -283.123926) (xy 60.769004 -283.074872) (xy 60.430156 -283.074872) (xy 60.429661 -283.099479)
			(xy 60.421766 -283.148056) (xy 60.406182 -283.194737) (xy 60.383311 -283.238314) (xy 60.353746 -283.277658)
			(xy 60.318253 -283.31175) (xy 60.27775 -283.339706) (xy 60.233288 -283.360804) (xy 60.186017 -283.374496)
			(xy 60.137162 -283.380428) (xy 60.087987 -283.378447) (xy 60.039768 -283.368603) (xy 59.993752 -283.351151)
			(xy 59.951131 -283.326544) (xy 59.91301 -283.295419) (xy 59.880375 -283.258582) (xy 59.854072 -283.216986)
			(xy 59.834781 -283.17171) (xy 59.823004 -283.123926) (xy 59.819044 -283.074872) (xy 58.530236 -283.074872)
			(xy 58.529741 -283.099479) (xy 58.521846 -283.148056) (xy 58.506262 -283.194737) (xy 58.483391 -283.238314)
			(xy 58.453826 -283.277658) (xy 58.418333 -283.31175) (xy 58.37783 -283.339706) (xy 58.333368 -283.360804)
			(xy 58.286097 -283.374496) (xy 58.237242 -283.380428) (xy 58.188067 -283.378447) (xy 58.139848 -283.368603)
			(xy 58.093832 -283.351151) (xy 58.051211 -283.326544) (xy 58.01309 -283.295419) (xy 57.980455 -283.258582)
			(xy 57.954152 -283.216986) (xy 57.934861 -283.17171) (xy 57.923084 -283.123926) (xy 57.919124 -283.074872)
			(xy 57.580276 -283.074872) (xy 57.579781 -283.099479) (xy 57.571886 -283.148056) (xy 57.556302 -283.194737)
			(xy 57.533431 -283.238314) (xy 57.503866 -283.277658) (xy 57.468373 -283.31175) (xy 57.42787 -283.339706)
			(xy 57.383408 -283.360804) (xy 57.336137 -283.374496) (xy 57.287282 -283.380428) (xy 57.238107 -283.378447)
			(xy 57.189888 -283.368603) (xy 57.143872 -283.351151) (xy 57.101251 -283.326544) (xy 57.06313 -283.295419)
			(xy 57.030495 -283.258582) (xy 57.004192 -283.216986) (xy 56.984901 -283.17171) (xy 56.973124 -283.123926)
			(xy 56.969164 -283.074872) (xy 56.630316 -283.074872) (xy 56.629821 -283.099479) (xy 56.621926 -283.148056)
			(xy 56.606342 -283.194737) (xy 56.583471 -283.238314) (xy 56.553906 -283.277658) (xy 56.518413 -283.31175)
			(xy 56.47791 -283.339706) (xy 56.433448 -283.360804) (xy 56.386177 -283.374496) (xy 56.337322 -283.380428)
			(xy 56.288147 -283.378447) (xy 56.239928 -283.368603) (xy 56.193912 -283.351151) (xy 56.151291 -283.326544)
			(xy 56.11317 -283.295419) (xy 56.080535 -283.258582) (xy 56.054232 -283.216986) (xy 56.034941 -283.17171)
			(xy 56.023164 -283.123926) (xy 56.019204 -283.074872) (xy 55.680102 -283.074872) (xy 55.679607 -283.099479)
			(xy 55.671712 -283.148056) (xy 55.656128 -283.194737) (xy 55.633257 -283.238314) (xy 55.603692 -283.277658)
			(xy 55.568199 -283.31175) (xy 55.527696 -283.339706) (xy 55.483234 -283.360804) (xy 55.435963 -283.374496)
			(xy 55.387108 -283.380428) (xy 55.337933 -283.378447) (xy 55.289714 -283.368603) (xy 55.243698 -283.351151)
			(xy 55.201077 -283.326544) (xy 55.162956 -283.295419) (xy 55.130321 -283.258582) (xy 55.104018 -283.216986)
			(xy 55.084727 -283.17171) (xy 55.07295 -283.123926) (xy 55.06899 -283.074872) (xy 54.730142 -283.074872)
			(xy 54.729647 -283.099479) (xy 54.721752 -283.148056) (xy 54.706168 -283.194737) (xy 54.683297 -283.238314)
			(xy 54.653732 -283.277658) (xy 54.618239 -283.31175) (xy 54.577736 -283.339706) (xy 54.533274 -283.360804)
			(xy 54.486003 -283.374496) (xy 54.437148 -283.380428) (xy 54.387973 -283.378447) (xy 54.339754 -283.368603)
			(xy 54.293738 -283.351151) (xy 54.251117 -283.326544) (xy 54.212996 -283.295419) (xy 54.180361 -283.258582)
			(xy 54.154058 -283.216986) (xy 54.134767 -283.17171) (xy 54.12299 -283.123926) (xy 54.11903 -283.074872)
			(xy 53.780182 -283.074872) (xy 53.779687 -283.099479) (xy 53.771792 -283.148056) (xy 53.756208 -283.194737)
			(xy 53.733337 -283.238314) (xy 53.703772 -283.277658) (xy 53.668279 -283.31175) (xy 53.627776 -283.339706)
			(xy 53.583314 -283.360804) (xy 53.536043 -283.374496) (xy 53.487188 -283.380428) (xy 53.438013 -283.378447)
			(xy 53.389794 -283.368603) (xy 53.343778 -283.351151) (xy 53.301157 -283.326544) (xy 53.263036 -283.295419)
			(xy 53.230401 -283.258582) (xy 53.204098 -283.216986) (xy 53.184807 -283.17171) (xy 53.17303 -283.123926)
			(xy 53.16907 -283.074872) (xy 52.830222 -283.074872) (xy 52.829727 -283.099479) (xy 52.821832 -283.148056)
			(xy 52.806248 -283.194737) (xy 52.783377 -283.238314) (xy 52.753812 -283.277658) (xy 52.718319 -283.31175)
			(xy 52.677816 -283.339706) (xy 52.633354 -283.360804) (xy 52.586083 -283.374496) (xy 52.537228 -283.380428)
			(xy 52.488053 -283.378447) (xy 52.439834 -283.368603) (xy 52.393818 -283.351151) (xy 52.351197 -283.326544)
			(xy 52.313076 -283.295419) (xy 52.280441 -283.258582) (xy 52.254138 -283.216986) (xy 52.234847 -283.17171)
			(xy 52.22307 -283.123926) (xy 52.21911 -283.074872) (xy 51.880262 -283.074872) (xy 51.879767 -283.099479)
			(xy 51.871872 -283.148056) (xy 51.856288 -283.194737) (xy 51.833417 -283.238314) (xy 51.803852 -283.277658)
			(xy 51.768359 -283.31175) (xy 51.727856 -283.339706) (xy 51.683394 -283.360804) (xy 51.636123 -283.374496)
			(xy 51.587268 -283.380428) (xy 51.538093 -283.378447) (xy 51.489874 -283.368603) (xy 51.443858 -283.351151)
			(xy 51.401237 -283.326544) (xy 51.363116 -283.295419) (xy 51.330481 -283.258582) (xy 51.304178 -283.216986)
			(xy 51.284887 -283.17171) (xy 51.27311 -283.123926) (xy 51.26915 -283.074872) (xy 50.930302 -283.074872)
			(xy 50.929807 -283.099479) (xy 50.921912 -283.148056) (xy 50.906328 -283.194737) (xy 50.883457 -283.238314)
			(xy 50.853892 -283.277658) (xy 50.818399 -283.31175) (xy 50.777896 -283.339706) (xy 50.733434 -283.360804)
			(xy 50.686163 -283.374496) (xy 50.637308 -283.380428) (xy 50.588133 -283.378447) (xy 50.539914 -283.368603)
			(xy 50.493898 -283.351151) (xy 50.451277 -283.326544) (xy 50.413156 -283.295419) (xy 50.380521 -283.258582)
			(xy 50.354218 -283.216986) (xy 50.334927 -283.17171) (xy 50.32315 -283.123926) (xy 50.31919 -283.074872)
			(xy 49.980088 -283.074872) (xy 49.979593 -283.099479) (xy 49.971698 -283.148056) (xy 49.956114 -283.194737)
			(xy 49.933243 -283.238314) (xy 49.903678 -283.277658) (xy 49.868185 -283.31175) (xy 49.827682 -283.339706)
			(xy 49.78322 -283.360804) (xy 49.735949 -283.374496) (xy 49.687094 -283.380428) (xy 49.637919 -283.378447)
			(xy 49.5897 -283.368603) (xy 49.543684 -283.351151) (xy 49.501063 -283.326544) (xy 49.462942 -283.295419)
			(xy 49.430307 -283.258582) (xy 49.404004 -283.216986) (xy 49.384713 -283.17171) (xy 49.372936 -283.123926)
			(xy 49.368976 -283.074872) (xy 49.030128 -283.074872) (xy 49.029633 -283.099479) (xy 49.021738 -283.148056)
			(xy 49.006154 -283.194737) (xy 48.983283 -283.238314) (xy 48.953718 -283.277658) (xy 48.918225 -283.31175)
			(xy 48.877722 -283.339706) (xy 48.83326 -283.360804) (xy 48.785989 -283.374496) (xy 48.737134 -283.380428)
			(xy 48.687959 -283.378447) (xy 48.63974 -283.368603) (xy 48.593724 -283.351151) (xy 48.551103 -283.326544)
			(xy 48.512982 -283.295419) (xy 48.480347 -283.258582) (xy 48.454044 -283.216986) (xy 48.434753 -283.17171)
			(xy 48.422976 -283.123926) (xy 48.419016 -283.074872) (xy 48.080168 -283.074872) (xy 48.079673 -283.099479)
			(xy 48.071778 -283.148056) (xy 48.056194 -283.194737) (xy 48.033323 -283.238314) (xy 48.003758 -283.277658)
			(xy 47.968265 -283.31175) (xy 47.927762 -283.339706) (xy 47.8833 -283.360804) (xy 47.836029 -283.374496)
			(xy 47.787174 -283.380428) (xy 47.737999 -283.378447) (xy 47.68978 -283.368603) (xy 47.643764 -283.351151)
			(xy 47.601143 -283.326544) (xy 47.563022 -283.295419) (xy 47.530387 -283.258582) (xy 47.504084 -283.216986)
			(xy 47.484793 -283.17171) (xy 47.473016 -283.123926) (xy 47.469056 -283.074872) (xy 47.130172 -283.074872)
			(xy 47.12793 -283.116197) (xy 47.117257 -283.164679) (xy 47.09888 -283.210795) (xy 47.073285 -283.253331)
			(xy 47.041145 -283.291165) (xy 47.003308 -283.323301) (xy 46.96077 -283.348893) (xy 46.914652 -283.367265)
			(xy 46.866169 -283.377934) (xy 46.816599 -283.380618) (xy 46.767248 -283.375248) (xy 46.719416 -283.361964)
			(xy 46.674363 -283.341116) (xy 46.633276 -283.313255) (xy 46.597238 -283.279113) (xy 46.567199 -283.23959)
			(xy 46.54395 -283.195728) (xy 46.528103 -283.148683) (xy 46.520076 -283.099693) (xy 46.519592 -283.074872)
			(xy 46.519765 -283.060689) (xy 46.522439 -283.032449) (xy 46.524926 -283.018484) (xy 46.527212 -283.006038)
			(xy 46.519846 -282.982416) (xy 46.442376 -282.904946) (xy 46.418754 -282.89758) (xy 46.406308 -282.899866)
			(xy 46.392341 -282.902337) (xy 46.364102 -282.905013) (xy 46.34992 -282.9052) (xy 46.335737 -282.905021)
			(xy 46.307497 -282.90235) (xy 46.293532 -282.899866) (xy 46.281086 -282.89758) (xy 46.257464 -282.904946)
			(xy 46.179994 -282.982416) (xy 46.172628 -283.006038) (xy 46.174914 -283.018484) (xy 46.177398 -283.032449)
			(xy 46.180065 -283.060689) (xy 46.180248 -283.074872) (xy 46.179726 -283.100127) (xy 46.171413 -283.149949)
			(xy 46.155012 -283.197723) (xy 46.130971 -283.242146) (xy 46.099947 -283.282006) (xy 46.062785 -283.316216)
			(xy 46.020499 -283.343842) (xy 45.974243 -283.364132) (xy 45.925278 -283.376532) (xy 45.87494 -283.380703)
			(xy 45.824602 -283.376532) (xy 45.775637 -283.364132) (xy 45.729381 -283.343842) (xy 45.687095 -283.316216)
			(xy 45.649933 -283.282006) (xy 45.618909 -283.242146) (xy 45.594868 -283.197723) (xy 45.578467 -283.149949)
			(xy 45.570154 -283.100127) (xy 45.569632 -283.074872) (xy 45.569804 -283.060689) (xy 45.572479 -283.032449)
			(xy 45.574966 -283.018484) (xy 45.577252 -283.006038) (xy 45.569886 -282.982416) (xy 45.492416 -282.904946)
			(xy 45.468794 -282.89758) (xy 45.456348 -282.899866) (xy 45.442383 -282.902345) (xy 45.414143 -282.905015)
			(xy 45.39996 -282.9052) (xy 45.385777 -282.905029) (xy 45.357537 -282.902353) (xy 45.343572 -282.899866)
			(xy 45.331126 -282.89758) (xy 45.307504 -282.904946) (xy 45.230034 -282.982416) (xy 45.222668 -283.006038)
			(xy 45.224954 -283.018484) (xy 45.227438 -283.032449) (xy 45.230105 -283.060689) (xy 45.230288 -283.074872)
			(xy 45.229852 -283.099695) (xy 45.221825 -283.148689) (xy 45.205977 -283.195738) (xy 45.182726 -283.239603)
			(xy 45.152685 -283.279129) (xy 45.116644 -283.313274) (xy 45.075555 -283.341139) (xy 45.030499 -283.361988)
			(xy 44.982663 -283.375274) (xy 44.933308 -283.380646) (xy 44.883734 -283.377962) (xy 44.835247 -283.367294)
			(xy 44.789125 -283.348922) (xy 44.746583 -283.323329) (xy 44.708742 -283.291192) (xy 44.676599 -283.253356)
			(xy 44.651 -283.210818) (xy 44.63262 -283.164699) (xy 44.621944 -283.116214) (xy 44.619253 -283.06664)
			(xy 42.379988 -283.06664) (xy 42.380154 -283.074872) (xy 42.379659 -283.099479) (xy 42.371764 -283.148056)
			(xy 42.35618 -283.194737) (xy 42.333309 -283.238314) (xy 42.303744 -283.277658) (xy 42.268251 -283.31175)
			(xy 42.227748 -283.339706) (xy 42.183286 -283.360804) (xy 42.136015 -283.374496) (xy 42.08716 -283.380428)
			(xy 42.037985 -283.378447) (xy 41.989766 -283.368603) (xy 41.94375 -283.351151) (xy 41.901129 -283.326544)
			(xy 41.863008 -283.295419) (xy 41.830373 -283.258582) (xy 41.80407 -283.216986) (xy 41.784779 -283.17171)
			(xy 41.773002 -283.123926) (xy 41.769042 -283.074872) (xy 41.430194 -283.074872) (xy 41.429699 -283.099479)
			(xy 41.421804 -283.148056) (xy 41.40622 -283.194737) (xy 41.383349 -283.238314) (xy 41.353784 -283.277658)
			(xy 41.318291 -283.31175) (xy 41.277788 -283.339706) (xy 41.233326 -283.360804) (xy 41.186055 -283.374496)
			(xy 41.1372 -283.380428) (xy 41.088025 -283.378447) (xy 41.039806 -283.368603) (xy 40.99379 -283.351151)
			(xy 40.951169 -283.326544) (xy 40.913048 -283.295419) (xy 40.880413 -283.258582) (xy 40.85411 -283.216986)
			(xy 40.834819 -283.17171) (xy 40.823042 -283.123926) (xy 40.819082 -283.074872) (xy 40.480234 -283.074872)
			(xy 40.479739 -283.099479) (xy 40.471844 -283.148056) (xy 40.45626 -283.194737) (xy 40.433389 -283.238314)
			(xy 40.403824 -283.277658) (xy 40.368331 -283.31175) (xy 40.327828 -283.339706) (xy 40.283366 -283.360804)
			(xy 40.236095 -283.374496) (xy 40.18724 -283.380428) (xy 40.138065 -283.378447) (xy 40.089846 -283.368603)
			(xy 40.04383 -283.351151) (xy 40.001209 -283.326544) (xy 39.963088 -283.295419) (xy 39.930453 -283.258582)
			(xy 39.90415 -283.216986) (xy 39.884859 -283.17171) (xy 39.873082 -283.123926) (xy 39.869122 -283.074872)
			(xy 39.530274 -283.074872) (xy 39.529779 -283.099479) (xy 39.521884 -283.148056) (xy 39.5063 -283.194737)
			(xy 39.483429 -283.238314) (xy 39.453864 -283.277658) (xy 39.418371 -283.31175) (xy 39.377868 -283.339706)
			(xy 39.333406 -283.360804) (xy 39.286135 -283.374496) (xy 39.23728 -283.380428) (xy 39.188105 -283.378447)
			(xy 39.139886 -283.368603) (xy 39.09387 -283.351151) (xy 39.051249 -283.326544) (xy 39.013128 -283.295419)
			(xy 38.980493 -283.258582) (xy 38.95419 -283.216986) (xy 38.934899 -283.17171) (xy 38.923122 -283.123926)
			(xy 38.919162 -283.074872) (xy 38.580314 -283.074872) (xy 38.579819 -283.099479) (xy 38.571924 -283.148056)
			(xy 38.55634 -283.194737) (xy 38.533469 -283.238314) (xy 38.503904 -283.277658) (xy 38.468411 -283.31175)
			(xy 38.427908 -283.339706) (xy 38.383446 -283.360804) (xy 38.336175 -283.374496) (xy 38.28732 -283.380428)
			(xy 38.238145 -283.378447) (xy 38.189926 -283.368603) (xy 38.14391 -283.351151) (xy 38.101289 -283.326544)
			(xy 38.063168 -283.295419) (xy 38.030533 -283.258582) (xy 38.00423 -283.216986) (xy 37.984939 -283.17171)
			(xy 37.973162 -283.123926) (xy 37.969202 -283.074872) (xy 37.6301 -283.074872) (xy 37.629605 -283.099479)
			(xy 37.62171 -283.148056) (xy 37.606126 -283.194737) (xy 37.583255 -283.238314) (xy 37.55369 -283.277658)
			(xy 37.518197 -283.31175) (xy 37.477694 -283.339706) (xy 37.433232 -283.360804) (xy 37.385961 -283.374496)
			(xy 37.337106 -283.380428) (xy 37.287931 -283.378447) (xy 37.239712 -283.368603) (xy 37.193696 -283.351151)
			(xy 37.151075 -283.326544) (xy 37.112954 -283.295419) (xy 37.080319 -283.258582) (xy 37.054016 -283.216986)
			(xy 37.034725 -283.17171) (xy 37.022948 -283.123926) (xy 37.018988 -283.074872) (xy 36.68014 -283.074872)
			(xy 36.679645 -283.099479) (xy 36.67175 -283.148056) (xy 36.656166 -283.194737) (xy 36.633295 -283.238314)
			(xy 36.60373 -283.277658) (xy 36.568237 -283.31175) (xy 36.527734 -283.339706) (xy 36.483272 -283.360804)
			(xy 36.436001 -283.374496) (xy 36.387146 -283.380428) (xy 36.337971 -283.378447) (xy 36.289752 -283.368603)
			(xy 36.243736 -283.351151) (xy 36.201115 -283.326544) (xy 36.162994 -283.295419) (xy 36.130359 -283.258582)
			(xy 36.104056 -283.216986) (xy 36.084765 -283.17171) (xy 36.072988 -283.123926) (xy 36.069028 -283.074872)
			(xy 32.107747 -283.074872) (xy 32.111972 -283.104263) (xy 32.112458 -283.131514) (xy 32.111907 -283.160896)
			(xy 32.102876 -283.218961) (xy 32.085044 -283.274954) (xy 32.058835 -283.327549) (xy 32.024867 -283.3755)
			(xy 31.983946 -283.417674) (xy 31.96082 -283.435806) (xy 31.951422 -283.443172) (xy 31.941008 -283.463746)
			(xy 31.939484 -283.567632) (xy 31.94939 -283.588714) (xy 31.958534 -283.59608) (xy 31.980362 -283.614309)
			(xy 32.018902 -283.656124) (xy 32.05081 -283.703195) (xy 32.07538 -283.75448) (xy 32.092068 -283.808843)
			(xy 32.100505 -283.865081) (xy 32.101028 -283.893514) (xy 32.734502 -283.893514) (xy 32.738573 -283.837892)
			(xy 32.750699 -283.783455) (xy 32.770622 -283.731364) (xy 32.797918 -283.682729) (xy 32.832004 -283.638586)
			(xy 32.872153 -283.599877) (xy 32.917511 -283.567426) (xy 32.967111 -283.541925) (xy 33.019895 -283.523918)
			(xy 33.074738 -283.513788) (xy 33.130472 -283.511751) (xy 33.185909 -283.517851) (xy 33.239866 -283.531957)
			(xy 33.291195 -283.553769) (xy 33.338801 -283.582823) (xy 33.381669 -283.618498) (xy 33.418886 -283.660035)
			(xy 33.449659 -283.706548) (xy 33.473331 -283.757045) (xy 33.489399 -283.810452) (xy 33.497519 -283.865628)
			(xy 33.498028 -283.893514) (xy 33.620962 -283.893514) (xy 33.625033 -283.837892) (xy 33.637159 -283.783455)
			(xy 33.657082 -283.731364) (xy 33.684378 -283.682729) (xy 33.718464 -283.638586) (xy 33.758613 -283.599877)
			(xy 33.803971 -283.567426) (xy 33.853571 -283.541925) (xy 33.906355 -283.523918) (xy 33.961198 -283.513788)
			(xy 34.016932 -283.511751) (xy 34.072369 -283.517851) (xy 34.126326 -283.531957) (xy 34.177655 -283.553769)
			(xy 34.225261 -283.582823) (xy 34.268129 -283.618498) (xy 34.305346 -283.660035) (xy 34.336119 -283.706548)
			(xy 34.359791 -283.757045) (xy 34.375859 -283.810452) (xy 34.383979 -283.865628) (xy 34.384488 -283.893514)
			(xy 34.383979 -283.9214) (xy 34.375859 -283.976576) (xy 34.361341 -284.024832) (xy 36.069028 -284.024832)
			(xy 36.072988 -283.975778) (xy 36.084765 -283.927994) (xy 36.104056 -283.882718) (xy 36.130359 -283.841122)
			(xy 36.162994 -283.804285) (xy 36.201115 -283.77316) (xy 36.243736 -283.748553) (xy 36.289752 -283.731101)
			(xy 36.337971 -283.721257) (xy 36.387146 -283.719276) (xy 36.436001 -283.725208) (xy 36.483272 -283.7389)
			(xy 36.527734 -283.759998) (xy 36.568237 -283.787954) (xy 36.60373 -283.822046) (xy 36.633295 -283.86139)
			(xy 36.656166 -283.904967) (xy 36.67175 -283.951648) (xy 36.679645 -284.000225) (xy 36.68014 -284.024832)
			(xy 37.018988 -284.024832) (xy 37.022948 -283.975778) (xy 37.034725 -283.927994) (xy 37.054016 -283.882718)
			(xy 37.080319 -283.841122) (xy 37.112954 -283.804285) (xy 37.151075 -283.77316) (xy 37.193696 -283.748553)
			(xy 37.239712 -283.731101) (xy 37.287931 -283.721257) (xy 37.337106 -283.719276) (xy 37.385961 -283.725208)
			(xy 37.433232 -283.7389) (xy 37.477694 -283.759998) (xy 37.518197 -283.787954) (xy 37.55369 -283.822046)
			(xy 37.583255 -283.86139) (xy 37.606126 -283.904967) (xy 37.62171 -283.951648) (xy 37.629605 -284.000225)
			(xy 37.6301 -284.024832) (xy 37.969202 -284.024832) (xy 37.973162 -283.975778) (xy 37.984939 -283.927994)
			(xy 38.00423 -283.882718) (xy 38.030533 -283.841122) (xy 38.063168 -283.804285) (xy 38.101289 -283.77316)
			(xy 38.14391 -283.748553) (xy 38.189926 -283.731101) (xy 38.238145 -283.721257) (xy 38.28732 -283.719276)
			(xy 38.336175 -283.725208) (xy 38.383446 -283.7389) (xy 38.427908 -283.759998) (xy 38.468411 -283.787954)
			(xy 38.503904 -283.822046) (xy 38.533469 -283.86139) (xy 38.55634 -283.904967) (xy 38.571924 -283.951648)
			(xy 38.579819 -284.000225) (xy 38.580314 -284.024832) (xy 38.919162 -284.024832) (xy 38.923122 -283.975778)
			(xy 38.934899 -283.927994) (xy 38.95419 -283.882718) (xy 38.980493 -283.841122) (xy 39.013128 -283.804285)
			(xy 39.051249 -283.77316) (xy 39.09387 -283.748553) (xy 39.139886 -283.731101) (xy 39.188105 -283.721257)
			(xy 39.23728 -283.719276) (xy 39.286135 -283.725208) (xy 39.333406 -283.7389) (xy 39.377868 -283.759998)
			(xy 39.418371 -283.787954) (xy 39.453864 -283.822046) (xy 39.483429 -283.86139) (xy 39.5063 -283.904967)
			(xy 39.521884 -283.951648) (xy 39.529779 -284.000225) (xy 39.530274 -284.024832) (xy 39.869122 -284.024832)
			(xy 39.873082 -283.975778) (xy 39.884859 -283.927994) (xy 39.90415 -283.882718) (xy 39.930453 -283.841122)
			(xy 39.963088 -283.804285) (xy 40.001209 -283.77316) (xy 40.04383 -283.748553) (xy 40.089846 -283.731101)
			(xy 40.138065 -283.721257) (xy 40.18724 -283.719276) (xy 40.236095 -283.725208) (xy 40.283366 -283.7389)
			(xy 40.327828 -283.759998) (xy 40.368331 -283.787954) (xy 40.403824 -283.822046) (xy 40.433389 -283.86139)
			(xy 40.45626 -283.904967) (xy 40.471844 -283.951648) (xy 40.479739 -284.000225) (xy 40.480234 -284.024832)
			(xy 40.819082 -284.024832) (xy 40.823042 -283.975778) (xy 40.834819 -283.927994) (xy 40.85411 -283.882718)
			(xy 40.880413 -283.841122) (xy 40.913048 -283.804285) (xy 40.951169 -283.77316) (xy 40.99379 -283.748553)
			(xy 41.039806 -283.731101) (xy 41.088025 -283.721257) (xy 41.1372 -283.719276) (xy 41.186055 -283.725208)
			(xy 41.233326 -283.7389) (xy 41.277788 -283.759998) (xy 41.318291 -283.787954) (xy 41.353784 -283.822046)
			(xy 41.383349 -283.86139) (xy 41.40622 -283.904967) (xy 41.421804 -283.951648) (xy 41.429699 -284.000225)
			(xy 41.430194 -284.024832) (xy 44.619176 -284.024832) (xy 44.623136 -283.975778) (xy 44.634913 -283.927994)
			(xy 44.654204 -283.882718) (xy 44.680507 -283.841122) (xy 44.713142 -283.804285) (xy 44.751263 -283.77316)
			(xy 44.793884 -283.748553) (xy 44.8399 -283.731101) (xy 44.888119 -283.721257) (xy 44.937294 -283.719276)
			(xy 44.986149 -283.725208) (xy 45.03342 -283.7389) (xy 45.077882 -283.759998) (xy 45.118385 -283.787954)
			(xy 45.153878 -283.822046) (xy 45.183443 -283.86139) (xy 45.206314 -283.904967) (xy 45.221898 -283.951648)
			(xy 45.229793 -284.000225) (xy 45.230288 -284.024832) (xy 45.569136 -284.024832) (xy 45.573096 -283.975778)
			(xy 45.584873 -283.927994) (xy 45.604164 -283.882718) (xy 45.630467 -283.841122) (xy 45.663102 -283.804285)
			(xy 45.701223 -283.77316) (xy 45.743844 -283.748553) (xy 45.78986 -283.731101) (xy 45.838079 -283.721257)
			(xy 45.887254 -283.719276) (xy 45.936109 -283.725208) (xy 45.98338 -283.7389) (xy 46.027842 -283.759998)
			(xy 46.068345 -283.787954) (xy 46.103838 -283.822046) (xy 46.133403 -283.86139) (xy 46.156274 -283.904967)
			(xy 46.171858 -283.951648) (xy 46.179753 -284.000225) (xy 46.180248 -284.024832) (xy 46.519096 -284.024832)
			(xy 46.523056 -283.975778) (xy 46.534833 -283.927994) (xy 46.554124 -283.882718) (xy 46.580427 -283.841122)
			(xy 46.613062 -283.804285) (xy 46.651183 -283.77316) (xy 46.693804 -283.748553) (xy 46.73982 -283.731101)
			(xy 46.788039 -283.721257) (xy 46.837214 -283.719276) (xy 46.886069 -283.725208) (xy 46.93334 -283.7389)
			(xy 46.977802 -283.759998) (xy 47.018305 -283.787954) (xy 47.053798 -283.822046) (xy 47.083363 -283.86139)
			(xy 47.106234 -283.904967) (xy 47.121818 -283.951648) (xy 47.129713 -284.000225) (xy 47.130208 -284.024832)
			(xy 47.469056 -284.024832) (xy 47.473016 -283.975778) (xy 47.484793 -283.927994) (xy 47.504084 -283.882718)
			(xy 47.530387 -283.841122) (xy 47.563022 -283.804285) (xy 47.601143 -283.77316) (xy 47.643764 -283.748553)
			(xy 47.68978 -283.731101) (xy 47.737999 -283.721257) (xy 47.787174 -283.719276) (xy 47.836029 -283.725208)
			(xy 47.8833 -283.7389) (xy 47.927762 -283.759998) (xy 47.968265 -283.787954) (xy 48.003758 -283.822046)
			(xy 48.033323 -283.86139) (xy 48.056194 -283.904967) (xy 48.071778 -283.951648) (xy 48.079673 -284.000225)
			(xy 48.080168 -284.024832) (xy 48.419016 -284.024832) (xy 48.422976 -283.975778) (xy 48.434753 -283.927994)
			(xy 48.454044 -283.882718) (xy 48.480347 -283.841122) (xy 48.512982 -283.804285) (xy 48.551103 -283.77316)
			(xy 48.593724 -283.748553) (xy 48.63974 -283.731101) (xy 48.687959 -283.721257) (xy 48.737134 -283.719276)
			(xy 48.785989 -283.725208) (xy 48.83326 -283.7389) (xy 48.877722 -283.759998) (xy 48.918225 -283.787954)
			(xy 48.953718 -283.822046) (xy 48.983283 -283.86139) (xy 49.006154 -283.904967) (xy 49.021738 -283.951648)
			(xy 49.029633 -284.000225) (xy 49.030128 -284.024832) (xy 49.368976 -284.024832) (xy 49.372936 -283.975778)
			(xy 49.384713 -283.927994) (xy 49.404004 -283.882718) (xy 49.430307 -283.841122) (xy 49.462942 -283.804285)
			(xy 49.501063 -283.77316) (xy 49.543684 -283.748553) (xy 49.5897 -283.731101) (xy 49.637919 -283.721257)
			(xy 49.687094 -283.719276) (xy 49.735949 -283.725208) (xy 49.78322 -283.7389) (xy 49.827682 -283.759998)
			(xy 49.868185 -283.787954) (xy 49.903678 -283.822046) (xy 49.933243 -283.86139) (xy 49.956114 -283.904967)
			(xy 49.971698 -283.951648) (xy 49.979593 -284.000225) (xy 49.980088 -284.024832) (xy 50.31919 -284.024832)
			(xy 50.32315 -283.975778) (xy 50.334927 -283.927994) (xy 50.354218 -283.882718) (xy 50.380521 -283.841122)
			(xy 50.413156 -283.804285) (xy 50.451277 -283.77316) (xy 50.493898 -283.748553) (xy 50.539914 -283.731101)
			(xy 50.588133 -283.721257) (xy 50.637308 -283.719276) (xy 50.686163 -283.725208) (xy 50.733434 -283.7389)
			(xy 50.777896 -283.759998) (xy 50.818399 -283.787954) (xy 50.853892 -283.822046) (xy 50.883457 -283.86139)
			(xy 50.906328 -283.904967) (xy 50.921912 -283.951648) (xy 50.929807 -284.000225) (xy 50.930302 -284.024832)
			(xy 51.26915 -284.024832) (xy 51.27311 -283.975778) (xy 51.284887 -283.927994) (xy 51.304178 -283.882718)
			(xy 51.330481 -283.841122) (xy 51.363116 -283.804285) (xy 51.401237 -283.77316) (xy 51.443858 -283.748553)
			(xy 51.489874 -283.731101) (xy 51.538093 -283.721257) (xy 51.587268 -283.719276) (xy 51.636123 -283.725208)
			(xy 51.683394 -283.7389) (xy 51.727856 -283.759998) (xy 51.768359 -283.787954) (xy 51.803852 -283.822046)
			(xy 51.833417 -283.86139) (xy 51.856288 -283.904967) (xy 51.871872 -283.951648) (xy 51.879767 -284.000225)
			(xy 51.880262 -284.024832) (xy 52.21911 -284.024832) (xy 52.22307 -283.975778) (xy 52.234847 -283.927994)
			(xy 52.254138 -283.882718) (xy 52.280441 -283.841122) (xy 52.313076 -283.804285) (xy 52.351197 -283.77316)
			(xy 52.393818 -283.748553) (xy 52.439834 -283.731101) (xy 52.488053 -283.721257) (xy 52.537228 -283.719276)
			(xy 52.586083 -283.725208) (xy 52.633354 -283.7389) (xy 52.677816 -283.759998) (xy 52.718319 -283.787954)
			(xy 52.753812 -283.822046) (xy 52.783377 -283.86139) (xy 52.806248 -283.904967) (xy 52.821832 -283.951648)
			(xy 52.829727 -284.000225) (xy 52.830222 -284.024832) (xy 53.16907 -284.024832) (xy 53.17303 -283.975778)
			(xy 53.184807 -283.927994) (xy 53.204098 -283.882718) (xy 53.230401 -283.841122) (xy 53.263036 -283.804285)
			(xy 53.301157 -283.77316) (xy 53.343778 -283.748553) (xy 53.389794 -283.731101) (xy 53.438013 -283.721257)
			(xy 53.487188 -283.719276) (xy 53.536043 -283.725208) (xy 53.583314 -283.7389) (xy 53.627776 -283.759998)
			(xy 53.668279 -283.787954) (xy 53.703772 -283.822046) (xy 53.733337 -283.86139) (xy 53.756208 -283.904967)
			(xy 53.771792 -283.951648) (xy 53.779687 -284.000225) (xy 53.780182 -284.024832) (xy 54.11903 -284.024832)
			(xy 54.12299 -283.975778) (xy 54.134767 -283.927994) (xy 54.154058 -283.882718) (xy 54.180361 -283.841122)
			(xy 54.212996 -283.804285) (xy 54.251117 -283.77316) (xy 54.293738 -283.748553) (xy 54.339754 -283.731101)
			(xy 54.387973 -283.721257) (xy 54.437148 -283.719276) (xy 54.486003 -283.725208) (xy 54.533274 -283.7389)
			(xy 54.577736 -283.759998) (xy 54.618239 -283.787954) (xy 54.653732 -283.822046) (xy 54.683297 -283.86139)
			(xy 54.706168 -283.904967) (xy 54.721752 -283.951648) (xy 54.729647 -284.000225) (xy 54.730142 -284.024832)
			(xy 55.06899 -284.024832) (xy 55.07295 -283.975778) (xy 55.084727 -283.927994) (xy 55.104018 -283.882718)
			(xy 55.130321 -283.841122) (xy 55.162956 -283.804285) (xy 55.201077 -283.77316) (xy 55.243698 -283.748553)
			(xy 55.289714 -283.731101) (xy 55.337933 -283.721257) (xy 55.387108 -283.719276) (xy 55.435963 -283.725208)
			(xy 55.483234 -283.7389) (xy 55.527696 -283.759998) (xy 55.568199 -283.787954) (xy 55.603692 -283.822046)
			(xy 55.633257 -283.86139) (xy 55.656128 -283.904967) (xy 55.671712 -283.951648) (xy 55.679607 -284.000225)
			(xy 55.680102 -284.024832) (xy 56.01895 -284.024832) (xy 56.02291 -283.975778) (xy 56.034687 -283.927994)
			(xy 56.053978 -283.882718) (xy 56.080281 -283.841122) (xy 56.112916 -283.804285) (xy 56.151037 -283.77316)
			(xy 56.193658 -283.748553) (xy 56.239674 -283.731101) (xy 56.287893 -283.721257) (xy 56.337068 -283.719276)
			(xy 56.385923 -283.725208) (xy 56.433194 -283.7389) (xy 56.477656 -283.759998) (xy 56.518159 -283.787954)
			(xy 56.553652 -283.822046) (xy 56.583217 -283.86139) (xy 56.606088 -283.904967) (xy 56.621672 -283.951648)
			(xy 56.629567 -284.000225) (xy 56.630062 -284.024832) (xy 56.969164 -284.024832) (xy 56.973124 -283.975778)
			(xy 56.984901 -283.927994) (xy 57.004192 -283.882718) (xy 57.030495 -283.841122) (xy 57.06313 -283.804285)
			(xy 57.101251 -283.77316) (xy 57.143872 -283.748553) (xy 57.189888 -283.731101) (xy 57.238107 -283.721257)
			(xy 57.287282 -283.719276) (xy 57.336137 -283.725208) (xy 57.383408 -283.7389) (xy 57.42787 -283.759998)
			(xy 57.468373 -283.787954) (xy 57.503866 -283.822046) (xy 57.533431 -283.86139) (xy 57.556302 -283.904967)
			(xy 57.571886 -283.951648) (xy 57.579781 -284.000225) (xy 57.580276 -284.024832) (xy 57.919124 -284.024832)
			(xy 57.923084 -283.975778) (xy 57.934861 -283.927994) (xy 57.954152 -283.882718) (xy 57.980455 -283.841122)
			(xy 58.01309 -283.804285) (xy 58.051211 -283.77316) (xy 58.093832 -283.748553) (xy 58.139848 -283.731101)
			(xy 58.188067 -283.721257) (xy 58.237242 -283.719276) (xy 58.286097 -283.725208) (xy 58.333368 -283.7389)
			(xy 58.37783 -283.759998) (xy 58.418333 -283.787954) (xy 58.453826 -283.822046) (xy 58.483391 -283.86139)
			(xy 58.506262 -283.904967) (xy 58.521846 -283.951648) (xy 58.529741 -284.000225) (xy 58.530236 -284.024832)
			(xy 59.819044 -284.024832) (xy 59.823004 -283.975778) (xy 59.834781 -283.927994) (xy 59.854072 -283.882718)
			(xy 59.880375 -283.841122) (xy 59.91301 -283.804285) (xy 59.951131 -283.77316) (xy 59.993752 -283.748553)
			(xy 60.039768 -283.731101) (xy 60.087987 -283.721257) (xy 60.137162 -283.719276) (xy 60.186017 -283.725208)
			(xy 60.233288 -283.7389) (xy 60.27775 -283.759998) (xy 60.318253 -283.787954) (xy 60.353746 -283.822046)
			(xy 60.383311 -283.86139) (xy 60.406182 -283.904967) (xy 60.421766 -283.951648) (xy 60.429661 -284.000225)
			(xy 60.430156 -284.024832) (xy 60.769004 -284.024832) (xy 60.772964 -283.975778) (xy 60.784741 -283.927994)
			(xy 60.804032 -283.882718) (xy 60.830335 -283.841122) (xy 60.86297 -283.804285) (xy 60.901091 -283.77316)
			(xy 60.943712 -283.748553) (xy 60.989728 -283.731101) (xy 61.037947 -283.721257) (xy 61.087122 -283.719276)
			(xy 61.135977 -283.725208) (xy 61.183248 -283.7389) (xy 61.22771 -283.759998) (xy 61.268213 -283.787954)
			(xy 61.303706 -283.822046) (xy 61.333271 -283.86139) (xy 61.356142 -283.904967) (xy 61.371726 -283.951648)
			(xy 61.379621 -284.000225) (xy 61.380116 -284.024832) (xy 61.718964 -284.024832) (xy 61.722924 -283.975778)
			(xy 61.734701 -283.927994) (xy 61.753992 -283.882718) (xy 61.780295 -283.841122) (xy 61.81293 -283.804285)
			(xy 61.851051 -283.77316) (xy 61.893672 -283.748553) (xy 61.939688 -283.731101) (xy 61.987907 -283.721257)
			(xy 62.037082 -283.719276) (xy 62.085937 -283.725208) (xy 62.133208 -283.7389) (xy 62.17767 -283.759998)
			(xy 62.218173 -283.787954) (xy 62.253666 -283.822046) (xy 62.283231 -283.86139) (xy 62.306102 -283.904967)
			(xy 62.321686 -283.951648) (xy 62.329581 -284.000225) (xy 62.330076 -284.024832) (xy 62.669178 -284.024832)
			(xy 62.673138 -283.975778) (xy 62.684915 -283.927994) (xy 62.704206 -283.882718) (xy 62.730509 -283.841122)
			(xy 62.763144 -283.804285) (xy 62.801265 -283.77316) (xy 62.843886 -283.748553) (xy 62.889902 -283.731101)
			(xy 62.938121 -283.721257) (xy 62.987296 -283.719276) (xy 63.036151 -283.725208) (xy 63.083422 -283.7389)
			(xy 63.127884 -283.759998) (xy 63.168387 -283.787954) (xy 63.20388 -283.822046) (xy 63.233445 -283.86139)
			(xy 63.256316 -283.904967) (xy 63.2719 -283.951648) (xy 63.279795 -284.000225) (xy 63.28029 -284.024832)
			(xy 63.619138 -284.024832) (xy 63.623098 -283.975778) (xy 63.634875 -283.927994) (xy 63.654166 -283.882718)
			(xy 63.680469 -283.841122) (xy 63.713104 -283.804285) (xy 63.751225 -283.77316) (xy 63.793846 -283.748553)
			(xy 63.839862 -283.731101) (xy 63.888081 -283.721257) (xy 63.937256 -283.719276) (xy 63.986111 -283.725208)
			(xy 64.033382 -283.7389) (xy 64.077844 -283.759998) (xy 64.118347 -283.787954) (xy 64.15384 -283.822046)
			(xy 64.183405 -283.86139) (xy 64.206276 -283.904967) (xy 64.22186 -283.951648) (xy 64.229755 -284.000225)
			(xy 64.23025 -284.024832) (xy 64.569098 -284.024832) (xy 64.573058 -283.975778) (xy 64.584835 -283.927994)
			(xy 64.604126 -283.882718) (xy 64.630429 -283.841122) (xy 64.663064 -283.804285) (xy 64.701185 -283.77316)
			(xy 64.743806 -283.748553) (xy 64.789822 -283.731101) (xy 64.838041 -283.721257) (xy 64.887216 -283.719276)
			(xy 64.936071 -283.725208) (xy 64.983342 -283.7389) (xy 65.027804 -283.759998) (xy 65.068307 -283.787954)
			(xy 65.1038 -283.822046) (xy 65.133365 -283.86139) (xy 65.156236 -283.904967) (xy 65.17182 -283.951648)
			(xy 65.179715 -284.000225) (xy 65.18021 -284.024832) (xy 65.519058 -284.024832) (xy 65.523018 -283.975778)
			(xy 65.534795 -283.927994) (xy 65.554086 -283.882718) (xy 65.580389 -283.841122) (xy 65.613024 -283.804285)
			(xy 65.651145 -283.77316) (xy 65.693766 -283.748553) (xy 65.739782 -283.731101) (xy 65.788001 -283.721257)
			(xy 65.837176 -283.719276) (xy 65.886031 -283.725208) (xy 65.933302 -283.7389) (xy 65.977764 -283.759998)
			(xy 66.018267 -283.787954) (xy 66.05376 -283.822046) (xy 66.083325 -283.86139) (xy 66.106196 -283.904967)
			(xy 66.12178 -283.951648) (xy 66.129675 -284.000225) (xy 66.13017 -284.024832) (xy 66.469018 -284.024832)
			(xy 66.472978 -283.975778) (xy 66.484755 -283.927994) (xy 66.504046 -283.882718) (xy 66.530349 -283.841122)
			(xy 66.562984 -283.804285) (xy 66.601105 -283.77316) (xy 66.643726 -283.748553) (xy 66.689742 -283.731101)
			(xy 66.737961 -283.721257) (xy 66.787136 -283.719276) (xy 66.835991 -283.725208) (xy 66.883262 -283.7389)
			(xy 66.927724 -283.759998) (xy 66.968227 -283.787954) (xy 67.00372 -283.822046) (xy 67.033285 -283.86139)
			(xy 67.056156 -283.904967) (xy 67.07174 -283.951648) (xy 67.079635 -284.000225) (xy 67.08013 -284.024832)
			(xy 68.368938 -284.024832) (xy 68.372898 -283.975778) (xy 68.384675 -283.927994) (xy 68.403966 -283.882718)
			(xy 68.430269 -283.841122) (xy 68.462904 -283.804285) (xy 68.501025 -283.77316) (xy 68.543646 -283.748553)
			(xy 68.589662 -283.731101) (xy 68.637881 -283.721257) (xy 68.687056 -283.719276) (xy 68.735911 -283.725208)
			(xy 68.783182 -283.7389) (xy 68.827644 -283.759998) (xy 68.868147 -283.787954) (xy 68.90364 -283.822046)
			(xy 68.933205 -283.86139) (xy 68.956076 -283.904967) (xy 68.97166 -283.951648) (xy 68.979555 -284.000225)
			(xy 68.98005 -284.024832) (xy 69.319152 -284.024832) (xy 69.323112 -283.975778) (xy 69.334889 -283.927994)
			(xy 69.35418 -283.882718) (xy 69.380483 -283.841122) (xy 69.413118 -283.804285) (xy 69.451239 -283.77316)
			(xy 69.49386 -283.748553) (xy 69.539876 -283.731101) (xy 69.588095 -283.721257) (xy 69.63727 -283.719276)
			(xy 69.686125 -283.725208) (xy 69.733396 -283.7389) (xy 69.777858 -283.759998) (xy 69.818361 -283.787954)
			(xy 69.853854 -283.822046) (xy 69.883419 -283.86139) (xy 69.90629 -283.904967) (xy 69.921874 -283.951648)
			(xy 69.929769 -284.000225) (xy 69.930264 -284.024832) (xy 70.269112 -284.024832) (xy 70.273072 -283.975778)
			(xy 70.284849 -283.927994) (xy 70.30414 -283.882718) (xy 70.330443 -283.841122) (xy 70.363078 -283.804285)
			(xy 70.401199 -283.77316) (xy 70.44382 -283.748553) (xy 70.489836 -283.731101) (xy 70.538055 -283.721257)
			(xy 70.58723 -283.719276) (xy 70.636085 -283.725208) (xy 70.683356 -283.7389) (xy 70.727818 -283.759998)
			(xy 70.768321 -283.787954) (xy 70.803814 -283.822046) (xy 70.833379 -283.86139) (xy 70.85625 -283.904967)
			(xy 70.871834 -283.951648) (xy 70.879729 -284.000225) (xy 70.880224 -284.024832) (xy 71.219072 -284.024832)
			(xy 71.223032 -283.975778) (xy 71.234809 -283.927994) (xy 71.2541 -283.882718) (xy 71.280403 -283.841122)
			(xy 71.313038 -283.804285) (xy 71.351159 -283.77316) (xy 71.39378 -283.748553) (xy 71.439796 -283.731101)
			(xy 71.488015 -283.721257) (xy 71.53719 -283.719276) (xy 71.586045 -283.725208) (xy 71.633316 -283.7389)
			(xy 71.677778 -283.759998) (xy 71.718281 -283.787954) (xy 71.753774 -283.822046) (xy 71.783339 -283.86139)
			(xy 71.80621 -283.904967) (xy 71.821794 -283.951648) (xy 71.829689 -284.000225) (xy 71.830184 -284.024832)
			(xy 72.169032 -284.024832) (xy 72.172992 -283.975778) (xy 72.184769 -283.927994) (xy 72.20406 -283.882718)
			(xy 72.230363 -283.841122) (xy 72.262998 -283.804285) (xy 72.301119 -283.77316) (xy 72.34374 -283.748553)
			(xy 72.389756 -283.731101) (xy 72.437975 -283.721257) (xy 72.48715 -283.719276) (xy 72.536005 -283.725208)
			(xy 72.583276 -283.7389) (xy 72.627738 -283.759998) (xy 72.668241 -283.787954) (xy 72.703734 -283.822046)
			(xy 72.733299 -283.86139) (xy 72.75617 -283.904967) (xy 72.771754 -283.951648) (xy 72.779649 -284.000225)
			(xy 72.780144 -284.024832) (xy 72.779649 -284.049439) (xy 72.771754 -284.098016) (xy 72.75617 -284.144697)
			(xy 72.733299 -284.188274) (xy 72.703734 -284.227618) (xy 72.668241 -284.26171) (xy 72.627738 -284.289666)
			(xy 72.583276 -284.310764) (xy 72.536005 -284.324456) (xy 72.48715 -284.330388) (xy 72.437975 -284.328407)
			(xy 72.389756 -284.318563) (xy 72.34374 -284.301111) (xy 72.301119 -284.276504) (xy 72.262998 -284.245379)
			(xy 72.230363 -284.208542) (xy 72.20406 -284.166946) (xy 72.184769 -284.12167) (xy 72.172992 -284.073886)
			(xy 72.169032 -284.024832) (xy 71.830184 -284.024832) (xy 71.829689 -284.049439) (xy 71.821794 -284.098016)
			(xy 71.80621 -284.144697) (xy 71.783339 -284.188274) (xy 71.753774 -284.227618) (xy 71.718281 -284.26171)
			(xy 71.677778 -284.289666) (xy 71.633316 -284.310764) (xy 71.586045 -284.324456) (xy 71.53719 -284.330388)
			(xy 71.488015 -284.328407) (xy 71.439796 -284.318563) (xy 71.39378 -284.301111) (xy 71.351159 -284.276504)
			(xy 71.313038 -284.245379) (xy 71.280403 -284.208542) (xy 71.2541 -284.166946) (xy 71.234809 -284.12167)
			(xy 71.223032 -284.073886) (xy 71.219072 -284.024832) (xy 70.880224 -284.024832) (xy 70.879729 -284.049439)
			(xy 70.871834 -284.098016) (xy 70.85625 -284.144697) (xy 70.833379 -284.188274) (xy 70.803814 -284.227618)
			(xy 70.768321 -284.26171) (xy 70.727818 -284.289666) (xy 70.683356 -284.310764) (xy 70.636085 -284.324456)
			(xy 70.58723 -284.330388) (xy 70.538055 -284.328407) (xy 70.489836 -284.318563) (xy 70.44382 -284.301111)
			(xy 70.401199 -284.276504) (xy 70.363078 -284.245379) (xy 70.330443 -284.208542) (xy 70.30414 -284.166946)
			(xy 70.284849 -284.12167) (xy 70.273072 -284.073886) (xy 70.269112 -284.024832) (xy 69.930264 -284.024832)
			(xy 69.929769 -284.049439) (xy 69.921874 -284.098016) (xy 69.90629 -284.144697) (xy 69.883419 -284.188274)
			(xy 69.853854 -284.227618) (xy 69.818361 -284.26171) (xy 69.777858 -284.289666) (xy 69.733396 -284.310764)
			(xy 69.686125 -284.324456) (xy 69.63727 -284.330388) (xy 69.588095 -284.328407) (xy 69.539876 -284.318563)
			(xy 69.49386 -284.301111) (xy 69.451239 -284.276504) (xy 69.413118 -284.245379) (xy 69.380483 -284.208542)
			(xy 69.35418 -284.166946) (xy 69.334889 -284.12167) (xy 69.323112 -284.073886) (xy 69.319152 -284.024832)
			(xy 68.98005 -284.024832) (xy 68.979555 -284.049439) (xy 68.97166 -284.098016) (xy 68.956076 -284.144697)
			(xy 68.933205 -284.188274) (xy 68.90364 -284.227618) (xy 68.868147 -284.26171) (xy 68.827644 -284.289666)
			(xy 68.783182 -284.310764) (xy 68.735911 -284.324456) (xy 68.687056 -284.330388) (xy 68.637881 -284.328407)
			(xy 68.589662 -284.318563) (xy 68.543646 -284.301111) (xy 68.501025 -284.276504) (xy 68.462904 -284.245379)
			(xy 68.430269 -284.208542) (xy 68.403966 -284.166946) (xy 68.384675 -284.12167) (xy 68.372898 -284.073886)
			(xy 68.368938 -284.024832) (xy 67.08013 -284.024832) (xy 67.079635 -284.049439) (xy 67.07174 -284.098016)
			(xy 67.056156 -284.144697) (xy 67.033285 -284.188274) (xy 67.00372 -284.227618) (xy 66.968227 -284.26171)
			(xy 66.927724 -284.289666) (xy 66.883262 -284.310764) (xy 66.835991 -284.324456) (xy 66.787136 -284.330388)
			(xy 66.737961 -284.328407) (xy 66.689742 -284.318563) (xy 66.643726 -284.301111) (xy 66.601105 -284.276504)
			(xy 66.562984 -284.245379) (xy 66.530349 -284.208542) (xy 66.504046 -284.166946) (xy 66.484755 -284.12167)
			(xy 66.472978 -284.073886) (xy 66.469018 -284.024832) (xy 66.13017 -284.024832) (xy 66.129675 -284.049439)
			(xy 66.12178 -284.098016) (xy 66.106196 -284.144697) (xy 66.083325 -284.188274) (xy 66.05376 -284.227618)
			(xy 66.018267 -284.26171) (xy 65.977764 -284.289666) (xy 65.933302 -284.310764) (xy 65.886031 -284.324456)
			(xy 65.837176 -284.330388) (xy 65.788001 -284.328407) (xy 65.739782 -284.318563) (xy 65.693766 -284.301111)
			(xy 65.651145 -284.276504) (xy 65.613024 -284.245379) (xy 65.580389 -284.208542) (xy 65.554086 -284.166946)
			(xy 65.534795 -284.12167) (xy 65.523018 -284.073886) (xy 65.519058 -284.024832) (xy 65.18021 -284.024832)
			(xy 65.179715 -284.049439) (xy 65.17182 -284.098016) (xy 65.156236 -284.144697) (xy 65.133365 -284.188274)
			(xy 65.1038 -284.227618) (xy 65.068307 -284.26171) (xy 65.027804 -284.289666) (xy 64.983342 -284.310764)
			(xy 64.936071 -284.324456) (xy 64.887216 -284.330388) (xy 64.838041 -284.328407) (xy 64.789822 -284.318563)
			(xy 64.743806 -284.301111) (xy 64.701185 -284.276504) (xy 64.663064 -284.245379) (xy 64.630429 -284.208542)
			(xy 64.604126 -284.166946) (xy 64.584835 -284.12167) (xy 64.573058 -284.073886) (xy 64.569098 -284.024832)
			(xy 64.23025 -284.024832) (xy 64.229755 -284.049439) (xy 64.22186 -284.098016) (xy 64.206276 -284.144697)
			(xy 64.183405 -284.188274) (xy 64.15384 -284.227618) (xy 64.118347 -284.26171) (xy 64.077844 -284.289666)
			(xy 64.033382 -284.310764) (xy 63.986111 -284.324456) (xy 63.937256 -284.330388) (xy 63.888081 -284.328407)
			(xy 63.839862 -284.318563) (xy 63.793846 -284.301111) (xy 63.751225 -284.276504) (xy 63.713104 -284.245379)
			(xy 63.680469 -284.208542) (xy 63.654166 -284.166946) (xy 63.634875 -284.12167) (xy 63.623098 -284.073886)
			(xy 63.619138 -284.024832) (xy 63.28029 -284.024832) (xy 63.279795 -284.049439) (xy 63.2719 -284.098016)
			(xy 63.256316 -284.144697) (xy 63.233445 -284.188274) (xy 63.20388 -284.227618) (xy 63.168387 -284.26171)
			(xy 63.127884 -284.289666) (xy 63.083422 -284.310764) (xy 63.036151 -284.324456) (xy 62.987296 -284.330388)
			(xy 62.938121 -284.328407) (xy 62.889902 -284.318563) (xy 62.843886 -284.301111) (xy 62.801265 -284.276504)
			(xy 62.763144 -284.245379) (xy 62.730509 -284.208542) (xy 62.704206 -284.166946) (xy 62.684915 -284.12167)
			(xy 62.673138 -284.073886) (xy 62.669178 -284.024832) (xy 62.330076 -284.024832) (xy 62.329581 -284.049439)
			(xy 62.321686 -284.098016) (xy 62.306102 -284.144697) (xy 62.283231 -284.188274) (xy 62.253666 -284.227618)
			(xy 62.218173 -284.26171) (xy 62.17767 -284.289666) (xy 62.133208 -284.310764) (xy 62.085937 -284.324456)
			(xy 62.037082 -284.330388) (xy 61.987907 -284.328407) (xy 61.939688 -284.318563) (xy 61.893672 -284.301111)
			(xy 61.851051 -284.276504) (xy 61.81293 -284.245379) (xy 61.780295 -284.208542) (xy 61.753992 -284.166946)
			(xy 61.734701 -284.12167) (xy 61.722924 -284.073886) (xy 61.718964 -284.024832) (xy 61.380116 -284.024832)
			(xy 61.379621 -284.049439) (xy 61.371726 -284.098016) (xy 61.356142 -284.144697) (xy 61.333271 -284.188274)
			(xy 61.303706 -284.227618) (xy 61.268213 -284.26171) (xy 61.22771 -284.289666) (xy 61.183248 -284.310764)
			(xy 61.135977 -284.324456) (xy 61.087122 -284.330388) (xy 61.037947 -284.328407) (xy 60.989728 -284.318563)
			(xy 60.943712 -284.301111) (xy 60.901091 -284.276504) (xy 60.86297 -284.245379) (xy 60.830335 -284.208542)
			(xy 60.804032 -284.166946) (xy 60.784741 -284.12167) (xy 60.772964 -284.073886) (xy 60.769004 -284.024832)
			(xy 60.430156 -284.024832) (xy 60.429661 -284.049439) (xy 60.421766 -284.098016) (xy 60.406182 -284.144697)
			(xy 60.383311 -284.188274) (xy 60.353746 -284.227618) (xy 60.318253 -284.26171) (xy 60.27775 -284.289666)
			(xy 60.233288 -284.310764) (xy 60.186017 -284.324456) (xy 60.137162 -284.330388) (xy 60.087987 -284.328407)
			(xy 60.039768 -284.318563) (xy 59.993752 -284.301111) (xy 59.951131 -284.276504) (xy 59.91301 -284.245379)
			(xy 59.880375 -284.208542) (xy 59.854072 -284.166946) (xy 59.834781 -284.12167) (xy 59.823004 -284.073886)
			(xy 59.819044 -284.024832) (xy 58.530236 -284.024832) (xy 58.529741 -284.049439) (xy 58.521846 -284.098016)
			(xy 58.506262 -284.144697) (xy 58.483391 -284.188274) (xy 58.453826 -284.227618) (xy 58.418333 -284.26171)
			(xy 58.37783 -284.289666) (xy 58.333368 -284.310764) (xy 58.286097 -284.324456) (xy 58.237242 -284.330388)
			(xy 58.188067 -284.328407) (xy 58.139848 -284.318563) (xy 58.093832 -284.301111) (xy 58.051211 -284.276504)
			(xy 58.01309 -284.245379) (xy 57.980455 -284.208542) (xy 57.954152 -284.166946) (xy 57.934861 -284.12167)
			(xy 57.923084 -284.073886) (xy 57.919124 -284.024832) (xy 57.580276 -284.024832) (xy 57.579781 -284.049439)
			(xy 57.571886 -284.098016) (xy 57.556302 -284.144697) (xy 57.533431 -284.188274) (xy 57.503866 -284.227618)
			(xy 57.468373 -284.26171) (xy 57.42787 -284.289666) (xy 57.383408 -284.310764) (xy 57.336137 -284.324456)
			(xy 57.287282 -284.330388) (xy 57.238107 -284.328407) (xy 57.189888 -284.318563) (xy 57.143872 -284.301111)
			(xy 57.101251 -284.276504) (xy 57.06313 -284.245379) (xy 57.030495 -284.208542) (xy 57.004192 -284.166946)
			(xy 56.984901 -284.12167) (xy 56.973124 -284.073886) (xy 56.969164 -284.024832) (xy 56.630062 -284.024832)
			(xy 56.629567 -284.049439) (xy 56.621672 -284.098016) (xy 56.606088 -284.144697) (xy 56.583217 -284.188274)
			(xy 56.553652 -284.227618) (xy 56.518159 -284.26171) (xy 56.477656 -284.289666) (xy 56.433194 -284.310764)
			(xy 56.385923 -284.324456) (xy 56.337068 -284.330388) (xy 56.287893 -284.328407) (xy 56.239674 -284.318563)
			(xy 56.193658 -284.301111) (xy 56.151037 -284.276504) (xy 56.112916 -284.245379) (xy 56.080281 -284.208542)
			(xy 56.053978 -284.166946) (xy 56.034687 -284.12167) (xy 56.02291 -284.073886) (xy 56.01895 -284.024832)
			(xy 55.680102 -284.024832) (xy 55.679607 -284.049439) (xy 55.671712 -284.098016) (xy 55.656128 -284.144697)
			(xy 55.633257 -284.188274) (xy 55.603692 -284.227618) (xy 55.568199 -284.26171) (xy 55.527696 -284.289666)
			(xy 55.483234 -284.310764) (xy 55.435963 -284.324456) (xy 55.387108 -284.330388) (xy 55.337933 -284.328407)
			(xy 55.289714 -284.318563) (xy 55.243698 -284.301111) (xy 55.201077 -284.276504) (xy 55.162956 -284.245379)
			(xy 55.130321 -284.208542) (xy 55.104018 -284.166946) (xy 55.084727 -284.12167) (xy 55.07295 -284.073886)
			(xy 55.06899 -284.024832) (xy 54.730142 -284.024832) (xy 54.729647 -284.049439) (xy 54.721752 -284.098016)
			(xy 54.706168 -284.144697) (xy 54.683297 -284.188274) (xy 54.653732 -284.227618) (xy 54.618239 -284.26171)
			(xy 54.577736 -284.289666) (xy 54.533274 -284.310764) (xy 54.486003 -284.324456) (xy 54.437148 -284.330388)
			(xy 54.387973 -284.328407) (xy 54.339754 -284.318563) (xy 54.293738 -284.301111) (xy 54.251117 -284.276504)
			(xy 54.212996 -284.245379) (xy 54.180361 -284.208542) (xy 54.154058 -284.166946) (xy 54.134767 -284.12167)
			(xy 54.12299 -284.073886) (xy 54.11903 -284.024832) (xy 53.780182 -284.024832) (xy 53.779687 -284.049439)
			(xy 53.771792 -284.098016) (xy 53.756208 -284.144697) (xy 53.733337 -284.188274) (xy 53.703772 -284.227618)
			(xy 53.668279 -284.26171) (xy 53.627776 -284.289666) (xy 53.583314 -284.310764) (xy 53.536043 -284.324456)
			(xy 53.487188 -284.330388) (xy 53.438013 -284.328407) (xy 53.389794 -284.318563) (xy 53.343778 -284.301111)
			(xy 53.301157 -284.276504) (xy 53.263036 -284.245379) (xy 53.230401 -284.208542) (xy 53.204098 -284.166946)
			(xy 53.184807 -284.12167) (xy 53.17303 -284.073886) (xy 53.16907 -284.024832) (xy 52.830222 -284.024832)
			(xy 52.829727 -284.049439) (xy 52.821832 -284.098016) (xy 52.806248 -284.144697) (xy 52.783377 -284.188274)
			(xy 52.753812 -284.227618) (xy 52.718319 -284.26171) (xy 52.677816 -284.289666) (xy 52.633354 -284.310764)
			(xy 52.586083 -284.324456) (xy 52.537228 -284.330388) (xy 52.488053 -284.328407) (xy 52.439834 -284.318563)
			(xy 52.393818 -284.301111) (xy 52.351197 -284.276504) (xy 52.313076 -284.245379) (xy 52.280441 -284.208542)
			(xy 52.254138 -284.166946) (xy 52.234847 -284.12167) (xy 52.22307 -284.073886) (xy 52.21911 -284.024832)
			(xy 51.880262 -284.024832) (xy 51.879767 -284.049439) (xy 51.871872 -284.098016) (xy 51.856288 -284.144697)
			(xy 51.833417 -284.188274) (xy 51.803852 -284.227618) (xy 51.768359 -284.26171) (xy 51.727856 -284.289666)
			(xy 51.683394 -284.310764) (xy 51.636123 -284.324456) (xy 51.587268 -284.330388) (xy 51.538093 -284.328407)
			(xy 51.489874 -284.318563) (xy 51.443858 -284.301111) (xy 51.401237 -284.276504) (xy 51.363116 -284.245379)
			(xy 51.330481 -284.208542) (xy 51.304178 -284.166946) (xy 51.284887 -284.12167) (xy 51.27311 -284.073886)
			(xy 51.26915 -284.024832) (xy 50.930302 -284.024832) (xy 50.929807 -284.049439) (xy 50.921912 -284.098016)
			(xy 50.906328 -284.144697) (xy 50.883457 -284.188274) (xy 50.853892 -284.227618) (xy 50.818399 -284.26171)
			(xy 50.777896 -284.289666) (xy 50.733434 -284.310764) (xy 50.686163 -284.324456) (xy 50.637308 -284.330388)
			(xy 50.588133 -284.328407) (xy 50.539914 -284.318563) (xy 50.493898 -284.301111) (xy 50.451277 -284.276504)
			(xy 50.413156 -284.245379) (xy 50.380521 -284.208542) (xy 50.354218 -284.166946) (xy 50.334927 -284.12167)
			(xy 50.32315 -284.073886) (xy 50.31919 -284.024832) (xy 49.980088 -284.024832) (xy 49.979593 -284.049439)
			(xy 49.971698 -284.098016) (xy 49.956114 -284.144697) (xy 49.933243 -284.188274) (xy 49.903678 -284.227618)
			(xy 49.868185 -284.26171) (xy 49.827682 -284.289666) (xy 49.78322 -284.310764) (xy 49.735949 -284.324456)
			(xy 49.687094 -284.330388) (xy 49.637919 -284.328407) (xy 49.5897 -284.318563) (xy 49.543684 -284.301111)
			(xy 49.501063 -284.276504) (xy 49.462942 -284.245379) (xy 49.430307 -284.208542) (xy 49.404004 -284.166946)
			(xy 49.384713 -284.12167) (xy 49.372936 -284.073886) (xy 49.368976 -284.024832) (xy 49.030128 -284.024832)
			(xy 49.029633 -284.049439) (xy 49.021738 -284.098016) (xy 49.006154 -284.144697) (xy 48.983283 -284.188274)
			(xy 48.953718 -284.227618) (xy 48.918225 -284.26171) (xy 48.877722 -284.289666) (xy 48.83326 -284.310764)
			(xy 48.785989 -284.324456) (xy 48.737134 -284.330388) (xy 48.687959 -284.328407) (xy 48.63974 -284.318563)
			(xy 48.593724 -284.301111) (xy 48.551103 -284.276504) (xy 48.512982 -284.245379) (xy 48.480347 -284.208542)
			(xy 48.454044 -284.166946) (xy 48.434753 -284.12167) (xy 48.422976 -284.073886) (xy 48.419016 -284.024832)
			(xy 48.080168 -284.024832) (xy 48.079673 -284.049439) (xy 48.071778 -284.098016) (xy 48.056194 -284.144697)
			(xy 48.033323 -284.188274) (xy 48.003758 -284.227618) (xy 47.968265 -284.26171) (xy 47.927762 -284.289666)
			(xy 47.8833 -284.310764) (xy 47.836029 -284.324456) (xy 47.787174 -284.330388) (xy 47.737999 -284.328407)
			(xy 47.68978 -284.318563) (xy 47.643764 -284.301111) (xy 47.601143 -284.276504) (xy 47.563022 -284.245379)
			(xy 47.530387 -284.208542) (xy 47.504084 -284.166946) (xy 47.484793 -284.12167) (xy 47.473016 -284.073886)
			(xy 47.469056 -284.024832) (xy 47.130208 -284.024832) (xy 47.129713 -284.049439) (xy 47.121818 -284.098016)
			(xy 47.106234 -284.144697) (xy 47.083363 -284.188274) (xy 47.053798 -284.227618) (xy 47.018305 -284.26171)
			(xy 46.977802 -284.289666) (xy 46.93334 -284.310764) (xy 46.886069 -284.324456) (xy 46.837214 -284.330388)
			(xy 46.788039 -284.328407) (xy 46.73982 -284.318563) (xy 46.693804 -284.301111) (xy 46.651183 -284.276504)
			(xy 46.613062 -284.245379) (xy 46.580427 -284.208542) (xy 46.554124 -284.166946) (xy 46.534833 -284.12167)
			(xy 46.523056 -284.073886) (xy 46.519096 -284.024832) (xy 46.180248 -284.024832) (xy 46.179753 -284.049439)
			(xy 46.171858 -284.098016) (xy 46.156274 -284.144697) (xy 46.133403 -284.188274) (xy 46.103838 -284.227618)
			(xy 46.068345 -284.26171) (xy 46.027842 -284.289666) (xy 45.98338 -284.310764) (xy 45.936109 -284.324456)
			(xy 45.887254 -284.330388) (xy 45.838079 -284.328407) (xy 45.78986 -284.318563) (xy 45.743844 -284.301111)
			(xy 45.701223 -284.276504) (xy 45.663102 -284.245379) (xy 45.630467 -284.208542) (xy 45.604164 -284.166946)
			(xy 45.584873 -284.12167) (xy 45.573096 -284.073886) (xy 45.569136 -284.024832) (xy 45.230288 -284.024832)
			(xy 45.229793 -284.049439) (xy 45.221898 -284.098016) (xy 45.206314 -284.144697) (xy 45.183443 -284.188274)
			(xy 45.153878 -284.227618) (xy 45.118385 -284.26171) (xy 45.077882 -284.289666) (xy 45.03342 -284.310764)
			(xy 44.986149 -284.324456) (xy 44.937294 -284.330388) (xy 44.888119 -284.328407) (xy 44.8399 -284.318563)
			(xy 44.793884 -284.301111) (xy 44.751263 -284.276504) (xy 44.713142 -284.245379) (xy 44.680507 -284.208542)
			(xy 44.654204 -284.166946) (xy 44.634913 -284.12167) (xy 44.623136 -284.073886) (xy 44.619176 -284.024832)
			(xy 41.430194 -284.024832) (xy 41.429699 -284.049439) (xy 41.421804 -284.098016) (xy 41.40622 -284.144697)
			(xy 41.383349 -284.188274) (xy 41.353784 -284.227618) (xy 41.318291 -284.26171) (xy 41.277788 -284.289666)
			(xy 41.233326 -284.310764) (xy 41.186055 -284.324456) (xy 41.1372 -284.330388) (xy 41.088025 -284.328407)
			(xy 41.039806 -284.318563) (xy 40.99379 -284.301111) (xy 40.951169 -284.276504) (xy 40.913048 -284.245379)
			(xy 40.880413 -284.208542) (xy 40.85411 -284.166946) (xy 40.834819 -284.12167) (xy 40.823042 -284.073886)
			(xy 40.819082 -284.024832) (xy 40.480234 -284.024832) (xy 40.479739 -284.049439) (xy 40.471844 -284.098016)
			(xy 40.45626 -284.144697) (xy 40.433389 -284.188274) (xy 40.403824 -284.227618) (xy 40.368331 -284.26171)
			(xy 40.327828 -284.289666) (xy 40.283366 -284.310764) (xy 40.236095 -284.324456) (xy 40.18724 -284.330388)
			(xy 40.138065 -284.328407) (xy 40.089846 -284.318563) (xy 40.04383 -284.301111) (xy 40.001209 -284.276504)
			(xy 39.963088 -284.245379) (xy 39.930453 -284.208542) (xy 39.90415 -284.166946) (xy 39.884859 -284.12167)
			(xy 39.873082 -284.073886) (xy 39.869122 -284.024832) (xy 39.530274 -284.024832) (xy 39.529779 -284.049439)
			(xy 39.521884 -284.098016) (xy 39.5063 -284.144697) (xy 39.483429 -284.188274) (xy 39.453864 -284.227618)
			(xy 39.418371 -284.26171) (xy 39.377868 -284.289666) (xy 39.333406 -284.310764) (xy 39.286135 -284.324456)
			(xy 39.23728 -284.330388) (xy 39.188105 -284.328407) (xy 39.139886 -284.318563) (xy 39.09387 -284.301111)
			(xy 39.051249 -284.276504) (xy 39.013128 -284.245379) (xy 38.980493 -284.208542) (xy 38.95419 -284.166946)
			(xy 38.934899 -284.12167) (xy 38.923122 -284.073886) (xy 38.919162 -284.024832) (xy 38.580314 -284.024832)
			(xy 38.579819 -284.049439) (xy 38.571924 -284.098016) (xy 38.55634 -284.144697) (xy 38.533469 -284.188274)
			(xy 38.503904 -284.227618) (xy 38.468411 -284.26171) (xy 38.427908 -284.289666) (xy 38.383446 -284.310764)
			(xy 38.336175 -284.324456) (xy 38.28732 -284.330388) (xy 38.238145 -284.328407) (xy 38.189926 -284.318563)
			(xy 38.14391 -284.301111) (xy 38.101289 -284.276504) (xy 38.063168 -284.245379) (xy 38.030533 -284.208542)
			(xy 38.00423 -284.166946) (xy 37.984939 -284.12167) (xy 37.973162 -284.073886) (xy 37.969202 -284.024832)
			(xy 37.6301 -284.024832) (xy 37.629605 -284.049439) (xy 37.62171 -284.098016) (xy 37.606126 -284.144697)
			(xy 37.583255 -284.188274) (xy 37.55369 -284.227618) (xy 37.518197 -284.26171) (xy 37.477694 -284.289666)
			(xy 37.433232 -284.310764) (xy 37.385961 -284.324456) (xy 37.337106 -284.330388) (xy 37.287931 -284.328407)
			(xy 37.239712 -284.318563) (xy 37.193696 -284.301111) (xy 37.151075 -284.276504) (xy 37.112954 -284.245379)
			(xy 37.080319 -284.208542) (xy 37.054016 -284.166946) (xy 37.034725 -284.12167) (xy 37.022948 -284.073886)
			(xy 37.018988 -284.024832) (xy 36.68014 -284.024832) (xy 36.679645 -284.049439) (xy 36.67175 -284.098016)
			(xy 36.656166 -284.144697) (xy 36.633295 -284.188274) (xy 36.60373 -284.227618) (xy 36.568237 -284.26171)
			(xy 36.527734 -284.289666) (xy 36.483272 -284.310764) (xy 36.436001 -284.324456) (xy 36.387146 -284.330388)
			(xy 36.337971 -284.328407) (xy 36.289752 -284.318563) (xy 36.243736 -284.301111) (xy 36.201115 -284.276504)
			(xy 36.162994 -284.245379) (xy 36.130359 -284.208542) (xy 36.104056 -284.166946) (xy 36.084765 -284.12167)
			(xy 36.072988 -284.073886) (xy 36.069028 -284.024832) (xy 34.361341 -284.024832) (xy 34.359791 -284.029983)
			(xy 34.336119 -284.08048) (xy 34.305346 -284.126993) (xy 34.268129 -284.16853) (xy 34.225261 -284.204205)
			(xy 34.177655 -284.233259) (xy 34.126326 -284.255071) (xy 34.072369 -284.269177) (xy 34.016932 -284.275277)
			(xy 33.961198 -284.27324) (xy 33.906355 -284.26311) (xy 33.853571 -284.245103) (xy 33.803971 -284.219602)
			(xy 33.758613 -284.187151) (xy 33.718464 -284.148442) (xy 33.684378 -284.104299) (xy 33.657082 -284.055664)
			(xy 33.637159 -284.003573) (xy 33.625033 -283.949136) (xy 33.620962 -283.893514) (xy 33.498028 -283.893514)
			(xy 33.497519 -283.9214) (xy 33.489399 -283.976576) (xy 33.473331 -284.029983) (xy 33.449659 -284.08048)
			(xy 33.418886 -284.126993) (xy 33.381669 -284.16853) (xy 33.338801 -284.204205) (xy 33.291195 -284.233259)
			(xy 33.239866 -284.255071) (xy 33.185909 -284.269177) (xy 33.130472 -284.275277) (xy 33.074738 -284.27324)
			(xy 33.019895 -284.26311) (xy 32.967111 -284.245103) (xy 32.917511 -284.219602) (xy 32.872153 -284.187151)
			(xy 32.832004 -284.148442) (xy 32.797918 -284.104299) (xy 32.770622 -284.055664) (xy 32.750699 -284.003573)
			(xy 32.738573 -283.949136) (xy 32.734502 -283.893514) (xy 32.101028 -283.893514) (xy 32.100542 -283.920765)
			(xy 32.092786 -283.974713) (xy 32.077431 -284.027008) (xy 32.054789 -284.076585) (xy 32.025323 -284.122435)
			(xy 31.989632 -284.163626) (xy 31.948441 -284.199317) (xy 31.902591 -284.228783) (xy 31.853014 -284.251425)
			(xy 31.800719 -284.26678) (xy 31.746771 -284.274536) (xy 31.692269 -284.274536) (xy 31.638321 -284.26678)
			(xy 31.586026 -284.251425) (xy 31.536449 -284.228783) (xy 31.490599 -284.199317) (xy 31.449408 -284.163626)
			(xy 31.413717 -284.122435) (xy 31.384251 -284.076585) (xy 31.361609 -284.027008) (xy 31.346254 -283.974713)
			(xy 31.338498 -283.920765) (xy 31.338012 -283.893514) (xy 1.468374 -283.893514) (xy 1.468374 -284.845831)
			(xy 1.89279 -284.845831) (xy 1.89279 -284.791329) (xy 1.900546 -284.737382) (xy 1.915901 -284.685087)
			(xy 1.938542 -284.635511) (xy 1.968008 -284.58966) (xy 2.003699 -284.548471) (xy 2.044889 -284.512779)
			(xy 2.090739 -284.483313) (xy 2.140316 -284.460672) (xy 2.19261 -284.445317) (xy 2.246557 -284.43756)
			(xy 2.273808 -284.437074) (xy 2.302547 -284.4376) (xy 2.359374 -284.446223) (xy 2.414264 -284.463273)
			(xy 2.465976 -284.488364) (xy 2.513339 -284.520928) (xy 2.534666 -284.540198) (xy 2.541778 -284.546802)
			(xy 2.559304 -284.553914) (xy 2.648712 -284.553914) (xy 2.666238 -284.546802) (xy 2.67335 -284.540198)
			(xy 2.694683 -284.520934) (xy 2.742042 -284.488364) (xy 2.793752 -284.46327) (xy 2.848642 -284.446218)
			(xy 2.905469 -284.437595) (xy 2.934208 -284.437074) (xy 2.964332 -284.437633) (xy 3.023829 -284.447116)
			(xy 3.081098 -284.465829) (xy 3.134714 -284.493308) (xy 3.183348 -284.528869) (xy 3.204972 -284.54985)
			(xy 3.212084 -284.557216) (xy 3.23088 -284.564836) (xy 3.323336 -284.564836) (xy 3.342132 -284.557216)
			(xy 3.349244 -284.54985) (xy 3.370879 -284.52888) (xy 3.419504 -284.493309) (xy 3.473118 -284.465826)
			(xy 3.530386 -284.447115) (xy 3.589884 -284.437643) (xy 3.620008 -284.437074) (xy 3.647379 -284.437517)
			(xy 3.70156 -284.445338) (xy 3.754064 -284.460831) (xy 3.803811 -284.483679) (xy 3.849776 -284.513409)
			(xy 3.870706 -284.531054) (xy 3.877818 -284.53715) (xy 3.894836 -284.5435) (xy 3.98018 -284.5435)
			(xy 3.997198 -284.53715) (xy 4.00431 -284.531054) (xy 4.025234 -284.513405) (xy 4.071208 -284.483693)
			(xy 4.120958 -284.460858) (xy 4.173461 -284.445369) (xy 4.227638 -284.437545) (xy 4.255008 -284.437074)
			(xy 4.282261 -284.437533) (xy 4.336213 -284.44529) (xy 4.388511 -284.460646) (xy 4.438091 -284.483288)
			(xy 4.483945 -284.512757) (xy 4.525138 -284.54845) (xy 4.560832 -284.589643) (xy 4.590301 -284.635497)
			(xy 4.612943 -284.685077) (xy 4.6283 -284.737376) (xy 4.636057 -284.791327) (xy 4.636057 -284.845831)
			(xy 5.88618 -284.845831) (xy 5.88618 -284.791329) (xy 5.893936 -284.737382) (xy 5.909291 -284.685088)
			(xy 5.931932 -284.635511) (xy 5.961397 -284.589661) (xy 5.997088 -284.548471) (xy 6.038278 -284.51278)
			(xy 6.084128 -284.483314) (xy 6.133704 -284.460672) (xy 6.185998 -284.445317) (xy 6.239945 -284.43756)
			(xy 6.267196 -284.437074) (xy 6.295934 -284.437607) (xy 6.352761 -284.446228) (xy 6.407651 -284.463277)
			(xy 6.459363 -284.488366) (xy 6.506727 -284.520929) (xy 6.528054 -284.540198) (xy 6.535166 -284.546802)
			(xy 6.552692 -284.553914) (xy 6.6421 -284.553914) (xy 6.659626 -284.546802) (xy 6.666738 -284.540198)
			(xy 6.688065 -284.520928) (xy 6.735428 -284.488363) (xy 6.787139 -284.463272) (xy 6.84203 -284.446222)
			(xy 6.898857 -284.4376) (xy 6.956335 -284.4376) (xy 7.013162 -284.446222) (xy 7.068053 -284.463272)
			(xy 7.119764 -284.488363) (xy 7.167127 -284.520928) (xy 7.188454 -284.540198) (xy 7.195566 -284.546802)
			(xy 7.213092 -284.553914) (xy 7.3025 -284.553914) (xy 7.320026 -284.546802) (xy 7.327138 -284.540198)
			(xy 7.348476 -284.52094) (xy 7.395834 -284.488369) (xy 7.447543 -284.463274) (xy 7.502431 -284.44622)
			(xy 7.559258 -284.437596) (xy 7.587996 -284.437074) (xy 7.61812 -284.43764) (xy 7.677617 -284.447121)
			(xy 7.734885 -284.465833) (xy 7.788502 -284.49331) (xy 7.837136 -284.52887) (xy 7.85876 -284.54985)
			(xy 7.865872 -284.557216) (xy 7.884668 -284.564836) (xy 7.977124 -284.564836) (xy 7.99592 -284.557216)
			(xy 8.003032 -284.54985) (xy 8.024672 -284.528886) (xy 8.073296 -284.493314) (xy 8.126908 -284.46583)
			(xy 8.184175 -284.447118) (xy 8.243673 -284.437644) (xy 8.273796 -284.437074) (xy 8.301049 -284.437533)
			(xy 8.355001 -284.44529) (xy 8.407299 -284.460645) (xy 8.45688 -284.483288) (xy 8.502734 -284.512756)
			(xy 8.543928 -284.54845) (xy 8.579622 -284.589643) (xy 8.60909 -284.635496) (xy 8.631733 -284.685077)
			(xy 8.64709 -284.737375) (xy 8.654847 -284.791327) (xy 8.654847 -284.845833) (xy 8.64709 -284.899785)
			(xy 8.631733 -284.952083) (xy 8.60909 -285.001664) (xy 8.591101 -285.029656) (xy 25.811478 -285.029656)
			(xy 25.815549 -284.974034) (xy 25.827675 -284.919597) (xy 25.847598 -284.867506) (xy 25.874894 -284.818871)
			(xy 25.90898 -284.774728) (xy 25.949129 -284.736019) (xy 25.994487 -284.703568) (xy 26.044087 -284.678067)
			(xy 26.096871 -284.66006) (xy 26.151714 -284.64993) (xy 26.207448 -284.647893) (xy 26.262885 -284.653993)
			(xy 26.316842 -284.668099) (xy 26.368171 -284.689911) (xy 26.415777 -284.718965) (xy 26.458645 -284.75464)
			(xy 26.495862 -284.796177) (xy 26.526635 -284.84269) (xy 26.550307 -284.893187) (xy 26.566375 -284.946594)
			(xy 26.574495 -285.00177) (xy 26.575004 -285.029656) (xy 27.296616 -285.029656) (xy 27.300687 -284.974034)
			(xy 27.312813 -284.919597) (xy 27.332736 -284.867506) (xy 27.360032 -284.818871) (xy 27.394118 -284.774728)
			(xy 27.434267 -284.736019) (xy 27.479625 -284.703568) (xy 27.529225 -284.678067) (xy 27.582009 -284.66006)
			(xy 27.636852 -284.64993) (xy 27.692586 -284.647893) (xy 27.748023 -284.653993) (xy 27.80198 -284.668099)
			(xy 27.853309 -284.689911) (xy 27.900915 -284.718965) (xy 27.943783 -284.75464) (xy 27.981 -284.796177)
			(xy 28.011773 -284.84269) (xy 28.035445 -284.893187) (xy 28.051513 -284.946594) (xy 28.055663 -284.974792)
			(xy 36.069028 -284.974792) (xy 36.072988 -284.925738) (xy 36.084765 -284.877954) (xy 36.104056 -284.832678)
			(xy 36.130359 -284.791082) (xy 36.162994 -284.754245) (xy 36.201115 -284.72312) (xy 36.243736 -284.698513)
			(xy 36.289752 -284.681061) (xy 36.337971 -284.671217) (xy 36.387146 -284.669236) (xy 36.436001 -284.675168)
			(xy 36.483272 -284.68886) (xy 36.527734 -284.709958) (xy 36.568237 -284.737914) (xy 36.60373 -284.772006)
			(xy 36.633295 -284.81135) (xy 36.656166 -284.854927) (xy 36.67175 -284.901608) (xy 36.679645 -284.950185)
			(xy 36.68014 -284.974792) (xy 37.018988 -284.974792) (xy 37.022948 -284.925738) (xy 37.034725 -284.877954)
			(xy 37.054016 -284.832678) (xy 37.080319 -284.791082) (xy 37.112954 -284.754245) (xy 37.151075 -284.72312)
			(xy 37.193696 -284.698513) (xy 37.239712 -284.681061) (xy 37.287931 -284.671217) (xy 37.337106 -284.669236)
			(xy 37.385961 -284.675168) (xy 37.433232 -284.68886) (xy 37.477694 -284.709958) (xy 37.518197 -284.737914)
			(xy 37.55369 -284.772006) (xy 37.583255 -284.81135) (xy 37.606126 -284.854927) (xy 37.62171 -284.901608)
			(xy 37.629605 -284.950185) (xy 37.6301 -284.974792) (xy 37.969202 -284.974792) (xy 37.973162 -284.925738)
			(xy 37.984939 -284.877954) (xy 38.00423 -284.832678) (xy 38.030533 -284.791082) (xy 38.063168 -284.754245)
			(xy 38.101289 -284.72312) (xy 38.14391 -284.698513) (xy 38.189926 -284.681061) (xy 38.238145 -284.671217)
			(xy 38.28732 -284.669236) (xy 38.336175 -284.675168) (xy 38.383446 -284.68886) (xy 38.427908 -284.709958)
			(xy 38.468411 -284.737914) (xy 38.503904 -284.772006) (xy 38.533469 -284.81135) (xy 38.55634 -284.854927)
			(xy 38.571924 -284.901608) (xy 38.579819 -284.950185) (xy 38.580314 -284.974792) (xy 38.919162 -284.974792)
			(xy 38.923122 -284.925738) (xy 38.934899 -284.877954) (xy 38.95419 -284.832678) (xy 38.980493 -284.791082)
			(xy 39.013128 -284.754245) (xy 39.051249 -284.72312) (xy 39.09387 -284.698513) (xy 39.139886 -284.681061)
			(xy 39.188105 -284.671217) (xy 39.23728 -284.669236) (xy 39.286135 -284.675168) (xy 39.333406 -284.68886)
			(xy 39.377868 -284.709958) (xy 39.418371 -284.737914) (xy 39.453864 -284.772006) (xy 39.483429 -284.81135)
			(xy 39.5063 -284.854927) (xy 39.521884 -284.901608) (xy 39.529779 -284.950185) (xy 39.530274 -284.974792)
			(xy 39.869122 -284.974792) (xy 39.873082 -284.925738) (xy 39.884859 -284.877954) (xy 39.90415 -284.832678)
			(xy 39.930453 -284.791082) (xy 39.963088 -284.754245) (xy 40.001209 -284.72312) (xy 40.04383 -284.698513)
			(xy 40.089846 -284.681061) (xy 40.138065 -284.671217) (xy 40.18724 -284.669236) (xy 40.236095 -284.675168)
			(xy 40.283366 -284.68886) (xy 40.327828 -284.709958) (xy 40.368331 -284.737914) (xy 40.403824 -284.772006)
			(xy 40.433389 -284.81135) (xy 40.45626 -284.854927) (xy 40.471844 -284.901608) (xy 40.479739 -284.950185)
			(xy 40.480234 -284.974792) (xy 40.819082 -284.974792) (xy 40.823042 -284.925738) (xy 40.834819 -284.877954)
			(xy 40.85411 -284.832678) (xy 40.880413 -284.791082) (xy 40.913048 -284.754245) (xy 40.951169 -284.72312)
			(xy 40.99379 -284.698513) (xy 41.039806 -284.681061) (xy 41.088025 -284.671217) (xy 41.1372 -284.669236)
			(xy 41.186055 -284.675168) (xy 41.233326 -284.68886) (xy 41.277788 -284.709958) (xy 41.318291 -284.737914)
			(xy 41.353784 -284.772006) (xy 41.383349 -284.81135) (xy 41.40622 -284.854927) (xy 41.421804 -284.901608)
			(xy 41.429699 -284.950185) (xy 41.430194 -284.974792) (xy 42.719002 -284.974792) (xy 42.722962 -284.925738)
			(xy 42.734739 -284.877954) (xy 42.75403 -284.832678) (xy 42.780333 -284.791082) (xy 42.812968 -284.754245)
			(xy 42.851089 -284.72312) (xy 42.89371 -284.698513) (xy 42.939726 -284.681061) (xy 42.987945 -284.671217)
			(xy 43.03712 -284.669236) (xy 43.085975 -284.675168) (xy 43.133246 -284.68886) (xy 43.177708 -284.709958)
			(xy 43.218211 -284.737914) (xy 43.253704 -284.772006) (xy 43.283269 -284.81135) (xy 43.30614 -284.854927)
			(xy 43.321724 -284.901608) (xy 43.329619 -284.950185) (xy 43.330114 -284.974792) (xy 44.619176 -284.974792)
			(xy 44.623136 -284.925738) (xy 44.634913 -284.877954) (xy 44.654204 -284.832678) (xy 44.680507 -284.791082)
			(xy 44.713142 -284.754245) (xy 44.751263 -284.72312) (xy 44.793884 -284.698513) (xy 44.8399 -284.681061)
			(xy 44.888119 -284.671217) (xy 44.937294 -284.669236) (xy 44.986149 -284.675168) (xy 45.03342 -284.68886)
			(xy 45.077882 -284.709958) (xy 45.118385 -284.737914) (xy 45.153878 -284.772006) (xy 45.183443 -284.81135)
			(xy 45.206314 -284.854927) (xy 45.221898 -284.901608) (xy 45.229793 -284.950185) (xy 45.230288 -284.974792)
			(xy 45.569136 -284.974792) (xy 45.573096 -284.925738) (xy 45.584873 -284.877954) (xy 45.604164 -284.832678)
			(xy 45.630467 -284.791082) (xy 45.663102 -284.754245) (xy 45.701223 -284.72312) (xy 45.743844 -284.698513)
			(xy 45.78986 -284.681061) (xy 45.838079 -284.671217) (xy 45.887254 -284.669236) (xy 45.936109 -284.675168)
			(xy 45.98338 -284.68886) (xy 46.027842 -284.709958) (xy 46.068345 -284.737914) (xy 46.103838 -284.772006)
			(xy 46.133403 -284.81135) (xy 46.156274 -284.854927) (xy 46.171858 -284.901608) (xy 46.179753 -284.950185)
			(xy 46.180248 -284.974792) (xy 46.519096 -284.974792) (xy 46.523056 -284.925738) (xy 46.534833 -284.877954)
			(xy 46.554124 -284.832678) (xy 46.580427 -284.791082) (xy 46.613062 -284.754245) (xy 46.651183 -284.72312)
			(xy 46.693804 -284.698513) (xy 46.73982 -284.681061) (xy 46.788039 -284.671217) (xy 46.837214 -284.669236)
			(xy 46.886069 -284.675168) (xy 46.93334 -284.68886) (xy 46.977802 -284.709958) (xy 47.018305 -284.737914)
			(xy 47.053798 -284.772006) (xy 47.083363 -284.81135) (xy 47.106234 -284.854927) (xy 47.121818 -284.901608)
			(xy 47.129713 -284.950185) (xy 47.130208 -284.974792) (xy 47.469056 -284.974792) (xy 47.473016 -284.925738)
			(xy 47.484793 -284.877954) (xy 47.504084 -284.832678) (xy 47.530387 -284.791082) (xy 47.563022 -284.754245)
			(xy 47.601143 -284.72312) (xy 47.643764 -284.698513) (xy 47.68978 -284.681061) (xy 47.737999 -284.671217)
			(xy 47.787174 -284.669236) (xy 47.836029 -284.675168) (xy 47.8833 -284.68886) (xy 47.927762 -284.709958)
			(xy 47.968265 -284.737914) (xy 48.003758 -284.772006) (xy 48.033323 -284.81135) (xy 48.056194 -284.854927)
			(xy 48.071778 -284.901608) (xy 48.079673 -284.950185) (xy 48.080168 -284.974792) (xy 48.419016 -284.974792)
			(xy 48.422976 -284.925738) (xy 48.434753 -284.877954) (xy 48.454044 -284.832678) (xy 48.480347 -284.791082)
			(xy 48.512982 -284.754245) (xy 48.551103 -284.72312) (xy 48.593724 -284.698513) (xy 48.63974 -284.681061)
			(xy 48.687959 -284.671217) (xy 48.737134 -284.669236) (xy 48.785989 -284.675168) (xy 48.83326 -284.68886)
			(xy 48.877722 -284.709958) (xy 48.918225 -284.737914) (xy 48.953718 -284.772006) (xy 48.983283 -284.81135)
			(xy 49.006154 -284.854927) (xy 49.021738 -284.901608) (xy 49.029633 -284.950185) (xy 49.030128 -284.974792)
			(xy 49.368976 -284.974792) (xy 49.372936 -284.925738) (xy 49.384713 -284.877954) (xy 49.404004 -284.832678)
			(xy 49.430307 -284.791082) (xy 49.462942 -284.754245) (xy 49.501063 -284.72312) (xy 49.543684 -284.698513)
			(xy 49.5897 -284.681061) (xy 49.637919 -284.671217) (xy 49.687094 -284.669236) (xy 49.735949 -284.675168)
			(xy 49.78322 -284.68886) (xy 49.827682 -284.709958) (xy 49.868185 -284.737914) (xy 49.903678 -284.772006)
			(xy 49.933243 -284.81135) (xy 49.956114 -284.854927) (xy 49.971698 -284.901608) (xy 49.979593 -284.950185)
			(xy 49.980088 -284.974792) (xy 50.31919 -284.974792) (xy 50.32315 -284.925738) (xy 50.334927 -284.877954)
			(xy 50.354218 -284.832678) (xy 50.380521 -284.791082) (xy 50.413156 -284.754245) (xy 50.451277 -284.72312)
			(xy 50.493898 -284.698513) (xy 50.539914 -284.681061) (xy 50.588133 -284.671217) (xy 50.637308 -284.669236)
			(xy 50.686163 -284.675168) (xy 50.733434 -284.68886) (xy 50.777896 -284.709958) (xy 50.818399 -284.737914)
			(xy 50.853892 -284.772006) (xy 50.883457 -284.81135) (xy 50.906328 -284.854927) (xy 50.921912 -284.901608)
			(xy 50.929807 -284.950185) (xy 50.930302 -284.974792) (xy 51.26915 -284.974792) (xy 51.27311 -284.925738)
			(xy 51.284887 -284.877954) (xy 51.304178 -284.832678) (xy 51.330481 -284.791082) (xy 51.363116 -284.754245)
			(xy 51.401237 -284.72312) (xy 51.443858 -284.698513) (xy 51.489874 -284.681061) (xy 51.538093 -284.671217)
			(xy 51.587268 -284.669236) (xy 51.636123 -284.675168) (xy 51.683394 -284.68886) (xy 51.727856 -284.709958)
			(xy 51.768359 -284.737914) (xy 51.803852 -284.772006) (xy 51.833417 -284.81135) (xy 51.856288 -284.854927)
			(xy 51.871872 -284.901608) (xy 51.879767 -284.950185) (xy 51.880262 -284.974792) (xy 52.21911 -284.974792)
			(xy 52.22307 -284.925738) (xy 52.234847 -284.877954) (xy 52.254138 -284.832678) (xy 52.280441 -284.791082)
			(xy 52.313076 -284.754245) (xy 52.351197 -284.72312) (xy 52.393818 -284.698513) (xy 52.439834 -284.681061)
			(xy 52.488053 -284.671217) (xy 52.537228 -284.669236) (xy 52.586083 -284.675168) (xy 52.633354 -284.68886)
			(xy 52.677816 -284.709958) (xy 52.718319 -284.737914) (xy 52.753812 -284.772006) (xy 52.783377 -284.81135)
			(xy 52.806248 -284.854927) (xy 52.821832 -284.901608) (xy 52.829727 -284.950185) (xy 52.830222 -284.974792)
			(xy 53.16907 -284.974792) (xy 53.17303 -284.925738) (xy 53.184807 -284.877954) (xy 53.204098 -284.832678)
			(xy 53.230401 -284.791082) (xy 53.263036 -284.754245) (xy 53.301157 -284.72312) (xy 53.343778 -284.698513)
			(xy 53.389794 -284.681061) (xy 53.438013 -284.671217) (xy 53.487188 -284.669236) (xy 53.536043 -284.675168)
			(xy 53.583314 -284.68886) (xy 53.627776 -284.709958) (xy 53.668279 -284.737914) (xy 53.703772 -284.772006)
			(xy 53.733337 -284.81135) (xy 53.756208 -284.854927) (xy 53.771792 -284.901608) (xy 53.779687 -284.950185)
			(xy 53.780182 -284.974792) (xy 54.11903 -284.974792) (xy 54.12299 -284.925738) (xy 54.134767 -284.877954)
			(xy 54.154058 -284.832678) (xy 54.180361 -284.791082) (xy 54.212996 -284.754245) (xy 54.251117 -284.72312)
			(xy 54.293738 -284.698513) (xy 54.339754 -284.681061) (xy 54.387973 -284.671217) (xy 54.437148 -284.669236)
			(xy 54.486003 -284.675168) (xy 54.533274 -284.68886) (xy 54.577736 -284.709958) (xy 54.618239 -284.737914)
			(xy 54.653732 -284.772006) (xy 54.683297 -284.81135) (xy 54.706168 -284.854927) (xy 54.721752 -284.901608)
			(xy 54.729647 -284.950185) (xy 54.730142 -284.974792) (xy 55.06899 -284.974792) (xy 55.07295 -284.925738)
			(xy 55.084727 -284.877954) (xy 55.104018 -284.832678) (xy 55.130321 -284.791082) (xy 55.162956 -284.754245)
			(xy 55.201077 -284.72312) (xy 55.243698 -284.698513) (xy 55.289714 -284.681061) (xy 55.337933 -284.671217)
			(xy 55.387108 -284.669236) (xy 55.435963 -284.675168) (xy 55.483234 -284.68886) (xy 55.527696 -284.709958)
			(xy 55.568199 -284.737914) (xy 55.603692 -284.772006) (xy 55.633257 -284.81135) (xy 55.656128 -284.854927)
			(xy 55.671712 -284.901608) (xy 55.679607 -284.950185) (xy 55.680102 -284.974792) (xy 56.01895 -284.974792)
			(xy 56.02291 -284.925738) (xy 56.034687 -284.877954) (xy 56.053978 -284.832678) (xy 56.080281 -284.791082)
			(xy 56.112916 -284.754245) (xy 56.151037 -284.72312) (xy 56.193658 -284.698513) (xy 56.239674 -284.681061)
			(xy 56.287893 -284.671217) (xy 56.337068 -284.669236) (xy 56.385923 -284.675168) (xy 56.433194 -284.68886)
			(xy 56.477656 -284.709958) (xy 56.518159 -284.737914) (xy 56.553652 -284.772006) (xy 56.583217 -284.81135)
			(xy 56.606088 -284.854927) (xy 56.621672 -284.901608) (xy 56.629567 -284.950185) (xy 56.630062 -284.974792)
			(xy 56.969164 -284.974792) (xy 56.973124 -284.925738) (xy 56.984901 -284.877954) (xy 57.004192 -284.832678)
			(xy 57.030495 -284.791082) (xy 57.06313 -284.754245) (xy 57.101251 -284.72312) (xy 57.143872 -284.698513)
			(xy 57.189888 -284.681061) (xy 57.238107 -284.671217) (xy 57.287282 -284.669236) (xy 57.336137 -284.675168)
			(xy 57.383408 -284.68886) (xy 57.42787 -284.709958) (xy 57.468373 -284.737914) (xy 57.503866 -284.772006)
			(xy 57.533431 -284.81135) (xy 57.556302 -284.854927) (xy 57.571886 -284.901608) (xy 57.579781 -284.950185)
			(xy 57.580276 -284.974792) (xy 57.919124 -284.974792) (xy 57.923084 -284.925738) (xy 57.934861 -284.877954)
			(xy 57.954152 -284.832678) (xy 57.980455 -284.791082) (xy 58.01309 -284.754245) (xy 58.051211 -284.72312)
			(xy 58.093832 -284.698513) (xy 58.139848 -284.681061) (xy 58.188067 -284.671217) (xy 58.237242 -284.669236)
			(xy 58.286097 -284.675168) (xy 58.333368 -284.68886) (xy 58.37783 -284.709958) (xy 58.418333 -284.737914)
			(xy 58.453826 -284.772006) (xy 58.483391 -284.81135) (xy 58.506262 -284.854927) (xy 58.521846 -284.901608)
			(xy 58.529741 -284.950185) (xy 58.530236 -284.974792) (xy 59.819044 -284.974792) (xy 59.823004 -284.925738)
			(xy 59.834781 -284.877954) (xy 59.854072 -284.832678) (xy 59.880375 -284.791082) (xy 59.91301 -284.754245)
			(xy 59.951131 -284.72312) (xy 59.993752 -284.698513) (xy 60.039768 -284.681061) (xy 60.087987 -284.671217)
			(xy 60.137162 -284.669236) (xy 60.186017 -284.675168) (xy 60.233288 -284.68886) (xy 60.27775 -284.709958)
			(xy 60.318253 -284.737914) (xy 60.353746 -284.772006) (xy 60.383311 -284.81135) (xy 60.406182 -284.854927)
			(xy 60.421766 -284.901608) (xy 60.429661 -284.950185) (xy 60.430156 -284.974792) (xy 60.769004 -284.974792)
			(xy 60.772964 -284.925738) (xy 60.784741 -284.877954) (xy 60.804032 -284.832678) (xy 60.830335 -284.791082)
			(xy 60.86297 -284.754245) (xy 60.901091 -284.72312) (xy 60.943712 -284.698513) (xy 60.989728 -284.681061)
			(xy 61.037947 -284.671217) (xy 61.087122 -284.669236) (xy 61.135977 -284.675168) (xy 61.183248 -284.68886)
			(xy 61.22771 -284.709958) (xy 61.268213 -284.737914) (xy 61.303706 -284.772006) (xy 61.333271 -284.81135)
			(xy 61.356142 -284.854927) (xy 61.371726 -284.901608) (xy 61.379621 -284.950185) (xy 61.380116 -284.974792)
			(xy 61.718964 -284.974792) (xy 61.722924 -284.925738) (xy 61.734701 -284.877954) (xy 61.753992 -284.832678)
			(xy 61.780295 -284.791082) (xy 61.81293 -284.754245) (xy 61.851051 -284.72312) (xy 61.893672 -284.698513)
			(xy 61.939688 -284.681061) (xy 61.987907 -284.671217) (xy 62.037082 -284.669236) (xy 62.085937 -284.675168)
			(xy 62.133208 -284.68886) (xy 62.17767 -284.709958) (xy 62.218173 -284.737914) (xy 62.253666 -284.772006)
			(xy 62.283231 -284.81135) (xy 62.306102 -284.854927) (xy 62.321686 -284.901608) (xy 62.329581 -284.950185)
			(xy 62.330076 -284.974792) (xy 62.669178 -284.974792) (xy 62.673138 -284.925738) (xy 62.684915 -284.877954)
			(xy 62.704206 -284.832678) (xy 62.730509 -284.791082) (xy 62.763144 -284.754245) (xy 62.801265 -284.72312)
			(xy 62.843886 -284.698513) (xy 62.889902 -284.681061) (xy 62.938121 -284.671217) (xy 62.987296 -284.669236)
			(xy 63.036151 -284.675168) (xy 63.083422 -284.68886) (xy 63.127884 -284.709958) (xy 63.168387 -284.737914)
			(xy 63.20388 -284.772006) (xy 63.233445 -284.81135) (xy 63.256316 -284.854927) (xy 63.2719 -284.901608)
			(xy 63.279795 -284.950185) (xy 63.28029 -284.974792) (xy 63.619138 -284.974792) (xy 63.623098 -284.925738)
			(xy 63.634875 -284.877954) (xy 63.654166 -284.832678) (xy 63.680469 -284.791082) (xy 63.713104 -284.754245)
			(xy 63.751225 -284.72312) (xy 63.793846 -284.698513) (xy 63.839862 -284.681061) (xy 63.888081 -284.671217)
			(xy 63.937256 -284.669236) (xy 63.986111 -284.675168) (xy 64.033382 -284.68886) (xy 64.077844 -284.709958)
			(xy 64.118347 -284.737914) (xy 64.15384 -284.772006) (xy 64.183405 -284.81135) (xy 64.206276 -284.854927)
			(xy 64.22186 -284.901608) (xy 64.229755 -284.950185) (xy 64.23025 -284.974792) (xy 64.569098 -284.974792)
			(xy 64.573058 -284.925738) (xy 64.584835 -284.877954) (xy 64.604126 -284.832678) (xy 64.630429 -284.791082)
			(xy 64.663064 -284.754245) (xy 64.701185 -284.72312) (xy 64.743806 -284.698513) (xy 64.789822 -284.681061)
			(xy 64.838041 -284.671217) (xy 64.887216 -284.669236) (xy 64.936071 -284.675168) (xy 64.983342 -284.68886)
			(xy 65.027804 -284.709958) (xy 65.068307 -284.737914) (xy 65.1038 -284.772006) (xy 65.133365 -284.81135)
			(xy 65.156236 -284.854927) (xy 65.17182 -284.901608) (xy 65.179715 -284.950185) (xy 65.18021 -284.974792)
			(xy 65.519058 -284.974792) (xy 65.523018 -284.925738) (xy 65.534795 -284.877954) (xy 65.554086 -284.832678)
			(xy 65.580389 -284.791082) (xy 65.613024 -284.754245) (xy 65.651145 -284.72312) (xy 65.693766 -284.698513)
			(xy 65.739782 -284.681061) (xy 65.788001 -284.671217) (xy 65.837176 -284.669236) (xy 65.886031 -284.675168)
			(xy 65.933302 -284.68886) (xy 65.977764 -284.709958) (xy 66.018267 -284.737914) (xy 66.05376 -284.772006)
			(xy 66.083325 -284.81135) (xy 66.106196 -284.854927) (xy 66.12178 -284.901608) (xy 66.129675 -284.950185)
			(xy 66.13017 -284.974792) (xy 66.469018 -284.974792) (xy 66.472978 -284.925738) (xy 66.484755 -284.877954)
			(xy 66.504046 -284.832678) (xy 66.530349 -284.791082) (xy 66.562984 -284.754245) (xy 66.601105 -284.72312)
			(xy 66.643726 -284.698513) (xy 66.689742 -284.681061) (xy 66.737961 -284.671217) (xy 66.787136 -284.669236)
			(xy 66.835991 -284.675168) (xy 66.883262 -284.68886) (xy 66.927724 -284.709958) (xy 66.968227 -284.737914)
			(xy 67.00372 -284.772006) (xy 67.033285 -284.81135) (xy 67.056156 -284.854927) (xy 67.07174 -284.901608)
			(xy 67.079635 -284.950185) (xy 67.08013 -284.974792) (xy 67.418978 -284.974792) (xy 67.422938 -284.925738)
			(xy 67.434715 -284.877954) (xy 67.454006 -284.832678) (xy 67.480309 -284.791082) (xy 67.512944 -284.754245)
			(xy 67.551065 -284.72312) (xy 67.593686 -284.698513) (xy 67.639702 -284.681061) (xy 67.687921 -284.671217)
			(xy 67.737096 -284.669236) (xy 67.785951 -284.675168) (xy 67.833222 -284.68886) (xy 67.877684 -284.709958)
			(xy 67.918187 -284.737914) (xy 67.95368 -284.772006) (xy 67.983245 -284.81135) (xy 68.006116 -284.854927)
			(xy 68.0217 -284.901608) (xy 68.029595 -284.950185) (xy 68.03009 -284.974792) (xy 68.368938 -284.974792)
			(xy 68.372898 -284.925738) (xy 68.384675 -284.877954) (xy 68.403966 -284.832678) (xy 68.430269 -284.791082)
			(xy 68.462904 -284.754245) (xy 68.501025 -284.72312) (xy 68.543646 -284.698513) (xy 68.589662 -284.681061)
			(xy 68.637881 -284.671217) (xy 68.687056 -284.669236) (xy 68.735911 -284.675168) (xy 68.783182 -284.68886)
			(xy 68.827644 -284.709958) (xy 68.868147 -284.737914) (xy 68.90364 -284.772006) (xy 68.933205 -284.81135)
			(xy 68.956076 -284.854927) (xy 68.97166 -284.901608) (xy 68.979555 -284.950185) (xy 68.98005 -284.974792)
			(xy 69.319152 -284.974792) (xy 69.323112 -284.925738) (xy 69.334889 -284.877954) (xy 69.35418 -284.832678)
			(xy 69.380483 -284.791082) (xy 69.413118 -284.754245) (xy 69.451239 -284.72312) (xy 69.49386 -284.698513)
			(xy 69.539876 -284.681061) (xy 69.588095 -284.671217) (xy 69.63727 -284.669236) (xy 69.686125 -284.675168)
			(xy 69.733396 -284.68886) (xy 69.777858 -284.709958) (xy 69.818361 -284.737914) (xy 69.853854 -284.772006)
			(xy 69.883419 -284.81135) (xy 69.90629 -284.854927) (xy 69.921874 -284.901608) (xy 69.929769 -284.950185)
			(xy 69.930264 -284.974792) (xy 70.269112 -284.974792) (xy 70.273072 -284.925738) (xy 70.284849 -284.877954)
			(xy 70.30414 -284.832678) (xy 70.330443 -284.791082) (xy 70.363078 -284.754245) (xy 70.401199 -284.72312)
			(xy 70.44382 -284.698513) (xy 70.489836 -284.681061) (xy 70.538055 -284.671217) (xy 70.58723 -284.669236)
			(xy 70.636085 -284.675168) (xy 70.683356 -284.68886) (xy 70.727818 -284.709958) (xy 70.768321 -284.737914)
			(xy 70.803814 -284.772006) (xy 70.833379 -284.81135) (xy 70.85625 -284.854927) (xy 70.871834 -284.901608)
			(xy 70.879729 -284.950185) (xy 70.880224 -284.974792) (xy 70.879729 -284.999399) (xy 70.871834 -285.047976)
			(xy 70.85625 -285.094657) (xy 70.833379 -285.138234) (xy 70.803814 -285.177578) (xy 70.768321 -285.21167)
			(xy 70.727818 -285.239626) (xy 70.683356 -285.260724) (xy 70.636085 -285.274416) (xy 70.58723 -285.280348)
			(xy 70.538055 -285.278367) (xy 70.489836 -285.268523) (xy 70.44382 -285.251071) (xy 70.401199 -285.226464)
			(xy 70.363078 -285.195339) (xy 70.330443 -285.158502) (xy 70.30414 -285.116906) (xy 70.284849 -285.07163)
			(xy 70.273072 -285.023846) (xy 70.269112 -284.974792) (xy 69.930264 -284.974792) (xy 69.929769 -284.999399)
			(xy 69.921874 -285.047976) (xy 69.90629 -285.094657) (xy 69.883419 -285.138234) (xy 69.853854 -285.177578)
			(xy 69.818361 -285.21167) (xy 69.777858 -285.239626) (xy 69.733396 -285.260724) (xy 69.686125 -285.274416)
			(xy 69.63727 -285.280348) (xy 69.588095 -285.278367) (xy 69.539876 -285.268523) (xy 69.49386 -285.251071)
			(xy 69.451239 -285.226464) (xy 69.413118 -285.195339) (xy 69.380483 -285.158502) (xy 69.35418 -285.116906)
			(xy 69.334889 -285.07163) (xy 69.323112 -285.023846) (xy 69.319152 -284.974792) (xy 68.98005 -284.974792)
			(xy 68.979555 -284.999399) (xy 68.97166 -285.047976) (xy 68.956076 -285.094657) (xy 68.933205 -285.138234)
			(xy 68.90364 -285.177578) (xy 68.868147 -285.21167) (xy 68.827644 -285.239626) (xy 68.783182 -285.260724)
			(xy 68.735911 -285.274416) (xy 68.687056 -285.280348) (xy 68.637881 -285.278367) (xy 68.589662 -285.268523)
			(xy 68.543646 -285.251071) (xy 68.501025 -285.226464) (xy 68.462904 -285.195339) (xy 68.430269 -285.158502)
			(xy 68.403966 -285.116906) (xy 68.384675 -285.07163) (xy 68.372898 -285.023846) (xy 68.368938 -284.974792)
			(xy 68.03009 -284.974792) (xy 68.029595 -284.999399) (xy 68.0217 -285.047976) (xy 68.006116 -285.094657)
			(xy 67.983245 -285.138234) (xy 67.95368 -285.177578) (xy 67.918187 -285.21167) (xy 67.877684 -285.239626)
			(xy 67.833222 -285.260724) (xy 67.785951 -285.274416) (xy 67.737096 -285.280348) (xy 67.687921 -285.278367)
			(xy 67.639702 -285.268523) (xy 67.593686 -285.251071) (xy 67.551065 -285.226464) (xy 67.512944 -285.195339)
			(xy 67.480309 -285.158502) (xy 67.454006 -285.116906) (xy 67.434715 -285.07163) (xy 67.422938 -285.023846)
			(xy 67.418978 -284.974792) (xy 67.08013 -284.974792) (xy 67.079635 -284.999399) (xy 67.07174 -285.047976)
			(xy 67.056156 -285.094657) (xy 67.033285 -285.138234) (xy 67.00372 -285.177578) (xy 66.968227 -285.21167)
			(xy 66.927724 -285.239626) (xy 66.883262 -285.260724) (xy 66.835991 -285.274416) (xy 66.787136 -285.280348)
			(xy 66.737961 -285.278367) (xy 66.689742 -285.268523) (xy 66.643726 -285.251071) (xy 66.601105 -285.226464)
			(xy 66.562984 -285.195339) (xy 66.530349 -285.158502) (xy 66.504046 -285.116906) (xy 66.484755 -285.07163)
			(xy 66.472978 -285.023846) (xy 66.469018 -284.974792) (xy 66.13017 -284.974792) (xy 66.129675 -284.999399)
			(xy 66.12178 -285.047976) (xy 66.106196 -285.094657) (xy 66.083325 -285.138234) (xy 66.05376 -285.177578)
			(xy 66.018267 -285.21167) (xy 65.977764 -285.239626) (xy 65.933302 -285.260724) (xy 65.886031 -285.274416)
			(xy 65.837176 -285.280348) (xy 65.788001 -285.278367) (xy 65.739782 -285.268523) (xy 65.693766 -285.251071)
			(xy 65.651145 -285.226464) (xy 65.613024 -285.195339) (xy 65.580389 -285.158502) (xy 65.554086 -285.116906)
			(xy 65.534795 -285.07163) (xy 65.523018 -285.023846) (xy 65.519058 -284.974792) (xy 65.18021 -284.974792)
			(xy 65.179715 -284.999399) (xy 65.17182 -285.047976) (xy 65.156236 -285.094657) (xy 65.133365 -285.138234)
			(xy 65.1038 -285.177578) (xy 65.068307 -285.21167) (xy 65.027804 -285.239626) (xy 64.983342 -285.260724)
			(xy 64.936071 -285.274416) (xy 64.887216 -285.280348) (xy 64.838041 -285.278367) (xy 64.789822 -285.268523)
			(xy 64.743806 -285.251071) (xy 64.701185 -285.226464) (xy 64.663064 -285.195339) (xy 64.630429 -285.158502)
			(xy 64.604126 -285.116906) (xy 64.584835 -285.07163) (xy 64.573058 -285.023846) (xy 64.569098 -284.974792)
			(xy 64.23025 -284.974792) (xy 64.229755 -284.999399) (xy 64.22186 -285.047976) (xy 64.206276 -285.094657)
			(xy 64.183405 -285.138234) (xy 64.15384 -285.177578) (xy 64.118347 -285.21167) (xy 64.077844 -285.239626)
			(xy 64.033382 -285.260724) (xy 63.986111 -285.274416) (xy 63.937256 -285.280348) (xy 63.888081 -285.278367)
			(xy 63.839862 -285.268523) (xy 63.793846 -285.251071) (xy 63.751225 -285.226464) (xy 63.713104 -285.195339)
			(xy 63.680469 -285.158502) (xy 63.654166 -285.116906) (xy 63.634875 -285.07163) (xy 63.623098 -285.023846)
			(xy 63.619138 -284.974792) (xy 63.28029 -284.974792) (xy 63.279795 -284.999399) (xy 63.2719 -285.047976)
			(xy 63.256316 -285.094657) (xy 63.233445 -285.138234) (xy 63.20388 -285.177578) (xy 63.168387 -285.21167)
			(xy 63.127884 -285.239626) (xy 63.083422 -285.260724) (xy 63.036151 -285.274416) (xy 62.987296 -285.280348)
			(xy 62.938121 -285.278367) (xy 62.889902 -285.268523) (xy 62.843886 -285.251071) (xy 62.801265 -285.226464)
			(xy 62.763144 -285.195339) (xy 62.730509 -285.158502) (xy 62.704206 -285.116906) (xy 62.684915 -285.07163)
			(xy 62.673138 -285.023846) (xy 62.669178 -284.974792) (xy 62.330076 -284.974792) (xy 62.329581 -284.999399)
			(xy 62.321686 -285.047976) (xy 62.306102 -285.094657) (xy 62.283231 -285.138234) (xy 62.253666 -285.177578)
			(xy 62.218173 -285.21167) (xy 62.17767 -285.239626) (xy 62.133208 -285.260724) (xy 62.085937 -285.274416)
			(xy 62.037082 -285.280348) (xy 61.987907 -285.278367) (xy 61.939688 -285.268523) (xy 61.893672 -285.251071)
			(xy 61.851051 -285.226464) (xy 61.81293 -285.195339) (xy 61.780295 -285.158502) (xy 61.753992 -285.116906)
			(xy 61.734701 -285.07163) (xy 61.722924 -285.023846) (xy 61.718964 -284.974792) (xy 61.380116 -284.974792)
			(xy 61.379621 -284.999399) (xy 61.371726 -285.047976) (xy 61.356142 -285.094657) (xy 61.333271 -285.138234)
			(xy 61.303706 -285.177578) (xy 61.268213 -285.21167) (xy 61.22771 -285.239626) (xy 61.183248 -285.260724)
			(xy 61.135977 -285.274416) (xy 61.087122 -285.280348) (xy 61.037947 -285.278367) (xy 60.989728 -285.268523)
			(xy 60.943712 -285.251071) (xy 60.901091 -285.226464) (xy 60.86297 -285.195339) (xy 60.830335 -285.158502)
			(xy 60.804032 -285.116906) (xy 60.784741 -285.07163) (xy 60.772964 -285.023846) (xy 60.769004 -284.974792)
			(xy 60.430156 -284.974792) (xy 60.429661 -284.999399) (xy 60.421766 -285.047976) (xy 60.406182 -285.094657)
			(xy 60.383311 -285.138234) (xy 60.353746 -285.177578) (xy 60.318253 -285.21167) (xy 60.27775 -285.239626)
			(xy 60.233288 -285.260724) (xy 60.186017 -285.274416) (xy 60.137162 -285.280348) (xy 60.087987 -285.278367)
			(xy 60.039768 -285.268523) (xy 59.993752 -285.251071) (xy 59.951131 -285.226464) (xy 59.91301 -285.195339)
			(xy 59.880375 -285.158502) (xy 59.854072 -285.116906) (xy 59.834781 -285.07163) (xy 59.823004 -285.023846)
			(xy 59.819044 -284.974792) (xy 58.530236 -284.974792) (xy 58.529741 -284.999399) (xy 58.521846 -285.047976)
			(xy 58.506262 -285.094657) (xy 58.483391 -285.138234) (xy 58.453826 -285.177578) (xy 58.418333 -285.21167)
			(xy 58.37783 -285.239626) (xy 58.333368 -285.260724) (xy 58.286097 -285.274416) (xy 58.237242 -285.280348)
			(xy 58.188067 -285.278367) (xy 58.139848 -285.268523) (xy 58.093832 -285.251071) (xy 58.051211 -285.226464)
			(xy 58.01309 -285.195339) (xy 57.980455 -285.158502) (xy 57.954152 -285.116906) (xy 57.934861 -285.07163)
			(xy 57.923084 -285.023846) (xy 57.919124 -284.974792) (xy 57.580276 -284.974792) (xy 57.579781 -284.999399)
			(xy 57.571886 -285.047976) (xy 57.556302 -285.094657) (xy 57.533431 -285.138234) (xy 57.503866 -285.177578)
			(xy 57.468373 -285.21167) (xy 57.42787 -285.239626) (xy 57.383408 -285.260724) (xy 57.336137 -285.274416)
			(xy 57.287282 -285.280348) (xy 57.238107 -285.278367) (xy 57.189888 -285.268523) (xy 57.143872 -285.251071)
			(xy 57.101251 -285.226464) (xy 57.06313 -285.195339) (xy 57.030495 -285.158502) (xy 57.004192 -285.116906)
			(xy 56.984901 -285.07163) (xy 56.973124 -285.023846) (xy 56.969164 -284.974792) (xy 56.630062 -284.974792)
			(xy 56.629567 -284.999399) (xy 56.621672 -285.047976) (xy 56.606088 -285.094657) (xy 56.583217 -285.138234)
			(xy 56.553652 -285.177578) (xy 56.518159 -285.21167) (xy 56.477656 -285.239626) (xy 56.433194 -285.260724)
			(xy 56.385923 -285.274416) (xy 56.337068 -285.280348) (xy 56.287893 -285.278367) (xy 56.239674 -285.268523)
			(xy 56.193658 -285.251071) (xy 56.151037 -285.226464) (xy 56.112916 -285.195339) (xy 56.080281 -285.158502)
			(xy 56.053978 -285.116906) (xy 56.034687 -285.07163) (xy 56.02291 -285.023846) (xy 56.01895 -284.974792)
			(xy 55.680102 -284.974792) (xy 55.679607 -284.999399) (xy 55.671712 -285.047976) (xy 55.656128 -285.094657)
			(xy 55.633257 -285.138234) (xy 55.603692 -285.177578) (xy 55.568199 -285.21167) (xy 55.527696 -285.239626)
			(xy 55.483234 -285.260724) (xy 55.435963 -285.274416) (xy 55.387108 -285.280348) (xy 55.337933 -285.278367)
			(xy 55.289714 -285.268523) (xy 55.243698 -285.251071) (xy 55.201077 -285.226464) (xy 55.162956 -285.195339)
			(xy 55.130321 -285.158502) (xy 55.104018 -285.116906) (xy 55.084727 -285.07163) (xy 55.07295 -285.023846)
			(xy 55.06899 -284.974792) (xy 54.730142 -284.974792) (xy 54.729647 -284.999399) (xy 54.721752 -285.047976)
			(xy 54.706168 -285.094657) (xy 54.683297 -285.138234) (xy 54.653732 -285.177578) (xy 54.618239 -285.21167)
			(xy 54.577736 -285.239626) (xy 54.533274 -285.260724) (xy 54.486003 -285.274416) (xy 54.437148 -285.280348)
			(xy 54.387973 -285.278367) (xy 54.339754 -285.268523) (xy 54.293738 -285.251071) (xy 54.251117 -285.226464)
			(xy 54.212996 -285.195339) (xy 54.180361 -285.158502) (xy 54.154058 -285.116906) (xy 54.134767 -285.07163)
			(xy 54.12299 -285.023846) (xy 54.11903 -284.974792) (xy 53.780182 -284.974792) (xy 53.779687 -284.999399)
			(xy 53.771792 -285.047976) (xy 53.756208 -285.094657) (xy 53.733337 -285.138234) (xy 53.703772 -285.177578)
			(xy 53.668279 -285.21167) (xy 53.627776 -285.239626) (xy 53.583314 -285.260724) (xy 53.536043 -285.274416)
			(xy 53.487188 -285.280348) (xy 53.438013 -285.278367) (xy 53.389794 -285.268523) (xy 53.343778 -285.251071)
			(xy 53.301157 -285.226464) (xy 53.263036 -285.195339) (xy 53.230401 -285.158502) (xy 53.204098 -285.116906)
			(xy 53.184807 -285.07163) (xy 53.17303 -285.023846) (xy 53.16907 -284.974792) (xy 52.830222 -284.974792)
			(xy 52.829727 -284.999399) (xy 52.821832 -285.047976) (xy 52.806248 -285.094657) (xy 52.783377 -285.138234)
			(xy 52.753812 -285.177578) (xy 52.718319 -285.21167) (xy 52.677816 -285.239626) (xy 52.633354 -285.260724)
			(xy 52.586083 -285.274416) (xy 52.537228 -285.280348) (xy 52.488053 -285.278367) (xy 52.439834 -285.268523)
			(xy 52.393818 -285.251071) (xy 52.351197 -285.226464) (xy 52.313076 -285.195339) (xy 52.280441 -285.158502)
			(xy 52.254138 -285.116906) (xy 52.234847 -285.07163) (xy 52.22307 -285.023846) (xy 52.21911 -284.974792)
			(xy 51.880262 -284.974792) (xy 51.879767 -284.999399) (xy 51.871872 -285.047976) (xy 51.856288 -285.094657)
			(xy 51.833417 -285.138234) (xy 51.803852 -285.177578) (xy 51.768359 -285.21167) (xy 51.727856 -285.239626)
			(xy 51.683394 -285.260724) (xy 51.636123 -285.274416) (xy 51.587268 -285.280348) (xy 51.538093 -285.278367)
			(xy 51.489874 -285.268523) (xy 51.443858 -285.251071) (xy 51.401237 -285.226464) (xy 51.363116 -285.195339)
			(xy 51.330481 -285.158502) (xy 51.304178 -285.116906) (xy 51.284887 -285.07163) (xy 51.27311 -285.023846)
			(xy 51.26915 -284.974792) (xy 50.930302 -284.974792) (xy 50.929807 -284.999399) (xy 50.921912 -285.047976)
			(xy 50.906328 -285.094657) (xy 50.883457 -285.138234) (xy 50.853892 -285.177578) (xy 50.818399 -285.21167)
			(xy 50.777896 -285.239626) (xy 50.733434 -285.260724) (xy 50.686163 -285.274416) (xy 50.637308 -285.280348)
			(xy 50.588133 -285.278367) (xy 50.539914 -285.268523) (xy 50.493898 -285.251071) (xy 50.451277 -285.226464)
			(xy 50.413156 -285.195339) (xy 50.380521 -285.158502) (xy 50.354218 -285.116906) (xy 50.334927 -285.07163)
			(xy 50.32315 -285.023846) (xy 50.31919 -284.974792) (xy 49.980088 -284.974792) (xy 49.979593 -284.999399)
			(xy 49.971698 -285.047976) (xy 49.956114 -285.094657) (xy 49.933243 -285.138234) (xy 49.903678 -285.177578)
			(xy 49.868185 -285.21167) (xy 49.827682 -285.239626) (xy 49.78322 -285.260724) (xy 49.735949 -285.274416)
			(xy 49.687094 -285.280348) (xy 49.637919 -285.278367) (xy 49.5897 -285.268523) (xy 49.543684 -285.251071)
			(xy 49.501063 -285.226464) (xy 49.462942 -285.195339) (xy 49.430307 -285.158502) (xy 49.404004 -285.116906)
			(xy 49.384713 -285.07163) (xy 49.372936 -285.023846) (xy 49.368976 -284.974792) (xy 49.030128 -284.974792)
			(xy 49.029633 -284.999399) (xy 49.021738 -285.047976) (xy 49.006154 -285.094657) (xy 48.983283 -285.138234)
			(xy 48.953718 -285.177578) (xy 48.918225 -285.21167) (xy 48.877722 -285.239626) (xy 48.83326 -285.260724)
			(xy 48.785989 -285.274416) (xy 48.737134 -285.280348) (xy 48.687959 -285.278367) (xy 48.63974 -285.268523)
			(xy 48.593724 -285.251071) (xy 48.551103 -285.226464) (xy 48.512982 -285.195339) (xy 48.480347 -285.158502)
			(xy 48.454044 -285.116906) (xy 48.434753 -285.07163) (xy 48.422976 -285.023846) (xy 48.419016 -284.974792)
			(xy 48.080168 -284.974792) (xy 48.079673 -284.999399) (xy 48.071778 -285.047976) (xy 48.056194 -285.094657)
			(xy 48.033323 -285.138234) (xy 48.003758 -285.177578) (xy 47.968265 -285.21167) (xy 47.927762 -285.239626)
			(xy 47.8833 -285.260724) (xy 47.836029 -285.274416) (xy 47.787174 -285.280348) (xy 47.737999 -285.278367)
			(xy 47.68978 -285.268523) (xy 47.643764 -285.251071) (xy 47.601143 -285.226464) (xy 47.563022 -285.195339)
			(xy 47.530387 -285.158502) (xy 47.504084 -285.116906) (xy 47.484793 -285.07163) (xy 47.473016 -285.023846)
			(xy 47.469056 -284.974792) (xy 47.130208 -284.974792) (xy 47.129713 -284.999399) (xy 47.121818 -285.047976)
			(xy 47.106234 -285.094657) (xy 47.083363 -285.138234) (xy 47.053798 -285.177578) (xy 47.018305 -285.21167)
			(xy 46.977802 -285.239626) (xy 46.93334 -285.260724) (xy 46.886069 -285.274416) (xy 46.837214 -285.280348)
			(xy 46.788039 -285.278367) (xy 46.73982 -285.268523) (xy 46.693804 -285.251071) (xy 46.651183 -285.226464)
			(xy 46.613062 -285.195339) (xy 46.580427 -285.158502) (xy 46.554124 -285.116906) (xy 46.534833 -285.07163)
			(xy 46.523056 -285.023846) (xy 46.519096 -284.974792) (xy 46.180248 -284.974792) (xy 46.179753 -284.999399)
			(xy 46.171858 -285.047976) (xy 46.156274 -285.094657) (xy 46.133403 -285.138234) (xy 46.103838 -285.177578)
			(xy 46.068345 -285.21167) (xy 46.027842 -285.239626) (xy 45.98338 -285.260724) (xy 45.936109 -285.274416)
			(xy 45.887254 -285.280348) (xy 45.838079 -285.278367) (xy 45.78986 -285.268523) (xy 45.743844 -285.251071)
			(xy 45.701223 -285.226464) (xy 45.663102 -285.195339) (xy 45.630467 -285.158502) (xy 45.604164 -285.116906)
			(xy 45.584873 -285.07163) (xy 45.573096 -285.023846) (xy 45.569136 -284.974792) (xy 45.230288 -284.974792)
			(xy 45.229793 -284.999399) (xy 45.221898 -285.047976) (xy 45.206314 -285.094657) (xy 45.183443 -285.138234)
			(xy 45.153878 -285.177578) (xy 45.118385 -285.21167) (xy 45.077882 -285.239626) (xy 45.03342 -285.260724)
			(xy 44.986149 -285.274416) (xy 44.937294 -285.280348) (xy 44.888119 -285.278367) (xy 44.8399 -285.268523)
			(xy 44.793884 -285.251071) (xy 44.751263 -285.226464) (xy 44.713142 -285.195339) (xy 44.680507 -285.158502)
			(xy 44.654204 -285.116906) (xy 44.634913 -285.07163) (xy 44.623136 -285.023846) (xy 44.619176 -284.974792)
			(xy 43.330114 -284.974792) (xy 43.329619 -284.999399) (xy 43.321724 -285.047976) (xy 43.30614 -285.094657)
			(xy 43.283269 -285.138234) (xy 43.253704 -285.177578) (xy 43.218211 -285.21167) (xy 43.177708 -285.239626)
			(xy 43.133246 -285.260724) (xy 43.085975 -285.274416) (xy 43.03712 -285.280348) (xy 42.987945 -285.278367)
			(xy 42.939726 -285.268523) (xy 42.89371 -285.251071) (xy 42.851089 -285.226464) (xy 42.812968 -285.195339)
			(xy 42.780333 -285.158502) (xy 42.75403 -285.116906) (xy 42.734739 -285.07163) (xy 42.722962 -285.023846)
			(xy 42.719002 -284.974792) (xy 41.430194 -284.974792) (xy 41.429699 -284.999399) (xy 41.421804 -285.047976)
			(xy 41.40622 -285.094657) (xy 41.383349 -285.138234) (xy 41.353784 -285.177578) (xy 41.318291 -285.21167)
			(xy 41.277788 -285.239626) (xy 41.233326 -285.260724) (xy 41.186055 -285.274416) (xy 41.1372 -285.280348)
			(xy 41.088025 -285.278367) (xy 41.039806 -285.268523) (xy 40.99379 -285.251071) (xy 40.951169 -285.226464)
			(xy 40.913048 -285.195339) (xy 40.880413 -285.158502) (xy 40.85411 -285.116906) (xy 40.834819 -285.07163)
			(xy 40.823042 -285.023846) (xy 40.819082 -284.974792) (xy 40.480234 -284.974792) (xy 40.479739 -284.999399)
			(xy 40.471844 -285.047976) (xy 40.45626 -285.094657) (xy 40.433389 -285.138234) (xy 40.403824 -285.177578)
			(xy 40.368331 -285.21167) (xy 40.327828 -285.239626) (xy 40.283366 -285.260724) (xy 40.236095 -285.274416)
			(xy 40.18724 -285.280348) (xy 40.138065 -285.278367) (xy 40.089846 -285.268523) (xy 40.04383 -285.251071)
			(xy 40.001209 -285.226464) (xy 39.963088 -285.195339) (xy 39.930453 -285.158502) (xy 39.90415 -285.116906)
			(xy 39.884859 -285.07163) (xy 39.873082 -285.023846) (xy 39.869122 -284.974792) (xy 39.530274 -284.974792)
			(xy 39.529779 -284.999399) (xy 39.521884 -285.047976) (xy 39.5063 -285.094657) (xy 39.483429 -285.138234)
			(xy 39.453864 -285.177578) (xy 39.418371 -285.21167) (xy 39.377868 -285.239626) (xy 39.333406 -285.260724)
			(xy 39.286135 -285.274416) (xy 39.23728 -285.280348) (xy 39.188105 -285.278367) (xy 39.139886 -285.268523)
			(xy 39.09387 -285.251071) (xy 39.051249 -285.226464) (xy 39.013128 -285.195339) (xy 38.980493 -285.158502)
			(xy 38.95419 -285.116906) (xy 38.934899 -285.07163) (xy 38.923122 -285.023846) (xy 38.919162 -284.974792)
			(xy 38.580314 -284.974792) (xy 38.579819 -284.999399) (xy 38.571924 -285.047976) (xy 38.55634 -285.094657)
			(xy 38.533469 -285.138234) (xy 38.503904 -285.177578) (xy 38.468411 -285.21167) (xy 38.427908 -285.239626)
			(xy 38.383446 -285.260724) (xy 38.336175 -285.274416) (xy 38.28732 -285.280348) (xy 38.238145 -285.278367)
			(xy 38.189926 -285.268523) (xy 38.14391 -285.251071) (xy 38.101289 -285.226464) (xy 38.063168 -285.195339)
			(xy 38.030533 -285.158502) (xy 38.00423 -285.116906) (xy 37.984939 -285.07163) (xy 37.973162 -285.023846)
			(xy 37.969202 -284.974792) (xy 37.6301 -284.974792) (xy 37.629605 -284.999399) (xy 37.62171 -285.047976)
			(xy 37.606126 -285.094657) (xy 37.583255 -285.138234) (xy 37.55369 -285.177578) (xy 37.518197 -285.21167)
			(xy 37.477694 -285.239626) (xy 37.433232 -285.260724) (xy 37.385961 -285.274416) (xy 37.337106 -285.280348)
			(xy 37.287931 -285.278367) (xy 37.239712 -285.268523) (xy 37.193696 -285.251071) (xy 37.151075 -285.226464)
			(xy 37.112954 -285.195339) (xy 37.080319 -285.158502) (xy 37.054016 -285.116906) (xy 37.034725 -285.07163)
			(xy 37.022948 -285.023846) (xy 37.018988 -284.974792) (xy 36.68014 -284.974792) (xy 36.679645 -284.999399)
			(xy 36.67175 -285.047976) (xy 36.656166 -285.094657) (xy 36.633295 -285.138234) (xy 36.60373 -285.177578)
			(xy 36.568237 -285.21167) (xy 36.527734 -285.239626) (xy 36.483272 -285.260724) (xy 36.436001 -285.274416)
			(xy 36.387146 -285.280348) (xy 36.337971 -285.278367) (xy 36.289752 -285.268523) (xy 36.243736 -285.251071)
			(xy 36.201115 -285.226464) (xy 36.162994 -285.195339) (xy 36.130359 -285.158502) (xy 36.104056 -285.116906)
			(xy 36.084765 -285.07163) (xy 36.072988 -285.023846) (xy 36.069028 -284.974792) (xy 28.055663 -284.974792)
			(xy 28.059633 -285.00177) (xy 28.060142 -285.029656) (xy 28.059633 -285.057542) (xy 28.051513 -285.112718)
			(xy 28.035445 -285.166125) (xy 28.011773 -285.216622) (xy 27.981 -285.263135) (xy 27.943783 -285.304672)
			(xy 27.900915 -285.340347) (xy 27.853309 -285.369401) (xy 27.80198 -285.391213) (xy 27.748023 -285.405319)
			(xy 27.692586 -285.411419) (xy 27.636852 -285.409382) (xy 27.582009 -285.399252) (xy 27.529225 -285.381245)
			(xy 27.479625 -285.355744) (xy 27.434267 -285.323293) (xy 27.394118 -285.284584) (xy 27.360032 -285.240441)
			(xy 27.332736 -285.191806) (xy 27.312813 -285.139715) (xy 27.300687 -285.085278) (xy 27.296616 -285.029656)
			(xy 26.575004 -285.029656) (xy 26.574495 -285.057542) (xy 26.566375 -285.112718) (xy 26.550307 -285.166125)
			(xy 26.526635 -285.216622) (xy 26.495862 -285.263135) (xy 26.458645 -285.304672) (xy 26.415777 -285.340347)
			(xy 26.368171 -285.369401) (xy 26.316842 -285.391213) (xy 26.262885 -285.405319) (xy 26.207448 -285.411419)
			(xy 26.151714 -285.409382) (xy 26.096871 -285.399252) (xy 26.044087 -285.381245) (xy 25.994487 -285.355744)
			(xy 25.949129 -285.323293) (xy 25.90898 -285.284584) (xy 25.874894 -285.240441) (xy 25.847598 -285.191806)
			(xy 25.827675 -285.139715) (xy 25.815549 -285.085278) (xy 25.811478 -285.029656) (xy 8.591101 -285.029656)
			(xy 8.579622 -285.047517) (xy 8.543928 -285.08871) (xy 8.502734 -285.124404) (xy 8.45688 -285.153872)
			(xy 8.407299 -285.176515) (xy 8.355001 -285.19187) (xy 8.301049 -285.199627) (xy 8.273796 -285.20009)
			(xy 8.243672 -285.199539) (xy 8.184174 -285.190056) (xy 8.126905 -285.171341) (xy 8.073288 -285.14386)
			(xy 8.024656 -285.108296) (xy 8.003032 -285.087314) (xy 7.99592 -285.079948) (xy 7.977124 -285.072328)
			(xy 7.884668 -285.072328) (xy 7.865872 -285.079948) (xy 7.85876 -285.087314) (xy 7.837134 -285.108293)
			(xy 7.788505 -285.143861) (xy 7.734889 -285.171341) (xy 7.677619 -285.190049) (xy 7.61812 -285.199521)
			(xy 7.587996 -285.20009) (xy 7.559257 -285.199571) (xy 7.502429 -285.190948) (xy 7.447538 -285.173897)
			(xy 7.395827 -285.148804) (xy 7.348464 -285.116237) (xy 7.327138 -285.096966) (xy 7.320026 -285.090362)
			(xy 7.3025 -285.08325) (xy 7.213092 -285.08325) (xy 7.195566 -285.090362) (xy 7.188454 -285.096966)
			(xy 7.167127 -285.116236) (xy 7.119764 -285.148801) (xy 7.068053 -285.173892) (xy 7.013162 -285.190942)
			(xy 6.956335 -285.199564) (xy 6.898857 -285.199564) (xy 6.84203 -285.190942) (xy 6.787139 -285.173892)
			(xy 6.735428 -285.148801) (xy 6.688065 -285.116236) (xy 6.666738 -285.096966) (xy 6.659626 -285.090362)
			(xy 6.6421 -285.08325) (xy 6.552692 -285.08325) (xy 6.535166 -285.090362) (xy 6.528054 -285.096966)
			(xy 6.506729 -285.116239) (xy 6.459366 -285.148805) (xy 6.407654 -285.173897) (xy 6.352763 -285.190947)
			(xy 6.295935 -285.199569) (xy 6.267196 -285.20009) (xy 6.239945 -285.1996) (xy 6.185998 -285.191843)
			(xy 6.133704 -285.176488) (xy 6.084128 -285.153846) (xy 6.038278 -285.12438) (xy 5.997088 -285.088689)
			(xy 5.961397 -285.047499) (xy 5.931932 -285.001649) (xy 5.909291 -284.952072) (xy 5.893936 -284.899778)
			(xy 5.88618 -284.845831) (xy 4.636057 -284.845831) (xy 4.636057 -284.845833) (xy 4.6283 -284.899784)
			(xy 4.612943 -284.952083) (xy 4.590301 -285.001663) (xy 4.560832 -285.047517) (xy 4.525138 -285.08871)
			(xy 4.483945 -285.124403) (xy 4.438091 -285.153872) (xy 4.388511 -285.176514) (xy 4.336213 -285.19187)
			(xy 4.282261 -285.199627) (xy 4.255008 -285.20009) (xy 4.227638 -285.199622) (xy 4.173459 -285.191805)
			(xy 4.120956 -285.176316) (xy 4.071209 -285.153475) (xy 4.025242 -285.123751) (xy 4.00431 -285.10611)
			(xy 3.997198 -285.100014) (xy 3.98018 -285.093664) (xy 3.894836 -285.093664) (xy 3.877818 -285.100014)
			(xy 3.870706 -285.10611) (xy 3.849784 -285.123761) (xy 3.803808 -285.153471) (xy 3.754058 -285.176304)
			(xy 3.701555 -285.191793) (xy 3.647378 -285.199618) (xy 3.620008 -285.20009) (xy 3.589884 -285.199531)
			(xy 3.530386 -285.19005) (xy 3.473117 -285.171337) (xy 3.419501 -285.143858) (xy 3.370868 -285.108295)
			(xy 3.349244 -285.087314) (xy 3.342132 -285.079948) (xy 3.323336 -285.072328) (xy 3.23088 -285.072328)
			(xy 3.212084 -285.079948) (xy 3.204972 -285.087314) (xy 3.183341 -285.108287) (xy 3.134713 -285.143856)
			(xy 3.081099 -285.171337) (xy 3.02383 -285.190047) (xy 2.964332 -285.19952) (xy 2.934208 -285.20009)
			(xy 2.905469 -285.199564) (xy 2.848642 -285.190942) (xy 2.793751 -285.173893) (xy 2.742039 -285.148802)
			(xy 2.694677 -285.116237) (xy 2.67335 -285.096966) (xy 2.666238 -285.090362) (xy 2.648712 -285.08325)
			(xy 2.559304 -285.08325) (xy 2.541778 -285.090362) (xy 2.534666 -285.096966) (xy 2.513336 -285.116234)
			(xy 2.465975 -285.1488) (xy 2.414264 -285.173893) (xy 2.359374 -285.190945) (xy 2.302547 -285.199568)
			(xy 2.273808 -285.20009) (xy 2.246557 -285.1996) (xy 2.19261 -285.191843) (xy 2.140316 -285.176488)
			(xy 2.090739 -285.153847) (xy 2.044889 -285.124381) (xy 2.003699 -285.088689) (xy 1.968008 -285.0475)
			(xy 1.938542 -285.001649) (xy 1.915901 -284.952073) (xy 1.900546 -284.899778) (xy 1.89279 -284.845831)
			(xy 1.468374 -284.845831) (xy 1.468374 -285.462218) (xy 11.958572 -285.462218) (xy 11.962643 -285.406596)
			(xy 11.974769 -285.352159) (xy 11.994692 -285.300068) (xy 12.021988 -285.251433) (xy 12.056074 -285.20729)
			(xy 12.096223 -285.168581) (xy 12.141581 -285.13613) (xy 12.191181 -285.110629) (xy 12.243965 -285.092622)
			(xy 12.298808 -285.082492) (xy 12.354542 -285.080455) (xy 12.409979 -285.086555) (xy 12.463936 -285.100661)
			(xy 12.515265 -285.122473) (xy 12.562871 -285.151527) (xy 12.605739 -285.187202) (xy 12.642956 -285.228739)
			(xy 12.673729 -285.275252) (xy 12.697401 -285.325749) (xy 12.713469 -285.379156) (xy 12.721589 -285.434332)
			(xy 12.722098 -285.462218) (xy 14.151354 -285.462218) (xy 14.155425 -285.406596) (xy 14.167551 -285.352159)
			(xy 14.187474 -285.300068) (xy 14.21477 -285.251433) (xy 14.248856 -285.20729) (xy 14.289005 -285.168581)
			(xy 14.334363 -285.13613) (xy 14.383963 -285.110629) (xy 14.436747 -285.092622) (xy 14.49159 -285.082492)
			(xy 14.547324 -285.080455) (xy 14.602761 -285.086555) (xy 14.656718 -285.100661) (xy 14.708047 -285.122473)
			(xy 14.755653 -285.151527) (xy 14.798521 -285.187202) (xy 14.835738 -285.228739) (xy 14.866511 -285.275252)
			(xy 14.890183 -285.325749) (xy 14.906251 -285.379156) (xy 14.914371 -285.434332) (xy 14.91488 -285.462218)
			(xy 14.914371 -285.490104) (xy 14.906251 -285.54528) (xy 14.890183 -285.598687) (xy 14.866511 -285.649184)
			(xy 14.835738 -285.695697) (xy 14.798521 -285.737234) (xy 14.755653 -285.772909) (xy 14.708047 -285.801963)
			(xy 14.656718 -285.823775) (xy 14.602761 -285.837881) (xy 14.547324 -285.843981) (xy 14.49159 -285.841944)
			(xy 14.436747 -285.831814) (xy 14.383963 -285.813807) (xy 14.334363 -285.788306) (xy 14.289005 -285.755855)
			(xy 14.248856 -285.717146) (xy 14.21477 -285.673003) (xy 14.187474 -285.624368) (xy 14.167551 -285.572277)
			(xy 14.155425 -285.51784) (xy 14.151354 -285.462218) (xy 12.722098 -285.462218) (xy 12.721589 -285.490104)
			(xy 12.713469 -285.54528) (xy 12.697401 -285.598687) (xy 12.673729 -285.649184) (xy 12.642956 -285.695697)
			(xy 12.605739 -285.737234) (xy 12.562871 -285.772909) (xy 12.515265 -285.801963) (xy 12.463936 -285.823775)
			(xy 12.409979 -285.837881) (xy 12.354542 -285.843981) (xy 12.298808 -285.841944) (xy 12.243965 -285.831814)
			(xy 12.191181 -285.813807) (xy 12.141581 -285.788306) (xy 12.096223 -285.755855) (xy 12.056074 -285.717146)
			(xy 12.021988 -285.673003) (xy 11.994692 -285.624368) (xy 11.974769 -285.572277) (xy 11.962643 -285.51784)
			(xy 11.958572 -285.462218) (xy 1.468374 -285.462218) (xy 1.468374 -285.924752) (xy 36.069028 -285.924752)
			(xy 36.072988 -285.875698) (xy 36.084765 -285.827914) (xy 36.104056 -285.782638) (xy 36.130359 -285.741042)
			(xy 36.162994 -285.704205) (xy 36.201115 -285.67308) (xy 36.243736 -285.648473) (xy 36.289752 -285.631021)
			(xy 36.337971 -285.621177) (xy 36.387146 -285.619196) (xy 36.436001 -285.625128) (xy 36.483272 -285.63882)
			(xy 36.527734 -285.659918) (xy 36.568237 -285.687874) (xy 36.60373 -285.721966) (xy 36.633295 -285.76131)
			(xy 36.656166 -285.804887) (xy 36.67175 -285.851568) (xy 36.679645 -285.900145) (xy 36.68014 -285.924752)
			(xy 37.018988 -285.924752) (xy 37.022948 -285.875698) (xy 37.034725 -285.827914) (xy 37.054016 -285.782638)
			(xy 37.080319 -285.741042) (xy 37.112954 -285.704205) (xy 37.151075 -285.67308) (xy 37.193696 -285.648473)
			(xy 37.239712 -285.631021) (xy 37.287931 -285.621177) (xy 37.337106 -285.619196) (xy 37.385961 -285.625128)
			(xy 37.433232 -285.63882) (xy 37.477694 -285.659918) (xy 37.518197 -285.687874) (xy 37.55369 -285.721966)
			(xy 37.583255 -285.76131) (xy 37.606126 -285.804887) (xy 37.62171 -285.851568) (xy 37.629605 -285.900145)
			(xy 37.6301 -285.924752) (xy 37.969202 -285.924752) (xy 37.973162 -285.875698) (xy 37.984939 -285.827914)
			(xy 38.00423 -285.782638) (xy 38.030533 -285.741042) (xy 38.063168 -285.704205) (xy 38.101289 -285.67308)
			(xy 38.14391 -285.648473) (xy 38.189926 -285.631021) (xy 38.238145 -285.621177) (xy 38.28732 -285.619196)
			(xy 38.336175 -285.625128) (xy 38.383446 -285.63882) (xy 38.427908 -285.659918) (xy 38.468411 -285.687874)
			(xy 38.503904 -285.721966) (xy 38.533469 -285.76131) (xy 38.55634 -285.804887) (xy 38.571924 -285.851568)
			(xy 38.579819 -285.900145) (xy 38.580314 -285.924752) (xy 38.919162 -285.924752) (xy 38.923122 -285.875698)
			(xy 38.934899 -285.827914) (xy 38.95419 -285.782638) (xy 38.980493 -285.741042) (xy 39.013128 -285.704205)
			(xy 39.051249 -285.67308) (xy 39.09387 -285.648473) (xy 39.139886 -285.631021) (xy 39.188105 -285.621177)
			(xy 39.23728 -285.619196) (xy 39.286135 -285.625128) (xy 39.333406 -285.63882) (xy 39.377868 -285.659918)
			(xy 39.418371 -285.687874) (xy 39.453864 -285.721966) (xy 39.483429 -285.76131) (xy 39.5063 -285.804887)
			(xy 39.521884 -285.851568) (xy 39.529779 -285.900145) (xy 39.530274 -285.924752) (xy 39.869122 -285.924752)
			(xy 39.873082 -285.875698) (xy 39.884859 -285.827914) (xy 39.90415 -285.782638) (xy 39.930453 -285.741042)
			(xy 39.963088 -285.704205) (xy 40.001209 -285.67308) (xy 40.04383 -285.648473) (xy 40.089846 -285.631021)
			(xy 40.138065 -285.621177) (xy 40.18724 -285.619196) (xy 40.236095 -285.625128) (xy 40.283366 -285.63882)
			(xy 40.327828 -285.659918) (xy 40.368331 -285.687874) (xy 40.403824 -285.721966) (xy 40.433389 -285.76131)
			(xy 40.45626 -285.804887) (xy 40.471844 -285.851568) (xy 40.479739 -285.900145) (xy 40.480234 -285.924752)
			(xy 40.819082 -285.924752) (xy 40.823042 -285.875698) (xy 40.834819 -285.827914) (xy 40.85411 -285.782638)
			(xy 40.880413 -285.741042) (xy 40.913048 -285.704205) (xy 40.951169 -285.67308) (xy 40.99379 -285.648473)
			(xy 41.039806 -285.631021) (xy 41.088025 -285.621177) (xy 41.1372 -285.619196) (xy 41.186055 -285.625128)
			(xy 41.233326 -285.63882) (xy 41.277788 -285.659918) (xy 41.318291 -285.687874) (xy 41.353784 -285.721966)
			(xy 41.383349 -285.76131) (xy 41.40622 -285.804887) (xy 41.421804 -285.851568) (xy 41.429699 -285.900145)
			(xy 41.430194 -285.924752) (xy 44.619176 -285.924752) (xy 44.623136 -285.875698) (xy 44.634913 -285.827914)
			(xy 44.654204 -285.782638) (xy 44.680507 -285.741042) (xy 44.713142 -285.704205) (xy 44.751263 -285.67308)
			(xy 44.793884 -285.648473) (xy 44.8399 -285.631021) (xy 44.888119 -285.621177) (xy 44.937294 -285.619196)
			(xy 44.986149 -285.625128) (xy 45.03342 -285.63882) (xy 45.077882 -285.659918) (xy 45.118385 -285.687874)
			(xy 45.153878 -285.721966) (xy 45.183443 -285.76131) (xy 45.206314 -285.804887) (xy 45.221898 -285.851568)
			(xy 45.229793 -285.900145) (xy 45.230288 -285.924752) (xy 45.569136 -285.924752) (xy 45.573096 -285.875698)
			(xy 45.584873 -285.827914) (xy 45.604164 -285.782638) (xy 45.630467 -285.741042) (xy 45.663102 -285.704205)
			(xy 45.701223 -285.67308) (xy 45.743844 -285.648473) (xy 45.78986 -285.631021) (xy 45.838079 -285.621177)
			(xy 45.887254 -285.619196) (xy 45.936109 -285.625128) (xy 45.98338 -285.63882) (xy 46.027842 -285.659918)
			(xy 46.068345 -285.687874) (xy 46.103838 -285.721966) (xy 46.133403 -285.76131) (xy 46.156274 -285.804887)
			(xy 46.171858 -285.851568) (xy 46.179753 -285.900145) (xy 46.180248 -285.924752) (xy 46.519096 -285.924752)
			(xy 46.523056 -285.875698) (xy 46.534833 -285.827914) (xy 46.554124 -285.782638) (xy 46.580427 -285.741042)
			(xy 46.613062 -285.704205) (xy 46.651183 -285.67308) (xy 46.693804 -285.648473) (xy 46.73982 -285.631021)
			(xy 46.788039 -285.621177) (xy 46.837214 -285.619196) (xy 46.886069 -285.625128) (xy 46.93334 -285.63882)
			(xy 46.977802 -285.659918) (xy 47.018305 -285.687874) (xy 47.053798 -285.721966) (xy 47.083363 -285.76131)
			(xy 47.106234 -285.804887) (xy 47.121818 -285.851568) (xy 47.129713 -285.900145) (xy 47.130208 -285.924752)
			(xy 47.469056 -285.924752) (xy 47.473016 -285.875698) (xy 47.484793 -285.827914) (xy 47.504084 -285.782638)
			(xy 47.530387 -285.741042) (xy 47.563022 -285.704205) (xy 47.601143 -285.67308) (xy 47.643764 -285.648473)
			(xy 47.68978 -285.631021) (xy 47.737999 -285.621177) (xy 47.787174 -285.619196) (xy 47.836029 -285.625128)
			(xy 47.8833 -285.63882) (xy 47.927762 -285.659918) (xy 47.968265 -285.687874) (xy 48.003758 -285.721966)
			(xy 48.033323 -285.76131) (xy 48.056194 -285.804887) (xy 48.071778 -285.851568) (xy 48.079673 -285.900145)
			(xy 48.080168 -285.924752) (xy 48.419016 -285.924752) (xy 48.422976 -285.875698) (xy 48.434753 -285.827914)
			(xy 48.454044 -285.782638) (xy 48.480347 -285.741042) (xy 48.512982 -285.704205) (xy 48.551103 -285.67308)
			(xy 48.593724 -285.648473) (xy 48.63974 -285.631021) (xy 48.687959 -285.621177) (xy 48.737134 -285.619196)
			(xy 48.785989 -285.625128) (xy 48.83326 -285.63882) (xy 48.877722 -285.659918) (xy 48.918225 -285.687874)
			(xy 48.953718 -285.721966) (xy 48.983283 -285.76131) (xy 49.006154 -285.804887) (xy 49.021738 -285.851568)
			(xy 49.029633 -285.900145) (xy 49.030128 -285.924752) (xy 49.368976 -285.924752) (xy 49.372936 -285.875698)
			(xy 49.384713 -285.827914) (xy 49.404004 -285.782638) (xy 49.430307 -285.741042) (xy 49.462942 -285.704205)
			(xy 49.501063 -285.67308) (xy 49.543684 -285.648473) (xy 49.5897 -285.631021) (xy 49.637919 -285.621177)
			(xy 49.687094 -285.619196) (xy 49.735949 -285.625128) (xy 49.78322 -285.63882) (xy 49.827682 -285.659918)
			(xy 49.868185 -285.687874) (xy 49.903678 -285.721966) (xy 49.933243 -285.76131) (xy 49.956114 -285.804887)
			(xy 49.971698 -285.851568) (xy 49.979593 -285.900145) (xy 49.980088 -285.924752) (xy 50.31919 -285.924752)
			(xy 50.32315 -285.875698) (xy 50.334927 -285.827914) (xy 50.354218 -285.782638) (xy 50.380521 -285.741042)
			(xy 50.413156 -285.704205) (xy 50.451277 -285.67308) (xy 50.493898 -285.648473) (xy 50.539914 -285.631021)
			(xy 50.588133 -285.621177) (xy 50.637308 -285.619196) (xy 50.686163 -285.625128) (xy 50.733434 -285.63882)
			(xy 50.777896 -285.659918) (xy 50.818399 -285.687874) (xy 50.853892 -285.721966) (xy 50.883457 -285.76131)
			(xy 50.906328 -285.804887) (xy 50.921912 -285.851568) (xy 50.929807 -285.900145) (xy 50.930302 -285.924752)
			(xy 51.26915 -285.924752) (xy 51.27311 -285.875698) (xy 51.284887 -285.827914) (xy 51.304178 -285.782638)
			(xy 51.330481 -285.741042) (xy 51.363116 -285.704205) (xy 51.401237 -285.67308) (xy 51.443858 -285.648473)
			(xy 51.489874 -285.631021) (xy 51.538093 -285.621177) (xy 51.587268 -285.619196) (xy 51.636123 -285.625128)
			(xy 51.683394 -285.63882) (xy 51.727856 -285.659918) (xy 51.768359 -285.687874) (xy 51.803852 -285.721966)
			(xy 51.833417 -285.76131) (xy 51.856288 -285.804887) (xy 51.871872 -285.851568) (xy 51.879767 -285.900145)
			(xy 51.880262 -285.924752) (xy 52.21911 -285.924752) (xy 52.22307 -285.875698) (xy 52.234847 -285.827914)
			(xy 52.254138 -285.782638) (xy 52.280441 -285.741042) (xy 52.313076 -285.704205) (xy 52.351197 -285.67308)
			(xy 52.393818 -285.648473) (xy 52.439834 -285.631021) (xy 52.488053 -285.621177) (xy 52.537228 -285.619196)
			(xy 52.586083 -285.625128) (xy 52.633354 -285.63882) (xy 52.677816 -285.659918) (xy 52.718319 -285.687874)
			(xy 52.753812 -285.721966) (xy 52.783377 -285.76131) (xy 52.806248 -285.804887) (xy 52.821832 -285.851568)
			(xy 52.829727 -285.900145) (xy 52.830222 -285.924752) (xy 53.16907 -285.924752) (xy 53.17303 -285.875698)
			(xy 53.184807 -285.827914) (xy 53.204098 -285.782638) (xy 53.230401 -285.741042) (xy 53.263036 -285.704205)
			(xy 53.301157 -285.67308) (xy 53.343778 -285.648473) (xy 53.389794 -285.631021) (xy 53.438013 -285.621177)
			(xy 53.487188 -285.619196) (xy 53.536043 -285.625128) (xy 53.583314 -285.63882) (xy 53.627776 -285.659918)
			(xy 53.668279 -285.687874) (xy 53.703772 -285.721966) (xy 53.733337 -285.76131) (xy 53.756208 -285.804887)
			(xy 53.771792 -285.851568) (xy 53.779687 -285.900145) (xy 53.780182 -285.924752) (xy 54.11903 -285.924752)
			(xy 54.12299 -285.875698) (xy 54.134767 -285.827914) (xy 54.154058 -285.782638) (xy 54.180361 -285.741042)
			(xy 54.212996 -285.704205) (xy 54.251117 -285.67308) (xy 54.293738 -285.648473) (xy 54.339754 -285.631021)
			(xy 54.387973 -285.621177) (xy 54.437148 -285.619196) (xy 54.486003 -285.625128) (xy 54.533274 -285.63882)
			(xy 54.577736 -285.659918) (xy 54.618239 -285.687874) (xy 54.653732 -285.721966) (xy 54.683297 -285.76131)
			(xy 54.706168 -285.804887) (xy 54.721752 -285.851568) (xy 54.729647 -285.900145) (xy 54.730142 -285.924752)
			(xy 55.06899 -285.924752) (xy 55.07295 -285.875698) (xy 55.084727 -285.827914) (xy 55.104018 -285.782638)
			(xy 55.130321 -285.741042) (xy 55.162956 -285.704205) (xy 55.201077 -285.67308) (xy 55.243698 -285.648473)
			(xy 55.289714 -285.631021) (xy 55.337933 -285.621177) (xy 55.387108 -285.619196) (xy 55.435963 -285.625128)
			(xy 55.483234 -285.63882) (xy 55.527696 -285.659918) (xy 55.568199 -285.687874) (xy 55.603692 -285.721966)
			(xy 55.633257 -285.76131) (xy 55.656128 -285.804887) (xy 55.671712 -285.851568) (xy 55.679607 -285.900145)
			(xy 55.680102 -285.924752) (xy 56.01895 -285.924752) (xy 56.02291 -285.875698) (xy 56.034687 -285.827914)
			(xy 56.053978 -285.782638) (xy 56.080281 -285.741042) (xy 56.112916 -285.704205) (xy 56.151037 -285.67308)
			(xy 56.193658 -285.648473) (xy 56.239674 -285.631021) (xy 56.287893 -285.621177) (xy 56.337068 -285.619196)
			(xy 56.385923 -285.625128) (xy 56.433194 -285.63882) (xy 56.477656 -285.659918) (xy 56.518159 -285.687874)
			(xy 56.553652 -285.721966) (xy 56.583217 -285.76131) (xy 56.606088 -285.804887) (xy 56.621672 -285.851568)
			(xy 56.629567 -285.900145) (xy 56.630062 -285.924752) (xy 56.969164 -285.924752) (xy 56.973124 -285.875698)
			(xy 56.984901 -285.827914) (xy 57.004192 -285.782638) (xy 57.030495 -285.741042) (xy 57.06313 -285.704205)
			(xy 57.101251 -285.67308) (xy 57.143872 -285.648473) (xy 57.189888 -285.631021) (xy 57.238107 -285.621177)
			(xy 57.287282 -285.619196) (xy 57.336137 -285.625128) (xy 57.383408 -285.63882) (xy 57.42787 -285.659918)
			(xy 57.468373 -285.687874) (xy 57.503866 -285.721966) (xy 57.533431 -285.76131) (xy 57.556302 -285.804887)
			(xy 57.571886 -285.851568) (xy 57.579781 -285.900145) (xy 57.580276 -285.924752) (xy 57.919124 -285.924752)
			(xy 57.923084 -285.875698) (xy 57.934861 -285.827914) (xy 57.954152 -285.782638) (xy 57.980455 -285.741042)
			(xy 58.01309 -285.704205) (xy 58.051211 -285.67308) (xy 58.093832 -285.648473) (xy 58.139848 -285.631021)
			(xy 58.188067 -285.621177) (xy 58.237242 -285.619196) (xy 58.286097 -285.625128) (xy 58.333368 -285.63882)
			(xy 58.37783 -285.659918) (xy 58.418333 -285.687874) (xy 58.453826 -285.721966) (xy 58.483391 -285.76131)
			(xy 58.506262 -285.804887) (xy 58.521846 -285.851568) (xy 58.529741 -285.900145) (xy 58.530236 -285.924752)
			(xy 59.819044 -285.924752) (xy 59.823004 -285.875698) (xy 59.834781 -285.827914) (xy 59.854072 -285.782638)
			(xy 59.880375 -285.741042) (xy 59.91301 -285.704205) (xy 59.951131 -285.67308) (xy 59.993752 -285.648473)
			(xy 60.039768 -285.631021) (xy 60.087987 -285.621177) (xy 60.137162 -285.619196) (xy 60.186017 -285.625128)
			(xy 60.233288 -285.63882) (xy 60.27775 -285.659918) (xy 60.318253 -285.687874) (xy 60.353746 -285.721966)
			(xy 60.383311 -285.76131) (xy 60.406182 -285.804887) (xy 60.421766 -285.851568) (xy 60.429661 -285.900145)
			(xy 60.430156 -285.924752) (xy 60.769004 -285.924752) (xy 60.772964 -285.875698) (xy 60.784741 -285.827914)
			(xy 60.804032 -285.782638) (xy 60.830335 -285.741042) (xy 60.86297 -285.704205) (xy 60.901091 -285.67308)
			(xy 60.943712 -285.648473) (xy 60.989728 -285.631021) (xy 61.037947 -285.621177) (xy 61.087122 -285.619196)
			(xy 61.135977 -285.625128) (xy 61.183248 -285.63882) (xy 61.22771 -285.659918) (xy 61.268213 -285.687874)
			(xy 61.303706 -285.721966) (xy 61.333271 -285.76131) (xy 61.356142 -285.804887) (xy 61.371726 -285.851568)
			(xy 61.379621 -285.900145) (xy 61.380116 -285.924752) (xy 61.718964 -285.924752) (xy 61.722924 -285.875698)
			(xy 61.734701 -285.827914) (xy 61.753992 -285.782638) (xy 61.780295 -285.741042) (xy 61.81293 -285.704205)
			(xy 61.851051 -285.67308) (xy 61.893672 -285.648473) (xy 61.939688 -285.631021) (xy 61.987907 -285.621177)
			(xy 62.037082 -285.619196) (xy 62.085937 -285.625128) (xy 62.133208 -285.63882) (xy 62.17767 -285.659918)
			(xy 62.218173 -285.687874) (xy 62.253666 -285.721966) (xy 62.283231 -285.76131) (xy 62.306102 -285.804887)
			(xy 62.321686 -285.851568) (xy 62.329581 -285.900145) (xy 62.330076 -285.924752) (xy 62.669178 -285.924752)
			(xy 62.673138 -285.875698) (xy 62.684915 -285.827914) (xy 62.704206 -285.782638) (xy 62.730509 -285.741042)
			(xy 62.763144 -285.704205) (xy 62.801265 -285.67308) (xy 62.843886 -285.648473) (xy 62.889902 -285.631021)
			(xy 62.938121 -285.621177) (xy 62.987296 -285.619196) (xy 63.036151 -285.625128) (xy 63.083422 -285.63882)
			(xy 63.127884 -285.659918) (xy 63.168387 -285.687874) (xy 63.20388 -285.721966) (xy 63.233445 -285.76131)
			(xy 63.256316 -285.804887) (xy 63.2719 -285.851568) (xy 63.279795 -285.900145) (xy 63.28029 -285.924752)
			(xy 63.619138 -285.924752) (xy 63.623098 -285.875698) (xy 63.634875 -285.827914) (xy 63.654166 -285.782638)
			(xy 63.680469 -285.741042) (xy 63.713104 -285.704205) (xy 63.751225 -285.67308) (xy 63.793846 -285.648473)
			(xy 63.839862 -285.631021) (xy 63.888081 -285.621177) (xy 63.937256 -285.619196) (xy 63.986111 -285.625128)
			(xy 64.033382 -285.63882) (xy 64.077844 -285.659918) (xy 64.118347 -285.687874) (xy 64.15384 -285.721966)
			(xy 64.183405 -285.76131) (xy 64.206276 -285.804887) (xy 64.22186 -285.851568) (xy 64.229755 -285.900145)
			(xy 64.23025 -285.924752) (xy 64.569098 -285.924752) (xy 64.573058 -285.875698) (xy 64.584835 -285.827914)
			(xy 64.604126 -285.782638) (xy 64.630429 -285.741042) (xy 64.663064 -285.704205) (xy 64.701185 -285.67308)
			(xy 64.743806 -285.648473) (xy 64.789822 -285.631021) (xy 64.838041 -285.621177) (xy 64.887216 -285.619196)
			(xy 64.936071 -285.625128) (xy 64.983342 -285.63882) (xy 65.027804 -285.659918) (xy 65.068307 -285.687874)
			(xy 65.1038 -285.721966) (xy 65.133365 -285.76131) (xy 65.156236 -285.804887) (xy 65.17182 -285.851568)
			(xy 65.179715 -285.900145) (xy 65.18021 -285.924752) (xy 65.519058 -285.924752) (xy 65.523018 -285.875698)
			(xy 65.534795 -285.827914) (xy 65.554086 -285.782638) (xy 65.580389 -285.741042) (xy 65.613024 -285.704205)
			(xy 65.651145 -285.67308) (xy 65.693766 -285.648473) (xy 65.739782 -285.631021) (xy 65.788001 -285.621177)
			(xy 65.837176 -285.619196) (xy 65.886031 -285.625128) (xy 65.933302 -285.63882) (xy 65.977764 -285.659918)
			(xy 66.018267 -285.687874) (xy 66.05376 -285.721966) (xy 66.083325 -285.76131) (xy 66.106196 -285.804887)
			(xy 66.12178 -285.851568) (xy 66.129675 -285.900145) (xy 66.13017 -285.924752) (xy 66.469018 -285.924752)
			(xy 66.472978 -285.875698) (xy 66.484755 -285.827914) (xy 66.504046 -285.782638) (xy 66.530349 -285.741042)
			(xy 66.562984 -285.704205) (xy 66.601105 -285.67308) (xy 66.643726 -285.648473) (xy 66.689742 -285.631021)
			(xy 66.737961 -285.621177) (xy 66.787136 -285.619196) (xy 66.835991 -285.625128) (xy 66.883262 -285.63882)
			(xy 66.927724 -285.659918) (xy 66.968227 -285.687874) (xy 67.00372 -285.721966) (xy 67.033285 -285.76131)
			(xy 67.056156 -285.804887) (xy 67.07174 -285.851568) (xy 67.079635 -285.900145) (xy 67.08013 -285.924752)
			(xy 67.418978 -285.924752) (xy 67.422938 -285.875698) (xy 67.434715 -285.827914) (xy 67.454006 -285.782638)
			(xy 67.480309 -285.741042) (xy 67.512944 -285.704205) (xy 67.551065 -285.67308) (xy 67.593686 -285.648473)
			(xy 67.639702 -285.631021) (xy 67.687921 -285.621177) (xy 67.737096 -285.619196) (xy 67.785951 -285.625128)
			(xy 67.833222 -285.63882) (xy 67.877684 -285.659918) (xy 67.918187 -285.687874) (xy 67.95368 -285.721966)
			(xy 67.983245 -285.76131) (xy 68.006116 -285.804887) (xy 68.0217 -285.851568) (xy 68.029595 -285.900145)
			(xy 68.03009 -285.924752) (xy 68.368938 -285.924752) (xy 68.372898 -285.875698) (xy 68.384675 -285.827914)
			(xy 68.403966 -285.782638) (xy 68.430269 -285.741042) (xy 68.462904 -285.704205) (xy 68.501025 -285.67308)
			(xy 68.543646 -285.648473) (xy 68.589662 -285.631021) (xy 68.637881 -285.621177) (xy 68.687056 -285.619196)
			(xy 68.735911 -285.625128) (xy 68.783182 -285.63882) (xy 68.827644 -285.659918) (xy 68.868147 -285.687874)
			(xy 68.90364 -285.721966) (xy 68.933205 -285.76131) (xy 68.956076 -285.804887) (xy 68.97166 -285.851568)
			(xy 68.979555 -285.900145) (xy 68.98005 -285.924752) (xy 69.319152 -285.924752) (xy 69.323112 -285.875698)
			(xy 69.334889 -285.827914) (xy 69.35418 -285.782638) (xy 69.380483 -285.741042) (xy 69.413118 -285.704205)
			(xy 69.451239 -285.67308) (xy 69.49386 -285.648473) (xy 69.539876 -285.631021) (xy 69.588095 -285.621177)
			(xy 69.63727 -285.619196) (xy 69.686125 -285.625128) (xy 69.733396 -285.63882) (xy 69.777858 -285.659918)
			(xy 69.818361 -285.687874) (xy 69.853854 -285.721966) (xy 69.883419 -285.76131) (xy 69.90629 -285.804887)
			(xy 69.921874 -285.851568) (xy 69.929769 -285.900145) (xy 69.930264 -285.924752) (xy 70.269112 -285.924752)
			(xy 70.273072 -285.875698) (xy 70.284849 -285.827914) (xy 70.30414 -285.782638) (xy 70.330443 -285.741042)
			(xy 70.363078 -285.704205) (xy 70.401199 -285.67308) (xy 70.44382 -285.648473) (xy 70.489836 -285.631021)
			(xy 70.538055 -285.621177) (xy 70.58723 -285.619196) (xy 70.636085 -285.625128) (xy 70.683356 -285.63882)
			(xy 70.727818 -285.659918) (xy 70.768321 -285.687874) (xy 70.803814 -285.721966) (xy 70.833379 -285.76131)
			(xy 70.85625 -285.804887) (xy 70.871834 -285.851568) (xy 70.879729 -285.900145) (xy 70.880224 -285.924752)
			(xy 70.879729 -285.949359) (xy 70.871834 -285.997936) (xy 70.85625 -286.044617) (xy 70.833379 -286.088194)
			(xy 70.803814 -286.127538) (xy 70.768321 -286.16163) (xy 70.727818 -286.189586) (xy 70.683356 -286.210684)
			(xy 70.636085 -286.224376) (xy 70.58723 -286.230308) (xy 70.538055 -286.228327) (xy 70.489836 -286.218483)
			(xy 70.44382 -286.201031) (xy 70.401199 -286.176424) (xy 70.363078 -286.145299) (xy 70.330443 -286.108462)
			(xy 70.30414 -286.066866) (xy 70.284849 -286.02159) (xy 70.273072 -285.973806) (xy 70.269112 -285.924752)
			(xy 69.930264 -285.924752) (xy 69.929769 -285.949359) (xy 69.921874 -285.997936) (xy 69.90629 -286.044617)
			(xy 69.883419 -286.088194) (xy 69.853854 -286.127538) (xy 69.818361 -286.16163) (xy 69.777858 -286.189586)
			(xy 69.733396 -286.210684) (xy 69.686125 -286.224376) (xy 69.63727 -286.230308) (xy 69.588095 -286.228327)
			(xy 69.539876 -286.218483) (xy 69.49386 -286.201031) (xy 69.451239 -286.176424) (xy 69.413118 -286.145299)
			(xy 69.380483 -286.108462) (xy 69.35418 -286.066866) (xy 69.334889 -286.02159) (xy 69.323112 -285.973806)
			(xy 69.319152 -285.924752) (xy 68.98005 -285.924752) (xy 68.979555 -285.949359) (xy 68.97166 -285.997936)
			(xy 68.956076 -286.044617) (xy 68.933205 -286.088194) (xy 68.90364 -286.127538) (xy 68.868147 -286.16163)
			(xy 68.827644 -286.189586) (xy 68.783182 -286.210684) (xy 68.735911 -286.224376) (xy 68.687056 -286.230308)
			(xy 68.637881 -286.228327) (xy 68.589662 -286.218483) (xy 68.543646 -286.201031) (xy 68.501025 -286.176424)
			(xy 68.462904 -286.145299) (xy 68.430269 -286.108462) (xy 68.403966 -286.066866) (xy 68.384675 -286.02159)
			(xy 68.372898 -285.973806) (xy 68.368938 -285.924752) (xy 68.03009 -285.924752) (xy 68.029595 -285.949359)
			(xy 68.0217 -285.997936) (xy 68.006116 -286.044617) (xy 67.983245 -286.088194) (xy 67.95368 -286.127538)
			(xy 67.918187 -286.16163) (xy 67.877684 -286.189586) (xy 67.833222 -286.210684) (xy 67.785951 -286.224376)
			(xy 67.737096 -286.230308) (xy 67.687921 -286.228327) (xy 67.639702 -286.218483) (xy 67.593686 -286.201031)
			(xy 67.551065 -286.176424) (xy 67.512944 -286.145299) (xy 67.480309 -286.108462) (xy 67.454006 -286.066866)
			(xy 67.434715 -286.02159) (xy 67.422938 -285.973806) (xy 67.418978 -285.924752) (xy 67.08013 -285.924752)
			(xy 67.079635 -285.949359) (xy 67.07174 -285.997936) (xy 67.056156 -286.044617) (xy 67.033285 -286.088194)
			(xy 67.00372 -286.127538) (xy 66.968227 -286.16163) (xy 66.927724 -286.189586) (xy 66.883262 -286.210684)
			(xy 66.835991 -286.224376) (xy 66.787136 -286.230308) (xy 66.737961 -286.228327) (xy 66.689742 -286.218483)
			(xy 66.643726 -286.201031) (xy 66.601105 -286.176424) (xy 66.562984 -286.145299) (xy 66.530349 -286.108462)
			(xy 66.504046 -286.066866) (xy 66.484755 -286.02159) (xy 66.472978 -285.973806) (xy 66.469018 -285.924752)
			(xy 66.13017 -285.924752) (xy 66.129675 -285.949359) (xy 66.12178 -285.997936) (xy 66.106196 -286.044617)
			(xy 66.083325 -286.088194) (xy 66.05376 -286.127538) (xy 66.018267 -286.16163) (xy 65.977764 -286.189586)
			(xy 65.933302 -286.210684) (xy 65.886031 -286.224376) (xy 65.837176 -286.230308) (xy 65.788001 -286.228327)
			(xy 65.739782 -286.218483) (xy 65.693766 -286.201031) (xy 65.651145 -286.176424) (xy 65.613024 -286.145299)
			(xy 65.580389 -286.108462) (xy 65.554086 -286.066866) (xy 65.534795 -286.02159) (xy 65.523018 -285.973806)
			(xy 65.519058 -285.924752) (xy 65.18021 -285.924752) (xy 65.179715 -285.949359) (xy 65.17182 -285.997936)
			(xy 65.156236 -286.044617) (xy 65.133365 -286.088194) (xy 65.1038 -286.127538) (xy 65.068307 -286.16163)
			(xy 65.027804 -286.189586) (xy 64.983342 -286.210684) (xy 64.936071 -286.224376) (xy 64.887216 -286.230308)
			(xy 64.838041 -286.228327) (xy 64.789822 -286.218483) (xy 64.743806 -286.201031) (xy 64.701185 -286.176424)
			(xy 64.663064 -286.145299) (xy 64.630429 -286.108462) (xy 64.604126 -286.066866) (xy 64.584835 -286.02159)
			(xy 64.573058 -285.973806) (xy 64.569098 -285.924752) (xy 64.23025 -285.924752) (xy 64.229755 -285.949359)
			(xy 64.22186 -285.997936) (xy 64.206276 -286.044617) (xy 64.183405 -286.088194) (xy 64.15384 -286.127538)
			(xy 64.118347 -286.16163) (xy 64.077844 -286.189586) (xy 64.033382 -286.210684) (xy 63.986111 -286.224376)
			(xy 63.937256 -286.230308) (xy 63.888081 -286.228327) (xy 63.839862 -286.218483) (xy 63.793846 -286.201031)
			(xy 63.751225 -286.176424) (xy 63.713104 -286.145299) (xy 63.680469 -286.108462) (xy 63.654166 -286.066866)
			(xy 63.634875 -286.02159) (xy 63.623098 -285.973806) (xy 63.619138 -285.924752) (xy 63.28029 -285.924752)
			(xy 63.279795 -285.949359) (xy 63.2719 -285.997936) (xy 63.256316 -286.044617) (xy 63.233445 -286.088194)
			(xy 63.20388 -286.127538) (xy 63.168387 -286.16163) (xy 63.127884 -286.189586) (xy 63.083422 -286.210684)
			(xy 63.036151 -286.224376) (xy 62.987296 -286.230308) (xy 62.938121 -286.228327) (xy 62.889902 -286.218483)
			(xy 62.843886 -286.201031) (xy 62.801265 -286.176424) (xy 62.763144 -286.145299) (xy 62.730509 -286.108462)
			(xy 62.704206 -286.066866) (xy 62.684915 -286.02159) (xy 62.673138 -285.973806) (xy 62.669178 -285.924752)
			(xy 62.330076 -285.924752) (xy 62.329581 -285.949359) (xy 62.321686 -285.997936) (xy 62.306102 -286.044617)
			(xy 62.283231 -286.088194) (xy 62.253666 -286.127538) (xy 62.218173 -286.16163) (xy 62.17767 -286.189586)
			(xy 62.133208 -286.210684) (xy 62.085937 -286.224376) (xy 62.037082 -286.230308) (xy 61.987907 -286.228327)
			(xy 61.939688 -286.218483) (xy 61.893672 -286.201031) (xy 61.851051 -286.176424) (xy 61.81293 -286.145299)
			(xy 61.780295 -286.108462) (xy 61.753992 -286.066866) (xy 61.734701 -286.02159) (xy 61.722924 -285.973806)
			(xy 61.718964 -285.924752) (xy 61.380116 -285.924752) (xy 61.379621 -285.949359) (xy 61.371726 -285.997936)
			(xy 61.356142 -286.044617) (xy 61.333271 -286.088194) (xy 61.303706 -286.127538) (xy 61.268213 -286.16163)
			(xy 61.22771 -286.189586) (xy 61.183248 -286.210684) (xy 61.135977 -286.224376) (xy 61.087122 -286.230308)
			(xy 61.037947 -286.228327) (xy 60.989728 -286.218483) (xy 60.943712 -286.201031) (xy 60.901091 -286.176424)
			(xy 60.86297 -286.145299) (xy 60.830335 -286.108462) (xy 60.804032 -286.066866) (xy 60.784741 -286.02159)
			(xy 60.772964 -285.973806) (xy 60.769004 -285.924752) (xy 60.430156 -285.924752) (xy 60.429661 -285.949359)
			(xy 60.421766 -285.997936) (xy 60.406182 -286.044617) (xy 60.383311 -286.088194) (xy 60.353746 -286.127538)
			(xy 60.318253 -286.16163) (xy 60.27775 -286.189586) (xy 60.233288 -286.210684) (xy 60.186017 -286.224376)
			(xy 60.137162 -286.230308) (xy 60.087987 -286.228327) (xy 60.039768 -286.218483) (xy 59.993752 -286.201031)
			(xy 59.951131 -286.176424) (xy 59.91301 -286.145299) (xy 59.880375 -286.108462) (xy 59.854072 -286.066866)
			(xy 59.834781 -286.02159) (xy 59.823004 -285.973806) (xy 59.819044 -285.924752) (xy 58.530236 -285.924752)
			(xy 58.529741 -285.949359) (xy 58.521846 -285.997936) (xy 58.506262 -286.044617) (xy 58.483391 -286.088194)
			(xy 58.453826 -286.127538) (xy 58.418333 -286.16163) (xy 58.37783 -286.189586) (xy 58.333368 -286.210684)
			(xy 58.286097 -286.224376) (xy 58.237242 -286.230308) (xy 58.188067 -286.228327) (xy 58.139848 -286.218483)
			(xy 58.093832 -286.201031) (xy 58.051211 -286.176424) (xy 58.01309 -286.145299) (xy 57.980455 -286.108462)
			(xy 57.954152 -286.066866) (xy 57.934861 -286.02159) (xy 57.923084 -285.973806) (xy 57.919124 -285.924752)
			(xy 57.580276 -285.924752) (xy 57.579781 -285.949359) (xy 57.571886 -285.997936) (xy 57.556302 -286.044617)
			(xy 57.533431 -286.088194) (xy 57.503866 -286.127538) (xy 57.468373 -286.16163) (xy 57.42787 -286.189586)
			(xy 57.383408 -286.210684) (xy 57.336137 -286.224376) (xy 57.287282 -286.230308) (xy 57.238107 -286.228327)
			(xy 57.189888 -286.218483) (xy 57.143872 -286.201031) (xy 57.101251 -286.176424) (xy 57.06313 -286.145299)
			(xy 57.030495 -286.108462) (xy 57.004192 -286.066866) (xy 56.984901 -286.02159) (xy 56.973124 -285.973806)
			(xy 56.969164 -285.924752) (xy 56.630062 -285.924752) (xy 56.629567 -285.949359) (xy 56.621672 -285.997936)
			(xy 56.606088 -286.044617) (xy 56.583217 -286.088194) (xy 56.553652 -286.127538) (xy 56.518159 -286.16163)
			(xy 56.477656 -286.189586) (xy 56.433194 -286.210684) (xy 56.385923 -286.224376) (xy 56.337068 -286.230308)
			(xy 56.287893 -286.228327) (xy 56.239674 -286.218483) (xy 56.193658 -286.201031) (xy 56.151037 -286.176424)
			(xy 56.112916 -286.145299) (xy 56.080281 -286.108462) (xy 56.053978 -286.066866) (xy 56.034687 -286.02159)
			(xy 56.02291 -285.973806) (xy 56.01895 -285.924752) (xy 55.680102 -285.924752) (xy 55.679607 -285.949359)
			(xy 55.671712 -285.997936) (xy 55.656128 -286.044617) (xy 55.633257 -286.088194) (xy 55.603692 -286.127538)
			(xy 55.568199 -286.16163) (xy 55.527696 -286.189586) (xy 55.483234 -286.210684) (xy 55.435963 -286.224376)
			(xy 55.387108 -286.230308) (xy 55.337933 -286.228327) (xy 55.289714 -286.218483) (xy 55.243698 -286.201031)
			(xy 55.201077 -286.176424) (xy 55.162956 -286.145299) (xy 55.130321 -286.108462) (xy 55.104018 -286.066866)
			(xy 55.084727 -286.02159) (xy 55.07295 -285.973806) (xy 55.06899 -285.924752) (xy 54.730142 -285.924752)
			(xy 54.729647 -285.949359) (xy 54.721752 -285.997936) (xy 54.706168 -286.044617) (xy 54.683297 -286.088194)
			(xy 54.653732 -286.127538) (xy 54.618239 -286.16163) (xy 54.577736 -286.189586) (xy 54.533274 -286.210684)
			(xy 54.486003 -286.224376) (xy 54.437148 -286.230308) (xy 54.387973 -286.228327) (xy 54.339754 -286.218483)
			(xy 54.293738 -286.201031) (xy 54.251117 -286.176424) (xy 54.212996 -286.145299) (xy 54.180361 -286.108462)
			(xy 54.154058 -286.066866) (xy 54.134767 -286.02159) (xy 54.12299 -285.973806) (xy 54.11903 -285.924752)
			(xy 53.780182 -285.924752) (xy 53.779687 -285.949359) (xy 53.771792 -285.997936) (xy 53.756208 -286.044617)
			(xy 53.733337 -286.088194) (xy 53.703772 -286.127538) (xy 53.668279 -286.16163) (xy 53.627776 -286.189586)
			(xy 53.583314 -286.210684) (xy 53.536043 -286.224376) (xy 53.487188 -286.230308) (xy 53.438013 -286.228327)
			(xy 53.389794 -286.218483) (xy 53.343778 -286.201031) (xy 53.301157 -286.176424) (xy 53.263036 -286.145299)
			(xy 53.230401 -286.108462) (xy 53.204098 -286.066866) (xy 53.184807 -286.02159) (xy 53.17303 -285.973806)
			(xy 53.16907 -285.924752) (xy 52.830222 -285.924752) (xy 52.829727 -285.949359) (xy 52.821832 -285.997936)
			(xy 52.806248 -286.044617) (xy 52.783377 -286.088194) (xy 52.753812 -286.127538) (xy 52.718319 -286.16163)
			(xy 52.677816 -286.189586) (xy 52.633354 -286.210684) (xy 52.586083 -286.224376) (xy 52.537228 -286.230308)
			(xy 52.488053 -286.228327) (xy 52.439834 -286.218483) (xy 52.393818 -286.201031) (xy 52.351197 -286.176424)
			(xy 52.313076 -286.145299) (xy 52.280441 -286.108462) (xy 52.254138 -286.066866) (xy 52.234847 -286.02159)
			(xy 52.22307 -285.973806) (xy 52.21911 -285.924752) (xy 51.880262 -285.924752) (xy 51.879767 -285.949359)
			(xy 51.871872 -285.997936) (xy 51.856288 -286.044617) (xy 51.833417 -286.088194) (xy 51.803852 -286.127538)
			(xy 51.768359 -286.16163) (xy 51.727856 -286.189586) (xy 51.683394 -286.210684) (xy 51.636123 -286.224376)
			(xy 51.587268 -286.230308) (xy 51.538093 -286.228327) (xy 51.489874 -286.218483) (xy 51.443858 -286.201031)
			(xy 51.401237 -286.176424) (xy 51.363116 -286.145299) (xy 51.330481 -286.108462) (xy 51.304178 -286.066866)
			(xy 51.284887 -286.02159) (xy 51.27311 -285.973806) (xy 51.26915 -285.924752) (xy 50.930302 -285.924752)
			(xy 50.929807 -285.949359) (xy 50.921912 -285.997936) (xy 50.906328 -286.044617) (xy 50.883457 -286.088194)
			(xy 50.853892 -286.127538) (xy 50.818399 -286.16163) (xy 50.777896 -286.189586) (xy 50.733434 -286.210684)
			(xy 50.686163 -286.224376) (xy 50.637308 -286.230308) (xy 50.588133 -286.228327) (xy 50.539914 -286.218483)
			(xy 50.493898 -286.201031) (xy 50.451277 -286.176424) (xy 50.413156 -286.145299) (xy 50.380521 -286.108462)
			(xy 50.354218 -286.066866) (xy 50.334927 -286.02159) (xy 50.32315 -285.973806) (xy 50.31919 -285.924752)
			(xy 49.980088 -285.924752) (xy 49.979593 -285.949359) (xy 49.971698 -285.997936) (xy 49.956114 -286.044617)
			(xy 49.933243 -286.088194) (xy 49.903678 -286.127538) (xy 49.868185 -286.16163) (xy 49.827682 -286.189586)
			(xy 49.78322 -286.210684) (xy 49.735949 -286.224376) (xy 49.687094 -286.230308) (xy 49.637919 -286.228327)
			(xy 49.5897 -286.218483) (xy 49.543684 -286.201031) (xy 49.501063 -286.176424) (xy 49.462942 -286.145299)
			(xy 49.430307 -286.108462) (xy 49.404004 -286.066866) (xy 49.384713 -286.02159) (xy 49.372936 -285.973806)
			(xy 49.368976 -285.924752) (xy 49.030128 -285.924752) (xy 49.029633 -285.949359) (xy 49.021738 -285.997936)
			(xy 49.006154 -286.044617) (xy 48.983283 -286.088194) (xy 48.953718 -286.127538) (xy 48.918225 -286.16163)
			(xy 48.877722 -286.189586) (xy 48.83326 -286.210684) (xy 48.785989 -286.224376) (xy 48.737134 -286.230308)
			(xy 48.687959 -286.228327) (xy 48.63974 -286.218483) (xy 48.593724 -286.201031) (xy 48.551103 -286.176424)
			(xy 48.512982 -286.145299) (xy 48.480347 -286.108462) (xy 48.454044 -286.066866) (xy 48.434753 -286.02159)
			(xy 48.422976 -285.973806) (xy 48.419016 -285.924752) (xy 48.080168 -285.924752) (xy 48.079673 -285.949359)
			(xy 48.071778 -285.997936) (xy 48.056194 -286.044617) (xy 48.033323 -286.088194) (xy 48.003758 -286.127538)
			(xy 47.968265 -286.16163) (xy 47.927762 -286.189586) (xy 47.8833 -286.210684) (xy 47.836029 -286.224376)
			(xy 47.787174 -286.230308) (xy 47.737999 -286.228327) (xy 47.68978 -286.218483) (xy 47.643764 -286.201031)
			(xy 47.601143 -286.176424) (xy 47.563022 -286.145299) (xy 47.530387 -286.108462) (xy 47.504084 -286.066866)
			(xy 47.484793 -286.02159) (xy 47.473016 -285.973806) (xy 47.469056 -285.924752) (xy 47.130208 -285.924752)
			(xy 47.129713 -285.949359) (xy 47.121818 -285.997936) (xy 47.106234 -286.044617) (xy 47.083363 -286.088194)
			(xy 47.053798 -286.127538) (xy 47.018305 -286.16163) (xy 46.977802 -286.189586) (xy 46.93334 -286.210684)
			(xy 46.886069 -286.224376) (xy 46.837214 -286.230308) (xy 46.788039 -286.228327) (xy 46.73982 -286.218483)
			(xy 46.693804 -286.201031) (xy 46.651183 -286.176424) (xy 46.613062 -286.145299) (xy 46.580427 -286.108462)
			(xy 46.554124 -286.066866) (xy 46.534833 -286.02159) (xy 46.523056 -285.973806) (xy 46.519096 -285.924752)
			(xy 46.180248 -285.924752) (xy 46.179753 -285.949359) (xy 46.171858 -285.997936) (xy 46.156274 -286.044617)
			(xy 46.133403 -286.088194) (xy 46.103838 -286.127538) (xy 46.068345 -286.16163) (xy 46.027842 -286.189586)
			(xy 45.98338 -286.210684) (xy 45.936109 -286.224376) (xy 45.887254 -286.230308) (xy 45.838079 -286.228327)
			(xy 45.78986 -286.218483) (xy 45.743844 -286.201031) (xy 45.701223 -286.176424) (xy 45.663102 -286.145299)
			(xy 45.630467 -286.108462) (xy 45.604164 -286.066866) (xy 45.584873 -286.02159) (xy 45.573096 -285.973806)
			(xy 45.569136 -285.924752) (xy 45.230288 -285.924752) (xy 45.229793 -285.949359) (xy 45.221898 -285.997936)
			(xy 45.206314 -286.044617) (xy 45.183443 -286.088194) (xy 45.153878 -286.127538) (xy 45.118385 -286.16163)
			(xy 45.077882 -286.189586) (xy 45.03342 -286.210684) (xy 44.986149 -286.224376) (xy 44.937294 -286.230308)
			(xy 44.888119 -286.228327) (xy 44.8399 -286.218483) (xy 44.793884 -286.201031) (xy 44.751263 -286.176424)
			(xy 44.713142 -286.145299) (xy 44.680507 -286.108462) (xy 44.654204 -286.066866) (xy 44.634913 -286.02159)
			(xy 44.623136 -285.973806) (xy 44.619176 -285.924752) (xy 41.430194 -285.924752) (xy 41.429699 -285.949359)
			(xy 41.421804 -285.997936) (xy 41.40622 -286.044617) (xy 41.383349 -286.088194) (xy 41.353784 -286.127538)
			(xy 41.318291 -286.16163) (xy 41.277788 -286.189586) (xy 41.233326 -286.210684) (xy 41.186055 -286.224376)
			(xy 41.1372 -286.230308) (xy 41.088025 -286.228327) (xy 41.039806 -286.218483) (xy 40.99379 -286.201031)
			(xy 40.951169 -286.176424) (xy 40.913048 -286.145299) (xy 40.880413 -286.108462) (xy 40.85411 -286.066866)
			(xy 40.834819 -286.02159) (xy 40.823042 -285.973806) (xy 40.819082 -285.924752) (xy 40.480234 -285.924752)
			(xy 40.479739 -285.949359) (xy 40.471844 -285.997936) (xy 40.45626 -286.044617) (xy 40.433389 -286.088194)
			(xy 40.403824 -286.127538) (xy 40.368331 -286.16163) (xy 40.327828 -286.189586) (xy 40.283366 -286.210684)
			(xy 40.236095 -286.224376) (xy 40.18724 -286.230308) (xy 40.138065 -286.228327) (xy 40.089846 -286.218483)
			(xy 40.04383 -286.201031) (xy 40.001209 -286.176424) (xy 39.963088 -286.145299) (xy 39.930453 -286.108462)
			(xy 39.90415 -286.066866) (xy 39.884859 -286.02159) (xy 39.873082 -285.973806) (xy 39.869122 -285.924752)
			(xy 39.530274 -285.924752) (xy 39.529779 -285.949359) (xy 39.521884 -285.997936) (xy 39.5063 -286.044617)
			(xy 39.483429 -286.088194) (xy 39.453864 -286.127538) (xy 39.418371 -286.16163) (xy 39.377868 -286.189586)
			(xy 39.333406 -286.210684) (xy 39.286135 -286.224376) (xy 39.23728 -286.230308) (xy 39.188105 -286.228327)
			(xy 39.139886 -286.218483) (xy 39.09387 -286.201031) (xy 39.051249 -286.176424) (xy 39.013128 -286.145299)
			(xy 38.980493 -286.108462) (xy 38.95419 -286.066866) (xy 38.934899 -286.02159) (xy 38.923122 -285.973806)
			(xy 38.919162 -285.924752) (xy 38.580314 -285.924752) (xy 38.579819 -285.949359) (xy 38.571924 -285.997936)
			(xy 38.55634 -286.044617) (xy 38.533469 -286.088194) (xy 38.503904 -286.127538) (xy 38.468411 -286.16163)
			(xy 38.427908 -286.189586) (xy 38.383446 -286.210684) (xy 38.336175 -286.224376) (xy 38.28732 -286.230308)
			(xy 38.238145 -286.228327) (xy 38.189926 -286.218483) (xy 38.14391 -286.201031) (xy 38.101289 -286.176424)
			(xy 38.063168 -286.145299) (xy 38.030533 -286.108462) (xy 38.00423 -286.066866) (xy 37.984939 -286.02159)
			(xy 37.973162 -285.973806) (xy 37.969202 -285.924752) (xy 37.6301 -285.924752) (xy 37.629605 -285.949359)
			(xy 37.62171 -285.997936) (xy 37.606126 -286.044617) (xy 37.583255 -286.088194) (xy 37.55369 -286.127538)
			(xy 37.518197 -286.16163) (xy 37.477694 -286.189586) (xy 37.433232 -286.210684) (xy 37.385961 -286.224376)
			(xy 37.337106 -286.230308) (xy 37.287931 -286.228327) (xy 37.239712 -286.218483) (xy 37.193696 -286.201031)
			(xy 37.151075 -286.176424) (xy 37.112954 -286.145299) (xy 37.080319 -286.108462) (xy 37.054016 -286.066866)
			(xy 37.034725 -286.02159) (xy 37.022948 -285.973806) (xy 37.018988 -285.924752) (xy 36.68014 -285.924752)
			(xy 36.679645 -285.949359) (xy 36.67175 -285.997936) (xy 36.656166 -286.044617) (xy 36.633295 -286.088194)
			(xy 36.60373 -286.127538) (xy 36.568237 -286.16163) (xy 36.527734 -286.189586) (xy 36.483272 -286.210684)
			(xy 36.436001 -286.224376) (xy 36.387146 -286.230308) (xy 36.337971 -286.228327) (xy 36.289752 -286.218483)
			(xy 36.243736 -286.201031) (xy 36.201115 -286.176424) (xy 36.162994 -286.145299) (xy 36.130359 -286.108462)
			(xy 36.104056 -286.066866) (xy 36.084765 -286.02159) (xy 36.072988 -285.973806) (xy 36.069028 -285.924752)
			(xy 1.468374 -285.924752) (xy 1.468374 -286.331914) (xy 25.811478 -286.331914) (xy 25.815549 -286.276292)
			(xy 25.827675 -286.221855) (xy 25.847598 -286.169764) (xy 25.874894 -286.121129) (xy 25.90898 -286.076986)
			(xy 25.949129 -286.038277) (xy 25.994487 -286.005826) (xy 26.044087 -285.980325) (xy 26.096871 -285.962318)
			(xy 26.151714 -285.952188) (xy 26.207448 -285.950151) (xy 26.262885 -285.956251) (xy 26.316842 -285.970357)
			(xy 26.368171 -285.992169) (xy 26.415777 -286.021223) (xy 26.458645 -286.056898) (xy 26.495862 -286.098435)
			(xy 26.526635 -286.144948) (xy 26.550307 -286.195445) (xy 26.566375 -286.248852) (xy 26.574495 -286.304028)
			(xy 26.575004 -286.331914) (xy 27.286964 -286.331914) (xy 27.291035 -286.276292) (xy 27.303161 -286.221855)
			(xy 27.323084 -286.169764) (xy 27.35038 -286.121129) (xy 27.384466 -286.076986) (xy 27.424615 -286.038277)
			(xy 27.469973 -286.005826) (xy 27.519573 -285.980325) (xy 27.572357 -285.962318) (xy 27.6272 -285.952188)
			(xy 27.682934 -285.950151) (xy 27.738371 -285.956251) (xy 27.792328 -285.970357) (xy 27.843657 -285.992169)
			(xy 27.891263 -286.021223) (xy 27.934131 -286.056898) (xy 27.971348 -286.098435) (xy 28.002121 -286.144948)
			(xy 28.025793 -286.195445) (xy 28.041861 -286.248852) (xy 28.049981 -286.304028) (xy 28.05049 -286.331914)
			(xy 28.175964 -286.331914) (xy 28.180035 -286.276292) (xy 28.192161 -286.221855) (xy 28.212084 -286.169764)
			(xy 28.23938 -286.121129) (xy 28.273466 -286.076986) (xy 28.313615 -286.038277) (xy 28.358973 -286.005826)
			(xy 28.408573 -285.980325) (xy 28.461357 -285.962318) (xy 28.5162 -285.952188) (xy 28.571934 -285.950151)
			(xy 28.627371 -285.956251) (xy 28.681328 -285.970357) (xy 28.732657 -285.992169) (xy 28.780263 -286.021223)
			(xy 28.823131 -286.056898) (xy 28.860348 -286.098435) (xy 28.891121 -286.144948) (xy 28.914793 -286.195445)
			(xy 28.930861 -286.248852) (xy 28.938981 -286.304028) (xy 28.93949 -286.331914) (xy 28.938981 -286.3598)
			(xy 28.930861 -286.414976) (xy 28.914793 -286.468383) (xy 28.891121 -286.51888) (xy 28.860348 -286.565393)
			(xy 28.823131 -286.60693) (xy 28.780263 -286.642605) (xy 28.732657 -286.671659) (xy 28.681328 -286.693471)
			(xy 28.627371 -286.707577) (xy 28.571934 -286.713677) (xy 28.5162 -286.71164) (xy 28.461357 -286.70151)
			(xy 28.408573 -286.683503) (xy 28.358973 -286.658002) (xy 28.313615 -286.625551) (xy 28.273466 -286.586842)
			(xy 28.23938 -286.542699) (xy 28.212084 -286.494064) (xy 28.192161 -286.441973) (xy 28.180035 -286.387536)
			(xy 28.175964 -286.331914) (xy 28.05049 -286.331914) (xy 28.049981 -286.3598) (xy 28.041861 -286.414976)
			(xy 28.025793 -286.468383) (xy 28.002121 -286.51888) (xy 27.971348 -286.565393) (xy 27.934131 -286.60693)
			(xy 27.891263 -286.642605) (xy 27.843657 -286.671659) (xy 27.792328 -286.693471) (xy 27.738371 -286.707577)
			(xy 27.682934 -286.713677) (xy 27.6272 -286.71164) (xy 27.572357 -286.70151) (xy 27.519573 -286.683503)
			(xy 27.469973 -286.658002) (xy 27.424615 -286.625551) (xy 27.384466 -286.586842) (xy 27.35038 -286.542699)
			(xy 27.323084 -286.494064) (xy 27.303161 -286.441973) (xy 27.291035 -286.387536) (xy 27.286964 -286.331914)
			(xy 26.575004 -286.331914) (xy 26.574495 -286.3598) (xy 26.566375 -286.414976) (xy 26.550307 -286.468383)
			(xy 26.526635 -286.51888) (xy 26.495862 -286.565393) (xy 26.458645 -286.60693) (xy 26.415777 -286.642605)
			(xy 26.368171 -286.671659) (xy 26.316842 -286.693471) (xy 26.262885 -286.707577) (xy 26.207448 -286.713677)
			(xy 26.151714 -286.71164) (xy 26.096871 -286.70151) (xy 26.044087 -286.683503) (xy 25.994487 -286.658002)
			(xy 25.949129 -286.625551) (xy 25.90898 -286.586842) (xy 25.874894 -286.542699) (xy 25.847598 -286.494064)
			(xy 25.827675 -286.441973) (xy 25.815549 -286.387536) (xy 25.811478 -286.331914) (xy 1.468374 -286.331914)
			(xy 1.468374 -287.131831) (xy 3.23899 -287.131831) (xy 3.23899 -287.077329) (xy 3.246746 -287.023382)
			(xy 3.262101 -286.971087) (xy 3.284742 -286.921511) (xy 3.314208 -286.87566) (xy 3.349899 -286.834471)
			(xy 3.391089 -286.798779) (xy 3.436939 -286.769313) (xy 3.486516 -286.746672) (xy 3.53881 -286.731317)
			(xy 3.592757 -286.72356) (xy 3.620008 -286.723074) (xy 3.647379 -286.723517) (xy 3.70156 -286.731338)
			(xy 3.754064 -286.746831) (xy 3.803811 -286.769679) (xy 3.849776 -286.799409) (xy 3.870706 -286.817054)
			(xy 3.877818 -286.82315) (xy 3.894836 -286.8295) (xy 3.98018 -286.8295) (xy 3.997198 -286.82315)
			(xy 4.00431 -286.817054) (xy 4.025234 -286.799405) (xy 4.071208 -286.769693) (xy 4.120958 -286.746858)
			(xy 4.173461 -286.731369) (xy 4.227638 -286.723545) (xy 4.255008 -286.723074) (xy 4.282261 -286.723533)
			(xy 4.336213 -286.73129) (xy 4.388511 -286.746646) (xy 4.438091 -286.769288) (xy 4.483945 -286.798757)
			(xy 4.525138 -286.83445) (xy 4.560832 -286.875643) (xy 4.590301 -286.921497) (xy 4.612943 -286.971077)
			(xy 4.6283 -287.023376) (xy 4.636057 -287.077327) (xy 4.636057 -287.131831) (xy 5.20038 -287.131831)
			(xy 5.20038 -287.077329) (xy 5.208136 -287.023382) (xy 5.223491 -286.971088) (xy 5.246132 -286.921511)
			(xy 5.275597 -286.875661) (xy 5.311288 -286.834471) (xy 5.352478 -286.79878) (xy 5.398328 -286.769314)
			(xy 5.447904 -286.746672) (xy 5.500198 -286.731317) (xy 5.554145 -286.72356) (xy 5.581396 -286.723074)
			(xy 5.61152 -286.72364) (xy 5.671017 -286.733121) (xy 5.728285 -286.751833) (xy 5.781902 -286.77931)
			(xy 5.830536 -286.81487) (xy 5.85216 -286.83585) (xy 5.859272 -286.843216) (xy 5.878068 -286.850836)
			(xy 5.970524 -286.850836) (xy 5.98932 -286.843216) (xy 5.996432 -286.83585) (xy 6.018072 -286.814886)
			(xy 6.066696 -286.779314) (xy 6.120308 -286.75183) (xy 6.177575 -286.733118) (xy 6.237073 -286.723644)
			(xy 6.267196 -286.723074) (xy 6.294449 -286.723533) (xy 6.348401 -286.73129) (xy 6.400699 -286.746645)
			(xy 6.45028 -286.769288) (xy 6.496134 -286.798756) (xy 6.537328 -286.83445) (xy 6.573022 -286.875643)
			(xy 6.60249 -286.921496) (xy 6.625133 -286.971077) (xy 6.64049 -287.023375) (xy 6.648247 -287.077327)
			(xy 6.648247 -287.093914) (xy 31.338012 -287.093914) (xy 31.338555 -287.064532) (xy 31.347584 -287.006465)
			(xy 31.365415 -286.95047) (xy 31.391626 -286.897875) (xy 31.425597 -286.849924) (xy 31.466521 -286.807752)
			(xy 31.48965 -286.789622) (xy 31.499048 -286.782256) (xy 31.509462 -286.761682) (xy 31.510986 -286.657796)
			(xy 31.50108 -286.636714) (xy 31.491936 -286.629348) (xy 31.470088 -286.611142) (xy 31.431546 -286.569324)
			(xy 31.399638 -286.522249) (xy 31.375071 -286.470959) (xy 31.358388 -286.416591) (xy 31.34996 -286.360349)
			(xy 31.349442 -286.331914) (xy 31.349928 -286.304663) (xy 31.357684 -286.250715) (xy 31.373039 -286.19842)
			(xy 31.395681 -286.148843) (xy 31.425147 -286.102993) (xy 31.460838 -286.061802) (xy 31.502029 -286.026111)
			(xy 31.547879 -285.996645) (xy 31.597456 -285.974003) (xy 31.649751 -285.958648) (xy 31.703699 -285.950892)
			(xy 31.758201 -285.950892) (xy 31.812149 -285.958648) (xy 31.864444 -285.974003) (xy 31.914021 -285.996645)
			(xy 31.959871 -286.026111) (xy 32.001062 -286.061802) (xy 32.036753 -286.102993) (xy 32.066219 -286.148843)
			(xy 32.088861 -286.19842) (xy 32.104216 -286.250715) (xy 32.111972 -286.304663) (xy 32.112458 -286.331914)
			(xy 32.111907 -286.361296) (xy 32.102876 -286.419361) (xy 32.085044 -286.475354) (xy 32.058835 -286.527949)
			(xy 32.024867 -286.5759) (xy 31.983946 -286.618074) (xy 31.96082 -286.636206) (xy 31.951422 -286.643572)
			(xy 31.941008 -286.664146) (xy 31.939484 -286.768032) (xy 31.94939 -286.789114) (xy 31.958534 -286.79648)
			(xy 31.980362 -286.814709) (xy 32.018902 -286.856524) (xy 32.05081 -286.903595) (xy 32.07538 -286.95488)
			(xy 32.092068 -287.009243) (xy 32.100505 -287.065481) (xy 32.101028 -287.093914) (xy 32.734502 -287.093914)
			(xy 32.738573 -287.038292) (xy 32.750699 -286.983855) (xy 32.770622 -286.931764) (xy 32.797918 -286.883129)
			(xy 32.832004 -286.838986) (xy 32.872153 -286.800277) (xy 32.917511 -286.767826) (xy 32.967111 -286.742325)
			(xy 33.019895 -286.724318) (xy 33.074738 -286.714188) (xy 33.130472 -286.712151) (xy 33.185909 -286.718251)
			(xy 33.239866 -286.732357) (xy 33.291195 -286.754169) (xy 33.338801 -286.783223) (xy 33.381669 -286.818898)
			(xy 33.418886 -286.860435) (xy 33.449659 -286.906948) (xy 33.473331 -286.957445) (xy 33.489399 -287.010852)
			(xy 33.497519 -287.066028) (xy 33.498028 -287.093914) (xy 33.620962 -287.093914) (xy 33.625033 -287.038292)
			(xy 33.637159 -286.983855) (xy 33.657082 -286.931764) (xy 33.684378 -286.883129) (xy 33.718464 -286.838986)
			(xy 33.758613 -286.800277) (xy 33.803971 -286.767826) (xy 33.853571 -286.742325) (xy 33.906355 -286.724318)
			(xy 33.961198 -286.714188) (xy 34.016932 -286.712151) (xy 34.072369 -286.718251) (xy 34.126326 -286.732357)
			(xy 34.177655 -286.754169) (xy 34.225261 -286.783223) (xy 34.268129 -286.818898) (xy 34.305346 -286.860435)
			(xy 34.31496 -286.874966) (xy 36.069028 -286.874966) (xy 36.072988 -286.825912) (xy 36.084765 -286.778128)
			(xy 36.104056 -286.732852) (xy 36.130359 -286.691256) (xy 36.162994 -286.654419) (xy 36.201115 -286.623294)
			(xy 36.243736 -286.598687) (xy 36.289752 -286.581235) (xy 36.337971 -286.571391) (xy 36.387146 -286.56941)
			(xy 36.436001 -286.575342) (xy 36.483272 -286.589034) (xy 36.527734 -286.610132) (xy 36.568237 -286.638088)
			(xy 36.60373 -286.67218) (xy 36.633295 -286.711524) (xy 36.656166 -286.755101) (xy 36.67175 -286.801782)
			(xy 36.679645 -286.850359) (xy 36.68014 -286.874966) (xy 37.018988 -286.874966) (xy 37.022948 -286.825912)
			(xy 37.034725 -286.778128) (xy 37.054016 -286.732852) (xy 37.080319 -286.691256) (xy 37.112954 -286.654419)
			(xy 37.151075 -286.623294) (xy 37.193696 -286.598687) (xy 37.239712 -286.581235) (xy 37.287931 -286.571391)
			(xy 37.337106 -286.56941) (xy 37.385961 -286.575342) (xy 37.433232 -286.589034) (xy 37.477694 -286.610132)
			(xy 37.518197 -286.638088) (xy 37.55369 -286.67218) (xy 37.583255 -286.711524) (xy 37.606126 -286.755101)
			(xy 37.62171 -286.801782) (xy 37.629605 -286.850359) (xy 37.6301 -286.874966) (xy 37.969202 -286.874966)
			(xy 37.973162 -286.825912) (xy 37.984939 -286.778128) (xy 38.00423 -286.732852) (xy 38.030533 -286.691256)
			(xy 38.063168 -286.654419) (xy 38.101289 -286.623294) (xy 38.14391 -286.598687) (xy 38.189926 -286.581235)
			(xy 38.238145 -286.571391) (xy 38.28732 -286.56941) (xy 38.336175 -286.575342) (xy 38.383446 -286.589034)
			(xy 38.427908 -286.610132) (xy 38.468411 -286.638088) (xy 38.503904 -286.67218) (xy 38.533469 -286.711524)
			(xy 38.55634 -286.755101) (xy 38.571924 -286.801782) (xy 38.579819 -286.850359) (xy 38.580314 -286.874966)
			(xy 38.919162 -286.874966) (xy 38.923122 -286.825912) (xy 38.934899 -286.778128) (xy 38.95419 -286.732852)
			(xy 38.980493 -286.691256) (xy 39.013128 -286.654419) (xy 39.051249 -286.623294) (xy 39.09387 -286.598687)
			(xy 39.139886 -286.581235) (xy 39.188105 -286.571391) (xy 39.23728 -286.56941) (xy 39.286135 -286.575342)
			(xy 39.333406 -286.589034) (xy 39.377868 -286.610132) (xy 39.418371 -286.638088) (xy 39.453864 -286.67218)
			(xy 39.483429 -286.711524) (xy 39.5063 -286.755101) (xy 39.521884 -286.801782) (xy 39.529779 -286.850359)
			(xy 39.530274 -286.874966) (xy 39.869122 -286.874966) (xy 39.873082 -286.825912) (xy 39.884859 -286.778128)
			(xy 39.90415 -286.732852) (xy 39.930453 -286.691256) (xy 39.963088 -286.654419) (xy 40.001209 -286.623294)
			(xy 40.04383 -286.598687) (xy 40.089846 -286.581235) (xy 40.138065 -286.571391) (xy 40.18724 -286.56941)
			(xy 40.236095 -286.575342) (xy 40.283366 -286.589034) (xy 40.327828 -286.610132) (xy 40.368331 -286.638088)
			(xy 40.403824 -286.67218) (xy 40.433389 -286.711524) (xy 40.45626 -286.755101) (xy 40.471844 -286.801782)
			(xy 40.479739 -286.850359) (xy 40.480234 -286.874966) (xy 40.819082 -286.874966) (xy 40.823042 -286.825912)
			(xy 40.834819 -286.778128) (xy 40.85411 -286.732852) (xy 40.880413 -286.691256) (xy 40.913048 -286.654419)
			(xy 40.951169 -286.623294) (xy 40.99379 -286.598687) (xy 41.039806 -286.581235) (xy 41.088025 -286.571391)
			(xy 41.1372 -286.56941) (xy 41.186055 -286.575342) (xy 41.233326 -286.589034) (xy 41.277788 -286.610132)
			(xy 41.318291 -286.638088) (xy 41.353784 -286.67218) (xy 41.383349 -286.711524) (xy 41.40622 -286.755101)
			(xy 41.421804 -286.801782) (xy 41.429699 -286.850359) (xy 41.430194 -286.874966) (xy 41.769042 -286.874966)
			(xy 41.773002 -286.825912) (xy 41.784779 -286.778128) (xy 41.80407 -286.732852) (xy 41.830373 -286.691256)
			(xy 41.863008 -286.654419) (xy 41.901129 -286.623294) (xy 41.94375 -286.598687) (xy 41.989766 -286.581235)
			(xy 42.037985 -286.571391) (xy 42.08716 -286.56941) (xy 42.136015 -286.575342) (xy 42.183286 -286.589034)
			(xy 42.227748 -286.610132) (xy 42.268251 -286.638088) (xy 42.303744 -286.67218) (xy 42.333309 -286.711524)
			(xy 42.35618 -286.755101) (xy 42.371764 -286.801782) (xy 42.379659 -286.850359) (xy 42.380149 -286.874712)
			(xy 42.719002 -286.874712) (xy 42.722962 -286.825658) (xy 42.734739 -286.777874) (xy 42.75403 -286.732598)
			(xy 42.780333 -286.691002) (xy 42.812968 -286.654165) (xy 42.851089 -286.62304) (xy 42.89371 -286.598433)
			(xy 42.939726 -286.580981) (xy 42.987945 -286.571137) (xy 43.03712 -286.569156) (xy 43.085975 -286.575088)
			(xy 43.133246 -286.58878) (xy 43.177708 -286.609878) (xy 43.218211 -286.637834) (xy 43.253704 -286.671926)
			(xy 43.283269 -286.71127) (xy 43.30614 -286.754847) (xy 43.321724 -286.801528) (xy 43.329619 -286.850105)
			(xy 43.330114 -286.874712) (xy 43.668962 -286.874712) (xy 43.672922 -286.825658) (xy 43.684699 -286.777874)
			(xy 43.70399 -286.732598) (xy 43.730293 -286.691002) (xy 43.762928 -286.654165) (xy 43.801049 -286.62304)
			(xy 43.84367 -286.598433) (xy 43.889686 -286.580981) (xy 43.937905 -286.571137) (xy 43.98708 -286.569156)
			(xy 44.035935 -286.575088) (xy 44.083206 -286.58878) (xy 44.127668 -286.609878) (xy 44.168171 -286.637834)
			(xy 44.203664 -286.671926) (xy 44.233229 -286.71127) (xy 44.2561 -286.754847) (xy 44.271684 -286.801528)
			(xy 44.279579 -286.850105) (xy 44.280074 -286.874712) (xy 44.280069 -286.874966) (xy 44.619176 -286.874966)
			(xy 44.623136 -286.825912) (xy 44.634913 -286.778128) (xy 44.654204 -286.732852) (xy 44.680507 -286.691256)
			(xy 44.713142 -286.654419) (xy 44.751263 -286.623294) (xy 44.793884 -286.598687) (xy 44.8399 -286.581235)
			(xy 44.888119 -286.571391) (xy 44.937294 -286.56941) (xy 44.986149 -286.575342) (xy 45.03342 -286.589034)
			(xy 45.077882 -286.610132) (xy 45.118385 -286.638088) (xy 45.153878 -286.67218) (xy 45.183443 -286.711524)
			(xy 45.206314 -286.755101) (xy 45.221898 -286.801782) (xy 45.229793 -286.850359) (xy 45.230288 -286.874966)
			(xy 45.569136 -286.874966) (xy 45.573096 -286.825912) (xy 45.584873 -286.778128) (xy 45.604164 -286.732852)
			(xy 45.630467 -286.691256) (xy 45.663102 -286.654419) (xy 45.701223 -286.623294) (xy 45.743844 -286.598687)
			(xy 45.78986 -286.581235) (xy 45.838079 -286.571391) (xy 45.887254 -286.56941) (xy 45.936109 -286.575342)
			(xy 45.98338 -286.589034) (xy 46.027842 -286.610132) (xy 46.068345 -286.638088) (xy 46.103838 -286.67218)
			(xy 46.133403 -286.711524) (xy 46.156274 -286.755101) (xy 46.171858 -286.801782) (xy 46.179753 -286.850359)
			(xy 46.180248 -286.874966) (xy 46.519096 -286.874966) (xy 46.523056 -286.825912) (xy 46.534833 -286.778128)
			(xy 46.554124 -286.732852) (xy 46.580427 -286.691256) (xy 46.613062 -286.654419) (xy 46.651183 -286.623294)
			(xy 46.693804 -286.598687) (xy 46.73982 -286.581235) (xy 46.788039 -286.571391) (xy 46.837214 -286.56941)
			(xy 46.886069 -286.575342) (xy 46.93334 -286.589034) (xy 46.977802 -286.610132) (xy 47.018305 -286.638088)
			(xy 47.053798 -286.67218) (xy 47.083363 -286.711524) (xy 47.106234 -286.755101) (xy 47.121818 -286.801782)
			(xy 47.129713 -286.850359) (xy 47.130208 -286.874966) (xy 47.469056 -286.874966) (xy 47.473016 -286.825912)
			(xy 47.484793 -286.778128) (xy 47.504084 -286.732852) (xy 47.530387 -286.691256) (xy 47.563022 -286.654419)
			(xy 47.601143 -286.623294) (xy 47.643764 -286.598687) (xy 47.68978 -286.581235) (xy 47.737999 -286.571391)
			(xy 47.787174 -286.56941) (xy 47.836029 -286.575342) (xy 47.8833 -286.589034) (xy 47.927762 -286.610132)
			(xy 47.968265 -286.638088) (xy 48.003758 -286.67218) (xy 48.033323 -286.711524) (xy 48.056194 -286.755101)
			(xy 48.071778 -286.801782) (xy 48.079673 -286.850359) (xy 48.080168 -286.874966) (xy 48.419016 -286.874966)
			(xy 48.422976 -286.825912) (xy 48.434753 -286.778128) (xy 48.454044 -286.732852) (xy 48.480347 -286.691256)
			(xy 48.512982 -286.654419) (xy 48.551103 -286.623294) (xy 48.593724 -286.598687) (xy 48.63974 -286.581235)
			(xy 48.687959 -286.571391) (xy 48.737134 -286.56941) (xy 48.785989 -286.575342) (xy 48.83326 -286.589034)
			(xy 48.877722 -286.610132) (xy 48.918225 -286.638088) (xy 48.953718 -286.67218) (xy 48.983283 -286.711524)
			(xy 49.006154 -286.755101) (xy 49.021738 -286.801782) (xy 49.029633 -286.850359) (xy 49.030128 -286.874966)
			(xy 49.368976 -286.874966) (xy 49.372936 -286.825912) (xy 49.384713 -286.778128) (xy 49.404004 -286.732852)
			(xy 49.430307 -286.691256) (xy 49.462942 -286.654419) (xy 49.501063 -286.623294) (xy 49.543684 -286.598687)
			(xy 49.5897 -286.581235) (xy 49.637919 -286.571391) (xy 49.687094 -286.56941) (xy 49.735949 -286.575342)
			(xy 49.78322 -286.589034) (xy 49.827682 -286.610132) (xy 49.868185 -286.638088) (xy 49.903678 -286.67218)
			(xy 49.933243 -286.711524) (xy 49.956114 -286.755101) (xy 49.971698 -286.801782) (xy 49.979593 -286.850359)
			(xy 49.980088 -286.874966) (xy 50.31919 -286.874966) (xy 50.32315 -286.825912) (xy 50.334927 -286.778128)
			(xy 50.354218 -286.732852) (xy 50.380521 -286.691256) (xy 50.413156 -286.654419) (xy 50.451277 -286.623294)
			(xy 50.493898 -286.598687) (xy 50.539914 -286.581235) (xy 50.588133 -286.571391) (xy 50.637308 -286.56941)
			(xy 50.686163 -286.575342) (xy 50.733434 -286.589034) (xy 50.777896 -286.610132) (xy 50.818399 -286.638088)
			(xy 50.853892 -286.67218) (xy 50.883457 -286.711524) (xy 50.906328 -286.755101) (xy 50.921912 -286.801782)
			(xy 50.929807 -286.850359) (xy 50.930302 -286.874966) (xy 51.26915 -286.874966) (xy 51.27311 -286.825912)
			(xy 51.284887 -286.778128) (xy 51.304178 -286.732852) (xy 51.330481 -286.691256) (xy 51.363116 -286.654419)
			(xy 51.401237 -286.623294) (xy 51.443858 -286.598687) (xy 51.489874 -286.581235) (xy 51.538093 -286.571391)
			(xy 51.587268 -286.56941) (xy 51.636123 -286.575342) (xy 51.683394 -286.589034) (xy 51.727856 -286.610132)
			(xy 51.768359 -286.638088) (xy 51.803852 -286.67218) (xy 51.833417 -286.711524) (xy 51.856288 -286.755101)
			(xy 51.871872 -286.801782) (xy 51.879767 -286.850359) (xy 51.880262 -286.874966) (xy 52.21911 -286.874966)
			(xy 52.22307 -286.825912) (xy 52.234847 -286.778128) (xy 52.254138 -286.732852) (xy 52.280441 -286.691256)
			(xy 52.313076 -286.654419) (xy 52.351197 -286.623294) (xy 52.393818 -286.598687) (xy 52.439834 -286.581235)
			(xy 52.488053 -286.571391) (xy 52.537228 -286.56941) (xy 52.586083 -286.575342) (xy 52.633354 -286.589034)
			(xy 52.677816 -286.610132) (xy 52.718319 -286.638088) (xy 52.753812 -286.67218) (xy 52.783377 -286.711524)
			(xy 52.806248 -286.755101) (xy 52.821832 -286.801782) (xy 52.829727 -286.850359) (xy 52.830222 -286.874966)
			(xy 53.16907 -286.874966) (xy 53.17303 -286.825912) (xy 53.184807 -286.778128) (xy 53.204098 -286.732852)
			(xy 53.230401 -286.691256) (xy 53.263036 -286.654419) (xy 53.301157 -286.623294) (xy 53.343778 -286.598687)
			(xy 53.389794 -286.581235) (xy 53.438013 -286.571391) (xy 53.487188 -286.56941) (xy 53.536043 -286.575342)
			(xy 53.583314 -286.589034) (xy 53.627776 -286.610132) (xy 53.668279 -286.638088) (xy 53.703772 -286.67218)
			(xy 53.733337 -286.711524) (xy 53.756208 -286.755101) (xy 53.771792 -286.801782) (xy 53.779687 -286.850359)
			(xy 53.780182 -286.874966) (xy 54.11903 -286.874966) (xy 54.12299 -286.825912) (xy 54.134767 -286.778128)
			(xy 54.154058 -286.732852) (xy 54.180361 -286.691256) (xy 54.212996 -286.654419) (xy 54.251117 -286.623294)
			(xy 54.293738 -286.598687) (xy 54.339754 -286.581235) (xy 54.387973 -286.571391) (xy 54.437148 -286.56941)
			(xy 54.486003 -286.575342) (xy 54.533274 -286.589034) (xy 54.577736 -286.610132) (xy 54.618239 -286.638088)
			(xy 54.653732 -286.67218) (xy 54.683297 -286.711524) (xy 54.706168 -286.755101) (xy 54.721752 -286.801782)
			(xy 54.729647 -286.850359) (xy 54.730142 -286.874966) (xy 55.06899 -286.874966) (xy 55.07295 -286.825912)
			(xy 55.084727 -286.778128) (xy 55.104018 -286.732852) (xy 55.130321 -286.691256) (xy 55.162956 -286.654419)
			(xy 55.201077 -286.623294) (xy 55.243698 -286.598687) (xy 55.289714 -286.581235) (xy 55.337933 -286.571391)
			(xy 55.387108 -286.56941) (xy 55.435963 -286.575342) (xy 55.483234 -286.589034) (xy 55.527696 -286.610132)
			(xy 55.568199 -286.638088) (xy 55.603692 -286.67218) (xy 55.633257 -286.711524) (xy 55.656128 -286.755101)
			(xy 55.671712 -286.801782) (xy 55.679607 -286.850359) (xy 55.680102 -286.874966) (xy 56.01895 -286.874966)
			(xy 56.02291 -286.825912) (xy 56.034687 -286.778128) (xy 56.053978 -286.732852) (xy 56.080281 -286.691256)
			(xy 56.112916 -286.654419) (xy 56.151037 -286.623294) (xy 56.193658 -286.598687) (xy 56.239674 -286.581235)
			(xy 56.287893 -286.571391) (xy 56.337068 -286.56941) (xy 56.385923 -286.575342) (xy 56.433194 -286.589034)
			(xy 56.477656 -286.610132) (xy 56.518159 -286.638088) (xy 56.553652 -286.67218) (xy 56.583217 -286.711524)
			(xy 56.606088 -286.755101) (xy 56.621672 -286.801782) (xy 56.629567 -286.850359) (xy 56.630062 -286.874966)
			(xy 56.969164 -286.874966) (xy 56.973124 -286.825912) (xy 56.984901 -286.778128) (xy 57.004192 -286.732852)
			(xy 57.030495 -286.691256) (xy 57.06313 -286.654419) (xy 57.101251 -286.623294) (xy 57.143872 -286.598687)
			(xy 57.189888 -286.581235) (xy 57.238107 -286.571391) (xy 57.287282 -286.56941) (xy 57.336137 -286.575342)
			(xy 57.383408 -286.589034) (xy 57.42787 -286.610132) (xy 57.468373 -286.638088) (xy 57.503866 -286.67218)
			(xy 57.533431 -286.711524) (xy 57.556302 -286.755101) (xy 57.571886 -286.801782) (xy 57.579781 -286.850359)
			(xy 57.580276 -286.874966) (xy 57.919124 -286.874966) (xy 57.923084 -286.825912) (xy 57.934861 -286.778128)
			(xy 57.954152 -286.732852) (xy 57.980455 -286.691256) (xy 58.01309 -286.654419) (xy 58.051211 -286.623294)
			(xy 58.093832 -286.598687) (xy 58.139848 -286.581235) (xy 58.188067 -286.571391) (xy 58.237242 -286.56941)
			(xy 58.286097 -286.575342) (xy 58.333368 -286.589034) (xy 58.37783 -286.610132) (xy 58.418333 -286.638088)
			(xy 58.453826 -286.67218) (xy 58.483391 -286.711524) (xy 58.506262 -286.755101) (xy 58.521846 -286.801782)
			(xy 58.529741 -286.850359) (xy 58.530236 -286.874966) (xy 59.819044 -286.874966) (xy 59.823004 -286.825912)
			(xy 59.834781 -286.778128) (xy 59.854072 -286.732852) (xy 59.880375 -286.691256) (xy 59.91301 -286.654419)
			(xy 59.951131 -286.623294) (xy 59.993752 -286.598687) (xy 60.039768 -286.581235) (xy 60.087987 -286.571391)
			(xy 60.137162 -286.56941) (xy 60.186017 -286.575342) (xy 60.233288 -286.589034) (xy 60.27775 -286.610132)
			(xy 60.318253 -286.638088) (xy 60.353746 -286.67218) (xy 60.383311 -286.711524) (xy 60.406182 -286.755101)
			(xy 60.421766 -286.801782) (xy 60.429661 -286.850359) (xy 60.430156 -286.874966) (xy 60.769004 -286.874966)
			(xy 60.772964 -286.825912) (xy 60.784741 -286.778128) (xy 60.804032 -286.732852) (xy 60.830335 -286.691256)
			(xy 60.86297 -286.654419) (xy 60.901091 -286.623294) (xy 60.943712 -286.598687) (xy 60.989728 -286.581235)
			(xy 61.037947 -286.571391) (xy 61.087122 -286.56941) (xy 61.135977 -286.575342) (xy 61.183248 -286.589034)
			(xy 61.22771 -286.610132) (xy 61.268213 -286.638088) (xy 61.303706 -286.67218) (xy 61.333271 -286.711524)
			(xy 61.356142 -286.755101) (xy 61.371726 -286.801782) (xy 61.379621 -286.850359) (xy 61.380116 -286.874966)
			(xy 61.718964 -286.874966) (xy 61.722924 -286.825912) (xy 61.734701 -286.778128) (xy 61.753992 -286.732852)
			(xy 61.780295 -286.691256) (xy 61.81293 -286.654419) (xy 61.851051 -286.623294) (xy 61.893672 -286.598687)
			(xy 61.939688 -286.581235) (xy 61.987907 -286.571391) (xy 62.037082 -286.56941) (xy 62.085937 -286.575342)
			(xy 62.133208 -286.589034) (xy 62.17767 -286.610132) (xy 62.218173 -286.638088) (xy 62.253666 -286.67218)
			(xy 62.283231 -286.711524) (xy 62.306102 -286.755101) (xy 62.321686 -286.801782) (xy 62.329581 -286.850359)
			(xy 62.330076 -286.874966) (xy 62.669178 -286.874966) (xy 62.673138 -286.825912) (xy 62.684915 -286.778128)
			(xy 62.704206 -286.732852) (xy 62.730509 -286.691256) (xy 62.763144 -286.654419) (xy 62.801265 -286.623294)
			(xy 62.843886 -286.598687) (xy 62.889902 -286.581235) (xy 62.938121 -286.571391) (xy 62.987296 -286.56941)
			(xy 63.036151 -286.575342) (xy 63.083422 -286.589034) (xy 63.127884 -286.610132) (xy 63.168387 -286.638088)
			(xy 63.20388 -286.67218) (xy 63.233445 -286.711524) (xy 63.256316 -286.755101) (xy 63.2719 -286.801782)
			(xy 63.279795 -286.850359) (xy 63.28029 -286.874966) (xy 63.619138 -286.874966) (xy 63.623098 -286.825912)
			(xy 63.634875 -286.778128) (xy 63.654166 -286.732852) (xy 63.680469 -286.691256) (xy 63.713104 -286.654419)
			(xy 63.751225 -286.623294) (xy 63.793846 -286.598687) (xy 63.839862 -286.581235) (xy 63.888081 -286.571391)
			(xy 63.937256 -286.56941) (xy 63.986111 -286.575342) (xy 64.033382 -286.589034) (xy 64.077844 -286.610132)
			(xy 64.118347 -286.638088) (xy 64.15384 -286.67218) (xy 64.183405 -286.711524) (xy 64.206276 -286.755101)
			(xy 64.22186 -286.801782) (xy 64.229755 -286.850359) (xy 64.23025 -286.874966) (xy 64.569098 -286.874966)
			(xy 64.573058 -286.825912) (xy 64.584835 -286.778128) (xy 64.604126 -286.732852) (xy 64.630429 -286.691256)
			(xy 64.663064 -286.654419) (xy 64.701185 -286.623294) (xy 64.743806 -286.598687) (xy 64.789822 -286.581235)
			(xy 64.838041 -286.571391) (xy 64.887216 -286.56941) (xy 64.936071 -286.575342) (xy 64.983342 -286.589034)
			(xy 65.027804 -286.610132) (xy 65.068307 -286.638088) (xy 65.1038 -286.67218) (xy 65.133365 -286.711524)
			(xy 65.156236 -286.755101) (xy 65.17182 -286.801782) (xy 65.179715 -286.850359) (xy 65.18021 -286.874966)
			(xy 65.519058 -286.874966) (xy 65.523018 -286.825912) (xy 65.534795 -286.778128) (xy 65.554086 -286.732852)
			(xy 65.580389 -286.691256) (xy 65.613024 -286.654419) (xy 65.651145 -286.623294) (xy 65.693766 -286.598687)
			(xy 65.739782 -286.581235) (xy 65.788001 -286.571391) (xy 65.837176 -286.56941) (xy 65.886031 -286.575342)
			(xy 65.933302 -286.589034) (xy 65.977764 -286.610132) (xy 66.018267 -286.638088) (xy 66.05376 -286.67218)
			(xy 66.083325 -286.711524) (xy 66.106196 -286.755101) (xy 66.12178 -286.801782) (xy 66.129675 -286.850359)
			(xy 66.13017 -286.874966) (xy 66.469018 -286.874966) (xy 66.472978 -286.825912) (xy 66.484755 -286.778128)
			(xy 66.504046 -286.732852) (xy 66.530349 -286.691256) (xy 66.562984 -286.654419) (xy 66.601105 -286.623294)
			(xy 66.643726 -286.598687) (xy 66.689742 -286.581235) (xy 66.737961 -286.571391) (xy 66.787136 -286.56941)
			(xy 66.835991 -286.575342) (xy 66.883262 -286.589034) (xy 66.927724 -286.610132) (xy 66.968227 -286.638088)
			(xy 67.00372 -286.67218) (xy 67.033285 -286.711524) (xy 67.056156 -286.755101) (xy 67.07174 -286.801782)
			(xy 67.079635 -286.850359) (xy 67.08013 -286.874966) (xy 67.418978 -286.874966) (xy 67.422938 -286.825912)
			(xy 67.434715 -286.778128) (xy 67.454006 -286.732852) (xy 67.480309 -286.691256) (xy 67.512944 -286.654419)
			(xy 67.551065 -286.623294) (xy 67.593686 -286.598687) (xy 67.639702 -286.581235) (xy 67.687921 -286.571391)
			(xy 67.737096 -286.56941) (xy 67.785951 -286.575342) (xy 67.833222 -286.589034) (xy 67.877684 -286.610132)
			(xy 67.918187 -286.638088) (xy 67.95368 -286.67218) (xy 67.983245 -286.711524) (xy 68.006116 -286.755101)
			(xy 68.0217 -286.801782) (xy 68.029595 -286.850359) (xy 68.03009 -286.874966) (xy 68.368938 -286.874966)
			(xy 68.372898 -286.825912) (xy 68.384675 -286.778128) (xy 68.403966 -286.732852) (xy 68.430269 -286.691256)
			(xy 68.462904 -286.654419) (xy 68.501025 -286.623294) (xy 68.543646 -286.598687) (xy 68.589662 -286.581235)
			(xy 68.637881 -286.571391) (xy 68.687056 -286.56941) (xy 68.735911 -286.575342) (xy 68.783182 -286.589034)
			(xy 68.827644 -286.610132) (xy 68.868147 -286.638088) (xy 68.90364 -286.67218) (xy 68.933205 -286.711524)
			(xy 68.956076 -286.755101) (xy 68.97166 -286.801782) (xy 68.979555 -286.850359) (xy 68.98005 -286.874966)
			(xy 69.319152 -286.874966) (xy 69.323112 -286.825912) (xy 69.334889 -286.778128) (xy 69.35418 -286.732852)
			(xy 69.380483 -286.691256) (xy 69.413118 -286.654419) (xy 69.451239 -286.623294) (xy 69.49386 -286.598687)
			(xy 69.539876 -286.581235) (xy 69.588095 -286.571391) (xy 69.63727 -286.56941) (xy 69.686125 -286.575342)
			(xy 69.733396 -286.589034) (xy 69.777858 -286.610132) (xy 69.818361 -286.638088) (xy 69.853854 -286.67218)
			(xy 69.883419 -286.711524) (xy 69.90629 -286.755101) (xy 69.921874 -286.801782) (xy 69.929769 -286.850359)
			(xy 69.930264 -286.874966) (xy 70.269112 -286.874966) (xy 70.273072 -286.825912) (xy 70.284849 -286.778128)
			(xy 70.30414 -286.732852) (xy 70.330443 -286.691256) (xy 70.363078 -286.654419) (xy 70.401199 -286.623294)
			(xy 70.44382 -286.598687) (xy 70.489836 -286.581235) (xy 70.538055 -286.571391) (xy 70.58723 -286.56941)
			(xy 70.636085 -286.575342) (xy 70.683356 -286.589034) (xy 70.727818 -286.610132) (xy 70.768321 -286.638088)
			(xy 70.803814 -286.67218) (xy 70.833379 -286.711524) (xy 70.85625 -286.755101) (xy 70.871834 -286.801782)
			(xy 70.879729 -286.850359) (xy 70.880224 -286.874966) (xy 70.879729 -286.899573) (xy 70.871834 -286.94815)
			(xy 70.85625 -286.994831) (xy 70.833379 -287.038408) (xy 70.803814 -287.077752) (xy 70.768321 -287.111844)
			(xy 70.727818 -287.1398) (xy 70.683356 -287.160898) (xy 70.636085 -287.17459) (xy 70.58723 -287.180522)
			(xy 70.538055 -287.178541) (xy 70.489836 -287.168697) (xy 70.44382 -287.151245) (xy 70.401199 -287.126638)
			(xy 70.363078 -287.095513) (xy 70.330443 -287.058676) (xy 70.30414 -287.01708) (xy 70.284849 -286.971804)
			(xy 70.273072 -286.92402) (xy 70.269112 -286.874966) (xy 69.930264 -286.874966) (xy 69.929769 -286.899573)
			(xy 69.921874 -286.94815) (xy 69.90629 -286.994831) (xy 69.883419 -287.038408) (xy 69.853854 -287.077752)
			(xy 69.818361 -287.111844) (xy 69.777858 -287.1398) (xy 69.733396 -287.160898) (xy 69.686125 -287.17459)
			(xy 69.63727 -287.180522) (xy 69.588095 -287.178541) (xy 69.539876 -287.168697) (xy 69.49386 -287.151245)
			(xy 69.451239 -287.126638) (xy 69.413118 -287.095513) (xy 69.380483 -287.058676) (xy 69.35418 -287.01708)
			(xy 69.334889 -286.971804) (xy 69.323112 -286.92402) (xy 69.319152 -286.874966) (xy 68.98005 -286.874966)
			(xy 68.979555 -286.899573) (xy 68.97166 -286.94815) (xy 68.956076 -286.994831) (xy 68.933205 -287.038408)
			(xy 68.90364 -287.077752) (xy 68.868147 -287.111844) (xy 68.827644 -287.1398) (xy 68.783182 -287.160898)
			(xy 68.735911 -287.17459) (xy 68.687056 -287.180522) (xy 68.637881 -287.178541) (xy 68.589662 -287.168697)
			(xy 68.543646 -287.151245) (xy 68.501025 -287.126638) (xy 68.462904 -287.095513) (xy 68.430269 -287.058676)
			(xy 68.403966 -287.01708) (xy 68.384675 -286.971804) (xy 68.372898 -286.92402) (xy 68.368938 -286.874966)
			(xy 68.03009 -286.874966) (xy 68.029595 -286.899573) (xy 68.0217 -286.94815) (xy 68.006116 -286.994831)
			(xy 67.983245 -287.038408) (xy 67.95368 -287.077752) (xy 67.918187 -287.111844) (xy 67.877684 -287.1398)
			(xy 67.833222 -287.160898) (xy 67.785951 -287.17459) (xy 67.737096 -287.180522) (xy 67.687921 -287.178541)
			(xy 67.639702 -287.168697) (xy 67.593686 -287.151245) (xy 67.551065 -287.126638) (xy 67.512944 -287.095513)
			(xy 67.480309 -287.058676) (xy 67.454006 -287.01708) (xy 67.434715 -286.971804) (xy 67.422938 -286.92402)
			(xy 67.418978 -286.874966) (xy 67.08013 -286.874966) (xy 67.079635 -286.899573) (xy 67.07174 -286.94815)
			(xy 67.056156 -286.994831) (xy 67.033285 -287.038408) (xy 67.00372 -287.077752) (xy 66.968227 -287.111844)
			(xy 66.927724 -287.1398) (xy 66.883262 -287.160898) (xy 66.835991 -287.17459) (xy 66.787136 -287.180522)
			(xy 66.737961 -287.178541) (xy 66.689742 -287.168697) (xy 66.643726 -287.151245) (xy 66.601105 -287.126638)
			(xy 66.562984 -287.095513) (xy 66.530349 -287.058676) (xy 66.504046 -287.01708) (xy 66.484755 -286.971804)
			(xy 66.472978 -286.92402) (xy 66.469018 -286.874966) (xy 66.13017 -286.874966) (xy 66.129675 -286.899573)
			(xy 66.12178 -286.94815) (xy 66.106196 -286.994831) (xy 66.083325 -287.038408) (xy 66.05376 -287.077752)
			(xy 66.018267 -287.111844) (xy 65.977764 -287.1398) (xy 65.933302 -287.160898) (xy 65.886031 -287.17459)
			(xy 65.837176 -287.180522) (xy 65.788001 -287.178541) (xy 65.739782 -287.168697) (xy 65.693766 -287.151245)
			(xy 65.651145 -287.126638) (xy 65.613024 -287.095513) (xy 65.580389 -287.058676) (xy 65.554086 -287.01708)
			(xy 65.534795 -286.971804) (xy 65.523018 -286.92402) (xy 65.519058 -286.874966) (xy 65.18021 -286.874966)
			(xy 65.179715 -286.899573) (xy 65.17182 -286.94815) (xy 65.156236 -286.994831) (xy 65.133365 -287.038408)
			(xy 65.1038 -287.077752) (xy 65.068307 -287.111844) (xy 65.027804 -287.1398) (xy 64.983342 -287.160898)
			(xy 64.936071 -287.17459) (xy 64.887216 -287.180522) (xy 64.838041 -287.178541) (xy 64.789822 -287.168697)
			(xy 64.743806 -287.151245) (xy 64.701185 -287.126638) (xy 64.663064 -287.095513) (xy 64.630429 -287.058676)
			(xy 64.604126 -287.01708) (xy 64.584835 -286.971804) (xy 64.573058 -286.92402) (xy 64.569098 -286.874966)
			(xy 64.23025 -286.874966) (xy 64.229755 -286.899573) (xy 64.22186 -286.94815) (xy 64.206276 -286.994831)
			(xy 64.183405 -287.038408) (xy 64.15384 -287.077752) (xy 64.118347 -287.111844) (xy 64.077844 -287.1398)
			(xy 64.033382 -287.160898) (xy 63.986111 -287.17459) (xy 63.937256 -287.180522) (xy 63.888081 -287.178541)
			(xy 63.839862 -287.168697) (xy 63.793846 -287.151245) (xy 63.751225 -287.126638) (xy 63.713104 -287.095513)
			(xy 63.680469 -287.058676) (xy 63.654166 -287.01708) (xy 63.634875 -286.971804) (xy 63.623098 -286.92402)
			(xy 63.619138 -286.874966) (xy 63.28029 -286.874966) (xy 63.279795 -286.899573) (xy 63.2719 -286.94815)
			(xy 63.256316 -286.994831) (xy 63.233445 -287.038408) (xy 63.20388 -287.077752) (xy 63.168387 -287.111844)
			(xy 63.127884 -287.1398) (xy 63.083422 -287.160898) (xy 63.036151 -287.17459) (xy 62.987296 -287.180522)
			(xy 62.938121 -287.178541) (xy 62.889902 -287.168697) (xy 62.843886 -287.151245) (xy 62.801265 -287.126638)
			(xy 62.763144 -287.095513) (xy 62.730509 -287.058676) (xy 62.704206 -287.01708) (xy 62.684915 -286.971804)
			(xy 62.673138 -286.92402) (xy 62.669178 -286.874966) (xy 62.330076 -286.874966) (xy 62.329581 -286.899573)
			(xy 62.321686 -286.94815) (xy 62.306102 -286.994831) (xy 62.283231 -287.038408) (xy 62.253666 -287.077752)
			(xy 62.218173 -287.111844) (xy 62.17767 -287.1398) (xy 62.133208 -287.160898) (xy 62.085937 -287.17459)
			(xy 62.037082 -287.180522) (xy 61.987907 -287.178541) (xy 61.939688 -287.168697) (xy 61.893672 -287.151245)
			(xy 61.851051 -287.126638) (xy 61.81293 -287.095513) (xy 61.780295 -287.058676) (xy 61.753992 -287.01708)
			(xy 61.734701 -286.971804) (xy 61.722924 -286.92402) (xy 61.718964 -286.874966) (xy 61.380116 -286.874966)
			(xy 61.379621 -286.899573) (xy 61.371726 -286.94815) (xy 61.356142 -286.994831) (xy 61.333271 -287.038408)
			(xy 61.303706 -287.077752) (xy 61.268213 -287.111844) (xy 61.22771 -287.1398) (xy 61.183248 -287.160898)
			(xy 61.135977 -287.17459) (xy 61.087122 -287.180522) (xy 61.037947 -287.178541) (xy 60.989728 -287.168697)
			(xy 60.943712 -287.151245) (xy 60.901091 -287.126638) (xy 60.86297 -287.095513) (xy 60.830335 -287.058676)
			(xy 60.804032 -287.01708) (xy 60.784741 -286.971804) (xy 60.772964 -286.92402) (xy 60.769004 -286.874966)
			(xy 60.430156 -286.874966) (xy 60.429661 -286.899573) (xy 60.421766 -286.94815) (xy 60.406182 -286.994831)
			(xy 60.383311 -287.038408) (xy 60.353746 -287.077752) (xy 60.318253 -287.111844) (xy 60.27775 -287.1398)
			(xy 60.233288 -287.160898) (xy 60.186017 -287.17459) (xy 60.137162 -287.180522) (xy 60.087987 -287.178541)
			(xy 60.039768 -287.168697) (xy 59.993752 -287.151245) (xy 59.951131 -287.126638) (xy 59.91301 -287.095513)
			(xy 59.880375 -287.058676) (xy 59.854072 -287.01708) (xy 59.834781 -286.971804) (xy 59.823004 -286.92402)
			(xy 59.819044 -286.874966) (xy 58.530236 -286.874966) (xy 58.529741 -286.899573) (xy 58.521846 -286.94815)
			(xy 58.506262 -286.994831) (xy 58.483391 -287.038408) (xy 58.453826 -287.077752) (xy 58.418333 -287.111844)
			(xy 58.37783 -287.1398) (xy 58.333368 -287.160898) (xy 58.286097 -287.17459) (xy 58.237242 -287.180522)
			(xy 58.188067 -287.178541) (xy 58.139848 -287.168697) (xy 58.093832 -287.151245) (xy 58.051211 -287.126638)
			(xy 58.01309 -287.095513) (xy 57.980455 -287.058676) (xy 57.954152 -287.01708) (xy 57.934861 -286.971804)
			(xy 57.923084 -286.92402) (xy 57.919124 -286.874966) (xy 57.580276 -286.874966) (xy 57.579781 -286.899573)
			(xy 57.571886 -286.94815) (xy 57.556302 -286.994831) (xy 57.533431 -287.038408) (xy 57.503866 -287.077752)
			(xy 57.468373 -287.111844) (xy 57.42787 -287.1398) (xy 57.383408 -287.160898) (xy 57.336137 -287.17459)
			(xy 57.287282 -287.180522) (xy 57.238107 -287.178541) (xy 57.189888 -287.168697) (xy 57.143872 -287.151245)
			(xy 57.101251 -287.126638) (xy 57.06313 -287.095513) (xy 57.030495 -287.058676) (xy 57.004192 -287.01708)
			(xy 56.984901 -286.971804) (xy 56.973124 -286.92402) (xy 56.969164 -286.874966) (xy 56.630062 -286.874966)
			(xy 56.629567 -286.899573) (xy 56.621672 -286.94815) (xy 56.606088 -286.994831) (xy 56.583217 -287.038408)
			(xy 56.553652 -287.077752) (xy 56.518159 -287.111844) (xy 56.477656 -287.1398) (xy 56.433194 -287.160898)
			(xy 56.385923 -287.17459) (xy 56.337068 -287.180522) (xy 56.287893 -287.178541) (xy 56.239674 -287.168697)
			(xy 56.193658 -287.151245) (xy 56.151037 -287.126638) (xy 56.112916 -287.095513) (xy 56.080281 -287.058676)
			(xy 56.053978 -287.01708) (xy 56.034687 -286.971804) (xy 56.02291 -286.92402) (xy 56.01895 -286.874966)
			(xy 55.680102 -286.874966) (xy 55.679607 -286.899573) (xy 55.671712 -286.94815) (xy 55.656128 -286.994831)
			(xy 55.633257 -287.038408) (xy 55.603692 -287.077752) (xy 55.568199 -287.111844) (xy 55.527696 -287.1398)
			(xy 55.483234 -287.160898) (xy 55.435963 -287.17459) (xy 55.387108 -287.180522) (xy 55.337933 -287.178541)
			(xy 55.289714 -287.168697) (xy 55.243698 -287.151245) (xy 55.201077 -287.126638) (xy 55.162956 -287.095513)
			(xy 55.130321 -287.058676) (xy 55.104018 -287.01708) (xy 55.084727 -286.971804) (xy 55.07295 -286.92402)
			(xy 55.06899 -286.874966) (xy 54.730142 -286.874966) (xy 54.729647 -286.899573) (xy 54.721752 -286.94815)
			(xy 54.706168 -286.994831) (xy 54.683297 -287.038408) (xy 54.653732 -287.077752) (xy 54.618239 -287.111844)
			(xy 54.577736 -287.1398) (xy 54.533274 -287.160898) (xy 54.486003 -287.17459) (xy 54.437148 -287.180522)
			(xy 54.387973 -287.178541) (xy 54.339754 -287.168697) (xy 54.293738 -287.151245) (xy 54.251117 -287.126638)
			(xy 54.212996 -287.095513) (xy 54.180361 -287.058676) (xy 54.154058 -287.01708) (xy 54.134767 -286.971804)
			(xy 54.12299 -286.92402) (xy 54.11903 -286.874966) (xy 53.780182 -286.874966) (xy 53.779687 -286.899573)
			(xy 53.771792 -286.94815) (xy 53.756208 -286.994831) (xy 53.733337 -287.038408) (xy 53.703772 -287.077752)
			(xy 53.668279 -287.111844) (xy 53.627776 -287.1398) (xy 53.583314 -287.160898) (xy 53.536043 -287.17459)
			(xy 53.487188 -287.180522) (xy 53.438013 -287.178541) (xy 53.389794 -287.168697) (xy 53.343778 -287.151245)
			(xy 53.301157 -287.126638) (xy 53.263036 -287.095513) (xy 53.230401 -287.058676) (xy 53.204098 -287.01708)
			(xy 53.184807 -286.971804) (xy 53.17303 -286.92402) (xy 53.16907 -286.874966) (xy 52.830222 -286.874966)
			(xy 52.829727 -286.899573) (xy 52.821832 -286.94815) (xy 52.806248 -286.994831) (xy 52.783377 -287.038408)
			(xy 52.753812 -287.077752) (xy 52.718319 -287.111844) (xy 52.677816 -287.1398) (xy 52.633354 -287.160898)
			(xy 52.586083 -287.17459) (xy 52.537228 -287.180522) (xy 52.488053 -287.178541) (xy 52.439834 -287.168697)
			(xy 52.393818 -287.151245) (xy 52.351197 -287.126638) (xy 52.313076 -287.095513) (xy 52.280441 -287.058676)
			(xy 52.254138 -287.01708) (xy 52.234847 -286.971804) (xy 52.22307 -286.92402) (xy 52.21911 -286.874966)
			(xy 51.880262 -286.874966) (xy 51.879767 -286.899573) (xy 51.871872 -286.94815) (xy 51.856288 -286.994831)
			(xy 51.833417 -287.038408) (xy 51.803852 -287.077752) (xy 51.768359 -287.111844) (xy 51.727856 -287.1398)
			(xy 51.683394 -287.160898) (xy 51.636123 -287.17459) (xy 51.587268 -287.180522) (xy 51.538093 -287.178541)
			(xy 51.489874 -287.168697) (xy 51.443858 -287.151245) (xy 51.401237 -287.126638) (xy 51.363116 -287.095513)
			(xy 51.330481 -287.058676) (xy 51.304178 -287.01708) (xy 51.284887 -286.971804) (xy 51.27311 -286.92402)
			(xy 51.26915 -286.874966) (xy 50.930302 -286.874966) (xy 50.929807 -286.899573) (xy 50.921912 -286.94815)
			(xy 50.906328 -286.994831) (xy 50.883457 -287.038408) (xy 50.853892 -287.077752) (xy 50.818399 -287.111844)
			(xy 50.777896 -287.1398) (xy 50.733434 -287.160898) (xy 50.686163 -287.17459) (xy 50.637308 -287.180522)
			(xy 50.588133 -287.178541) (xy 50.539914 -287.168697) (xy 50.493898 -287.151245) (xy 50.451277 -287.126638)
			(xy 50.413156 -287.095513) (xy 50.380521 -287.058676) (xy 50.354218 -287.01708) (xy 50.334927 -286.971804)
			(xy 50.32315 -286.92402) (xy 50.31919 -286.874966) (xy 49.980088 -286.874966) (xy 49.979593 -286.899573)
			(xy 49.971698 -286.94815) (xy 49.956114 -286.994831) (xy 49.933243 -287.038408) (xy 49.903678 -287.077752)
			(xy 49.868185 -287.111844) (xy 49.827682 -287.1398) (xy 49.78322 -287.160898) (xy 49.735949 -287.17459)
			(xy 49.687094 -287.180522) (xy 49.637919 -287.178541) (xy 49.5897 -287.168697) (xy 49.543684 -287.151245)
			(xy 49.501063 -287.126638) (xy 49.462942 -287.095513) (xy 49.430307 -287.058676) (xy 49.404004 -287.01708)
			(xy 49.384713 -286.971804) (xy 49.372936 -286.92402) (xy 49.368976 -286.874966) (xy 49.030128 -286.874966)
			(xy 49.029633 -286.899573) (xy 49.021738 -286.94815) (xy 49.006154 -286.994831) (xy 48.983283 -287.038408)
			(xy 48.953718 -287.077752) (xy 48.918225 -287.111844) (xy 48.877722 -287.1398) (xy 48.83326 -287.160898)
			(xy 48.785989 -287.17459) (xy 48.737134 -287.180522) (xy 48.687959 -287.178541) (xy 48.63974 -287.168697)
			(xy 48.593724 -287.151245) (xy 48.551103 -287.126638) (xy 48.512982 -287.095513) (xy 48.480347 -287.058676)
			(xy 48.454044 -287.01708) (xy 48.434753 -286.971804) (xy 48.422976 -286.92402) (xy 48.419016 -286.874966)
			(xy 48.080168 -286.874966) (xy 48.079673 -286.899573) (xy 48.071778 -286.94815) (xy 48.056194 -286.994831)
			(xy 48.033323 -287.038408) (xy 48.003758 -287.077752) (xy 47.968265 -287.111844) (xy 47.927762 -287.1398)
			(xy 47.8833 -287.160898) (xy 47.836029 -287.17459) (xy 47.787174 -287.180522) (xy 47.737999 -287.178541)
			(xy 47.68978 -287.168697) (xy 47.643764 -287.151245) (xy 47.601143 -287.126638) (xy 47.563022 -287.095513)
			(xy 47.530387 -287.058676) (xy 47.504084 -287.01708) (xy 47.484793 -286.971804) (xy 47.473016 -286.92402)
			(xy 47.469056 -286.874966) (xy 47.130208 -286.874966) (xy 47.129713 -286.899573) (xy 47.121818 -286.94815)
			(xy 47.106234 -286.994831) (xy 47.083363 -287.038408) (xy 47.053798 -287.077752) (xy 47.018305 -287.111844)
			(xy 46.977802 -287.1398) (xy 46.93334 -287.160898) (xy 46.886069 -287.17459) (xy 46.837214 -287.180522)
			(xy 46.788039 -287.178541) (xy 46.73982 -287.168697) (xy 46.693804 -287.151245) (xy 46.651183 -287.126638)
			(xy 46.613062 -287.095513) (xy 46.580427 -287.058676) (xy 46.554124 -287.01708) (xy 46.534833 -286.971804)
			(xy 46.523056 -286.92402) (xy 46.519096 -286.874966) (xy 46.180248 -286.874966) (xy 46.179753 -286.899573)
			(xy 46.171858 -286.94815) (xy 46.156274 -286.994831) (xy 46.133403 -287.038408) (xy 46.103838 -287.077752)
			(xy 46.068345 -287.111844) (xy 46.027842 -287.1398) (xy 45.98338 -287.160898) (xy 45.936109 -287.17459)
			(xy 45.887254 -287.180522) (xy 45.838079 -287.178541) (xy 45.78986 -287.168697) (xy 45.743844 -287.151245)
			(xy 45.701223 -287.126638) (xy 45.663102 -287.095513) (xy 45.630467 -287.058676) (xy 45.604164 -287.01708)
			(xy 45.584873 -286.971804) (xy 45.573096 -286.92402) (xy 45.569136 -286.874966) (xy 45.230288 -286.874966)
			(xy 45.229793 -286.899573) (xy 45.221898 -286.94815) (xy 45.206314 -286.994831) (xy 45.183443 -287.038408)
			(xy 45.153878 -287.077752) (xy 45.118385 -287.111844) (xy 45.077882 -287.1398) (xy 45.03342 -287.160898)
			(xy 44.986149 -287.17459) (xy 44.937294 -287.180522) (xy 44.888119 -287.178541) (xy 44.8399 -287.168697)
			(xy 44.793884 -287.151245) (xy 44.751263 -287.126638) (xy 44.713142 -287.095513) (xy 44.680507 -287.058676)
			(xy 44.654204 -287.01708) (xy 44.634913 -286.971804) (xy 44.623136 -286.92402) (xy 44.619176 -286.874966)
			(xy 44.280069 -286.874966) (xy 44.279579 -286.899319) (xy 44.271684 -286.947896) (xy 44.2561 -286.994577)
			(xy 44.233229 -287.038154) (xy 44.203664 -287.077498) (xy 44.168171 -287.11159) (xy 44.127668 -287.139546)
			(xy 44.083206 -287.160644) (xy 44.035935 -287.174336) (xy 43.98708 -287.180268) (xy 43.937905 -287.178287)
			(xy 43.889686 -287.168443) (xy 43.84367 -287.150991) (xy 43.801049 -287.126384) (xy 43.762928 -287.095259)
			(xy 43.730293 -287.058422) (xy 43.70399 -287.016826) (xy 43.684699 -286.97155) (xy 43.672922 -286.923766)
			(xy 43.668962 -286.874712) (xy 43.330114 -286.874712) (xy 43.329619 -286.899319) (xy 43.321724 -286.947896)
			(xy 43.30614 -286.994577) (xy 43.283269 -287.038154) (xy 43.253704 -287.077498) (xy 43.218211 -287.11159)
			(xy 43.177708 -287.139546) (xy 43.133246 -287.160644) (xy 43.085975 -287.174336) (xy 43.03712 -287.180268)
			(xy 42.987945 -287.178287) (xy 42.939726 -287.168443) (xy 42.89371 -287.150991) (xy 42.851089 -287.126384)
			(xy 42.812968 -287.095259) (xy 42.780333 -287.058422) (xy 42.75403 -287.016826) (xy 42.734739 -286.97155)
			(xy 42.722962 -286.923766) (xy 42.719002 -286.874712) (xy 42.380149 -286.874712) (xy 42.380154 -286.874966)
			(xy 42.379659 -286.899573) (xy 42.371764 -286.94815) (xy 42.35618 -286.994831) (xy 42.333309 -287.038408)
			(xy 42.303744 -287.077752) (xy 42.268251 -287.111844) (xy 42.227748 -287.1398) (xy 42.183286 -287.160898)
			(xy 42.136015 -287.17459) (xy 42.08716 -287.180522) (xy 42.037985 -287.178541) (xy 41.989766 -287.168697)
			(xy 41.94375 -287.151245) (xy 41.901129 -287.126638) (xy 41.863008 -287.095513) (xy 41.830373 -287.058676)
			(xy 41.80407 -287.01708) (xy 41.784779 -286.971804) (xy 41.773002 -286.92402) (xy 41.769042 -286.874966)
			(xy 41.430194 -286.874966) (xy 41.429699 -286.899573) (xy 41.421804 -286.94815) (xy 41.40622 -286.994831)
			(xy 41.383349 -287.038408) (xy 41.353784 -287.077752) (xy 41.318291 -287.111844) (xy 41.277788 -287.1398)
			(xy 41.233326 -287.160898) (xy 41.186055 -287.17459) (xy 41.1372 -287.180522) (xy 41.088025 -287.178541)
			(xy 41.039806 -287.168697) (xy 40.99379 -287.151245) (xy 40.951169 -287.126638) (xy 40.913048 -287.095513)
			(xy 40.880413 -287.058676) (xy 40.85411 -287.01708) (xy 40.834819 -286.971804) (xy 40.823042 -286.92402)
			(xy 40.819082 -286.874966) (xy 40.480234 -286.874966) (xy 40.479739 -286.899573) (xy 40.471844 -286.94815)
			(xy 40.45626 -286.994831) (xy 40.433389 -287.038408) (xy 40.403824 -287.077752) (xy 40.368331 -287.111844)
			(xy 40.327828 -287.1398) (xy 40.283366 -287.160898) (xy 40.236095 -287.17459) (xy 40.18724 -287.180522)
			(xy 40.138065 -287.178541) (xy 40.089846 -287.168697) (xy 40.04383 -287.151245) (xy 40.001209 -287.126638)
			(xy 39.963088 -287.095513) (xy 39.930453 -287.058676) (xy 39.90415 -287.01708) (xy 39.884859 -286.971804)
			(xy 39.873082 -286.92402) (xy 39.869122 -286.874966) (xy 39.530274 -286.874966) (xy 39.529779 -286.899573)
			(xy 39.521884 -286.94815) (xy 39.5063 -286.994831) (xy 39.483429 -287.038408) (xy 39.453864 -287.077752)
			(xy 39.418371 -287.111844) (xy 39.377868 -287.1398) (xy 39.333406 -287.160898) (xy 39.286135 -287.17459)
			(xy 39.23728 -287.180522) (xy 39.188105 -287.178541) (xy 39.139886 -287.168697) (xy 39.09387 -287.151245)
			(xy 39.051249 -287.126638) (xy 39.013128 -287.095513) (xy 38.980493 -287.058676) (xy 38.95419 -287.01708)
			(xy 38.934899 -286.971804) (xy 38.923122 -286.92402) (xy 38.919162 -286.874966) (xy 38.580314 -286.874966)
			(xy 38.579819 -286.899573) (xy 38.571924 -286.94815) (xy 38.55634 -286.994831) (xy 38.533469 -287.038408)
			(xy 38.503904 -287.077752) (xy 38.468411 -287.111844) (xy 38.427908 -287.1398) (xy 38.383446 -287.160898)
			(xy 38.336175 -287.17459) (xy 38.28732 -287.180522) (xy 38.238145 -287.178541) (xy 38.189926 -287.168697)
			(xy 38.14391 -287.151245) (xy 38.101289 -287.126638) (xy 38.063168 -287.095513) (xy 38.030533 -287.058676)
			(xy 38.00423 -287.01708) (xy 37.984939 -286.971804) (xy 37.973162 -286.92402) (xy 37.969202 -286.874966)
			(xy 37.6301 -286.874966) (xy 37.629605 -286.899573) (xy 37.62171 -286.94815) (xy 37.606126 -286.994831)
			(xy 37.583255 -287.038408) (xy 37.55369 -287.077752) (xy 37.518197 -287.111844) (xy 37.477694 -287.1398)
			(xy 37.433232 -287.160898) (xy 37.385961 -287.17459) (xy 37.337106 -287.180522) (xy 37.287931 -287.178541)
			(xy 37.239712 -287.168697) (xy 37.193696 -287.151245) (xy 37.151075 -287.126638) (xy 37.112954 -287.095513)
			(xy 37.080319 -287.058676) (xy 37.054016 -287.01708) (xy 37.034725 -286.971804) (xy 37.022948 -286.92402)
			(xy 37.018988 -286.874966) (xy 36.68014 -286.874966) (xy 36.679645 -286.899573) (xy 36.67175 -286.94815)
			(xy 36.656166 -286.994831) (xy 36.633295 -287.038408) (xy 36.60373 -287.077752) (xy 36.568237 -287.111844)
			(xy 36.527734 -287.1398) (xy 36.483272 -287.160898) (xy 36.436001 -287.17459) (xy 36.387146 -287.180522)
			(xy 36.337971 -287.178541) (xy 36.289752 -287.168697) (xy 36.243736 -287.151245) (xy 36.201115 -287.126638)
			(xy 36.162994 -287.095513) (xy 36.130359 -287.058676) (xy 36.104056 -287.01708) (xy 36.084765 -286.971804)
			(xy 36.072988 -286.92402) (xy 36.069028 -286.874966) (xy 34.31496 -286.874966) (xy 34.336119 -286.906948)
			(xy 34.359791 -286.957445) (xy 34.375859 -287.010852) (xy 34.383979 -287.066028) (xy 34.384488 -287.093914)
			(xy 34.383979 -287.1218) (xy 34.375859 -287.176976) (xy 34.359791 -287.230383) (xy 34.336119 -287.28088)
			(xy 34.305346 -287.327393) (xy 34.268129 -287.36893) (xy 34.225261 -287.404605) (xy 34.177655 -287.433659)
			(xy 34.126326 -287.455471) (xy 34.072369 -287.469577) (xy 34.016932 -287.475677) (xy 33.961198 -287.47364)
			(xy 33.906355 -287.46351) (xy 33.853571 -287.445503) (xy 33.803971 -287.420002) (xy 33.758613 -287.387551)
			(xy 33.718464 -287.348842) (xy 33.684378 -287.304699) (xy 33.657082 -287.256064) (xy 33.637159 -287.203973)
			(xy 33.625033 -287.149536) (xy 33.620962 -287.093914) (xy 33.498028 -287.093914) (xy 33.497519 -287.1218)
			(xy 33.489399 -287.176976) (xy 33.473331 -287.230383) (xy 33.449659 -287.28088) (xy 33.418886 -287.327393)
			(xy 33.381669 -287.36893) (xy 33.338801 -287.404605) (xy 33.291195 -287.433659) (xy 33.239866 -287.455471)
			(xy 33.185909 -287.469577) (xy 33.130472 -287.475677) (xy 33.074738 -287.47364) (xy 33.019895 -287.46351)
			(xy 32.967111 -287.445503) (xy 32.917511 -287.420002) (xy 32.872153 -287.387551) (xy 32.832004 -287.348842)
			(xy 32.797918 -287.304699) (xy 32.770622 -287.256064) (xy 32.750699 -287.203973) (xy 32.738573 -287.149536)
			(xy 32.734502 -287.093914) (xy 32.101028 -287.093914) (xy 32.100542 -287.121165) (xy 32.092786 -287.175113)
			(xy 32.077431 -287.227408) (xy 32.054789 -287.276985) (xy 32.025323 -287.322835) (xy 31.989632 -287.364026)
			(xy 31.948441 -287.399717) (xy 31.902591 -287.429183) (xy 31.853014 -287.451825) (xy 31.800719 -287.46718)
			(xy 31.746771 -287.474936) (xy 31.692269 -287.474936) (xy 31.638321 -287.46718) (xy 31.586026 -287.451825)
			(xy 31.536449 -287.429183) (xy 31.490599 -287.399717) (xy 31.449408 -287.364026) (xy 31.413717 -287.322835)
			(xy 31.384251 -287.276985) (xy 31.361609 -287.227408) (xy 31.346254 -287.175113) (xy 31.338498 -287.121165)
			(xy 31.338012 -287.093914) (xy 6.648247 -287.093914) (xy 6.648247 -287.131833) (xy 6.64049 -287.185785)
			(xy 6.625133 -287.238083) (xy 6.60249 -287.287664) (xy 6.573022 -287.333517) (xy 6.537328 -287.37471)
			(xy 6.496134 -287.410404) (xy 6.45028 -287.439872) (xy 6.400699 -287.462515) (xy 6.348401 -287.47787)
			(xy 6.294449 -287.485627) (xy 6.267196 -287.48609) (xy 6.237072 -287.485539) (xy 6.177574 -287.476056)
			(xy 6.120305 -287.457341) (xy 6.066688 -287.42986) (xy 6.018056 -287.394296) (xy 5.996432 -287.373314)
			(xy 5.98932 -287.365948) (xy 5.970524 -287.358328) (xy 5.878068 -287.358328) (xy 5.859272 -287.365948)
			(xy 5.85216 -287.373314) (xy 5.830534 -287.394293) (xy 5.781905 -287.429861) (xy 5.728289 -287.457341)
			(xy 5.671019 -287.476049) (xy 5.61152 -287.485521) (xy 5.581396 -287.48609) (xy 5.554145 -287.4856)
			(xy 5.500198 -287.477843) (xy 5.447904 -287.462488) (xy 5.398328 -287.439846) (xy 5.352478 -287.41038)
			(xy 5.311288 -287.374689) (xy 5.275597 -287.333499) (xy 5.246132 -287.287649) (xy 5.223491 -287.238072)
			(xy 5.208136 -287.185778) (xy 5.20038 -287.131831) (xy 4.636057 -287.131831) (xy 4.636057 -287.131833)
			(xy 4.6283 -287.185784) (xy 4.612943 -287.238083) (xy 4.590301 -287.287663) (xy 4.560832 -287.333517)
			(xy 4.525138 -287.37471) (xy 4.483945 -287.410403) (xy 4.438091 -287.439872) (xy 4.388511 -287.462514)
			(xy 4.336213 -287.47787) (xy 4.282261 -287.485627) (xy 4.255008 -287.48609) (xy 4.227638 -287.485622)
			(xy 4.173459 -287.477805) (xy 4.120956 -287.462316) (xy 4.071209 -287.439475) (xy 4.025242 -287.409751)
			(xy 4.00431 -287.39211) (xy 3.997198 -287.386014) (xy 3.98018 -287.379664) (xy 3.894836 -287.379664)
			(xy 3.877818 -287.386014) (xy 3.870706 -287.39211) (xy 3.849784 -287.409761) (xy 3.803808 -287.439471)
			(xy 3.754058 -287.462304) (xy 3.701555 -287.477793) (xy 3.647378 -287.485618) (xy 3.620008 -287.48609)
			(xy 3.592757 -287.4856) (xy 3.53881 -287.477843) (xy 3.486516 -287.462488) (xy 3.436939 -287.439847)
			(xy 3.391089 -287.410381) (xy 3.349899 -287.374689) (xy 3.314208 -287.3335) (xy 3.284742 -287.287649)
			(xy 3.262101 -287.238073) (xy 3.246746 -287.185778) (xy 3.23899 -287.131831) (xy 1.468374 -287.131831)
			(xy 1.468374 -287.984001) (xy 11.94992 -287.984001) (xy 11.94992 -287.929499) (xy 11.957676 -287.875552)
			(xy 11.973031 -287.823257) (xy 11.995672 -287.773681) (xy 12.025138 -287.72783) (xy 12.060829 -287.686641)
			(xy 12.102019 -287.650949) (xy 12.147869 -287.621483) (xy 12.197446 -287.598842) (xy 12.24974 -287.583487)
			(xy 12.303687 -287.57573) (xy 12.330938 -287.575244) (xy 12.358307 -287.575736) (xy 12.412486 -287.583546)
			(xy 12.464989 -287.599028) (xy 12.514736 -287.621865) (xy 12.560704 -287.651585) (xy 12.581636 -287.669224)
			(xy 12.588748 -287.67532) (xy 12.605766 -287.68167) (xy 12.69111 -287.68167) (xy 12.708128 -287.67532)
			(xy 12.71524 -287.669224) (xy 12.736187 -287.651603) (xy 12.782155 -287.621888) (xy 12.831899 -287.599048)
			(xy 12.884396 -287.583553) (xy 12.93857 -287.57572) (xy 12.965938 -287.575244) (xy 12.993191 -287.575703)
			(xy 13.047143 -287.58346) (xy 13.099441 -287.598816) (xy 13.149021 -287.621458) (xy 13.194875 -287.650927)
			(xy 13.236068 -287.68662) (xy 13.271762 -287.727813) (xy 13.301231 -287.773667) (xy 13.323873 -287.823247)
			(xy 13.33923 -287.875546) (xy 13.346987 -287.929497) (xy 13.346987 -287.984001) (xy 13.68982 -287.984001)
			(xy 13.68982 -287.929499) (xy 13.697576 -287.875552) (xy 13.712931 -287.823257) (xy 13.735572 -287.773681)
			(xy 13.765038 -287.72783) (xy 13.800729 -287.686641) (xy 13.841919 -287.650949) (xy 13.887769 -287.621483)
			(xy 13.937346 -287.598842) (xy 13.98964 -287.583487) (xy 14.043587 -287.57573) (xy 14.070838 -287.575244)
			(xy 14.098207 -287.575736) (xy 14.152386 -287.583546) (xy 14.204889 -287.599028) (xy 14.254636 -287.621865)
			(xy 14.300604 -287.651585) (xy 14.321536 -287.669224) (xy 14.328648 -287.67532) (xy 14.345666 -287.68167)
			(xy 14.43101 -287.68167) (xy 14.448028 -287.67532) (xy 14.45514 -287.669224) (xy 14.476087 -287.651603)
			(xy 14.522055 -287.621888) (xy 14.571799 -287.599048) (xy 14.624296 -287.583553) (xy 14.67847 -287.57572)
			(xy 14.705838 -287.575244) (xy 14.733091 -287.575703) (xy 14.787043 -287.58346) (xy 14.839341 -287.598816)
			(xy 14.888921 -287.621458) (xy 14.934775 -287.650927) (xy 14.975968 -287.68662) (xy 15.011662 -287.727813)
			(xy 15.041131 -287.773667) (xy 15.063773 -287.823247) (xy 15.064266 -287.824926) (xy 36.069028 -287.824926)
			(xy 36.072988 -287.775872) (xy 36.084765 -287.728088) (xy 36.104056 -287.682812) (xy 36.130359 -287.641216)
			(xy 36.162994 -287.604379) (xy 36.201115 -287.573254) (xy 36.243736 -287.548647) (xy 36.289752 -287.531195)
			(xy 36.337971 -287.521351) (xy 36.387146 -287.51937) (xy 36.436001 -287.525302) (xy 36.483272 -287.538994)
			(xy 36.527734 -287.560092) (xy 36.568237 -287.588048) (xy 36.60373 -287.62214) (xy 36.633295 -287.661484)
			(xy 36.656166 -287.705061) (xy 36.67175 -287.751742) (xy 36.679645 -287.800319) (xy 36.68014 -287.824926)
			(xy 37.018988 -287.824926) (xy 37.022948 -287.775872) (xy 37.034725 -287.728088) (xy 37.054016 -287.682812)
			(xy 37.080319 -287.641216) (xy 37.112954 -287.604379) (xy 37.151075 -287.573254) (xy 37.193696 -287.548647)
			(xy 37.239712 -287.531195) (xy 37.287931 -287.521351) (xy 37.337106 -287.51937) (xy 37.385961 -287.525302)
			(xy 37.433232 -287.538994) (xy 37.477694 -287.560092) (xy 37.518197 -287.588048) (xy 37.55369 -287.62214)
			(xy 37.583255 -287.661484) (xy 37.606126 -287.705061) (xy 37.62171 -287.751742) (xy 37.629605 -287.800319)
			(xy 37.6301 -287.824926) (xy 37.629605 -287.849533) (xy 37.629463 -287.850408) (xy 37.944539 -287.850408)
			(xy 37.944539 -287.798392) (xy 37.952677 -287.747016) (xy 37.968751 -287.697546) (xy 37.992366 -287.651199)
			(xy 38.02294 -287.609117) (xy 38.059722 -287.572337) (xy 38.101804 -287.541763) (xy 38.148151 -287.518148)
			(xy 38.197622 -287.502075) (xy 38.248998 -287.493939) (xy 38.275006 -287.493456) (xy 39.224966 -287.493456)
			(xy 39.250978 -287.493901) (xy 39.302363 -287.502035) (xy 39.351843 -287.518107) (xy 39.398199 -287.541722)
			(xy 39.44029 -287.572299) (xy 39.477079 -287.609084) (xy 39.50766 -287.651172) (xy 39.53128 -287.697525)
			(xy 39.547357 -287.747004) (xy 39.555496 -287.798388) (xy 39.555496 -287.824926) (xy 39.869122 -287.824926)
			(xy 39.873082 -287.775872) (xy 39.884859 -287.728088) (xy 39.90415 -287.682812) (xy 39.930453 -287.641216)
			(xy 39.963088 -287.604379) (xy 40.001209 -287.573254) (xy 40.04383 -287.548647) (xy 40.089846 -287.531195)
			(xy 40.138065 -287.521351) (xy 40.18724 -287.51937) (xy 40.236095 -287.525302) (xy 40.283366 -287.538994)
			(xy 40.327828 -287.560092) (xy 40.368331 -287.588048) (xy 40.403824 -287.62214) (xy 40.433389 -287.661484)
			(xy 40.45626 -287.705061) (xy 40.471844 -287.751742) (xy 40.479739 -287.800319) (xy 40.480234 -287.824926)
			(xy 40.479739 -287.849533) (xy 40.479597 -287.850405) (xy 40.794466 -287.850405) (xy 40.794466 -287.798395)
			(xy 40.802602 -287.747025) (xy 40.818674 -287.697561) (xy 40.842285 -287.651219) (xy 40.872855 -287.609142)
			(xy 40.909631 -287.572364) (xy 40.951707 -287.541792) (xy 40.998048 -287.518179) (xy 41.047512 -287.502105)
			(xy 41.098881 -287.493967) (xy 41.124886 -287.493456) (xy 42.074846 -287.493456) (xy 42.100852 -287.493934)
			(xy 42.152223 -287.502077) (xy 42.201688 -287.518155) (xy 42.248029 -287.541773) (xy 42.290106 -287.572348)
			(xy 42.326882 -287.609129) (xy 42.357451 -287.65121) (xy 42.381063 -287.697554) (xy 42.397134 -287.747022)
			(xy 42.40527 -287.798394) (xy 42.40527 -287.824926) (xy 42.719002 -287.824926) (xy 42.722962 -287.775872)
			(xy 42.734739 -287.728088) (xy 42.75403 -287.682812) (xy 42.780333 -287.641216) (xy 42.812968 -287.604379)
			(xy 42.851089 -287.573254) (xy 42.89371 -287.548647) (xy 42.939726 -287.531195) (xy 42.987945 -287.521351)
			(xy 43.03712 -287.51937) (xy 43.085975 -287.525302) (xy 43.133246 -287.538994) (xy 43.177708 -287.560092)
			(xy 43.218211 -287.588048) (xy 43.253704 -287.62214) (xy 43.283269 -287.661484) (xy 43.30614 -287.705061)
			(xy 43.321724 -287.751742) (xy 43.329619 -287.800319) (xy 43.330114 -287.824926) (xy 43.668962 -287.824926)
			(xy 43.672922 -287.775872) (xy 43.684699 -287.728088) (xy 43.70399 -287.682812) (xy 43.730293 -287.641216)
			(xy 43.762928 -287.604379) (xy 43.801049 -287.573254) (xy 43.84367 -287.548647) (xy 43.889686 -287.531195)
			(xy 43.937905 -287.521351) (xy 43.98708 -287.51937) (xy 44.035935 -287.525302) (xy 44.083206 -287.538994)
			(xy 44.127668 -287.560092) (xy 44.168171 -287.588048) (xy 44.203664 -287.62214) (xy 44.233229 -287.661484)
			(xy 44.2561 -287.705061) (xy 44.271684 -287.751742) (xy 44.279579 -287.800319) (xy 44.280074 -287.824926)
			(xy 44.619176 -287.824926) (xy 44.623136 -287.775872) (xy 44.634913 -287.728088) (xy 44.654204 -287.682812)
			(xy 44.680507 -287.641216) (xy 44.713142 -287.604379) (xy 44.751263 -287.573254) (xy 44.793884 -287.548647)
			(xy 44.8399 -287.531195) (xy 44.888119 -287.521351) (xy 44.937294 -287.51937) (xy 44.986149 -287.525302)
			(xy 45.03342 -287.538994) (xy 45.077882 -287.560092) (xy 45.118385 -287.588048) (xy 45.153878 -287.62214)
			(xy 45.183443 -287.661484) (xy 45.206314 -287.705061) (xy 45.221898 -287.751742) (xy 45.229793 -287.800319)
			(xy 45.230288 -287.824926) (xy 45.569136 -287.824926) (xy 45.573096 -287.775872) (xy 45.584873 -287.728088)
			(xy 45.604164 -287.682812) (xy 45.630467 -287.641216) (xy 45.663102 -287.604379) (xy 45.701223 -287.573254)
			(xy 45.743844 -287.548647) (xy 45.78986 -287.531195) (xy 45.838079 -287.521351) (xy 45.887254 -287.51937)
			(xy 45.936109 -287.525302) (xy 45.98338 -287.538994) (xy 46.027842 -287.560092) (xy 46.068345 -287.588048)
			(xy 46.103838 -287.62214) (xy 46.133403 -287.661484) (xy 46.156274 -287.705061) (xy 46.171858 -287.751742)
			(xy 46.179753 -287.800319) (xy 46.180248 -287.824926) (xy 46.519096 -287.824926) (xy 46.523056 -287.775872)
			(xy 46.534833 -287.728088) (xy 46.554124 -287.682812) (xy 46.580427 -287.641216) (xy 46.613062 -287.604379)
			(xy 46.651183 -287.573254) (xy 46.693804 -287.548647) (xy 46.73982 -287.531195) (xy 46.788039 -287.521351)
			(xy 46.837214 -287.51937) (xy 46.886069 -287.525302) (xy 46.93334 -287.538994) (xy 46.977802 -287.560092)
			(xy 47.018305 -287.588048) (xy 47.053798 -287.62214) (xy 47.083363 -287.661484) (xy 47.106234 -287.705061)
			(xy 47.121818 -287.751742) (xy 47.129713 -287.800319) (xy 47.130208 -287.824926) (xy 47.469056 -287.824926)
			(xy 47.473016 -287.775872) (xy 47.484793 -287.728088) (xy 47.504084 -287.682812) (xy 47.530387 -287.641216)
			(xy 47.563022 -287.604379) (xy 47.601143 -287.573254) (xy 47.643764 -287.548647) (xy 47.68978 -287.531195)
			(xy 47.737999 -287.521351) (xy 47.787174 -287.51937) (xy 47.836029 -287.525302) (xy 47.8833 -287.538994)
			(xy 47.927762 -287.560092) (xy 47.968265 -287.588048) (xy 48.003758 -287.62214) (xy 48.033323 -287.661484)
			(xy 48.056194 -287.705061) (xy 48.071778 -287.751742) (xy 48.079673 -287.800319) (xy 48.080168 -287.824926)
			(xy 48.419016 -287.824926) (xy 48.422976 -287.775872) (xy 48.434753 -287.728088) (xy 48.454044 -287.682812)
			(xy 48.480347 -287.641216) (xy 48.512982 -287.604379) (xy 48.551103 -287.573254) (xy 48.593724 -287.548647)
			(xy 48.63974 -287.531195) (xy 48.687959 -287.521351) (xy 48.737134 -287.51937) (xy 48.785989 -287.525302)
			(xy 48.83326 -287.538994) (xy 48.877722 -287.560092) (xy 48.918225 -287.588048) (xy 48.953718 -287.62214)
			(xy 48.983283 -287.661484) (xy 49.006154 -287.705061) (xy 49.021738 -287.751742) (xy 49.029633 -287.800319)
			(xy 49.030128 -287.824926) (xy 49.368976 -287.824926) (xy 49.372936 -287.775872) (xy 49.384713 -287.728088)
			(xy 49.404004 -287.682812) (xy 49.430307 -287.641216) (xy 49.462942 -287.604379) (xy 49.501063 -287.573254)
			(xy 49.543684 -287.548647) (xy 49.5897 -287.531195) (xy 49.637919 -287.521351) (xy 49.687094 -287.51937)
			(xy 49.735949 -287.525302) (xy 49.78322 -287.538994) (xy 49.827682 -287.560092) (xy 49.868185 -287.588048)
			(xy 49.903678 -287.62214) (xy 49.933243 -287.661484) (xy 49.956114 -287.705061) (xy 49.971698 -287.751742)
			(xy 49.979593 -287.800319) (xy 49.980088 -287.824926) (xy 50.31919 -287.824926) (xy 50.32315 -287.775872)
			(xy 50.334927 -287.728088) (xy 50.354218 -287.682812) (xy 50.380521 -287.641216) (xy 50.413156 -287.604379)
			(xy 50.451277 -287.573254) (xy 50.493898 -287.548647) (xy 50.539914 -287.531195) (xy 50.588133 -287.521351)
			(xy 50.637308 -287.51937) (xy 50.686163 -287.525302) (xy 50.733434 -287.538994) (xy 50.777896 -287.560092)
			(xy 50.818399 -287.588048) (xy 50.853892 -287.62214) (xy 50.883457 -287.661484) (xy 50.906328 -287.705061)
			(xy 50.921912 -287.751742) (xy 50.929807 -287.800319) (xy 50.930302 -287.824926) (xy 51.26915 -287.824926)
			(xy 51.27311 -287.775872) (xy 51.284887 -287.728088) (xy 51.304178 -287.682812) (xy 51.330481 -287.641216)
			(xy 51.363116 -287.604379) (xy 51.401237 -287.573254) (xy 51.443858 -287.548647) (xy 51.489874 -287.531195)
			(xy 51.538093 -287.521351) (xy 51.587268 -287.51937) (xy 51.636123 -287.525302) (xy 51.683394 -287.538994)
			(xy 51.727856 -287.560092) (xy 51.768359 -287.588048) (xy 51.803852 -287.62214) (xy 51.833417 -287.661484)
			(xy 51.856288 -287.705061) (xy 51.871872 -287.751742) (xy 51.879767 -287.800319) (xy 51.880262 -287.824926)
			(xy 52.21911 -287.824926) (xy 52.22307 -287.775872) (xy 52.234847 -287.728088) (xy 52.254138 -287.682812)
			(xy 52.280441 -287.641216) (xy 52.313076 -287.604379) (xy 52.351197 -287.573254) (xy 52.393818 -287.548647)
			(xy 52.439834 -287.531195) (xy 52.488053 -287.521351) (xy 52.537228 -287.51937) (xy 52.586083 -287.525302)
			(xy 52.633354 -287.538994) (xy 52.677816 -287.560092) (xy 52.718319 -287.588048) (xy 52.753812 -287.62214)
			(xy 52.783377 -287.661484) (xy 52.806248 -287.705061) (xy 52.821832 -287.751742) (xy 52.829727 -287.800319)
			(xy 52.830222 -287.824926) (xy 53.16907 -287.824926) (xy 53.17303 -287.775872) (xy 53.184807 -287.728088)
			(xy 53.204098 -287.682812) (xy 53.230401 -287.641216) (xy 53.263036 -287.604379) (xy 53.301157 -287.573254)
			(xy 53.343778 -287.548647) (xy 53.389794 -287.531195) (xy 53.438013 -287.521351) (xy 53.487188 -287.51937)
			(xy 53.536043 -287.525302) (xy 53.583314 -287.538994) (xy 53.627776 -287.560092) (xy 53.668279 -287.588048)
			(xy 53.703772 -287.62214) (xy 53.733337 -287.661484) (xy 53.756208 -287.705061) (xy 53.771792 -287.751742)
			(xy 53.779687 -287.800319) (xy 53.780182 -287.824926) (xy 54.11903 -287.824926) (xy 54.12299 -287.775872)
			(xy 54.134767 -287.728088) (xy 54.154058 -287.682812) (xy 54.180361 -287.641216) (xy 54.212996 -287.604379)
			(xy 54.251117 -287.573254) (xy 54.293738 -287.548647) (xy 54.339754 -287.531195) (xy 54.387973 -287.521351)
			(xy 54.437148 -287.51937) (xy 54.486003 -287.525302) (xy 54.533274 -287.538994) (xy 54.577736 -287.560092)
			(xy 54.618239 -287.588048) (xy 54.653732 -287.62214) (xy 54.683297 -287.661484) (xy 54.706168 -287.705061)
			(xy 54.721752 -287.751742) (xy 54.729647 -287.800319) (xy 54.730142 -287.824926) (xy 55.06899 -287.824926)
			(xy 55.07295 -287.775872) (xy 55.084727 -287.728088) (xy 55.104018 -287.682812) (xy 55.130321 -287.641216)
			(xy 55.162956 -287.604379) (xy 55.201077 -287.573254) (xy 55.243698 -287.548647) (xy 55.289714 -287.531195)
			(xy 55.337933 -287.521351) (xy 55.387108 -287.51937) (xy 55.435963 -287.525302) (xy 55.483234 -287.538994)
			(xy 55.527696 -287.560092) (xy 55.568199 -287.588048) (xy 55.603692 -287.62214) (xy 55.633257 -287.661484)
			(xy 55.656128 -287.705061) (xy 55.671712 -287.751742) (xy 55.679607 -287.800319) (xy 55.680102 -287.824926)
			(xy 56.01895 -287.824926) (xy 56.02291 -287.775872) (xy 56.034687 -287.728088) (xy 56.053978 -287.682812)
			(xy 56.080281 -287.641216) (xy 56.112916 -287.604379) (xy 56.151037 -287.573254) (xy 56.193658 -287.548647)
			(xy 56.239674 -287.531195) (xy 56.287893 -287.521351) (xy 56.337068 -287.51937) (xy 56.385923 -287.525302)
			(xy 56.433194 -287.538994) (xy 56.477656 -287.560092) (xy 56.518159 -287.588048) (xy 56.553652 -287.62214)
			(xy 56.583217 -287.661484) (xy 56.606088 -287.705061) (xy 56.621672 -287.751742) (xy 56.629567 -287.800319)
			(xy 56.630062 -287.824926) (xy 56.969164 -287.824926) (xy 56.973124 -287.775872) (xy 56.984901 -287.728088)
			(xy 57.004192 -287.682812) (xy 57.030495 -287.641216) (xy 57.06313 -287.604379) (xy 57.101251 -287.573254)
			(xy 57.143872 -287.548647) (xy 57.189888 -287.531195) (xy 57.238107 -287.521351) (xy 57.287282 -287.51937)
			(xy 57.336137 -287.525302) (xy 57.383408 -287.538994) (xy 57.42787 -287.560092) (xy 57.468373 -287.588048)
			(xy 57.503866 -287.62214) (xy 57.533431 -287.661484) (xy 57.553624 -287.699958) (xy 57.944016 -287.699958)
			(xy 57.947976 -287.650904) (xy 57.959753 -287.60312) (xy 57.979044 -287.557844) (xy 58.005347 -287.516248)
			(xy 58.037982 -287.479411) (xy 58.076103 -287.448286) (xy 58.118724 -287.423679) (xy 58.16474 -287.406227)
			(xy 58.212959 -287.396383) (xy 58.262134 -287.394402) (xy 58.310989 -287.400334) (xy 58.35826 -287.414026)
			(xy 58.402722 -287.435124) (xy 58.443225 -287.46308) (xy 58.478718 -287.497172) (xy 58.508283 -287.536516)
			(xy 58.531154 -287.580093) (xy 58.546738 -287.626774) (xy 58.554633 -287.675351) (xy 58.555128 -287.699958)
			(xy 58.554633 -287.724565) (xy 58.546738 -287.773142) (xy 58.531154 -287.819823) (xy 58.508283 -287.8634)
			(xy 58.480888 -287.899856) (xy 59.819044 -287.899856) (xy 59.823004 -287.850802) (xy 59.834781 -287.803018)
			(xy 59.854072 -287.757742) (xy 59.880375 -287.716146) (xy 59.91301 -287.679309) (xy 59.951131 -287.648184)
			(xy 59.993752 -287.623577) (xy 60.039768 -287.606125) (xy 60.087987 -287.596281) (xy 60.137162 -287.5943)
			(xy 60.186017 -287.600232) (xy 60.233288 -287.613924) (xy 60.27775 -287.635022) (xy 60.318253 -287.662978)
			(xy 60.353746 -287.69707) (xy 60.383311 -287.736414) (xy 60.406182 -287.779991) (xy 60.421183 -287.824926)
			(xy 60.769004 -287.824926) (xy 60.772964 -287.775872) (xy 60.784741 -287.728088) (xy 60.804032 -287.682812)
			(xy 60.830335 -287.641216) (xy 60.86297 -287.604379) (xy 60.901091 -287.573254) (xy 60.943712 -287.548647)
			(xy 60.989728 -287.531195) (xy 61.037947 -287.521351) (xy 61.087122 -287.51937) (xy 61.135977 -287.525302)
			(xy 61.183248 -287.538994) (xy 61.22771 -287.560092) (xy 61.268213 -287.588048) (xy 61.303706 -287.62214)
			(xy 61.333271 -287.661484) (xy 61.356142 -287.705061) (xy 61.371726 -287.751742) (xy 61.379621 -287.800319)
			(xy 61.380116 -287.824926) (xy 61.718964 -287.824926) (xy 61.722924 -287.775872) (xy 61.734701 -287.728088)
			(xy 61.753992 -287.682812) (xy 61.780295 -287.641216) (xy 61.81293 -287.604379) (xy 61.851051 -287.573254)
			(xy 61.893672 -287.548647) (xy 61.939688 -287.531195) (xy 61.987907 -287.521351) (xy 62.037082 -287.51937)
			(xy 62.085937 -287.525302) (xy 62.133208 -287.538994) (xy 62.17767 -287.560092) (xy 62.218173 -287.588048)
			(xy 62.253666 -287.62214) (xy 62.283231 -287.661484) (xy 62.306102 -287.705061) (xy 62.321686 -287.751742)
			(xy 62.329581 -287.800319) (xy 62.330076 -287.824926) (xy 62.669178 -287.824926) (xy 62.673138 -287.775872)
			(xy 62.684915 -287.728088) (xy 62.704206 -287.682812) (xy 62.730509 -287.641216) (xy 62.763144 -287.604379)
			(xy 62.801265 -287.573254) (xy 62.843886 -287.548647) (xy 62.889902 -287.531195) (xy 62.938121 -287.521351)
			(xy 62.987296 -287.51937) (xy 63.036151 -287.525302) (xy 63.083422 -287.538994) (xy 63.127884 -287.560092)
			(xy 63.168387 -287.588048) (xy 63.20388 -287.62214) (xy 63.233445 -287.661484) (xy 63.256316 -287.705061)
			(xy 63.2719 -287.751742) (xy 63.279795 -287.800319) (xy 63.28029 -287.824926) (xy 63.619138 -287.824926)
			(xy 63.623098 -287.775872) (xy 63.634875 -287.728088) (xy 63.654166 -287.682812) (xy 63.680469 -287.641216)
			(xy 63.713104 -287.604379) (xy 63.751225 -287.573254) (xy 63.793846 -287.548647) (xy 63.839862 -287.531195)
			(xy 63.888081 -287.521351) (xy 63.937256 -287.51937) (xy 63.986111 -287.525302) (xy 64.033382 -287.538994)
			(xy 64.077844 -287.560092) (xy 64.118347 -287.588048) (xy 64.15384 -287.62214) (xy 64.183405 -287.661484)
			(xy 64.206276 -287.705061) (xy 64.22186 -287.751742) (xy 64.229755 -287.800319) (xy 64.23025 -287.824926)
			(xy 64.569098 -287.824926) (xy 64.573058 -287.775872) (xy 64.584835 -287.728088) (xy 64.604126 -287.682812)
			(xy 64.630429 -287.641216) (xy 64.663064 -287.604379) (xy 64.701185 -287.573254) (xy 64.743806 -287.548647)
			(xy 64.789822 -287.531195) (xy 64.838041 -287.521351) (xy 64.887216 -287.51937) (xy 64.936071 -287.525302)
			(xy 64.983342 -287.538994) (xy 65.027804 -287.560092) (xy 65.068307 -287.588048) (xy 65.1038 -287.62214)
			(xy 65.133365 -287.661484) (xy 65.156236 -287.705061) (xy 65.17182 -287.751742) (xy 65.179715 -287.800319)
			(xy 65.18021 -287.824926) (xy 65.519058 -287.824926) (xy 65.523018 -287.775872) (xy 65.534795 -287.728088)
			(xy 65.554086 -287.682812) (xy 65.580389 -287.641216) (xy 65.613024 -287.604379) (xy 65.651145 -287.573254)
			(xy 65.693766 -287.548647) (xy 65.739782 -287.531195) (xy 65.788001 -287.521351) (xy 65.837176 -287.51937)
			(xy 65.886031 -287.525302) (xy 65.933302 -287.538994) (xy 65.977764 -287.560092) (xy 66.018267 -287.588048)
			(xy 66.05376 -287.62214) (xy 66.083325 -287.661484) (xy 66.106196 -287.705061) (xy 66.12178 -287.751742)
			(xy 66.129675 -287.800319) (xy 66.13017 -287.824926) (xy 66.469018 -287.824926) (xy 66.472978 -287.775872)
			(xy 66.484755 -287.728088) (xy 66.504046 -287.682812) (xy 66.530349 -287.641216) (xy 66.562984 -287.604379)
			(xy 66.601105 -287.573254) (xy 66.643726 -287.548647) (xy 66.689742 -287.531195) (xy 66.737961 -287.521351)
			(xy 66.787136 -287.51937) (xy 66.835991 -287.525302) (xy 66.883262 -287.538994) (xy 66.927724 -287.560092)
			(xy 66.968227 -287.588048) (xy 67.00372 -287.62214) (xy 67.033285 -287.661484) (xy 67.056156 -287.705061)
			(xy 67.07174 -287.751742) (xy 67.079635 -287.800319) (xy 67.08013 -287.824926) (xy 67.418978 -287.824926)
			(xy 67.422938 -287.775872) (xy 67.434715 -287.728088) (xy 67.454006 -287.682812) (xy 67.480309 -287.641216)
			(xy 67.512944 -287.604379) (xy 67.551065 -287.573254) (xy 67.593686 -287.548647) (xy 67.639702 -287.531195)
			(xy 67.687921 -287.521351) (xy 67.737096 -287.51937) (xy 67.785951 -287.525302) (xy 67.833222 -287.538994)
			(xy 67.877684 -287.560092) (xy 67.918187 -287.588048) (xy 67.95368 -287.62214) (xy 67.983245 -287.661484)
			(xy 68.006116 -287.705061) (xy 68.0217 -287.751742) (xy 68.029595 -287.800319) (xy 68.03009 -287.824926)
			(xy 68.368938 -287.824926) (xy 68.372898 -287.775872) (xy 68.384675 -287.728088) (xy 68.403966 -287.682812)
			(xy 68.430269 -287.641216) (xy 68.462904 -287.604379) (xy 68.501025 -287.573254) (xy 68.543646 -287.548647)
			(xy 68.589662 -287.531195) (xy 68.637881 -287.521351) (xy 68.687056 -287.51937) (xy 68.735911 -287.525302)
			(xy 68.783182 -287.538994) (xy 68.827644 -287.560092) (xy 68.868147 -287.588048) (xy 68.90364 -287.62214)
			(xy 68.933205 -287.661484) (xy 68.956076 -287.705061) (xy 68.97166 -287.751742) (xy 68.979555 -287.800319)
			(xy 68.98005 -287.824926) (xy 70.269112 -287.824926) (xy 70.273072 -287.775872) (xy 70.284849 -287.728088)
			(xy 70.30414 -287.682812) (xy 70.330443 -287.641216) (xy 70.363078 -287.604379) (xy 70.401199 -287.573254)
			(xy 70.44382 -287.548647) (xy 70.489836 -287.531195) (xy 70.538055 -287.521351) (xy 70.58723 -287.51937)
			(xy 70.636085 -287.525302) (xy 70.683356 -287.538994) (xy 70.727818 -287.560092) (xy 70.768321 -287.588048)
			(xy 70.803814 -287.62214) (xy 70.833379 -287.661484) (xy 70.85625 -287.705061) (xy 70.871834 -287.751742)
			(xy 70.879729 -287.800319) (xy 70.880224 -287.824926) (xy 70.879729 -287.849533) (xy 70.871834 -287.89811)
			(xy 70.85625 -287.944791) (xy 70.833379 -287.988368) (xy 70.803814 -288.027712) (xy 70.768321 -288.061804)
			(xy 70.727818 -288.08976) (xy 70.683356 -288.110858) (xy 70.636085 -288.12455) (xy 70.58723 -288.130482)
			(xy 70.538055 -288.128501) (xy 70.489836 -288.118657) (xy 70.44382 -288.101205) (xy 70.401199 -288.076598)
			(xy 70.363078 -288.045473) (xy 70.330443 -288.008636) (xy 70.30414 -287.96704) (xy 70.284849 -287.921764)
			(xy 70.273072 -287.87398) (xy 70.269112 -287.824926) (xy 68.98005 -287.824926) (xy 68.979555 -287.849533)
			(xy 68.97166 -287.89811) (xy 68.956076 -287.944791) (xy 68.933205 -287.988368) (xy 68.90364 -288.027712)
			(xy 68.868147 -288.061804) (xy 68.827644 -288.08976) (xy 68.783182 -288.110858) (xy 68.735911 -288.12455)
			(xy 68.687056 -288.130482) (xy 68.637881 -288.128501) (xy 68.589662 -288.118657) (xy 68.543646 -288.101205)
			(xy 68.501025 -288.076598) (xy 68.462904 -288.045473) (xy 68.430269 -288.008636) (xy 68.403966 -287.96704)
			(xy 68.384675 -287.921764) (xy 68.372898 -287.87398) (xy 68.368938 -287.824926) (xy 68.03009 -287.824926)
			(xy 68.029595 -287.849533) (xy 68.0217 -287.89811) (xy 68.006116 -287.944791) (xy 67.983245 -287.988368)
			(xy 67.95368 -288.027712) (xy 67.918187 -288.061804) (xy 67.877684 -288.08976) (xy 67.833222 -288.110858)
			(xy 67.785951 -288.12455) (xy 67.737096 -288.130482) (xy 67.687921 -288.128501) (xy 67.639702 -288.118657)
			(xy 67.593686 -288.101205) (xy 67.551065 -288.076598) (xy 67.512944 -288.045473) (xy 67.480309 -288.008636)
			(xy 67.454006 -287.96704) (xy 67.434715 -287.921764) (xy 67.422938 -287.87398) (xy 67.418978 -287.824926)
			(xy 67.08013 -287.824926) (xy 67.079635 -287.849533) (xy 67.07174 -287.89811) (xy 67.056156 -287.944791)
			(xy 67.033285 -287.988368) (xy 67.00372 -288.027712) (xy 66.968227 -288.061804) (xy 66.927724 -288.08976)
			(xy 66.883262 -288.110858) (xy 66.835991 -288.12455) (xy 66.787136 -288.130482) (xy 66.737961 -288.128501)
			(xy 66.689742 -288.118657) (xy 66.643726 -288.101205) (xy 66.601105 -288.076598) (xy 66.562984 -288.045473)
			(xy 66.530349 -288.008636) (xy 66.504046 -287.96704) (xy 66.484755 -287.921764) (xy 66.472978 -287.87398)
			(xy 66.469018 -287.824926) (xy 66.13017 -287.824926) (xy 66.129675 -287.849533) (xy 66.12178 -287.89811)
			(xy 66.106196 -287.944791) (xy 66.083325 -287.988368) (xy 66.05376 -288.027712) (xy 66.018267 -288.061804)
			(xy 65.977764 -288.08976) (xy 65.933302 -288.110858) (xy 65.886031 -288.12455) (xy 65.837176 -288.130482)
			(xy 65.788001 -288.128501) (xy 65.739782 -288.118657) (xy 65.693766 -288.101205) (xy 65.651145 -288.076598)
			(xy 65.613024 -288.045473) (xy 65.580389 -288.008636) (xy 65.554086 -287.96704) (xy 65.534795 -287.921764)
			(xy 65.523018 -287.87398) (xy 65.519058 -287.824926) (xy 65.18021 -287.824926) (xy 65.179715 -287.849533)
			(xy 65.17182 -287.89811) (xy 65.156236 -287.944791) (xy 65.133365 -287.988368) (xy 65.1038 -288.027712)
			(xy 65.068307 -288.061804) (xy 65.027804 -288.08976) (xy 64.983342 -288.110858) (xy 64.936071 -288.12455)
			(xy 64.887216 -288.130482) (xy 64.838041 -288.128501) (xy 64.789822 -288.118657) (xy 64.743806 -288.101205)
			(xy 64.701185 -288.076598) (xy 64.663064 -288.045473) (xy 64.630429 -288.008636) (xy 64.604126 -287.96704)
			(xy 64.584835 -287.921764) (xy 64.573058 -287.87398) (xy 64.569098 -287.824926) (xy 64.23025 -287.824926)
			(xy 64.229755 -287.849533) (xy 64.22186 -287.89811) (xy 64.206276 -287.944791) (xy 64.183405 -287.988368)
			(xy 64.15384 -288.027712) (xy 64.118347 -288.061804) (xy 64.077844 -288.08976) (xy 64.033382 -288.110858)
			(xy 63.986111 -288.12455) (xy 63.937256 -288.130482) (xy 63.888081 -288.128501) (xy 63.839862 -288.118657)
			(xy 63.793846 -288.101205) (xy 63.751225 -288.076598) (xy 63.713104 -288.045473) (xy 63.680469 -288.008636)
			(xy 63.654166 -287.96704) (xy 63.634875 -287.921764) (xy 63.623098 -287.87398) (xy 63.619138 -287.824926)
			(xy 63.28029 -287.824926) (xy 63.279795 -287.849533) (xy 63.2719 -287.89811) (xy 63.256316 -287.944791)
			(xy 63.233445 -287.988368) (xy 63.20388 -288.027712) (xy 63.168387 -288.061804) (xy 63.127884 -288.08976)
			(xy 63.083422 -288.110858) (xy 63.036151 -288.12455) (xy 62.987296 -288.130482) (xy 62.938121 -288.128501)
			(xy 62.889902 -288.118657) (xy 62.843886 -288.101205) (xy 62.801265 -288.076598) (xy 62.763144 -288.045473)
			(xy 62.730509 -288.008636) (xy 62.704206 -287.96704) (xy 62.684915 -287.921764) (xy 62.673138 -287.87398)
			(xy 62.669178 -287.824926) (xy 62.330076 -287.824926) (xy 62.329581 -287.849533) (xy 62.321686 -287.89811)
			(xy 62.306102 -287.944791) (xy 62.283231 -287.988368) (xy 62.253666 -288.027712) (xy 62.218173 -288.061804)
			(xy 62.17767 -288.08976) (xy 62.133208 -288.110858) (xy 62.085937 -288.12455) (xy 62.037082 -288.130482)
			(xy 61.987907 -288.128501) (xy 61.939688 -288.118657) (xy 61.893672 -288.101205) (xy 61.851051 -288.076598)
			(xy 61.81293 -288.045473) (xy 61.780295 -288.008636) (xy 61.753992 -287.96704) (xy 61.734701 -287.921764)
			(xy 61.722924 -287.87398) (xy 61.718964 -287.824926) (xy 61.380116 -287.824926) (xy 61.379621 -287.849533)
			(xy 61.371726 -287.89811) (xy 61.356142 -287.944791) (xy 61.333271 -287.988368) (xy 61.303706 -288.027712)
			(xy 61.268213 -288.061804) (xy 61.22771 -288.08976) (xy 61.183248 -288.110858) (xy 61.135977 -288.12455)
			(xy 61.087122 -288.130482) (xy 61.037947 -288.128501) (xy 60.989728 -288.118657) (xy 60.943712 -288.101205)
			(xy 60.901091 -288.076598) (xy 60.86297 -288.045473) (xy 60.830335 -288.008636) (xy 60.804032 -287.96704)
			(xy 60.784741 -287.921764) (xy 60.772964 -287.87398) (xy 60.769004 -287.824926) (xy 60.421183 -287.824926)
			(xy 60.421766 -287.826672) (xy 60.429661 -287.875249) (xy 60.430156 -287.899856) (xy 60.429661 -287.924463)
			(xy 60.421766 -287.97304) (xy 60.406182 -288.019721) (xy 60.383311 -288.063298) (xy 60.353746 -288.102642)
			(xy 60.318253 -288.136734) (xy 60.27775 -288.16469) (xy 60.233288 -288.185788) (xy 60.186017 -288.19948)
			(xy 60.137162 -288.205412) (xy 60.087987 -288.203431) (xy 60.039768 -288.193587) (xy 59.993752 -288.176135)
			(xy 59.951131 -288.151528) (xy 59.91301 -288.120403) (xy 59.880375 -288.083566) (xy 59.854072 -288.04197)
			(xy 59.834781 -287.996694) (xy 59.823004 -287.94891) (xy 59.819044 -287.899856) (xy 58.480888 -287.899856)
			(xy 58.478718 -287.902744) (xy 58.443225 -287.936836) (xy 58.402722 -287.964792) (xy 58.35826 -287.98589)
			(xy 58.310989 -287.999582) (xy 58.262134 -288.005514) (xy 58.212959 -288.003533) (xy 58.16474 -287.993689)
			(xy 58.118724 -287.976237) (xy 58.076103 -287.95163) (xy 58.037982 -287.920505) (xy 58.005347 -287.883668)
			(xy 57.979044 -287.842072) (xy 57.959753 -287.796796) (xy 57.947976 -287.749012) (xy 57.944016 -287.699958)
			(xy 57.553624 -287.699958) (xy 57.556302 -287.705061) (xy 57.571886 -287.751742) (xy 57.579781 -287.800319)
			(xy 57.580276 -287.824926) (xy 57.579781 -287.849533) (xy 57.571886 -287.89811) (xy 57.556302 -287.944791)
			(xy 57.533431 -287.988368) (xy 57.503866 -288.027712) (xy 57.468373 -288.061804) (xy 57.42787 -288.08976)
			(xy 57.383408 -288.110858) (xy 57.336137 -288.12455) (xy 57.287282 -288.130482) (xy 57.238107 -288.128501)
			(xy 57.189888 -288.118657) (xy 57.143872 -288.101205) (xy 57.101251 -288.076598) (xy 57.06313 -288.045473)
			(xy 57.030495 -288.008636) (xy 57.004192 -287.96704) (xy 56.984901 -287.921764) (xy 56.973124 -287.87398)
			(xy 56.969164 -287.824926) (xy 56.630062 -287.824926) (xy 56.629567 -287.849533) (xy 56.621672 -287.89811)
			(xy 56.606088 -287.944791) (xy 56.583217 -287.988368) (xy 56.553652 -288.027712) (xy 56.518159 -288.061804)
			(xy 56.477656 -288.08976) (xy 56.433194 -288.110858) (xy 56.385923 -288.12455) (xy 56.337068 -288.130482)
			(xy 56.287893 -288.128501) (xy 56.239674 -288.118657) (xy 56.193658 -288.101205) (xy 56.151037 -288.076598)
			(xy 56.112916 -288.045473) (xy 56.080281 -288.008636) (xy 56.053978 -287.96704) (xy 56.034687 -287.921764)
			(xy 56.02291 -287.87398) (xy 56.01895 -287.824926) (xy 55.680102 -287.824926) (xy 55.679607 -287.849533)
			(xy 55.671712 -287.89811) (xy 55.656128 -287.944791) (xy 55.633257 -287.988368) (xy 55.603692 -288.027712)
			(xy 55.568199 -288.061804) (xy 55.527696 -288.08976) (xy 55.483234 -288.110858) (xy 55.435963 -288.12455)
			(xy 55.387108 -288.130482) (xy 55.337933 -288.128501) (xy 55.289714 -288.118657) (xy 55.243698 -288.101205)
			(xy 55.201077 -288.076598) (xy 55.162956 -288.045473) (xy 55.130321 -288.008636) (xy 55.104018 -287.96704)
			(xy 55.084727 -287.921764) (xy 55.07295 -287.87398) (xy 55.06899 -287.824926) (xy 54.730142 -287.824926)
			(xy 54.729647 -287.849533) (xy 54.721752 -287.89811) (xy 54.706168 -287.944791) (xy 54.683297 -287.988368)
			(xy 54.653732 -288.027712) (xy 54.618239 -288.061804) (xy 54.577736 -288.08976) (xy 54.533274 -288.110858)
			(xy 54.486003 -288.12455) (xy 54.437148 -288.130482) (xy 54.387973 -288.128501) (xy 54.339754 -288.118657)
			(xy 54.293738 -288.101205) (xy 54.251117 -288.076598) (xy 54.212996 -288.045473) (xy 54.180361 -288.008636)
			(xy 54.154058 -287.96704) (xy 54.134767 -287.921764) (xy 54.12299 -287.87398) (xy 54.11903 -287.824926)
			(xy 53.780182 -287.824926) (xy 53.779687 -287.849533) (xy 53.771792 -287.89811) (xy 53.756208 -287.944791)
			(xy 53.733337 -287.988368) (xy 53.703772 -288.027712) (xy 53.668279 -288.061804) (xy 53.627776 -288.08976)
			(xy 53.583314 -288.110858) (xy 53.536043 -288.12455) (xy 53.487188 -288.130482) (xy 53.438013 -288.128501)
			(xy 53.389794 -288.118657) (xy 53.343778 -288.101205) (xy 53.301157 -288.076598) (xy 53.263036 -288.045473)
			(xy 53.230401 -288.008636) (xy 53.204098 -287.96704) (xy 53.184807 -287.921764) (xy 53.17303 -287.87398)
			(xy 53.16907 -287.824926) (xy 52.830222 -287.824926) (xy 52.829727 -287.849533) (xy 52.821832 -287.89811)
			(xy 52.806248 -287.944791) (xy 52.783377 -287.988368) (xy 52.753812 -288.027712) (xy 52.718319 -288.061804)
			(xy 52.677816 -288.08976) (xy 52.633354 -288.110858) (xy 52.586083 -288.12455) (xy 52.537228 -288.130482)
			(xy 52.488053 -288.128501) (xy 52.439834 -288.118657) (xy 52.393818 -288.101205) (xy 52.351197 -288.076598)
			(xy 52.313076 -288.045473) (xy 52.280441 -288.008636) (xy 52.254138 -287.96704) (xy 52.234847 -287.921764)
			(xy 52.22307 -287.87398) (xy 52.21911 -287.824926) (xy 51.880262 -287.824926) (xy 51.879767 -287.849533)
			(xy 51.871872 -287.89811) (xy 51.856288 -287.944791) (xy 51.833417 -287.988368) (xy 51.803852 -288.027712)
			(xy 51.768359 -288.061804) (xy 51.727856 -288.08976) (xy 51.683394 -288.110858) (xy 51.636123 -288.12455)
			(xy 51.587268 -288.130482) (xy 51.538093 -288.128501) (xy 51.489874 -288.118657) (xy 51.443858 -288.101205)
			(xy 51.401237 -288.076598) (xy 51.363116 -288.045473) (xy 51.330481 -288.008636) (xy 51.304178 -287.96704)
			(xy 51.284887 -287.921764) (xy 51.27311 -287.87398) (xy 51.26915 -287.824926) (xy 50.930302 -287.824926)
			(xy 50.929807 -287.849533) (xy 50.921912 -287.89811) (xy 50.906328 -287.944791) (xy 50.883457 -287.988368)
			(xy 50.853892 -288.027712) (xy 50.818399 -288.061804) (xy 50.777896 -288.08976) (xy 50.733434 -288.110858)
			(xy 50.686163 -288.12455) (xy 50.637308 -288.130482) (xy 50.588133 -288.128501) (xy 50.539914 -288.118657)
			(xy 50.493898 -288.101205) (xy 50.451277 -288.076598) (xy 50.413156 -288.045473) (xy 50.380521 -288.008636)
			(xy 50.354218 -287.96704) (xy 50.334927 -287.921764) (xy 50.32315 -287.87398) (xy 50.31919 -287.824926)
			(xy 49.980088 -287.824926) (xy 49.979593 -287.849533) (xy 49.971698 -287.89811) (xy 49.956114 -287.944791)
			(xy 49.933243 -287.988368) (xy 49.903678 -288.027712) (xy 49.868185 -288.061804) (xy 49.827682 -288.08976)
			(xy 49.78322 -288.110858) (xy 49.735949 -288.12455) (xy 49.687094 -288.130482) (xy 49.637919 -288.128501)
			(xy 49.5897 -288.118657) (xy 49.543684 -288.101205) (xy 49.501063 -288.076598) (xy 49.462942 -288.045473)
			(xy 49.430307 -288.008636) (xy 49.404004 -287.96704) (xy 49.384713 -287.921764) (xy 49.372936 -287.87398)
			(xy 49.368976 -287.824926) (xy 49.030128 -287.824926) (xy 49.029633 -287.849533) (xy 49.021738 -287.89811)
			(xy 49.006154 -287.944791) (xy 48.983283 -287.988368) (xy 48.953718 -288.027712) (xy 48.918225 -288.061804)
			(xy 48.877722 -288.08976) (xy 48.83326 -288.110858) (xy 48.785989 -288.12455) (xy 48.737134 -288.130482)
			(xy 48.687959 -288.128501) (xy 48.63974 -288.118657) (xy 48.593724 -288.101205) (xy 48.551103 -288.076598)
			(xy 48.512982 -288.045473) (xy 48.480347 -288.008636) (xy 48.454044 -287.96704) (xy 48.434753 -287.921764)
			(xy 48.422976 -287.87398) (xy 48.419016 -287.824926) (xy 48.080168 -287.824926) (xy 48.079673 -287.849533)
			(xy 48.071778 -287.89811) (xy 48.056194 -287.944791) (xy 48.033323 -287.988368) (xy 48.003758 -288.027712)
			(xy 47.968265 -288.061804) (xy 47.927762 -288.08976) (xy 47.8833 -288.110858) (xy 47.836029 -288.12455)
			(xy 47.787174 -288.130482) (xy 47.737999 -288.128501) (xy 47.68978 -288.118657) (xy 47.643764 -288.101205)
			(xy 47.601143 -288.076598) (xy 47.563022 -288.045473) (xy 47.530387 -288.008636) (xy 47.504084 -287.96704)
			(xy 47.484793 -287.921764) (xy 47.473016 -287.87398) (xy 47.469056 -287.824926) (xy 47.130208 -287.824926)
			(xy 47.129713 -287.849533) (xy 47.121818 -287.89811) (xy 47.106234 -287.944791) (xy 47.083363 -287.988368)
			(xy 47.053798 -288.027712) (xy 47.018305 -288.061804) (xy 46.977802 -288.08976) (xy 46.93334 -288.110858)
			(xy 46.886069 -288.12455) (xy 46.837214 -288.130482) (xy 46.788039 -288.128501) (xy 46.73982 -288.118657)
			(xy 46.693804 -288.101205) (xy 46.651183 -288.076598) (xy 46.613062 -288.045473) (xy 46.580427 -288.008636)
			(xy 46.554124 -287.96704) (xy 46.534833 -287.921764) (xy 46.523056 -287.87398) (xy 46.519096 -287.824926)
			(xy 46.180248 -287.824926) (xy 46.179753 -287.849533) (xy 46.171858 -287.89811) (xy 46.156274 -287.944791)
			(xy 46.133403 -287.988368) (xy 46.103838 -288.027712) (xy 46.068345 -288.061804) (xy 46.027842 -288.08976)
			(xy 45.98338 -288.110858) (xy 45.936109 -288.12455) (xy 45.887254 -288.130482) (xy 45.838079 -288.128501)
			(xy 45.78986 -288.118657) (xy 45.743844 -288.101205) (xy 45.701223 -288.076598) (xy 45.663102 -288.045473)
			(xy 45.630467 -288.008636) (xy 45.604164 -287.96704) (xy 45.584873 -287.921764) (xy 45.573096 -287.87398)
			(xy 45.569136 -287.824926) (xy 45.230288 -287.824926) (xy 45.229793 -287.849533) (xy 45.221898 -287.89811)
			(xy 45.206314 -287.944791) (xy 45.183443 -287.988368) (xy 45.153878 -288.027712) (xy 45.118385 -288.061804)
			(xy 45.077882 -288.08976) (xy 45.03342 -288.110858) (xy 44.986149 -288.12455) (xy 44.937294 -288.130482)
			(xy 44.888119 -288.128501) (xy 44.8399 -288.118657) (xy 44.793884 -288.101205) (xy 44.751263 -288.076598)
			(xy 44.713142 -288.045473) (xy 44.680507 -288.008636) (xy 44.654204 -287.96704) (xy 44.634913 -287.921764)
			(xy 44.623136 -287.87398) (xy 44.619176 -287.824926) (xy 44.280074 -287.824926) (xy 44.279579 -287.849533)
			(xy 44.271684 -287.89811) (xy 44.2561 -287.944791) (xy 44.233229 -287.988368) (xy 44.203664 -288.027712)
			(xy 44.168171 -288.061804) (xy 44.127668 -288.08976) (xy 44.083206 -288.110858) (xy 44.035935 -288.12455)
			(xy 43.98708 -288.130482) (xy 43.937905 -288.128501) (xy 43.889686 -288.118657) (xy 43.84367 -288.101205)
			(xy 43.801049 -288.076598) (xy 43.762928 -288.045473) (xy 43.730293 -288.008636) (xy 43.70399 -287.96704)
			(xy 43.684699 -287.921764) (xy 43.672922 -287.87398) (xy 43.668962 -287.824926) (xy 43.330114 -287.824926)
			(xy 43.329619 -287.849533) (xy 43.321724 -287.89811) (xy 43.30614 -287.944791) (xy 43.283269 -287.988368)
			(xy 43.253704 -288.027712) (xy 43.218211 -288.061804) (xy 43.177708 -288.08976) (xy 43.133246 -288.110858)
			(xy 43.085975 -288.12455) (xy 43.03712 -288.130482) (xy 42.987945 -288.128501) (xy 42.939726 -288.118657)
			(xy 42.89371 -288.101205) (xy 42.851089 -288.076598) (xy 42.812968 -288.045473) (xy 42.780333 -288.008636)
			(xy 42.75403 -287.96704) (xy 42.734739 -287.921764) (xy 42.722962 -287.87398) (xy 42.719002 -287.824926)
			(xy 42.40527 -287.824926) (xy 42.40527 -287.850406) (xy 42.397134 -287.901778) (xy 42.381063 -287.951246)
			(xy 42.357451 -287.99759) (xy 42.326882 -288.039671) (xy 42.290106 -288.076452) (xy 42.248029 -288.107027)
			(xy 42.201688 -288.130645) (xy 42.152223 -288.146723) (xy 42.100852 -288.154866) (xy 42.074846 -288.15538)
			(xy 41.124886 -288.15538) (xy 41.098881 -288.154833) (xy 41.047512 -288.146695) (xy 40.998048 -288.130621)
			(xy 40.951707 -288.107008) (xy 40.909631 -288.076436) (xy 40.872855 -288.039658) (xy 40.842285 -287.997581)
			(xy 40.818674 -287.951239) (xy 40.802602 -287.901775) (xy 40.794466 -287.850405) (xy 40.479597 -287.850405)
			(xy 40.471844 -287.89811) (xy 40.45626 -287.944791) (xy 40.433389 -287.988368) (xy 40.403824 -288.027712)
			(xy 40.368331 -288.061804) (xy 40.327828 -288.08976) (xy 40.283366 -288.110858) (xy 40.236095 -288.12455)
			(xy 40.18724 -288.130482) (xy 40.138065 -288.128501) (xy 40.089846 -288.118657) (xy 40.04383 -288.101205)
			(xy 40.001209 -288.076598) (xy 39.963088 -288.045473) (xy 39.930453 -288.008636) (xy 39.90415 -287.96704)
			(xy 39.884859 -287.921764) (xy 39.873082 -287.87398) (xy 39.869122 -287.824926) (xy 39.555496 -287.824926)
			(xy 39.555496 -287.850412) (xy 39.547357 -287.901796) (xy 39.53128 -287.951275) (xy 39.50766 -287.997628)
			(xy 39.477079 -288.039716) (xy 39.44029 -288.076501) (xy 39.398199 -288.107078) (xy 39.351843 -288.130693)
			(xy 39.302363 -288.146765) (xy 39.250978 -288.154899) (xy 39.224966 -288.15538) (xy 38.275006 -288.15538)
			(xy 38.248998 -288.154861) (xy 38.197622 -288.146725) (xy 38.148151 -288.130652) (xy 38.101804 -288.107037)
			(xy 38.059722 -288.076463) (xy 38.02294 -288.039683) (xy 37.992366 -287.997601) (xy 37.968751 -287.951254)
			(xy 37.952677 -287.901784) (xy 37.944539 -287.850408) (xy 37.629463 -287.850408) (xy 37.62171 -287.89811)
			(xy 37.606126 -287.944791) (xy 37.583255 -287.988368) (xy 37.55369 -288.027712) (xy 37.518197 -288.061804)
			(xy 37.477694 -288.08976) (xy 37.433232 -288.110858) (xy 37.385961 -288.12455) (xy 37.337106 -288.130482)
			(xy 37.287931 -288.128501) (xy 37.239712 -288.118657) (xy 37.193696 -288.101205) (xy 37.151075 -288.076598)
			(xy 37.112954 -288.045473) (xy 37.080319 -288.008636) (xy 37.054016 -287.96704) (xy 37.034725 -287.921764)
			(xy 37.022948 -287.87398) (xy 37.018988 -287.824926) (xy 36.68014 -287.824926) (xy 36.679645 -287.849533)
			(xy 36.67175 -287.89811) (xy 36.656166 -287.944791) (xy 36.633295 -287.988368) (xy 36.60373 -288.027712)
			(xy 36.568237 -288.061804) (xy 36.527734 -288.08976) (xy 36.483272 -288.110858) (xy 36.436001 -288.12455)
			(xy 36.387146 -288.130482) (xy 36.337971 -288.128501) (xy 36.289752 -288.118657) (xy 36.243736 -288.101205)
			(xy 36.201115 -288.076598) (xy 36.162994 -288.045473) (xy 36.130359 -288.008636) (xy 36.104056 -287.96704)
			(xy 36.084765 -287.921764) (xy 36.072988 -287.87398) (xy 36.069028 -287.824926) (xy 15.064266 -287.824926)
			(xy 15.07913 -287.875546) (xy 15.086887 -287.929497) (xy 15.086887 -287.984003) (xy 15.07913 -288.037954)
			(xy 15.063773 -288.090253) (xy 15.041131 -288.139833) (xy 15.011662 -288.185687) (xy 14.975968 -288.22688)
			(xy 14.972303 -288.230056) (xy 25.811478 -288.230056) (xy 25.815549 -288.174434) (xy 25.827675 -288.119997)
			(xy 25.847598 -288.067906) (xy 25.874894 -288.019271) (xy 25.90898 -287.975128) (xy 25.949129 -287.936419)
			(xy 25.994487 -287.903968) (xy 26.044087 -287.878467) (xy 26.096871 -287.86046) (xy 26.151714 -287.85033)
			(xy 26.207448 -287.848293) (xy 26.262885 -287.854393) (xy 26.316842 -287.868499) (xy 26.368171 -287.890311)
			(xy 26.415777 -287.919365) (xy 26.458645 -287.95504) (xy 26.495862 -287.996577) (xy 26.526635 -288.04309)
			(xy 26.550307 -288.093587) (xy 26.566375 -288.146994) (xy 26.574495 -288.20217) (xy 26.575004 -288.230056)
			(xy 27.296616 -288.230056) (xy 27.300687 -288.174434) (xy 27.312813 -288.119997) (xy 27.332736 -288.067906)
			(xy 27.360032 -288.019271) (xy 27.394118 -287.975128) (xy 27.434267 -287.936419) (xy 27.479625 -287.903968)
			(xy 27.529225 -287.878467) (xy 27.582009 -287.86046) (xy 27.636852 -287.85033) (xy 27.692586 -287.848293)
			(xy 27.748023 -287.854393) (xy 27.80198 -287.868499) (xy 27.853309 -287.890311) (xy 27.900915 -287.919365)
			(xy 27.943783 -287.95504) (xy 27.981 -287.996577) (xy 28.011773 -288.04309) (xy 28.035445 -288.093587)
			(xy 28.051513 -288.146994) (xy 28.059633 -288.20217) (xy 28.060142 -288.230056) (xy 28.059633 -288.257942)
			(xy 28.051513 -288.313118) (xy 28.035445 -288.366525) (xy 28.011773 -288.417022) (xy 27.981 -288.463535)
			(xy 27.943783 -288.505072) (xy 27.900915 -288.540747) (xy 27.853309 -288.569801) (xy 27.80198 -288.591613)
			(xy 27.748023 -288.605719) (xy 27.692586 -288.611819) (xy 27.636852 -288.609782) (xy 27.582009 -288.599652)
			(xy 27.529225 -288.581645) (xy 27.479625 -288.556144) (xy 27.434267 -288.523693) (xy 27.394118 -288.484984)
			(xy 27.360032 -288.440841) (xy 27.332736 -288.392206) (xy 27.312813 -288.340115) (xy 27.300687 -288.285678)
			(xy 27.296616 -288.230056) (xy 26.575004 -288.230056) (xy 26.574495 -288.257942) (xy 26.566375 -288.313118)
			(xy 26.550307 -288.366525) (xy 26.526635 -288.417022) (xy 26.495862 -288.463535) (xy 26.458645 -288.505072)
			(xy 26.415777 -288.540747) (xy 26.368171 -288.569801) (xy 26.316842 -288.591613) (xy 26.262885 -288.605719)
			(xy 26.207448 -288.611819) (xy 26.151714 -288.609782) (xy 26.096871 -288.599652) (xy 26.044087 -288.581645)
			(xy 25.994487 -288.556144) (xy 25.949129 -288.523693) (xy 25.90898 -288.484984) (xy 25.874894 -288.440841)
			(xy 25.847598 -288.392206) (xy 25.827675 -288.340115) (xy 25.815549 -288.285678) (xy 25.811478 -288.230056)
			(xy 14.972303 -288.230056) (xy 14.934775 -288.262573) (xy 14.888921 -288.292042) (xy 14.839341 -288.314684)
			(xy 14.787043 -288.33004) (xy 14.733091 -288.337797) (xy 14.705838 -288.33826) (xy 14.678468 -288.337781)
			(xy 14.624289 -288.329968) (xy 14.571786 -288.314482) (xy 14.522039 -288.291643) (xy 14.476072 -288.261921)
			(xy 14.45514 -288.24428) (xy 14.448028 -288.238184) (xy 14.43101 -288.231834) (xy 14.345666 -288.231834)
			(xy 14.328648 -288.238184) (xy 14.321536 -288.24428) (xy 14.300599 -288.261913) (xy 14.254628 -288.291626)
			(xy 14.204881 -288.314464) (xy 14.152382 -288.329956) (xy 14.098207 -288.337785) (xy 14.070838 -288.33826)
			(xy 14.043587 -288.33777) (xy 13.98964 -288.330013) (xy 13.937346 -288.314658) (xy 13.887769 -288.292017)
			(xy 13.841919 -288.262551) (xy 13.800729 -288.226859) (xy 13.765038 -288.18567) (xy 13.735572 -288.139819)
			(xy 13.712931 -288.090243) (xy 13.697576 -288.037948) (xy 13.68982 -287.984001) (xy 13.346987 -287.984001)
			(xy 13.346987 -287.984003) (xy 13.33923 -288.037954) (xy 13.323873 -288.090253) (xy 13.301231 -288.139833)
			(xy 13.271762 -288.185687) (xy 13.236068 -288.22688) (xy 13.194875 -288.262573) (xy 13.149021 -288.292042)
			(xy 13.099441 -288.314684) (xy 13.047143 -288.33004) (xy 12.993191 -288.337797) (xy 12.965938 -288.33826)
			(xy 12.938568 -288.337781) (xy 12.884389 -288.329968) (xy 12.831886 -288.314482) (xy 12.782139 -288.291643)
			(xy 12.736172 -288.261921) (xy 12.71524 -288.24428) (xy 12.708128 -288.238184) (xy 12.69111 -288.231834)
			(xy 12.605766 -288.231834) (xy 12.588748 -288.238184) (xy 12.581636 -288.24428) (xy 12.560699 -288.261913)
			(xy 12.514728 -288.291626) (xy 12.464981 -288.314464) (xy 12.412482 -288.329956) (xy 12.358307 -288.337785)
			(xy 12.330938 -288.33826) (xy 12.303687 -288.33777) (xy 12.24974 -288.330013) (xy 12.197446 -288.314658)
			(xy 12.147869 -288.292017) (xy 12.102019 -288.262551) (xy 12.060829 -288.226859) (xy 12.025138 -288.18567)
			(xy 11.995672 -288.139819) (xy 11.973031 -288.090243) (xy 11.957676 -288.037948) (xy 11.94992 -287.984001)
			(xy 1.468374 -287.984001) (xy 1.468374 -288.774886) (xy 35.119068 -288.774886) (xy 35.123028 -288.725832)
			(xy 35.134805 -288.678048) (xy 35.154096 -288.632772) (xy 35.180399 -288.591176) (xy 35.213034 -288.554339)
			(xy 35.251155 -288.523214) (xy 35.293776 -288.498607) (xy 35.339792 -288.481155) (xy 35.388011 -288.471311)
			(xy 35.437186 -288.46933) (xy 35.486041 -288.475262) (xy 35.533312 -288.488954) (xy 35.577774 -288.510052)
			(xy 35.618277 -288.538008) (xy 35.65377 -288.5721) (xy 35.683335 -288.611444) (xy 35.706206 -288.655021)
			(xy 35.72179 -288.701702) (xy 35.729685 -288.750279) (xy 35.73018 -288.774886) (xy 35.729685 -288.799493)
			(xy 35.729535 -288.800413) (xy 36.0443 -288.800413) (xy 36.0443 -288.748387) (xy 36.052439 -288.697003)
			(xy 36.068516 -288.647524) (xy 36.092136 -288.60117) (xy 36.122718 -288.559082) (xy 36.159507 -288.522297)
			(xy 36.201598 -288.49172) (xy 36.247954 -288.468104) (xy 36.297434 -288.452031) (xy 36.348819 -288.443897)
			(xy 36.374832 -288.443416) (xy 37.324792 -288.443416) (xy 37.3508 -288.443943) (xy 37.402175 -288.452079)
			(xy 37.451646 -288.468151) (xy 37.497993 -288.491765) (xy 37.540075 -288.522339) (xy 37.576856 -288.559119)
			(xy 37.60743 -288.601201) (xy 37.631045 -288.647547) (xy 37.647119 -288.697017) (xy 37.655257 -288.748392)
			(xy 37.655257 -288.774886) (xy 37.969202 -288.774886) (xy 37.973162 -288.725832) (xy 37.984939 -288.678048)
			(xy 38.00423 -288.632772) (xy 38.030533 -288.591176) (xy 38.063168 -288.554339) (xy 38.101289 -288.523214)
			(xy 38.14391 -288.498607) (xy 38.189926 -288.481155) (xy 38.238145 -288.471311) (xy 38.28732 -288.46933)
			(xy 38.336175 -288.475262) (xy 38.383446 -288.488954) (xy 38.427908 -288.510052) (xy 38.468411 -288.538008)
			(xy 38.503904 -288.5721) (xy 38.533469 -288.611444) (xy 38.55634 -288.655021) (xy 38.571924 -288.701702)
			(xy 38.579819 -288.750279) (xy 38.580314 -288.774886) (xy 41.769042 -288.774886) (xy 41.773002 -288.725832)
			(xy 41.784779 -288.678048) (xy 41.80407 -288.632772) (xy 41.830373 -288.591176) (xy 41.863008 -288.554339)
			(xy 41.901129 -288.523214) (xy 41.94375 -288.498607) (xy 41.989766 -288.481155) (xy 42.037985 -288.471311)
			(xy 42.08716 -288.46933) (xy 42.136015 -288.475262) (xy 42.183286 -288.488954) (xy 42.227748 -288.510052)
			(xy 42.268251 -288.538008) (xy 42.303744 -288.5721) (xy 42.333309 -288.611444) (xy 42.35618 -288.655021)
			(xy 42.371764 -288.701702) (xy 42.379659 -288.750279) (xy 42.380154 -288.774886) (xy 42.379659 -288.799493)
			(xy 42.37951 -288.800411) (xy 42.694299 -288.800411) (xy 42.694299 -288.748389) (xy 42.702438 -288.697007)
			(xy 42.718514 -288.64753) (xy 42.742132 -288.601178) (xy 42.77271 -288.559091) (xy 42.809496 -288.522306)
			(xy 42.851583 -288.491729) (xy 42.897936 -288.468111) (xy 42.947413 -288.452036) (xy 42.998795 -288.443899)
			(xy 43.024806 -288.443416) (xy 43.974766 -288.443416) (xy 44.000775 -288.443941) (xy 44.052154 -288.452074)
			(xy 44.101628 -288.468144) (xy 44.147978 -288.491757) (xy 44.190064 -288.52233) (xy 44.226848 -288.55911)
			(xy 44.257426 -288.601193) (xy 44.281043 -288.647541) (xy 44.297119 -288.697013) (xy 44.305257 -288.748391)
			(xy 44.305257 -288.774886) (xy 44.619176 -288.774886) (xy 44.623136 -288.725832) (xy 44.634913 -288.678048)
			(xy 44.654204 -288.632772) (xy 44.680507 -288.591176) (xy 44.713142 -288.554339) (xy 44.751263 -288.523214)
			(xy 44.793884 -288.498607) (xy 44.8399 -288.481155) (xy 44.888119 -288.471311) (xy 44.937294 -288.46933)
			(xy 44.986149 -288.475262) (xy 45.03342 -288.488954) (xy 45.077882 -288.510052) (xy 45.118385 -288.538008)
			(xy 45.153878 -288.5721) (xy 45.183443 -288.611444) (xy 45.206314 -288.655021) (xy 45.221898 -288.701702)
			(xy 45.229793 -288.750279) (xy 45.230288 -288.774886) (xy 45.569136 -288.774886) (xy 45.573096 -288.725832)
			(xy 45.584873 -288.678048) (xy 45.604164 -288.632772) (xy 45.630467 -288.591176) (xy 45.663102 -288.554339)
			(xy 45.701223 -288.523214) (xy 45.743844 -288.498607) (xy 45.78986 -288.481155) (xy 45.838079 -288.471311)
			(xy 45.887254 -288.46933) (xy 45.936109 -288.475262) (xy 45.98338 -288.488954) (xy 46.027842 -288.510052)
			(xy 46.068345 -288.538008) (xy 46.103838 -288.5721) (xy 46.133403 -288.611444) (xy 46.156274 -288.655021)
			(xy 46.171858 -288.701702) (xy 46.179753 -288.750279) (xy 46.180248 -288.774886) (xy 46.519096 -288.774886)
			(xy 46.523056 -288.725832) (xy 46.534833 -288.678048) (xy 46.554124 -288.632772) (xy 46.580427 -288.591176)
			(xy 46.613062 -288.554339) (xy 46.651183 -288.523214) (xy 46.693804 -288.498607) (xy 46.73982 -288.481155)
			(xy 46.788039 -288.471311) (xy 46.837214 -288.46933) (xy 46.886069 -288.475262) (xy 46.93334 -288.488954)
			(xy 46.977802 -288.510052) (xy 47.018305 -288.538008) (xy 47.053798 -288.5721) (xy 47.083363 -288.611444)
			(xy 47.106234 -288.655021) (xy 47.121818 -288.701702) (xy 47.129713 -288.750279) (xy 47.130208 -288.774886)
			(xy 47.469056 -288.774886) (xy 47.473016 -288.725832) (xy 47.484793 -288.678048) (xy 47.504084 -288.632772)
			(xy 47.530387 -288.591176) (xy 47.563022 -288.554339) (xy 47.601143 -288.523214) (xy 47.643764 -288.498607)
			(xy 47.68978 -288.481155) (xy 47.737999 -288.471311) (xy 47.787174 -288.46933) (xy 47.836029 -288.475262)
			(xy 47.8833 -288.488954) (xy 47.927762 -288.510052) (xy 47.968265 -288.538008) (xy 48.003758 -288.5721)
			(xy 48.033323 -288.611444) (xy 48.056194 -288.655021) (xy 48.071778 -288.701702) (xy 48.079673 -288.750279)
			(xy 48.080168 -288.774886) (xy 48.419016 -288.774886) (xy 48.422976 -288.725832) (xy 48.434753 -288.678048)
			(xy 48.454044 -288.632772) (xy 48.480347 -288.591176) (xy 48.512982 -288.554339) (xy 48.551103 -288.523214)
			(xy 48.593724 -288.498607) (xy 48.63974 -288.481155) (xy 48.687959 -288.471311) (xy 48.737134 -288.46933)
			(xy 48.785989 -288.475262) (xy 48.83326 -288.488954) (xy 48.877722 -288.510052) (xy 48.918225 -288.538008)
			(xy 48.953718 -288.5721) (xy 48.983283 -288.611444) (xy 49.006154 -288.655021) (xy 49.021738 -288.701702)
			(xy 49.029633 -288.750279) (xy 49.030128 -288.774886) (xy 49.368976 -288.774886) (xy 49.372936 -288.725832)
			(xy 49.384713 -288.678048) (xy 49.404004 -288.632772) (xy 49.430307 -288.591176) (xy 49.462942 -288.554339)
			(xy 49.501063 -288.523214) (xy 49.543684 -288.498607) (xy 49.5897 -288.481155) (xy 49.637919 -288.471311)
			(xy 49.687094 -288.46933) (xy 49.735949 -288.475262) (xy 49.78322 -288.488954) (xy 49.827682 -288.510052)
			(xy 49.868185 -288.538008) (xy 49.903678 -288.5721) (xy 49.933243 -288.611444) (xy 49.956114 -288.655021)
			(xy 49.971698 -288.701702) (xy 49.979593 -288.750279) (xy 49.980088 -288.774886) (xy 68.368938 -288.774886)
			(xy 68.372898 -288.725832) (xy 68.384675 -288.678048) (xy 68.403966 -288.632772) (xy 68.430269 -288.591176)
			(xy 68.462904 -288.554339) (xy 68.501025 -288.523214) (xy 68.543646 -288.498607) (xy 68.589662 -288.481155)
			(xy 68.637881 -288.471311) (xy 68.687056 -288.46933) (xy 68.735911 -288.475262) (xy 68.783182 -288.488954)
			(xy 68.827644 -288.510052) (xy 68.868147 -288.538008) (xy 68.90364 -288.5721) (xy 68.933205 -288.611444)
			(xy 68.956076 -288.655021) (xy 68.97166 -288.701702) (xy 68.979555 -288.750279) (xy 68.98005 -288.774886)
			(xy 69.319152 -288.774886) (xy 69.323112 -288.725832) (xy 69.334889 -288.678048) (xy 69.35418 -288.632772)
			(xy 69.380483 -288.591176) (xy 69.413118 -288.554339) (xy 69.451239 -288.523214) (xy 69.49386 -288.498607)
			(xy 69.539876 -288.481155) (xy 69.588095 -288.471311) (xy 69.63727 -288.46933) (xy 69.686125 -288.475262)
			(xy 69.733396 -288.488954) (xy 69.777858 -288.510052) (xy 69.818361 -288.538008) (xy 69.853854 -288.5721)
			(xy 69.883419 -288.611444) (xy 69.90629 -288.655021) (xy 69.921874 -288.701702) (xy 69.929769 -288.750279)
			(xy 69.930264 -288.774886) (xy 70.269112 -288.774886) (xy 70.273072 -288.725832) (xy 70.284849 -288.678048)
			(xy 70.30414 -288.632772) (xy 70.330443 -288.591176) (xy 70.363078 -288.554339) (xy 70.401199 -288.523214)
			(xy 70.44382 -288.498607) (xy 70.489836 -288.481155) (xy 70.538055 -288.471311) (xy 70.58723 -288.46933)
			(xy 70.636085 -288.475262) (xy 70.683356 -288.488954) (xy 70.727818 -288.510052) (xy 70.768321 -288.538008)
			(xy 70.803814 -288.5721) (xy 70.833379 -288.611444) (xy 70.85625 -288.655021) (xy 70.871834 -288.701702)
			(xy 70.879729 -288.750279) (xy 70.880224 -288.774886) (xy 71.219072 -288.774886) (xy 71.223032 -288.725832)
			(xy 71.234809 -288.678048) (xy 71.2541 -288.632772) (xy 71.280403 -288.591176) (xy 71.313038 -288.554339)
			(xy 71.351159 -288.523214) (xy 71.39378 -288.498607) (xy 71.439796 -288.481155) (xy 71.488015 -288.471311)
			(xy 71.53719 -288.46933) (xy 71.586045 -288.475262) (xy 71.633316 -288.488954) (xy 71.677778 -288.510052)
			(xy 71.718281 -288.538008) (xy 71.753774 -288.5721) (xy 71.783339 -288.611444) (xy 71.80621 -288.655021)
			(xy 71.821794 -288.701702) (xy 71.829689 -288.750279) (xy 71.830184 -288.774886) (xy 72.169032 -288.774886)
			(xy 72.172992 -288.725832) (xy 72.184769 -288.678048) (xy 72.20406 -288.632772) (xy 72.230363 -288.591176)
			(xy 72.262998 -288.554339) (xy 72.301119 -288.523214) (xy 72.34374 -288.498607) (xy 72.389756 -288.481155)
			(xy 72.437975 -288.471311) (xy 72.48715 -288.46933) (xy 72.536005 -288.475262) (xy 72.583276 -288.488954)
			(xy 72.627738 -288.510052) (xy 72.668241 -288.538008) (xy 72.703734 -288.5721) (xy 72.733299 -288.611444)
			(xy 72.75617 -288.655021) (xy 72.771754 -288.701702) (xy 72.779649 -288.750279) (xy 72.780144 -288.774886)
			(xy 72.779649 -288.799493) (xy 72.771754 -288.84807) (xy 72.75617 -288.894751) (xy 72.733299 -288.938328)
			(xy 72.703734 -288.977672) (xy 72.668241 -289.011764) (xy 72.627738 -289.03972) (xy 72.583276 -289.060818)
			(xy 72.536005 -289.07451) (xy 72.48715 -289.080442) (xy 72.437975 -289.078461) (xy 72.389756 -289.068617)
			(xy 72.34374 -289.051165) (xy 72.301119 -289.026558) (xy 72.262998 -288.995433) (xy 72.230363 -288.958596)
			(xy 72.20406 -288.917) (xy 72.184769 -288.871724) (xy 72.172992 -288.82394) (xy 72.169032 -288.774886)
			(xy 71.830184 -288.774886) (xy 71.829689 -288.799493) (xy 71.821794 -288.84807) (xy 71.80621 -288.894751)
			(xy 71.783339 -288.938328) (xy 71.753774 -288.977672) (xy 71.718281 -289.011764) (xy 71.677778 -289.03972)
			(xy 71.633316 -289.060818) (xy 71.586045 -289.07451) (xy 71.53719 -289.080442) (xy 71.488015 -289.078461)
			(xy 71.439796 -289.068617) (xy 71.39378 -289.051165) (xy 71.351159 -289.026558) (xy 71.313038 -288.995433)
			(xy 71.280403 -288.958596) (xy 71.2541 -288.917) (xy 71.234809 -288.871724) (xy 71.223032 -288.82394)
			(xy 71.219072 -288.774886) (xy 70.880224 -288.774886) (xy 70.879729 -288.799493) (xy 70.871834 -288.84807)
			(xy 70.85625 -288.894751) (xy 70.833379 -288.938328) (xy 70.803814 -288.977672) (xy 70.768321 -289.011764)
			(xy 70.727818 -289.03972) (xy 70.683356 -289.060818) (xy 70.636085 -289.07451) (xy 70.58723 -289.080442)
			(xy 70.538055 -289.078461) (xy 70.489836 -289.068617) (xy 70.44382 -289.051165) (xy 70.401199 -289.026558)
			(xy 70.363078 -288.995433) (xy 70.330443 -288.958596) (xy 70.30414 -288.917) (xy 70.284849 -288.871724)
			(xy 70.273072 -288.82394) (xy 70.269112 -288.774886) (xy 69.930264 -288.774886) (xy 69.929769 -288.799493)
			(xy 69.921874 -288.84807) (xy 69.90629 -288.894751) (xy 69.883419 -288.938328) (xy 69.853854 -288.977672)
			(xy 69.818361 -289.011764) (xy 69.777858 -289.03972) (xy 69.733396 -289.060818) (xy 69.686125 -289.07451)
			(xy 69.63727 -289.080442) (xy 69.588095 -289.078461) (xy 69.539876 -289.068617) (xy 69.49386 -289.051165)
			(xy 69.451239 -289.026558) (xy 69.413118 -288.995433) (xy 69.380483 -288.958596) (xy 69.35418 -288.917)
			(xy 69.334889 -288.871724) (xy 69.323112 -288.82394) (xy 69.319152 -288.774886) (xy 68.98005 -288.774886)
			(xy 68.979555 -288.799493) (xy 68.97166 -288.84807) (xy 68.956076 -288.894751) (xy 68.933205 -288.938328)
			(xy 68.90364 -288.977672) (xy 68.868147 -289.011764) (xy 68.827644 -289.03972) (xy 68.783182 -289.060818)
			(xy 68.735911 -289.07451) (xy 68.687056 -289.080442) (xy 68.637881 -289.078461) (xy 68.589662 -289.068617)
			(xy 68.543646 -289.051165) (xy 68.501025 -289.026558) (xy 68.462904 -288.995433) (xy 68.430269 -288.958596)
			(xy 68.403966 -288.917) (xy 68.384675 -288.871724) (xy 68.372898 -288.82394) (xy 68.368938 -288.774886)
			(xy 49.980088 -288.774886) (xy 49.979593 -288.799493) (xy 49.971698 -288.84807) (xy 49.956114 -288.894751)
			(xy 49.933243 -288.938328) (xy 49.903678 -288.977672) (xy 49.868185 -289.011764) (xy 49.827682 -289.03972)
			(xy 49.78322 -289.060818) (xy 49.735949 -289.07451) (xy 49.687094 -289.080442) (xy 49.637919 -289.078461)
			(xy 49.5897 -289.068617) (xy 49.543684 -289.051165) (xy 49.501063 -289.026558) (xy 49.462942 -288.995433)
			(xy 49.430307 -288.958596) (xy 49.404004 -288.917) (xy 49.384713 -288.871724) (xy 49.372936 -288.82394)
			(xy 49.368976 -288.774886) (xy 49.030128 -288.774886) (xy 49.029633 -288.799493) (xy 49.021738 -288.84807)
			(xy 49.006154 -288.894751) (xy 48.983283 -288.938328) (xy 48.953718 -288.977672) (xy 48.918225 -289.011764)
			(xy 48.877722 -289.03972) (xy 48.83326 -289.060818) (xy 48.785989 -289.07451) (xy 48.737134 -289.080442)
			(xy 48.687959 -289.078461) (xy 48.63974 -289.068617) (xy 48.593724 -289.051165) (xy 48.551103 -289.026558)
			(xy 48.512982 -288.995433) (xy 48.480347 -288.958596) (xy 48.454044 -288.917) (xy 48.434753 -288.871724)
			(xy 48.422976 -288.82394) (xy 48.419016 -288.774886) (xy 48.080168 -288.774886) (xy 48.079673 -288.799493)
			(xy 48.071778 -288.84807) (xy 48.056194 -288.894751) (xy 48.033323 -288.938328) (xy 48.003758 -288.977672)
			(xy 47.968265 -289.011764) (xy 47.927762 -289.03972) (xy 47.8833 -289.060818) (xy 47.836029 -289.07451)
			(xy 47.787174 -289.080442) (xy 47.737999 -289.078461) (xy 47.68978 -289.068617) (xy 47.643764 -289.051165)
			(xy 47.601143 -289.026558) (xy 47.563022 -288.995433) (xy 47.530387 -288.958596) (xy 47.504084 -288.917)
			(xy 47.484793 -288.871724) (xy 47.473016 -288.82394) (xy 47.469056 -288.774886) (xy 47.130208 -288.774886)
			(xy 47.129713 -288.799493) (xy 47.121818 -288.84807) (xy 47.106234 -288.894751) (xy 47.083363 -288.938328)
			(xy 47.053798 -288.977672) (xy 47.018305 -289.011764) (xy 46.977802 -289.03972) (xy 46.93334 -289.060818)
			(xy 46.886069 -289.07451) (xy 46.837214 -289.080442) (xy 46.788039 -289.078461) (xy 46.73982 -289.068617)
			(xy 46.693804 -289.051165) (xy 46.651183 -289.026558) (xy 46.613062 -288.995433) (xy 46.580427 -288.958596)
			(xy 46.554124 -288.917) (xy 46.534833 -288.871724) (xy 46.523056 -288.82394) (xy 46.519096 -288.774886)
			(xy 46.180248 -288.774886) (xy 46.179753 -288.799493) (xy 46.171858 -288.84807) (xy 46.156274 -288.894751)
			(xy 46.133403 -288.938328) (xy 46.103838 -288.977672) (xy 46.068345 -289.011764) (xy 46.027842 -289.03972)
			(xy 45.98338 -289.060818) (xy 45.936109 -289.07451) (xy 45.887254 -289.080442) (xy 45.838079 -289.078461)
			(xy 45.78986 -289.068617) (xy 45.743844 -289.051165) (xy 45.701223 -289.026558) (xy 45.663102 -288.995433)
			(xy 45.630467 -288.958596) (xy 45.604164 -288.917) (xy 45.584873 -288.871724) (xy 45.573096 -288.82394)
			(xy 45.569136 -288.774886) (xy 45.230288 -288.774886) (xy 45.229793 -288.799493) (xy 45.221898 -288.84807)
			(xy 45.206314 -288.894751) (xy 45.183443 -288.938328) (xy 45.153878 -288.977672) (xy 45.118385 -289.011764)
			(xy 45.077882 -289.03972) (xy 45.03342 -289.060818) (xy 44.986149 -289.07451) (xy 44.937294 -289.080442)
			(xy 44.888119 -289.078461) (xy 44.8399 -289.068617) (xy 44.793884 -289.051165) (xy 44.751263 -289.026558)
			(xy 44.713142 -288.995433) (xy 44.680507 -288.958596) (xy 44.654204 -288.917) (xy 44.634913 -288.871724)
			(xy 44.623136 -288.82394) (xy 44.619176 -288.774886) (xy 44.305257 -288.774886) (xy 44.305257 -288.800409)
			(xy 44.297119 -288.851787) (xy 44.281043 -288.901259) (xy 44.257426 -288.947607) (xy 44.226848 -288.98969)
			(xy 44.190064 -289.02647) (xy 44.147978 -289.057043) (xy 44.101628 -289.080656) (xy 44.052154 -289.096726)
			(xy 44.000775 -289.104859) (xy 43.974766 -289.10534) (xy 43.024806 -289.10534) (xy 42.998795 -289.104901)
			(xy 42.947413 -289.096764) (xy 42.897936 -289.080689) (xy 42.851583 -289.057071) (xy 42.809496 -289.026494)
			(xy 42.77271 -288.989709) (xy 42.742132 -288.947622) (xy 42.718514 -288.90127) (xy 42.702438 -288.851793)
			(xy 42.694299 -288.800411) (xy 42.37951 -288.800411) (xy 42.371764 -288.84807) (xy 42.35618 -288.894751)
			(xy 42.333309 -288.938328) (xy 42.303744 -288.977672) (xy 42.268251 -289.011764) (xy 42.227748 -289.03972)
			(xy 42.183286 -289.060818) (xy 42.136015 -289.07451) (xy 42.08716 -289.080442) (xy 42.037985 -289.078461)
			(xy 41.989766 -289.068617) (xy 41.94375 -289.051165) (xy 41.901129 -289.026558) (xy 41.863008 -288.995433)
			(xy 41.830373 -288.958596) (xy 41.80407 -288.917) (xy 41.784779 -288.871724) (xy 41.773002 -288.82394)
			(xy 41.769042 -288.774886) (xy 38.580314 -288.774886) (xy 38.579819 -288.799493) (xy 38.571924 -288.84807)
			(xy 38.55634 -288.894751) (xy 38.533469 -288.938328) (xy 38.503904 -288.977672) (xy 38.468411 -289.011764)
			(xy 38.427908 -289.03972) (xy 38.383446 -289.060818) (xy 38.336175 -289.07451) (xy 38.28732 -289.080442)
			(xy 38.238145 -289.078461) (xy 38.189926 -289.068617) (xy 38.14391 -289.051165) (xy 38.101289 -289.026558)
			(xy 38.063168 -288.995433) (xy 38.030533 -288.958596) (xy 38.00423 -288.917) (xy 37.984939 -288.871724)
			(xy 37.973162 -288.82394) (xy 37.969202 -288.774886) (xy 37.655257 -288.774886) (xy 37.655257 -288.800408)
			(xy 37.647119 -288.851783) (xy 37.631045 -288.901253) (xy 37.60743 -288.947599) (xy 37.576856 -288.989681)
			(xy 37.540075 -289.026461) (xy 37.497993 -289.057035) (xy 37.451646 -289.080649) (xy 37.402175 -289.096721)
			(xy 37.3508 -289.104857) (xy 37.324792 -289.10534) (xy 36.374832 -289.10534) (xy 36.348819 -289.104903)
			(xy 36.297434 -289.096769) (xy 36.247954 -289.080696) (xy 36.201598 -289.05708) (xy 36.159507 -289.026503)
			(xy 36.122718 -288.989718) (xy 36.092136 -288.94763) (xy 36.068516 -288.901276) (xy 36.052439 -288.851797)
			(xy 36.0443 -288.800413) (xy 35.729535 -288.800413) (xy 35.72179 -288.84807) (xy 35.706206 -288.894751)
			(xy 35.683335 -288.938328) (xy 35.65377 -288.977672) (xy 35.618277 -289.011764) (xy 35.577774 -289.03972)
			(xy 35.533312 -289.060818) (xy 35.486041 -289.07451) (xy 35.437186 -289.080442) (xy 35.388011 -289.078461)
			(xy 35.339792 -289.068617) (xy 35.293776 -289.051165) (xy 35.251155 -289.026558) (xy 35.213034 -288.995433)
			(xy 35.180399 -288.958596) (xy 35.154096 -288.917) (xy 35.134805 -288.871724) (xy 35.123028 -288.82394)
			(xy 35.119068 -288.774886) (xy 1.468374 -288.774886) (xy 1.468374 -289.258323) (xy 3.252675 -289.258323)
			(xy 3.252675 -289.203817) (xy 3.260432 -289.149866) (xy 3.275789 -289.097568) (xy 3.298431 -289.047987)
			(xy 3.3279 -289.002134) (xy 3.363594 -288.960941) (xy 3.404787 -288.925247) (xy 3.450641 -288.89578)
			(xy 3.500221 -288.873137) (xy 3.55252 -288.857782) (xy 3.606471 -288.850025) (xy 3.633724 -288.849562)
			(xy 3.661095 -288.849999) (xy 3.715276 -288.857821) (xy 3.76778 -288.873316) (xy 3.817527 -288.896165)
			(xy 3.863492 -288.925897) (xy 3.884422 -288.943542) (xy 3.891534 -288.949638) (xy 3.908552 -288.955988)
			(xy 3.993896 -288.955988) (xy 4.010914 -288.949638) (xy 4.018026 -288.943542) (xy 4.038981 -288.925931)
			(xy 4.084947 -288.896213) (xy 4.134688 -288.873371) (xy 4.187184 -288.857874) (xy 4.241356 -288.850039)
			(xy 4.268724 -288.849562) (xy 4.295975 -288.850048) (xy 4.349922 -288.857805) (xy 4.402217 -288.873161)
			(xy 4.451793 -288.895802) (xy 4.497643 -288.925268) (xy 4.538833 -288.96096) (xy 4.574524 -289.00215)
			(xy 4.60399 -289.048) (xy 4.626631 -289.097577) (xy 4.641986 -289.149872) (xy 4.649742 -289.203819)
			(xy 4.649742 -289.258321) (xy 5.006068 -289.258321) (xy 5.006068 -289.203819) (xy 5.013824 -289.149872)
			(xy 5.029179 -289.097577) (xy 5.05182 -289.048) (xy 5.081286 -289.00215) (xy 5.116977 -288.96096)
			(xy 5.158167 -288.925268) (xy 5.204017 -288.895802) (xy 5.253593 -288.873161) (xy 5.305888 -288.857805)
			(xy 5.359835 -288.850048) (xy 5.387086 -288.849562) (xy 5.414457 -288.850021) (xy 5.468637 -288.857838)
			(xy 5.52114 -288.873328) (xy 5.570887 -288.896172) (xy 5.616853 -288.925899) (xy 5.637784 -288.943542)
			(xy 5.644896 -288.949638) (xy 5.661914 -288.955988) (xy 5.747258 -288.955988) (xy 5.764276 -288.949638)
			(xy 5.771388 -288.943542) (xy 5.792319 -288.925902) (xy 5.838292 -288.896189) (xy 5.888039 -288.873352)
			(xy 5.94054 -288.857862) (xy 5.994717 -288.850035) (xy 6.022086 -288.849562) (xy 6.049339 -288.850025)
			(xy 6.10329 -288.857782) (xy 6.155589 -288.873137) (xy 6.205169 -288.89578) (xy 6.251023 -288.925247)
			(xy 6.292216 -288.960941) (xy 6.32791 -289.002134) (xy 6.357379 -289.047987) (xy 6.380021 -289.097568)
			(xy 6.395378 -289.149866) (xy 6.403135 -289.203817) (xy 6.403135 -289.258323) (xy 6.395378 -289.312274)
			(xy 6.380021 -289.364572) (xy 6.357379 -289.414153) (xy 6.32791 -289.460006) (xy 6.292216 -289.501199)
			(xy 6.256307 -289.532314) (xy 28.175964 -289.532314) (xy 28.180035 -289.476692) (xy 28.192161 -289.422255)
			(xy 28.212084 -289.370164) (xy 28.23938 -289.321529) (xy 28.273466 -289.277386) (xy 28.313615 -289.238677)
			(xy 28.358973 -289.206226) (xy 28.408573 -289.180725) (xy 28.461357 -289.162718) (xy 28.5162 -289.152588)
			(xy 28.571934 -289.150551) (xy 28.627371 -289.156651) (xy 28.681328 -289.170757) (xy 28.732657 -289.192569)
			(xy 28.780263 -289.221623) (xy 28.823131 -289.257298) (xy 28.860348 -289.298835) (xy 28.891121 -289.345348)
			(xy 28.914793 -289.395845) (xy 28.930861 -289.449252) (xy 28.938981 -289.504428) (xy 28.93949 -289.532314)
			(xy 28.938981 -289.5602) (xy 28.930861 -289.615376) (xy 28.914793 -289.668783) (xy 28.891121 -289.71928)
			(xy 28.860348 -289.765793) (xy 28.823131 -289.80733) (xy 28.780263 -289.843005) (xy 28.732657 -289.872059)
			(xy 28.681328 -289.893871) (xy 28.627371 -289.907977) (xy 28.571934 -289.914077) (xy 28.5162 -289.91204)
			(xy 28.461357 -289.90191) (xy 28.408573 -289.883903) (xy 28.358973 -289.858402) (xy 28.313615 -289.825951)
			(xy 28.273466 -289.787242) (xy 28.23938 -289.743099) (xy 28.212084 -289.694464) (xy 28.192161 -289.642373)
			(xy 28.180035 -289.587936) (xy 28.175964 -289.532314) (xy 6.256307 -289.532314) (xy 6.251023 -289.536893)
			(xy 6.205169 -289.56636) (xy 6.155589 -289.589003) (xy 6.10329 -289.604358) (xy 6.049339 -289.612115)
			(xy 6.022086 -289.612578) (xy 5.994715 -289.612125) (xy 5.940535 -289.604305) (xy 5.888032 -289.588813)
			(xy 5.838285 -289.565968) (xy 5.792319 -289.536241) (xy 5.771388 -289.518598) (xy 5.764276 -289.512502)
			(xy 5.747258 -289.506152) (xy 5.661914 -289.506152) (xy 5.644896 -289.512502) (xy 5.637784 -289.518598)
			(xy 5.616831 -289.536211) (xy 5.570864 -289.565927) (xy 5.521122 -289.588768) (xy 5.468626 -289.604265)
			(xy 5.414454 -289.6121) (xy 5.387086 -289.612578) (xy 5.359835 -289.612092) (xy 5.305888 -289.604335)
			(xy 5.253593 -289.588979) (xy 5.204017 -289.566338) (xy 5.158167 -289.536872) (xy 5.116977 -289.50118)
			(xy 5.081286 -289.45999) (xy 5.05182 -289.41414) (xy 5.029179 -289.364563) (xy 5.013824 -289.312268)
			(xy 5.006068 -289.258321) (xy 4.649742 -289.258321) (xy 4.641986 -289.312268) (xy 4.626631 -289.364563)
			(xy 4.60399 -289.41414) (xy 4.574524 -289.45999) (xy 4.538833 -289.50118) (xy 4.497643 -289.536872)
			(xy 4.451793 -289.566338) (xy 4.402217 -289.588979) (xy 4.349922 -289.604335) (xy 4.295975 -289.612092)
			(xy 4.268724 -289.612578) (xy 4.241354 -289.612103) (xy 4.187175 -289.604288) (xy 4.134672 -289.588802)
			(xy 4.084925 -289.565962) (xy 4.038958 -289.536239) (xy 4.018026 -289.518598) (xy 4.010914 -289.512502)
			(xy 3.993896 -289.506152) (xy 3.908552 -289.506152) (xy 3.891534 -289.512502) (xy 3.884422 -289.518598)
			(xy 3.863492 -289.53624) (xy 3.817519 -289.565951) (xy 3.767771 -289.588787) (xy 3.71527 -289.604277)
			(xy 3.661093 -289.612105) (xy 3.633724 -289.612578) (xy 3.606471 -289.612115) (xy 3.55252 -289.604358)
			(xy 3.500221 -289.589003) (xy 3.450641 -289.56636) (xy 3.404787 -289.536893) (xy 3.363594 -289.501199)
			(xy 3.3279 -289.460006) (xy 3.298431 -289.414153) (xy 3.275789 -289.364572) (xy 3.260432 -289.312274)
			(xy 3.252675 -289.258323) (xy 1.468374 -289.258323) (xy 1.468374 -290.321238) (xy 31.234888 -290.321238)
			(xy 31.235327 -290.29466) (xy 31.242726 -290.24202) (xy 31.257359 -290.190917) (xy 31.278942 -290.142339)
			(xy 31.307058 -290.097226) (xy 31.341163 -290.056452) (xy 31.380596 -290.020805) (xy 31.424594 -289.990976)
			(xy 31.448248 -289.978846) (xy 31.460777 -289.972266) (xy 31.481831 -289.953371) (xy 31.49689 -289.929422)
			(xy 31.504794 -289.902259) (xy 31.504938 -289.873969) (xy 31.49731 -289.846727) (xy 31.482496 -289.822626)
			(xy 31.472378 -289.81273) (xy 31.45335 -289.794617) (xy 31.419969 -289.754051) (xy 31.392474 -289.709287)
			(xy 31.371382 -289.661172) (xy 31.357095 -289.610618) (xy 31.349882 -289.558581) (xy 31.349442 -289.532314)
			(xy 31.349928 -289.505063) (xy 31.357684 -289.451115) (xy 31.373039 -289.39882) (xy 31.395681 -289.349243)
			(xy 31.425147 -289.303393) (xy 31.460838 -289.262202) (xy 31.502029 -289.226511) (xy 31.547879 -289.197045)
			(xy 31.597456 -289.174403) (xy 31.649751 -289.159048) (xy 31.703699 -289.151292) (xy 31.758201 -289.151292)
			(xy 31.812149 -289.159048) (xy 31.864444 -289.174403) (xy 31.914021 -289.197045) (xy 31.959871 -289.226511)
			(xy 32.001062 -289.262202) (xy 32.036753 -289.303393) (xy 32.066219 -289.349243) (xy 32.088861 -289.39882)
			(xy 32.104216 -289.451115) (xy 32.111972 -289.505063) (xy 32.112458 -289.532314) (xy 32.111954 -289.55889)
			(xy 32.104562 -289.611525) (xy 32.089937 -289.662626) (xy 32.068363 -289.711202) (xy 32.059862 -289.724846)
			(xy 36.069028 -289.724846) (xy 36.072988 -289.675792) (xy 36.084765 -289.628008) (xy 36.104056 -289.582732)
			(xy 36.130359 -289.541136) (xy 36.162994 -289.504299) (xy 36.201115 -289.473174) (xy 36.243736 -289.448567)
			(xy 36.289752 -289.431115) (xy 36.337971 -289.421271) (xy 36.387146 -289.41929) (xy 36.436001 -289.425222)
			(xy 36.483272 -289.438914) (xy 36.527734 -289.460012) (xy 36.568237 -289.487968) (xy 36.60373 -289.52206)
			(xy 36.633295 -289.561404) (xy 36.656166 -289.604981) (xy 36.67175 -289.651662) (xy 36.679645 -289.700239)
			(xy 36.68014 -289.724846) (xy 37.018988 -289.724846) (xy 37.022948 -289.675792) (xy 37.034725 -289.628008)
			(xy 37.054016 -289.582732) (xy 37.080319 -289.541136) (xy 37.112954 -289.504299) (xy 37.151075 -289.473174)
			(xy 37.193696 -289.448567) (xy 37.239712 -289.431115) (xy 37.287931 -289.421271) (xy 37.337106 -289.41929)
			(xy 37.385961 -289.425222) (xy 37.433232 -289.438914) (xy 37.477694 -289.460012) (xy 37.518197 -289.487968)
			(xy 37.55369 -289.52206) (xy 37.583255 -289.561404) (xy 37.606126 -289.604981) (xy 37.62171 -289.651662)
			(xy 37.629605 -289.700239) (xy 37.6301 -289.724846) (xy 37.969202 -289.724846) (xy 37.973162 -289.675792)
			(xy 37.984939 -289.628008) (xy 38.00423 -289.582732) (xy 38.030533 -289.541136) (xy 38.063168 -289.504299)
			(xy 38.101289 -289.473174) (xy 38.14391 -289.448567) (xy 38.189926 -289.431115) (xy 38.238145 -289.421271)
			(xy 38.28732 -289.41929) (xy 38.336175 -289.425222) (xy 38.383446 -289.438914) (xy 38.427908 -289.460012)
			(xy 38.468411 -289.487968) (xy 38.503904 -289.52206) (xy 38.533469 -289.561404) (xy 38.55634 -289.604981)
			(xy 38.571924 -289.651662) (xy 38.579819 -289.700239) (xy 38.580314 -289.724846) (xy 38.919162 -289.724846)
			(xy 38.923122 -289.675792) (xy 38.934899 -289.628008) (xy 38.95419 -289.582732) (xy 38.980493 -289.541136)
			(xy 39.013128 -289.504299) (xy 39.051249 -289.473174) (xy 39.09387 -289.448567) (xy 39.139886 -289.431115)
			(xy 39.188105 -289.421271) (xy 39.23728 -289.41929) (xy 39.286135 -289.425222) (xy 39.333406 -289.438914)
			(xy 39.377868 -289.460012) (xy 39.418371 -289.487968) (xy 39.453864 -289.52206) (xy 39.483429 -289.561404)
			(xy 39.5063 -289.604981) (xy 39.521884 -289.651662) (xy 39.529779 -289.700239) (xy 39.530274 -289.724846)
			(xy 39.869122 -289.724846) (xy 39.873082 -289.675792) (xy 39.884859 -289.628008) (xy 39.90415 -289.582732)
			(xy 39.930453 -289.541136) (xy 39.963088 -289.504299) (xy 40.001209 -289.473174) (xy 40.04383 -289.448567)
			(xy 40.089846 -289.431115) (xy 40.138065 -289.421271) (xy 40.18724 -289.41929) (xy 40.236095 -289.425222)
			(xy 40.283366 -289.438914) (xy 40.327828 -289.460012) (xy 40.368331 -289.487968) (xy 40.403824 -289.52206)
			(xy 40.433389 -289.561404) (xy 40.45626 -289.604981) (xy 40.471844 -289.651662) (xy 40.479739 -289.700239)
			(xy 40.480234 -289.724846) (xy 40.819082 -289.724846) (xy 40.823042 -289.675792) (xy 40.834819 -289.628008)
			(xy 40.85411 -289.582732) (xy 40.880413 -289.541136) (xy 40.913048 -289.504299) (xy 40.951169 -289.473174)
			(xy 40.99379 -289.448567) (xy 41.039806 -289.431115) (xy 41.088025 -289.421271) (xy 41.1372 -289.41929)
			(xy 41.186055 -289.425222) (xy 41.233326 -289.438914) (xy 41.277788 -289.460012) (xy 41.318291 -289.487968)
			(xy 41.353784 -289.52206) (xy 41.383349 -289.561404) (xy 41.40622 -289.604981) (xy 41.421804 -289.651662)
			(xy 41.429699 -289.700239) (xy 41.430194 -289.724846) (xy 41.769042 -289.724846) (xy 41.773002 -289.675792)
			(xy 41.784779 -289.628008) (xy 41.80407 -289.582732) (xy 41.830373 -289.541136) (xy 41.863008 -289.504299)
			(xy 41.901129 -289.473174) (xy 41.94375 -289.448567) (xy 41.989766 -289.431115) (xy 42.037985 -289.421271)
			(xy 42.08716 -289.41929) (xy 42.136015 -289.425222) (xy 42.183286 -289.438914) (xy 42.227748 -289.460012)
			(xy 42.268251 -289.487968) (xy 42.303744 -289.52206) (xy 42.333309 -289.561404) (xy 42.35618 -289.604981)
			(xy 42.371764 -289.651662) (xy 42.379659 -289.700239) (xy 42.380154 -289.724846) (xy 42.719002 -289.724846)
			(xy 42.722962 -289.675792) (xy 42.734739 -289.628008) (xy 42.75403 -289.582732) (xy 42.780333 -289.541136)
			(xy 42.812968 -289.504299) (xy 42.851089 -289.473174) (xy 42.89371 -289.448567) (xy 42.939726 -289.431115)
			(xy 42.987945 -289.421271) (xy 43.03712 -289.41929) (xy 43.085975 -289.425222) (xy 43.133246 -289.438914)
			(xy 43.177708 -289.460012) (xy 43.218211 -289.487968) (xy 43.253704 -289.52206) (xy 43.283269 -289.561404)
			(xy 43.30614 -289.604981) (xy 43.321724 -289.651662) (xy 43.329619 -289.700239) (xy 43.330114 -289.724846)
			(xy 43.668962 -289.724846) (xy 43.672922 -289.675792) (xy 43.684699 -289.628008) (xy 43.70399 -289.582732)
			(xy 43.730293 -289.541136) (xy 43.762928 -289.504299) (xy 43.801049 -289.473174) (xy 43.84367 -289.448567)
			(xy 43.889686 -289.431115) (xy 43.937905 -289.421271) (xy 43.98708 -289.41929) (xy 44.035935 -289.425222)
			(xy 44.083206 -289.438914) (xy 44.127668 -289.460012) (xy 44.168171 -289.487968) (xy 44.203664 -289.52206)
			(xy 44.233229 -289.561404) (xy 44.2561 -289.604981) (xy 44.271684 -289.651662) (xy 44.279579 -289.700239)
			(xy 44.280074 -289.724846) (xy 44.619176 -289.724846) (xy 44.623136 -289.675792) (xy 44.634913 -289.628008)
			(xy 44.654204 -289.582732) (xy 44.680507 -289.541136) (xy 44.713142 -289.504299) (xy 44.751263 -289.473174)
			(xy 44.793884 -289.448567) (xy 44.8399 -289.431115) (xy 44.888119 -289.421271) (xy 44.937294 -289.41929)
			(xy 44.986149 -289.425222) (xy 45.03342 -289.438914) (xy 45.077882 -289.460012) (xy 45.118385 -289.487968)
			(xy 45.153878 -289.52206) (xy 45.183443 -289.561404) (xy 45.206314 -289.604981) (xy 45.221898 -289.651662)
			(xy 45.229793 -289.700239) (xy 45.230288 -289.724846) (xy 45.569136 -289.724846) (xy 45.573096 -289.675792)
			(xy 45.584873 -289.628008) (xy 45.604164 -289.582732) (xy 45.630467 -289.541136) (xy 45.663102 -289.504299)
			(xy 45.701223 -289.473174) (xy 45.743844 -289.448567) (xy 45.78986 -289.431115) (xy 45.838079 -289.421271)
			(xy 45.887254 -289.41929) (xy 45.936109 -289.425222) (xy 45.98338 -289.438914) (xy 46.027842 -289.460012)
			(xy 46.068345 -289.487968) (xy 46.103838 -289.52206) (xy 46.133403 -289.561404) (xy 46.156274 -289.604981)
			(xy 46.171858 -289.651662) (xy 46.179753 -289.700239) (xy 46.180248 -289.724846) (xy 46.519096 -289.724846)
			(xy 46.523056 -289.675792) (xy 46.534833 -289.628008) (xy 46.554124 -289.582732) (xy 46.580427 -289.541136)
			(xy 46.613062 -289.504299) (xy 46.651183 -289.473174) (xy 46.693804 -289.448567) (xy 46.73982 -289.431115)
			(xy 46.788039 -289.421271) (xy 46.837214 -289.41929) (xy 46.886069 -289.425222) (xy 46.93334 -289.438914)
			(xy 46.977802 -289.460012) (xy 47.018305 -289.487968) (xy 47.053798 -289.52206) (xy 47.083363 -289.561404)
			(xy 47.106234 -289.604981) (xy 47.121818 -289.651662) (xy 47.129713 -289.700239) (xy 47.130208 -289.724846)
			(xy 47.469056 -289.724846) (xy 47.473016 -289.675792) (xy 47.484793 -289.628008) (xy 47.504084 -289.582732)
			(xy 47.530387 -289.541136) (xy 47.563022 -289.504299) (xy 47.601143 -289.473174) (xy 47.643764 -289.448567)
			(xy 47.68978 -289.431115) (xy 47.737999 -289.421271) (xy 47.787174 -289.41929) (xy 47.836029 -289.425222)
			(xy 47.8833 -289.438914) (xy 47.927762 -289.460012) (xy 47.968265 -289.487968) (xy 48.003758 -289.52206)
			(xy 48.033323 -289.561404) (xy 48.056194 -289.604981) (xy 48.071778 -289.651662) (xy 48.079673 -289.700239)
			(xy 48.080168 -289.724846) (xy 48.079673 -289.749453) (xy 48.071778 -289.79803) (xy 48.056194 -289.844711)
			(xy 48.033323 -289.888288) (xy 48.003758 -289.927632) (xy 47.968265 -289.961724) (xy 47.927762 -289.98968)
			(xy 47.8833 -290.010778) (xy 47.836029 -290.02447) (xy 47.787174 -290.030402) (xy 47.737999 -290.028421)
			(xy 47.68978 -290.018577) (xy 47.643764 -290.001125) (xy 47.601143 -289.976518) (xy 47.563022 -289.945393)
			(xy 47.530387 -289.908556) (xy 47.504084 -289.86696) (xy 47.484793 -289.821684) (xy 47.473016 -289.7739)
			(xy 47.469056 -289.724846) (xy 47.130208 -289.724846) (xy 47.129713 -289.749453) (xy 47.121818 -289.79803)
			(xy 47.106234 -289.844711) (xy 47.083363 -289.888288) (xy 47.053798 -289.927632) (xy 47.018305 -289.961724)
			(xy 46.977802 -289.98968) (xy 46.93334 -290.010778) (xy 46.886069 -290.02447) (xy 46.837214 -290.030402)
			(xy 46.788039 -290.028421) (xy 46.73982 -290.018577) (xy 46.693804 -290.001125) (xy 46.651183 -289.976518)
			(xy 46.613062 -289.945393) (xy 46.580427 -289.908556) (xy 46.554124 -289.86696) (xy 46.534833 -289.821684)
			(xy 46.523056 -289.7739) (xy 46.519096 -289.724846) (xy 46.180248 -289.724846) (xy 46.179753 -289.749453)
			(xy 46.171858 -289.79803) (xy 46.156274 -289.844711) (xy 46.133403 -289.888288) (xy 46.103838 -289.927632)
			(xy 46.068345 -289.961724) (xy 46.027842 -289.98968) (xy 45.98338 -290.010778) (xy 45.936109 -290.02447)
			(xy 45.887254 -290.030402) (xy 45.838079 -290.028421) (xy 45.78986 -290.018577) (xy 45.743844 -290.001125)
			(xy 45.701223 -289.976518) (xy 45.663102 -289.945393) (xy 45.630467 -289.908556) (xy 45.604164 -289.86696)
			(xy 45.584873 -289.821684) (xy 45.573096 -289.7739) (xy 45.569136 -289.724846) (xy 45.230288 -289.724846)
			(xy 45.229793 -289.749453) (xy 45.221898 -289.79803) (xy 45.206314 -289.844711) (xy 45.183443 -289.888288)
			(xy 45.153878 -289.927632) (xy 45.118385 -289.961724) (xy 45.077882 -289.98968) (xy 45.03342 -290.010778)
			(xy 44.986149 -290.02447) (xy 44.937294 -290.030402) (xy 44.888119 -290.028421) (xy 44.8399 -290.018577)
			(xy 44.793884 -290.001125) (xy 44.751263 -289.976518) (xy 44.713142 -289.945393) (xy 44.680507 -289.908556)
			(xy 44.654204 -289.86696) (xy 44.634913 -289.821684) (xy 44.623136 -289.7739) (xy 44.619176 -289.724846)
			(xy 44.280074 -289.724846) (xy 44.279579 -289.749453) (xy 44.271684 -289.79803) (xy 44.2561 -289.844711)
			(xy 44.233229 -289.888288) (xy 44.203664 -289.927632) (xy 44.168171 -289.961724) (xy 44.127668 -289.98968)
			(xy 44.083206 -290.010778) (xy 44.035935 -290.02447) (xy 43.98708 -290.030402) (xy 43.937905 -290.028421)
			(xy 43.889686 -290.018577) (xy 43.84367 -290.001125) (xy 43.801049 -289.976518) (xy 43.762928 -289.945393)
			(xy 43.730293 -289.908556) (xy 43.70399 -289.86696) (xy 43.684699 -289.821684) (xy 43.672922 -289.7739)
			(xy 43.668962 -289.724846) (xy 43.330114 -289.724846) (xy 43.329619 -289.749453) (xy 43.321724 -289.79803)
			(xy 43.30614 -289.844711) (xy 43.283269 -289.888288) (xy 43.253704 -289.927632) (xy 43.218211 -289.961724)
			(xy 43.177708 -289.98968) (xy 43.133246 -290.010778) (xy 43.085975 -290.02447) (xy 43.03712 -290.030402)
			(xy 42.987945 -290.028421) (xy 42.939726 -290.018577) (xy 42.89371 -290.001125) (xy 42.851089 -289.976518)
			(xy 42.812968 -289.945393) (xy 42.780333 -289.908556) (xy 42.75403 -289.86696) (xy 42.734739 -289.821684)
			(xy 42.722962 -289.7739) (xy 42.719002 -289.724846) (xy 42.380154 -289.724846) (xy 42.379659 -289.749453)
			(xy 42.371764 -289.79803) (xy 42.35618 -289.844711) (xy 42.333309 -289.888288) (xy 42.303744 -289.927632)
			(xy 42.268251 -289.961724) (xy 42.227748 -289.98968) (xy 42.183286 -290.010778) (xy 42.136015 -290.02447)
			(xy 42.08716 -290.030402) (xy 42.037985 -290.028421) (xy 41.989766 -290.018577) (xy 41.94375 -290.001125)
			(xy 41.901129 -289.976518) (xy 41.863008 -289.945393) (xy 41.830373 -289.908556) (xy 41.80407 -289.86696)
			(xy 41.784779 -289.821684) (xy 41.773002 -289.7739) (xy 41.769042 -289.724846) (xy 41.430194 -289.724846)
			(xy 41.429699 -289.749453) (xy 41.421804 -289.79803) (xy 41.40622 -289.844711) (xy 41.383349 -289.888288)
			(xy 41.353784 -289.927632) (xy 41.318291 -289.961724) (xy 41.277788 -289.98968) (xy 41.233326 -290.010778)
			(xy 41.186055 -290.02447) (xy 41.1372 -290.030402) (xy 41.088025 -290.028421) (xy 41.039806 -290.018577)
			(xy 40.99379 -290.001125) (xy 40.951169 -289.976518) (xy 40.913048 -289.945393) (xy 40.880413 -289.908556)
			(xy 40.85411 -289.86696) (xy 40.834819 -289.821684) (xy 40.823042 -289.7739) (xy 40.819082 -289.724846)
			(xy 40.480234 -289.724846) (xy 40.479739 -289.749453) (xy 40.471844 -289.79803) (xy 40.45626 -289.844711)
			(xy 40.433389 -289.888288) (xy 40.403824 -289.927632) (xy 40.368331 -289.961724) (xy 40.327828 -289.98968)
			(xy 40.283366 -290.010778) (xy 40.236095 -290.02447) (xy 40.18724 -290.030402) (xy 40.138065 -290.028421)
			(xy 40.089846 -290.018577) (xy 40.04383 -290.001125) (xy 40.001209 -289.976518) (xy 39.963088 -289.945393)
			(xy 39.930453 -289.908556) (xy 39.90415 -289.86696) (xy 39.884859 -289.821684) (xy 39.873082 -289.7739)
			(xy 39.869122 -289.724846) (xy 39.530274 -289.724846) (xy 39.529779 -289.749453) (xy 39.521884 -289.79803)
			(xy 39.5063 -289.844711) (xy 39.483429 -289.888288) (xy 39.453864 -289.927632) (xy 39.418371 -289.961724)
			(xy 39.377868 -289.98968) (xy 39.333406 -290.010778) (xy 39.286135 -290.02447) (xy 39.23728 -290.030402)
			(xy 39.188105 -290.028421) (xy 39.139886 -290.018577) (xy 39.09387 -290.001125) (xy 39.051249 -289.976518)
			(xy 39.013128 -289.945393) (xy 38.980493 -289.908556) (xy 38.95419 -289.86696) (xy 38.934899 -289.821684)
			(xy 38.923122 -289.7739) (xy 38.919162 -289.724846) (xy 38.580314 -289.724846) (xy 38.579819 -289.749453)
			(xy 38.571924 -289.79803) (xy 38.55634 -289.844711) (xy 38.533469 -289.888288) (xy 38.503904 -289.927632)
			(xy 38.468411 -289.961724) (xy 38.427908 -289.98968) (xy 38.383446 -290.010778) (xy 38.336175 -290.02447)
			(xy 38.28732 -290.030402) (xy 38.238145 -290.028421) (xy 38.189926 -290.018577) (xy 38.14391 -290.001125)
			(xy 38.101289 -289.976518) (xy 38.063168 -289.945393) (xy 38.030533 -289.908556) (xy 38.00423 -289.86696)
			(xy 37.984939 -289.821684) (xy 37.973162 -289.7739) (xy 37.969202 -289.724846) (xy 37.6301 -289.724846)
			(xy 37.629605 -289.749453) (xy 37.62171 -289.79803) (xy 37.606126 -289.844711) (xy 37.583255 -289.888288)
			(xy 37.55369 -289.927632) (xy 37.518197 -289.961724) (xy 37.477694 -289.98968) (xy 37.433232 -290.010778)
			(xy 37.385961 -290.02447) (xy 37.337106 -290.030402) (xy 37.287931 -290.028421) (xy 37.239712 -290.018577)
			(xy 37.193696 -290.001125) (xy 37.151075 -289.976518) (xy 37.112954 -289.945393) (xy 37.080319 -289.908556)
			(xy 37.054016 -289.86696) (xy 37.034725 -289.821684) (xy 37.022948 -289.7739) (xy 37.018988 -289.724846)
			(xy 36.68014 -289.724846) (xy 36.679645 -289.749453) (xy 36.67175 -289.79803) (xy 36.656166 -289.844711)
			(xy 36.633295 -289.888288) (xy 36.60373 -289.927632) (xy 36.568237 -289.961724) (xy 36.527734 -289.98968)
			(xy 36.483272 -290.010778) (xy 36.436001 -290.02447) (xy 36.387146 -290.030402) (xy 36.337971 -290.028421)
			(xy 36.289752 -290.018577) (xy 36.243736 -290.001125) (xy 36.201115 -289.976518) (xy 36.162994 -289.945393)
			(xy 36.130359 -289.908556) (xy 36.104056 -289.86696) (xy 36.084765 -289.821684) (xy 36.072988 -289.7739)
			(xy 36.069028 -289.724846) (xy 32.059862 -289.724846) (xy 32.040256 -289.756315) (xy 32.006161 -289.79709)
			(xy 31.966737 -289.83274) (xy 31.922747 -289.862573) (xy 31.899098 -289.874706) (xy 31.886606 -289.881344)
			(xy 31.865564 -289.900233) (xy 31.850513 -289.92417) (xy 31.842608 -289.951319) (xy 31.842456 -289.979595)
			(xy 31.850069 -290.006827) (xy 31.864862 -290.030925) (xy 31.874968 -290.040822) (xy 31.893963 -290.058969)
			(xy 31.927348 -290.099526) (xy 31.95485 -290.144283) (xy 31.975947 -290.192391) (xy 31.990241 -290.24294)
			(xy 31.99737 -290.294314) (xy 33.620962 -290.294314) (xy 33.625033 -290.238692) (xy 33.637159 -290.184255)
			(xy 33.657082 -290.132164) (xy 33.684378 -290.083529) (xy 33.718464 -290.039386) (xy 33.758613 -290.000677)
			(xy 33.803971 -289.968226) (xy 33.853571 -289.942725) (xy 33.906355 -289.924718) (xy 33.961198 -289.914588)
			(xy 34.016932 -289.912551) (xy 34.072369 -289.918651) (xy 34.126326 -289.932757) (xy 34.177655 -289.954569)
			(xy 34.225261 -289.983623) (xy 34.268129 -290.019298) (xy 34.305346 -290.060835) (xy 34.336119 -290.107348)
			(xy 34.359791 -290.157845) (xy 34.375859 -290.211252) (xy 34.383979 -290.266428) (xy 34.384488 -290.294314)
			(xy 34.383979 -290.3222) (xy 34.375859 -290.377376) (xy 34.359791 -290.430783) (xy 34.336119 -290.48128)
			(xy 34.305346 -290.527793) (xy 34.268129 -290.56933) (xy 34.225261 -290.605005) (xy 34.177655 -290.634059)
			(xy 34.126326 -290.655871) (xy 34.072369 -290.669977) (xy 34.028483 -290.674806) (xy 36.069028 -290.674806)
			(xy 36.072988 -290.625752) (xy 36.084765 -290.577968) (xy 36.104056 -290.532692) (xy 36.130359 -290.491096)
			(xy 36.162994 -290.454259) (xy 36.201115 -290.423134) (xy 36.243736 -290.398527) (xy 36.289752 -290.381075)
			(xy 36.337971 -290.371231) (xy 36.387146 -290.36925) (xy 36.436001 -290.375182) (xy 36.483272 -290.388874)
			(xy 36.527734 -290.409972) (xy 36.568237 -290.437928) (xy 36.60373 -290.47202) (xy 36.633295 -290.511364)
			(xy 36.656166 -290.554941) (xy 36.67175 -290.601622) (xy 36.679645 -290.650199) (xy 36.68014 -290.674806)
			(xy 37.018988 -290.674806) (xy 37.022948 -290.625752) (xy 37.034725 -290.577968) (xy 37.054016 -290.532692)
			(xy 37.080319 -290.491096) (xy 37.112954 -290.454259) (xy 37.151075 -290.423134) (xy 37.193696 -290.398527)
			(xy 37.239712 -290.381075) (xy 37.287931 -290.371231) (xy 37.337106 -290.36925) (xy 37.385961 -290.375182)
			(xy 37.433232 -290.388874) (xy 37.477694 -290.409972) (xy 37.518197 -290.437928) (xy 37.55369 -290.47202)
			(xy 37.583255 -290.511364) (xy 37.606126 -290.554941) (xy 37.62171 -290.601622) (xy 37.629605 -290.650199)
			(xy 37.6301 -290.674806) (xy 37.969202 -290.674806) (xy 37.973162 -290.625752) (xy 37.984939 -290.577968)
			(xy 38.00423 -290.532692) (xy 38.030533 -290.491096) (xy 38.063168 -290.454259) (xy 38.101289 -290.423134)
			(xy 38.14391 -290.398527) (xy 38.189926 -290.381075) (xy 38.238145 -290.371231) (xy 38.28732 -290.36925)
			(xy 38.336175 -290.375182) (xy 38.383446 -290.388874) (xy 38.427908 -290.409972) (xy 38.468411 -290.437928)
			(xy 38.503904 -290.47202) (xy 38.533469 -290.511364) (xy 38.55634 -290.554941) (xy 38.571924 -290.601622)
			(xy 38.579819 -290.650199) (xy 38.580314 -290.674806) (xy 40.819082 -290.674806) (xy 40.823042 -290.625752)
			(xy 40.834819 -290.577968) (xy 40.85411 -290.532692) (xy 40.880413 -290.491096) (xy 40.913048 -290.454259)
			(xy 40.951169 -290.423134) (xy 40.99379 -290.398527) (xy 41.039806 -290.381075) (xy 41.088025 -290.371231)
			(xy 41.1372 -290.36925) (xy 41.186055 -290.375182) (xy 41.233326 -290.388874) (xy 41.277788 -290.409972)
			(xy 41.318291 -290.437928) (xy 41.353784 -290.47202) (xy 41.383349 -290.511364) (xy 41.40622 -290.554941)
			(xy 41.421804 -290.601622) (xy 41.429699 -290.650199) (xy 41.430194 -290.674806) (xy 41.769042 -290.674806)
			(xy 41.773002 -290.625752) (xy 41.784779 -290.577968) (xy 41.80407 -290.532692) (xy 41.830373 -290.491096)
			(xy 41.863008 -290.454259) (xy 41.901129 -290.423134) (xy 41.94375 -290.398527) (xy 41.989766 -290.381075)
			(xy 42.037985 -290.371231) (xy 42.08716 -290.36925) (xy 42.136015 -290.375182) (xy 42.183286 -290.388874)
			(xy 42.227748 -290.409972) (xy 42.268251 -290.437928) (xy 42.303744 -290.47202) (xy 42.333309 -290.511364)
			(xy 42.35618 -290.554941) (xy 42.371764 -290.601622) (xy 42.379659 -290.650199) (xy 42.380154 -290.674806)
			(xy 42.719002 -290.674806) (xy 42.722962 -290.625752) (xy 42.734739 -290.577968) (xy 42.75403 -290.532692)
			(xy 42.780333 -290.491096) (xy 42.812968 -290.454259) (xy 42.851089 -290.423134) (xy 42.89371 -290.398527)
			(xy 42.939726 -290.381075) (xy 42.987945 -290.371231) (xy 43.03712 -290.36925) (xy 43.085975 -290.375182)
			(xy 43.133246 -290.388874) (xy 43.177708 -290.409972) (xy 43.218211 -290.437928) (xy 43.253704 -290.47202)
			(xy 43.283269 -290.511364) (xy 43.30614 -290.554941) (xy 43.321724 -290.601622) (xy 43.329619 -290.650199)
			(xy 43.330114 -290.674806) (xy 43.668962 -290.674806) (xy 43.672922 -290.625752) (xy 43.684699 -290.577968)
			(xy 43.70399 -290.532692) (xy 43.730293 -290.491096) (xy 43.762928 -290.454259) (xy 43.801049 -290.423134)
			(xy 43.84367 -290.398527) (xy 43.889686 -290.381075) (xy 43.937905 -290.371231) (xy 43.98708 -290.36925)
			(xy 44.035935 -290.375182) (xy 44.083206 -290.388874) (xy 44.127668 -290.409972) (xy 44.168171 -290.437928)
			(xy 44.203664 -290.47202) (xy 44.233229 -290.511364) (xy 44.2561 -290.554941) (xy 44.271684 -290.601622)
			(xy 44.279579 -290.650199) (xy 44.280074 -290.674806) (xy 44.619176 -290.674806) (xy 44.623136 -290.625752)
			(xy 44.634913 -290.577968) (xy 44.654204 -290.532692) (xy 44.680507 -290.491096) (xy 44.713142 -290.454259)
			(xy 44.751263 -290.423134) (xy 44.793884 -290.398527) (xy 44.8399 -290.381075) (xy 44.888119 -290.371231)
			(xy 44.937294 -290.36925) (xy 44.986149 -290.375182) (xy 45.03342 -290.388874) (xy 45.077882 -290.409972)
			(xy 45.118385 -290.437928) (xy 45.153878 -290.47202) (xy 45.183443 -290.511364) (xy 45.206314 -290.554941)
			(xy 45.221898 -290.601622) (xy 45.229793 -290.650199) (xy 45.230288 -290.674806) (xy 45.569136 -290.674806)
			(xy 45.573096 -290.625752) (xy 45.584873 -290.577968) (xy 45.604164 -290.532692) (xy 45.630467 -290.491096)
			(xy 45.663102 -290.454259) (xy 45.701223 -290.423134) (xy 45.743844 -290.398527) (xy 45.78986 -290.381075)
			(xy 45.838079 -290.371231) (xy 45.887254 -290.36925) (xy 45.936109 -290.375182) (xy 45.98338 -290.388874)
			(xy 46.027842 -290.409972) (xy 46.068345 -290.437928) (xy 46.103838 -290.47202) (xy 46.133403 -290.511364)
			(xy 46.156274 -290.554941) (xy 46.171858 -290.601622) (xy 46.179753 -290.650199) (xy 46.180248 -290.674806)
			(xy 46.519096 -290.674806) (xy 46.523056 -290.625752) (xy 46.534833 -290.577968) (xy 46.554124 -290.532692)
			(xy 46.580427 -290.491096) (xy 46.613062 -290.454259) (xy 46.651183 -290.423134) (xy 46.693804 -290.398527)
			(xy 46.73982 -290.381075) (xy 46.788039 -290.371231) (xy 46.837214 -290.36925) (xy 46.886069 -290.375182)
			(xy 46.93334 -290.388874) (xy 46.977802 -290.409972) (xy 47.018305 -290.437928) (xy 47.053798 -290.47202)
			(xy 47.083363 -290.511364) (xy 47.106234 -290.554941) (xy 47.121818 -290.601622) (xy 47.129713 -290.650199)
			(xy 47.130208 -290.674806) (xy 47.469056 -290.674806) (xy 47.473016 -290.625752) (xy 47.484793 -290.577968)
			(xy 47.504084 -290.532692) (xy 47.530387 -290.491096) (xy 47.563022 -290.454259) (xy 47.601143 -290.423134)
			(xy 47.643764 -290.398527) (xy 47.68978 -290.381075) (xy 47.737999 -290.371231) (xy 47.787174 -290.36925)
			(xy 47.836029 -290.375182) (xy 47.8833 -290.388874) (xy 47.927762 -290.409972) (xy 47.968265 -290.437928)
			(xy 48.003758 -290.47202) (xy 48.033323 -290.511364) (xy 48.056194 -290.554941) (xy 48.071778 -290.601622)
			(xy 48.079673 -290.650199) (xy 48.080168 -290.674806) (xy 48.079673 -290.699413) (xy 48.071778 -290.74799)
			(xy 48.056194 -290.794671) (xy 48.033323 -290.838248) (xy 48.003758 -290.877592) (xy 47.968265 -290.911684)
			(xy 47.927762 -290.93964) (xy 47.8833 -290.960738) (xy 47.836029 -290.97443) (xy 47.787174 -290.980362)
			(xy 47.737999 -290.978381) (xy 47.68978 -290.968537) (xy 47.643764 -290.951085) (xy 47.601143 -290.926478)
			(xy 47.563022 -290.895353) (xy 47.530387 -290.858516) (xy 47.504084 -290.81692) (xy 47.484793 -290.771644)
			(xy 47.473016 -290.72386) (xy 47.469056 -290.674806) (xy 47.130208 -290.674806) (xy 47.129713 -290.699413)
			(xy 47.121818 -290.74799) (xy 47.106234 -290.794671) (xy 47.083363 -290.838248) (xy 47.053798 -290.877592)
			(xy 47.018305 -290.911684) (xy 46.977802 -290.93964) (xy 46.93334 -290.960738) (xy 46.886069 -290.97443)
			(xy 46.837214 -290.980362) (xy 46.788039 -290.978381) (xy 46.73982 -290.968537) (xy 46.693804 -290.951085)
			(xy 46.651183 -290.926478) (xy 46.613062 -290.895353) (xy 46.580427 -290.858516) (xy 46.554124 -290.81692)
			(xy 46.534833 -290.771644) (xy 46.523056 -290.72386) (xy 46.519096 -290.674806) (xy 46.180248 -290.674806)
			(xy 46.179753 -290.699413) (xy 46.171858 -290.74799) (xy 46.156274 -290.794671) (xy 46.133403 -290.838248)
			(xy 46.103838 -290.877592) (xy 46.068345 -290.911684) (xy 46.027842 -290.93964) (xy 45.98338 -290.960738)
			(xy 45.936109 -290.97443) (xy 45.887254 -290.980362) (xy 45.838079 -290.978381) (xy 45.78986 -290.968537)
			(xy 45.743844 -290.951085) (xy 45.701223 -290.926478) (xy 45.663102 -290.895353) (xy 45.630467 -290.858516)
			(xy 45.604164 -290.81692) (xy 45.584873 -290.771644) (xy 45.573096 -290.72386) (xy 45.569136 -290.674806)
			(xy 45.230288 -290.674806) (xy 45.229793 -290.699413) (xy 45.221898 -290.74799) (xy 45.206314 -290.794671)
			(xy 45.183443 -290.838248) (xy 45.153878 -290.877592) (xy 45.118385 -290.911684) (xy 45.077882 -290.93964)
			(xy 45.03342 -290.960738) (xy 44.986149 -290.97443) (xy 44.937294 -290.980362) (xy 44.888119 -290.978381)
			(xy 44.8399 -290.968537) (xy 44.793884 -290.951085) (xy 44.751263 -290.926478) (xy 44.713142 -290.895353)
			(xy 44.680507 -290.858516) (xy 44.654204 -290.81692) (xy 44.634913 -290.771644) (xy 44.623136 -290.72386)
			(xy 44.619176 -290.674806) (xy 44.280074 -290.674806) (xy 44.279579 -290.699413) (xy 44.271684 -290.74799)
			(xy 44.2561 -290.794671) (xy 44.233229 -290.838248) (xy 44.203664 -290.877592) (xy 44.168171 -290.911684)
			(xy 44.127668 -290.93964) (xy 44.083206 -290.960738) (xy 44.035935 -290.97443) (xy 43.98708 -290.980362)
			(xy 43.937905 -290.978381) (xy 43.889686 -290.968537) (xy 43.84367 -290.951085) (xy 43.801049 -290.926478)
			(xy 43.762928 -290.895353) (xy 43.730293 -290.858516) (xy 43.70399 -290.81692) (xy 43.684699 -290.771644)
			(xy 43.672922 -290.72386) (xy 43.668962 -290.674806) (xy 43.330114 -290.674806) (xy 43.329619 -290.699413)
			(xy 43.321724 -290.74799) (xy 43.30614 -290.794671) (xy 43.283269 -290.838248) (xy 43.253704 -290.877592)
			(xy 43.218211 -290.911684) (xy 43.177708 -290.93964) (xy 43.133246 -290.960738) (xy 43.085975 -290.97443)
			(xy 43.03712 -290.980362) (xy 42.987945 -290.978381) (xy 42.939726 -290.968537) (xy 42.89371 -290.951085)
			(xy 42.851089 -290.926478) (xy 42.812968 -290.895353) (xy 42.780333 -290.858516) (xy 42.75403 -290.81692)
			(xy 42.734739 -290.771644) (xy 42.722962 -290.72386) (xy 42.719002 -290.674806) (xy 42.380154 -290.674806)
			(xy 42.379659 -290.699413) (xy 42.371764 -290.74799) (xy 42.35618 -290.794671) (xy 42.333309 -290.838248)
			(xy 42.303744 -290.877592) (xy 42.268251 -290.911684) (xy 42.227748 -290.93964) (xy 42.183286 -290.960738)
			(xy 42.136015 -290.97443) (xy 42.08716 -290.980362) (xy 42.037985 -290.978381) (xy 41.989766 -290.968537)
			(xy 41.94375 -290.951085) (xy 41.901129 -290.926478) (xy 41.863008 -290.895353) (xy 41.830373 -290.858516)
			(xy 41.80407 -290.81692) (xy 41.784779 -290.771644) (xy 41.773002 -290.72386) (xy 41.769042 -290.674806)
			(xy 41.430194 -290.674806) (xy 41.429699 -290.699413) (xy 41.421804 -290.74799) (xy 41.40622 -290.794671)
			(xy 41.383349 -290.838248) (xy 41.353784 -290.877592) (xy 41.318291 -290.911684) (xy 41.277788 -290.93964)
			(xy 41.233326 -290.960738) (xy 41.186055 -290.97443) (xy 41.1372 -290.980362) (xy 41.088025 -290.978381)
			(xy 41.039806 -290.968537) (xy 40.99379 -290.951085) (xy 40.951169 -290.926478) (xy 40.913048 -290.895353)
			(xy 40.880413 -290.858516) (xy 40.85411 -290.81692) (xy 40.834819 -290.771644) (xy 40.823042 -290.72386)
			(xy 40.819082 -290.674806) (xy 38.580314 -290.674806) (xy 38.579819 -290.699413) (xy 38.571924 -290.74799)
			(xy 38.55634 -290.794671) (xy 38.533469 -290.838248) (xy 38.503904 -290.877592) (xy 38.468411 -290.911684)
			(xy 38.427908 -290.93964) (xy 38.383446 -290.960738) (xy 38.336175 -290.97443) (xy 38.28732 -290.980362)
			(xy 38.238145 -290.978381) (xy 38.189926 -290.968537) (xy 38.14391 -290.951085) (xy 38.101289 -290.926478)
			(xy 38.063168 -290.895353) (xy 38.030533 -290.858516) (xy 38.00423 -290.81692) (xy 37.984939 -290.771644)
			(xy 37.973162 -290.72386) (xy 37.969202 -290.674806) (xy 37.6301 -290.674806) (xy 37.629605 -290.699413)
			(xy 37.62171 -290.74799) (xy 37.606126 -290.794671) (xy 37.583255 -290.838248) (xy 37.55369 -290.877592)
			(xy 37.518197 -290.911684) (xy 37.477694 -290.93964) (xy 37.433232 -290.960738) (xy 37.385961 -290.97443)
			(xy 37.337106 -290.980362) (xy 37.287931 -290.978381) (xy 37.239712 -290.968537) (xy 37.193696 -290.951085)
			(xy 37.151075 -290.926478) (xy 37.112954 -290.895353) (xy 37.080319 -290.858516) (xy 37.054016 -290.81692)
			(xy 37.034725 -290.771644) (xy 37.022948 -290.72386) (xy 37.018988 -290.674806) (xy 36.68014 -290.674806)
			(xy 36.679645 -290.699413) (xy 36.67175 -290.74799) (xy 36.656166 -290.794671) (xy 36.633295 -290.838248)
			(xy 36.60373 -290.877592) (xy 36.568237 -290.911684) (xy 36.527734 -290.93964) (xy 36.483272 -290.960738)
			(xy 36.436001 -290.97443) (xy 36.387146 -290.980362) (xy 36.337971 -290.978381) (xy 36.289752 -290.968537)
			(xy 36.243736 -290.951085) (xy 36.201115 -290.926478) (xy 36.162994 -290.895353) (xy 36.130359 -290.858516)
			(xy 36.104056 -290.81692) (xy 36.084765 -290.771644) (xy 36.072988 -290.72386) (xy 36.069028 -290.674806)
			(xy 34.028483 -290.674806) (xy 34.016932 -290.676077) (xy 33.961198 -290.67404) (xy 33.906355 -290.66391)
			(xy 33.853571 -290.645903) (xy 33.803971 -290.620402) (xy 33.758613 -290.587951) (xy 33.718464 -290.549242)
			(xy 33.684378 -290.505099) (xy 33.657082 -290.456464) (xy 33.637159 -290.404373) (xy 33.625033 -290.349936)
			(xy 33.620962 -290.294314) (xy 31.99737 -290.294314) (xy 31.997461 -290.294973) (xy 31.997904 -290.321238)
			(xy 31.997418 -290.348489) (xy 31.989662 -290.402437) (xy 31.974307 -290.454732) (xy 31.951665 -290.504309)
			(xy 31.922199 -290.550159) (xy 31.886508 -290.59135) (xy 31.845317 -290.627041) (xy 31.799467 -290.656507)
			(xy 31.74989 -290.679149) (xy 31.697595 -290.694504) (xy 31.643647 -290.70226) (xy 31.589145 -290.70226)
			(xy 31.535197 -290.694504) (xy 31.482902 -290.679149) (xy 31.433325 -290.656507) (xy 31.387475 -290.627041)
			(xy 31.346284 -290.59135) (xy 31.310593 -290.550159) (xy 31.281127 -290.504309) (xy 31.258485 -290.454732)
			(xy 31.24313 -290.402437) (xy 31.235374 -290.348489) (xy 31.234888 -290.321238) (xy 1.468374 -290.321238)
			(xy 1.468374 -290.820856) (xy 32.748218 -290.820856) (xy 32.752289 -290.765234) (xy 32.764415 -290.710797)
			(xy 32.784338 -290.658706) (xy 32.811634 -290.610071) (xy 32.84572 -290.565928) (xy 32.885869 -290.527219)
			(xy 32.931227 -290.494768) (xy 32.980827 -290.469267) (xy 33.033611 -290.45126) (xy 33.088454 -290.44113)
			(xy 33.144188 -290.439093) (xy 33.199625 -290.445193) (xy 33.253582 -290.459299) (xy 33.304911 -290.481111)
			(xy 33.352517 -290.510165) (xy 33.395385 -290.54584) (xy 33.432602 -290.587377) (xy 33.463375 -290.63389)
			(xy 33.487047 -290.684387) (xy 33.503115 -290.737794) (xy 33.511235 -290.79297) (xy 33.511744 -290.820856)
			(xy 33.511235 -290.848742) (xy 33.503115 -290.903918) (xy 33.487047 -290.957325) (xy 33.463375 -291.007822)
			(xy 33.432602 -291.054335) (xy 33.395385 -291.095872) (xy 33.352517 -291.131547) (xy 33.304911 -291.160601)
			(xy 33.253582 -291.182413) (xy 33.199625 -291.196519) (xy 33.144188 -291.202619) (xy 33.088454 -291.200582)
			(xy 33.033611 -291.190452) (xy 32.980827 -291.172445) (xy 32.931227 -291.146944) (xy 32.885869 -291.114493)
			(xy 32.84572 -291.075784) (xy 32.811634 -291.031641) (xy 32.784338 -290.983006) (xy 32.764415 -290.930915)
			(xy 32.752289 -290.876478) (xy 32.748218 -290.820856) (xy 1.468374 -290.820856) (xy 1.468374 -291.430456)
			(xy 25.811478 -291.430456) (xy 25.815549 -291.374834) (xy 25.827675 -291.320397) (xy 25.847598 -291.268306)
			(xy 25.874894 -291.219671) (xy 25.90898 -291.175528) (xy 25.949129 -291.136819) (xy 25.994487 -291.104368)
			(xy 26.044087 -291.078867) (xy 26.096871 -291.06086) (xy 26.151714 -291.05073) (xy 26.207448 -291.048693)
			(xy 26.262885 -291.054793) (xy 26.316842 -291.068899) (xy 26.368171 -291.090711) (xy 26.415777 -291.119765)
			(xy 26.458645 -291.15544) (xy 26.495862 -291.196977) (xy 26.526635 -291.24349) (xy 26.550307 -291.293987)
			(xy 26.566375 -291.347394) (xy 26.574495 -291.40257) (xy 26.575004 -291.430456) (xy 27.296616 -291.430456)
			(xy 27.300687 -291.374834) (xy 27.312813 -291.320397) (xy 27.332736 -291.268306) (xy 27.360032 -291.219671)
			(xy 27.394118 -291.175528) (xy 27.434267 -291.136819) (xy 27.479625 -291.104368) (xy 27.529225 -291.078867)
			(xy 27.582009 -291.06086) (xy 27.636852 -291.05073) (xy 27.692586 -291.048693) (xy 27.748023 -291.054793)
			(xy 27.80198 -291.068899) (xy 27.853309 -291.090711) (xy 27.900915 -291.119765) (xy 27.943783 -291.15544)
			(xy 27.981 -291.196977) (xy 28.011773 -291.24349) (xy 28.035445 -291.293987) (xy 28.051513 -291.347394)
			(xy 28.059633 -291.40257) (xy 28.060142 -291.430456) (xy 28.059633 -291.458342) (xy 28.051513 -291.513518)
			(xy 28.035445 -291.566925) (xy 28.011773 -291.617422) (xy 28.006914 -291.624766) (xy 36.069028 -291.624766)
			(xy 36.072988 -291.575712) (xy 36.084765 -291.527928) (xy 36.104056 -291.482652) (xy 36.130359 -291.441056)
			(xy 36.162994 -291.404219) (xy 36.201115 -291.373094) (xy 36.243736 -291.348487) (xy 36.289752 -291.331035)
			(xy 36.337971 -291.321191) (xy 36.387146 -291.31921) (xy 36.436001 -291.325142) (xy 36.483272 -291.338834)
			(xy 36.527734 -291.359932) (xy 36.568237 -291.387888) (xy 36.60373 -291.42198) (xy 36.633295 -291.461324)
			(xy 36.656166 -291.504901) (xy 36.67175 -291.551582) (xy 36.679645 -291.600159) (xy 36.68014 -291.624766)
			(xy 37.018988 -291.624766) (xy 37.022948 -291.575712) (xy 37.034725 -291.527928) (xy 37.054016 -291.482652)
			(xy 37.080319 -291.441056) (xy 37.112954 -291.404219) (xy 37.151075 -291.373094) (xy 37.193696 -291.348487)
			(xy 37.239712 -291.331035) (xy 37.287931 -291.321191) (xy 37.337106 -291.31921) (xy 37.385961 -291.325142)
			(xy 37.433232 -291.338834) (xy 37.477694 -291.359932) (xy 37.518197 -291.387888) (xy 37.55369 -291.42198)
			(xy 37.583255 -291.461324) (xy 37.606126 -291.504901) (xy 37.62171 -291.551582) (xy 37.629605 -291.600159)
			(xy 37.6301 -291.624766) (xy 37.969202 -291.624766) (xy 37.973162 -291.575712) (xy 37.984939 -291.527928)
			(xy 38.00423 -291.482652) (xy 38.030533 -291.441056) (xy 38.063168 -291.404219) (xy 38.101289 -291.373094)
			(xy 38.14391 -291.348487) (xy 38.189926 -291.331035) (xy 38.238145 -291.321191) (xy 38.28732 -291.31921)
			(xy 38.336175 -291.325142) (xy 38.383446 -291.338834) (xy 38.427908 -291.359932) (xy 38.468411 -291.387888)
			(xy 38.503904 -291.42198) (xy 38.533469 -291.461324) (xy 38.55634 -291.504901) (xy 38.571924 -291.551582)
			(xy 38.579819 -291.600159) (xy 38.580314 -291.624766) (xy 40.819082 -291.624766) (xy 40.823042 -291.575712)
			(xy 40.834819 -291.527928) (xy 40.85411 -291.482652) (xy 40.880413 -291.441056) (xy 40.913048 -291.404219)
			(xy 40.951169 -291.373094) (xy 40.99379 -291.348487) (xy 41.039806 -291.331035) (xy 41.088025 -291.321191)
			(xy 41.1372 -291.31921) (xy 41.186055 -291.325142) (xy 41.233326 -291.338834) (xy 41.277788 -291.359932)
			(xy 41.318291 -291.387888) (xy 41.353784 -291.42198) (xy 41.383349 -291.461324) (xy 41.40622 -291.504901)
			(xy 41.421804 -291.551582) (xy 41.429699 -291.600159) (xy 41.430194 -291.624766) (xy 41.769042 -291.624766)
			(xy 41.773002 -291.575712) (xy 41.784779 -291.527928) (xy 41.80407 -291.482652) (xy 41.830373 -291.441056)
			(xy 41.863008 -291.404219) (xy 41.901129 -291.373094) (xy 41.94375 -291.348487) (xy 41.989766 -291.331035)
			(xy 42.037985 -291.321191) (xy 42.08716 -291.31921) (xy 42.136015 -291.325142) (xy 42.183286 -291.338834)
			(xy 42.227748 -291.359932) (xy 42.268251 -291.387888) (xy 42.303744 -291.42198) (xy 42.333309 -291.461324)
			(xy 42.35618 -291.504901) (xy 42.371764 -291.551582) (xy 42.379659 -291.600159) (xy 42.380154 -291.624766)
			(xy 42.719002 -291.624766) (xy 42.722962 -291.575712) (xy 42.734739 -291.527928) (xy 42.75403 -291.482652)
			(xy 42.780333 -291.441056) (xy 42.812968 -291.404219) (xy 42.851089 -291.373094) (xy 42.89371 -291.348487)
			(xy 42.939726 -291.331035) (xy 42.987945 -291.321191) (xy 43.03712 -291.31921) (xy 43.085975 -291.325142)
			(xy 43.133246 -291.338834) (xy 43.177708 -291.359932) (xy 43.218211 -291.387888) (xy 43.253704 -291.42198)
			(xy 43.283269 -291.461324) (xy 43.30614 -291.504901) (xy 43.321724 -291.551582) (xy 43.329619 -291.600159)
			(xy 43.330114 -291.624766) (xy 43.668962 -291.624766) (xy 43.672922 -291.575712) (xy 43.684699 -291.527928)
			(xy 43.70399 -291.482652) (xy 43.730293 -291.441056) (xy 43.762928 -291.404219) (xy 43.801049 -291.373094)
			(xy 43.84367 -291.348487) (xy 43.889686 -291.331035) (xy 43.937905 -291.321191) (xy 43.98708 -291.31921)
			(xy 44.035935 -291.325142) (xy 44.083206 -291.338834) (xy 44.127668 -291.359932) (xy 44.168171 -291.387888)
			(xy 44.203664 -291.42198) (xy 44.233229 -291.461324) (xy 44.2561 -291.504901) (xy 44.271684 -291.551582)
			(xy 44.279579 -291.600159) (xy 44.280074 -291.624766) (xy 44.619176 -291.624766) (xy 44.623136 -291.575712)
			(xy 44.634913 -291.527928) (xy 44.654204 -291.482652) (xy 44.680507 -291.441056) (xy 44.713142 -291.404219)
			(xy 44.751263 -291.373094) (xy 44.793884 -291.348487) (xy 44.8399 -291.331035) (xy 44.888119 -291.321191)
			(xy 44.937294 -291.31921) (xy 44.986149 -291.325142) (xy 45.03342 -291.338834) (xy 45.077882 -291.359932)
			(xy 45.118385 -291.387888) (xy 45.153878 -291.42198) (xy 45.183443 -291.461324) (xy 45.206314 -291.504901)
			(xy 45.221898 -291.551582) (xy 45.229793 -291.600159) (xy 45.230288 -291.624766) (xy 45.569136 -291.624766)
			(xy 45.573096 -291.575712) (xy 45.584873 -291.527928) (xy 45.604164 -291.482652) (xy 45.630467 -291.441056)
			(xy 45.663102 -291.404219) (xy 45.701223 -291.373094) (xy 45.743844 -291.348487) (xy 45.78986 -291.331035)
			(xy 45.838079 -291.321191) (xy 45.887254 -291.31921) (xy 45.936109 -291.325142) (xy 45.98338 -291.338834)
			(xy 46.027842 -291.359932) (xy 46.068345 -291.387888) (xy 46.103838 -291.42198) (xy 46.133403 -291.461324)
			(xy 46.156274 -291.504901) (xy 46.171858 -291.551582) (xy 46.179753 -291.600159) (xy 46.180248 -291.624766)
			(xy 47.469056 -291.624766) (xy 47.473016 -291.575712) (xy 47.484793 -291.527928) (xy 47.504084 -291.482652)
			(xy 47.530387 -291.441056) (xy 47.563022 -291.404219) (xy 47.601143 -291.373094) (xy 47.643764 -291.348487)
			(xy 47.68978 -291.331035) (xy 47.737999 -291.321191) (xy 47.787174 -291.31921) (xy 47.836029 -291.325142)
			(xy 47.8833 -291.338834) (xy 47.927762 -291.359932) (xy 47.968265 -291.387888) (xy 48.003758 -291.42198)
			(xy 48.033323 -291.461324) (xy 48.056194 -291.504901) (xy 48.071778 -291.551582) (xy 48.079673 -291.600159)
			(xy 48.080168 -291.624766) (xy 48.079673 -291.649373) (xy 48.071778 -291.69795) (xy 48.056194 -291.744631)
			(xy 48.033323 -291.788208) (xy 48.003758 -291.827552) (xy 47.968265 -291.861644) (xy 47.927762 -291.8896)
			(xy 47.8833 -291.910698) (xy 47.836029 -291.92439) (xy 47.787174 -291.930322) (xy 47.737999 -291.928341)
			(xy 47.68978 -291.918497) (xy 47.643764 -291.901045) (xy 47.601143 -291.876438) (xy 47.563022 -291.845313)
			(xy 47.530387 -291.808476) (xy 47.504084 -291.76688) (xy 47.484793 -291.721604) (xy 47.473016 -291.67382)
			(xy 47.469056 -291.624766) (xy 46.180248 -291.624766) (xy 46.179753 -291.649373) (xy 46.171858 -291.69795)
			(xy 46.156274 -291.744631) (xy 46.133403 -291.788208) (xy 46.103838 -291.827552) (xy 46.068345 -291.861644)
			(xy 46.027842 -291.8896) (xy 45.98338 -291.910698) (xy 45.936109 -291.92439) (xy 45.887254 -291.930322)
			(xy 45.838079 -291.928341) (xy 45.78986 -291.918497) (xy 45.743844 -291.901045) (xy 45.701223 -291.876438)
			(xy 45.663102 -291.845313) (xy 45.630467 -291.808476) (xy 45.604164 -291.76688) (xy 45.584873 -291.721604)
			(xy 45.573096 -291.67382) (xy 45.569136 -291.624766) (xy 45.230288 -291.624766) (xy 45.229793 -291.649373)
			(xy 45.221898 -291.69795) (xy 45.206314 -291.744631) (xy 45.183443 -291.788208) (xy 45.153878 -291.827552)
			(xy 45.118385 -291.861644) (xy 45.077882 -291.8896) (xy 45.03342 -291.910698) (xy 44.986149 -291.92439)
			(xy 44.937294 -291.930322) (xy 44.888119 -291.928341) (xy 44.8399 -291.918497) (xy 44.793884 -291.901045)
			(xy 44.751263 -291.876438) (xy 44.713142 -291.845313) (xy 44.680507 -291.808476) (xy 44.654204 -291.76688)
			(xy 44.634913 -291.721604) (xy 44.623136 -291.67382) (xy 44.619176 -291.624766) (xy 44.280074 -291.624766)
			(xy 44.279579 -291.649373) (xy 44.271684 -291.69795) (xy 44.2561 -291.744631) (xy 44.233229 -291.788208)
			(xy 44.203664 -291.827552) (xy 44.168171 -291.861644) (xy 44.127668 -291.8896) (xy 44.083206 -291.910698)
			(xy 44.035935 -291.92439) (xy 43.98708 -291.930322) (xy 43.937905 -291.928341) (xy 43.889686 -291.918497)
			(xy 43.84367 -291.901045) (xy 43.801049 -291.876438) (xy 43.762928 -291.845313) (xy 43.730293 -291.808476)
			(xy 43.70399 -291.76688) (xy 43.684699 -291.721604) (xy 43.672922 -291.67382) (xy 43.668962 -291.624766)
			(xy 43.330114 -291.624766) (xy 43.329619 -291.649373) (xy 43.321724 -291.69795) (xy 43.30614 -291.744631)
			(xy 43.283269 -291.788208) (xy 43.253704 -291.827552) (xy 43.218211 -291.861644) (xy 43.177708 -291.8896)
			(xy 43.133246 -291.910698) (xy 43.085975 -291.92439) (xy 43.03712 -291.930322) (xy 42.987945 -291.928341)
			(xy 42.939726 -291.918497) (xy 42.89371 -291.901045) (xy 42.851089 -291.876438) (xy 42.812968 -291.845313)
			(xy 42.780333 -291.808476) (xy 42.75403 -291.76688) (xy 42.734739 -291.721604) (xy 42.722962 -291.67382)
			(xy 42.719002 -291.624766) (xy 42.380154 -291.624766) (xy 42.379659 -291.649373) (xy 42.371764 -291.69795)
			(xy 42.35618 -291.744631) (xy 42.333309 -291.788208) (xy 42.303744 -291.827552) (xy 42.268251 -291.861644)
			(xy 42.227748 -291.8896) (xy 42.183286 -291.910698) (xy 42.136015 -291.92439) (xy 42.08716 -291.930322)
			(xy 42.037985 -291.928341) (xy 41.989766 -291.918497) (xy 41.94375 -291.901045) (xy 41.901129 -291.876438)
			(xy 41.863008 -291.845313) (xy 41.830373 -291.808476) (xy 41.80407 -291.76688) (xy 41.784779 -291.721604)
			(xy 41.773002 -291.67382) (xy 41.769042 -291.624766) (xy 41.430194 -291.624766) (xy 41.429699 -291.649373)
			(xy 41.421804 -291.69795) (xy 41.40622 -291.744631) (xy 41.383349 -291.788208) (xy 41.353784 -291.827552)
			(xy 41.318291 -291.861644) (xy 41.277788 -291.8896) (xy 41.233326 -291.910698) (xy 41.186055 -291.92439)
			(xy 41.1372 -291.930322) (xy 41.088025 -291.928341) (xy 41.039806 -291.918497) (xy 40.99379 -291.901045)
			(xy 40.951169 -291.876438) (xy 40.913048 -291.845313) (xy 40.880413 -291.808476) (xy 40.85411 -291.76688)
			(xy 40.834819 -291.721604) (xy 40.823042 -291.67382) (xy 40.819082 -291.624766) (xy 38.580314 -291.624766)
			(xy 38.579819 -291.649373) (xy 38.571924 -291.69795) (xy 38.55634 -291.744631) (xy 38.533469 -291.788208)
			(xy 38.503904 -291.827552) (xy 38.468411 -291.861644) (xy 38.427908 -291.8896) (xy 38.383446 -291.910698)
			(xy 38.336175 -291.92439) (xy 38.28732 -291.930322) (xy 38.238145 -291.928341) (xy 38.189926 -291.918497)
			(xy 38.14391 -291.901045) (xy 38.101289 -291.876438) (xy 38.063168 -291.845313) (xy 38.030533 -291.808476)
			(xy 38.00423 -291.76688) (xy 37.984939 -291.721604) (xy 37.973162 -291.67382) (xy 37.969202 -291.624766)
			(xy 37.6301 -291.624766) (xy 37.629605 -291.649373) (xy 37.62171 -291.69795) (xy 37.606126 -291.744631)
			(xy 37.583255 -291.788208) (xy 37.55369 -291.827552) (xy 37.518197 -291.861644) (xy 37.477694 -291.8896)
			(xy 37.433232 -291.910698) (xy 37.385961 -291.92439) (xy 37.337106 -291.930322) (xy 37.287931 -291.928341)
			(xy 37.239712 -291.918497) (xy 37.193696 -291.901045) (xy 37.151075 -291.876438) (xy 37.112954 -291.845313)
			(xy 37.080319 -291.808476) (xy 37.054016 -291.76688) (xy 37.034725 -291.721604) (xy 37.022948 -291.67382)
			(xy 37.018988 -291.624766) (xy 36.68014 -291.624766) (xy 36.679645 -291.649373) (xy 36.67175 -291.69795)
			(xy 36.656166 -291.744631) (xy 36.633295 -291.788208) (xy 36.60373 -291.827552) (xy 36.568237 -291.861644)
			(xy 36.527734 -291.8896) (xy 36.483272 -291.910698) (xy 36.436001 -291.92439) (xy 36.387146 -291.930322)
			(xy 36.337971 -291.928341) (xy 36.289752 -291.918497) (xy 36.243736 -291.901045) (xy 36.201115 -291.876438)
			(xy 36.162994 -291.845313) (xy 36.130359 -291.808476) (xy 36.104056 -291.76688) (xy 36.084765 -291.721604)
			(xy 36.072988 -291.67382) (xy 36.069028 -291.624766) (xy 28.006914 -291.624766) (xy 27.981 -291.663935)
			(xy 27.943783 -291.705472) (xy 27.900915 -291.741147) (xy 27.853309 -291.770201) (xy 27.80198 -291.792013)
			(xy 27.748023 -291.806119) (xy 27.692586 -291.812219) (xy 27.636852 -291.810182) (xy 27.582009 -291.800052)
			(xy 27.529225 -291.782045) (xy 27.479625 -291.756544) (xy 27.434267 -291.724093) (xy 27.394118 -291.685384)
			(xy 27.360032 -291.641241) (xy 27.332736 -291.592606) (xy 27.312813 -291.540515) (xy 27.300687 -291.486078)
			(xy 27.296616 -291.430456) (xy 26.575004 -291.430456) (xy 26.574495 -291.458342) (xy 26.566375 -291.513518)
			(xy 26.550307 -291.566925) (xy 26.526635 -291.617422) (xy 26.495862 -291.663935) (xy 26.458645 -291.705472)
			(xy 26.415777 -291.741147) (xy 26.368171 -291.770201) (xy 26.316842 -291.792013) (xy 26.262885 -291.806119)
			(xy 26.207448 -291.812219) (xy 26.151714 -291.810182) (xy 26.096871 -291.800052) (xy 26.044087 -291.782045)
			(xy 25.994487 -291.756544) (xy 25.949129 -291.724093) (xy 25.90898 -291.685384) (xy 25.874894 -291.641241)
			(xy 25.847598 -291.592606) (xy 25.827675 -291.540515) (xy 25.815549 -291.486078) (xy 25.811478 -291.430456)
			(xy 1.468374 -291.430456) (xy 1.468374 -292.732714) (xy 25.811478 -292.732714) (xy 25.815549 -292.677092)
			(xy 25.827675 -292.622655) (xy 25.847598 -292.570564) (xy 25.874894 -292.521929) (xy 25.90898 -292.477786)
			(xy 25.949129 -292.439077) (xy 25.994487 -292.406626) (xy 26.044087 -292.381125) (xy 26.096871 -292.363118)
			(xy 26.151714 -292.352988) (xy 26.207448 -292.350951) (xy 26.262885 -292.357051) (xy 26.316842 -292.371157)
			(xy 26.368171 -292.392969) (xy 26.415777 -292.422023) (xy 26.458645 -292.457698) (xy 26.495862 -292.499235)
			(xy 26.526635 -292.545748) (xy 26.550307 -292.596245) (xy 26.566375 -292.649652) (xy 26.574495 -292.704828)
			(xy 26.575004 -292.732714) (xy 27.286964 -292.732714) (xy 27.291035 -292.677092) (xy 27.303161 -292.622655)
			(xy 27.323084 -292.570564) (xy 27.35038 -292.521929) (xy 27.384466 -292.477786) (xy 27.424615 -292.439077)
			(xy 27.469973 -292.406626) (xy 27.519573 -292.381125) (xy 27.572357 -292.363118) (xy 27.6272 -292.352988)
			(xy 27.682934 -292.350951) (xy 27.738371 -292.357051) (xy 27.792328 -292.371157) (xy 27.843657 -292.392969)
			(xy 27.891263 -292.422023) (xy 27.934131 -292.457698) (xy 27.971348 -292.499235) (xy 28.002121 -292.545748)
			(xy 28.025793 -292.596245) (xy 28.041861 -292.649652) (xy 28.049981 -292.704828) (xy 28.05049 -292.732714)
			(xy 28.175964 -292.732714) (xy 28.180035 -292.677092) (xy 28.192161 -292.622655) (xy 28.212084 -292.570564)
			(xy 28.23938 -292.521929) (xy 28.273466 -292.477786) (xy 28.313615 -292.439077) (xy 28.358973 -292.406626)
			(xy 28.408573 -292.381125) (xy 28.461357 -292.363118) (xy 28.5162 -292.352988) (xy 28.571934 -292.350951)
			(xy 28.627371 -292.357051) (xy 28.681328 -292.371157) (xy 28.732657 -292.392969) (xy 28.780263 -292.422023)
			(xy 28.823131 -292.457698) (xy 28.860348 -292.499235) (xy 28.891121 -292.545748) (xy 28.914793 -292.596245)
			(xy 28.930861 -292.649652) (xy 28.938981 -292.704828) (xy 28.93949 -292.732714) (xy 28.938981 -292.7606)
			(xy 28.930861 -292.815776) (xy 28.914793 -292.869183) (xy 28.891121 -292.91968) (xy 28.860348 -292.966193)
			(xy 28.823131 -293.00773) (xy 28.780263 -293.043405) (xy 28.732657 -293.072459) (xy 28.681328 -293.094271)
			(xy 28.627371 -293.108377) (xy 28.571934 -293.114477) (xy 28.5162 -293.11244) (xy 28.461357 -293.10231)
			(xy 28.408573 -293.084303) (xy 28.358973 -293.058802) (xy 28.313615 -293.026351) (xy 28.273466 -292.987642)
			(xy 28.23938 -292.943499) (xy 28.212084 -292.894864) (xy 28.192161 -292.842773) (xy 28.180035 -292.788336)
			(xy 28.175964 -292.732714) (xy 28.05049 -292.732714) (xy 28.049981 -292.7606) (xy 28.041861 -292.815776)
			(xy 28.025793 -292.869183) (xy 28.002121 -292.91968) (xy 27.971348 -292.966193) (xy 27.934131 -293.00773)
			(xy 27.891263 -293.043405) (xy 27.843657 -293.072459) (xy 27.792328 -293.094271) (xy 27.738371 -293.108377)
			(xy 27.682934 -293.114477) (xy 27.6272 -293.11244) (xy 27.572357 -293.10231) (xy 27.519573 -293.084303)
			(xy 27.469973 -293.058802) (xy 27.424615 -293.026351) (xy 27.384466 -292.987642) (xy 27.35038 -292.943499)
			(xy 27.323084 -292.894864) (xy 27.303161 -292.842773) (xy 27.291035 -292.788336) (xy 27.286964 -292.732714)
			(xy 26.575004 -292.732714) (xy 26.574495 -292.7606) (xy 26.566375 -292.815776) (xy 26.550307 -292.869183)
			(xy 26.526635 -292.91968) (xy 26.495862 -292.966193) (xy 26.458645 -293.00773) (xy 26.415777 -293.043405)
			(xy 26.368171 -293.072459) (xy 26.316842 -293.094271) (xy 26.262885 -293.108377) (xy 26.207448 -293.114477)
			(xy 26.151714 -293.11244) (xy 26.096871 -293.10231) (xy 26.044087 -293.084303) (xy 25.994487 -293.058802)
			(xy 25.949129 -293.026351) (xy 25.90898 -292.987642) (xy 25.874894 -292.943499) (xy 25.847598 -292.894864)
			(xy 25.827675 -292.842773) (xy 25.815549 -292.788336) (xy 25.811478 -292.732714) (xy 1.468374 -292.732714)
			(xy 1.468374 -292.949884) (xy 1.468845 -292.959756) (xy 1.476302 -292.97804) (xy 1.482852 -292.985444)
			(xy 1.483106 -292.985698) (xy 1.992122 -293.494714) (xy 31.338012 -293.494714) (xy 31.338555 -293.465332)
			(xy 31.347584 -293.407265) (xy 31.365415 -293.35127) (xy 31.391626 -293.298675) (xy 31.425597 -293.250724)
			(xy 31.466521 -293.208552) (xy 31.48965 -293.190422) (xy 31.499048 -293.183056) (xy 31.509462 -293.162482)
			(xy 31.510986 -293.058596) (xy 31.50108 -293.037514) (xy 31.491936 -293.030148) (xy 31.470088 -293.011942)
			(xy 31.431546 -292.970124) (xy 31.399638 -292.923049) (xy 31.375071 -292.871759) (xy 31.358388 -292.817391)
			(xy 31.34996 -292.761149) (xy 31.349442 -292.732714) (xy 31.349928 -292.705463) (xy 31.357684 -292.651515)
			(xy 31.373039 -292.59922) (xy 31.395681 -292.549643) (xy 31.425147 -292.503793) (xy 31.460838 -292.462602)
			(xy 31.502029 -292.426911) (xy 31.547879 -292.397445) (xy 31.597456 -292.374803) (xy 31.649751 -292.359448)
			(xy 31.703699 -292.351692) (xy 31.758201 -292.351692) (xy 31.812149 -292.359448) (xy 31.864444 -292.374803)
			(xy 31.914021 -292.397445) (xy 31.959871 -292.426911) (xy 32.001062 -292.462602) (xy 32.036753 -292.503793)
			(xy 32.066219 -292.549643) (xy 32.077791 -292.57498) (xy 36.069028 -292.57498) (xy 36.072988 -292.525926)
			(xy 36.084765 -292.478142) (xy 36.104056 -292.432866) (xy 36.130359 -292.39127) (xy 36.162994 -292.354433)
			(xy 36.201115 -292.323308) (xy 36.243736 -292.298701) (xy 36.289752 -292.281249) (xy 36.337971 -292.271405)
			(xy 36.387146 -292.269424) (xy 36.436001 -292.275356) (xy 36.483272 -292.289048) (xy 36.527734 -292.310146)
			(xy 36.568237 -292.338102) (xy 36.60373 -292.372194) (xy 36.633295 -292.411538) (xy 36.656166 -292.455115)
			(xy 36.67175 -292.501796) (xy 36.679645 -292.550373) (xy 36.68014 -292.57498) (xy 37.018988 -292.57498)
			(xy 37.022948 -292.525926) (xy 37.034725 -292.478142) (xy 37.054016 -292.432866) (xy 37.080319 -292.39127)
			(xy 37.112954 -292.354433) (xy 37.151075 -292.323308) (xy 37.193696 -292.298701) (xy 37.239712 -292.281249)
			(xy 37.287931 -292.271405) (xy 37.337106 -292.269424) (xy 37.385961 -292.275356) (xy 37.433232 -292.289048)
			(xy 37.477694 -292.310146) (xy 37.518197 -292.338102) (xy 37.55369 -292.372194) (xy 37.583255 -292.411538)
			(xy 37.606126 -292.455115) (xy 37.62171 -292.501796) (xy 37.629605 -292.550373) (xy 37.6301 -292.57498)
			(xy 37.969202 -292.57498) (xy 37.973162 -292.525926) (xy 37.984939 -292.478142) (xy 38.00423 -292.432866)
			(xy 38.030533 -292.39127) (xy 38.063168 -292.354433) (xy 38.101289 -292.323308) (xy 38.14391 -292.298701)
			(xy 38.189926 -292.281249) (xy 38.238145 -292.271405) (xy 38.28732 -292.269424) (xy 38.336175 -292.275356)
			(xy 38.383446 -292.289048) (xy 38.427908 -292.310146) (xy 38.468411 -292.338102) (xy 38.503904 -292.372194)
			(xy 38.533469 -292.411538) (xy 38.55634 -292.455115) (xy 38.571924 -292.501796) (xy 38.579819 -292.550373)
			(xy 38.580309 -292.574726) (xy 38.919162 -292.574726) (xy 38.923122 -292.525672) (xy 38.934899 -292.477888)
			(xy 38.95419 -292.432612) (xy 38.980493 -292.391016) (xy 39.013128 -292.354179) (xy 39.051249 -292.323054)
			(xy 39.09387 -292.298447) (xy 39.139886 -292.280995) (xy 39.188105 -292.271151) (xy 39.23728 -292.26917)
			(xy 39.286135 -292.275102) (xy 39.333406 -292.288794) (xy 39.377868 -292.309892) (xy 39.418371 -292.337848)
			(xy 39.453864 -292.37194) (xy 39.483429 -292.411284) (xy 39.5063 -292.454861) (xy 39.521884 -292.501542)
			(xy 39.529779 -292.550119) (xy 39.530274 -292.574726) (xy 39.869122 -292.574726) (xy 39.873082 -292.525672)
			(xy 39.884859 -292.477888) (xy 39.90415 -292.432612) (xy 39.930453 -292.391016) (xy 39.963088 -292.354179)
			(xy 40.001209 -292.323054) (xy 40.04383 -292.298447) (xy 40.089846 -292.280995) (xy 40.138065 -292.271151)
			(xy 40.18724 -292.26917) (xy 40.236095 -292.275102) (xy 40.283366 -292.288794) (xy 40.327828 -292.309892)
			(xy 40.368331 -292.337848) (xy 40.403824 -292.37194) (xy 40.433389 -292.411284) (xy 40.45626 -292.454861)
			(xy 40.471844 -292.501542) (xy 40.479739 -292.550119) (xy 40.480234 -292.574726) (xy 40.480229 -292.57498)
			(xy 40.819082 -292.57498) (xy 40.823042 -292.525926) (xy 40.834819 -292.478142) (xy 40.85411 -292.432866)
			(xy 40.880413 -292.39127) (xy 40.913048 -292.354433) (xy 40.951169 -292.323308) (xy 40.99379 -292.298701)
			(xy 41.039806 -292.281249) (xy 41.088025 -292.271405) (xy 41.1372 -292.269424) (xy 41.186055 -292.275356)
			(xy 41.233326 -292.289048) (xy 41.277788 -292.310146) (xy 41.318291 -292.338102) (xy 41.353784 -292.372194)
			(xy 41.383349 -292.411538) (xy 41.40622 -292.455115) (xy 41.421804 -292.501796) (xy 41.429699 -292.550373)
			(xy 41.430194 -292.57498) (xy 41.429699 -292.599587) (xy 41.429367 -292.601629) (xy 41.719236 -292.601629)
			(xy 41.719236 -292.548331) (xy 41.727179 -292.495627) (xy 41.742889 -292.444697) (xy 41.766015 -292.396676)
			(xy 41.796039 -292.352639) (xy 41.832291 -292.313568) (xy 41.873962 -292.280337) (xy 41.92012 -292.253688)
			(xy 41.969734 -292.234216) (xy 42.021696 -292.222356) (xy 42.074846 -292.218373) (xy 42.127996 -292.222356)
			(xy 42.179958 -292.234216) (xy 42.229572 -292.253688) (xy 42.27573 -292.280337) (xy 42.317401 -292.313568)
			(xy 42.353653 -292.352639) (xy 42.383677 -292.396676) (xy 42.406803 -292.444697) (xy 42.422513 -292.495627)
			(xy 42.430456 -292.548331) (xy 42.430954 -292.57498) (xy 42.719002 -292.57498) (xy 42.722962 -292.525926)
			(xy 42.734739 -292.478142) (xy 42.75403 -292.432866) (xy 42.780333 -292.39127) (xy 42.812968 -292.354433)
			(xy 42.851089 -292.323308) (xy 42.89371 -292.298701) (xy 42.939726 -292.281249) (xy 42.987945 -292.271405)
			(xy 43.03712 -292.269424) (xy 43.085975 -292.275356) (xy 43.133246 -292.289048) (xy 43.177708 -292.310146)
			(xy 43.218211 -292.338102) (xy 43.253704 -292.372194) (xy 43.283269 -292.411538) (xy 43.30614 -292.455115)
			(xy 43.321724 -292.501796) (xy 43.329619 -292.550373) (xy 43.330114 -292.57498) (xy 43.668962 -292.57498)
			(xy 43.672922 -292.525926) (xy 43.684699 -292.478142) (xy 43.70399 -292.432866) (xy 43.730293 -292.39127)
			(xy 43.762928 -292.354433) (xy 43.801049 -292.323308) (xy 43.84367 -292.298701) (xy 43.889686 -292.281249)
			(xy 43.937905 -292.271405) (xy 43.98708 -292.269424) (xy 44.035935 -292.275356) (xy 44.083206 -292.289048)
			(xy 44.127668 -292.310146) (xy 44.168171 -292.338102) (xy 44.203664 -292.372194) (xy 44.233229 -292.411538)
			(xy 44.2561 -292.455115) (xy 44.271684 -292.501796) (xy 44.279579 -292.550373) (xy 44.280074 -292.57498)
			(xy 44.619176 -292.57498) (xy 44.623136 -292.525926) (xy 44.634913 -292.478142) (xy 44.654204 -292.432866)
			(xy 44.680507 -292.39127) (xy 44.713142 -292.354433) (xy 44.751263 -292.323308) (xy 44.793884 -292.298701)
			(xy 44.8399 -292.281249) (xy 44.888119 -292.271405) (xy 44.937294 -292.269424) (xy 44.986149 -292.275356)
			(xy 45.03342 -292.289048) (xy 45.077882 -292.310146) (xy 45.118385 -292.338102) (xy 45.153878 -292.372194)
			(xy 45.183443 -292.411538) (xy 45.206314 -292.455115) (xy 45.221898 -292.501796) (xy 45.229793 -292.550373)
			(xy 45.230288 -292.57498) (xy 45.569136 -292.57498) (xy 45.573096 -292.525926) (xy 45.584873 -292.478142)
			(xy 45.604164 -292.432866) (xy 45.630467 -292.39127) (xy 45.663102 -292.354433) (xy 45.701223 -292.323308)
			(xy 45.743844 -292.298701) (xy 45.78986 -292.281249) (xy 45.838079 -292.271405) (xy 45.887254 -292.269424)
			(xy 45.936109 -292.275356) (xy 45.98338 -292.289048) (xy 46.027842 -292.310146) (xy 46.068345 -292.338102)
			(xy 46.103838 -292.372194) (xy 46.133403 -292.411538) (xy 46.156274 -292.455115) (xy 46.171858 -292.501796)
			(xy 46.179753 -292.550373) (xy 46.180248 -292.57498) (xy 46.519096 -292.57498) (xy 46.523056 -292.525926)
			(xy 46.534833 -292.478142) (xy 46.554124 -292.432866) (xy 46.580427 -292.39127) (xy 46.613062 -292.354433)
			(xy 46.651183 -292.323308) (xy 46.693804 -292.298701) (xy 46.73982 -292.281249) (xy 46.788039 -292.271405)
			(xy 46.837214 -292.269424) (xy 46.886069 -292.275356) (xy 46.93334 -292.289048) (xy 46.977802 -292.310146)
			(xy 47.018305 -292.338102) (xy 47.053798 -292.372194) (xy 47.083363 -292.411538) (xy 47.106234 -292.455115)
			(xy 47.121818 -292.501796) (xy 47.129713 -292.550373) (xy 47.130208 -292.57498) (xy 47.469056 -292.57498)
			(xy 47.473016 -292.525926) (xy 47.484793 -292.478142) (xy 47.504084 -292.432866) (xy 47.530387 -292.39127)
			(xy 47.563022 -292.354433) (xy 47.601143 -292.323308) (xy 47.643764 -292.298701) (xy 47.68978 -292.281249)
			(xy 47.737999 -292.271405) (xy 47.787174 -292.269424) (xy 47.836029 -292.275356) (xy 47.8833 -292.289048)
			(xy 47.927762 -292.310146) (xy 47.968265 -292.338102) (xy 48.003758 -292.372194) (xy 48.033323 -292.411538)
			(xy 48.056194 -292.455115) (xy 48.071778 -292.501796) (xy 48.079673 -292.550373) (xy 48.080168 -292.57498)
			(xy 48.079673 -292.599587) (xy 48.071778 -292.648164) (xy 48.056194 -292.694845) (xy 48.033323 -292.738422)
			(xy 48.003758 -292.777766) (xy 47.968265 -292.811858) (xy 47.927762 -292.839814) (xy 47.8833 -292.860912)
			(xy 47.836029 -292.874604) (xy 47.787174 -292.880536) (xy 47.737999 -292.878555) (xy 47.68978 -292.868711)
			(xy 47.643764 -292.851259) (xy 47.601143 -292.826652) (xy 47.563022 -292.795527) (xy 47.530387 -292.75869)
			(xy 47.504084 -292.717094) (xy 47.484793 -292.671818) (xy 47.473016 -292.624034) (xy 47.469056 -292.57498)
			(xy 47.130208 -292.57498) (xy 47.129713 -292.599587) (xy 47.121818 -292.648164) (xy 47.106234 -292.694845)
			(xy 47.083363 -292.738422) (xy 47.053798 -292.777766) (xy 47.018305 -292.811858) (xy 46.977802 -292.839814)
			(xy 46.93334 -292.860912) (xy 46.886069 -292.874604) (xy 46.837214 -292.880536) (xy 46.788039 -292.878555)
			(xy 46.73982 -292.868711) (xy 46.693804 -292.851259) (xy 46.651183 -292.826652) (xy 46.613062 -292.795527)
			(xy 46.580427 -292.75869) (xy 46.554124 -292.717094) (xy 46.534833 -292.671818) (xy 46.523056 -292.624034)
			(xy 46.519096 -292.57498) (xy 46.180248 -292.57498) (xy 46.179753 -292.599587) (xy 46.171858 -292.648164)
			(xy 46.156274 -292.694845) (xy 46.133403 -292.738422) (xy 46.103838 -292.777766) (xy 46.068345 -292.811858)
			(xy 46.027842 -292.839814) (xy 45.98338 -292.860912) (xy 45.936109 -292.874604) (xy 45.887254 -292.880536)
			(xy 45.838079 -292.878555) (xy 45.78986 -292.868711) (xy 45.743844 -292.851259) (xy 45.701223 -292.826652)
			(xy 45.663102 -292.795527) (xy 45.630467 -292.75869) (xy 45.604164 -292.717094) (xy 45.584873 -292.671818)
			(xy 45.573096 -292.624034) (xy 45.569136 -292.57498) (xy 45.230288 -292.57498) (xy 45.229793 -292.599587)
			(xy 45.221898 -292.648164) (xy 45.206314 -292.694845) (xy 45.183443 -292.738422) (xy 45.153878 -292.777766)
			(xy 45.118385 -292.811858) (xy 45.077882 -292.839814) (xy 45.03342 -292.860912) (xy 44.986149 -292.874604)
			(xy 44.937294 -292.880536) (xy 44.888119 -292.878555) (xy 44.8399 -292.868711) (xy 44.793884 -292.851259)
			(xy 44.751263 -292.826652) (xy 44.713142 -292.795527) (xy 44.680507 -292.75869) (xy 44.654204 -292.717094)
			(xy 44.634913 -292.671818) (xy 44.623136 -292.624034) (xy 44.619176 -292.57498) (xy 44.280074 -292.57498)
			(xy 44.279579 -292.599587) (xy 44.271684 -292.648164) (xy 44.2561 -292.694845) (xy 44.233229 -292.738422)
			(xy 44.203664 -292.777766) (xy 44.168171 -292.811858) (xy 44.127668 -292.839814) (xy 44.083206 -292.860912)
			(xy 44.035935 -292.874604) (xy 43.98708 -292.880536) (xy 43.937905 -292.878555) (xy 43.889686 -292.868711)
			(xy 43.84367 -292.851259) (xy 43.801049 -292.826652) (xy 43.762928 -292.795527) (xy 43.730293 -292.75869)
			(xy 43.70399 -292.717094) (xy 43.684699 -292.671818) (xy 43.672922 -292.624034) (xy 43.668962 -292.57498)
			(xy 43.330114 -292.57498) (xy 43.329619 -292.599587) (xy 43.321724 -292.648164) (xy 43.30614 -292.694845)
			(xy 43.283269 -292.738422) (xy 43.253704 -292.777766) (xy 43.218211 -292.811858) (xy 43.177708 -292.839814)
			(xy 43.133246 -292.860912) (xy 43.085975 -292.874604) (xy 43.03712 -292.880536) (xy 42.987945 -292.878555)
			(xy 42.939726 -292.868711) (xy 42.89371 -292.851259) (xy 42.851089 -292.826652) (xy 42.812968 -292.795527)
			(xy 42.780333 -292.75869) (xy 42.75403 -292.717094) (xy 42.734739 -292.671818) (xy 42.722962 -292.624034)
			(xy 42.719002 -292.57498) (xy 42.430954 -292.57498) (xy 42.430456 -292.601629) (xy 42.422513 -292.654333)
			(xy 42.406803 -292.705263) (xy 42.383677 -292.753284) (xy 42.353653 -292.797321) (xy 42.317401 -292.836392)
			(xy 42.27573 -292.869623) (xy 42.229572 -292.896272) (xy 42.179958 -292.915744) (xy 42.127996 -292.927604)
			(xy 42.074846 -292.931588) (xy 42.021696 -292.927604) (xy 41.969734 -292.915744) (xy 41.92012 -292.896272)
			(xy 41.873962 -292.869623) (xy 41.832291 -292.836392) (xy 41.796039 -292.797321) (xy 41.766015 -292.753284)
			(xy 41.742889 -292.705263) (xy 41.727179 -292.654333) (xy 41.719236 -292.601629) (xy 41.429367 -292.601629)
			(xy 41.421804 -292.648164) (xy 41.40622 -292.694845) (xy 41.383349 -292.738422) (xy 41.353784 -292.777766)
			(xy 41.318291 -292.811858) (xy 41.277788 -292.839814) (xy 41.233326 -292.860912) (xy 41.186055 -292.874604)
			(xy 41.1372 -292.880536) (xy 41.088025 -292.878555) (xy 41.039806 -292.868711) (xy 40.99379 -292.851259)
			(xy 40.951169 -292.826652) (xy 40.913048 -292.795527) (xy 40.880413 -292.75869) (xy 40.85411 -292.717094)
			(xy 40.834819 -292.671818) (xy 40.823042 -292.624034) (xy 40.819082 -292.57498) (xy 40.480229 -292.57498)
			(xy 40.479739 -292.599333) (xy 40.471844 -292.64791) (xy 40.45626 -292.694591) (xy 40.433389 -292.738168)
			(xy 40.403824 -292.777512) (xy 40.368331 -292.811604) (xy 40.327828 -292.83956) (xy 40.283366 -292.860658)
			(xy 40.236095 -292.87435) (xy 40.18724 -292.880282) (xy 40.138065 -292.878301) (xy 40.089846 -292.868457)
			(xy 40.04383 -292.851005) (xy 40.001209 -292.826398) (xy 39.963088 -292.795273) (xy 39.930453 -292.758436)
			(xy 39.90415 -292.71684) (xy 39.884859 -292.671564) (xy 39.873082 -292.62378) (xy 39.869122 -292.574726)
			(xy 39.530274 -292.574726) (xy 39.529779 -292.599333) (xy 39.521884 -292.64791) (xy 39.5063 -292.694591)
			(xy 39.483429 -292.738168) (xy 39.453864 -292.777512) (xy 39.418371 -292.811604) (xy 39.377868 -292.83956)
			(xy 39.333406 -292.860658) (xy 39.286135 -292.87435) (xy 39.23728 -292.880282) (xy 39.188105 -292.878301)
			(xy 39.139886 -292.868457) (xy 39.09387 -292.851005) (xy 39.051249 -292.826398) (xy 39.013128 -292.795273)
			(xy 38.980493 -292.758436) (xy 38.95419 -292.71684) (xy 38.934899 -292.671564) (xy 38.923122 -292.62378)
			(xy 38.919162 -292.574726) (xy 38.580309 -292.574726) (xy 38.580314 -292.57498) (xy 38.579819 -292.599587)
			(xy 38.571924 -292.648164) (xy 38.55634 -292.694845) (xy 38.533469 -292.738422) (xy 38.503904 -292.777766)
			(xy 38.468411 -292.811858) (xy 38.427908 -292.839814) (xy 38.383446 -292.860912) (xy 38.336175 -292.874604)
			(xy 38.28732 -292.880536) (xy 38.238145 -292.878555) (xy 38.189926 -292.868711) (xy 38.14391 -292.851259)
			(xy 38.101289 -292.826652) (xy 38.063168 -292.795527) (xy 38.030533 -292.75869) (xy 38.00423 -292.717094)
			(xy 37.984939 -292.671818) (xy 37.973162 -292.624034) (xy 37.969202 -292.57498) (xy 37.6301 -292.57498)
			(xy 37.629605 -292.599587) (xy 37.62171 -292.648164) (xy 37.606126 -292.694845) (xy 37.583255 -292.738422)
			(xy 37.55369 -292.777766) (xy 37.518197 -292.811858) (xy 37.477694 -292.839814) (xy 37.433232 -292.860912)
			(xy 37.385961 -292.874604) (xy 37.337106 -292.880536) (xy 37.287931 -292.878555) (xy 37.239712 -292.868711)
			(xy 37.193696 -292.851259) (xy 37.151075 -292.826652) (xy 37.112954 -292.795527) (xy 37.080319 -292.75869)
			(xy 37.054016 -292.717094) (xy 37.034725 -292.671818) (xy 37.022948 -292.624034) (xy 37.018988 -292.57498)
			(xy 36.68014 -292.57498) (xy 36.679645 -292.599587) (xy 36.67175 -292.648164) (xy 36.656166 -292.694845)
			(xy 36.633295 -292.738422) (xy 36.60373 -292.777766) (xy 36.568237 -292.811858) (xy 36.527734 -292.839814)
			(xy 36.483272 -292.860912) (xy 36.436001 -292.874604) (xy 36.387146 -292.880536) (xy 36.337971 -292.878555)
			(xy 36.289752 -292.868711) (xy 36.243736 -292.851259) (xy 36.201115 -292.826652) (xy 36.162994 -292.795527)
			(xy 36.130359 -292.75869) (xy 36.104056 -292.717094) (xy 36.084765 -292.671818) (xy 36.072988 -292.624034)
			(xy 36.069028 -292.57498) (xy 32.077791 -292.57498) (xy 32.088861 -292.59922) (xy 32.104216 -292.651515)
			(xy 32.111972 -292.705463) (xy 32.112458 -292.732714) (xy 32.111907 -292.762096) (xy 32.102876 -292.820161)
			(xy 32.085044 -292.876154) (xy 32.058835 -292.928749) (xy 32.024867 -292.9767) (xy 31.983946 -293.018874)
			(xy 31.96082 -293.037006) (xy 31.951422 -293.044372) (xy 31.941008 -293.064946) (xy 31.939484 -293.168832)
			(xy 31.94939 -293.189914) (xy 31.958534 -293.19728) (xy 31.980362 -293.215509) (xy 32.018902 -293.257324)
			(xy 32.05081 -293.304395) (xy 32.07538 -293.35568) (xy 32.092068 -293.410043) (xy 32.100505 -293.466281)
			(xy 32.101028 -293.494714) (xy 32.734502 -293.494714) (xy 32.738573 -293.439092) (xy 32.750699 -293.384655)
			(xy 32.770622 -293.332564) (xy 32.797918 -293.283929) (xy 32.832004 -293.239786) (xy 32.872153 -293.201077)
			(xy 32.917511 -293.168626) (xy 32.967111 -293.143125) (xy 33.019895 -293.125118) (xy 33.074738 -293.114988)
			(xy 33.130472 -293.112951) (xy 33.185909 -293.119051) (xy 33.239866 -293.133157) (xy 33.291195 -293.154969)
			(xy 33.338801 -293.184023) (xy 33.381669 -293.219698) (xy 33.418886 -293.261235) (xy 33.449659 -293.307748)
			(xy 33.473331 -293.358245) (xy 33.489399 -293.411652) (xy 33.497519 -293.466828) (xy 33.498028 -293.494714)
			(xy 33.620962 -293.494714) (xy 33.625033 -293.439092) (xy 33.637159 -293.384655) (xy 33.657082 -293.332564)
			(xy 33.684378 -293.283929) (xy 33.718464 -293.239786) (xy 33.758613 -293.201077) (xy 33.803971 -293.168626)
			(xy 33.853571 -293.143125) (xy 33.906355 -293.125118) (xy 33.961198 -293.114988) (xy 34.016932 -293.112951)
			(xy 34.072369 -293.119051) (xy 34.126326 -293.133157) (xy 34.177655 -293.154969) (xy 34.225261 -293.184023)
			(xy 34.268129 -293.219698) (xy 34.305346 -293.261235) (xy 34.336119 -293.307748) (xy 34.359791 -293.358245)
			(xy 34.375859 -293.411652) (xy 34.383979 -293.466828) (xy 34.384488 -293.494714) (xy 34.383979 -293.5226)
			(xy 34.383635 -293.52494) (xy 37.969202 -293.52494) (xy 37.973162 -293.475886) (xy 37.984939 -293.428102)
			(xy 38.00423 -293.382826) (xy 38.030533 -293.34123) (xy 38.063168 -293.304393) (xy 38.101289 -293.273268)
			(xy 38.14391 -293.248661) (xy 38.189926 -293.231209) (xy 38.238145 -293.221365) (xy 38.28732 -293.219384)
			(xy 38.336175 -293.225316) (xy 38.383446 -293.239008) (xy 38.427908 -293.260106) (xy 38.468411 -293.288062)
			(xy 38.503904 -293.322154) (xy 38.533469 -293.361498) (xy 38.55634 -293.405075) (xy 38.571924 -293.451756)
			(xy 38.579819 -293.500333) (xy 38.580314 -293.52494) (xy 38.919162 -293.52494) (xy 38.923122 -293.475886)
			(xy 38.934899 -293.428102) (xy 38.95419 -293.382826) (xy 38.980493 -293.34123) (xy 39.013128 -293.304393)
			(xy 39.051249 -293.273268) (xy 39.09387 -293.248661) (xy 39.139886 -293.231209) (xy 39.188105 -293.221365)
			(xy 39.23728 -293.219384) (xy 39.286135 -293.225316) (xy 39.333406 -293.239008) (xy 39.377868 -293.260106)
			(xy 39.418371 -293.288062) (xy 39.453864 -293.322154) (xy 39.483429 -293.361498) (xy 39.5063 -293.405075)
			(xy 39.521884 -293.451756) (xy 39.529779 -293.500333) (xy 39.530274 -293.52494) (xy 39.869122 -293.52494)
			(xy 39.873082 -293.475886) (xy 39.884859 -293.428102) (xy 39.90415 -293.382826) (xy 39.930453 -293.34123)
			(xy 39.963088 -293.304393) (xy 40.001209 -293.273268) (xy 40.04383 -293.248661) (xy 40.089846 -293.231209)
			(xy 40.138065 -293.221365) (xy 40.18724 -293.219384) (xy 40.236095 -293.225316) (xy 40.283366 -293.239008)
			(xy 40.327828 -293.260106) (xy 40.368331 -293.288062) (xy 40.403824 -293.322154) (xy 40.433389 -293.361498)
			(xy 40.45626 -293.405075) (xy 40.471844 -293.451756) (xy 40.479739 -293.500333) (xy 40.480234 -293.52494)
			(xy 40.819082 -293.52494) (xy 40.823042 -293.475886) (xy 40.834819 -293.428102) (xy 40.85411 -293.382826)
			(xy 40.880413 -293.34123) (xy 40.913048 -293.304393) (xy 40.951169 -293.273268) (xy 40.99379 -293.248661)
			(xy 41.039806 -293.231209) (xy 41.088025 -293.221365) (xy 41.1372 -293.219384) (xy 41.186055 -293.225316)
			(xy 41.233326 -293.239008) (xy 41.277788 -293.260106) (xy 41.318291 -293.288062) (xy 41.353784 -293.322154)
			(xy 41.383349 -293.361498) (xy 41.40622 -293.405075) (xy 41.421804 -293.451756) (xy 41.429699 -293.500333)
			(xy 41.430194 -293.52494) (xy 41.769042 -293.52494) (xy 41.773002 -293.475886) (xy 41.784779 -293.428102)
			(xy 41.80407 -293.382826) (xy 41.830373 -293.34123) (xy 41.863008 -293.304393) (xy 41.901129 -293.273268)
			(xy 41.94375 -293.248661) (xy 41.989766 -293.231209) (xy 42.037985 -293.221365) (xy 42.08716 -293.219384)
			(xy 42.136015 -293.225316) (xy 42.183286 -293.239008) (xy 42.227748 -293.260106) (xy 42.268251 -293.288062)
			(xy 42.303744 -293.322154) (xy 42.333309 -293.361498) (xy 42.35618 -293.405075) (xy 42.371764 -293.451756)
			(xy 42.379659 -293.500333) (xy 42.380154 -293.52494) (xy 42.379659 -293.549547) (xy 42.379327 -293.551589)
			(xy 42.669196 -293.551589) (xy 42.669196 -293.498291) (xy 42.677139 -293.445587) (xy 42.692849 -293.394657)
			(xy 42.715975 -293.346636) (xy 42.745999 -293.302599) (xy 42.782251 -293.263528) (xy 42.823922 -293.230297)
			(xy 42.87008 -293.203648) (xy 42.919694 -293.184176) (xy 42.971656 -293.172316) (xy 43.024806 -293.168333)
			(xy 43.077956 -293.172316) (xy 43.129918 -293.184176) (xy 43.179532 -293.203648) (xy 43.22569 -293.230297)
			(xy 43.267361 -293.263528) (xy 43.303613 -293.302599) (xy 43.333637 -293.346636) (xy 43.356763 -293.394657)
			(xy 43.372473 -293.445587) (xy 43.380416 -293.498291) (xy 43.380914 -293.52494) (xy 43.668962 -293.52494)
			(xy 43.672922 -293.475886) (xy 43.684699 -293.428102) (xy 43.70399 -293.382826) (xy 43.730293 -293.34123)
			(xy 43.762928 -293.304393) (xy 43.801049 -293.273268) (xy 43.84367 -293.248661) (xy 43.889686 -293.231209)
			(xy 43.937905 -293.221365) (xy 43.98708 -293.219384) (xy 44.035935 -293.225316) (xy 44.083206 -293.239008)
			(xy 44.127668 -293.260106) (xy 44.168171 -293.288062) (xy 44.203664 -293.322154) (xy 44.233229 -293.361498)
			(xy 44.2561 -293.405075) (xy 44.271684 -293.451756) (xy 44.279579 -293.500333) (xy 44.280074 -293.52494)
			(xy 45.569136 -293.52494) (xy 45.573096 -293.475886) (xy 45.584873 -293.428102) (xy 45.604164 -293.382826)
			(xy 45.630467 -293.34123) (xy 45.663102 -293.304393) (xy 45.701223 -293.273268) (xy 45.743844 -293.248661)
			(xy 45.78986 -293.231209) (xy 45.838079 -293.221365) (xy 45.887254 -293.219384) (xy 45.936109 -293.225316)
			(xy 45.98338 -293.239008) (xy 46.027842 -293.260106) (xy 46.068345 -293.288062) (xy 46.103838 -293.322154)
			(xy 46.133403 -293.361498) (xy 46.156274 -293.405075) (xy 46.171858 -293.451756) (xy 46.179753 -293.500333)
			(xy 46.180248 -293.52494) (xy 47.469056 -293.52494) (xy 47.473016 -293.475886) (xy 47.484793 -293.428102)
			(xy 47.504084 -293.382826) (xy 47.530387 -293.34123) (xy 47.563022 -293.304393) (xy 47.601143 -293.273268)
			(xy 47.643764 -293.248661) (xy 47.68978 -293.231209) (xy 47.737999 -293.221365) (xy 47.787174 -293.219384)
			(xy 47.836029 -293.225316) (xy 47.8833 -293.239008) (xy 47.927762 -293.260106) (xy 47.968265 -293.288062)
			(xy 48.003758 -293.322154) (xy 48.033323 -293.361498) (xy 48.056194 -293.405075) (xy 48.071778 -293.451756)
			(xy 48.079673 -293.500333) (xy 48.080168 -293.52494) (xy 48.079673 -293.549547) (xy 48.071778 -293.598124)
			(xy 48.056194 -293.644805) (xy 48.033323 -293.688382) (xy 48.003758 -293.727726) (xy 47.968265 -293.761818)
			(xy 47.927762 -293.789774) (xy 47.8833 -293.810872) (xy 47.836029 -293.824564) (xy 47.787174 -293.830496)
			(xy 47.737999 -293.828515) (xy 47.68978 -293.818671) (xy 47.643764 -293.801219) (xy 47.601143 -293.776612)
			(xy 47.563022 -293.745487) (xy 47.530387 -293.70865) (xy 47.504084 -293.667054) (xy 47.484793 -293.621778)
			(xy 47.473016 -293.573994) (xy 47.469056 -293.52494) (xy 46.180248 -293.52494) (xy 46.179753 -293.549547)
			(xy 46.171858 -293.598124) (xy 46.156274 -293.644805) (xy 46.133403 -293.688382) (xy 46.103838 -293.727726)
			(xy 46.068345 -293.761818) (xy 46.027842 -293.789774) (xy 45.98338 -293.810872) (xy 45.936109 -293.824564)
			(xy 45.887254 -293.830496) (xy 45.838079 -293.828515) (xy 45.78986 -293.818671) (xy 45.743844 -293.801219)
			(xy 45.701223 -293.776612) (xy 45.663102 -293.745487) (xy 45.630467 -293.70865) (xy 45.604164 -293.667054)
			(xy 45.584873 -293.621778) (xy 45.573096 -293.573994) (xy 45.569136 -293.52494) (xy 44.280074 -293.52494)
			(xy 44.279579 -293.549547) (xy 44.271684 -293.598124) (xy 44.2561 -293.644805) (xy 44.233229 -293.688382)
			(xy 44.203664 -293.727726) (xy 44.168171 -293.761818) (xy 44.127668 -293.789774) (xy 44.083206 -293.810872)
			(xy 44.035935 -293.824564) (xy 43.98708 -293.830496) (xy 43.937905 -293.828515) (xy 43.889686 -293.818671)
			(xy 43.84367 -293.801219) (xy 43.801049 -293.776612) (xy 43.762928 -293.745487) (xy 43.730293 -293.70865)
			(xy 43.70399 -293.667054) (xy 43.684699 -293.621778) (xy 43.672922 -293.573994) (xy 43.668962 -293.52494)
			(xy 43.380914 -293.52494) (xy 43.380416 -293.551589) (xy 43.372473 -293.604293) (xy 43.356763 -293.655223)
			(xy 43.333637 -293.703244) (xy 43.303613 -293.747281) (xy 43.267361 -293.786352) (xy 43.22569 -293.819583)
			(xy 43.179532 -293.846232) (xy 43.129918 -293.865704) (xy 43.077956 -293.877564) (xy 43.024806 -293.881548)
			(xy 42.971656 -293.877564) (xy 42.919694 -293.865704) (xy 42.87008 -293.846232) (xy 42.823922 -293.819583)
			(xy 42.782251 -293.786352) (xy 42.745999 -293.747281) (xy 42.715975 -293.703244) (xy 42.692849 -293.655223)
			(xy 42.677139 -293.604293) (xy 42.669196 -293.551589) (xy 42.379327 -293.551589) (xy 42.371764 -293.598124)
			(xy 42.35618 -293.644805) (xy 42.333309 -293.688382) (xy 42.303744 -293.727726) (xy 42.268251 -293.761818)
			(xy 42.227748 -293.789774) (xy 42.183286 -293.810872) (xy 42.136015 -293.824564) (xy 42.08716 -293.830496)
			(xy 42.037985 -293.828515) (xy 41.989766 -293.818671) (xy 41.94375 -293.801219) (xy 41.901129 -293.776612)
			(xy 41.863008 -293.745487) (xy 41.830373 -293.70865) (xy 41.80407 -293.667054) (xy 41.784779 -293.621778)
			(xy 41.773002 -293.573994) (xy 41.769042 -293.52494) (xy 41.430194 -293.52494) (xy 41.429699 -293.549547)
			(xy 41.421804 -293.598124) (xy 41.40622 -293.644805) (xy 41.383349 -293.688382) (xy 41.353784 -293.727726)
			(xy 41.318291 -293.761818) (xy 41.277788 -293.789774) (xy 41.233326 -293.810872) (xy 41.186055 -293.824564)
			(xy 41.1372 -293.830496) (xy 41.088025 -293.828515) (xy 41.039806 -293.818671) (xy 40.99379 -293.801219)
			(xy 40.951169 -293.776612) (xy 40.913048 -293.745487) (xy 40.880413 -293.70865) (xy 40.85411 -293.667054)
			(xy 40.834819 -293.621778) (xy 40.823042 -293.573994) (xy 40.819082 -293.52494) (xy 40.480234 -293.52494)
			(xy 40.479739 -293.549547) (xy 40.471844 -293.598124) (xy 40.45626 -293.644805) (xy 40.433389 -293.688382)
			(xy 40.403824 -293.727726) (xy 40.368331 -293.761818) (xy 40.327828 -293.789774) (xy 40.283366 -293.810872)
			(xy 40.236095 -293.824564) (xy 40.18724 -293.830496) (xy 40.138065 -293.828515) (xy 40.089846 -293.818671)
			(xy 40.04383 -293.801219) (xy 40.001209 -293.776612) (xy 39.963088 -293.745487) (xy 39.930453 -293.70865)
			(xy 39.90415 -293.667054) (xy 39.884859 -293.621778) (xy 39.873082 -293.573994) (xy 39.869122 -293.52494)
			(xy 39.530274 -293.52494) (xy 39.529779 -293.549547) (xy 39.521884 -293.598124) (xy 39.5063 -293.644805)
			(xy 39.483429 -293.688382) (xy 39.453864 -293.727726) (xy 39.418371 -293.761818) (xy 39.377868 -293.789774)
			(xy 39.333406 -293.810872) (xy 39.286135 -293.824564) (xy 39.23728 -293.830496) (xy 39.188105 -293.828515)
			(xy 39.139886 -293.818671) (xy 39.09387 -293.801219) (xy 39.051249 -293.776612) (xy 39.013128 -293.745487)
			(xy 38.980493 -293.70865) (xy 38.95419 -293.667054) (xy 38.934899 -293.621778) (xy 38.923122 -293.573994)
			(xy 38.919162 -293.52494) (xy 38.580314 -293.52494) (xy 38.579819 -293.549547) (xy 38.571924 -293.598124)
			(xy 38.55634 -293.644805) (xy 38.533469 -293.688382) (xy 38.503904 -293.727726) (xy 38.468411 -293.761818)
			(xy 38.427908 -293.789774) (xy 38.383446 -293.810872) (xy 38.336175 -293.824564) (xy 38.28732 -293.830496)
			(xy 38.238145 -293.828515) (xy 38.189926 -293.818671) (xy 38.14391 -293.801219) (xy 38.101289 -293.776612)
			(xy 38.063168 -293.745487) (xy 38.030533 -293.70865) (xy 38.00423 -293.667054) (xy 37.984939 -293.621778)
			(xy 37.973162 -293.573994) (xy 37.969202 -293.52494) (xy 34.383635 -293.52494) (xy 34.375859 -293.577776)
			(xy 34.359791 -293.631183) (xy 34.336119 -293.68168) (xy 34.305346 -293.728193) (xy 34.268129 -293.76973)
			(xy 34.225261 -293.805405) (xy 34.177655 -293.834459) (xy 34.126326 -293.856271) (xy 34.072369 -293.870377)
			(xy 34.016932 -293.876477) (xy 33.961198 -293.87444) (xy 33.906355 -293.86431) (xy 33.853571 -293.846303)
			(xy 33.803971 -293.820802) (xy 33.758613 -293.788351) (xy 33.718464 -293.749642) (xy 33.684378 -293.705499)
			(xy 33.657082 -293.656864) (xy 33.637159 -293.604773) (xy 33.625033 -293.550336) (xy 33.620962 -293.494714)
			(xy 33.498028 -293.494714) (xy 33.497519 -293.5226) (xy 33.489399 -293.577776) (xy 33.473331 -293.631183)
			(xy 33.449659 -293.68168) (xy 33.418886 -293.728193) (xy 33.381669 -293.76973) (xy 33.338801 -293.805405)
			(xy 33.291195 -293.834459) (xy 33.239866 -293.856271) (xy 33.185909 -293.870377) (xy 33.130472 -293.876477)
			(xy 33.074738 -293.87444) (xy 33.019895 -293.86431) (xy 32.967111 -293.846303) (xy 32.917511 -293.820802)
			(xy 32.872153 -293.788351) (xy 32.832004 -293.749642) (xy 32.797918 -293.705499) (xy 32.770622 -293.656864)
			(xy 32.750699 -293.604773) (xy 32.738573 -293.550336) (xy 32.734502 -293.494714) (xy 32.101028 -293.494714)
			(xy 32.100542 -293.521965) (xy 32.092786 -293.575913) (xy 32.077431 -293.628208) (xy 32.054789 -293.677785)
			(xy 32.025323 -293.723635) (xy 31.989632 -293.764826) (xy 31.948441 -293.800517) (xy 31.902591 -293.829983)
			(xy 31.853014 -293.852625) (xy 31.800719 -293.86798) (xy 31.746771 -293.875736) (xy 31.692269 -293.875736)
			(xy 31.638321 -293.86798) (xy 31.586026 -293.852625) (xy 31.536449 -293.829983) (xy 31.490599 -293.800517)
			(xy 31.449408 -293.764826) (xy 31.413717 -293.723635) (xy 31.384251 -293.677785) (xy 31.361609 -293.628208)
			(xy 31.346254 -293.575913) (xy 31.338498 -293.521965) (xy 31.338012 -293.494714) (xy 1.992122 -293.494714)
			(xy 2.689352 -294.191944) (xy 2.68986 -294.192452) (xy 2.697241 -294.199033) (xy 2.715541 -294.206481)
			(xy 2.72542 -294.20693) (xy 18.758662 -294.20693) (xy 18.758916 -294.20693) (xy 18.76387 -294.20705)
			(xy 18.773591 -294.208969) (xy 18.77822 -294.21074) (xy 18.804636 -294.221916)
		)
		(stroke
			(width 0)
			(type solid)
		)
		(fill yes)
		(layer "In9.Cu")
		(net "P1V25_PEX0")
	)
	(gr_poly
		(pts
			(xy 423.904918 -311.6326) (xy 423.914795 -311.63214) (xy 423.933094 -311.624697) (xy 423.940478 -311.618122)
			(xy 423.940732 -311.617868) (xy 423.996104 -311.562496) (xy 424.004252 -311.553256) (xy 424.011549 -311.529768)
			(xy 424.010074 -311.517538) (xy 423.992548 -311.422796) (xy 423.977308 -311.403238) (xy 423.965878 -311.398158)
			(xy 423.941625 -311.386667) (xy 423.896926 -311.35697) (xy 423.857681 -311.320369) (xy 423.824944 -311.277847)
			(xy 423.799594 -311.230547) (xy 423.782314 -311.179741) (xy 423.773568 -311.126794) (xy 423.773092 -311.099962)
			(xy 423.773599 -311.074276) (xy 423.78164 -311.023537) (xy 423.797519 -310.97468) (xy 423.820845 -310.928909)
			(xy 423.851043 -310.887349) (xy 423.887371 -310.851025) (xy 423.928933 -310.820831) (xy 423.974706 -310.797509)
			(xy 424.023564 -310.781634) (xy 424.074304 -310.773596) (xy 424.09999 -310.773064) (xy 424.126815 -310.773611)
			(xy 424.179744 -310.78238) (xy 424.230534 -310.799667) (xy 424.277821 -310.825011) (xy 424.32034 -310.857731)
			(xy 424.356949 -310.89695) (xy 424.386669 -310.941617) (xy 424.398186 -310.96585) (xy 424.403266 -310.97728)
			(xy 424.422824 -310.99252) (xy 424.517566 -311.010046) (xy 424.529797 -311.011541) (xy 424.553285 -311.004231)
			(xy 424.562524 -310.996076) (xy 424.962574 -310.596026) (xy 424.970941 -310.586692) (xy 424.978126 -310.562708)
			(xy 424.97629 -310.550306) (xy 424.960034 -310.467502) (xy 424.956958 -310.455547) (xy 424.941554 -310.436309)
			(xy 424.93057 -310.430672) (xy 424.930316 -310.430672) (xy 424.90706 -310.420213) (xy 424.864117 -310.392722)
			(xy 424.826338 -310.358478) (xy 424.794774 -310.318434) (xy 424.770302 -310.273701) (xy 424.753602 -310.225524)
			(xy 424.745139 -310.175243) (xy 424.744642 -310.149748) (xy 424.745127 -310.125311) (xy 424.752917 -310.077063)
			(xy 424.768291 -310.03067) (xy 424.790855 -309.987317) (xy 424.820035 -309.94811) (xy 424.855086 -309.91405)
			(xy 424.895113 -309.886006) (xy 424.939094 -309.864693) (xy 424.985908 -309.850655) (xy 425.010072 -309.84698)
			(xy 425.01911 -309.845398) (xy 425.035286 -309.836764) (xy 425.047397 -309.822998) (xy 425.053901 -309.805854)
			(xy 425.054268 -309.796688) (xy 425.054268 -309.61584) (xy 425.059462 -309.610161) (xy 425.066447 -309.596457)
			(xy 425.067984 -309.588916) (xy 425.067984 -309.588408) (xy 425.068746 -309.58028) (xy 425.068746 -309.576216)
			(xy 425.040806 -309.54599) (xy 425.037792 -309.54288) (xy 425.030897 -309.537641) (xy 425.02709 -309.535576)
			(xy 425.004992 -309.523892) (xy 424.996864 -309.522368) (xy 424.971718 -309.517709) (xy 424.92318 -309.501614)
			(xy 424.877739 -309.478158) (xy 424.836505 -309.447913) (xy 424.800482 -309.411617) (xy 424.770549 -309.370155)
			(xy 424.747436 -309.324539) (xy 424.731708 -309.275881) (xy 424.723746 -309.225367) (xy 424.723747 -309.174229)
			(xy 424.731709 -309.123715) (xy 424.747438 -309.075057) (xy 424.770551 -309.029441) (xy 424.800484 -308.98798)
			(xy 424.836508 -308.951685) (xy 424.877743 -308.92144) (xy 424.923184 -308.897985) (xy 424.971722 -308.88189)
			(xy 424.996864 -308.877208) (xy 425.004992 -308.875684) (xy 425.02709 -308.864) (xy 425.030978 -308.861894)
			(xy 425.038008 -308.856532) (xy 425.04106 -308.853332) (xy 425.055284 -308.837584) (xy 425.061439 -308.830381)
			(xy 425.068363 -308.81276) (xy 425.068746 -308.803294) (xy 425.068746 -308.62397) (xy 425.068258 -308.614524)
			(xy 425.061353 -308.596934) (xy 425.055284 -308.58968) (xy 425.028868 -308.560978) (xy 425.013628 -308.553104)
			(xy 425.004992 -308.551834) (xy 424.981165 -308.547827) (xy 424.935092 -308.533285) (xy 424.891883 -308.511669)
			(xy 424.852617 -308.483518) (xy 424.818274 -308.449535) (xy 424.789711 -308.410569) (xy 424.767641 -308.36759)
			(xy 424.752614 -308.321672) (xy 424.745005 -308.273961) (xy 424.745004 -308.225647) (xy 424.752612 -308.177936)
			(xy 424.767638 -308.132017) (xy 424.789707 -308.089038) (xy 424.818269 -308.050071) (xy 424.852611 -308.016087)
			(xy 424.891876 -307.987935) (xy 424.935084 -307.966318) (xy 424.981157 -307.951775) (xy 425.004992 -307.947822)
			(xy 425.013628 -307.946552) (xy 425.028868 -307.938678) (xy 425.055284 -307.909976) (xy 425.061438 -307.902773)
			(xy 425.068358 -307.885152) (xy 425.068746 -307.875686) (xy 425.068746 -307.696362) (xy 425.068257 -307.686917)
			(xy 425.06135 -307.669329) (xy 425.055284 -307.662072) (xy 425.04106 -307.646324) (xy 425.037987 -307.643148)
			(xy 425.030961 -307.637789) (xy 425.02709 -307.635656) (xy 425.004992 -307.623972) (xy 424.996864 -307.622448)
			(xy 424.97172 -307.617789) (xy 424.923185 -307.601694) (xy 424.877747 -307.578239) (xy 424.836515 -307.547996)
			(xy 424.800495 -307.511702) (xy 424.770564 -307.470242) (xy 424.747453 -307.424629) (xy 424.731726 -307.375973)
			(xy 424.723766 -307.325462) (xy 424.723767 -307.274328) (xy 424.731729 -307.223817) (xy 424.747457 -307.175162)
			(xy 424.77057 -307.129549) (xy 424.800502 -307.08809) (xy 424.836523 -307.051797) (xy 424.877756 -307.021555)
			(xy 424.923194 -306.998102) (xy 424.97173 -306.982008) (xy 424.996864 -306.977288) (xy 425.004992 -306.975764)
			(xy 425.02709 -306.96408) (xy 425.030978 -306.961973) (xy 425.038006 -306.956609) (xy 425.04106 -306.953412)
			(xy 425.055284 -306.937664) (xy 425.061436 -306.93046) (xy 425.068352 -306.912839) (xy 425.068746 -306.903374)
			(xy 425.068746 -306.72405) (xy 425.068255 -306.714606) (xy 425.061344 -306.69702) (xy 425.055284 -306.68976)
			(xy 425.028868 -306.661058) (xy 425.013628 -306.653184) (xy 425.004992 -306.651914) (xy 424.981167 -306.647907)
			(xy 424.935096 -306.633366) (xy 424.89189 -306.61175) (xy 424.852628 -306.583601) (xy 424.818287 -306.54962)
			(xy 424.789727 -306.510656) (xy 424.767658 -306.46768) (xy 424.752632 -306.421765) (xy 424.745024 -306.374057)
			(xy 424.745024 -306.325746) (xy 424.752632 -306.278037) (xy 424.767657 -306.232122) (xy 424.789725 -306.189146)
			(xy 424.818286 -306.150181) (xy 424.852626 -306.1162) (xy 424.891888 -306.088051) (xy 424.935094 -306.066435)
			(xy 424.981164 -306.051893) (xy 425.004992 -306.047902) (xy 425.013628 -306.046632) (xy 425.028868 -306.038758)
			(xy 425.055284 -306.010056) (xy 425.061435 -306.002852) (xy 425.068348 -305.985231) (xy 425.068746 -305.975766)
			(xy 425.068746 -305.796442) (xy 425.068253 -305.786998) (xy 425.061341 -305.769415) (xy 425.055284 -305.762152)
			(xy 425.04106 -305.746404) (xy 425.03799 -305.743224) (xy 425.030967 -305.737858) (xy 425.02709 -305.735736)
			(xy 425.004992 -305.724052) (xy 424.996864 -305.722528) (xy 424.971714 -305.717869) (xy 424.923166 -305.701772)
			(xy 424.877717 -305.678313) (xy 424.836474 -305.648064) (xy 424.800443 -305.611763) (xy 424.770504 -305.570295)
			(xy 424.747385 -305.524671) (xy 424.731652 -305.476004) (xy 424.723688 -305.425481) (xy 424.723687 -305.374334)
			(xy 424.731649 -305.323811) (xy 424.747379 -305.275144) (xy 424.770495 -305.229519) (xy 424.800433 -305.188049)
			(xy 424.836462 -305.151746) (xy 424.877703 -305.121495) (xy 424.923152 -305.098034) (xy 424.971699 -305.081935)
			(xy 424.996864 -305.077368) (xy 425.004992 -305.075844) (xy 425.02709 -305.06416) (xy 425.030977 -305.062053)
			(xy 425.038004 -305.056687) (xy 425.04106 -305.053492) (xy 425.055284 -305.037744) (xy 425.061433 -305.030539)
			(xy 425.068342 -305.012918) (xy 425.068746 -305.003454) (xy 425.068746 -304.823876) (xy 425.068259 -304.81443)
			(xy 425.061355 -304.796838) (xy 425.055284 -304.789586) (xy 425.028868 -304.760884) (xy 425.013628 -304.75301)
			(xy 425.004992 -304.75174) (xy 424.981165 -304.747733) (xy 424.93509 -304.733191) (xy 424.89188 -304.711574)
			(xy 424.852614 -304.683423) (xy 424.81827 -304.64944) (xy 424.789707 -304.610473) (xy 424.767636 -304.567493)
			(xy 424.752608 -304.521575) (xy 424.744999 -304.473863) (xy 424.744998 -304.425547) (xy 424.752606 -304.377835)
			(xy 424.767632 -304.331916) (xy 424.789701 -304.288936) (xy 424.818264 -304.249968) (xy 424.852606 -304.215983)
			(xy 424.891872 -304.187831) (xy 424.935081 -304.166213) (xy 424.981155 -304.151669) (xy 425.004992 -304.147728)
			(xy 425.013628 -304.146458) (xy 425.028868 -304.138584) (xy 425.055284 -304.109882) (xy 425.061439 -304.102679)
			(xy 425.068362 -304.085058) (xy 425.068746 -304.075592) (xy 425.068746 -290.356798) (xy 425.068574 -290.35079)
			(xy 425.065741 -290.339112) (xy 425.063158 -290.333684) (xy 425.061317 -290.330211) (xy 425.056721 -290.323834)
			(xy 425.054014 -290.320984) (xy 424.769788 -290.036758) (xy 424.766486 -290.034472) (xy 424.761152 -290.029646)
			(xy 424.751366 -290.023935) (xy 424.728957 -290.020773) (xy 424.717972 -290.02355) (xy 424.707812 -290.028122)
			(xy 424.698922 -290.031678) (xy 424.669289 -290.042829) (xy 424.607132 -290.054845) (xy 424.575478 -290.055554)
			(xy 424.57497 -290.055554) (xy 424.548983 -290.055042) (xy 424.497649 -290.046908) (xy 424.44822 -290.030845)
			(xy 424.401911 -290.007248) (xy 424.359863 -289.976699) (xy 424.323111 -289.939949) (xy 424.29256 -289.897902)
			(xy 424.268961 -289.851595) (xy 424.252895 -289.802166) (xy 424.244759 -289.750833) (xy 424.244262 -289.724846)
			(xy 424.244262 -289.724338) (xy 424.244626 -289.702051) (xy 424.250618 -289.657883) (xy 424.262499 -289.614923)
			(xy 424.270932 -289.59429) (xy 424.271948 -289.592004) (xy 424.274996 -289.582606) (xy 424.277028 -289.571938)
			(xy 424.277824 -289.562403) (xy 424.273136 -289.543867) (xy 424.267884 -289.53587) (xy 424.26255 -289.52952)
			(xy 423.819828 -289.086798) (xy 423.816526 -289.084512) (xy 423.811192 -289.079686) (xy 423.801407 -289.073963)
			(xy 423.778992 -289.070782) (xy 423.768012 -289.07359) (xy 423.757852 -289.078162) (xy 423.748962 -289.081718)
			(xy 423.71933 -289.092874) (xy 423.657173 -289.104901) (xy 423.625518 -289.105594) (xy 423.62501 -289.105594)
			(xy 423.600046 -289.105133) (xy 423.550687 -289.097618) (xy 423.503017 -289.082773) (xy 423.458119 -289.060935)
			(xy 423.417011 -289.0326) (xy 423.380626 -288.99841) (xy 423.349792 -288.959142) (xy 423.325206 -288.915686)
			(xy 423.307429 -288.869031) (xy 423.301668 -288.844736) (xy 423.30116 -288.842196) (xy 423.300906 -288.841434)
			(xy 423.300906 -288.840418) (xy 423.299636 -288.834576) (xy 423.29608 -288.828226) (xy 423.294139 -288.824883)
			(xy 423.289422 -288.818761) (xy 423.286682 -288.816034) (xy 423.283888 -288.813494) (xy 423.263314 -288.793936)
			(xy 423.260107 -288.791548) (xy 423.253091 -288.787711) (xy 423.249344 -288.786316) (xy 423.23639 -288.782506)
			(xy 423.236136 -288.782506) (xy 423.234866 -288.782252) (xy 423.232072 -288.781998) (xy 423.208196 -288.778696)
			(xy 423.17797 -288.773616) (xy 423.15638 -288.769298) (xy 423.142918 -288.769552) (xy 423.129964 -288.772092)
			(xy 423.129202 -288.772092) (xy 423.11193 -288.775394) (xy 423.111422 -288.775394) (xy 423.107358 -288.776156)
			(xy 423.062908 -288.782506) (xy 423.062146 -288.782506) (xy 423.05732 -288.783522) (xy 423.05224 -288.784538)
			(xy 423.04716 -288.786824) (xy 423.037 -288.79292) (xy 423.029126 -288.80054) (xy 423.028618 -288.801048)
			(xy 423.013378 -288.815526) (xy 423.012108 -288.81705) (xy 423.009568 -288.819844) (xy 423.003726 -288.827972)
			(xy 423.000678 -288.833814) (xy 422.999408 -288.839148) (xy 422.994007 -288.863855) (xy 422.976713 -288.911377)
			(xy 422.952391 -288.955716) (xy 422.921606 -288.995838) (xy 422.885076 -289.03081) (xy 422.843651 -289.059817)
			(xy 422.798295 -289.082185) (xy 422.750065 -289.097392) (xy 422.700082 -289.105085) (xy 422.674796 -289.105594)
			(xy 422.661146 -289.105497) (xy 422.633933 -289.103338) (xy 422.62044 -289.101276) (xy 422.608502 -289.099244)
			(xy 422.585642 -289.106356) (xy 422.518332 -289.170618) (xy 422.510691 -289.17863) (xy 422.502502 -289.199173)
			(xy 422.502584 -289.210242) (xy 422.502838 -289.213544) (xy 422.503092 -289.215068) (xy 422.505124 -289.249612)
			(xy 422.505124 -289.25012) (xy 422.504955 -289.263142) (xy 422.502664 -289.289085) (xy 422.500552 -289.301936)
			(xy 422.49979 -289.306254) (xy 422.49979 -289.306508) (xy 422.497504 -289.318954) (xy 422.50487 -289.342576)
			(xy 422.572434 -289.41014) (xy 422.579862 -289.416908) (xy 422.598459 -289.424483) (xy 422.608502 -289.424872)
			(xy 422.618408 -289.424872) (xy 422.622726 -289.42411) (xy 422.635703 -289.421986) (xy 422.661901 -289.419696)
			(xy 422.67505 -289.419538) (xy 422.699865 -289.420028) (xy 422.748841 -289.428065) (xy 422.795872 -289.443918)
			(xy 422.839718 -289.467172) (xy 422.879226 -289.497212) (xy 422.913353 -289.533247) (xy 422.941201 -289.574329)
			(xy 422.962037 -289.619375) (xy 422.975311 -289.667198) (xy 422.980673 -289.716538) (xy 422.977984 -289.766096)
			(xy 422.967312 -289.814566) (xy 422.94894 -289.860672) (xy 422.923352 -289.903198) (xy 422.891221 -289.941024)
			(xy 422.853394 -289.973154) (xy 422.810868 -289.998742) (xy 422.764762 -290.017113) (xy 422.716292 -290.027784)
			(xy 422.666734 -290.030473) (xy 422.617394 -290.02511) (xy 422.569571 -290.011835) (xy 422.524526 -289.990999)
			(xy 422.483444 -289.96315) (xy 422.447409 -289.929023) (xy 422.41737 -289.889515) (xy 422.394117 -289.845668)
			(xy 422.378264 -289.798637) (xy 422.370227 -289.749661) (xy 422.369742 -289.724846) (xy 422.369899 -289.71176)
			(xy 422.37219 -289.685689) (xy 422.374314 -289.672776) (xy 422.375076 -289.668458) (xy 422.375076 -289.668204)
			(xy 422.377362 -289.655758) (xy 422.369996 -289.632136) (xy 422.302432 -289.564572) (xy 422.295008 -289.557792)
			(xy 422.276411 -289.550191) (xy 422.266364 -289.54984) (xy 422.256458 -289.54984) (xy 422.25214 -289.550602)
			(xy 422.239163 -289.552725) (xy 422.212965 -289.555012) (xy 422.199816 -289.555174) (xy 422.185761 -289.554966)
			(xy 422.157777 -289.552296) (xy 422.143936 -289.54984) (xy 422.13149 -289.547554) (xy 422.10736 -289.55492)
			(xy 422.03878 -289.6235) (xy 422.030634 -289.63274) (xy 422.023337 -289.656228) (xy 422.02481 -289.668458)
			(xy 422.02481 -289.668712) (xy 422.025572 -289.67303) (xy 422.027676 -289.685882) (xy 422.029964 -289.711825)
			(xy 422.030144 -289.724846) (xy 422.029654 -289.74967) (xy 422.021615 -289.798662) (xy 422.005756 -289.845707)
			(xy 421.982494 -289.889568) (xy 421.952443 -289.929087) (xy 421.916394 -289.963225) (xy 421.875298 -289.99108)
			(xy 421.830236 -290.01192) (xy 421.782397 -290.025195) (xy 421.73304 -290.030556) (xy 421.683466 -290.027861)
			(xy 421.634981 -290.017182) (xy 421.588862 -289.998799) (xy 421.546325 -289.973198) (xy 421.50849 -289.941052)
			(xy 421.476354 -289.903208) (xy 421.450764 -289.860664) (xy 421.432394 -289.814541) (xy 421.421728 -289.766053)
			(xy 421.419046 -289.716478) (xy 421.42442 -289.667122) (xy 421.437708 -289.619287) (xy 421.45856 -289.574231)
			(xy 421.486427 -289.533142) (xy 421.520574 -289.497102) (xy 421.560101 -289.467062) (xy 421.603968 -289.443812)
			(xy 421.651018 -289.427965) (xy 421.700012 -289.419939) (xy 421.724836 -289.419538) (xy 421.738891 -289.419743)
			(xy 421.766877 -289.42241) (xy 421.780716 -289.424872) (xy 421.793162 -289.427158) (xy 421.817292 -289.419792)
			(xy 421.885872 -289.351212) (xy 421.894027 -289.341975) (xy 421.901336 -289.318484) (xy 421.899842 -289.306254)
			(xy 421.899842 -289.306) (xy 421.89908 -289.301682) (xy 421.896984 -289.288893) (xy 421.894696 -289.263078)
			(xy 421.894508 -289.25012) (xy 421.894508 -289.249612) (xy 421.89654 -289.215068) (xy 421.896794 -289.213544)
			(xy 421.897048 -289.210242) (xy 421.897117 -289.19917) (xy 421.888958 -289.178613) (xy 421.8813 -289.170618)
			(xy 421.81399 -289.106356) (xy 421.79113 -289.099244) (xy 421.779192 -289.101276) (xy 421.765699 -289.103344)
			(xy 421.738486 -289.105508) (xy 421.724836 -289.105594) (xy 421.698845 -289.105114) (xy 421.647503 -289.096987)
			(xy 421.598065 -289.080927) (xy 421.551748 -289.057331) (xy 421.509692 -289.02678) (xy 421.472935 -288.990024)
			(xy 421.44238 -288.947971) (xy 421.418781 -288.901656) (xy 421.402718 -288.852218) (xy 421.394588 -288.800877)
			(xy 421.394128 -288.774886) (xy 421.394638 -288.748913) (xy 421.402762 -288.697607) (xy 421.418809 -288.648202)
			(xy 421.442384 -288.601914) (xy 421.472907 -288.559882) (xy 421.509627 -288.52314) (xy 421.55164 -288.492591)
			(xy 421.597914 -288.468988) (xy 421.647308 -288.45291) (xy 421.69861 -288.444754) (xy 421.724582 -288.444178)
			(xy 421.72509 -288.444178) (xy 421.73271 -288.444432) (xy 421.741092 -288.444432) (xy 421.750727 -288.443971)
			(xy 421.768619 -288.436799) (xy 421.77589 -288.430462) (xy 421.782748 -288.42335) (xy 421.831008 -288.345372)
			(xy 421.835457 -288.337482) (xy 421.839021 -288.319735) (xy 421.836178 -288.301858) (xy 421.832024 -288.29381)
			(xy 421.825928 -288.282634) (xy 421.825928 -288.282126) (xy 421.823388 -288.277554) (xy 421.819578 -288.270696)
			(xy 421.814752 -288.261552) (xy 421.809418 -288.250884) (xy 421.786558 -288.200846) (xy 421.78351 -288.19348)
			(xy 421.7797 -288.188908) (xy 421.770048 -288.179764) (xy 421.769032 -288.179256) (xy 421.768524 -288.178748)
			(xy 421.756332 -288.17062) (xy 421.74795 -288.165286) (xy 421.74287 -288.163) (xy 421.741854 -288.162492)
			(xy 421.719756 -288.155634) (xy 421.712898 -288.15538) (xy 421.687539 -288.154003) (xy 421.637665 -288.144438)
			(xy 421.589839 -288.127361) (xy 421.545186 -288.103173) (xy 421.504755 -288.072443) (xy 421.469498 -288.035893)
			(xy 421.440243 -287.994383) (xy 421.417678 -287.948889) (xy 421.402333 -287.900479) (xy 421.394569 -287.850293)
			(xy 421.394569 -287.799509) (xy 421.402332 -287.749323) (xy 421.417677 -287.700913) (xy 421.440242 -287.655418)
			(xy 421.469497 -287.613908) (xy 421.504754 -287.577358) (xy 421.545184 -287.546628) (xy 421.589837 -287.52244)
			(xy 421.637663 -287.505362) (xy 421.687538 -287.495797) (xy 421.712898 -287.494472) (xy 421.719756 -287.494218)
			(xy 421.742362 -287.487106) (xy 421.74287 -287.486852) (xy 421.752522 -287.481772) (xy 421.768524 -287.471104)
			(xy 421.769032 -287.47085) (xy 421.770048 -287.469834) (xy 421.773858 -287.46704) (xy 421.77589 -287.465008)
			(xy 421.7797 -287.460944) (xy 421.779954 -287.46069) (xy 421.786304 -287.450784) (xy 421.787066 -287.448244)
			(xy 421.794432 -287.431226) (xy 421.795956 -287.42767) (xy 421.795956 -287.427416) (xy 421.801798 -287.415224)
			(xy 421.801798 -287.414716) (xy 421.80383 -287.410906) (xy 421.80383 -287.410398) (xy 421.804338 -287.409636)
			(xy 421.804846 -287.408874) (xy 421.804846 -287.408366) (xy 421.8051 -287.407858) (xy 421.805608 -287.407096)
			(xy 421.822372 -287.373822) (xy 421.82288 -287.372806) (xy 421.823896 -287.370774) (xy 421.824658 -287.369504)
			(xy 421.828976 -287.360614) (xy 421.830246 -287.356042) (xy 421.832024 -287.342834) (xy 421.832024 -287.320736)
			(xy 421.832024 -287.31972) (xy 421.83169 -287.313171) (xy 421.828087 -287.300566) (xy 421.824912 -287.294828)
			(xy 421.804338 -287.262062) (xy 421.804338 -287.261554) (xy 421.784018 -287.229042) (xy 421.776842 -287.218867)
			(xy 421.755275 -287.20648) (xy 421.74287 -287.20542) (xy 421.73271 -287.20542) (xy 421.72509 -287.205674)
			(xy 421.724582 -287.205674) (xy 421.698609 -287.205148) (xy 421.647306 -287.196992) (xy 421.597909 -287.180913)
			(xy 421.551635 -287.157308) (xy 421.509621 -287.126757) (xy 421.472901 -287.090013) (xy 421.442378 -287.047979)
			(xy 421.418804 -287.001689) (xy 421.402757 -286.952282) (xy 421.394635 -286.900974) (xy 421.394635 -286.849026)
			(xy 421.402757 -286.797718) (xy 421.418804 -286.748311) (xy 421.442378 -286.702021) (xy 421.472901 -286.659987)
			(xy 421.509621 -286.623242) (xy 421.551635 -286.592692) (xy 421.59791 -286.569087) (xy 421.647306 -286.553008)
			(xy 421.698609 -286.544852) (xy 421.724582 -286.544258) (xy 421.72509 -286.544258) (xy 421.736774 -286.544512)
			(xy 421.742362 -286.544512) (xy 421.754726 -286.543442) (xy 421.776352 -286.531353) (xy 421.783764 -286.521398)
			(xy 421.824658 -286.455358) (xy 421.82796 -286.448754) (xy 421.829941 -286.443974) (xy 421.832115 -286.43386)
			(xy 421.832278 -286.428688) (xy 421.832278 -286.40913) (xy 421.832024 -286.404304) (xy 421.831516 -286.399732)
			(xy 421.830764 -286.395144) (xy 421.82783 -286.386324) (xy 421.825674 -286.382206) (xy 421.81772 -286.367261)
			(xy 421.80273 -286.336902) (xy 421.795702 -286.3215) (xy 421.795702 -286.321246) (xy 421.786812 -286.300672)
			(xy 421.78478 -286.296354) (xy 421.784272 -286.295084) (xy 421.783256 -286.293052) (xy 421.779192 -286.288226)
			(xy 421.769286 -286.279082) (xy 421.75303 -286.26816) (xy 421.74668 -286.263842) (xy 421.719756 -286.25546)
			(xy 421.712898 -286.255206) (xy 421.687545 -286.253829) (xy 421.637682 -286.244266) (xy 421.589867 -286.227192)
			(xy 421.545224 -286.203009) (xy 421.504803 -286.172286) (xy 421.469554 -286.135744) (xy 421.440306 -286.094243)
			(xy 421.417746 -286.048758) (xy 421.402405 -286.000359) (xy 421.394643 -285.950184) (xy 421.394643 -285.899412)
			(xy 421.402406 -285.849237) (xy 421.417747 -285.800838) (xy 421.440307 -285.755354) (xy 421.469556 -285.713853)
			(xy 421.504805 -285.677312) (xy 421.545227 -285.646589) (xy 421.58987 -285.622407) (xy 421.637685 -285.605333)
			(xy 421.687549 -285.595771) (xy 421.712898 -285.594298) (xy 421.719756 -285.594044) (xy 421.742362 -285.586932)
			(xy 421.74287 -285.586678) (xy 421.752522 -285.581598) (xy 421.768524 -285.57093) (xy 421.769032 -285.570676)
			(xy 421.770048 -285.56966) (xy 421.773858 -285.566866) (xy 421.77589 -285.564834) (xy 421.7797 -285.56077)
			(xy 421.779954 -285.560516) (xy 421.786304 -285.55061) (xy 421.787066 -285.54807) (xy 421.794432 -285.531052)
			(xy 421.795956 -285.527496) (xy 421.795956 -285.527242) (xy 421.801798 -285.51505) (xy 421.801798 -285.514542)
			(xy 421.80383 -285.510732) (xy 421.80383 -285.510224) (xy 421.804338 -285.509462) (xy 421.804846 -285.5087)
			(xy 421.804846 -285.508192) (xy 421.8051 -285.507684) (xy 421.805608 -285.506922) (xy 421.822372 -285.473648)
			(xy 421.82288 -285.472632) (xy 421.823896 -285.4706) (xy 421.824658 -285.46933) (xy 421.828976 -285.46044)
			(xy 421.830246 -285.455868) (xy 421.832024 -285.44266) (xy 421.832024 -285.420562) (xy 421.832024 -285.419546)
			(xy 421.831693 -285.412996) (xy 421.828096 -285.400388) (xy 421.824912 -285.394654) (xy 421.804338 -285.361888)
			(xy 421.804338 -285.36138) (xy 421.784018 -285.328868) (xy 421.776844 -285.318689) (xy 421.755277 -285.306295)
			(xy 421.74287 -285.305246) (xy 421.73271 -285.305246) (xy 421.72509 -285.3055) (xy 421.724582 -285.3055)
			(xy 421.698607 -285.304974) (xy 421.6473 -285.296817) (xy 421.5979 -285.280737) (xy 421.551621 -285.25713)
			(xy 421.509604 -285.226577) (xy 421.472881 -285.18983) (xy 421.442356 -285.147792) (xy 421.41878 -285.101499)
			(xy 421.402732 -285.052088) (xy 421.394609 -285.000776) (xy 421.394609 -284.948824) (xy 421.402732 -284.897512)
			(xy 421.41878 -284.848101) (xy 421.442356 -284.801808) (xy 421.472881 -284.75977) (xy 421.509604 -284.723023)
			(xy 421.551621 -284.69247) (xy 421.5979 -284.668863) (xy 421.6473 -284.652783) (xy 421.698607 -284.644626)
			(xy 421.724582 -284.644084) (xy 421.72509 -284.644084) (xy 421.73271 -284.644338) (xy 421.741092 -284.644338)
			(xy 421.750727 -284.643877) (xy 421.768619 -284.636706) (xy 421.77589 -284.630368) (xy 421.782748 -284.623256)
			(xy 421.831008 -284.545278) (xy 421.835458 -284.537388) (xy 421.839024 -284.51964) (xy 421.836183 -284.501762)
			(xy 421.832024 -284.493716) (xy 421.825928 -284.48254) (xy 421.825928 -284.482032) (xy 421.823388 -284.47746)
			(xy 421.819578 -284.470602) (xy 421.814752 -284.461458) (xy 421.809418 -284.45079) (xy 421.786558 -284.400752)
			(xy 421.78351 -284.393386) (xy 421.7797 -284.388814) (xy 421.770048 -284.37967) (xy 421.769032 -284.379162)
			(xy 421.768524 -284.378654) (xy 421.756332 -284.370526) (xy 421.74795 -284.365192) (xy 421.74287 -284.362906)
			(xy 421.741854 -284.362398) (xy 421.719756 -284.35554) (xy 421.712898 -284.355286) (xy 421.68738 -284.353883)
			(xy 421.637202 -284.344194) (xy 421.589112 -284.326901) (xy 421.544254 -284.302416) (xy 421.503697 -284.271322)
			(xy 421.468407 -284.234359) (xy 421.439222 -284.192406) (xy 421.416839 -284.146464) (xy 421.40179 -284.097625)
			(xy 421.394433 -284.047053) (xy 421.394943 -283.99595) (xy 421.403309 -283.945535) (xy 421.419331 -283.897006)
			(xy 421.442628 -283.85152) (xy 421.472644 -283.810159) (xy 421.508666 -283.773909) (xy 421.549836 -283.743631)
			(xy 421.595173 -283.720047) (xy 421.643599 -283.703718) (xy 421.693961 -283.695033) (xy 421.719502 -283.694124)
			(xy 421.721026 -283.694124) (xy 421.725746 -283.693807) (xy 421.734949 -283.69163) (xy 421.739314 -283.689806)
			(xy 421.746934 -283.685488) (xy 421.76954 -283.670502) (xy 421.76954 -283.670248) (xy 421.774271 -283.666781)
			(xy 421.782109 -283.658059) (xy 421.785034 -283.652976) (xy 421.785288 -283.652214) (xy 421.786812 -283.648658)
			(xy 421.798937 -283.620553) (xy 421.826264 -283.565776) (xy 421.841422 -283.539184) (xy 421.841422 -283.538676)
			(xy 421.84828 -283.5275) (xy 421.851836 -283.521404) (xy 421.854445 -283.514544) (xy 421.855991 -283.499957)
			(xy 421.854884 -283.492702) (xy 421.851074 -283.479494) (xy 421.847264 -283.471366) (xy 421.79494 -283.419042)
			(xy 421.78843 -283.412948) (xy 421.772295 -283.405383) (xy 421.763444 -283.40431) (xy 421.758618 -283.40431)
			(xy 421.755316 -283.404564) (xy 421.728646 -283.40558) (xy 421.724582 -283.40558) (xy 421.698607 -283.405054)
			(xy 421.6473 -283.396896) (xy 421.597901 -283.380816) (xy 421.551624 -283.357208) (xy 421.509607 -283.326654)
			(xy 421.472886 -283.289905) (xy 421.442363 -283.247866) (xy 421.41879 -283.201572) (xy 421.402746 -283.15216)
			(xy 421.394626 -283.100848) (xy 421.394128 -283.074872) (xy 421.395398 -283.044138) (xy 421.395639 -283.033238)
			(xy 421.387991 -283.012846) (xy 421.380666 -283.004768) (xy 420.844726 -282.468828) (xy 420.838214 -282.462738)
			(xy 420.822079 -282.455179) (xy 420.81323 -282.454096) (xy 420.808404 -282.454096) (xy 420.805102 -282.45435)
			(xy 420.778432 -282.455366) (xy 420.774368 -282.455366) (xy 420.747188 -282.454796) (xy 420.693568 -282.445862)
			(xy 420.642132 -282.428273) (xy 420.594269 -282.402503) (xy 420.551268 -282.369247) (xy 420.51429 -282.329403)
			(xy 420.484331 -282.284043) (xy 420.4622 -282.234393) (xy 420.454836 -282.208224) (xy 420.453312 -282.202382)
			(xy 420.441882 -282.181554) (xy 420.441628 -282.1813) (xy 420.434135 -282.173853) (xy 420.41484 -282.165314)
			(xy 420.40429 -282.16479) (xy 420.19474 -282.16479) (xy 420.18585 -282.165552) (xy 420.179551 -282.166911)
			(xy 420.167854 -282.172306) (xy 420.162736 -282.17622) (xy 420.157377 -282.18093) (xy 420.14927 -282.192664)
			(xy 420.146734 -282.199334) (xy 420.145718 -282.203398) (xy 420.139078 -282.228414) (xy 420.119091 -282.276153)
			(xy 420.091908 -282.320194) (xy 420.058195 -282.359461) (xy 420.018775 -282.392995) (xy 419.97461 -282.419977)
			(xy 419.926781 -282.439747) (xy 419.876455 -282.451822) (xy 419.824862 -282.455908) (xy 419.773263 -282.451904)
			(xy 419.722918 -282.439908) (xy 419.675057 -282.420214) (xy 419.63085 -282.393302) (xy 419.591376 -282.35983)
			(xy 419.557601 -282.320617) (xy 419.530349 -282.276618) (xy 419.510286 -282.228911) (xy 419.503606 -282.203906)
			(xy 419.503606 -282.203652) (xy 419.502844 -282.200858) (xy 419.502336 -282.198572) (xy 419.498598 -282.189269)
			(xy 419.485191 -282.174381) (xy 419.467104 -282.165762) (xy 419.457124 -282.16479) (xy 419.24478 -282.16479)
			(xy 419.23589 -282.165552) (xy 419.229594 -282.166917) (xy 419.217906 -282.172323) (xy 419.212776 -282.17622)
			(xy 419.207414 -282.180928) (xy 419.1993 -282.19266) (xy 419.196774 -282.199334) (xy 419.195758 -282.203398)
			(xy 419.189118 -282.228417) (xy 419.16913 -282.276162) (xy 419.141945 -282.320209) (xy 419.108229 -282.359482)
			(xy 419.068805 -282.393021) (xy 419.024636 -282.420007) (xy 418.976802 -282.439781) (xy 418.92647 -282.451859)
			(xy 418.874871 -282.455947) (xy 418.823266 -282.451944) (xy 418.772915 -282.439948) (xy 418.725048 -282.420253)
			(xy 418.680835 -282.393339) (xy 418.641356 -282.359865) (xy 418.607575 -282.320647) (xy 418.580319 -282.276645)
			(xy 418.560252 -282.228933) (xy 418.553646 -282.203906) (xy 418.553646 -282.203652) (xy 418.552884 -282.200858)
			(xy 418.552376 -282.198572) (xy 418.548639 -282.189265) (xy 418.535235 -282.174367) (xy 418.517149 -282.165735)
			(xy 418.507164 -282.16479) (xy 418.29482 -282.16479) (xy 418.28593 -282.165552) (xy 418.279632 -282.166913)
			(xy 418.267938 -282.172311) (xy 418.262816 -282.17622) (xy 418.25745 -282.180926) (xy 418.249331 -282.192656)
			(xy 418.246814 -282.199334) (xy 418.245798 -282.203398) (xy 418.239159 -282.228412) (xy 418.219171 -282.276148)
			(xy 418.19199 -282.320186) (xy 418.158278 -282.359451) (xy 418.118859 -282.392983) (xy 418.074697 -282.419962)
			(xy 418.02687 -282.43973) (xy 417.976547 -282.451804) (xy 417.924957 -282.455889) (xy 417.873361 -282.451884)
			(xy 417.823019 -282.439888) (xy 417.775162 -282.420195) (xy 417.730957 -282.393284) (xy 417.691487 -282.359813)
			(xy 417.657714 -282.320601) (xy 417.630464 -282.276605) (xy 417.610403 -282.228901) (xy 417.603686 -282.203906)
			(xy 417.603686 -282.203652) (xy 417.602924 -282.200858) (xy 417.602416 -282.198572) (xy 417.598622 -282.189296)
			(xy 417.585238 -282.174408) (xy 417.567176 -282.165774) (xy 417.557204 -282.16479) (xy 417.34486 -282.16479)
			(xy 417.33597 -282.165552) (xy 417.329675 -282.166919) (xy 417.31799 -282.172329) (xy 417.312856 -282.17622)
			(xy 417.307495 -282.180929) (xy 417.299385 -282.192662) (xy 417.296854 -282.199334) (xy 417.295838 -282.203398)
			(xy 417.289198 -282.228415) (xy 417.26921 -282.276157) (xy 417.242027 -282.320202) (xy 417.208312 -282.359472)
			(xy 417.16889 -282.393008) (xy 417.124723 -282.419992) (xy 417.076891 -282.439764) (xy 417.026562 -282.451841)
			(xy 416.974967 -282.455927) (xy 416.923364 -282.451924) (xy 416.873016 -282.439928) (xy 416.825152 -282.420234)
			(xy 416.780942 -282.393321) (xy 416.741466 -282.359848) (xy 416.707688 -282.320632) (xy 416.680434 -282.276632)
			(xy 416.660369 -282.228922) (xy 416.653726 -282.203906) (xy 416.653726 -282.203652) (xy 416.652964 -282.200858)
			(xy 416.652456 -282.198572) (xy 416.648719 -282.189267) (xy 416.635313 -282.174374) (xy 416.617227 -282.165749)
			(xy 416.607244 -282.16479) (xy 416.395154 -282.16479) (xy 416.386264 -282.165552) (xy 416.37997 -282.16692)
			(xy 416.368285 -282.17233) (xy 416.36315 -282.17622) (xy 416.35779 -282.180929) (xy 416.34968 -282.192662)
			(xy 416.347148 -282.199334) (xy 416.346132 -282.203398) (xy 416.339491 -282.228434) (xy 416.319495 -282.276212)
			(xy 416.292296 -282.32029) (xy 416.25856 -282.359591) (xy 416.219112 -282.393153) (xy 416.174915 -282.420158)
			(xy 416.127049 -282.439944) (xy 416.076685 -282.452029) (xy 416.025052 -282.456116) (xy 415.973414 -282.452107)
			(xy 415.923031 -282.440099) (xy 415.875135 -282.420386) (xy 415.830897 -282.393449) (xy 415.791397 -282.359946)
			(xy 415.757602 -282.320697) (xy 415.730336 -282.276661) (xy 415.710267 -282.228913) (xy 415.703512 -282.203906)
			(xy 415.703512 -282.203652) (xy 415.70275 -282.200604) (xy 415.702242 -282.198572) (xy 415.698504 -282.189268)
			(xy 415.685097 -282.174379) (xy 415.667011 -282.165758) (xy 415.65703 -282.16479) (xy 415.445194 -282.16479)
			(xy 415.436304 -282.165552) (xy 415.430008 -282.166916) (xy 415.418317 -282.172319) (xy 415.41319 -282.17622)
			(xy 415.407826 -282.180927) (xy 415.399711 -282.192658) (xy 415.397188 -282.199334) (xy 415.396172 -282.203398)
			(xy 415.389531 -282.228437) (xy 415.369533 -282.276222) (xy 415.342333 -282.320305) (xy 415.308595 -282.359611)
			(xy 415.269142 -282.393179) (xy 415.224941 -282.420188) (xy 415.17707 -282.439978) (xy 415.1267 -282.452065)
			(xy 415.075062 -282.456155) (xy 415.023417 -282.452147) (xy 414.973028 -282.440139) (xy 414.925126 -282.420425)
			(xy 414.880882 -282.393486) (xy 414.841377 -282.359981) (xy 414.807576 -282.320728) (xy 414.780306 -282.276687)
			(xy 414.760233 -282.228935) (xy 414.753552 -282.203906) (xy 414.753552 -282.203652) (xy 414.75279 -282.200604)
			(xy 414.752282 -282.198572) (xy 414.748546 -282.189264) (xy 414.735142 -282.174364) (xy 414.717055 -282.16573)
			(xy 414.70707 -282.16479) (xy 414.495234 -282.16479) (xy 414.486344 -282.165552) (xy 414.480045 -282.166911)
			(xy 414.468349 -282.172307) (xy 414.46323 -282.17622) (xy 414.457863 -282.180925) (xy 414.449742 -282.192654)
			(xy 414.447228 -282.199334) (xy 414.446212 -282.203398) (xy 414.439571 -282.22844) (xy 414.419572 -282.276231)
			(xy 414.39237 -282.320321) (xy 414.358629 -282.359632) (xy 414.319173 -282.393205) (xy 414.274967 -282.420218)
			(xy 414.227091 -282.440012) (xy 414.176716 -282.452102) (xy 414.125071 -282.456194) (xy 414.07342 -282.452187)
			(xy 414.023025 -282.440179) (xy 413.975117 -282.420464) (xy 413.930867 -282.393523) (xy 413.891356 -282.360015)
			(xy 413.857551 -282.320759) (xy 413.830276 -282.276714) (xy 413.810199 -282.228956) (xy 413.803592 -282.203906)
			(xy 413.803592 -282.203652) (xy 413.80283 -282.200604) (xy 413.802322 -282.198572) (xy 413.798583 -282.18927)
			(xy 413.785175 -282.174386) (xy 413.767089 -282.165773) (xy 413.75711 -282.16479) (xy 413.545274 -282.16479)
			(xy 413.536384 -282.165552) (xy 413.530089 -282.166918) (xy 413.518401 -282.172325) (xy 413.51327 -282.17622)
			(xy 413.507908 -282.180928) (xy 413.499796 -282.19266) (xy 413.497268 -282.199334) (xy 413.496252 -282.203398)
			(xy 413.489611 -282.228436) (xy 413.469614 -282.276217) (xy 413.442415 -282.320298) (xy 413.408677 -282.359601)
			(xy 413.369227 -282.393166) (xy 413.325028 -282.420173) (xy 413.27716 -282.439961) (xy 413.226792 -282.452047)
			(xy 413.175157 -282.456136) (xy 413.123515 -282.452127) (xy 413.073129 -282.440119) (xy 413.025231 -282.420405)
			(xy 412.980989 -282.393467) (xy 412.941487 -282.359964) (xy 412.907689 -282.320713) (xy 412.880421 -282.276674)
			(xy 412.86035 -282.228924) (xy 412.853632 -282.203906) (xy 412.853632 -282.203652) (xy 412.85287 -282.200604)
			(xy 412.852362 -282.198572) (xy 412.848625 -282.189266) (xy 412.83522 -282.174372) (xy 412.817133 -282.165744)
			(xy 412.80715 -282.16479) (xy 412.595314 -282.16479) (xy 412.586424 -282.165552) (xy 412.580127 -282.166914)
			(xy 412.568433 -282.172313) (xy 412.56331 -282.17622) (xy 412.557945 -282.180926) (xy 412.549826 -282.192656)
			(xy 412.547308 -282.199334) (xy 412.546292 -282.203398) (xy 412.539651 -282.228439) (xy 412.519653 -282.276226)
			(xy 412.492452 -282.320313) (xy 412.458712 -282.359622) (xy 412.419258 -282.393192) (xy 412.375054 -282.420203)
			(xy 412.327181 -282.439995) (xy 412.276808 -282.452084) (xy 412.225167 -282.456175) (xy 412.173519 -282.452167)
			(xy 412.123127 -282.440159) (xy 412.075222 -282.420444) (xy 412.030974 -282.393504) (xy 411.991467 -282.359998)
			(xy 411.957663 -282.320743) (xy 411.930391 -282.2767) (xy 411.910316 -282.228945) (xy 411.903672 -282.203906)
			(xy 411.903672 -282.203652) (xy 411.90291 -282.200604) (xy 411.902402 -282.198572) (xy 411.898667 -282.189262)
			(xy 411.885264 -282.174357) (xy 411.867177 -282.165716) (xy 411.85719 -282.16479) (xy 411.645354 -282.16479)
			(xy 411.636464 -282.165552) (xy 411.63017 -282.16692) (xy 411.618485 -282.17233) (xy 411.61335 -282.17622)
			(xy 411.60799 -282.180929) (xy 411.59988 -282.192662) (xy 411.597348 -282.199334) (xy 411.596332 -282.203398)
			(xy 411.589691 -282.228434) (xy 411.569695 -282.276212) (xy 411.542496 -282.32029) (xy 411.50876 -282.359591)
			(xy 411.469312 -282.393153) (xy 411.425115 -282.420158) (xy 411.377249 -282.439944) (xy 411.326885 -282.452029)
			(xy 411.275252 -282.456116) (xy 411.223614 -282.452107) (xy 411.173231 -282.440099) (xy 411.125335 -282.420386)
			(xy 411.081097 -282.393449) (xy 411.041597 -282.359946) (xy 411.007802 -282.320697) (xy 410.980536 -282.276661)
			(xy 410.960467 -282.228913) (xy 410.953712 -282.203906) (xy 410.953712 -282.203652) (xy 410.95295 -282.200604)
			(xy 410.952442 -282.198572) (xy 410.948704 -282.189268) (xy 410.935297 -282.174379) (xy 410.917211 -282.165758)
			(xy 410.90723 -282.16479) (xy 410.69514 -282.16479) (xy 410.68625 -282.165552) (xy 410.679951 -282.166911)
			(xy 410.668254 -282.172306) (xy 410.663136 -282.17622) (xy 410.657777 -282.18093) (xy 410.64967 -282.192664)
			(xy 410.647134 -282.199334) (xy 410.646118 -282.203398) (xy 410.639477 -282.228441) (xy 410.619478 -282.276232)
			(xy 410.592276 -282.320323) (xy 410.558534 -282.359635) (xy 410.519078 -282.393209) (xy 410.474871 -282.420223)
			(xy 410.426995 -282.440017) (xy 410.376618 -282.452108) (xy 410.324973 -282.4562) (xy 410.273321 -282.452193)
			(xy 410.222925 -282.440185) (xy 410.175016 -282.42047) (xy 410.130765 -282.393529) (xy 410.091253 -282.36002)
			(xy 410.057447 -282.320763) (xy 410.030172 -282.276718) (xy 410.010094 -282.228959) (xy 410.003498 -282.203906)
			(xy 410.003498 -282.203652) (xy 410.002736 -282.200604) (xy 410.002228 -282.198572) (xy 409.998489 -282.18927)
			(xy 409.985082 -282.174384) (xy 409.966996 -282.165768) (xy 409.957016 -282.16479) (xy 409.74518 -282.16479)
			(xy 409.73629 -282.165552) (xy 409.729994 -282.166917) (xy 409.718306 -282.172323) (xy 409.713176 -282.17622)
			(xy 409.707814 -282.180928) (xy 409.6997 -282.19266) (xy 409.697174 -282.199334) (xy 409.696158 -282.203398)
			(xy 409.689517 -282.228436) (xy 409.66952 -282.276218) (xy 409.64232 -282.3203) (xy 409.608583 -282.359604)
			(xy 409.569132 -282.39317) (xy 409.524932 -282.420177) (xy 409.477063 -282.439966) (xy 409.426695 -282.452053)
			(xy 409.375059 -282.456142) (xy 409.323416 -282.452133) (xy 409.273029 -282.440125) (xy 409.225129 -282.420411)
			(xy 409.180887 -282.393473) (xy 409.141384 -282.359969) (xy 409.107585 -282.320717) (xy 409.080317 -282.276678)
			(xy 409.060245 -282.228927) (xy 409.053538 -282.203906) (xy 409.053538 -282.203652) (xy 409.052776 -282.200604)
			(xy 409.052268 -282.198572) (xy 409.048531 -282.189266) (xy 409.035126 -282.17437) (xy 409.01704 -282.16574)
			(xy 409.007056 -282.16479) (xy 408.79522 -282.16479) (xy 408.78633 -282.165552) (xy 408.780032 -282.166913)
			(xy 408.768338 -282.172311) (xy 408.763216 -282.17622) (xy 408.75785 -282.180926) (xy 408.749731 -282.192656)
			(xy 408.747214 -282.199334) (xy 408.746198 -282.203398) (xy 408.739557 -282.228439) (xy 408.719559 -282.276228)
			(xy 408.692357 -282.320315) (xy 408.658617 -282.359625) (xy 408.619162 -282.393196) (xy 408.574958 -282.420208)
			(xy 408.527084 -282.44) (xy 408.47671 -282.452089) (xy 408.425068 -282.45618) (xy 408.373419 -282.452173)
			(xy 408.323026 -282.440165) (xy 408.27512 -282.42045) (xy 408.230872 -282.39351) (xy 408.191363 -282.360003)
			(xy 408.15756 -282.320748) (xy 408.130287 -282.276704) (xy 408.110211 -282.228948) (xy 408.103578 -282.203906)
			(xy 408.103578 -282.203652) (xy 408.102816 -282.200604) (xy 408.102308 -282.198572) (xy 408.098513 -282.189297)
			(xy 408.085129 -282.174411) (xy 408.067067 -282.16578) (xy 408.057096 -282.16479) (xy 407.149046 -282.16479)
			(xy 407.143458 -282.165044) (xy 407.14168 -282.165298) (xy 407.13361 -282.166785) (xy 407.11896 -282.174159)
			(xy 407.112978 -282.179776) (xy 406.779222 -282.513786) (xy 406.77182 -282.520622) (xy 406.753222 -282.52833)
			(xy 406.743154 -282.528772) (xy 403.605746 -282.528772) (xy 403.596134 -282.529181) (xy 403.578245 -282.53622)
			(xy 403.570948 -282.542488) (xy 403.527514 -282.582874) (xy 403.524108 -282.586195) (xy 403.518483 -282.593867)
			(xy 403.516338 -282.598114) (xy 403.504654 -282.622498) (xy 403.503638 -282.631134) (xy 403.499828 -282.655264)
			(xy 403.499828 -282.655772) (xy 403.498084 -282.668136) (xy 403.505429 -282.691969) (xy 403.513798 -282.701238)
			(xy 403.572472 -282.759912) (xy 403.57987 -282.766757) (xy 403.598469 -282.774479) (xy 403.60854 -282.774898)
			(xy 403.618446 -282.774898) (xy 403.622764 -282.774136) (xy 403.635678 -282.772021) (xy 403.661749 -282.769735)
			(xy 403.674834 -282.769564) (xy 403.699657 -282.770053) (xy 403.748648 -282.77809) (xy 403.795694 -282.793947)
			(xy 403.839554 -282.817207) (xy 403.879074 -282.847255) (xy 403.913211 -282.883302) (xy 403.941068 -282.924396)
			(xy 403.961909 -282.969456) (xy 403.975185 -283.017294) (xy 403.980548 -283.06665) (xy 403.980101 -283.074872)
			(xy 404.319244 -283.074872) (xy 404.323204 -283.025818) (xy 404.334981 -282.978034) (xy 404.354272 -282.932758)
			(xy 404.380575 -282.891162) (xy 404.41321 -282.854325) (xy 404.451331 -282.8232) (xy 404.493952 -282.798593)
			(xy 404.539968 -282.781141) (xy 404.588187 -282.771297) (xy 404.637362 -282.769316) (xy 404.686217 -282.775248)
			(xy 404.733488 -282.78894) (xy 404.77795 -282.810038) (xy 404.818453 -282.837994) (xy 404.853946 -282.872086)
			(xy 404.883511 -282.91143) (xy 404.906382 -282.955007) (xy 404.921966 -283.001688) (xy 404.929861 -283.050265)
			(xy 404.930356 -283.074872) (xy 405.269204 -283.074872) (xy 405.273164 -283.025818) (xy 405.284941 -282.978034)
			(xy 405.304232 -282.932758) (xy 405.330535 -282.891162) (xy 405.36317 -282.854325) (xy 405.401291 -282.8232)
			(xy 405.443912 -282.798593) (xy 405.489928 -282.781141) (xy 405.538147 -282.771297) (xy 405.587322 -282.769316)
			(xy 405.636177 -282.775248) (xy 405.683448 -282.78894) (xy 405.72791 -282.810038) (xy 405.768413 -282.837994)
			(xy 405.803906 -282.872086) (xy 405.833471 -282.91143) (xy 405.856342 -282.955007) (xy 405.871926 -283.001688)
			(xy 405.879821 -283.050265) (xy 405.880316 -283.074872) (xy 406.219164 -283.074872) (xy 406.223124 -283.025818)
			(xy 406.234901 -282.978034) (xy 406.254192 -282.932758) (xy 406.280495 -282.891162) (xy 406.31313 -282.854325)
			(xy 406.351251 -282.8232) (xy 406.393872 -282.798593) (xy 406.439888 -282.781141) (xy 406.488107 -282.771297)
			(xy 406.537282 -282.769316) (xy 406.586137 -282.775248) (xy 406.633408 -282.78894) (xy 406.67787 -282.810038)
			(xy 406.718373 -282.837994) (xy 406.753866 -282.872086) (xy 406.783431 -282.91143) (xy 406.806302 -282.955007)
			(xy 406.821886 -283.001688) (xy 406.829781 -283.050265) (xy 406.830276 -283.074872) (xy 408.119084 -283.074872)
			(xy 408.123044 -283.025818) (xy 408.134821 -282.978034) (xy 408.154112 -282.932758) (xy 408.180415 -282.891162)
			(xy 408.21305 -282.854325) (xy 408.251171 -282.8232) (xy 408.293792 -282.798593) (xy 408.339808 -282.781141)
			(xy 408.388027 -282.771297) (xy 408.437202 -282.769316) (xy 408.486057 -282.775248) (xy 408.533328 -282.78894)
			(xy 408.57779 -282.810038) (xy 408.618293 -282.837994) (xy 408.653786 -282.872086) (xy 408.683351 -282.91143)
			(xy 408.706222 -282.955007) (xy 408.721806 -283.001688) (xy 408.729701 -283.050265) (xy 408.730196 -283.074872)
			(xy 409.069044 -283.074872) (xy 409.073004 -283.025818) (xy 409.084781 -282.978034) (xy 409.104072 -282.932758)
			(xy 409.130375 -282.891162) (xy 409.16301 -282.854325) (xy 409.201131 -282.8232) (xy 409.243752 -282.798593)
			(xy 409.289768 -282.781141) (xy 409.337987 -282.771297) (xy 409.387162 -282.769316) (xy 409.436017 -282.775248)
			(xy 409.483288 -282.78894) (xy 409.52775 -282.810038) (xy 409.568253 -282.837994) (xy 409.603746 -282.872086)
			(xy 409.633311 -282.91143) (xy 409.656182 -282.955007) (xy 409.671766 -283.001688) (xy 409.679661 -283.050265)
			(xy 409.680156 -283.074872) (xy 410.019004 -283.074872) (xy 410.022964 -283.025818) (xy 410.034741 -282.978034)
			(xy 410.054032 -282.932758) (xy 410.080335 -282.891162) (xy 410.11297 -282.854325) (xy 410.151091 -282.8232)
			(xy 410.193712 -282.798593) (xy 410.239728 -282.781141) (xy 410.287947 -282.771297) (xy 410.337122 -282.769316)
			(xy 410.385977 -282.775248) (xy 410.433248 -282.78894) (xy 410.47771 -282.810038) (xy 410.518213 -282.837994)
			(xy 410.553706 -282.872086) (xy 410.583271 -282.91143) (xy 410.606142 -282.955007) (xy 410.621726 -283.001688)
			(xy 410.629621 -283.050265) (xy 410.630116 -283.074872) (xy 410.969218 -283.074872) (xy 410.973178 -283.025818)
			(xy 410.984955 -282.978034) (xy 411.004246 -282.932758) (xy 411.030549 -282.891162) (xy 411.063184 -282.854325)
			(xy 411.101305 -282.8232) (xy 411.143926 -282.798593) (xy 411.189942 -282.781141) (xy 411.238161 -282.771297)
			(xy 411.287336 -282.769316) (xy 411.336191 -282.775248) (xy 411.383462 -282.78894) (xy 411.427924 -282.810038)
			(xy 411.468427 -282.837994) (xy 411.50392 -282.872086) (xy 411.533485 -282.91143) (xy 411.556356 -282.955007)
			(xy 411.57194 -283.001688) (xy 411.579835 -283.050265) (xy 411.58033 -283.074872) (xy 411.919178 -283.074872)
			(xy 411.923138 -283.025818) (xy 411.934915 -282.978034) (xy 411.954206 -282.932758) (xy 411.980509 -282.891162)
			(xy 412.013144 -282.854325) (xy 412.051265 -282.8232) (xy 412.093886 -282.798593) (xy 412.139902 -282.781141)
			(xy 412.188121 -282.771297) (xy 412.237296 -282.769316) (xy 412.286151 -282.775248) (xy 412.333422 -282.78894)
			(xy 412.377884 -282.810038) (xy 412.418387 -282.837994) (xy 412.45388 -282.872086) (xy 412.483445 -282.91143)
			(xy 412.506316 -282.955007) (xy 412.5219 -283.001688) (xy 412.529795 -283.050265) (xy 412.53029 -283.074872)
			(xy 412.869138 -283.074872) (xy 412.873098 -283.025818) (xy 412.884875 -282.978034) (xy 412.904166 -282.932758)
			(xy 412.930469 -282.891162) (xy 412.963104 -282.854325) (xy 413.001225 -282.8232) (xy 413.043846 -282.798593)
			(xy 413.089862 -282.781141) (xy 413.138081 -282.771297) (xy 413.187256 -282.769316) (xy 413.236111 -282.775248)
			(xy 413.283382 -282.78894) (xy 413.327844 -282.810038) (xy 413.368347 -282.837994) (xy 413.40384 -282.872086)
			(xy 413.433405 -282.91143) (xy 413.456276 -282.955007) (xy 413.47186 -283.001688) (xy 413.479755 -283.050265)
			(xy 413.48025 -283.074872) (xy 413.819098 -283.074872) (xy 413.823058 -283.025818) (xy 413.834835 -282.978034)
			(xy 413.854126 -282.932758) (xy 413.880429 -282.891162) (xy 413.913064 -282.854325) (xy 413.951185 -282.8232)
			(xy 413.993806 -282.798593) (xy 414.039822 -282.781141) (xy 414.088041 -282.771297) (xy 414.137216 -282.769316)
			(xy 414.186071 -282.775248) (xy 414.233342 -282.78894) (xy 414.277804 -282.810038) (xy 414.318307 -282.837994)
			(xy 414.3538 -282.872086) (xy 414.383365 -282.91143) (xy 414.406236 -282.955007) (xy 414.42182 -283.001688)
			(xy 414.429715 -283.050265) (xy 414.43021 -283.074872) (xy 414.769058 -283.074872) (xy 414.773018 -283.025818)
			(xy 414.784795 -282.978034) (xy 414.804086 -282.932758) (xy 414.830389 -282.891162) (xy 414.863024 -282.854325)
			(xy 414.901145 -282.8232) (xy 414.943766 -282.798593) (xy 414.989782 -282.781141) (xy 415.038001 -282.771297)
			(xy 415.087176 -282.769316) (xy 415.136031 -282.775248) (xy 415.183302 -282.78894) (xy 415.227764 -282.810038)
			(xy 415.268267 -282.837994) (xy 415.30376 -282.872086) (xy 415.333325 -282.91143) (xy 415.356196 -282.955007)
			(xy 415.37178 -283.001688) (xy 415.379675 -283.050265) (xy 415.38017 -283.074872) (xy 415.719018 -283.074872)
			(xy 415.722978 -283.025818) (xy 415.734755 -282.978034) (xy 415.754046 -282.932758) (xy 415.780349 -282.891162)
			(xy 415.812984 -282.854325) (xy 415.851105 -282.8232) (xy 415.893726 -282.798593) (xy 415.939742 -282.781141)
			(xy 415.987961 -282.771297) (xy 416.037136 -282.769316) (xy 416.085991 -282.775248) (xy 416.133262 -282.78894)
			(xy 416.177724 -282.810038) (xy 416.218227 -282.837994) (xy 416.25372 -282.872086) (xy 416.283285 -282.91143)
			(xy 416.306156 -282.955007) (xy 416.32174 -283.001688) (xy 416.329635 -283.050265) (xy 416.33013 -283.074872)
			(xy 416.668978 -283.074872) (xy 416.672938 -283.025818) (xy 416.684715 -282.978034) (xy 416.704006 -282.932758)
			(xy 416.730309 -282.891162) (xy 416.762944 -282.854325) (xy 416.801065 -282.8232) (xy 416.843686 -282.798593)
			(xy 416.889702 -282.781141) (xy 416.937921 -282.771297) (xy 416.987096 -282.769316) (xy 417.035951 -282.775248)
			(xy 417.083222 -282.78894) (xy 417.127684 -282.810038) (xy 417.168187 -282.837994) (xy 417.20368 -282.872086)
			(xy 417.233245 -282.91143) (xy 417.256116 -282.955007) (xy 417.2717 -283.001688) (xy 417.279595 -283.050265)
			(xy 417.28009 -283.074872) (xy 417.619192 -283.074872) (xy 417.623152 -283.025818) (xy 417.634929 -282.978034)
			(xy 417.65422 -282.932758) (xy 417.680523 -282.891162) (xy 417.713158 -282.854325) (xy 417.751279 -282.8232)
			(xy 417.7939 -282.798593) (xy 417.839916 -282.781141) (xy 417.888135 -282.771297) (xy 417.93731 -282.769316)
			(xy 417.986165 -282.775248) (xy 418.033436 -282.78894) (xy 418.077898 -282.810038) (xy 418.118401 -282.837994)
			(xy 418.153894 -282.872086) (xy 418.183459 -282.91143) (xy 418.20633 -282.955007) (xy 418.221914 -283.001688)
			(xy 418.229809 -283.050265) (xy 418.230304 -283.074872) (xy 418.569152 -283.074872) (xy 418.573112 -283.025818)
			(xy 418.584889 -282.978034) (xy 418.60418 -282.932758) (xy 418.630483 -282.891162) (xy 418.663118 -282.854325)
			(xy 418.701239 -282.8232) (xy 418.74386 -282.798593) (xy 418.789876 -282.781141) (xy 418.838095 -282.771297)
			(xy 418.88727 -282.769316) (xy 418.936125 -282.775248) (xy 418.983396 -282.78894) (xy 419.027858 -282.810038)
			(xy 419.068361 -282.837994) (xy 419.103854 -282.872086) (xy 419.133419 -282.91143) (xy 419.15629 -282.955007)
			(xy 419.171874 -283.001688) (xy 419.179769 -283.050265) (xy 419.180264 -283.074872) (xy 419.519112 -283.074872)
			(xy 419.523072 -283.025818) (xy 419.534849 -282.978034) (xy 419.55414 -282.932758) (xy 419.580443 -282.891162)
			(xy 419.613078 -282.854325) (xy 419.651199 -282.8232) (xy 419.69382 -282.798593) (xy 419.739836 -282.781141)
			(xy 419.788055 -282.771297) (xy 419.83723 -282.769316) (xy 419.886085 -282.775248) (xy 419.933356 -282.78894)
			(xy 419.977818 -282.810038) (xy 420.018321 -282.837994) (xy 420.053814 -282.872086) (xy 420.083379 -282.91143)
			(xy 420.10625 -282.955007) (xy 420.121834 -283.001688) (xy 420.129729 -283.050265) (xy 420.130224 -283.074872)
			(xy 420.469072 -283.074872) (xy 420.473032 -283.025818) (xy 420.484809 -282.978034) (xy 420.5041 -282.932758)
			(xy 420.530403 -282.891162) (xy 420.563038 -282.854325) (xy 420.601159 -282.8232) (xy 420.64378 -282.798593)
			(xy 420.689796 -282.781141) (xy 420.738015 -282.771297) (xy 420.78719 -282.769316) (xy 420.836045 -282.775248)
			(xy 420.883316 -282.78894) (xy 420.927778 -282.810038) (xy 420.968281 -282.837994) (xy 421.003774 -282.872086)
			(xy 421.033339 -282.91143) (xy 421.05621 -282.955007) (xy 421.071794 -283.001688) (xy 421.079689 -283.050265)
			(xy 421.080184 -283.074872) (xy 421.079689 -283.099479) (xy 421.071794 -283.148056) (xy 421.05621 -283.194737)
			(xy 421.033339 -283.238314) (xy 421.003774 -283.277658) (xy 420.968281 -283.31175) (xy 420.927778 -283.339706)
			(xy 420.883316 -283.360804) (xy 420.836045 -283.374496) (xy 420.78719 -283.380428) (xy 420.738015 -283.378447)
			(xy 420.689796 -283.368603) (xy 420.64378 -283.351151) (xy 420.601159 -283.326544) (xy 420.563038 -283.295419)
			(xy 420.530403 -283.258582) (xy 420.5041 -283.216986) (xy 420.484809 -283.17171) (xy 420.473032 -283.123926)
			(xy 420.469072 -283.074872) (xy 420.130224 -283.074872) (xy 420.129729 -283.099479) (xy 420.121834 -283.148056)
			(xy 420.10625 -283.194737) (xy 420.083379 -283.238314) (xy 420.053814 -283.277658) (xy 420.018321 -283.31175)
			(xy 419.977818 -283.339706) (xy 419.933356 -283.360804) (xy 419.886085 -283.374496) (xy 419.83723 -283.380428)
			(xy 419.788055 -283.378447) (xy 419.739836 -283.368603) (xy 419.69382 -283.351151) (xy 419.651199 -283.326544)
			(xy 419.613078 -283.295419) (xy 419.580443 -283.258582) (xy 419.55414 -283.216986) (xy 419.534849 -283.17171)
			(xy 419.523072 -283.123926) (xy 419.519112 -283.074872) (xy 419.180264 -283.074872) (xy 419.179769 -283.099479)
			(xy 419.171874 -283.148056) (xy 419.15629 -283.194737) (xy 419.133419 -283.238314) (xy 419.103854 -283.277658)
			(xy 419.068361 -283.31175) (xy 419.027858 -283.339706) (xy 418.983396 -283.360804) (xy 418.936125 -283.374496)
			(xy 418.88727 -283.380428) (xy 418.838095 -283.378447) (xy 418.789876 -283.368603) (xy 418.74386 -283.351151)
			(xy 418.701239 -283.326544) (xy 418.663118 -283.295419) (xy 418.630483 -283.258582) (xy 418.60418 -283.216986)
			(xy 418.584889 -283.17171) (xy 418.573112 -283.123926) (xy 418.569152 -283.074872) (xy 418.230304 -283.074872)
			(xy 418.229809 -283.099479) (xy 418.221914 -283.148056) (xy 418.20633 -283.194737) (xy 418.183459 -283.238314)
			(xy 418.153894 -283.277658) (xy 418.118401 -283.31175) (xy 418.077898 -283.339706) (xy 418.033436 -283.360804)
			(xy 417.986165 -283.374496) (xy 417.93731 -283.380428) (xy 417.888135 -283.378447) (xy 417.839916 -283.368603)
			(xy 417.7939 -283.351151) (xy 417.751279 -283.326544) (xy 417.713158 -283.295419) (xy 417.680523 -283.258582)
			(xy 417.65422 -283.216986) (xy 417.634929 -283.17171) (xy 417.623152 -283.123926) (xy 417.619192 -283.074872)
			(xy 417.28009 -283.074872) (xy 417.279595 -283.099479) (xy 417.2717 -283.148056) (xy 417.256116 -283.194737)
			(xy 417.233245 -283.238314) (xy 417.20368 -283.277658) (xy 417.168187 -283.31175) (xy 417.127684 -283.339706)
			(xy 417.083222 -283.360804) (xy 417.035951 -283.374496) (xy 416.987096 -283.380428) (xy 416.937921 -283.378447)
			(xy 416.889702 -283.368603) (xy 416.843686 -283.351151) (xy 416.801065 -283.326544) (xy 416.762944 -283.295419)
			(xy 416.730309 -283.258582) (xy 416.704006 -283.216986) (xy 416.684715 -283.17171) (xy 416.672938 -283.123926)
			(xy 416.668978 -283.074872) (xy 416.33013 -283.074872) (xy 416.329635 -283.099479) (xy 416.32174 -283.148056)
			(xy 416.306156 -283.194737) (xy 416.283285 -283.238314) (xy 416.25372 -283.277658) (xy 416.218227 -283.31175)
			(xy 416.177724 -283.339706) (xy 416.133262 -283.360804) (xy 416.085991 -283.374496) (xy 416.037136 -283.380428)
			(xy 415.987961 -283.378447) (xy 415.939742 -283.368603) (xy 415.893726 -283.351151) (xy 415.851105 -283.326544)
			(xy 415.812984 -283.295419) (xy 415.780349 -283.258582) (xy 415.754046 -283.216986) (xy 415.734755 -283.17171)
			(xy 415.722978 -283.123926) (xy 415.719018 -283.074872) (xy 415.38017 -283.074872) (xy 415.379675 -283.099479)
			(xy 415.37178 -283.148056) (xy 415.356196 -283.194737) (xy 415.333325 -283.238314) (xy 415.30376 -283.277658)
			(xy 415.268267 -283.31175) (xy 415.227764 -283.339706) (xy 415.183302 -283.360804) (xy 415.136031 -283.374496)
			(xy 415.087176 -283.380428) (xy 415.038001 -283.378447) (xy 414.989782 -283.368603) (xy 414.943766 -283.351151)
			(xy 414.901145 -283.326544) (xy 414.863024 -283.295419) (xy 414.830389 -283.258582) (xy 414.804086 -283.216986)
			(xy 414.784795 -283.17171) (xy 414.773018 -283.123926) (xy 414.769058 -283.074872) (xy 414.43021 -283.074872)
			(xy 414.429715 -283.099479) (xy 414.42182 -283.148056) (xy 414.406236 -283.194737) (xy 414.383365 -283.238314)
			(xy 414.3538 -283.277658) (xy 414.318307 -283.31175) (xy 414.277804 -283.339706) (xy 414.233342 -283.360804)
			(xy 414.186071 -283.374496) (xy 414.137216 -283.380428) (xy 414.088041 -283.378447) (xy 414.039822 -283.368603)
			(xy 413.993806 -283.351151) (xy 413.951185 -283.326544) (xy 413.913064 -283.295419) (xy 413.880429 -283.258582)
			(xy 413.854126 -283.216986) (xy 413.834835 -283.17171) (xy 413.823058 -283.123926) (xy 413.819098 -283.074872)
			(xy 413.48025 -283.074872) (xy 413.479755 -283.099479) (xy 413.47186 -283.148056) (xy 413.456276 -283.194737)
			(xy 413.433405 -283.238314) (xy 413.40384 -283.277658) (xy 413.368347 -283.31175) (xy 413.327844 -283.339706)
			(xy 413.283382 -283.360804) (xy 413.236111 -283.374496) (xy 413.187256 -283.380428) (xy 413.138081 -283.378447)
			(xy 413.089862 -283.368603) (xy 413.043846 -283.351151) (xy 413.001225 -283.326544) (xy 412.963104 -283.295419)
			(xy 412.930469 -283.258582) (xy 412.904166 -283.216986) (xy 412.884875 -283.17171) (xy 412.873098 -283.123926)
			(xy 412.869138 -283.074872) (xy 412.53029 -283.074872) (xy 412.529795 -283.099479) (xy 412.5219 -283.148056)
			(xy 412.506316 -283.194737) (xy 412.483445 -283.238314) (xy 412.45388 -283.277658) (xy 412.418387 -283.31175)
			(xy 412.377884 -283.339706) (xy 412.333422 -283.360804) (xy 412.286151 -283.374496) (xy 412.237296 -283.380428)
			(xy 412.188121 -283.378447) (xy 412.139902 -283.368603) (xy 412.093886 -283.351151) (xy 412.051265 -283.326544)
			(xy 412.013144 -283.295419) (xy 411.980509 -283.258582) (xy 411.954206 -283.216986) (xy 411.934915 -283.17171)
			(xy 411.923138 -283.123926) (xy 411.919178 -283.074872) (xy 411.58033 -283.074872) (xy 411.579835 -283.099479)
			(xy 411.57194 -283.148056) (xy 411.556356 -283.194737) (xy 411.533485 -283.238314) (xy 411.50392 -283.277658)
			(xy 411.468427 -283.31175) (xy 411.427924 -283.339706) (xy 411.383462 -283.360804) (xy 411.336191 -283.374496)
			(xy 411.287336 -283.380428) (xy 411.238161 -283.378447) (xy 411.189942 -283.368603) (xy 411.143926 -283.351151)
			(xy 411.101305 -283.326544) (xy 411.063184 -283.295419) (xy 411.030549 -283.258582) (xy 411.004246 -283.216986)
			(xy 410.984955 -283.17171) (xy 410.973178 -283.123926) (xy 410.969218 -283.074872) (xy 410.630116 -283.074872)
			(xy 410.629621 -283.099479) (xy 410.621726 -283.148056) (xy 410.606142 -283.194737) (xy 410.583271 -283.238314)
			(xy 410.553706 -283.277658) (xy 410.518213 -283.31175) (xy 410.47771 -283.339706) (xy 410.433248 -283.360804)
			(xy 410.385977 -283.374496) (xy 410.337122 -283.380428) (xy 410.287947 -283.378447) (xy 410.239728 -283.368603)
			(xy 410.193712 -283.351151) (xy 410.151091 -283.326544) (xy 410.11297 -283.295419) (xy 410.080335 -283.258582)
			(xy 410.054032 -283.216986) (xy 410.034741 -283.17171) (xy 410.022964 -283.123926) (xy 410.019004 -283.074872)
			(xy 409.680156 -283.074872) (xy 409.679661 -283.099479) (xy 409.671766 -283.148056) (xy 409.656182 -283.194737)
			(xy 409.633311 -283.238314) (xy 409.603746 -283.277658) (xy 409.568253 -283.31175) (xy 409.52775 -283.339706)
			(xy 409.483288 -283.360804) (xy 409.436017 -283.374496) (xy 409.387162 -283.380428) (xy 409.337987 -283.378447)
			(xy 409.289768 -283.368603) (xy 409.243752 -283.351151) (xy 409.201131 -283.326544) (xy 409.16301 -283.295419)
			(xy 409.130375 -283.258582) (xy 409.104072 -283.216986) (xy 409.084781 -283.17171) (xy 409.073004 -283.123926)
			(xy 409.069044 -283.074872) (xy 408.730196 -283.074872) (xy 408.729701 -283.099479) (xy 408.721806 -283.148056)
			(xy 408.706222 -283.194737) (xy 408.683351 -283.238314) (xy 408.653786 -283.277658) (xy 408.618293 -283.31175)
			(xy 408.57779 -283.339706) (xy 408.533328 -283.360804) (xy 408.486057 -283.374496) (xy 408.437202 -283.380428)
			(xy 408.388027 -283.378447) (xy 408.339808 -283.368603) (xy 408.293792 -283.351151) (xy 408.251171 -283.326544)
			(xy 408.21305 -283.295419) (xy 408.180415 -283.258582) (xy 408.154112 -283.216986) (xy 408.134821 -283.17171)
			(xy 408.123044 -283.123926) (xy 408.119084 -283.074872) (xy 406.830276 -283.074872) (xy 406.829781 -283.099479)
			(xy 406.821886 -283.148056) (xy 406.806302 -283.194737) (xy 406.783431 -283.238314) (xy 406.753866 -283.277658)
			(xy 406.718373 -283.31175) (xy 406.67787 -283.339706) (xy 406.633408 -283.360804) (xy 406.586137 -283.374496)
			(xy 406.537282 -283.380428) (xy 406.488107 -283.378447) (xy 406.439888 -283.368603) (xy 406.393872 -283.351151)
			(xy 406.351251 -283.326544) (xy 406.31313 -283.295419) (xy 406.280495 -283.258582) (xy 406.254192 -283.216986)
			(xy 406.234901 -283.17171) (xy 406.223124 -283.123926) (xy 406.219164 -283.074872) (xy 405.880316 -283.074872)
			(xy 405.879821 -283.099479) (xy 405.871926 -283.148056) (xy 405.856342 -283.194737) (xy 405.833471 -283.238314)
			(xy 405.803906 -283.277658) (xy 405.768413 -283.31175) (xy 405.72791 -283.339706) (xy 405.683448 -283.360804)
			(xy 405.636177 -283.374496) (xy 405.587322 -283.380428) (xy 405.538147 -283.378447) (xy 405.489928 -283.368603)
			(xy 405.443912 -283.351151) (xy 405.401291 -283.326544) (xy 405.36317 -283.295419) (xy 405.330535 -283.258582)
			(xy 405.304232 -283.216986) (xy 405.284941 -283.17171) (xy 405.273164 -283.123926) (xy 405.269204 -283.074872)
			(xy 404.930356 -283.074872) (xy 404.929861 -283.099479) (xy 404.921966 -283.148056) (xy 404.906382 -283.194737)
			(xy 404.883511 -283.238314) (xy 404.853946 -283.277658) (xy 404.818453 -283.31175) (xy 404.77795 -283.339706)
			(xy 404.733488 -283.360804) (xy 404.686217 -283.374496) (xy 404.637362 -283.380428) (xy 404.588187 -283.378447)
			(xy 404.539968 -283.368603) (xy 404.493952 -283.351151) (xy 404.451331 -283.326544) (xy 404.41321 -283.295419)
			(xy 404.380575 -283.258582) (xy 404.354272 -283.216986) (xy 404.334981 -283.17171) (xy 404.323204 -283.123926)
			(xy 404.319244 -283.074872) (xy 403.980101 -283.074872) (xy 403.977855 -283.116223) (xy 403.967177 -283.164707)
			(xy 403.948797 -283.210825) (xy 403.923197 -283.253362) (xy 403.891053 -283.291197) (xy 403.853211 -283.323333)
			(xy 403.810669 -283.348924) (xy 403.764547 -283.367296) (xy 403.716061 -283.377963) (xy 403.666488 -283.380646)
			(xy 403.617133 -283.375274) (xy 403.569298 -283.361987) (xy 403.524242 -283.341137) (xy 403.483154 -283.313272)
			(xy 403.447114 -283.279127) (xy 403.417073 -283.239602) (xy 403.393823 -283.195737) (xy 403.377975 -283.148688)
			(xy 403.369948 -283.099695) (xy 403.369526 -283.074872) (xy 403.369736 -283.060817) (xy 403.37241 -283.032833)
			(xy 403.37486 -283.018992) (xy 403.377146 -283.006546) (xy 403.36978 -282.982416) (xy 403.302216 -282.914852)
			(xy 403.294816 -282.908013) (xy 403.276217 -282.900301) (xy 403.266148 -282.899866) (xy 403.256242 -282.899866)
			(xy 403.251924 -282.900628) (xy 403.239073 -282.902734) (xy 403.21313 -282.905027) (xy 403.200108 -282.9052)
			(xy 403.1996 -282.9052) (xy 403.185608 -282.904985) (xy 403.157751 -282.902317) (xy 403.143974 -282.899866)
			(xy 403.131528 -282.89758) (xy 403.107398 -282.904946) (xy 403.038818 -282.973526) (xy 403.030672 -282.982765)
			(xy 403.023382 -283.006253) (xy 403.024848 -283.018484) (xy 403.024848 -283.018738) (xy 403.02561 -283.023056)
			(xy 403.027712 -283.035908) (xy 403.029998 -283.061851) (xy 403.030182 -283.074872) (xy 403.029698 -283.099691)
			(xy 403.021672 -283.148675) (xy 403.005827 -283.195716) (xy 402.982581 -283.239573) (xy 402.952545 -283.279092)
			(xy 402.916511 -283.313231) (xy 402.87543 -283.341091) (xy 402.830382 -283.361937) (xy 402.782554 -283.375221)
			(xy 402.733208 -283.380592) (xy 402.683643 -283.377909) (xy 402.635165 -283.367243) (xy 402.589052 -283.348874)
			(xy 402.546517 -283.323287) (xy 402.508682 -283.291156) (xy 402.476544 -283.253327) (xy 402.45095 -283.210797)
			(xy 402.432573 -283.164686) (xy 402.421898 -283.11621) (xy 402.419206 -283.066646) (xy 402.424569 -283.017299)
			(xy 402.437844 -282.969469) (xy 402.458683 -282.924418) (xy 402.486535 -282.883331) (xy 402.520668 -282.847291)
			(xy 402.560181 -282.817248) (xy 402.604034 -282.793994) (xy 402.651072 -282.778141) (xy 402.700055 -282.770106)
			(xy 402.724874 -282.769564) (xy 402.738929 -282.769771) (xy 402.766914 -282.772442) (xy 402.780754 -282.774898)
			(xy 402.7932 -282.777184) (xy 402.81733 -282.769818) (xy 402.884894 -282.702254) (xy 402.891734 -282.694853)
			(xy 402.899453 -282.676255) (xy 402.89988 -282.666186) (xy 402.89988 -282.655772) (xy 402.899118 -282.6512)
			(xy 402.89607 -282.631134) (xy 402.895054 -282.622498) (xy 402.88337 -282.598114) (xy 402.881222 -282.593869)
			(xy 402.875598 -282.586197) (xy 402.872194 -282.582874) (xy 402.82876 -282.542488) (xy 402.82147 -282.536205)
			(xy 402.803579 -282.529157) (xy 402.793962 -282.528772) (xy 391.351262 -282.528772) (xy 391.341261 -282.528277)
			(xy 391.322787 -282.52061) (xy 391.308653 -282.506457) (xy 391.30101 -282.487973) (xy 391.300462 -282.477972)
			(xy 391.300462 -282.473146) (xy 391.2999 -282.461551) (xy 391.289764 -282.440694) (xy 391.271547 -282.426344)
			(xy 391.26033 -282.423362) (xy 391.236575 -282.417741) (xy 391.19111 -282.399975) (xy 391.149051 -282.375203)
			(xy 391.111468 -282.344055) (xy 391.079319 -282.307324) (xy 391.053424 -282.265947) (xy 391.03444 -282.220977)
			(xy 391.022854 -282.173559) (xy 391.018958 -282.124903) (xy 391.022853 -282.076246) (xy 391.034439 -282.028828)
			(xy 391.053421 -281.983858) (xy 391.079316 -281.94248) (xy 391.111464 -281.905749) (xy 391.149047 -281.8746)
			(xy 391.191106 -281.849827) (xy 391.23657 -281.832061) (xy 391.26033 -281.826462) (xy 391.271499 -281.823474)
			(xy 391.289675 -281.809223) (xy 391.299829 -281.788478) (xy 391.300462 -281.776932) (xy 391.300462 -281.523186)
			(xy 391.299888 -281.5116) (xy 391.289741 -281.490765) (xy 391.271528 -281.476435) (xy 391.26033 -281.473402)
			(xy 391.23658 -281.467781) (xy 391.191124 -281.450017) (xy 391.149074 -281.425248) (xy 391.1115 -281.394104)
			(xy 391.079359 -281.357379) (xy 391.05347 -281.316009) (xy 391.034492 -281.271046) (xy 391.022909 -281.223638)
			(xy 391.019017 -281.17499) (xy 391.022913 -281.126342) (xy 391.034499 -281.078934) (xy 391.053479 -281.033973)
			(xy 391.079371 -280.992605) (xy 391.111514 -280.955882) (xy 391.149091 -280.924741) (xy 391.191143 -280.899974)
			(xy 391.236599 -280.882213) (xy 391.26033 -280.876502) (xy 391.271503 -280.873516) (xy 391.28969 -280.859267)
			(xy 391.29986 -280.838521) (xy 391.300462 -280.826972) (xy 391.300462 -280.572972) (xy 391.299885 -280.561388)
			(xy 391.289736 -280.540558) (xy 391.271523 -280.526233) (xy 391.26033 -280.523188) (xy 391.236573 -280.517567)
			(xy 391.191104 -280.499801) (xy 391.149041 -280.475027) (xy 391.111454 -280.443877) (xy 391.079302 -280.407144)
			(xy 391.053404 -280.365764) (xy 391.034418 -280.32079) (xy 391.022829 -280.273369) (xy 391.018932 -280.224708)
			(xy 391.022827 -280.176047) (xy 391.034413 -280.128625) (xy 391.053396 -280.083651) (xy 391.079293 -280.042269)
			(xy 391.111443 -280.005534) (xy 391.149027 -279.974382) (xy 391.19109 -279.949606) (xy 391.236558 -279.931838)
			(xy 391.26033 -279.926288) (xy 391.271501 -279.923301) (xy 391.289685 -279.909052) (xy 391.299849 -279.888306)
			(xy 391.300462 -279.876758) (xy 391.300462 -279.623012) (xy 391.299893 -279.611422) (xy 391.289751 -279.590577)
			(xy 391.271536 -279.576239) (xy 391.26033 -279.573228) (xy 391.236578 -279.567607) (xy 391.191118 -279.549842)
			(xy 391.149064 -279.525072) (xy 391.111486 -279.493926) (xy 391.079342 -279.457199) (xy 391.05345 -279.415825)
			(xy 391.03447 -279.37086) (xy 391.022885 -279.323447) (xy 391.018991 -279.274795) (xy 391.022887 -279.226144)
			(xy 391.034473 -279.178732) (xy 391.053454 -279.133766) (xy 391.079347 -279.092394) (xy 391.111493 -279.055668)
			(xy 391.149071 -279.024523) (xy 391.191127 -278.999754) (xy 391.236587 -278.98199) (xy 391.26033 -278.976328)
			(xy 391.271506 -278.973343) (xy 391.2897 -278.959096) (xy 391.29988 -278.938349) (xy 391.300462 -278.926798)
			(xy 391.300462 -278.673052) (xy 391.299901 -278.661457) (xy 391.289767 -278.640596) (xy 391.271549 -278.626245)
			(xy 391.26033 -278.623268) (xy 391.236575 -278.617647) (xy 391.191109 -278.599881) (xy 391.149048 -278.575108)
			(xy 391.111465 -278.54396) (xy 391.079315 -278.507229) (xy 391.053419 -278.465851) (xy 391.034435 -278.42088)
			(xy 391.022848 -278.373462) (xy 391.018952 -278.324804) (xy 391.022847 -278.276146) (xy 391.034433 -278.228727)
			(xy 391.053415 -278.183756) (xy 391.079311 -278.142377) (xy 391.111459 -278.105645) (xy 391.149042 -278.074496)
			(xy 391.191102 -278.049722) (xy 391.236567 -278.031955) (xy 391.26033 -278.026368) (xy 391.271499 -278.02338)
			(xy 391.289677 -278.009129) (xy 391.299834 -277.988384) (xy 391.300462 -277.976838) (xy 391.300462 -277.723092)
			(xy 391.299889 -277.711505) (xy 391.289743 -277.690668) (xy 391.27153 -277.676336) (xy 391.26033 -277.673308)
			(xy 391.236579 -277.667687) (xy 391.191123 -277.649923) (xy 391.149072 -277.625153) (xy 391.111497 -277.594009)
			(xy 391.079355 -277.557284) (xy 391.053465 -277.515912) (xy 391.034487 -277.470949) (xy 391.022904 -277.42354)
			(xy 391.019011 -277.374891) (xy 391.022907 -277.326243) (xy 391.034493 -277.278834) (xy 391.053473 -277.233872)
			(xy 391.079365 -277.192502) (xy 391.111509 -277.155779) (xy 391.149086 -277.124637) (xy 391.191139 -277.099869)
			(xy 391.236596 -277.082108) (xy 391.26033 -277.076408) (xy 391.271503 -277.073422) (xy 391.289692 -277.059173)
			(xy 391.299864 -277.038428) (xy 391.300462 -277.026878) (xy 391.300462 -276.773132) (xy 391.299897 -276.761539)
			(xy 391.289759 -276.740687) (xy 391.271542 -276.726342) (xy 391.26033 -276.723348) (xy 391.236576 -276.717727)
			(xy 391.191113 -276.699962) (xy 391.149056 -276.67519) (xy 391.111475 -276.644043) (xy 391.079328 -276.607314)
			(xy 391.053434 -276.565938) (xy 391.034453 -276.52097) (xy 391.022867 -276.473554) (xy 391.018972 -276.4249)
			(xy 391.022867 -276.376245) (xy 391.034453 -276.328829) (xy 391.053435 -276.283861) (xy 391.079329 -276.242486)
			(xy 391.111476 -276.205756) (xy 391.149057 -276.174609) (xy 391.191114 -276.149838) (xy 391.236577 -276.132073)
			(xy 391.26033 -276.126448) (xy 391.271508 -276.123464) (xy 391.289708 -276.109218) (xy 391.299895 -276.088471)
			(xy 391.300462 -276.076918) (xy 391.300462 -275.823172) (xy 391.299885 -275.811588) (xy 391.289736 -275.790758)
			(xy 391.271523 -275.776433) (xy 391.26033 -275.773388) (xy 391.236573 -275.767767) (xy 391.191104 -275.750001)
			(xy 391.149041 -275.725227) (xy 391.111454 -275.694077) (xy 391.079302 -275.657344) (xy 391.053404 -275.615964)
			(xy 391.034418 -275.57099) (xy 391.022829 -275.523569) (xy 391.018932 -275.474908) (xy 391.022827 -275.426247)
			(xy 391.034413 -275.378825) (xy 391.053396 -275.333851) (xy 391.079293 -275.292469) (xy 391.111443 -275.255734)
			(xy 391.149027 -275.224582) (xy 391.19109 -275.199806) (xy 391.236558 -275.182038) (xy 391.26033 -275.176488)
			(xy 391.271501 -275.173501) (xy 391.289685 -275.159252) (xy 391.299849 -275.138506) (xy 391.300462 -275.126958)
			(xy 391.300462 -274.873212) (xy 391.299893 -274.861622) (xy 391.289751 -274.840777) (xy 391.271536 -274.826439)
			(xy 391.26033 -274.823428) (xy 391.236578 -274.817807) (xy 391.191118 -274.800042) (xy 391.149064 -274.775272)
			(xy 391.111486 -274.744126) (xy 391.079342 -274.707399) (xy 391.05345 -274.666025) (xy 391.03447 -274.62106)
			(xy 391.022885 -274.573647) (xy 391.018991 -274.524995) (xy 391.022887 -274.476344) (xy 391.034473 -274.428932)
			(xy 391.053454 -274.383966) (xy 391.079347 -274.342594) (xy 391.111493 -274.305868) (xy 391.149071 -274.274723)
			(xy 391.191127 -274.249954) (xy 391.236587 -274.23219) (xy 391.26033 -274.226528) (xy 391.271506 -274.223543)
			(xy 391.2897 -274.209296) (xy 391.29988 -274.188549) (xy 391.300462 -274.176998) (xy 391.300462 -273.922998)
			(xy 391.299891 -273.91141) (xy 391.289746 -273.890571) (xy 391.271531 -273.876237) (xy 391.26033 -273.873214)
			(xy 391.236579 -273.867593) (xy 391.191122 -273.849829) (xy 391.149069 -273.825059) (xy 391.111493 -273.793914)
			(xy 391.079351 -273.757188) (xy 391.053461 -273.715816) (xy 391.034482 -273.670852) (xy 391.022898 -273.623442)
			(xy 391.019005 -273.574792) (xy 391.022901 -273.526143) (xy 391.034487 -273.478733) (xy 391.053468 -273.43377)
			(xy 391.07936 -273.3924) (xy 391.111504 -273.355675) (xy 391.149082 -273.324533) (xy 391.191135 -273.299765)
			(xy 391.236593 -273.282003) (xy 391.26033 -273.276314) (xy 391.271504 -273.273329) (xy 391.289695 -273.25908)
			(xy 391.299869 -273.238334) (xy 391.300462 -273.226784) (xy 391.300462 -272.973038) (xy 391.299898 -272.961445)
			(xy 391.289761 -272.94059) (xy 391.271544 -272.926243) (xy 391.26033 -272.923254) (xy 391.236576 -272.917633)
			(xy 391.191112 -272.899868) (xy 391.149054 -272.875096) (xy 391.111472 -272.843948) (xy 391.079325 -272.807218)
			(xy 391.05343 -272.765842) (xy 391.034447 -272.720873) (xy 391.022861 -272.673457) (xy 391.018966 -272.624801)
			(xy 391.022861 -272.576145) (xy 391.034447 -272.528729) (xy 391.053429 -272.48376) (xy 391.079324 -272.442383)
			(xy 391.111471 -272.405653) (xy 391.149052 -272.374505) (xy 391.191111 -272.349733) (xy 391.236574 -272.331968)
			(xy 391.26033 -272.326354) (xy 391.271498 -272.323366) (xy 391.289672 -272.309114) (xy 391.299823 -272.288369)
			(xy 391.300462 -272.276824) (xy 391.300462 -271.861788) (xy 391.300036 -271.85172) (xy 391.292314 -271.833122)
			(xy 391.285476 -271.82572) (xy 390.3599 -270.900144) (xy 390.353062 -270.892742) (xy 390.345348 -270.874144)
			(xy 390.344914 -270.864076) (xy 390.344914 -258.382516) (xy 390.344476 -258.372452) (xy 390.336742 -258.353869)
			(xy 390.329928 -258.346448) (xy 389.655812 -257.672332) (xy 389.648975 -257.66493) (xy 389.641264 -257.646332)
			(xy 389.640826 -257.636264) (xy 389.640826 -253.151894) (xy 389.640403 -253.141824) (xy 389.63269 -253.123218)
			(xy 389.62584 -253.115826) (xy 388.853426 -252.343666) (xy 388.846027 -252.336824) (xy 388.827428 -252.329106)
			(xy 388.817358 -252.32868) (xy 373.11203 -252.32868) (xy 373.101965 -252.329115) (xy 373.083377 -252.336845)
			(xy 373.075962 -252.343666) (xy 372.514622 -252.904752) (xy 372.510812 -252.908816) (xy 372.501668 -252.9205)
			(xy 372.498366 -252.949456) (xy 372.546626 -253.049024) (xy 372.551416 -253.0578) (xy 372.56631 -253.07111)
			(xy 372.585142 -253.077766) (xy 372.59514 -253.077726) (xy 372.598188 -253.077472) (xy 372.599458 -253.077218)
			(xy 372.610029 -253.076131) (xy 372.63125 -253.074986) (xy 372.641876 -253.074932) (xy 372.642384 -253.074932)
			(xy 372.669632 -253.075417) (xy 372.723574 -253.08317) (xy 372.775863 -253.098521) (xy 372.825435 -253.121157)
			(xy 372.871282 -253.150618) (xy 372.912469 -253.186303) (xy 372.948158 -253.227486) (xy 372.977624 -253.27333)
			(xy 373.000265 -253.3229) (xy 373.015621 -253.375187) (xy 373.02338 -253.429128) (xy 373.023382 -253.45644)
			(xy 373.276366 -253.45644) (xy 373.280437 -253.400818) (xy 373.292563 -253.346381) (xy 373.312486 -253.29429)
			(xy 373.339782 -253.245655) (xy 373.373868 -253.201512) (xy 373.414017 -253.162803) (xy 373.459375 -253.130352)
			(xy 373.508975 -253.104851) (xy 373.561759 -253.086844) (xy 373.616602 -253.076714) (xy 373.672336 -253.074677)
			(xy 373.727773 -253.080777) (xy 373.78173 -253.094883) (xy 373.833059 -253.116695) (xy 373.880665 -253.145749)
			(xy 373.923533 -253.181424) (xy 373.96075 -253.222961) (xy 373.991523 -253.269474) (xy 374.015195 -253.319971)
			(xy 374.031263 -253.373378) (xy 374.039383 -253.428554) (xy 374.039892 -253.45644) (xy 374.039383 -253.484326)
			(xy 374.031263 -253.539502) (xy 374.015195 -253.592909) (xy 373.991523 -253.643406) (xy 373.96075 -253.689919)
			(xy 373.923533 -253.731456) (xy 373.880665 -253.767131) (xy 373.833059 -253.796185) (xy 373.78173 -253.817997)
			(xy 373.727773 -253.832103) (xy 373.672336 -253.838203) (xy 373.616602 -253.836166) (xy 373.561759 -253.826036)
			(xy 373.508975 -253.808029) (xy 373.459375 -253.782528) (xy 373.414017 -253.750077) (xy 373.373868 -253.711368)
			(xy 373.339782 -253.667225) (xy 373.312486 -253.61859) (xy 373.292563 -253.566499) (xy 373.280437 -253.512062)
			(xy 373.276366 -253.45644) (xy 373.023382 -253.45644) (xy 373.023384 -253.483624) (xy 373.015631 -253.537566)
			(xy 373.000282 -253.589855) (xy 372.977647 -253.639428) (xy 372.948187 -253.685275) (xy 372.912503 -253.726463)
			(xy 372.87132 -253.762153) (xy 372.825477 -253.79162) (xy 372.775908 -253.814262) (xy 372.723621 -253.82962)
			(xy 372.66968 -253.83738) (xy 372.615184 -253.837384) (xy 372.561242 -253.829633) (xy 372.508952 -253.814284)
			(xy 372.459379 -253.79165) (xy 372.413531 -253.762192) (xy 372.372343 -253.726508) (xy 372.336651 -253.685327)
			(xy 372.307184 -253.639484) (xy 372.284541 -253.589915) (xy 372.269182 -253.537628) (xy 372.261421 -253.483688)
			(xy 372.260876 -253.45644) (xy 372.260876 -253.455932) (xy 372.260927 -253.445306) (xy 372.26207 -253.424084)
			(xy 372.263162 -253.413514) (xy 372.263416 -253.412244) (xy 372.26367 -253.409196) (xy 372.263819 -253.399175)
			(xy 372.257198 -253.380277) (xy 372.243824 -253.365371) (xy 372.234968 -253.360682) (xy 372.148862 -253.318772)
			(xy 372.139149 -253.314654) (xy 372.11809 -253.313851) (xy 372.098475 -253.321555) (xy 372.090696 -253.328678)
			(xy 371.800628 -253.618746) (xy 371.793786 -253.626146) (xy 371.786064 -253.644744) (xy 371.785642 -253.654814)
			(xy 371.785642 -255.473454) (xy 371.786912 -255.484884) (xy 371.790722 -255.501394) (xy 371.793008 -255.50622)
			(xy 371.797682 -255.516539) (xy 371.80594 -255.537636) (xy 371.809518 -255.548384) (xy 371.811804 -255.555496)
			(xy 371.824504 -255.573784) (xy 371.83065 -255.582055) (xy 371.847959 -255.593199) (xy 371.858032 -255.595374)
			(xy 371.868192 -255.596898) (xy 371.88775 -255.592326) (xy 371.900196 -255.582928) (xy 371.903281 -255.580576)
			(xy 371.908767 -255.575091) (xy 371.911118 -255.572006) (xy 371.91569 -255.56591) (xy 371.91823 -255.558798)
			(xy 371.9287 -255.531536) (xy 371.956726 -255.480306) (xy 371.992225 -255.43394) (xy 372.034371 -255.39352)
			(xy 372.08218 -255.359989) (xy 372.134537 -255.334129) (xy 372.190221 -255.316542) (xy 372.247934 -255.30764)
			(xy 372.277132 -255.307084) (xy 372.304382 -255.307572) (xy 372.358328 -255.315332) (xy 372.41062 -255.330691)
			(xy 372.460194 -255.353334) (xy 372.506041 -255.382802) (xy 372.547229 -255.418494) (xy 372.582917 -255.459684)
			(xy 372.612381 -255.505534) (xy 372.635021 -255.55511) (xy 372.650374 -255.607404) (xy 372.65813 -255.66135)
			(xy 372.65813 -255.71585) (xy 372.650374 -255.769796) (xy 372.635021 -255.82209) (xy 372.612381 -255.871666)
			(xy 372.582917 -255.917516) (xy 372.547229 -255.958706) (xy 372.506041 -255.994398) (xy 372.460194 -256.023866)
			(xy 372.41062 -256.046509) (xy 372.358328 -256.061868) (xy 372.304382 -256.069628) (xy 372.277132 -256.0701)
			(xy 372.250083 -256.069631) (xy 372.196528 -256.061993) (xy 372.144588 -256.046867) (xy 372.095306 -256.024555)
			(xy 372.04967 -255.995504) (xy 372.008596 -255.960299) (xy 371.972907 -255.919644) (xy 371.943319 -255.874355)
			(xy 371.920426 -255.82534) (xy 371.912134 -255.79959) (xy 371.912134 -255.799082) (xy 371.909523 -255.791728)
			(xy 371.9006 -255.778935) (xy 371.894608 -255.773936) (xy 371.88902 -255.769618) (xy 371.880025 -255.76333)
			(xy 371.858669 -255.758369) (xy 371.837192 -255.762771) (xy 371.82806 -255.768856) (xy 371.827806 -255.768856)
			(xy 371.817138 -255.776476) (xy 371.807994 -255.788414) (xy 371.805454 -255.79578) (xy 371.793008 -255.826514)
			(xy 371.790722 -255.83134) (xy 371.786912 -255.847596) (xy 371.785642 -255.859026) (xy 371.785642 -258.282694)
			(xy 371.785987 -258.2913) (xy 371.791684 -258.307544) (xy 371.802412 -258.321007) (xy 371.809518 -258.325874)
			(xy 371.832771 -258.340893) (xy 371.875085 -258.376579) (xy 371.9118 -258.418005) (xy 371.942145 -258.464299)
			(xy 371.965484 -258.514492) (xy 371.981327 -258.567531) (xy 371.989341 -258.622301) (xy 371.989858 -258.649978)
			(xy 371.989661 -258.666963) (xy 371.987479 -258.691126) (xy 372.710708 -258.691126) (xy 372.714779 -258.635504)
			(xy 372.726905 -258.581067) (xy 372.746828 -258.528976) (xy 372.774124 -258.480341) (xy 372.80821 -258.436198)
			(xy 372.848359 -258.397489) (xy 372.893717 -258.365038) (xy 372.943317 -258.339537) (xy 372.996101 -258.32153)
			(xy 373.050944 -258.3114) (xy 373.106678 -258.309363) (xy 373.162115 -258.315463) (xy 373.216072 -258.329569)
			(xy 373.267401 -258.351381) (xy 373.315007 -258.380435) (xy 373.357875 -258.41611) (xy 373.395092 -258.457647)
			(xy 373.425865 -258.50416) (xy 373.449537 -258.554657) (xy 373.465605 -258.608064) (xy 373.473725 -258.66324)
			(xy 373.474234 -258.691126) (xy 373.473725 -258.719012) (xy 373.465605 -258.774188) (xy 373.449537 -258.827595)
			(xy 373.425865 -258.878092) (xy 373.395092 -258.924605) (xy 373.357875 -258.966142) (xy 373.315007 -259.001817)
			(xy 373.267401 -259.030871) (xy 373.216072 -259.052683) (xy 373.162115 -259.066789) (xy 373.106678 -259.072889)
			(xy 373.050944 -259.070852) (xy 372.996101 -259.060722) (xy 372.943317 -259.042715) (xy 372.893717 -259.017214)
			(xy 372.848359 -258.984763) (xy 372.80821 -258.946054) (xy 372.774124 -258.901911) (xy 372.746828 -258.853276)
			(xy 372.726905 -258.801185) (xy 372.714779 -258.746748) (xy 372.710708 -258.691126) (xy 371.987479 -258.691126)
			(xy 371.986606 -258.700796) (xy 371.983762 -258.717542) (xy 371.982261 -258.729775) (xy 371.989564 -258.753271)
			(xy 371.997732 -258.7625) (xy 372.939818 -259.704586) (xy 372.94666 -259.711985) (xy 372.954376 -259.730584)
			(xy 372.954804 -259.740654) (xy 372.954804 -261.347966) (xy 372.955278 -261.357323) (xy 372.962051 -261.374774)
			(xy 372.968012 -261.382002) (xy 372.987824 -261.403846) (xy 372.99408 -261.410181) (xy 373.0098 -261.418509)
			(xy 373.018558 -261.420102) (xy 373.045593 -261.424316) (xy 373.098165 -261.439477) (xy 373.148031 -261.461993)
			(xy 373.19417 -261.491402) (xy 373.235634 -261.527101) (xy 373.271572 -261.568357) (xy 373.301248 -261.614324)
			(xy 373.324053 -261.664059) (xy 373.339518 -261.716543) (xy 373.347327 -261.770697) (xy 373.347742 -261.798054)
			(xy 373.347198 -261.827157) (xy 373.338369 -261.884689) (xy 373.320908 -261.940214) (xy 373.295221 -261.992444)
			(xy 373.261902 -262.04017) (xy 373.221724 -262.082285) (xy 373.175619 -262.117812) (xy 373.150384 -262.132318)
			(xy 373.149876 -262.132318) (xy 373.149876 -262.132572) (xy 373.144986 -262.135457) (xy 373.136522 -262.143019)
			(xy 373.133112 -262.147558) (xy 373.132858 -262.147812) (xy 373.129576 -262.152761) (xy 373.125209 -262.1638)
			(xy 373.124222 -262.169656) (xy 373.112792 -262.250174) (xy 373.111712 -262.261657) (xy 373.118713 -262.283612)
			(xy 373.126254 -262.292338) (xy 373.126762 -262.292846) (xy 373.203978 -262.370062) (xy 373.204486 -262.37057)
			(xy 373.21187 -262.377146) (xy 373.230169 -262.384581) (xy 373.240046 -262.385048) (xy 375.197116 -262.385048)
			(xy 375.206994 -262.38459) (xy 375.225298 -262.377152) (xy 375.232676 -262.37057) (xy 375.23293 -262.370316)
			(xy 375.379234 -262.224012) (xy 375.379742 -262.223504) (xy 375.386319 -262.216121) (xy 375.393755 -262.197822)
			(xy 375.39422 -262.187944) (xy 375.39422 -259.82168) (xy 375.393794 -259.811611) (xy 375.386077 -259.79301)
			(xy 375.379234 -259.785612) (xy 373.796052 -258.20243) (xy 373.796052 -258.199128) (xy 373.789956 -258.191254)
			(xy 373.785384 -258.18592) (xy 373.775224 -258.17576) (xy 373.775224 -258.133596) (xy 373.785384 -258.123436)
			(xy 373.789956 -258.118102) (xy 373.796052 -258.110228) (xy 373.796052 -254.700786) (xy 373.796479 -254.690718)
			(xy 373.804203 -254.672122) (xy 373.811038 -254.664718) (xy 373.835676 -254.640334) (xy 373.835676 -254.639572)
			(xy 374.520206 -253.955042) (xy 374.528159 -253.94614) (xy 374.535594 -253.923487) (xy 374.53443 -253.911608)
			(xy 374.52046 -253.818644) (xy 374.50649 -253.799086) (xy 374.495822 -253.793498) (xy 374.469965 -253.779193)
			(xy 374.42262 -253.743837) (xy 374.381299 -253.701596) (xy 374.346993 -253.653484) (xy 374.320524 -253.600654)
			(xy 374.302526 -253.544371) (xy 374.29343 -253.485985) (xy 374.292876 -253.45644) (xy 374.293362 -253.429189)
			(xy 374.301118 -253.375241) (xy 374.316473 -253.322946) (xy 374.339115 -253.273369) (xy 374.368581 -253.227519)
			(xy 374.404272 -253.186328) (xy 374.445463 -253.150637) (xy 374.491313 -253.121171) (xy 374.54089 -253.098529)
			(xy 374.593185 -253.083174) (xy 374.647133 -253.075418) (xy 374.701635 -253.075418) (xy 374.755583 -253.083174)
			(xy 374.807878 -253.098529) (xy 374.857455 -253.121171) (xy 374.903305 -253.150637) (xy 374.944496 -253.186328)
			(xy 374.980187 -253.227519) (xy 375.009653 -253.273369) (xy 375.032295 -253.322946) (xy 375.04765 -253.375241)
			(xy 375.055406 -253.429189) (xy 375.055892 -253.45644) (xy 375.308366 -253.45644) (xy 375.312437 -253.400818)
			(xy 375.324563 -253.346381) (xy 375.344486 -253.29429) (xy 375.371782 -253.245655) (xy 375.405868 -253.201512)
			(xy 375.446017 -253.162803) (xy 375.491375 -253.130352) (xy 375.540975 -253.104851) (xy 375.593759 -253.086844)
			(xy 375.648602 -253.076714) (xy 375.704336 -253.074677) (xy 375.759773 -253.080777) (xy 375.81373 -253.094883)
			(xy 375.865059 -253.116695) (xy 375.912665 -253.145749) (xy 375.955533 -253.181424) (xy 375.99275 -253.222961)
			(xy 376.023523 -253.269474) (xy 376.047195 -253.319971) (xy 376.063263 -253.373378) (xy 376.071383 -253.428554)
			(xy 376.071892 -253.45644) (xy 376.324366 -253.45644) (xy 376.328437 -253.400818) (xy 376.340563 -253.346381)
			(xy 376.360486 -253.29429) (xy 376.387782 -253.245655) (xy 376.421868 -253.201512) (xy 376.462017 -253.162803)
			(xy 376.507375 -253.130352) (xy 376.556975 -253.104851) (xy 376.609759 -253.086844) (xy 376.664602 -253.076714)
			(xy 376.720336 -253.074677) (xy 376.775773 -253.080777) (xy 376.82973 -253.094883) (xy 376.881059 -253.116695)
			(xy 376.928665 -253.145749) (xy 376.971533 -253.181424) (xy 377.00875 -253.222961) (xy 377.039523 -253.269474)
			(xy 377.063195 -253.319971) (xy 377.079263 -253.373378) (xy 377.087383 -253.428554) (xy 377.087892 -253.45644)
			(xy 377.340366 -253.45644) (xy 377.344437 -253.400818) (xy 377.356563 -253.346381) (xy 377.376486 -253.29429)
			(xy 377.403782 -253.245655) (xy 377.437868 -253.201512) (xy 377.478017 -253.162803) (xy 377.523375 -253.130352)
			(xy 377.572975 -253.104851) (xy 377.625759 -253.086844) (xy 377.680602 -253.076714) (xy 377.736336 -253.074677)
			(xy 377.791773 -253.080777) (xy 377.84573 -253.094883) (xy 377.897059 -253.116695) (xy 377.944665 -253.145749)
			(xy 377.987533 -253.181424) (xy 378.02475 -253.222961) (xy 378.055523 -253.269474) (xy 378.079195 -253.319971)
			(xy 378.095263 -253.373378) (xy 378.103383 -253.428554) (xy 378.103892 -253.45644) (xy 378.356366 -253.45644)
			(xy 378.360437 -253.400818) (xy 378.372563 -253.346381) (xy 378.392486 -253.29429) (xy 378.419782 -253.245655)
			(xy 378.453868 -253.201512) (xy 378.494017 -253.162803) (xy 378.539375 -253.130352) (xy 378.588975 -253.104851)
			(xy 378.641759 -253.086844) (xy 378.696602 -253.076714) (xy 378.752336 -253.074677) (xy 378.807773 -253.080777)
			(xy 378.86173 -253.094883) (xy 378.913059 -253.116695) (xy 378.960665 -253.145749) (xy 379.003533 -253.181424)
			(xy 379.04075 -253.222961) (xy 379.071523 -253.269474) (xy 379.095195 -253.319971) (xy 379.111263 -253.373378)
			(xy 379.119383 -253.428554) (xy 379.119892 -253.45644) (xy 379.372366 -253.45644) (xy 379.376437 -253.400818)
			(xy 379.388563 -253.346381) (xy 379.408486 -253.29429) (xy 379.435782 -253.245655) (xy 379.469868 -253.201512)
			(xy 379.510017 -253.162803) (xy 379.555375 -253.130352) (xy 379.604975 -253.104851) (xy 379.657759 -253.086844)
			(xy 379.712602 -253.076714) (xy 379.768336 -253.074677) (xy 379.823773 -253.080777) (xy 379.87773 -253.094883)
			(xy 379.929059 -253.116695) (xy 379.976665 -253.145749) (xy 380.019533 -253.181424) (xy 380.05675 -253.222961)
			(xy 380.087523 -253.269474) (xy 380.111195 -253.319971) (xy 380.127263 -253.373378) (xy 380.135383 -253.428554)
			(xy 380.135892 -253.45644) (xy 380.388366 -253.45644) (xy 380.392437 -253.400818) (xy 380.404563 -253.346381)
			(xy 380.424486 -253.29429) (xy 380.451782 -253.245655) (xy 380.485868 -253.201512) (xy 380.526017 -253.162803)
			(xy 380.571375 -253.130352) (xy 380.620975 -253.104851) (xy 380.673759 -253.086844) (xy 380.728602 -253.076714)
			(xy 380.784336 -253.074677) (xy 380.839773 -253.080777) (xy 380.89373 -253.094883) (xy 380.945059 -253.116695)
			(xy 380.992665 -253.145749) (xy 381.035533 -253.181424) (xy 381.07275 -253.222961) (xy 381.103523 -253.269474)
			(xy 381.127195 -253.319971) (xy 381.143263 -253.373378) (xy 381.151383 -253.428554) (xy 381.151892 -253.45644)
			(xy 381.404366 -253.45644) (xy 381.408437 -253.400818) (xy 381.420563 -253.346381) (xy 381.440486 -253.29429)
			(xy 381.467782 -253.245655) (xy 381.501868 -253.201512) (xy 381.542017 -253.162803) (xy 381.587375 -253.130352)
			(xy 381.636975 -253.104851) (xy 381.689759 -253.086844) (xy 381.744602 -253.076714) (xy 381.800336 -253.074677)
			(xy 381.855773 -253.080777) (xy 381.90973 -253.094883) (xy 381.961059 -253.116695) (xy 382.008665 -253.145749)
			(xy 382.051533 -253.181424) (xy 382.08875 -253.222961) (xy 382.119523 -253.269474) (xy 382.143195 -253.319971)
			(xy 382.159263 -253.373378) (xy 382.167383 -253.428554) (xy 382.167892 -253.45644) (xy 382.420366 -253.45644)
			(xy 382.424437 -253.400818) (xy 382.436563 -253.346381) (xy 382.456486 -253.29429) (xy 382.483782 -253.245655)
			(xy 382.517868 -253.201512) (xy 382.558017 -253.162803) (xy 382.603375 -253.130352) (xy 382.652975 -253.104851)
			(xy 382.705759 -253.086844) (xy 382.760602 -253.076714) (xy 382.816336 -253.074677) (xy 382.871773 -253.080777)
			(xy 382.92573 -253.094883) (xy 382.977059 -253.116695) (xy 383.024665 -253.145749) (xy 383.067533 -253.181424)
			(xy 383.10475 -253.222961) (xy 383.135523 -253.269474) (xy 383.159195 -253.319971) (xy 383.175263 -253.373378)
			(xy 383.183383 -253.428554) (xy 383.183892 -253.45644) (xy 383.436366 -253.45644) (xy 383.440437 -253.400818)
			(xy 383.452563 -253.346381) (xy 383.472486 -253.29429) (xy 383.499782 -253.245655) (xy 383.533868 -253.201512)
			(xy 383.574017 -253.162803) (xy 383.619375 -253.130352) (xy 383.668975 -253.104851) (xy 383.721759 -253.086844)
			(xy 383.776602 -253.076714) (xy 383.832336 -253.074677) (xy 383.887773 -253.080777) (xy 383.94173 -253.094883)
			(xy 383.993059 -253.116695) (xy 384.040665 -253.145749) (xy 384.083533 -253.181424) (xy 384.12075 -253.222961)
			(xy 384.151523 -253.269474) (xy 384.175195 -253.319971) (xy 384.191263 -253.373378) (xy 384.199383 -253.428554)
			(xy 384.199892 -253.45644) (xy 384.452366 -253.45644) (xy 384.456437 -253.400818) (xy 384.468563 -253.346381)
			(xy 384.488486 -253.29429) (xy 384.515782 -253.245655) (xy 384.549868 -253.201512) (xy 384.590017 -253.162803)
			(xy 384.635375 -253.130352) (xy 384.684975 -253.104851) (xy 384.737759 -253.086844) (xy 384.792602 -253.076714)
			(xy 384.848336 -253.074677) (xy 384.903773 -253.080777) (xy 384.95773 -253.094883) (xy 385.009059 -253.116695)
			(xy 385.056665 -253.145749) (xy 385.099533 -253.181424) (xy 385.13675 -253.222961) (xy 385.167523 -253.269474)
			(xy 385.191195 -253.319971) (xy 385.207263 -253.373378) (xy 385.215383 -253.428554) (xy 385.215892 -253.45644)
			(xy 385.468366 -253.45644) (xy 385.472437 -253.400818) (xy 385.484563 -253.346381) (xy 385.504486 -253.29429)
			(xy 385.531782 -253.245655) (xy 385.565868 -253.201512) (xy 385.606017 -253.162803) (xy 385.651375 -253.130352)
			(xy 385.700975 -253.104851) (xy 385.753759 -253.086844) (xy 385.808602 -253.076714) (xy 385.864336 -253.074677)
			(xy 385.919773 -253.080777) (xy 385.97373 -253.094883) (xy 386.025059 -253.116695) (xy 386.072665 -253.145749)
			(xy 386.115533 -253.181424) (xy 386.15275 -253.222961) (xy 386.183523 -253.269474) (xy 386.207195 -253.319971)
			(xy 386.223263 -253.373378) (xy 386.231383 -253.428554) (xy 386.231892 -253.45644) (xy 386.484366 -253.45644)
			(xy 386.488437 -253.400818) (xy 386.500563 -253.346381) (xy 386.520486 -253.29429) (xy 386.547782 -253.245655)
			(xy 386.581868 -253.201512) (xy 386.622017 -253.162803) (xy 386.667375 -253.130352) (xy 386.716975 -253.104851)
			(xy 386.769759 -253.086844) (xy 386.824602 -253.076714) (xy 386.880336 -253.074677) (xy 386.935773 -253.080777)
			(xy 386.98973 -253.094883) (xy 387.041059 -253.116695) (xy 387.088665 -253.145749) (xy 387.131533 -253.181424)
			(xy 387.16875 -253.222961) (xy 387.199523 -253.269474) (xy 387.223195 -253.319971) (xy 387.239263 -253.373378)
			(xy 387.247383 -253.428554) (xy 387.247892 -253.45644) (xy 387.500366 -253.45644) (xy 387.504437 -253.400818)
			(xy 387.516563 -253.346381) (xy 387.536486 -253.29429) (xy 387.563782 -253.245655) (xy 387.597868 -253.201512)
			(xy 387.638017 -253.162803) (xy 387.683375 -253.130352) (xy 387.732975 -253.104851) (xy 387.785759 -253.086844)
			(xy 387.840602 -253.076714) (xy 387.896336 -253.074677) (xy 387.951773 -253.080777) (xy 388.00573 -253.094883)
			(xy 388.057059 -253.116695) (xy 388.104665 -253.145749) (xy 388.147533 -253.181424) (xy 388.18475 -253.222961)
			(xy 388.215523 -253.269474) (xy 388.239195 -253.319971) (xy 388.255263 -253.373378) (xy 388.263383 -253.428554)
			(xy 388.263892 -253.45644) (xy 388.516366 -253.45644) (xy 388.520437 -253.400818) (xy 388.532563 -253.346381)
			(xy 388.552486 -253.29429) (xy 388.579782 -253.245655) (xy 388.613868 -253.201512) (xy 388.654017 -253.162803)
			(xy 388.699375 -253.130352) (xy 388.748975 -253.104851) (xy 388.801759 -253.086844) (xy 388.856602 -253.076714)
			(xy 388.912336 -253.074677) (xy 388.967773 -253.080777) (xy 389.02173 -253.094883) (xy 389.073059 -253.116695)
			(xy 389.120665 -253.145749) (xy 389.163533 -253.181424) (xy 389.20075 -253.222961) (xy 389.231523 -253.269474)
			(xy 389.255195 -253.319971) (xy 389.271263 -253.373378) (xy 389.279383 -253.428554) (xy 389.279892 -253.45644)
			(xy 389.279383 -253.484326) (xy 389.271263 -253.539502) (xy 389.255195 -253.592909) (xy 389.231523 -253.643406)
			(xy 389.20075 -253.689919) (xy 389.163533 -253.731456) (xy 389.120665 -253.767131) (xy 389.073059 -253.796185)
			(xy 389.02173 -253.817997) (xy 388.967773 -253.832103) (xy 388.912336 -253.838203) (xy 388.856602 -253.836166)
			(xy 388.801759 -253.826036) (xy 388.748975 -253.808029) (xy 388.699375 -253.782528) (xy 388.654017 -253.750077)
			(xy 388.613868 -253.711368) (xy 388.579782 -253.667225) (xy 388.552486 -253.61859) (xy 388.532563 -253.566499)
			(xy 388.520437 -253.512062) (xy 388.516366 -253.45644) (xy 388.263892 -253.45644) (xy 388.263383 -253.484326)
			(xy 388.255263 -253.539502) (xy 388.239195 -253.592909) (xy 388.215523 -253.643406) (xy 388.18475 -253.689919)
			(xy 388.147533 -253.731456) (xy 388.104665 -253.767131) (xy 388.057059 -253.796185) (xy 388.00573 -253.817997)
			(xy 387.951773 -253.832103) (xy 387.896336 -253.838203) (xy 387.840602 -253.836166) (xy 387.785759 -253.826036)
			(xy 387.732975 -253.808029) (xy 387.683375 -253.782528) (xy 387.638017 -253.750077) (xy 387.597868 -253.711368)
			(xy 387.563782 -253.667225) (xy 387.536486 -253.61859) (xy 387.516563 -253.566499) (xy 387.504437 -253.512062)
			(xy 387.500366 -253.45644) (xy 387.247892 -253.45644) (xy 387.247383 -253.484326) (xy 387.239263 -253.539502)
			(xy 387.223195 -253.592909) (xy 387.199523 -253.643406) (xy 387.16875 -253.689919) (xy 387.131533 -253.731456)
			(xy 387.088665 -253.767131) (xy 387.041059 -253.796185) (xy 386.98973 -253.817997) (xy 386.935773 -253.832103)
			(xy 386.880336 -253.838203) (xy 386.824602 -253.836166) (xy 386.769759 -253.826036) (xy 386.716975 -253.808029)
			(xy 386.667375 -253.782528) (xy 386.622017 -253.750077) (xy 386.581868 -253.711368) (xy 386.547782 -253.667225)
			(xy 386.520486 -253.61859) (xy 386.500563 -253.566499) (xy 386.488437 -253.512062) (xy 386.484366 -253.45644)
			(xy 386.231892 -253.45644) (xy 386.231383 -253.484326) (xy 386.223263 -253.539502) (xy 386.207195 -253.592909)
			(xy 386.183523 -253.643406) (xy 386.15275 -253.689919) (xy 386.115533 -253.731456) (xy 386.072665 -253.767131)
			(xy 386.025059 -253.796185) (xy 385.97373 -253.817997) (xy 385.919773 -253.832103) (xy 385.864336 -253.838203)
			(xy 385.808602 -253.836166) (xy 385.753759 -253.826036) (xy 385.700975 -253.808029) (xy 385.651375 -253.782528)
			(xy 385.606017 -253.750077) (xy 385.565868 -253.711368) (xy 385.531782 -253.667225) (xy 385.504486 -253.61859)
			(xy 385.484563 -253.566499) (xy 385.472437 -253.512062) (xy 385.468366 -253.45644) (xy 385.215892 -253.45644)
			(xy 385.215383 -253.484326) (xy 385.207263 -253.539502) (xy 385.191195 -253.592909) (xy 385.167523 -253.643406)
			(xy 385.13675 -253.689919) (xy 385.099533 -253.731456) (xy 385.056665 -253.767131) (xy 385.009059 -253.796185)
			(xy 384.95773 -253.817997) (xy 384.903773 -253.832103) (xy 384.848336 -253.838203) (xy 384.792602 -253.836166)
			(xy 384.737759 -253.826036) (xy 384.684975 -253.808029) (xy 384.635375 -253.782528) (xy 384.590017 -253.750077)
			(xy 384.549868 -253.711368) (xy 384.515782 -253.667225) (xy 384.488486 -253.61859) (xy 384.468563 -253.566499)
			(xy 384.456437 -253.512062) (xy 384.452366 -253.45644) (xy 384.199892 -253.45644) (xy 384.199383 -253.484326)
			(xy 384.191263 -253.539502) (xy 384.175195 -253.592909) (xy 384.151523 -253.643406) (xy 384.12075 -253.689919)
			(xy 384.083533 -253.731456) (xy 384.040665 -253.767131) (xy 383.993059 -253.796185) (xy 383.94173 -253.817997)
			(xy 383.887773 -253.832103) (xy 383.832336 -253.838203) (xy 383.776602 -253.836166) (xy 383.721759 -253.826036)
			(xy 383.668975 -253.808029) (xy 383.619375 -253.782528) (xy 383.574017 -253.750077) (xy 383.533868 -253.711368)
			(xy 383.499782 -253.667225) (xy 383.472486 -253.61859) (xy 383.452563 -253.566499) (xy 383.440437 -253.512062)
			(xy 383.436366 -253.45644) (xy 383.183892 -253.45644) (xy 383.183383 -253.484326) (xy 383.175263 -253.539502)
			(xy 383.159195 -253.592909) (xy 383.135523 -253.643406) (xy 383.10475 -253.689919) (xy 383.067533 -253.731456)
			(xy 383.024665 -253.767131) (xy 382.977059 -253.796185) (xy 382.92573 -253.817997) (xy 382.871773 -253.832103)
			(xy 382.816336 -253.838203) (xy 382.760602 -253.836166) (xy 382.705759 -253.826036) (xy 382.652975 -253.808029)
			(xy 382.603375 -253.782528) (xy 382.558017 -253.750077) (xy 382.517868 -253.711368) (xy 382.483782 -253.667225)
			(xy 382.456486 -253.61859) (xy 382.436563 -253.566499) (xy 382.424437 -253.512062) (xy 382.420366 -253.45644)
			(xy 382.167892 -253.45644) (xy 382.167383 -253.484326) (xy 382.159263 -253.539502) (xy 382.143195 -253.592909)
			(xy 382.119523 -253.643406) (xy 382.08875 -253.689919) (xy 382.051533 -253.731456) (xy 382.008665 -253.767131)
			(xy 381.961059 -253.796185) (xy 381.90973 -253.817997) (xy 381.855773 -253.832103) (xy 381.800336 -253.838203)
			(xy 381.744602 -253.836166) (xy 381.689759 -253.826036) (xy 381.636975 -253.808029) (xy 381.587375 -253.782528)
			(xy 381.542017 -253.750077) (xy 381.501868 -253.711368) (xy 381.467782 -253.667225) (xy 381.440486 -253.61859)
			(xy 381.420563 -253.566499) (xy 381.408437 -253.512062) (xy 381.404366 -253.45644) (xy 381.151892 -253.45644)
			(xy 381.151383 -253.484326) (xy 381.143263 -253.539502) (xy 381.127195 -253.592909) (xy 381.103523 -253.643406)
			(xy 381.07275 -253.689919) (xy 381.035533 -253.731456) (xy 380.992665 -253.767131) (xy 380.945059 -253.796185)
			(xy 380.89373 -253.817997) (xy 380.839773 -253.832103) (xy 380.784336 -253.838203) (xy 380.728602 -253.836166)
			(xy 380.673759 -253.826036) (xy 380.620975 -253.808029) (xy 380.571375 -253.782528) (xy 380.526017 -253.750077)
			(xy 380.485868 -253.711368) (xy 380.451782 -253.667225) (xy 380.424486 -253.61859) (xy 380.404563 -253.566499)
			(xy 380.392437 -253.512062) (xy 380.388366 -253.45644) (xy 380.135892 -253.45644) (xy 380.135383 -253.484326)
			(xy 380.127263 -253.539502) (xy 380.111195 -253.592909) (xy 380.087523 -253.643406) (xy 380.05675 -253.689919)
			(xy 380.019533 -253.731456) (xy 379.976665 -253.767131) (xy 379.929059 -253.796185) (xy 379.87773 -253.817997)
			(xy 379.823773 -253.832103) (xy 379.768336 -253.838203) (xy 379.712602 -253.836166) (xy 379.657759 -253.826036)
			(xy 379.604975 -253.808029) (xy 379.555375 -253.782528) (xy 379.510017 -253.750077) (xy 379.469868 -253.711368)
			(xy 379.435782 -253.667225) (xy 379.408486 -253.61859) (xy 379.388563 -253.566499) (xy 379.376437 -253.512062)
			(xy 379.372366 -253.45644) (xy 379.119892 -253.45644) (xy 379.119383 -253.484326) (xy 379.111263 -253.539502)
			(xy 379.095195 -253.592909) (xy 379.071523 -253.643406) (xy 379.04075 -253.689919) (xy 379.003533 -253.731456)
			(xy 378.960665 -253.767131) (xy 378.913059 -253.796185) (xy 378.86173 -253.817997) (xy 378.807773 -253.832103)
			(xy 378.752336 -253.838203) (xy 378.696602 -253.836166) (xy 378.641759 -253.826036) (xy 378.588975 -253.808029)
			(xy 378.539375 -253.782528) (xy 378.494017 -253.750077) (xy 378.453868 -253.711368) (xy 378.419782 -253.667225)
			(xy 378.392486 -253.61859) (xy 378.372563 -253.566499) (xy 378.360437 -253.512062) (xy 378.356366 -253.45644)
			(xy 378.103892 -253.45644) (xy 378.103383 -253.484326) (xy 378.095263 -253.539502) (xy 378.079195 -253.592909)
			(xy 378.055523 -253.643406) (xy 378.02475 -253.689919) (xy 377.987533 -253.731456) (xy 377.944665 -253.767131)
			(xy 377.897059 -253.796185) (xy 377.84573 -253.817997) (xy 377.791773 -253.832103) (xy 377.736336 -253.838203)
			(xy 377.680602 -253.836166) (xy 377.625759 -253.826036) (xy 377.572975 -253.808029) (xy 377.523375 -253.782528)
			(xy 377.478017 -253.750077) (xy 377.437868 -253.711368) (xy 377.403782 -253.667225) (xy 377.376486 -253.61859)
			(xy 377.356563 -253.566499) (xy 377.344437 -253.512062) (xy 377.340366 -253.45644) (xy 377.087892 -253.45644)
			(xy 377.087383 -253.484326) (xy 377.079263 -253.539502) (xy 377.063195 -253.592909) (xy 377.039523 -253.643406)
			(xy 377.00875 -253.689919) (xy 376.971533 -253.731456) (xy 376.928665 -253.767131) (xy 376.881059 -253.796185)
			(xy 376.82973 -253.817997) (xy 376.775773 -253.832103) (xy 376.720336 -253.838203) (xy 376.664602 -253.836166)
			(xy 376.609759 -253.826036) (xy 376.556975 -253.808029) (xy 376.507375 -253.782528) (xy 376.462017 -253.750077)
			(xy 376.421868 -253.711368) (xy 376.387782 -253.667225) (xy 376.360486 -253.61859) (xy 376.340563 -253.566499)
			(xy 376.328437 -253.512062) (xy 376.324366 -253.45644) (xy 376.071892 -253.45644) (xy 376.071383 -253.484326)
			(xy 376.063263 -253.539502) (xy 376.047195 -253.592909) (xy 376.023523 -253.643406) (xy 375.99275 -253.689919)
			(xy 375.955533 -253.731456) (xy 375.912665 -253.767131) (xy 375.865059 -253.796185) (xy 375.81373 -253.817997)
			(xy 375.759773 -253.832103) (xy 375.704336 -253.838203) (xy 375.648602 -253.836166) (xy 375.593759 -253.826036)
			(xy 375.540975 -253.808029) (xy 375.491375 -253.782528) (xy 375.446017 -253.750077) (xy 375.405868 -253.711368)
			(xy 375.371782 -253.667225) (xy 375.344486 -253.61859) (xy 375.324563 -253.566499) (xy 375.312437 -253.512062)
			(xy 375.308366 -253.45644) (xy 375.055892 -253.45644) (xy 375.055892 -253.456948) (xy 375.055447 -253.483076)
			(xy 375.048284 -253.534838) (xy 375.034128 -253.58514) (xy 375.013241 -253.63304) (xy 375.000012 -253.655576)
			(xy 374.9929 -253.667006) (xy 374.992392 -253.694692) (xy 375.04243 -253.783846) (xy 375.047147 -253.791492)
			(xy 375.060812 -253.803138) (xy 375.07765 -253.809371) (xy 375.086626 -253.809754) (xy 375.272554 -253.809754)
			(xy 375.282619 -253.810189) (xy 375.301204 -253.817923) (xy 375.308622 -253.82474) (xy 376.03176 -254.547878)
			(xy 376.038146 -254.553826) (xy 376.053874 -254.561357) (xy 376.071223 -254.563119) (xy 376.079766 -254.56134)
			(xy 376.177302 -254.537464) (xy 376.196352 -254.519684) (xy 376.200416 -254.506984) (xy 376.208984 -254.481632)
			(xy 376.232224 -254.43343) (xy 376.261973 -254.388949) (xy 376.297647 -254.349062) (xy 376.338546 -254.314552)
			(xy 376.383866 -254.286097) (xy 376.432719 -254.264256) (xy 376.484144 -254.249457) (xy 376.537134 -254.24199)
			(xy 376.56389 -254.241554) (xy 376.591143 -254.242039) (xy 376.645094 -254.249794) (xy 376.697392 -254.265148)
			(xy 376.746973 -254.287788) (xy 376.792827 -254.317254) (xy 376.834021 -254.352945) (xy 376.869718 -254.394135)
			(xy 376.899189 -254.439985) (xy 376.921835 -254.489563) (xy 376.930682 -254.519684) (xy 377.383546 -254.519684)
			(xy 377.387617 -254.464062) (xy 377.399743 -254.409625) (xy 377.419666 -254.357534) (xy 377.446962 -254.308899)
			(xy 377.481048 -254.264756) (xy 377.521197 -254.226047) (xy 377.566555 -254.193596) (xy 377.616155 -254.168095)
			(xy 377.668939 -254.150088) (xy 377.723782 -254.139958) (xy 377.779516 -254.137921) (xy 377.834953 -254.144021)
			(xy 377.88891 -254.158127) (xy 377.940239 -254.179939) (xy 377.987845 -254.208993) (xy 378.030713 -254.244668)
			(xy 378.06793 -254.286205) (xy 378.098703 -254.332718) (xy 378.122375 -254.383215) (xy 378.138443 -254.436622)
			(xy 378.146563 -254.491798) (xy 378.147072 -254.519684) (xy 378.146563 -254.54757) (xy 378.138443 -254.602746)
			(xy 378.122375 -254.656153) (xy 378.098703 -254.70665) (xy 378.06793 -254.753163) (xy 378.030713 -254.7947)
			(xy 377.987845 -254.830375) (xy 377.940239 -254.859429) (xy 377.88891 -254.881241) (xy 377.834953 -254.895347)
			(xy 377.779516 -254.901447) (xy 377.723782 -254.89941) (xy 377.668939 -254.88928) (xy 377.616155 -254.871273)
			(xy 377.566555 -254.845772) (xy 377.521197 -254.813321) (xy 377.481048 -254.774612) (xy 377.446962 -254.730469)
			(xy 377.419666 -254.681834) (xy 377.399743 -254.629743) (xy 377.387617 -254.575306) (xy 377.383546 -254.519684)
			(xy 376.930682 -254.519684) (xy 376.937196 -254.541859) (xy 376.944957 -254.595809) (xy 376.945398 -254.623062)
			(xy 376.944937 -254.649604) (xy 376.937573 -254.702174) (xy 376.922995 -254.753216) (xy 376.901485 -254.801747)
			(xy 376.873459 -254.846828) (xy 376.839455 -254.887591) (xy 376.800131 -254.923249) (xy 376.756246 -254.953114)
			(xy 376.708646 -254.97661) (xy 376.658249 -254.993283) (xy 376.632216 -254.998474) (xy 376.631962 -254.998474)
			(xy 376.622919 -255.000536) (xy 376.607075 -255.010149) (xy 376.595715 -255.02479) (xy 376.592592 -255.033526)
			(xy 376.565922 -255.119378) (xy 376.563583 -255.12827) (xy 376.564687 -255.146608) (xy 376.572172 -255.163386)
			(xy 376.578368 -255.170178) (xy 376.862848 -255.454658) (xy 376.863356 -255.455166) (xy 376.870738 -255.461746)
			(xy 376.889037 -255.469194) (xy 376.898916 -255.469644) (xy 378.058934 -255.469644) (xy 378.070909 -255.46899)
			(xy 378.092241 -255.458107) (xy 378.099828 -255.448816) (xy 378.148088 -255.38303) (xy 378.154608 -255.373067)
			(xy 378.158592 -255.349623) (xy 378.155708 -255.338072) (xy 378.155708 -255.337818) (xy 378.153676 -255.330706)
			(xy 378.146426 -255.304439) (xy 378.138645 -255.250509) (xy 378.138182 -255.223264) (xy 378.138668 -255.196013)
			(xy 378.146424 -255.142065) (xy 378.161779 -255.08977) (xy 378.184421 -255.040193) (xy 378.213887 -254.994343)
			(xy 378.249578 -254.953152) (xy 378.290769 -254.917461) (xy 378.336619 -254.887995) (xy 378.386196 -254.865353)
			(xy 378.438491 -254.849998) (xy 378.492439 -254.842242) (xy 378.546941 -254.842242) (xy 378.600889 -254.849998)
			(xy 378.653184 -254.865353) (xy 378.702761 -254.887995) (xy 378.748611 -254.917461) (xy 378.789802 -254.953152)
			(xy 378.825493 -254.994343) (xy 378.854959 -255.040193) (xy 378.877601 -255.08977) (xy 378.892956 -255.142065)
			(xy 378.900712 -255.196013) (xy 378.901198 -255.223264) (xy 378.900691 -255.250505) (xy 378.89291 -255.30443)
			(xy 378.885704 -255.330706) (xy 378.883672 -255.337818) (xy 378.883672 -255.338072) (xy 378.880768 -255.349622)
			(xy 378.884758 -255.37307) (xy 378.891292 -255.38303) (xy 378.939552 -255.448816) (xy 378.947152 -255.458088)
			(xy 378.968478 -255.468974) (xy 378.980446 -255.469644) (xy 385.205732 -255.469644) (xy 385.215799 -255.470074)
			(xy 385.23439 -255.477802) (xy 385.2418 -255.48463) (xy 388.141718 -258.384548) (xy 388.148566 -258.391945)
			(xy 388.156296 -258.410544) (xy 388.156704 -258.420616) (xy 388.156704 -260.213856) (xy 388.160768 -260.223508)
			(xy 388.170415 -260.247213) (xy 388.183989 -260.296557) (xy 388.19084 -260.347274) (xy 388.190845 -260.398452)
			(xy 388.184004 -260.449171) (xy 388.170439 -260.498518) (xy 388.160768 -260.522212) (xy 388.156704 -260.531864)
			(xy 388.156704 -264.625328) (xy 388.763 -264.625328) (xy 388.767071 -264.569706) (xy 388.779197 -264.515269)
			(xy 388.79912 -264.463178) (xy 388.826416 -264.414543) (xy 388.860502 -264.3704) (xy 388.900651 -264.331691)
			(xy 388.946009 -264.29924) (xy 388.995609 -264.273739) (xy 389.048393 -264.255732) (xy 389.103236 -264.245602)
			(xy 389.15897 -264.243565) (xy 389.214407 -264.249665) (xy 389.268364 -264.263771) (xy 389.319693 -264.285583)
			(xy 389.367299 -264.314637) (xy 389.410167 -264.350312) (xy 389.447384 -264.391849) (xy 389.478157 -264.438362)
			(xy 389.501829 -264.488859) (xy 389.517897 -264.542266) (xy 389.526017 -264.597442) (xy 389.526526 -264.625328)
			(xy 389.526017 -264.653214) (xy 389.517897 -264.70839) (xy 389.501829 -264.761797) (xy 389.478157 -264.812294)
			(xy 389.447384 -264.858807) (xy 389.410167 -264.900344) (xy 389.367299 -264.936019) (xy 389.319693 -264.965073)
			(xy 389.268364 -264.986885) (xy 389.214407 -265.000991) (xy 389.15897 -265.007091) (xy 389.103236 -265.005054)
			(xy 389.048393 -264.994924) (xy 388.995609 -264.976917) (xy 388.946009 -264.951416) (xy 388.900651 -264.918965)
			(xy 388.860502 -264.880256) (xy 388.826416 -264.836113) (xy 388.79912 -264.787478) (xy 388.779197 -264.735387)
			(xy 388.767071 -264.68095) (xy 388.763 -264.625328) (xy 388.156704 -264.625328) (xy 388.156704 -265.737848)
			(xy 388.73252 -265.737848) (xy 388.736591 -265.682226) (xy 388.748717 -265.627789) (xy 388.76864 -265.575698)
			(xy 388.795936 -265.527063) (xy 388.830022 -265.48292) (xy 388.870171 -265.444211) (xy 388.915529 -265.41176)
			(xy 388.965129 -265.386259) (xy 389.017913 -265.368252) (xy 389.072756 -265.358122) (xy 389.12849 -265.356085)
			(xy 389.183927 -265.362185) (xy 389.237884 -265.376291) (xy 389.289213 -265.398103) (xy 389.336819 -265.427157)
			(xy 389.379687 -265.462832) (xy 389.416904 -265.504369) (xy 389.447677 -265.550882) (xy 389.471349 -265.601379)
			(xy 389.487417 -265.654786) (xy 389.495537 -265.709962) (xy 389.496046 -265.737848) (xy 389.495537 -265.765734)
			(xy 389.487417 -265.82091) (xy 389.471349 -265.874317) (xy 389.447677 -265.924814) (xy 389.416904 -265.971327)
			(xy 389.379687 -266.012864) (xy 389.336819 -266.048539) (xy 389.289213 -266.077593) (xy 389.237884 -266.099405)
			(xy 389.183927 -266.113511) (xy 389.12849 -266.119611) (xy 389.072756 -266.117574) (xy 389.017913 -266.107444)
			(xy 388.965129 -266.089437) (xy 388.915529 -266.063936) (xy 388.870171 -266.031485) (xy 388.830022 -265.992776)
			(xy 388.795936 -265.948633) (xy 388.76864 -265.899998) (xy 388.748717 -265.847907) (xy 388.736591 -265.79347)
			(xy 388.73252 -265.737848) (xy 388.156704 -265.737848) (xy 388.156704 -266.915646) (xy 388.736076 -266.915646)
			(xy 388.740147 -266.860024) (xy 388.752273 -266.805587) (xy 388.772196 -266.753496) (xy 388.799492 -266.704861)
			(xy 388.833578 -266.660718) (xy 388.873727 -266.622009) (xy 388.919085 -266.589558) (xy 388.968685 -266.564057)
			(xy 389.021469 -266.54605) (xy 389.076312 -266.53592) (xy 389.132046 -266.533883) (xy 389.187483 -266.539983)
			(xy 389.24144 -266.554089) (xy 389.292769 -266.575901) (xy 389.340375 -266.604955) (xy 389.383243 -266.64063)
			(xy 389.42046 -266.682167) (xy 389.451233 -266.72868) (xy 389.474905 -266.779177) (xy 389.490973 -266.832584)
			(xy 389.499093 -266.88776) (xy 389.499602 -266.915646) (xy 389.499093 -266.943532) (xy 389.490973 -266.998708)
			(xy 389.474905 -267.052115) (xy 389.451233 -267.102612) (xy 389.42046 -267.149125) (xy 389.383243 -267.190662)
			(xy 389.340375 -267.226337) (xy 389.292769 -267.255391) (xy 389.24144 -267.277203) (xy 389.187483 -267.291309)
			(xy 389.132046 -267.297409) (xy 389.076312 -267.295372) (xy 389.021469 -267.285242) (xy 388.968685 -267.267235)
			(xy 388.919085 -267.241734) (xy 388.873727 -267.209283) (xy 388.833578 -267.170574) (xy 388.799492 -267.126431)
			(xy 388.772196 -267.077796) (xy 388.752273 -267.025705) (xy 388.740147 -266.971268) (xy 388.736076 -266.915646)
			(xy 388.156704 -266.915646) (xy 388.156704 -268.339062) (xy 388.744204 -268.339062) (xy 388.748275 -268.28344)
			(xy 388.760401 -268.229003) (xy 388.780324 -268.176912) (xy 388.80762 -268.128277) (xy 388.841706 -268.084134)
			(xy 388.881855 -268.045425) (xy 388.927213 -268.012974) (xy 388.976813 -267.987473) (xy 389.029597 -267.969466)
			(xy 389.08444 -267.959336) (xy 389.140174 -267.957299) (xy 389.195611 -267.963399) (xy 389.249568 -267.977505)
			(xy 389.300897 -267.999317) (xy 389.348503 -268.028371) (xy 389.391371 -268.064046) (xy 389.428588 -268.105583)
			(xy 389.459361 -268.152096) (xy 389.483033 -268.202593) (xy 389.499101 -268.256) (xy 389.507221 -268.311176)
			(xy 389.50773 -268.339062) (xy 389.507221 -268.366948) (xy 389.499101 -268.422124) (xy 389.483033 -268.475531)
			(xy 389.459361 -268.526028) (xy 389.428588 -268.572541) (xy 389.391371 -268.614078) (xy 389.348503 -268.649753)
			(xy 389.300897 -268.678807) (xy 389.249568 -268.700619) (xy 389.195611 -268.714725) (xy 389.140174 -268.720825)
			(xy 389.08444 -268.718788) (xy 389.029597 -268.708658) (xy 388.976813 -268.690651) (xy 388.927213 -268.66515)
			(xy 388.881855 -268.632699) (xy 388.841706 -268.59399) (xy 388.80762 -268.549847) (xy 388.780324 -268.501212)
			(xy 388.760401 -268.449121) (xy 388.748275 -268.394684) (xy 388.744204 -268.339062) (xy 388.156704 -268.339062)
			(xy 388.156704 -269.943326) (xy 388.630666 -269.943326) (xy 388.634737 -269.887704) (xy 388.646863 -269.833267)
			(xy 388.666786 -269.781176) (xy 388.694082 -269.732541) (xy 388.728168 -269.688398) (xy 388.768317 -269.649689)
			(xy 388.813675 -269.617238) (xy 388.863275 -269.591737) (xy 388.916059 -269.57373) (xy 388.970902 -269.5636)
			(xy 389.026636 -269.561563) (xy 389.082073 -269.567663) (xy 389.13603 -269.581769) (xy 389.187359 -269.603581)
			(xy 389.234965 -269.632635) (xy 389.277833 -269.66831) (xy 389.31505 -269.709847) (xy 389.345823 -269.75636)
			(xy 389.369495 -269.806857) (xy 389.385563 -269.860264) (xy 389.393683 -269.91544) (xy 389.394192 -269.943326)
			(xy 389.393683 -269.971212) (xy 389.385563 -270.026388) (xy 389.369495 -270.079795) (xy 389.345823 -270.130292)
			(xy 389.31505 -270.176805) (xy 389.277833 -270.218342) (xy 389.234965 -270.254017) (xy 389.187359 -270.283071)
			(xy 389.13603 -270.304883) (xy 389.082073 -270.318989) (xy 389.026636 -270.325089) (xy 388.970902 -270.323052)
			(xy 388.916059 -270.312922) (xy 388.863275 -270.294915) (xy 388.813675 -270.269414) (xy 388.768317 -270.236963)
			(xy 388.728168 -270.198254) (xy 388.694082 -270.154111) (xy 388.666786 -270.105476) (xy 388.646863 -270.053385)
			(xy 388.634737 -269.998948) (xy 388.630666 -269.943326) (xy 388.156704 -269.943326) (xy 388.156704 -272.28038)
			(xy 388.157063 -272.289459) (xy 388.163403 -272.306472) (xy 388.175318 -272.320172) (xy 388.18312 -272.32483)
			(xy 388.258558 -272.366486) (xy 388.267606 -272.37093) (xy 388.287642 -272.37301) (xy 388.29742 -272.37055)
			(xy 388.312406 -272.366232) (xy 388.317994 -272.36293) (xy 388.341881 -272.349294) (xy 388.393356 -272.329924)
			(xy 388.447467 -272.320086) (xy 388.474966 -272.319496) (xy 388.500225 -272.319986) (xy 388.550055 -272.328296)
			(xy 388.597838 -272.344695) (xy 388.642269 -272.368736) (xy 388.682137 -272.399762) (xy 388.716355 -272.436928)
			(xy 388.743987 -272.479219) (xy 388.764282 -272.525482) (xy 388.776684 -272.574454) (xy 388.780856 -272.6248)
			(xy 388.780856 -272.624804) (xy 389.119122 -272.624804) (xy 389.123082 -272.57575) (xy 389.134859 -272.527966)
			(xy 389.15415 -272.48269) (xy 389.180453 -272.441094) (xy 389.213088 -272.404257) (xy 389.251209 -272.373132)
			(xy 389.29383 -272.348525) (xy 389.339846 -272.331073) (xy 389.388065 -272.321229) (xy 389.43724 -272.319248)
			(xy 389.486095 -272.32518) (xy 389.533366 -272.338872) (xy 389.577828 -272.35997) (xy 389.618331 -272.387926)
			(xy 389.653824 -272.422018) (xy 389.683389 -272.461362) (xy 389.70626 -272.504939) (xy 389.721844 -272.55162)
			(xy 389.729739 -272.600197) (xy 389.730234 -272.624804) (xy 390.069082 -272.624804) (xy 390.073042 -272.57575)
			(xy 390.084819 -272.527966) (xy 390.10411 -272.48269) (xy 390.130413 -272.441094) (xy 390.163048 -272.404257)
			(xy 390.201169 -272.373132) (xy 390.24379 -272.348525) (xy 390.289806 -272.331073) (xy 390.338025 -272.321229)
			(xy 390.3872 -272.319248) (xy 390.436055 -272.32518) (xy 390.483326 -272.338872) (xy 390.527788 -272.35997)
			(xy 390.568291 -272.387926) (xy 390.603784 -272.422018) (xy 390.633349 -272.461362) (xy 390.65622 -272.504939)
			(xy 390.671804 -272.55162) (xy 390.679699 -272.600197) (xy 390.680194 -272.624804) (xy 390.679699 -272.649411)
			(xy 390.671804 -272.697988) (xy 390.65622 -272.744669) (xy 390.633349 -272.788246) (xy 390.603784 -272.82759)
			(xy 390.568291 -272.861682) (xy 390.527788 -272.889638) (xy 390.483326 -272.910736) (xy 390.436055 -272.924428)
			(xy 390.3872 -272.93036) (xy 390.338025 -272.928379) (xy 390.289806 -272.918535) (xy 390.24379 -272.901083)
			(xy 390.201169 -272.876476) (xy 390.163048 -272.845351) (xy 390.130413 -272.808514) (xy 390.10411 -272.766918)
			(xy 390.084819 -272.721642) (xy 390.073042 -272.673858) (xy 390.069082 -272.624804) (xy 389.730234 -272.624804)
			(xy 389.729739 -272.649411) (xy 389.721844 -272.697988) (xy 389.70626 -272.744669) (xy 389.683389 -272.788246)
			(xy 389.653824 -272.82759) (xy 389.618331 -272.861682) (xy 389.577828 -272.889638) (xy 389.533366 -272.910736)
			(xy 389.486095 -272.924428) (xy 389.43724 -272.93036) (xy 389.388065 -272.928379) (xy 389.339846 -272.918535)
			(xy 389.29383 -272.901083) (xy 389.251209 -272.876476) (xy 389.213088 -272.845351) (xy 389.180453 -272.808514)
			(xy 389.15415 -272.766918) (xy 389.134859 -272.721642) (xy 389.123082 -272.673858) (xy 389.119122 -272.624804)
			(xy 388.780856 -272.624804) (xy 388.776684 -272.675146) (xy 388.764282 -272.724118) (xy 388.743987 -272.770381)
			(xy 388.716355 -272.812672) (xy 388.682137 -272.849838) (xy 388.642269 -272.880864) (xy 388.597838 -272.904905)
			(xy 388.550055 -272.921304) (xy 388.500225 -272.929614) (xy 388.474966 -272.930112) (xy 388.447467 -272.929525)
			(xy 388.393359 -272.919677) (xy 388.341887 -272.900304) (xy 388.317994 -272.886678) (xy 388.312406 -272.883376)
			(xy 388.29742 -272.879058) (xy 388.287638 -272.876673) (xy 388.267632 -272.87876) (xy 388.258558 -272.883122)
			(xy 388.18312 -272.924778) (xy 388.175358 -272.929474) (xy 388.163501 -272.943191) (xy 388.15713 -272.960165)
			(xy 388.156704 -272.969228) (xy 388.156704 -273.23034) (xy 388.157073 -273.239413) (xy 388.163426 -273.256411)
			(xy 388.175345 -273.270093) (xy 388.18312 -273.27479) (xy 388.258558 -273.316446) (xy 388.267606 -273.320893)
			(xy 388.287643 -273.322974) (xy 388.29742 -273.32051) (xy 388.312406 -273.316192) (xy 388.317994 -273.31289)
			(xy 388.341881 -273.299252) (xy 388.393354 -273.279878) (xy 388.447466 -273.270038) (xy 388.474966 -273.269456)
			(xy 388.500229 -273.269946) (xy 388.550065 -273.278257) (xy 388.597854 -273.294659) (xy 388.642291 -273.318702)
			(xy 388.682165 -273.349733) (xy 388.716386 -273.386903) (xy 388.744022 -273.4292) (xy 388.764319 -273.475469)
			(xy 388.776723 -273.524448) (xy 388.780893 -273.574764) (xy 389.119122 -273.574764) (xy 389.123082 -273.52571)
			(xy 389.134859 -273.477926) (xy 389.15415 -273.43265) (xy 389.180453 -273.391054) (xy 389.213088 -273.354217)
			(xy 389.251209 -273.323092) (xy 389.29383 -273.298485) (xy 389.339846 -273.281033) (xy 389.388065 -273.271189)
			(xy 389.43724 -273.269208) (xy 389.486095 -273.27514) (xy 389.533366 -273.288832) (xy 389.577828 -273.30993)
			(xy 389.618331 -273.337886) (xy 389.653824 -273.371978) (xy 389.683389 -273.411322) (xy 389.70626 -273.454899)
			(xy 389.721844 -273.50158) (xy 389.729739 -273.550157) (xy 389.730234 -273.574764) (xy 390.069082 -273.574764)
			(xy 390.073042 -273.52571) (xy 390.084819 -273.477926) (xy 390.10411 -273.43265) (xy 390.130413 -273.391054)
			(xy 390.163048 -273.354217) (xy 390.201169 -273.323092) (xy 390.24379 -273.298485) (xy 390.289806 -273.281033)
			(xy 390.338025 -273.271189) (xy 390.3872 -273.269208) (xy 390.436055 -273.27514) (xy 390.483326 -273.288832)
			(xy 390.527788 -273.30993) (xy 390.568291 -273.337886) (xy 390.603784 -273.371978) (xy 390.633349 -273.411322)
			(xy 390.65622 -273.454899) (xy 390.671804 -273.50158) (xy 390.679699 -273.550157) (xy 390.680194 -273.574764)
			(xy 390.679699 -273.599371) (xy 390.671804 -273.647948) (xy 390.65622 -273.694629) (xy 390.633349 -273.738206)
			(xy 390.603784 -273.77755) (xy 390.568291 -273.811642) (xy 390.527788 -273.839598) (xy 390.483326 -273.860696)
			(xy 390.436055 -273.874388) (xy 390.3872 -273.88032) (xy 390.338025 -273.878339) (xy 390.289806 -273.868495)
			(xy 390.24379 -273.851043) (xy 390.201169 -273.826436) (xy 390.163048 -273.795311) (xy 390.130413 -273.758474)
			(xy 390.10411 -273.716878) (xy 390.084819 -273.671602) (xy 390.073042 -273.623818) (xy 390.069082 -273.574764)
			(xy 389.730234 -273.574764) (xy 389.729739 -273.599371) (xy 389.721844 -273.647948) (xy 389.70626 -273.694629)
			(xy 389.683389 -273.738206) (xy 389.653824 -273.77755) (xy 389.618331 -273.811642) (xy 389.577828 -273.839598)
			(xy 389.533366 -273.860696) (xy 389.486095 -273.874388) (xy 389.43724 -273.88032) (xy 389.388065 -273.878339)
			(xy 389.339846 -273.868495) (xy 389.29383 -273.851043) (xy 389.251209 -273.826436) (xy 389.213088 -273.795311)
			(xy 389.180453 -273.758474) (xy 389.15415 -273.716878) (xy 389.134859 -273.671602) (xy 389.123082 -273.623818)
			(xy 389.119122 -273.574764) (xy 388.780893 -273.574764) (xy 388.780896 -273.5748) (xy 388.776723 -273.625152)
			(xy 388.764319 -273.674131) (xy 388.744022 -273.7204) (xy 388.716386 -273.762697) (xy 388.682165 -273.799867)
			(xy 388.642291 -273.830898) (xy 388.597854 -273.854941) (xy 388.550065 -273.871343) (xy 388.500229 -273.879654)
			(xy 388.474966 -273.880072) (xy 388.447467 -273.879486) (xy 388.393358 -273.869639) (xy 388.341884 -273.850269)
			(xy 388.317994 -273.836638) (xy 388.312406 -273.833336) (xy 388.29742 -273.829018) (xy 388.287638 -273.826631)
			(xy 388.267633 -273.82872) (xy 388.258558 -273.833082) (xy 388.18312 -273.874738) (xy 388.175353 -273.879433)
			(xy 388.163486 -273.893147) (xy 388.157103 -273.910122) (xy 388.156704 -273.919188) (xy 388.156704 -274.180554)
			(xy 388.157059 -274.189635) (xy 388.163393 -274.206656) (xy 388.175307 -274.220363) (xy 388.18312 -274.225004)
			(xy 388.258558 -274.26666) (xy 388.267606 -274.271106) (xy 388.287642 -274.273186) (xy 388.29742 -274.270724)
			(xy 388.312406 -274.266406) (xy 388.317994 -274.263104) (xy 388.341882 -274.249469) (xy 388.393356 -274.2301)
			(xy 388.447467 -274.220263) (xy 388.474966 -274.21967) (xy 388.500227 -274.22016) (xy 388.550062 -274.228471)
			(xy 388.597848 -274.244871) (xy 388.642284 -274.268914) (xy 388.682155 -274.299943) (xy 388.716375 -274.337112)
			(xy 388.74401 -274.379407) (xy 388.764306 -274.425673) (xy 388.77671 -274.47465) (xy 388.78088 -274.524978)
			(xy 389.119122 -274.524978) (xy 389.123082 -274.475924) (xy 389.134859 -274.42814) (xy 389.15415 -274.382864)
			(xy 389.180453 -274.341268) (xy 389.213088 -274.304431) (xy 389.251209 -274.273306) (xy 389.29383 -274.248699)
			(xy 389.339846 -274.231247) (xy 389.388065 -274.221403) (xy 389.43724 -274.219422) (xy 389.486095 -274.225354)
			(xy 389.533366 -274.239046) (xy 389.577828 -274.260144) (xy 389.618331 -274.2881) (xy 389.653824 -274.322192)
			(xy 389.683389 -274.361536) (xy 389.70626 -274.405113) (xy 389.721844 -274.451794) (xy 389.729739 -274.500371)
			(xy 389.730234 -274.524978) (xy 390.069082 -274.524978) (xy 390.073042 -274.475924) (xy 390.084819 -274.42814)
			(xy 390.10411 -274.382864) (xy 390.130413 -274.341268) (xy 390.163048 -274.304431) (xy 390.201169 -274.273306)
			(xy 390.24379 -274.248699) (xy 390.289806 -274.231247) (xy 390.338025 -274.221403) (xy 390.3872 -274.219422)
			(xy 390.436055 -274.225354) (xy 390.483326 -274.239046) (xy 390.527788 -274.260144) (xy 390.568291 -274.2881)
			(xy 390.603784 -274.322192) (xy 390.633349 -274.361536) (xy 390.65622 -274.405113) (xy 390.671804 -274.451794)
			(xy 390.679699 -274.500371) (xy 390.680194 -274.524978) (xy 390.679699 -274.549585) (xy 390.671804 -274.598162)
			(xy 390.65622 -274.644843) (xy 390.633349 -274.68842) (xy 390.603784 -274.727764) (xy 390.568291 -274.761856)
			(xy 390.527788 -274.789812) (xy 390.483326 -274.81091) (xy 390.436055 -274.824602) (xy 390.3872 -274.830534)
			(xy 390.338025 -274.828553) (xy 390.289806 -274.818709) (xy 390.24379 -274.801257) (xy 390.201169 -274.77665)
			(xy 390.163048 -274.745525) (xy 390.130413 -274.708688) (xy 390.10411 -274.667092) (xy 390.084819 -274.621816)
			(xy 390.073042 -274.574032) (xy 390.069082 -274.524978) (xy 389.730234 -274.524978) (xy 389.729739 -274.549585)
			(xy 389.721844 -274.598162) (xy 389.70626 -274.644843) (xy 389.683389 -274.68842) (xy 389.653824 -274.727764)
			(xy 389.618331 -274.761856) (xy 389.577828 -274.789812) (xy 389.533366 -274.81091) (xy 389.486095 -274.824602)
			(xy 389.43724 -274.830534) (xy 389.388065 -274.828553) (xy 389.339846 -274.818709) (xy 389.29383 -274.801257)
			(xy 389.251209 -274.77665) (xy 389.213088 -274.745525) (xy 389.180453 -274.708688) (xy 389.15415 -274.667092)
			(xy 389.134859 -274.621816) (xy 389.123082 -274.574032) (xy 389.119122 -274.524978) (xy 388.78088 -274.524978)
			(xy 388.780882 -274.525) (xy 388.77671 -274.57535) (xy 388.764306 -274.624327) (xy 388.74401 -274.670593)
			(xy 388.716375 -274.712888) (xy 388.682155 -274.750057) (xy 388.642284 -274.781086) (xy 388.597848 -274.805129)
			(xy 388.550062 -274.821529) (xy 388.500227 -274.82984) (xy 388.474966 -274.830286) (xy 388.447468 -274.829699)
			(xy 388.39336 -274.81985) (xy 388.341888 -274.800475) (xy 388.317994 -274.786852) (xy 388.312406 -274.78355)
			(xy 388.29742 -274.779232) (xy 388.287638 -274.776845) (xy 388.267633 -274.778935) (xy 388.258558 -274.783296)
			(xy 388.18312 -274.824952) (xy 388.175355 -274.829647) (xy 388.163492 -274.843362) (xy 388.157112 -274.860337)
			(xy 388.156704 -274.869402) (xy 388.156704 -275.130514) (xy 388.157069 -275.13959) (xy 388.163416 -275.156594)
			(xy 388.175333 -275.170284) (xy 388.18312 -275.174964) (xy 388.258558 -275.21662) (xy 388.267607 -275.221062)
			(xy 388.287642 -275.22314) (xy 388.29742 -275.220684) (xy 388.312406 -275.216366) (xy 388.317994 -275.213064)
			(xy 388.341881 -275.199427) (xy 388.393355 -275.180054) (xy 388.447466 -275.170215) (xy 388.474966 -275.16963)
			(xy 388.500222 -275.17012) (xy 388.550047 -275.178429) (xy 388.597824 -275.194826) (xy 388.642251 -275.218864)
			(xy 388.682114 -275.249887) (xy 388.716328 -275.287049) (xy 388.743957 -275.329335) (xy 388.764249 -275.375593)
			(xy 388.77665 -275.42456) (xy 388.780822 -275.4749) (xy 388.780819 -275.474938) (xy 389.119122 -275.474938)
			(xy 389.123082 -275.425884) (xy 389.134859 -275.3781) (xy 389.15415 -275.332824) (xy 389.180453 -275.291228)
			(xy 389.213088 -275.254391) (xy 389.251209 -275.223266) (xy 389.29383 -275.198659) (xy 389.339846 -275.181207)
			(xy 389.388065 -275.171363) (xy 389.43724 -275.169382) (xy 389.486095 -275.175314) (xy 389.533366 -275.189006)
			(xy 389.577828 -275.210104) (xy 389.618331 -275.23806) (xy 389.653824 -275.272152) (xy 389.683389 -275.311496)
			(xy 389.70626 -275.355073) (xy 389.721844 -275.401754) (xy 389.729739 -275.450331) (xy 389.730234 -275.474938)
			(xy 390.069082 -275.474938) (xy 390.073042 -275.425884) (xy 390.084819 -275.3781) (xy 390.10411 -275.332824)
			(xy 390.130413 -275.291228) (xy 390.163048 -275.254391) (xy 390.201169 -275.223266) (xy 390.24379 -275.198659)
			(xy 390.289806 -275.181207) (xy 390.338025 -275.171363) (xy 390.3872 -275.169382) (xy 390.436055 -275.175314)
			(xy 390.483326 -275.189006) (xy 390.527788 -275.210104) (xy 390.568291 -275.23806) (xy 390.603784 -275.272152)
			(xy 390.633349 -275.311496) (xy 390.65622 -275.355073) (xy 390.671804 -275.401754) (xy 390.679699 -275.450331)
			(xy 390.680194 -275.474938) (xy 390.679699 -275.499545) (xy 390.671804 -275.548122) (xy 390.65622 -275.594803)
			(xy 390.633349 -275.63838) (xy 390.603784 -275.677724) (xy 390.568291 -275.711816) (xy 390.527788 -275.739772)
			(xy 390.483326 -275.76087) (xy 390.436055 -275.774562) (xy 390.3872 -275.780494) (xy 390.338025 -275.778513)
			(xy 390.289806 -275.768669) (xy 390.24379 -275.751217) (xy 390.201169 -275.72661) (xy 390.163048 -275.695485)
			(xy 390.130413 -275.658648) (xy 390.10411 -275.617052) (xy 390.084819 -275.571776) (xy 390.073042 -275.523992)
			(xy 390.069082 -275.474938) (xy 389.730234 -275.474938) (xy 389.729739 -275.499545) (xy 389.721844 -275.548122)
			(xy 389.70626 -275.594803) (xy 389.683389 -275.63838) (xy 389.653824 -275.677724) (xy 389.618331 -275.711816)
			(xy 389.577828 -275.739772) (xy 389.533366 -275.76087) (xy 389.486095 -275.774562) (xy 389.43724 -275.780494)
			(xy 389.388065 -275.778513) (xy 389.339846 -275.768669) (xy 389.29383 -275.751217) (xy 389.251209 -275.72661)
			(xy 389.213088 -275.695485) (xy 389.180453 -275.658648) (xy 389.15415 -275.617052) (xy 389.134859 -275.571776)
			(xy 389.123082 -275.523992) (xy 389.119122 -275.474938) (xy 388.780819 -275.474938) (xy 388.77665 -275.52524)
			(xy 388.764249 -275.574207) (xy 388.743957 -275.620465) (xy 388.716328 -275.662751) (xy 388.682114 -275.699913)
			(xy 388.642251 -275.730936) (xy 388.597824 -275.754974) (xy 388.550047 -275.771371) (xy 388.500222 -275.77968)
			(xy 388.474966 -275.780246) (xy 388.447467 -275.77966) (xy 388.393358 -275.769812) (xy 388.341885 -275.750441)
			(xy 388.317994 -275.736812) (xy 388.312406 -275.73351) (xy 388.29742 -275.729192) (xy 388.287638 -275.726806)
			(xy 388.267632 -275.728894) (xy 388.258558 -275.733256) (xy 388.18312 -275.774912) (xy 388.175362 -275.77961)
			(xy 388.163514 -275.793328) (xy 388.157154 -275.810301) (xy 388.156704 -275.819362) (xy 388.156704 -276.080474)
			(xy 388.157062 -276.089554) (xy 388.163401 -276.106569) (xy 388.175316 -276.12027) (xy 388.18312 -276.124924)
			(xy 388.258558 -276.16658) (xy 388.267606 -276.171025) (xy 388.287642 -276.173105) (xy 388.29742 -276.170644)
			(xy 388.312406 -276.166326) (xy 388.317994 -276.163024) (xy 388.341881 -276.149388) (xy 388.393356 -276.130019)
			(xy 388.447467 -276.120181) (xy 388.474966 -276.11959) (xy 388.500226 -276.12008) (xy 388.550057 -276.12839)
			(xy 388.59784 -276.14479) (xy 388.642273 -276.168831) (xy 388.682142 -276.199858) (xy 388.716359 -276.237024)
			(xy 388.743992 -276.279316) (xy 388.764287 -276.32558) (xy 388.77669 -276.374553) (xy 388.780862 -276.424898)
			(xy 389.119122 -276.424898) (xy 389.123082 -276.375844) (xy 389.134859 -276.32806) (xy 389.15415 -276.282784)
			(xy 389.180453 -276.241188) (xy 389.213088 -276.204351) (xy 389.251209 -276.173226) (xy 389.29383 -276.148619)
			(xy 389.339846 -276.131167) (xy 389.388065 -276.121323) (xy 389.43724 -276.119342) (xy 389.486095 -276.125274)
			(xy 389.533366 -276.138966) (xy 389.577828 -276.160064) (xy 389.618331 -276.18802) (xy 389.653824 -276.222112)
			(xy 389.683389 -276.261456) (xy 389.70626 -276.305033) (xy 389.721844 -276.351714) (xy 389.729739 -276.400291)
			(xy 389.730234 -276.424898) (xy 390.069082 -276.424898) (xy 390.073042 -276.375844) (xy 390.084819 -276.32806)
			(xy 390.10411 -276.282784) (xy 390.130413 -276.241188) (xy 390.163048 -276.204351) (xy 390.201169 -276.173226)
			(xy 390.24379 -276.148619) (xy 390.289806 -276.131167) (xy 390.338025 -276.121323) (xy 390.3872 -276.119342)
			(xy 390.436055 -276.125274) (xy 390.483326 -276.138966) (xy 390.527788 -276.160064) (xy 390.568291 -276.18802)
			(xy 390.603784 -276.222112) (xy 390.633349 -276.261456) (xy 390.65622 -276.305033) (xy 390.671804 -276.351714)
			(xy 390.679699 -276.400291) (xy 390.680194 -276.424898) (xy 390.679699 -276.449505) (xy 390.671804 -276.498082)
			(xy 390.65622 -276.544763) (xy 390.633349 -276.58834) (xy 390.603784 -276.627684) (xy 390.568291 -276.661776)
			(xy 390.527788 -276.689732) (xy 390.483326 -276.71083) (xy 390.436055 -276.724522) (xy 390.3872 -276.730454)
			(xy 390.338025 -276.728473) (xy 390.289806 -276.718629) (xy 390.24379 -276.701177) (xy 390.201169 -276.67657)
			(xy 390.163048 -276.645445) (xy 390.130413 -276.608608) (xy 390.10411 -276.567012) (xy 390.084819 -276.521736)
			(xy 390.073042 -276.473952) (xy 390.069082 -276.424898) (xy 389.730234 -276.424898) (xy 389.729739 -276.449505)
			(xy 389.721844 -276.498082) (xy 389.70626 -276.544763) (xy 389.683389 -276.58834) (xy 389.653824 -276.627684)
			(xy 389.618331 -276.661776) (xy 389.577828 -276.689732) (xy 389.533366 -276.71083) (xy 389.486095 -276.724522)
			(xy 389.43724 -276.730454) (xy 389.388065 -276.728473) (xy 389.339846 -276.718629) (xy 389.29383 -276.701177)
			(xy 389.251209 -276.67657) (xy 389.213088 -276.645445) (xy 389.180453 -276.608608) (xy 389.15415 -276.567012)
			(xy 389.134859 -276.521736) (xy 389.123082 -276.473952) (xy 389.119122 -276.424898) (xy 388.780862 -276.424898)
			(xy 388.780862 -276.4249) (xy 388.77669 -276.475247) (xy 388.764287 -276.52422) (xy 388.743992 -276.570484)
			(xy 388.716359 -276.612776) (xy 388.682142 -276.649942) (xy 388.642273 -276.680969) (xy 388.59784 -276.70501)
			(xy 388.550057 -276.72141) (xy 388.500226 -276.72972) (xy 388.474966 -276.730206) (xy 388.447467 -276.729619)
			(xy 388.393359 -276.71977) (xy 388.341887 -276.700397) (xy 388.317994 -276.686772) (xy 388.312406 -276.68347)
			(xy 388.29742 -276.679152) (xy 388.287638 -276.676765) (xy 388.267633 -276.678855) (xy 388.258558 -276.683216)
			(xy 388.18312 -276.724872) (xy 388.175357 -276.729568) (xy 388.163499 -276.743284) (xy 388.157126 -276.760259)
			(xy 388.156704 -276.769322) (xy 388.156704 -277.030434) (xy 388.157072 -277.039508) (xy 388.163424 -277.056507)
			(xy 388.175342 -277.070191) (xy 388.18312 -277.074884) (xy 388.258558 -277.11654) (xy 388.267607 -277.120981)
			(xy 388.287641 -277.123058) (xy 388.29742 -277.120604) (xy 388.312406 -277.116286) (xy 388.317994 -277.112984)
			(xy 388.341881 -277.099346) (xy 388.393355 -277.079972) (xy 388.447466 -277.070132) (xy 388.474966 -277.06955)
			(xy 388.500229 -277.07004) (xy 388.550067 -277.078351) (xy 388.597856 -277.094753) (xy 388.642295 -277.118797)
			(xy 388.682169 -277.149828) (xy 388.716391 -277.187) (xy 388.744028 -277.229297) (xy 388.764325 -277.275567)
			(xy 388.776729 -277.324547) (xy 388.780899 -277.374858) (xy 389.119122 -277.374858) (xy 389.123082 -277.325804)
			(xy 389.134859 -277.27802) (xy 389.15415 -277.232744) (xy 389.180453 -277.191148) (xy 389.213088 -277.154311)
			(xy 389.251209 -277.123186) (xy 389.29383 -277.098579) (xy 389.339846 -277.081127) (xy 389.388065 -277.071283)
			(xy 389.43724 -277.069302) (xy 389.486095 -277.075234) (xy 389.533366 -277.088926) (xy 389.577828 -277.110024)
			(xy 389.618331 -277.13798) (xy 389.653824 -277.172072) (xy 389.683389 -277.211416) (xy 389.70626 -277.254993)
			(xy 389.721844 -277.301674) (xy 389.729739 -277.350251) (xy 389.730234 -277.374858) (xy 390.069082 -277.374858)
			(xy 390.073042 -277.325804) (xy 390.084819 -277.27802) (xy 390.10411 -277.232744) (xy 390.130413 -277.191148)
			(xy 390.163048 -277.154311) (xy 390.201169 -277.123186) (xy 390.24379 -277.098579) (xy 390.289806 -277.081127)
			(xy 390.338025 -277.071283) (xy 390.3872 -277.069302) (xy 390.436055 -277.075234) (xy 390.483326 -277.088926)
			(xy 390.527788 -277.110024) (xy 390.568291 -277.13798) (xy 390.603784 -277.172072) (xy 390.633349 -277.211416)
			(xy 390.65622 -277.254993) (xy 390.671804 -277.301674) (xy 390.679699 -277.350251) (xy 390.680194 -277.374858)
			(xy 390.679699 -277.399465) (xy 390.671804 -277.448042) (xy 390.65622 -277.494723) (xy 390.633349 -277.5383)
			(xy 390.603784 -277.577644) (xy 390.568291 -277.611736) (xy 390.527788 -277.639692) (xy 390.483326 -277.66079)
			(xy 390.436055 -277.674482) (xy 390.3872 -277.680414) (xy 390.338025 -277.678433) (xy 390.289806 -277.668589)
			(xy 390.24379 -277.651137) (xy 390.201169 -277.62653) (xy 390.163048 -277.595405) (xy 390.130413 -277.558568)
			(xy 390.10411 -277.516972) (xy 390.084819 -277.471696) (xy 390.073042 -277.423912) (xy 390.069082 -277.374858)
			(xy 389.730234 -277.374858) (xy 389.729739 -277.399465) (xy 389.721844 -277.448042) (xy 389.70626 -277.494723)
			(xy 389.683389 -277.5383) (xy 389.653824 -277.577644) (xy 389.618331 -277.611736) (xy 389.577828 -277.639692)
			(xy 389.533366 -277.66079) (xy 389.486095 -277.674482) (xy 389.43724 -277.680414) (xy 389.388065 -277.678433)
			(xy 389.339846 -277.668589) (xy 389.29383 -277.651137) (xy 389.251209 -277.62653) (xy 389.213088 -277.595405)
			(xy 389.180453 -277.558568) (xy 389.15415 -277.516972) (xy 389.134859 -277.471696) (xy 389.123082 -277.423912)
			(xy 389.119122 -277.374858) (xy 388.780899 -277.374858) (xy 388.780902 -277.3749) (xy 388.776729 -277.425253)
			(xy 388.764325 -277.474233) (xy 388.744028 -277.520503) (xy 388.716391 -277.5628) (xy 388.682169 -277.599972)
			(xy 388.642295 -277.631003) (xy 388.597856 -277.655047) (xy 388.550067 -277.671449) (xy 388.500229 -277.67976)
			(xy 388.474966 -277.680166) (xy 388.447467 -277.67958) (xy 388.393358 -277.669733) (xy 388.341884 -277.650363)
			(xy 388.317994 -277.636732) (xy 388.312406 -277.63343) (xy 388.29742 -277.629112) (xy 388.287638 -277.626726)
			(xy 388.267633 -277.628814) (xy 388.258558 -277.633176) (xy 388.18312 -277.674832) (xy 388.175353 -277.679526)
			(xy 388.163484 -277.693241) (xy 388.157098 -277.710216) (xy 388.156704 -277.719282) (xy 388.156704 -277.980394)
			(xy 388.157065 -277.989472) (xy 388.163409 -278.006481) (xy 388.175325 -278.020177) (xy 388.18312 -278.024844)
			(xy 388.258558 -278.0665) (xy 388.267607 -278.070943) (xy 388.287642 -278.073022) (xy 388.29742 -278.070564)
			(xy 388.312406 -278.066246) (xy 388.317994 -278.062944) (xy 388.341881 -278.049308) (xy 388.393355 -278.029937)
			(xy 388.447467 -278.020098) (xy 388.474966 -278.01951) (xy 388.500224 -278.02) (xy 388.550052 -278.02831)
			(xy 388.597832 -278.044708) (xy 388.642262 -278.068748) (xy 388.682128 -278.099773) (xy 388.716344 -278.136937)
			(xy 388.743975 -278.179226) (xy 388.764268 -278.225486) (xy 388.77667 -278.274457) (xy 388.780842 -278.3248)
			(xy 388.780841 -278.324818) (xy 389.119122 -278.324818) (xy 389.123082 -278.275764) (xy 389.134859 -278.22798)
			(xy 389.15415 -278.182704) (xy 389.180453 -278.141108) (xy 389.213088 -278.104271) (xy 389.251209 -278.073146)
			(xy 389.29383 -278.048539) (xy 389.339846 -278.031087) (xy 389.388065 -278.021243) (xy 389.43724 -278.019262)
			(xy 389.486095 -278.025194) (xy 389.533366 -278.038886) (xy 389.577828 -278.059984) (xy 389.618331 -278.08794)
			(xy 389.653824 -278.122032) (xy 389.683389 -278.161376) (xy 389.70626 -278.204953) (xy 389.721844 -278.251634)
			(xy 389.729739 -278.300211) (xy 389.730234 -278.324818) (xy 390.069082 -278.324818) (xy 390.073042 -278.275764)
			(xy 390.084819 -278.22798) (xy 390.10411 -278.182704) (xy 390.130413 -278.141108) (xy 390.163048 -278.104271)
			(xy 390.201169 -278.073146) (xy 390.24379 -278.048539) (xy 390.289806 -278.031087) (xy 390.338025 -278.021243)
			(xy 390.3872 -278.019262) (xy 390.436055 -278.025194) (xy 390.483326 -278.038886) (xy 390.527788 -278.059984)
			(xy 390.568291 -278.08794) (xy 390.603784 -278.122032) (xy 390.633349 -278.161376) (xy 390.65622 -278.204953)
			(xy 390.671804 -278.251634) (xy 390.679699 -278.300211) (xy 390.680194 -278.324818) (xy 390.679699 -278.349425)
			(xy 390.671804 -278.398002) (xy 390.65622 -278.444683) (xy 390.633349 -278.48826) (xy 390.603784 -278.527604)
			(xy 390.568291 -278.561696) (xy 390.527788 -278.589652) (xy 390.483326 -278.61075) (xy 390.436055 -278.624442)
			(xy 390.3872 -278.630374) (xy 390.338025 -278.628393) (xy 390.289806 -278.618549) (xy 390.24379 -278.601097)
			(xy 390.201169 -278.57649) (xy 390.163048 -278.545365) (xy 390.130413 -278.508528) (xy 390.10411 -278.466932)
			(xy 390.084819 -278.421656) (xy 390.073042 -278.373872) (xy 390.069082 -278.324818) (xy 389.730234 -278.324818)
			(xy 389.729739 -278.349425) (xy 389.721844 -278.398002) (xy 389.70626 -278.444683) (xy 389.683389 -278.48826)
			(xy 389.653824 -278.527604) (xy 389.618331 -278.561696) (xy 389.577828 -278.589652) (xy 389.533366 -278.61075)
			(xy 389.486095 -278.624442) (xy 389.43724 -278.630374) (xy 389.388065 -278.628393) (xy 389.339846 -278.618549)
			(xy 389.29383 -278.601097) (xy 389.251209 -278.57649) (xy 389.213088 -278.545365) (xy 389.180453 -278.508528)
			(xy 389.15415 -278.466932) (xy 389.134859 -278.421656) (xy 389.123082 -278.373872) (xy 389.119122 -278.324818)
			(xy 388.780841 -278.324818) (xy 388.77667 -278.375143) (xy 388.764268 -278.424114) (xy 388.743975 -278.470374)
			(xy 388.716344 -278.512663) (xy 388.682128 -278.549827) (xy 388.642262 -278.580852) (xy 388.597832 -278.604892)
			(xy 388.550052 -278.62129) (xy 388.500224 -278.6296) (xy 388.474966 -278.630126) (xy 388.447467 -278.629539)
			(xy 388.393359 -278.619691) (xy 388.341886 -278.600319) (xy 388.317994 -278.586692) (xy 388.312406 -278.58339)
			(xy 388.29742 -278.579072) (xy 388.287638 -278.576687) (xy 388.267632 -278.578774) (xy 388.258558 -278.583136)
			(xy 388.18312 -278.624792) (xy 388.175359 -278.629489) (xy 388.163506 -278.643206) (xy 388.15714 -278.66018)
			(xy 388.156704 -278.669242) (xy 388.156704 -278.930354) (xy 388.157059 -278.939435) (xy 388.163393 -278.956456)
			(xy 388.175307 -278.970163) (xy 388.18312 -278.974804) (xy 388.258558 -279.01646) (xy 388.267606 -279.020906)
			(xy 388.287642 -279.022986) (xy 388.29742 -279.020524) (xy 388.312406 -279.016206) (xy 388.317994 -279.012904)
			(xy 388.341882 -278.999269) (xy 388.393356 -278.9799) (xy 388.447467 -278.970063) (xy 388.474966 -278.96947)
			(xy 388.500227 -278.96996) (xy 388.550062 -278.978271) (xy 388.597848 -278.994671) (xy 388.642284 -279.018714)
			(xy 388.682155 -279.049743) (xy 388.716375 -279.086912) (xy 388.74401 -279.129207) (xy 388.764306 -279.175473)
			(xy 388.77671 -279.22445) (xy 388.78088 -279.274778) (xy 389.119122 -279.274778) (xy 389.123082 -279.225724)
			(xy 389.134859 -279.17794) (xy 389.15415 -279.132664) (xy 389.180453 -279.091068) (xy 389.213088 -279.054231)
			(xy 389.251209 -279.023106) (xy 389.29383 -278.998499) (xy 389.339846 -278.981047) (xy 389.388065 -278.971203)
			(xy 389.43724 -278.969222) (xy 389.486095 -278.975154) (xy 389.533366 -278.988846) (xy 389.577828 -279.009944)
			(xy 389.618331 -279.0379) (xy 389.653824 -279.071992) (xy 389.683389 -279.111336) (xy 389.70626 -279.154913)
			(xy 389.721844 -279.201594) (xy 389.729739 -279.250171) (xy 389.730234 -279.274778) (xy 390.069082 -279.274778)
			(xy 390.073042 -279.225724) (xy 390.084819 -279.17794) (xy 390.10411 -279.132664) (xy 390.130413 -279.091068)
			(xy 390.163048 -279.054231) (xy 390.201169 -279.023106) (xy 390.24379 -278.998499) (xy 390.289806 -278.981047)
			(xy 390.338025 -278.971203) (xy 390.3872 -278.969222) (xy 390.436055 -278.975154) (xy 390.483326 -278.988846)
			(xy 390.527788 -279.009944) (xy 390.568291 -279.0379) (xy 390.603784 -279.071992) (xy 390.633349 -279.111336)
			(xy 390.65622 -279.154913) (xy 390.671804 -279.201594) (xy 390.679699 -279.250171) (xy 390.680194 -279.274778)
			(xy 390.679699 -279.299385) (xy 390.671804 -279.347962) (xy 390.65622 -279.394643) (xy 390.633349 -279.43822)
			(xy 390.603784 -279.477564) (xy 390.568291 -279.511656) (xy 390.527788 -279.539612) (xy 390.483326 -279.56071)
			(xy 390.436055 -279.574402) (xy 390.3872 -279.580334) (xy 390.338025 -279.578353) (xy 390.289806 -279.568509)
			(xy 390.24379 -279.551057) (xy 390.201169 -279.52645) (xy 390.163048 -279.495325) (xy 390.130413 -279.458488)
			(xy 390.10411 -279.416892) (xy 390.084819 -279.371616) (xy 390.073042 -279.323832) (xy 390.069082 -279.274778)
			(xy 389.730234 -279.274778) (xy 389.729739 -279.299385) (xy 389.721844 -279.347962) (xy 389.70626 -279.394643)
			(xy 389.683389 -279.43822) (xy 389.653824 -279.477564) (xy 389.618331 -279.511656) (xy 389.577828 -279.539612)
			(xy 389.533366 -279.56071) (xy 389.486095 -279.574402) (xy 389.43724 -279.580334) (xy 389.388065 -279.578353)
			(xy 389.339846 -279.568509) (xy 389.29383 -279.551057) (xy 389.251209 -279.52645) (xy 389.213088 -279.495325)
			(xy 389.180453 -279.458488) (xy 389.15415 -279.416892) (xy 389.134859 -279.371616) (xy 389.123082 -279.323832)
			(xy 389.119122 -279.274778) (xy 388.78088 -279.274778) (xy 388.780882 -279.2748) (xy 388.77671 -279.32515)
			(xy 388.764306 -279.374127) (xy 388.74401 -279.420393) (xy 388.716375 -279.462688) (xy 388.682155 -279.499857)
			(xy 388.642284 -279.530886) (xy 388.597848 -279.554929) (xy 388.550062 -279.571329) (xy 388.500227 -279.57964)
			(xy 388.474966 -279.580086) (xy 388.447468 -279.579499) (xy 388.39336 -279.56965) (xy 388.341888 -279.550275)
			(xy 388.317994 -279.536652) (xy 388.312406 -279.53335) (xy 388.29742 -279.529032) (xy 388.287638 -279.526645)
			(xy 388.267633 -279.528735) (xy 388.258558 -279.533096) (xy 388.18312 -279.574752) (xy 388.175355 -279.579447)
			(xy 388.163492 -279.593162) (xy 388.157112 -279.610137) (xy 388.156704 -279.619202) (xy 388.156704 -279.880314)
			(xy 388.157069 -279.88939) (xy 388.163416 -279.906394) (xy 388.175333 -279.920084) (xy 388.18312 -279.924764)
			(xy 388.258558 -279.96642) (xy 388.267607 -279.970862) (xy 388.287642 -279.97294) (xy 388.29742 -279.970484)
			(xy 388.312406 -279.966166) (xy 388.317994 -279.962864) (xy 388.341881 -279.949227) (xy 388.393355 -279.929854)
			(xy 388.447466 -279.920015) (xy 388.474966 -279.91943) (xy 388.500222 -279.91992) (xy 388.550047 -279.928229)
			(xy 388.597824 -279.944626) (xy 388.642251 -279.968664) (xy 388.682114 -279.999687) (xy 388.716328 -280.036849)
			(xy 388.743957 -280.079135) (xy 388.764249 -280.125393) (xy 388.77665 -280.17436) (xy 388.780822 -280.2247)
			(xy 388.780819 -280.224738) (xy 389.119122 -280.224738) (xy 389.123082 -280.175684) (xy 389.134859 -280.1279)
			(xy 389.15415 -280.082624) (xy 389.180453 -280.041028) (xy 389.213088 -280.004191) (xy 389.251209 -279.973066)
			(xy 389.29383 -279.948459) (xy 389.339846 -279.931007) (xy 389.388065 -279.921163) (xy 389.43724 -279.919182)
			(xy 389.486095 -279.925114) (xy 389.533366 -279.938806) (xy 389.577828 -279.959904) (xy 389.618331 -279.98786)
			(xy 389.653824 -280.021952) (xy 389.683389 -280.061296) (xy 389.70626 -280.104873) (xy 389.721844 -280.151554)
			(xy 389.729739 -280.200131) (xy 389.730234 -280.224738) (xy 390.069082 -280.224738) (xy 390.073042 -280.175684)
			(xy 390.084819 -280.1279) (xy 390.10411 -280.082624) (xy 390.130413 -280.041028) (xy 390.163048 -280.004191)
			(xy 390.201169 -279.973066) (xy 390.24379 -279.948459) (xy 390.289806 -279.931007) (xy 390.338025 -279.921163)
			(xy 390.3872 -279.919182) (xy 390.436055 -279.925114) (xy 390.483326 -279.938806) (xy 390.527788 -279.959904)
			(xy 390.568291 -279.98786) (xy 390.603784 -280.021952) (xy 390.633349 -280.061296) (xy 390.65622 -280.104873)
			(xy 390.671804 -280.151554) (xy 390.679699 -280.200131) (xy 390.680194 -280.224738) (xy 390.679699 -280.249345)
			(xy 390.671804 -280.297922) (xy 390.65622 -280.344603) (xy 390.633349 -280.38818) (xy 390.603784 -280.427524)
			(xy 390.568291 -280.461616) (xy 390.527788 -280.489572) (xy 390.483326 -280.51067) (xy 390.436055 -280.524362)
			(xy 390.3872 -280.530294) (xy 390.338025 -280.528313) (xy 390.289806 -280.518469) (xy 390.24379 -280.501017)
			(xy 390.201169 -280.47641) (xy 390.163048 -280.445285) (xy 390.130413 -280.408448) (xy 390.10411 -280.366852)
			(xy 390.084819 -280.321576) (xy 390.073042 -280.273792) (xy 390.069082 -280.224738) (xy 389.730234 -280.224738)
			(xy 389.729739 -280.249345) (xy 389.721844 -280.297922) (xy 389.70626 -280.344603) (xy 389.683389 -280.38818)
			(xy 389.653824 -280.427524) (xy 389.618331 -280.461616) (xy 389.577828 -280.489572) (xy 389.533366 -280.51067)
			(xy 389.486095 -280.524362) (xy 389.43724 -280.530294) (xy 389.388065 -280.528313) (xy 389.339846 -280.518469)
			(xy 389.29383 -280.501017) (xy 389.251209 -280.47641) (xy 389.213088 -280.445285) (xy 389.180453 -280.408448)
			(xy 389.15415 -280.366852) (xy 389.134859 -280.321576) (xy 389.123082 -280.273792) (xy 389.119122 -280.224738)
			(xy 388.780819 -280.224738) (xy 388.77665 -280.27504) (xy 388.764249 -280.324007) (xy 388.743957 -280.370265)
			(xy 388.716328 -280.412551) (xy 388.682114 -280.449713) (xy 388.642251 -280.480736) (xy 388.597824 -280.504774)
			(xy 388.550047 -280.521171) (xy 388.500222 -280.52948) (xy 388.474966 -280.530046) (xy 388.474712 -280.530046)
			(xy 388.447193 -280.529438) (xy 388.39305 -280.519547) (xy 388.341548 -280.500135) (xy 388.294346 -280.471827)
			(xy 388.27329 -280.4541) (xy 388.266686 -280.448258) (xy 388.246112 -280.44013) (xy 388.237224 -280.437107)
			(xy 388.218466 -280.436979) (xy 388.209536 -280.439876) (xy 388.18947 -280.447496) (xy 388.180032 -280.451581)
			(xy 388.165215 -280.465817) (xy 388.157161 -280.48472) (xy 388.156704 -280.494994) (xy 388.156704 -280.502614)
			(xy 388.156278 -280.512683) (xy 388.148561 -280.531284) (xy 388.141718 -280.538682) (xy 387.77926 -280.90114)
			(xy 387.775958 -280.90495) (xy 387.775704 -280.90495) (xy 387.770936 -280.911412) (xy 387.765241 -280.926416)
			(xy 387.764528 -280.934414) (xy 387.763004 -280.963878) (xy 387.763004 -280.968958) (xy 387.763627 -280.976322)
			(xy 387.768535 -280.990255) (xy 387.772656 -280.99639) (xy 387.78623 -281.016008) (xy 387.807766 -281.058576)
			(xy 387.822418 -281.103974) (xy 387.82983 -281.1511) (xy 387.830314 -281.174952) (xy 388.169162 -281.174952)
			(xy 388.173122 -281.125898) (xy 388.184899 -281.078114) (xy 388.20419 -281.032838) (xy 388.230493 -280.991242)
			(xy 388.263128 -280.954405) (xy 388.301249 -280.92328) (xy 388.34387 -280.898673) (xy 388.389886 -280.881221)
			(xy 388.438105 -280.871377) (xy 388.48728 -280.869396) (xy 388.536135 -280.875328) (xy 388.583406 -280.88902)
			(xy 388.627868 -280.910118) (xy 388.668371 -280.938074) (xy 388.703864 -280.972166) (xy 388.733429 -281.01151)
			(xy 388.7563 -281.055087) (xy 388.771884 -281.101768) (xy 388.779779 -281.150345) (xy 388.780274 -281.174952)
			(xy 389.119122 -281.174952) (xy 389.123082 -281.125898) (xy 389.134859 -281.078114) (xy 389.15415 -281.032838)
			(xy 389.180453 -280.991242) (xy 389.213088 -280.954405) (xy 389.251209 -280.92328) (xy 389.29383 -280.898673)
			(xy 389.339846 -280.881221) (xy 389.388065 -280.871377) (xy 389.43724 -280.869396) (xy 389.486095 -280.875328)
			(xy 389.533366 -280.88902) (xy 389.577828 -280.910118) (xy 389.618331 -280.938074) (xy 389.653824 -280.972166)
			(xy 389.683389 -281.01151) (xy 389.70626 -281.055087) (xy 389.721844 -281.101768) (xy 389.729739 -281.150345)
			(xy 389.730234 -281.174952) (xy 390.069082 -281.174952) (xy 390.073042 -281.125898) (xy 390.084819 -281.078114)
			(xy 390.10411 -281.032838) (xy 390.130413 -280.991242) (xy 390.163048 -280.954405) (xy 390.201169 -280.92328)
			(xy 390.24379 -280.898673) (xy 390.289806 -280.881221) (xy 390.338025 -280.871377) (xy 390.3872 -280.869396)
			(xy 390.436055 -280.875328) (xy 390.483326 -280.88902) (xy 390.527788 -280.910118) (xy 390.568291 -280.938074)
			(xy 390.603784 -280.972166) (xy 390.633349 -281.01151) (xy 390.65622 -281.055087) (xy 390.671804 -281.101768)
			(xy 390.679699 -281.150345) (xy 390.680194 -281.174952) (xy 390.679699 -281.199559) (xy 390.671804 -281.248136)
			(xy 390.65622 -281.294817) (xy 390.633349 -281.338394) (xy 390.603784 -281.377738) (xy 390.568291 -281.41183)
			(xy 390.527788 -281.439786) (xy 390.483326 -281.460884) (xy 390.436055 -281.474576) (xy 390.3872 -281.480508)
			(xy 390.338025 -281.478527) (xy 390.289806 -281.468683) (xy 390.24379 -281.451231) (xy 390.201169 -281.426624)
			(xy 390.163048 -281.395499) (xy 390.130413 -281.358662) (xy 390.10411 -281.317066) (xy 390.084819 -281.27179)
			(xy 390.073042 -281.224006) (xy 390.069082 -281.174952) (xy 389.730234 -281.174952) (xy 389.729739 -281.199559)
			(xy 389.721844 -281.248136) (xy 389.70626 -281.294817) (xy 389.683389 -281.338394) (xy 389.653824 -281.377738)
			(xy 389.618331 -281.41183) (xy 389.577828 -281.439786) (xy 389.533366 -281.460884) (xy 389.486095 -281.474576)
			(xy 389.43724 -281.480508) (xy 389.388065 -281.478527) (xy 389.339846 -281.468683) (xy 389.29383 -281.451231)
			(xy 389.251209 -281.426624) (xy 389.213088 -281.395499) (xy 389.180453 -281.358662) (xy 389.15415 -281.317066)
			(xy 389.134859 -281.27179) (xy 389.123082 -281.224006) (xy 389.119122 -281.174952) (xy 388.780274 -281.174952)
			(xy 388.779779 -281.199559) (xy 388.771884 -281.248136) (xy 388.7563 -281.294817) (xy 388.733429 -281.338394)
			(xy 388.703864 -281.377738) (xy 388.668371 -281.41183) (xy 388.627868 -281.439786) (xy 388.583406 -281.460884)
			(xy 388.536135 -281.474576) (xy 388.48728 -281.480508) (xy 388.438105 -281.478527) (xy 388.389886 -281.468683)
			(xy 388.34387 -281.451231) (xy 388.301249 -281.426624) (xy 388.263128 -281.395499) (xy 388.230493 -281.358662)
			(xy 388.20419 -281.317066) (xy 388.184899 -281.27179) (xy 388.173122 -281.224006) (xy 388.169162 -281.174952)
			(xy 387.830314 -281.174952) (xy 387.829871 -281.198948) (xy 387.822371 -281.246349) (xy 387.807546 -281.291994)
			(xy 387.785764 -281.334757) (xy 387.757559 -281.373586) (xy 387.723627 -281.407524) (xy 387.684803 -281.435735)
			(xy 387.642044 -281.457526) (xy 387.596402 -281.472358) (xy 387.549002 -281.479867) (xy 387.525006 -281.48026)
			(xy 387.501152 -281.479801) (xy 387.454025 -281.472382) (xy 387.408625 -281.457725) (xy 387.366057 -281.436186)
			(xy 387.346444 -281.422602) (xy 387.341123 -281.418986) (xy 387.329172 -281.414237) (xy 387.322822 -281.413204)
			(xy 387.313932 -281.41295) (xy 387.284468 -281.414474) (xy 387.275163 -281.415346) (xy 387.258084 -281.422894)
			(xy 387.251194 -281.429206) (xy 386.8293 -281.8511) (xy 386.825998 -281.85491) (xy 386.825744 -281.85491)
			(xy 386.820976 -281.861372) (xy 386.815276 -281.876375) (xy 386.814568 -281.884374) (xy 386.813044 -281.913838)
			(xy 386.813044 -281.918918) (xy 386.81366 -281.926285) (xy 386.818555 -281.940227) (xy 386.822696 -281.94635)
			(xy 386.836275 -281.965967) (xy 386.85782 -282.008532) (xy 386.872481 -282.053931) (xy 386.879901 -282.101058)
			(xy 386.880354 -282.124912) (xy 387.219202 -282.124912) (xy 387.223162 -282.075858) (xy 387.234939 -282.028074)
			(xy 387.25423 -281.982798) (xy 387.280533 -281.941202) (xy 387.313168 -281.904365) (xy 387.351289 -281.87324)
			(xy 387.39391 -281.848633) (xy 387.439926 -281.831181) (xy 387.488145 -281.821337) (xy 387.53732 -281.819356)
			(xy 387.586175 -281.825288) (xy 387.633446 -281.83898) (xy 387.677908 -281.860078) (xy 387.718411 -281.888034)
			(xy 387.753904 -281.922126) (xy 387.783469 -281.96147) (xy 387.80634 -282.005047) (xy 387.821924 -282.051728)
			(xy 387.829819 -282.100305) (xy 387.830314 -282.124912) (xy 388.169162 -282.124912) (xy 388.173122 -282.075858)
			(xy 388.184899 -282.028074) (xy 388.20419 -281.982798) (xy 388.230493 -281.941202) (xy 388.263128 -281.904365)
			(xy 388.301249 -281.87324) (xy 388.34387 -281.848633) (xy 388.389886 -281.831181) (xy 388.438105 -281.821337)
			(xy 388.48728 -281.819356) (xy 388.536135 -281.825288) (xy 388.583406 -281.83898) (xy 388.627868 -281.860078)
			(xy 388.668371 -281.888034) (xy 388.703864 -281.922126) (xy 388.733429 -281.96147) (xy 388.7563 -282.005047)
			(xy 388.771884 -282.051728) (xy 388.779779 -282.100305) (xy 388.780274 -282.124912) (xy 389.119122 -282.124912)
			(xy 389.123082 -282.075858) (xy 389.134859 -282.028074) (xy 389.15415 -281.982798) (xy 389.180453 -281.941202)
			(xy 389.213088 -281.904365) (xy 389.251209 -281.87324) (xy 389.29383 -281.848633) (xy 389.339846 -281.831181)
			(xy 389.388065 -281.821337) (xy 389.43724 -281.819356) (xy 389.486095 -281.825288) (xy 389.533366 -281.83898)
			(xy 389.577828 -281.860078) (xy 389.618331 -281.888034) (xy 389.653824 -281.922126) (xy 389.683389 -281.96147)
			(xy 389.70626 -282.005047) (xy 389.721844 -282.051728) (xy 389.729739 -282.100305) (xy 389.730234 -282.124912)
			(xy 390.069082 -282.124912) (xy 390.073042 -282.075858) (xy 390.084819 -282.028074) (xy 390.10411 -281.982798)
			(xy 390.130413 -281.941202) (xy 390.163048 -281.904365) (xy 390.201169 -281.87324) (xy 390.24379 -281.848633)
			(xy 390.289806 -281.831181) (xy 390.338025 -281.821337) (xy 390.3872 -281.819356) (xy 390.436055 -281.825288)
			(xy 390.483326 -281.83898) (xy 390.527788 -281.860078) (xy 390.568291 -281.888034) (xy 390.603784 -281.922126)
			(xy 390.633349 -281.96147) (xy 390.65622 -282.005047) (xy 390.671804 -282.051728) (xy 390.679699 -282.100305)
			(xy 390.680194 -282.124912) (xy 390.679699 -282.149519) (xy 390.671804 -282.198096) (xy 390.65622 -282.244777)
			(xy 390.633349 -282.288354) (xy 390.603784 -282.327698) (xy 390.568291 -282.36179) (xy 390.527788 -282.389746)
			(xy 390.483326 -282.410844) (xy 390.436055 -282.424536) (xy 390.3872 -282.430468) (xy 390.338025 -282.428487)
			(xy 390.289806 -282.418643) (xy 390.24379 -282.401191) (xy 390.201169 -282.376584) (xy 390.163048 -282.345459)
			(xy 390.130413 -282.308622) (xy 390.10411 -282.267026) (xy 390.084819 -282.22175) (xy 390.073042 -282.173966)
			(xy 390.069082 -282.124912) (xy 389.730234 -282.124912) (xy 389.729739 -282.149519) (xy 389.721844 -282.198096)
			(xy 389.70626 -282.244777) (xy 389.683389 -282.288354) (xy 389.653824 -282.327698) (xy 389.618331 -282.36179)
			(xy 389.577828 -282.389746) (xy 389.533366 -282.410844) (xy 389.486095 -282.424536) (xy 389.43724 -282.430468)
			(xy 389.388065 -282.428487) (xy 389.339846 -282.418643) (xy 389.29383 -282.401191) (xy 389.251209 -282.376584)
			(xy 389.213088 -282.345459) (xy 389.180453 -282.308622) (xy 389.15415 -282.267026) (xy 389.134859 -282.22175)
			(xy 389.123082 -282.173966) (xy 389.119122 -282.124912) (xy 388.780274 -282.124912) (xy 388.779779 -282.149519)
			(xy 388.771884 -282.198096) (xy 388.7563 -282.244777) (xy 388.733429 -282.288354) (xy 388.703864 -282.327698)
			(xy 388.668371 -282.36179) (xy 388.627868 -282.389746) (xy 388.583406 -282.410844) (xy 388.536135 -282.424536)
			(xy 388.48728 -282.430468) (xy 388.438105 -282.428487) (xy 388.389886 -282.418643) (xy 388.34387 -282.401191)
			(xy 388.301249 -282.376584) (xy 388.263128 -282.345459) (xy 388.230493 -282.308622) (xy 388.20419 -282.267026)
			(xy 388.184899 -282.22175) (xy 388.173122 -282.173966) (xy 388.169162 -282.124912) (xy 387.830314 -282.124912)
			(xy 387.829819 -282.149519) (xy 387.821924 -282.198096) (xy 387.80634 -282.244777) (xy 387.783469 -282.288354)
			(xy 387.753904 -282.327698) (xy 387.718411 -282.36179) (xy 387.677908 -282.389746) (xy 387.633446 -282.410844)
			(xy 387.586175 -282.424536) (xy 387.53732 -282.430468) (xy 387.488145 -282.428487) (xy 387.439926 -282.418643)
			(xy 387.39391 -282.401191) (xy 387.351289 -282.376584) (xy 387.313168 -282.345459) (xy 387.280533 -282.308622)
			(xy 387.25423 -282.267026) (xy 387.234939 -282.22175) (xy 387.223162 -282.173966) (xy 387.219202 -282.124912)
			(xy 386.880354 -282.124912) (xy 386.879883 -282.148904) (xy 386.872375 -282.196297) (xy 386.857547 -282.241932)
			(xy 386.835764 -282.284687) (xy 386.807561 -282.323507) (xy 386.773633 -282.357439) (xy 386.734816 -282.385646)
			(xy 386.692064 -282.407434) (xy 386.64643 -282.422267) (xy 386.599038 -282.42978) (xy 386.575046 -282.43022)
			(xy 386.551194 -282.429756) (xy 386.504072 -282.422329) (xy 386.458678 -282.407663) (xy 386.416118 -282.386115)
			(xy 386.396484 -282.372562) (xy 386.389295 -282.367865) (xy 386.372814 -282.363074) (xy 386.364226 -282.363164)
			(xy 386.334254 -282.364688) (xy 386.32495 -282.365562) (xy 386.307876 -282.373115) (xy 386.30098 -282.37942)
			(xy 385.87934 -282.80106) (xy 385.873063 -282.807975) (xy 385.865513 -282.825039) (xy 385.864608 -282.834334)
			(xy 385.863084 -282.864052) (xy 385.862942 -282.872645) (xy 385.867752 -282.889133) (xy 385.872482 -282.89631)
			(xy 385.886064 -282.915926) (xy 385.907616 -282.95849) (xy 385.922284 -283.003889) (xy 385.92971 -283.051017)
			(xy 385.93014 -283.074872) (xy 386.269242 -283.074872) (xy 386.273202 -283.025818) (xy 386.284979 -282.978034)
			(xy 386.30427 -282.932758) (xy 386.330573 -282.891162) (xy 386.363208 -282.854325) (xy 386.401329 -282.8232)
			(xy 386.44395 -282.798593) (xy 386.489966 -282.781141) (xy 386.538185 -282.771297) (xy 386.58736 -282.769316)
			(xy 386.636215 -282.775248) (xy 386.683486 -282.78894) (xy 386.727948 -282.810038) (xy 386.768451 -282.837994)
			(xy 386.803944 -282.872086) (xy 386.833509 -282.91143) (xy 386.85638 -282.955007) (xy 386.871964 -283.001688)
			(xy 386.879859 -283.050265) (xy 386.880354 -283.074872) (xy 387.219202 -283.074872) (xy 387.223162 -283.025818)
			(xy 387.234939 -282.978034) (xy 387.25423 -282.932758) (xy 387.280533 -282.891162) (xy 387.313168 -282.854325)
			(xy 387.351289 -282.8232) (xy 387.39391 -282.798593) (xy 387.439926 -282.781141) (xy 387.488145 -282.771297)
			(xy 387.53732 -282.769316) (xy 387.586175 -282.775248) (xy 387.633446 -282.78894) (xy 387.677908 -282.810038)
			(xy 387.718411 -282.837994) (xy 387.753904 -282.872086) (xy 387.783469 -282.91143) (xy 387.80634 -282.955007)
			(xy 387.821924 -283.001688) (xy 387.829819 -283.050265) (xy 387.830314 -283.074872) (xy 388.169162 -283.074872)
			(xy 388.173122 -283.025818) (xy 388.184899 -282.978034) (xy 388.20419 -282.932758) (xy 388.230493 -282.891162)
			(xy 388.263128 -282.854325) (xy 388.301249 -282.8232) (xy 388.34387 -282.798593) (xy 388.389886 -282.781141)
			(xy 388.438105 -282.771297) (xy 388.48728 -282.769316) (xy 388.536135 -282.775248) (xy 388.583406 -282.78894)
			(xy 388.627868 -282.810038) (xy 388.668371 -282.837994) (xy 388.703864 -282.872086) (xy 388.733429 -282.91143)
			(xy 388.7563 -282.955007) (xy 388.771884 -283.001688) (xy 388.779779 -283.050265) (xy 388.780274 -283.074872)
			(xy 389.119122 -283.074872) (xy 389.123082 -283.025818) (xy 389.134859 -282.978034) (xy 389.15415 -282.932758)
			(xy 389.180453 -282.891162) (xy 389.213088 -282.854325) (xy 389.251209 -282.8232) (xy 389.29383 -282.798593)
			(xy 389.339846 -282.781141) (xy 389.388065 -282.771297) (xy 389.43724 -282.769316) (xy 389.486095 -282.775248)
			(xy 389.533366 -282.78894) (xy 389.577828 -282.810038) (xy 389.618331 -282.837994) (xy 389.653824 -282.872086)
			(xy 389.683389 -282.91143) (xy 389.70626 -282.955007) (xy 389.721844 -283.001688) (xy 389.729739 -283.050265)
			(xy 389.730234 -283.074872) (xy 390.069082 -283.074872) (xy 390.073042 -283.025818) (xy 390.084819 -282.978034)
			(xy 390.10411 -282.932758) (xy 390.130413 -282.891162) (xy 390.163048 -282.854325) (xy 390.201169 -282.8232)
			(xy 390.24379 -282.798593) (xy 390.289806 -282.781141) (xy 390.338025 -282.771297) (xy 390.3872 -282.769316)
			(xy 390.436055 -282.775248) (xy 390.483326 -282.78894) (xy 390.527788 -282.810038) (xy 390.568291 -282.837994)
			(xy 390.603784 -282.872086) (xy 390.633349 -282.91143) (xy 390.65622 -282.955007) (xy 390.671804 -283.001688)
			(xy 390.679699 -283.050265) (xy 390.680194 -283.074872) (xy 391.019042 -283.074872) (xy 391.023002 -283.025818)
			(xy 391.034779 -282.978034) (xy 391.05407 -282.932758) (xy 391.080373 -282.891162) (xy 391.113008 -282.854325)
			(xy 391.151129 -282.8232) (xy 391.19375 -282.798593) (xy 391.239766 -282.781141) (xy 391.287985 -282.771297)
			(xy 391.33716 -282.769316) (xy 391.386015 -282.775248) (xy 391.433286 -282.78894) (xy 391.477748 -282.810038)
			(xy 391.518251 -282.837994) (xy 391.553744 -282.872086) (xy 391.583309 -282.91143) (xy 391.60618 -282.955007)
			(xy 391.621764 -283.001688) (xy 391.629659 -283.050265) (xy 391.630154 -283.074872) (xy 391.969002 -283.074872)
			(xy 391.972962 -283.025818) (xy 391.984739 -282.978034) (xy 392.00403 -282.932758) (xy 392.030333 -282.891162)
			(xy 392.062968 -282.854325) (xy 392.101089 -282.8232) (xy 392.14371 -282.798593) (xy 392.189726 -282.781141)
			(xy 392.237945 -282.771297) (xy 392.28712 -282.769316) (xy 392.335975 -282.775248) (xy 392.383246 -282.78894)
			(xy 392.427708 -282.810038) (xy 392.468211 -282.837994) (xy 392.503704 -282.872086) (xy 392.533269 -282.91143)
			(xy 392.55614 -282.955007) (xy 392.571724 -283.001688) (xy 392.579619 -283.050265) (xy 392.580114 -283.074872)
			(xy 392.919216 -283.074872) (xy 392.923176 -283.025818) (xy 392.934953 -282.978034) (xy 392.954244 -282.932758)
			(xy 392.980547 -282.891162) (xy 393.013182 -282.854325) (xy 393.051303 -282.8232) (xy 393.093924 -282.798593)
			(xy 393.13994 -282.781141) (xy 393.188159 -282.771297) (xy 393.237334 -282.769316) (xy 393.286189 -282.775248)
			(xy 393.33346 -282.78894) (xy 393.377922 -282.810038) (xy 393.418425 -282.837994) (xy 393.453918 -282.872086)
			(xy 393.483483 -282.91143) (xy 393.506354 -282.955007) (xy 393.521938 -283.001688) (xy 393.529833 -283.050265)
			(xy 393.530328 -283.074872) (xy 393.869176 -283.074872) (xy 393.873136 -283.025818) (xy 393.884913 -282.978034)
			(xy 393.904204 -282.932758) (xy 393.930507 -282.891162) (xy 393.963142 -282.854325) (xy 394.001263 -282.8232)
			(xy 394.043884 -282.798593) (xy 394.0899 -282.781141) (xy 394.138119 -282.771297) (xy 394.187294 -282.769316)
			(xy 394.236149 -282.775248) (xy 394.28342 -282.78894) (xy 394.327882 -282.810038) (xy 394.368385 -282.837994)
			(xy 394.403878 -282.872086) (xy 394.433443 -282.91143) (xy 394.456314 -282.955007) (xy 394.471898 -283.001688)
			(xy 394.479793 -283.050265) (xy 394.480288 -283.074872) (xy 394.819136 -283.074872) (xy 394.823096 -283.025818)
			(xy 394.834873 -282.978034) (xy 394.854164 -282.932758) (xy 394.880467 -282.891162) (xy 394.913102 -282.854325)
			(xy 394.951223 -282.8232) (xy 394.993844 -282.798593) (xy 395.03986 -282.781141) (xy 395.088079 -282.771297)
			(xy 395.137254 -282.769316) (xy 395.186109 -282.775248) (xy 395.23338 -282.78894) (xy 395.277842 -282.810038)
			(xy 395.318345 -282.837994) (xy 395.353838 -282.872086) (xy 395.383403 -282.91143) (xy 395.406274 -282.955007)
			(xy 395.421858 -283.001688) (xy 395.429753 -283.050265) (xy 395.430248 -283.074872) (xy 395.769096 -283.074872)
			(xy 395.773056 -283.025818) (xy 395.784833 -282.978034) (xy 395.804124 -282.932758) (xy 395.830427 -282.891162)
			(xy 395.863062 -282.854325) (xy 395.901183 -282.8232) (xy 395.943804 -282.798593) (xy 395.98982 -282.781141)
			(xy 396.038039 -282.771297) (xy 396.087214 -282.769316) (xy 396.136069 -282.775248) (xy 396.18334 -282.78894)
			(xy 396.227802 -282.810038) (xy 396.268305 -282.837994) (xy 396.303798 -282.872086) (xy 396.333363 -282.91143)
			(xy 396.356234 -282.955007) (xy 396.371818 -283.001688) (xy 396.379713 -283.050265) (xy 396.380208 -283.074872)
			(xy 396.719056 -283.074872) (xy 396.723016 -283.025818) (xy 396.734793 -282.978034) (xy 396.754084 -282.932758)
			(xy 396.780387 -282.891162) (xy 396.813022 -282.854325) (xy 396.851143 -282.8232) (xy 396.893764 -282.798593)
			(xy 396.93978 -282.781141) (xy 396.987999 -282.771297) (xy 397.037174 -282.769316) (xy 397.086029 -282.775248)
			(xy 397.1333 -282.78894) (xy 397.177762 -282.810038) (xy 397.218265 -282.837994) (xy 397.253758 -282.872086)
			(xy 397.283323 -282.91143) (xy 397.306194 -282.955007) (xy 397.321778 -283.001688) (xy 397.329673 -283.050265)
			(xy 397.330168 -283.074872) (xy 397.669016 -283.074872) (xy 397.672976 -283.025818) (xy 397.684753 -282.978034)
			(xy 397.704044 -282.932758) (xy 397.730347 -282.891162) (xy 397.762982 -282.854325) (xy 397.801103 -282.8232)
			(xy 397.843724 -282.798593) (xy 397.88974 -282.781141) (xy 397.937959 -282.771297) (xy 397.987134 -282.769316)
			(xy 398.035989 -282.775248) (xy 398.08326 -282.78894) (xy 398.127722 -282.810038) (xy 398.168225 -282.837994)
			(xy 398.203718 -282.872086) (xy 398.233283 -282.91143) (xy 398.256154 -282.955007) (xy 398.271738 -283.001688)
			(xy 398.279633 -283.050265) (xy 398.280128 -283.074872) (xy 398.61923 -283.074872) (xy 398.62319 -283.025818)
			(xy 398.634967 -282.978034) (xy 398.654258 -282.932758) (xy 398.680561 -282.891162) (xy 398.713196 -282.854325)
			(xy 398.751317 -282.8232) (xy 398.793938 -282.798593) (xy 398.839954 -282.781141) (xy 398.888173 -282.771297)
			(xy 398.937348 -282.769316) (xy 398.986203 -282.775248) (xy 399.033474 -282.78894) (xy 399.077936 -282.810038)
			(xy 399.118439 -282.837994) (xy 399.153932 -282.872086) (xy 399.183497 -282.91143) (xy 399.206368 -282.955007)
			(xy 399.221952 -283.001688) (xy 399.229847 -283.050265) (xy 399.230342 -283.074872) (xy 399.56919 -283.074872)
			(xy 399.57315 -283.025818) (xy 399.584927 -282.978034) (xy 399.604218 -282.932758) (xy 399.630521 -282.891162)
			(xy 399.663156 -282.854325) (xy 399.701277 -282.8232) (xy 399.743898 -282.798593) (xy 399.789914 -282.781141)
			(xy 399.838133 -282.771297) (xy 399.887308 -282.769316) (xy 399.936163 -282.775248) (xy 399.983434 -282.78894)
			(xy 400.027896 -282.810038) (xy 400.068399 -282.837994) (xy 400.103892 -282.872086) (xy 400.133457 -282.91143)
			(xy 400.156328 -282.955007) (xy 400.171912 -283.001688) (xy 400.179807 -283.050265) (xy 400.180302 -283.074872)
			(xy 400.51915 -283.074872) (xy 400.52311 -283.025818) (xy 400.534887 -282.978034) (xy 400.554178 -282.932758)
			(xy 400.580481 -282.891162) (xy 400.613116 -282.854325) (xy 400.651237 -282.8232) (xy 400.693858 -282.798593)
			(xy 400.739874 -282.781141) (xy 400.788093 -282.771297) (xy 400.837268 -282.769316) (xy 400.886123 -282.775248)
			(xy 400.933394 -282.78894) (xy 400.977856 -282.810038) (xy 401.018359 -282.837994) (xy 401.053852 -282.872086)
			(xy 401.083417 -282.91143) (xy 401.106288 -282.955007) (xy 401.121872 -283.001688) (xy 401.129767 -283.050265)
			(xy 401.130262 -283.074872) (xy 401.46911 -283.074872) (xy 401.47307 -283.025818) (xy 401.484847 -282.978034)
			(xy 401.504138 -282.932758) (xy 401.530441 -282.891162) (xy 401.563076 -282.854325) (xy 401.601197 -282.8232)
			(xy 401.643818 -282.798593) (xy 401.689834 -282.781141) (xy 401.738053 -282.771297) (xy 401.787228 -282.769316)
			(xy 401.836083 -282.775248) (xy 401.883354 -282.78894) (xy 401.927816 -282.810038) (xy 401.968319 -282.837994)
			(xy 402.003812 -282.872086) (xy 402.033377 -282.91143) (xy 402.056248 -282.955007) (xy 402.071832 -283.001688)
			(xy 402.079727 -283.050265) (xy 402.080222 -283.074872) (xy 402.079727 -283.099479) (xy 402.071832 -283.148056)
			(xy 402.056248 -283.194737) (xy 402.033377 -283.238314) (xy 402.003812 -283.277658) (xy 401.968319 -283.31175)
			(xy 401.927816 -283.339706) (xy 401.883354 -283.360804) (xy 401.836083 -283.374496) (xy 401.787228 -283.380428)
			(xy 401.738053 -283.378447) (xy 401.689834 -283.368603) (xy 401.643818 -283.351151) (xy 401.601197 -283.326544)
			(xy 401.563076 -283.295419) (xy 401.530441 -283.258582) (xy 401.504138 -283.216986) (xy 401.484847 -283.17171)
			(xy 401.47307 -283.123926) (xy 401.46911 -283.074872) (xy 401.130262 -283.074872) (xy 401.129767 -283.099479)
			(xy 401.121872 -283.148056) (xy 401.106288 -283.194737) (xy 401.083417 -283.238314) (xy 401.053852 -283.277658)
			(xy 401.018359 -283.31175) (xy 400.977856 -283.339706) (xy 400.933394 -283.360804) (xy 400.886123 -283.374496)
			(xy 400.837268 -283.380428) (xy 400.788093 -283.378447) (xy 400.739874 -283.368603) (xy 400.693858 -283.351151)
			(xy 400.651237 -283.326544) (xy 400.613116 -283.295419) (xy 400.580481 -283.258582) (xy 400.554178 -283.216986)
			(xy 400.534887 -283.17171) (xy 400.52311 -283.123926) (xy 400.51915 -283.074872) (xy 400.180302 -283.074872)
			(xy 400.179807 -283.099479) (xy 400.171912 -283.148056) (xy 400.156328 -283.194737) (xy 400.133457 -283.238314)
			(xy 400.103892 -283.277658) (xy 400.068399 -283.31175) (xy 400.027896 -283.339706) (xy 399.983434 -283.360804)
			(xy 399.936163 -283.374496) (xy 399.887308 -283.380428) (xy 399.838133 -283.378447) (xy 399.789914 -283.368603)
			(xy 399.743898 -283.351151) (xy 399.701277 -283.326544) (xy 399.663156 -283.295419) (xy 399.630521 -283.258582)
			(xy 399.604218 -283.216986) (xy 399.584927 -283.17171) (xy 399.57315 -283.123926) (xy 399.56919 -283.074872)
			(xy 399.230342 -283.074872) (xy 399.229847 -283.099479) (xy 399.221952 -283.148056) (xy 399.206368 -283.194737)
			(xy 399.183497 -283.238314) (xy 399.153932 -283.277658) (xy 399.118439 -283.31175) (xy 399.077936 -283.339706)
			(xy 399.033474 -283.360804) (xy 398.986203 -283.374496) (xy 398.937348 -283.380428) (xy 398.888173 -283.378447)
			(xy 398.839954 -283.368603) (xy 398.793938 -283.351151) (xy 398.751317 -283.326544) (xy 398.713196 -283.295419)
			(xy 398.680561 -283.258582) (xy 398.654258 -283.216986) (xy 398.634967 -283.17171) (xy 398.62319 -283.123926)
			(xy 398.61923 -283.074872) (xy 398.280128 -283.074872) (xy 398.279633 -283.099479) (xy 398.271738 -283.148056)
			(xy 398.256154 -283.194737) (xy 398.233283 -283.238314) (xy 398.203718 -283.277658) (xy 398.168225 -283.31175)
			(xy 398.127722 -283.339706) (xy 398.08326 -283.360804) (xy 398.035989 -283.374496) (xy 397.987134 -283.380428)
			(xy 397.937959 -283.378447) (xy 397.88974 -283.368603) (xy 397.843724 -283.351151) (xy 397.801103 -283.326544)
			(xy 397.762982 -283.295419) (xy 397.730347 -283.258582) (xy 397.704044 -283.216986) (xy 397.684753 -283.17171)
			(xy 397.672976 -283.123926) (xy 397.669016 -283.074872) (xy 397.330168 -283.074872) (xy 397.329673 -283.099479)
			(xy 397.321778 -283.148056) (xy 397.306194 -283.194737) (xy 397.283323 -283.238314) (xy 397.253758 -283.277658)
			(xy 397.218265 -283.31175) (xy 397.177762 -283.339706) (xy 397.1333 -283.360804) (xy 397.086029 -283.374496)
			(xy 397.037174 -283.380428) (xy 396.987999 -283.378447) (xy 396.93978 -283.368603) (xy 396.893764 -283.351151)
			(xy 396.851143 -283.326544) (xy 396.813022 -283.295419) (xy 396.780387 -283.258582) (xy 396.754084 -283.216986)
			(xy 396.734793 -283.17171) (xy 396.723016 -283.123926) (xy 396.719056 -283.074872) (xy 396.380208 -283.074872)
			(xy 396.379713 -283.099479) (xy 396.371818 -283.148056) (xy 396.356234 -283.194737) (xy 396.333363 -283.238314)
			(xy 396.303798 -283.277658) (xy 396.268305 -283.31175) (xy 396.227802 -283.339706) (xy 396.18334 -283.360804)
			(xy 396.136069 -283.374496) (xy 396.087214 -283.380428) (xy 396.038039 -283.378447) (xy 395.98982 -283.368603)
			(xy 395.943804 -283.351151) (xy 395.901183 -283.326544) (xy 395.863062 -283.295419) (xy 395.830427 -283.258582)
			(xy 395.804124 -283.216986) (xy 395.784833 -283.17171) (xy 395.773056 -283.123926) (xy 395.769096 -283.074872)
			(xy 395.430248 -283.074872) (xy 395.429753 -283.099479) (xy 395.421858 -283.148056) (xy 395.406274 -283.194737)
			(xy 395.383403 -283.238314) (xy 395.353838 -283.277658) (xy 395.318345 -283.31175) (xy 395.277842 -283.339706)
			(xy 395.23338 -283.360804) (xy 395.186109 -283.374496) (xy 395.137254 -283.380428) (xy 395.088079 -283.378447)
			(xy 395.03986 -283.368603) (xy 394.993844 -283.351151) (xy 394.951223 -283.326544) (xy 394.913102 -283.295419)
			(xy 394.880467 -283.258582) (xy 394.854164 -283.216986) (xy 394.834873 -283.17171) (xy 394.823096 -283.123926)
			(xy 394.819136 -283.074872) (xy 394.480288 -283.074872) (xy 394.479793 -283.099479) (xy 394.471898 -283.148056)
			(xy 394.456314 -283.194737) (xy 394.433443 -283.238314) (xy 394.403878 -283.277658) (xy 394.368385 -283.31175)
			(xy 394.327882 -283.339706) (xy 394.28342 -283.360804) (xy 394.236149 -283.374496) (xy 394.187294 -283.380428)
			(xy 394.138119 -283.378447) (xy 394.0899 -283.368603) (xy 394.043884 -283.351151) (xy 394.001263 -283.326544)
			(xy 393.963142 -283.295419) (xy 393.930507 -283.258582) (xy 393.904204 -283.216986) (xy 393.884913 -283.17171)
			(xy 393.873136 -283.123926) (xy 393.869176 -283.074872) (xy 393.530328 -283.074872) (xy 393.529833 -283.099479)
			(xy 393.521938 -283.148056) (xy 393.506354 -283.194737) (xy 393.483483 -283.238314) (xy 393.453918 -283.277658)
			(xy 393.418425 -283.31175) (xy 393.377922 -283.339706) (xy 393.33346 -283.360804) (xy 393.286189 -283.374496)
			(xy 393.237334 -283.380428) (xy 393.188159 -283.378447) (xy 393.13994 -283.368603) (xy 393.093924 -283.351151)
			(xy 393.051303 -283.326544) (xy 393.013182 -283.295419) (xy 392.980547 -283.258582) (xy 392.954244 -283.216986)
			(xy 392.934953 -283.17171) (xy 392.923176 -283.123926) (xy 392.919216 -283.074872) (xy 392.580114 -283.074872)
			(xy 392.579619 -283.099479) (xy 392.571724 -283.148056) (xy 392.55614 -283.194737) (xy 392.533269 -283.238314)
			(xy 392.503704 -283.277658) (xy 392.468211 -283.31175) (xy 392.427708 -283.339706) (xy 392.383246 -283.360804)
			(xy 392.335975 -283.374496) (xy 392.28712 -283.380428) (xy 392.237945 -283.378447) (xy 392.189726 -283.368603)
			(xy 392.14371 -283.351151) (xy 392.101089 -283.326544) (xy 392.062968 -283.295419) (xy 392.030333 -283.258582)
			(xy 392.00403 -283.216986) (xy 391.984739 -283.17171) (xy 391.972962 -283.123926) (xy 391.969002 -283.074872)
			(xy 391.630154 -283.074872) (xy 391.629659 -283.099479) (xy 391.621764 -283.148056) (xy 391.60618 -283.194737)
			(xy 391.583309 -283.238314) (xy 391.553744 -283.277658) (xy 391.518251 -283.31175) (xy 391.477748 -283.339706)
			(xy 391.433286 -283.360804) (xy 391.386015 -283.374496) (xy 391.33716 -283.380428) (xy 391.287985 -283.378447)
			(xy 391.239766 -283.368603) (xy 391.19375 -283.351151) (xy 391.151129 -283.326544) (xy 391.113008 -283.295419)
			(xy 391.080373 -283.258582) (xy 391.05407 -283.216986) (xy 391.034779 -283.17171) (xy 391.023002 -283.123926)
			(xy 391.019042 -283.074872) (xy 390.680194 -283.074872) (xy 390.679699 -283.099479) (xy 390.671804 -283.148056)
			(xy 390.65622 -283.194737) (xy 390.633349 -283.238314) (xy 390.603784 -283.277658) (xy 390.568291 -283.31175)
			(xy 390.527788 -283.339706) (xy 390.483326 -283.360804) (xy 390.436055 -283.374496) (xy 390.3872 -283.380428)
			(xy 390.338025 -283.378447) (xy 390.289806 -283.368603) (xy 390.24379 -283.351151) (xy 390.201169 -283.326544)
			(xy 390.163048 -283.295419) (xy 390.130413 -283.258582) (xy 390.10411 -283.216986) (xy 390.084819 -283.17171)
			(xy 390.073042 -283.123926) (xy 390.069082 -283.074872) (xy 389.730234 -283.074872) (xy 389.729739 -283.099479)
			(xy 389.721844 -283.148056) (xy 389.70626 -283.194737) (xy 389.683389 -283.238314) (xy 389.653824 -283.277658)
			(xy 389.618331 -283.31175) (xy 389.577828 -283.339706) (xy 389.533366 -283.360804) (xy 389.486095 -283.374496)
			(xy 389.43724 -283.380428) (xy 389.388065 -283.378447) (xy 389.339846 -283.368603) (xy 389.29383 -283.351151)
			(xy 389.251209 -283.326544) (xy 389.213088 -283.295419) (xy 389.180453 -283.258582) (xy 389.15415 -283.216986)
			(xy 389.134859 -283.17171) (xy 389.123082 -283.123926) (xy 389.119122 -283.074872) (xy 388.780274 -283.074872)
			(xy 388.779779 -283.099479) (xy 388.771884 -283.148056) (xy 388.7563 -283.194737) (xy 388.733429 -283.238314)
			(xy 388.703864 -283.277658) (xy 388.668371 -283.31175) (xy 388.627868 -283.339706) (xy 388.583406 -283.360804)
			(xy 388.536135 -283.374496) (xy 388.48728 -283.380428) (xy 388.438105 -283.378447) (xy 388.389886 -283.368603)
			(xy 388.34387 -283.351151) (xy 388.301249 -283.326544) (xy 388.263128 -283.295419) (xy 388.230493 -283.258582)
			(xy 388.20419 -283.216986) (xy 388.184899 -283.17171) (xy 388.173122 -283.123926) (xy 388.169162 -283.074872)
			(xy 387.830314 -283.074872) (xy 387.829819 -283.099479) (xy 387.821924 -283.148056) (xy 387.80634 -283.194737)
			(xy 387.783469 -283.238314) (xy 387.753904 -283.277658) (xy 387.718411 -283.31175) (xy 387.677908 -283.339706)
			(xy 387.633446 -283.360804) (xy 387.586175 -283.374496) (xy 387.53732 -283.380428) (xy 387.488145 -283.378447)
			(xy 387.439926 -283.368603) (xy 387.39391 -283.351151) (xy 387.351289 -283.326544) (xy 387.313168 -283.295419)
			(xy 387.280533 -283.258582) (xy 387.25423 -283.216986) (xy 387.234939 -283.17171) (xy 387.223162 -283.123926)
			(xy 387.219202 -283.074872) (xy 386.880354 -283.074872) (xy 386.879859 -283.099479) (xy 386.871964 -283.148056)
			(xy 386.85638 -283.194737) (xy 386.833509 -283.238314) (xy 386.803944 -283.277658) (xy 386.768451 -283.31175)
			(xy 386.727948 -283.339706) (xy 386.683486 -283.360804) (xy 386.636215 -283.374496) (xy 386.58736 -283.380428)
			(xy 386.538185 -283.378447) (xy 386.489966 -283.368603) (xy 386.44395 -283.351151) (xy 386.401329 -283.326544)
			(xy 386.363208 -283.295419) (xy 386.330573 -283.258582) (xy 386.30427 -283.216986) (xy 386.284979 -283.17171)
			(xy 386.273202 -283.123926) (xy 386.269242 -283.074872) (xy 385.93014 -283.074872) (xy 385.929671 -283.098866)
			(xy 385.922169 -283.146263) (xy 385.907345 -283.191902) (xy 385.885563 -283.234661) (xy 385.857361 -283.273486)
			(xy 385.823432 -283.307422) (xy 385.784612 -283.335632) (xy 385.741858 -283.357422) (xy 385.696221 -283.372255)
			(xy 385.648825 -283.379767) (xy 385.624832 -283.38018) (xy 385.600978 -283.379723) (xy 385.553848 -283.372309)
			(xy 385.508446 -283.357655) (xy 385.465874 -283.33612) (xy 385.44627 -283.322522) (xy 385.439158 -283.317442)
			(xy 385.422648 -283.312616) (xy 385.384294 -283.314648) (xy 385.374994 -283.315531) (xy 385.357931 -283.323094)
			(xy 385.35102 -283.32938) (xy 384.92938 -283.75102) (xy 384.923104 -283.757936) (xy 384.915549 -283.774998)
			(xy 384.914648 -283.784294) (xy 384.912616 -283.822648) (xy 384.917442 -283.839158) (xy 384.922522 -283.84627)
			(xy 384.936099 -283.865888) (xy 384.957639 -283.908454) (xy 384.972296 -283.953853) (xy 384.979712 -284.000979)
			(xy 384.98018 -284.024832) (xy 385.319028 -284.024832) (xy 385.322988 -283.975778) (xy 385.334765 -283.927994)
			(xy 385.354056 -283.882718) (xy 385.380359 -283.841122) (xy 385.412994 -283.804285) (xy 385.451115 -283.77316)
			(xy 385.493736 -283.748553) (xy 385.539752 -283.731101) (xy 385.587971 -283.721257) (xy 385.637146 -283.719276)
			(xy 385.686001 -283.725208) (xy 385.733272 -283.7389) (xy 385.777734 -283.759998) (xy 385.818237 -283.787954)
			(xy 385.85373 -283.822046) (xy 385.883295 -283.86139) (xy 385.906166 -283.904967) (xy 385.92175 -283.951648)
			(xy 385.929645 -284.000225) (xy 385.93014 -284.024832) (xy 386.269242 -284.024832) (xy 386.273202 -283.975778)
			(xy 386.284979 -283.927994) (xy 386.30427 -283.882718) (xy 386.330573 -283.841122) (xy 386.363208 -283.804285)
			(xy 386.401329 -283.77316) (xy 386.44395 -283.748553) (xy 386.489966 -283.731101) (xy 386.538185 -283.721257)
			(xy 386.58736 -283.719276) (xy 386.636215 -283.725208) (xy 386.683486 -283.7389) (xy 386.727948 -283.759998)
			(xy 386.768451 -283.787954) (xy 386.803944 -283.822046) (xy 386.833509 -283.86139) (xy 386.85638 -283.904967)
			(xy 386.871964 -283.951648) (xy 386.879859 -284.000225) (xy 386.880354 -284.024832) (xy 387.219202 -284.024832)
			(xy 387.223162 -283.975778) (xy 387.234939 -283.927994) (xy 387.25423 -283.882718) (xy 387.280533 -283.841122)
			(xy 387.313168 -283.804285) (xy 387.351289 -283.77316) (xy 387.39391 -283.748553) (xy 387.439926 -283.731101)
			(xy 387.488145 -283.721257) (xy 387.53732 -283.719276) (xy 387.586175 -283.725208) (xy 387.633446 -283.7389)
			(xy 387.677908 -283.759998) (xy 387.718411 -283.787954) (xy 387.753904 -283.822046) (xy 387.783469 -283.86139)
			(xy 387.80634 -283.904967) (xy 387.821924 -283.951648) (xy 387.829819 -284.000225) (xy 387.830314 -284.024832)
			(xy 388.169162 -284.024832) (xy 388.173122 -283.975778) (xy 388.184899 -283.927994) (xy 388.20419 -283.882718)
			(xy 388.230493 -283.841122) (xy 388.263128 -283.804285) (xy 388.301249 -283.77316) (xy 388.34387 -283.748553)
			(xy 388.389886 -283.731101) (xy 388.438105 -283.721257) (xy 388.48728 -283.719276) (xy 388.536135 -283.725208)
			(xy 388.583406 -283.7389) (xy 388.627868 -283.759998) (xy 388.668371 -283.787954) (xy 388.703864 -283.822046)
			(xy 388.733429 -283.86139) (xy 388.7563 -283.904967) (xy 388.771884 -283.951648) (xy 388.779779 -284.000225)
			(xy 388.780274 -284.024832) (xy 389.119122 -284.024832) (xy 389.123082 -283.975778) (xy 389.134859 -283.927994)
			(xy 389.15415 -283.882718) (xy 389.180453 -283.841122) (xy 389.213088 -283.804285) (xy 389.251209 -283.77316)
			(xy 389.29383 -283.748553) (xy 389.339846 -283.731101) (xy 389.388065 -283.721257) (xy 389.43724 -283.719276)
			(xy 389.486095 -283.725208) (xy 389.533366 -283.7389) (xy 389.577828 -283.759998) (xy 389.618331 -283.787954)
			(xy 389.653824 -283.822046) (xy 389.683389 -283.86139) (xy 389.70626 -283.904967) (xy 389.721844 -283.951648)
			(xy 389.729739 -284.000225) (xy 389.730234 -284.024832) (xy 390.069082 -284.024832) (xy 390.073042 -283.975778)
			(xy 390.084819 -283.927994) (xy 390.10411 -283.882718) (xy 390.130413 -283.841122) (xy 390.163048 -283.804285)
			(xy 390.201169 -283.77316) (xy 390.24379 -283.748553) (xy 390.289806 -283.731101) (xy 390.338025 -283.721257)
			(xy 390.3872 -283.719276) (xy 390.436055 -283.725208) (xy 390.483326 -283.7389) (xy 390.527788 -283.759998)
			(xy 390.568291 -283.787954) (xy 390.603784 -283.822046) (xy 390.633349 -283.86139) (xy 390.65622 -283.904967)
			(xy 390.671804 -283.951648) (xy 390.679699 -284.000225) (xy 390.680194 -284.024832) (xy 391.019042 -284.024832)
			(xy 391.023002 -283.975778) (xy 391.034779 -283.927994) (xy 391.05407 -283.882718) (xy 391.080373 -283.841122)
			(xy 391.113008 -283.804285) (xy 391.151129 -283.77316) (xy 391.19375 -283.748553) (xy 391.239766 -283.731101)
			(xy 391.287985 -283.721257) (xy 391.33716 -283.719276) (xy 391.386015 -283.725208) (xy 391.433286 -283.7389)
			(xy 391.477748 -283.759998) (xy 391.518251 -283.787954) (xy 391.553744 -283.822046) (xy 391.583309 -283.86139)
			(xy 391.60618 -283.904967) (xy 391.621764 -283.951648) (xy 391.629659 -284.000225) (xy 391.630154 -284.024832)
			(xy 391.969002 -284.024832) (xy 391.972962 -283.975778) (xy 391.984739 -283.927994) (xy 392.00403 -283.882718)
			(xy 392.030333 -283.841122) (xy 392.062968 -283.804285) (xy 392.101089 -283.77316) (xy 392.14371 -283.748553)
			(xy 392.189726 -283.731101) (xy 392.237945 -283.721257) (xy 392.28712 -283.719276) (xy 392.335975 -283.725208)
			(xy 392.383246 -283.7389) (xy 392.427708 -283.759998) (xy 392.468211 -283.787954) (xy 392.503704 -283.822046)
			(xy 392.533269 -283.86139) (xy 392.55614 -283.904967) (xy 392.571724 -283.951648) (xy 392.579619 -284.000225)
			(xy 392.580114 -284.024832) (xy 392.919216 -284.024832) (xy 392.923176 -283.975778) (xy 392.934953 -283.927994)
			(xy 392.954244 -283.882718) (xy 392.980547 -283.841122) (xy 393.013182 -283.804285) (xy 393.051303 -283.77316)
			(xy 393.093924 -283.748553) (xy 393.13994 -283.731101) (xy 393.188159 -283.721257) (xy 393.237334 -283.719276)
			(xy 393.286189 -283.725208) (xy 393.33346 -283.7389) (xy 393.377922 -283.759998) (xy 393.418425 -283.787954)
			(xy 393.453918 -283.822046) (xy 393.483483 -283.86139) (xy 393.506354 -283.904967) (xy 393.521938 -283.951648)
			(xy 393.529833 -284.000225) (xy 393.530328 -284.024832) (xy 393.869176 -284.024832) (xy 393.873136 -283.975778)
			(xy 393.884913 -283.927994) (xy 393.904204 -283.882718) (xy 393.930507 -283.841122) (xy 393.963142 -283.804285)
			(xy 394.001263 -283.77316) (xy 394.043884 -283.748553) (xy 394.0899 -283.731101) (xy 394.138119 -283.721257)
			(xy 394.187294 -283.719276) (xy 394.236149 -283.725208) (xy 394.28342 -283.7389) (xy 394.327882 -283.759998)
			(xy 394.368385 -283.787954) (xy 394.403878 -283.822046) (xy 394.433443 -283.86139) (xy 394.456314 -283.904967)
			(xy 394.471898 -283.951648) (xy 394.479793 -284.000225) (xy 394.480288 -284.024832) (xy 394.819136 -284.024832)
			(xy 394.823096 -283.975778) (xy 394.834873 -283.927994) (xy 394.854164 -283.882718) (xy 394.880467 -283.841122)
			(xy 394.913102 -283.804285) (xy 394.951223 -283.77316) (xy 394.993844 -283.748553) (xy 395.03986 -283.731101)
			(xy 395.088079 -283.721257) (xy 395.137254 -283.719276) (xy 395.186109 -283.725208) (xy 395.23338 -283.7389)
			(xy 395.277842 -283.759998) (xy 395.318345 -283.787954) (xy 395.353838 -283.822046) (xy 395.383403 -283.86139)
			(xy 395.406274 -283.904967) (xy 395.421858 -283.951648) (xy 395.429753 -284.000225) (xy 395.430248 -284.024832)
			(xy 395.769096 -284.024832) (xy 395.773056 -283.975778) (xy 395.784833 -283.927994) (xy 395.804124 -283.882718)
			(xy 395.830427 -283.841122) (xy 395.863062 -283.804285) (xy 395.901183 -283.77316) (xy 395.943804 -283.748553)
			(xy 395.98982 -283.731101) (xy 396.038039 -283.721257) (xy 396.087214 -283.719276) (xy 396.136069 -283.725208)
			(xy 396.18334 -283.7389) (xy 396.227802 -283.759998) (xy 396.268305 -283.787954) (xy 396.303798 -283.822046)
			(xy 396.333363 -283.86139) (xy 396.356234 -283.904967) (xy 396.371818 -283.951648) (xy 396.379713 -284.000225)
			(xy 396.380208 -284.024832) (xy 396.719056 -284.024832) (xy 396.723016 -283.975778) (xy 396.734793 -283.927994)
			(xy 396.754084 -283.882718) (xy 396.780387 -283.841122) (xy 396.813022 -283.804285) (xy 396.851143 -283.77316)
			(xy 396.893764 -283.748553) (xy 396.93978 -283.731101) (xy 396.987999 -283.721257) (xy 397.037174 -283.719276)
			(xy 397.086029 -283.725208) (xy 397.1333 -283.7389) (xy 397.177762 -283.759998) (xy 397.218265 -283.787954)
			(xy 397.253758 -283.822046) (xy 397.283323 -283.86139) (xy 397.306194 -283.904967) (xy 397.321778 -283.951648)
			(xy 397.329673 -284.000225) (xy 397.330168 -284.024832) (xy 397.669016 -284.024832) (xy 397.672976 -283.975778)
			(xy 397.684753 -283.927994) (xy 397.704044 -283.882718) (xy 397.730347 -283.841122) (xy 397.762982 -283.804285)
			(xy 397.801103 -283.77316) (xy 397.843724 -283.748553) (xy 397.88974 -283.731101) (xy 397.937959 -283.721257)
			(xy 397.987134 -283.719276) (xy 398.035989 -283.725208) (xy 398.08326 -283.7389) (xy 398.127722 -283.759998)
			(xy 398.168225 -283.787954) (xy 398.203718 -283.822046) (xy 398.233283 -283.86139) (xy 398.256154 -283.904967)
			(xy 398.271738 -283.951648) (xy 398.279633 -284.000225) (xy 398.280128 -284.024832) (xy 398.61923 -284.024832)
			(xy 398.62319 -283.975778) (xy 398.634967 -283.927994) (xy 398.654258 -283.882718) (xy 398.680561 -283.841122)
			(xy 398.713196 -283.804285) (xy 398.751317 -283.77316) (xy 398.793938 -283.748553) (xy 398.839954 -283.731101)
			(xy 398.888173 -283.721257) (xy 398.937348 -283.719276) (xy 398.986203 -283.725208) (xy 399.033474 -283.7389)
			(xy 399.077936 -283.759998) (xy 399.118439 -283.787954) (xy 399.153932 -283.822046) (xy 399.183497 -283.86139)
			(xy 399.206368 -283.904967) (xy 399.221952 -283.951648) (xy 399.229847 -284.000225) (xy 399.230342 -284.024832)
			(xy 399.56919 -284.024832) (xy 399.57315 -283.975778) (xy 399.584927 -283.927994) (xy 399.604218 -283.882718)
			(xy 399.630521 -283.841122) (xy 399.663156 -283.804285) (xy 399.701277 -283.77316) (xy 399.743898 -283.748553)
			(xy 399.789914 -283.731101) (xy 399.838133 -283.721257) (xy 399.887308 -283.719276) (xy 399.936163 -283.725208)
			(xy 399.983434 -283.7389) (xy 400.027896 -283.759998) (xy 400.068399 -283.787954) (xy 400.103892 -283.822046)
			(xy 400.133457 -283.86139) (xy 400.156328 -283.904967) (xy 400.171912 -283.951648) (xy 400.179807 -284.000225)
			(xy 400.180302 -284.024832) (xy 400.51915 -284.024832) (xy 400.52311 -283.975778) (xy 400.534887 -283.927994)
			(xy 400.554178 -283.882718) (xy 400.580481 -283.841122) (xy 400.613116 -283.804285) (xy 400.651237 -283.77316)
			(xy 400.693858 -283.748553) (xy 400.739874 -283.731101) (xy 400.788093 -283.721257) (xy 400.837268 -283.719276)
			(xy 400.886123 -283.725208) (xy 400.933394 -283.7389) (xy 400.977856 -283.759998) (xy 401.018359 -283.787954)
			(xy 401.053852 -283.822046) (xy 401.083417 -283.86139) (xy 401.106288 -283.904967) (xy 401.121872 -283.951648)
			(xy 401.129767 -284.000225) (xy 401.130262 -284.024832) (xy 401.46911 -284.024832) (xy 401.47307 -283.975778)
			(xy 401.484847 -283.927994) (xy 401.504138 -283.882718) (xy 401.530441 -283.841122) (xy 401.563076 -283.804285)
			(xy 401.601197 -283.77316) (xy 401.643818 -283.748553) (xy 401.689834 -283.731101) (xy 401.738053 -283.721257)
			(xy 401.787228 -283.719276) (xy 401.836083 -283.725208) (xy 401.883354 -283.7389) (xy 401.927816 -283.759998)
			(xy 401.968319 -283.787954) (xy 402.003812 -283.822046) (xy 402.033377 -283.86139) (xy 402.056248 -283.904967)
			(xy 402.071832 -283.951648) (xy 402.079727 -284.000225) (xy 402.080222 -284.024832) (xy 402.41907 -284.024832)
			(xy 402.42303 -283.975778) (xy 402.434807 -283.927994) (xy 402.454098 -283.882718) (xy 402.480401 -283.841122)
			(xy 402.513036 -283.804285) (xy 402.551157 -283.77316) (xy 402.593778 -283.748553) (xy 402.639794 -283.731101)
			(xy 402.688013 -283.721257) (xy 402.737188 -283.719276) (xy 402.786043 -283.725208) (xy 402.833314 -283.7389)
			(xy 402.877776 -283.759998) (xy 402.918279 -283.787954) (xy 402.953772 -283.822046) (xy 402.983337 -283.86139)
			(xy 403.006208 -283.904967) (xy 403.021792 -283.951648) (xy 403.029687 -284.000225) (xy 403.030182 -284.024832)
			(xy 403.36903 -284.024832) (xy 403.37299 -283.975778) (xy 403.384767 -283.927994) (xy 403.404058 -283.882718)
			(xy 403.430361 -283.841122) (xy 403.462996 -283.804285) (xy 403.501117 -283.77316) (xy 403.543738 -283.748553)
			(xy 403.589754 -283.731101) (xy 403.637973 -283.721257) (xy 403.687148 -283.719276) (xy 403.736003 -283.725208)
			(xy 403.783274 -283.7389) (xy 403.827736 -283.759998) (xy 403.868239 -283.787954) (xy 403.903732 -283.822046)
			(xy 403.933297 -283.86139) (xy 403.956168 -283.904967) (xy 403.971752 -283.951648) (xy 403.979647 -284.000225)
			(xy 403.980142 -284.024832) (xy 404.31899 -284.024832) (xy 404.32295 -283.975778) (xy 404.334727 -283.927994)
			(xy 404.354018 -283.882718) (xy 404.380321 -283.841122) (xy 404.412956 -283.804285) (xy 404.451077 -283.77316)
			(xy 404.493698 -283.748553) (xy 404.539714 -283.731101) (xy 404.587933 -283.721257) (xy 404.637108 -283.719276)
			(xy 404.685963 -283.725208) (xy 404.733234 -283.7389) (xy 404.777696 -283.759998) (xy 404.818199 -283.787954)
			(xy 404.853692 -283.822046) (xy 404.883257 -283.86139) (xy 404.906128 -283.904967) (xy 404.921712 -283.951648)
			(xy 404.929607 -284.000225) (xy 404.930102 -284.024832) (xy 405.269204 -284.024832) (xy 405.273164 -283.975778)
			(xy 405.284941 -283.927994) (xy 405.304232 -283.882718) (xy 405.330535 -283.841122) (xy 405.36317 -283.804285)
			(xy 405.401291 -283.77316) (xy 405.443912 -283.748553) (xy 405.489928 -283.731101) (xy 405.538147 -283.721257)
			(xy 405.587322 -283.719276) (xy 405.636177 -283.725208) (xy 405.683448 -283.7389) (xy 405.72791 -283.759998)
			(xy 405.768413 -283.787954) (xy 405.803906 -283.822046) (xy 405.833471 -283.86139) (xy 405.856342 -283.904967)
			(xy 405.871926 -283.951648) (xy 405.879821 -284.000225) (xy 405.880316 -284.024832) (xy 406.219164 -284.024832)
			(xy 406.223124 -283.975778) (xy 406.234901 -283.927994) (xy 406.254192 -283.882718) (xy 406.280495 -283.841122)
			(xy 406.31313 -283.804285) (xy 406.351251 -283.77316) (xy 406.393872 -283.748553) (xy 406.439888 -283.731101)
			(xy 406.488107 -283.721257) (xy 406.537282 -283.719276) (xy 406.586137 -283.725208) (xy 406.633408 -283.7389)
			(xy 406.67787 -283.759998) (xy 406.718373 -283.787954) (xy 406.753866 -283.822046) (xy 406.783431 -283.86139)
			(xy 406.806302 -283.904967) (xy 406.821886 -283.951648) (xy 406.829781 -284.000225) (xy 406.830276 -284.024832)
			(xy 408.119084 -284.024832) (xy 408.123044 -283.975778) (xy 408.134821 -283.927994) (xy 408.154112 -283.882718)
			(xy 408.180415 -283.841122) (xy 408.21305 -283.804285) (xy 408.251171 -283.77316) (xy 408.293792 -283.748553)
			(xy 408.339808 -283.731101) (xy 408.388027 -283.721257) (xy 408.437202 -283.719276) (xy 408.486057 -283.725208)
			(xy 408.533328 -283.7389) (xy 408.57779 -283.759998) (xy 408.618293 -283.787954) (xy 408.653786 -283.822046)
			(xy 408.683351 -283.86139) (xy 408.706222 -283.904967) (xy 408.721806 -283.951648) (xy 408.729701 -284.000225)
			(xy 408.730196 -284.024832) (xy 409.069044 -284.024832) (xy 409.073004 -283.975778) (xy 409.084781 -283.927994)
			(xy 409.104072 -283.882718) (xy 409.130375 -283.841122) (xy 409.16301 -283.804285) (xy 409.201131 -283.77316)
			(xy 409.243752 -283.748553) (xy 409.289768 -283.731101) (xy 409.337987 -283.721257) (xy 409.387162 -283.719276)
			(xy 409.436017 -283.725208) (xy 409.483288 -283.7389) (xy 409.52775 -283.759998) (xy 409.568253 -283.787954)
			(xy 409.603746 -283.822046) (xy 409.633311 -283.86139) (xy 409.656182 -283.904967) (xy 409.671766 -283.951648)
			(xy 409.679661 -284.000225) (xy 409.680156 -284.024832) (xy 410.019004 -284.024832) (xy 410.022964 -283.975778)
			(xy 410.034741 -283.927994) (xy 410.054032 -283.882718) (xy 410.080335 -283.841122) (xy 410.11297 -283.804285)
			(xy 410.151091 -283.77316) (xy 410.193712 -283.748553) (xy 410.239728 -283.731101) (xy 410.287947 -283.721257)
			(xy 410.337122 -283.719276) (xy 410.385977 -283.725208) (xy 410.433248 -283.7389) (xy 410.47771 -283.759998)
			(xy 410.518213 -283.787954) (xy 410.553706 -283.822046) (xy 410.583271 -283.86139) (xy 410.606142 -283.904967)
			(xy 410.621726 -283.951648) (xy 410.629621 -284.000225) (xy 410.630116 -284.024832) (xy 410.969218 -284.024832)
			(xy 410.973178 -283.975778) (xy 410.984955 -283.927994) (xy 411.004246 -283.882718) (xy 411.030549 -283.841122)
			(xy 411.063184 -283.804285) (xy 411.101305 -283.77316) (xy 411.143926 -283.748553) (xy 411.189942 -283.731101)
			(xy 411.238161 -283.721257) (xy 411.287336 -283.719276) (xy 411.336191 -283.725208) (xy 411.383462 -283.7389)
			(xy 411.427924 -283.759998) (xy 411.468427 -283.787954) (xy 411.50392 -283.822046) (xy 411.533485 -283.86139)
			(xy 411.556356 -283.904967) (xy 411.57194 -283.951648) (xy 411.579835 -284.000225) (xy 411.58033 -284.024832)
			(xy 411.919178 -284.024832) (xy 411.923138 -283.975778) (xy 411.934915 -283.927994) (xy 411.954206 -283.882718)
			(xy 411.980509 -283.841122) (xy 412.013144 -283.804285) (xy 412.051265 -283.77316) (xy 412.093886 -283.748553)
			(xy 412.139902 -283.731101) (xy 412.188121 -283.721257) (xy 412.237296 -283.719276) (xy 412.286151 -283.725208)
			(xy 412.333422 -283.7389) (xy 412.377884 -283.759998) (xy 412.418387 -283.787954) (xy 412.45388 -283.822046)
			(xy 412.483445 -283.86139) (xy 412.506316 -283.904967) (xy 412.5219 -283.951648) (xy 412.529795 -284.000225)
			(xy 412.53029 -284.024832) (xy 412.869138 -284.024832) (xy 412.873098 -283.975778) (xy 412.884875 -283.927994)
			(xy 412.904166 -283.882718) (xy 412.930469 -283.841122) (xy 412.963104 -283.804285) (xy 413.001225 -283.77316)
			(xy 413.043846 -283.748553) (xy 413.089862 -283.731101) (xy 413.138081 -283.721257) (xy 413.187256 -283.719276)
			(xy 413.236111 -283.725208) (xy 413.283382 -283.7389) (xy 413.327844 -283.759998) (xy 413.368347 -283.787954)
			(xy 413.40384 -283.822046) (xy 413.433405 -283.86139) (xy 413.456276 -283.904967) (xy 413.47186 -283.951648)
			(xy 413.479755 -284.000225) (xy 413.48025 -284.024832) (xy 413.819098 -284.024832) (xy 413.823058 -283.975778)
			(xy 413.834835 -283.927994) (xy 413.854126 -283.882718) (xy 413.880429 -283.841122) (xy 413.913064 -283.804285)
			(xy 413.951185 -283.77316) (xy 413.993806 -283.748553) (xy 414.039822 -283.731101) (xy 414.088041 -283.721257)
			(xy 414.137216 -283.719276) (xy 414.186071 -283.725208) (xy 414.233342 -283.7389) (xy 414.277804 -283.759998)
			(xy 414.318307 -283.787954) (xy 414.3538 -283.822046) (xy 414.383365 -283.86139) (xy 414.406236 -283.904967)
			(xy 414.42182 -283.951648) (xy 414.429715 -284.000225) (xy 414.43021 -284.024832) (xy 414.769058 -284.024832)
			(xy 414.773018 -283.975778) (xy 414.784795 -283.927994) (xy 414.804086 -283.882718) (xy 414.830389 -283.841122)
			(xy 414.863024 -283.804285) (xy 414.901145 -283.77316) (xy 414.943766 -283.748553) (xy 414.989782 -283.731101)
			(xy 415.038001 -283.721257) (xy 415.087176 -283.719276) (xy 415.136031 -283.725208) (xy 415.183302 -283.7389)
			(xy 415.227764 -283.759998) (xy 415.268267 -283.787954) (xy 415.30376 -283.822046) (xy 415.333325 -283.86139)
			(xy 415.356196 -283.904967) (xy 415.37178 -283.951648) (xy 415.379675 -284.000225) (xy 415.38017 -284.024832)
			(xy 415.719018 -284.024832) (xy 415.722978 -283.975778) (xy 415.734755 -283.927994) (xy 415.754046 -283.882718)
			(xy 415.780349 -283.841122) (xy 415.812984 -283.804285) (xy 415.851105 -283.77316) (xy 415.893726 -283.748553)
			(xy 415.939742 -283.731101) (xy 415.987961 -283.721257) (xy 416.037136 -283.719276) (xy 416.085991 -283.725208)
			(xy 416.133262 -283.7389) (xy 416.177724 -283.759998) (xy 416.218227 -283.787954) (xy 416.25372 -283.822046)
			(xy 416.283285 -283.86139) (xy 416.306156 -283.904967) (xy 416.32174 -283.951648) (xy 416.329635 -284.000225)
			(xy 416.33013 -284.024832) (xy 416.668978 -284.024832) (xy 416.672938 -283.975778) (xy 416.684715 -283.927994)
			(xy 416.704006 -283.882718) (xy 416.730309 -283.841122) (xy 416.762944 -283.804285) (xy 416.801065 -283.77316)
			(xy 416.843686 -283.748553) (xy 416.889702 -283.731101) (xy 416.937921 -283.721257) (xy 416.987096 -283.719276)
			(xy 417.035951 -283.725208) (xy 417.083222 -283.7389) (xy 417.127684 -283.759998) (xy 417.168187 -283.787954)
			(xy 417.20368 -283.822046) (xy 417.233245 -283.86139) (xy 417.256116 -283.904967) (xy 417.2717 -283.951648)
			(xy 417.279595 -284.000225) (xy 417.28009 -284.024832) (xy 417.619192 -284.024832) (xy 417.623152 -283.975778)
			(xy 417.634929 -283.927994) (xy 417.65422 -283.882718) (xy 417.680523 -283.841122) (xy 417.713158 -283.804285)
			(xy 417.751279 -283.77316) (xy 417.7939 -283.748553) (xy 417.839916 -283.731101) (xy 417.888135 -283.721257)
			(xy 417.93731 -283.719276) (xy 417.986165 -283.725208) (xy 418.033436 -283.7389) (xy 418.077898 -283.759998)
			(xy 418.118401 -283.787954) (xy 418.153894 -283.822046) (xy 418.183459 -283.86139) (xy 418.20633 -283.904967)
			(xy 418.221914 -283.951648) (xy 418.229809 -284.000225) (xy 418.230304 -284.024832) (xy 418.569152 -284.024832)
			(xy 418.573112 -283.975778) (xy 418.584889 -283.927994) (xy 418.60418 -283.882718) (xy 418.630483 -283.841122)
			(xy 418.663118 -283.804285) (xy 418.701239 -283.77316) (xy 418.74386 -283.748553) (xy 418.789876 -283.731101)
			(xy 418.838095 -283.721257) (xy 418.88727 -283.719276) (xy 418.936125 -283.725208) (xy 418.983396 -283.7389)
			(xy 419.027858 -283.759998) (xy 419.068361 -283.787954) (xy 419.103854 -283.822046) (xy 419.133419 -283.86139)
			(xy 419.15629 -283.904967) (xy 419.171874 -283.951648) (xy 419.179769 -284.000225) (xy 419.180264 -284.024832)
			(xy 419.519112 -284.024832) (xy 419.523072 -283.975778) (xy 419.534849 -283.927994) (xy 419.55414 -283.882718)
			(xy 419.580443 -283.841122) (xy 419.613078 -283.804285) (xy 419.651199 -283.77316) (xy 419.69382 -283.748553)
			(xy 419.739836 -283.731101) (xy 419.788055 -283.721257) (xy 419.83723 -283.719276) (xy 419.886085 -283.725208)
			(xy 419.933356 -283.7389) (xy 419.977818 -283.759998) (xy 420.018321 -283.787954) (xy 420.053814 -283.822046)
			(xy 420.083379 -283.86139) (xy 420.10625 -283.904967) (xy 420.121834 -283.951648) (xy 420.129729 -284.000225)
			(xy 420.130224 -284.024832) (xy 420.469072 -284.024832) (xy 420.473032 -283.975778) (xy 420.484809 -283.927994)
			(xy 420.5041 -283.882718) (xy 420.530403 -283.841122) (xy 420.563038 -283.804285) (xy 420.601159 -283.77316)
			(xy 420.64378 -283.748553) (xy 420.689796 -283.731101) (xy 420.738015 -283.721257) (xy 420.78719 -283.719276)
			(xy 420.836045 -283.725208) (xy 420.883316 -283.7389) (xy 420.927778 -283.759998) (xy 420.968281 -283.787954)
			(xy 421.003774 -283.822046) (xy 421.033339 -283.86139) (xy 421.05621 -283.904967) (xy 421.071794 -283.951648)
			(xy 421.079689 -284.000225) (xy 421.080184 -284.024832) (xy 421.079689 -284.049439) (xy 421.071794 -284.098016)
			(xy 421.05621 -284.144697) (xy 421.033339 -284.188274) (xy 421.003774 -284.227618) (xy 420.968281 -284.26171)
			(xy 420.927778 -284.289666) (xy 420.883316 -284.310764) (xy 420.836045 -284.324456) (xy 420.78719 -284.330388)
			(xy 420.738015 -284.328407) (xy 420.689796 -284.318563) (xy 420.64378 -284.301111) (xy 420.601159 -284.276504)
			(xy 420.563038 -284.245379) (xy 420.530403 -284.208542) (xy 420.5041 -284.166946) (xy 420.484809 -284.12167)
			(xy 420.473032 -284.073886) (xy 420.469072 -284.024832) (xy 420.130224 -284.024832) (xy 420.129729 -284.049439)
			(xy 420.121834 -284.098016) (xy 420.10625 -284.144697) (xy 420.083379 -284.188274) (xy 420.053814 -284.227618)
			(xy 420.018321 -284.26171) (xy 419.977818 -284.289666) (xy 419.933356 -284.310764) (xy 419.886085 -284.324456)
			(xy 419.83723 -284.330388) (xy 419.788055 -284.328407) (xy 419.739836 -284.318563) (xy 419.69382 -284.301111)
			(xy 419.651199 -284.276504) (xy 419.613078 -284.245379) (xy 419.580443 -284.208542) (xy 419.55414 -284.166946)
			(xy 419.534849 -284.12167) (xy 419.523072 -284.073886) (xy 419.519112 -284.024832) (xy 419.180264 -284.024832)
			(xy 419.179769 -284.049439) (xy 419.171874 -284.098016) (xy 419.15629 -284.144697) (xy 419.133419 -284.188274)
			(xy 419.103854 -284.227618) (xy 419.068361 -284.26171) (xy 419.027858 -284.289666) (xy 418.983396 -284.310764)
			(xy 418.936125 -284.324456) (xy 418.88727 -284.330388) (xy 418.838095 -284.328407) (xy 418.789876 -284.318563)
			(xy 418.74386 -284.301111) (xy 418.701239 -284.276504) (xy 418.663118 -284.245379) (xy 418.630483 -284.208542)
			(xy 418.60418 -284.166946) (xy 418.584889 -284.12167) (xy 418.573112 -284.073886) (xy 418.569152 -284.024832)
			(xy 418.230304 -284.024832) (xy 418.229809 -284.049439) (xy 418.221914 -284.098016) (xy 418.20633 -284.144697)
			(xy 418.183459 -284.188274) (xy 418.153894 -284.227618) (xy 418.118401 -284.26171) (xy 418.077898 -284.289666)
			(xy 418.033436 -284.310764) (xy 417.986165 -284.324456) (xy 417.93731 -284.330388) (xy 417.888135 -284.328407)
			(xy 417.839916 -284.318563) (xy 417.7939 -284.301111) (xy 417.751279 -284.276504) (xy 417.713158 -284.245379)
			(xy 417.680523 -284.208542) (xy 417.65422 -284.166946) (xy 417.634929 -284.12167) (xy 417.623152 -284.073886)
			(xy 417.619192 -284.024832) (xy 417.28009 -284.024832) (xy 417.279595 -284.049439) (xy 417.2717 -284.098016)
			(xy 417.256116 -284.144697) (xy 417.233245 -284.188274) (xy 417.20368 -284.227618) (xy 417.168187 -284.26171)
			(xy 417.127684 -284.289666) (xy 417.083222 -284.310764) (xy 417.035951 -284.324456) (xy 416.987096 -284.330388)
			(xy 416.937921 -284.328407) (xy 416.889702 -284.318563) (xy 416.843686 -284.301111) (xy 416.801065 -284.276504)
			(xy 416.762944 -284.245379) (xy 416.730309 -284.208542) (xy 416.704006 -284.166946) (xy 416.684715 -284.12167)
			(xy 416.672938 -284.073886) (xy 416.668978 -284.024832) (xy 416.33013 -284.024832) (xy 416.329635 -284.049439)
			(xy 416.32174 -284.098016) (xy 416.306156 -284.144697) (xy 416.283285 -284.188274) (xy 416.25372 -284.227618)
			(xy 416.218227 -284.26171) (xy 416.177724 -284.289666) (xy 416.133262 -284.310764) (xy 416.085991 -284.324456)
			(xy 416.037136 -284.330388) (xy 415.987961 -284.328407) (xy 415.939742 -284.318563) (xy 415.893726 -284.301111)
			(xy 415.851105 -284.276504) (xy 415.812984 -284.245379) (xy 415.780349 -284.208542) (xy 415.754046 -284.166946)
			(xy 415.734755 -284.12167) (xy 415.722978 -284.073886) (xy 415.719018 -284.024832) (xy 415.38017 -284.024832)
			(xy 415.379675 -284.049439) (xy 415.37178 -284.098016) (xy 415.356196 -284.144697) (xy 415.333325 -284.188274)
			(xy 415.30376 -284.227618) (xy 415.268267 -284.26171) (xy 415.227764 -284.289666) (xy 415.183302 -284.310764)
			(xy 415.136031 -284.324456) (xy 415.087176 -284.330388) (xy 415.038001 -284.328407) (xy 414.989782 -284.318563)
			(xy 414.943766 -284.301111) (xy 414.901145 -284.276504) (xy 414.863024 -284.245379) (xy 414.830389 -284.208542)
			(xy 414.804086 -284.166946) (xy 414.784795 -284.12167) (xy 414.773018 -284.073886) (xy 414.769058 -284.024832)
			(xy 414.43021 -284.024832) (xy 414.429715 -284.049439) (xy 414.42182 -284.098016) (xy 414.406236 -284.144697)
			(xy 414.383365 -284.188274) (xy 414.3538 -284.227618) (xy 414.318307 -284.26171) (xy 414.277804 -284.289666)
			(xy 414.233342 -284.310764) (xy 414.186071 -284.324456) (xy 414.137216 -284.330388) (xy 414.088041 -284.328407)
			(xy 414.039822 -284.318563) (xy 413.993806 -284.301111) (xy 413.951185 -284.276504) (xy 413.913064 -284.245379)
			(xy 413.880429 -284.208542) (xy 413.854126 -284.166946) (xy 413.834835 -284.12167) (xy 413.823058 -284.073886)
			(xy 413.819098 -284.024832) (xy 413.48025 -284.024832) (xy 413.479755 -284.049439) (xy 413.47186 -284.098016)
			(xy 413.456276 -284.144697) (xy 413.433405 -284.188274) (xy 413.40384 -284.227618) (xy 413.368347 -284.26171)
			(xy 413.327844 -284.289666) (xy 413.283382 -284.310764) (xy 413.236111 -284.324456) (xy 413.187256 -284.330388)
			(xy 413.138081 -284.328407) (xy 413.089862 -284.318563) (xy 413.043846 -284.301111) (xy 413.001225 -284.276504)
			(xy 412.963104 -284.245379) (xy 412.930469 -284.208542) (xy 412.904166 -284.166946) (xy 412.884875 -284.12167)
			(xy 412.873098 -284.073886) (xy 412.869138 -284.024832) (xy 412.53029 -284.024832) (xy 412.529795 -284.049439)
			(xy 412.5219 -284.098016) (xy 412.506316 -284.144697) (xy 412.483445 -284.188274) (xy 412.45388 -284.227618)
			(xy 412.418387 -284.26171) (xy 412.377884 -284.289666) (xy 412.333422 -284.310764) (xy 412.286151 -284.324456)
			(xy 412.237296 -284.330388) (xy 412.188121 -284.328407) (xy 412.139902 -284.318563) (xy 412.093886 -284.301111)
			(xy 412.051265 -284.276504) (xy 412.013144 -284.245379) (xy 411.980509 -284.208542) (xy 411.954206 -284.166946)
			(xy 411.934915 -284.12167) (xy 411.923138 -284.073886) (xy 411.919178 -284.024832) (xy 411.58033 -284.024832)
			(xy 411.579835 -284.049439) (xy 411.57194 -284.098016) (xy 411.556356 -284.144697) (xy 411.533485 -284.188274)
			(xy 411.50392 -284.227618) (xy 411.468427 -284.26171) (xy 411.427924 -284.289666) (xy 411.383462 -284.310764)
			(xy 411.336191 -284.324456) (xy 411.287336 -284.330388) (xy 411.238161 -284.328407) (xy 411.189942 -284.318563)
			(xy 411.143926 -284.301111) (xy 411.101305 -284.276504) (xy 411.063184 -284.245379) (xy 411.030549 -284.208542)
			(xy 411.004246 -284.166946) (xy 410.984955 -284.12167) (xy 410.973178 -284.073886) (xy 410.969218 -284.024832)
			(xy 410.630116 -284.024832) (xy 410.629621 -284.049439) (xy 410.621726 -284.098016) (xy 410.606142 -284.144697)
			(xy 410.583271 -284.188274) (xy 410.553706 -284.227618) (xy 410.518213 -284.26171) (xy 410.47771 -284.289666)
			(xy 410.433248 -284.310764) (xy 410.385977 -284.324456) (xy 410.337122 -284.330388) (xy 410.287947 -284.328407)
			(xy 410.239728 -284.318563) (xy 410.193712 -284.301111) (xy 410.151091 -284.276504) (xy 410.11297 -284.245379)
			(xy 410.080335 -284.208542) (xy 410.054032 -284.166946) (xy 410.034741 -284.12167) (xy 410.022964 -284.073886)
			(xy 410.019004 -284.024832) (xy 409.680156 -284.024832) (xy 409.679661 -284.049439) (xy 409.671766 -284.098016)
			(xy 409.656182 -284.144697) (xy 409.633311 -284.188274) (xy 409.603746 -284.227618) (xy 409.568253 -284.26171)
			(xy 409.52775 -284.289666) (xy 409.483288 -284.310764) (xy 409.436017 -284.324456) (xy 409.387162 -284.330388)
			(xy 409.337987 -284.328407) (xy 409.289768 -284.318563) (xy 409.243752 -284.301111) (xy 409.201131 -284.276504)
			(xy 409.16301 -284.245379) (xy 409.130375 -284.208542) (xy 409.104072 -284.166946) (xy 409.084781 -284.12167)
			(xy 409.073004 -284.073886) (xy 409.069044 -284.024832) (xy 408.730196 -284.024832) (xy 408.729701 -284.049439)
			(xy 408.721806 -284.098016) (xy 408.706222 -284.144697) (xy 408.683351 -284.188274) (xy 408.653786 -284.227618)
			(xy 408.618293 -284.26171) (xy 408.57779 -284.289666) (xy 408.533328 -284.310764) (xy 408.486057 -284.324456)
			(xy 408.437202 -284.330388) (xy 408.388027 -284.328407) (xy 408.339808 -284.318563) (xy 408.293792 -284.301111)
			(xy 408.251171 -284.276504) (xy 408.21305 -284.245379) (xy 408.180415 -284.208542) (xy 408.154112 -284.166946)
			(xy 408.134821 -284.12167) (xy 408.123044 -284.073886) (xy 408.119084 -284.024832) (xy 406.830276 -284.024832)
			(xy 406.829781 -284.049439) (xy 406.821886 -284.098016) (xy 406.806302 -284.144697) (xy 406.783431 -284.188274)
			(xy 406.753866 -284.227618) (xy 406.718373 -284.26171) (xy 406.67787 -284.289666) (xy 406.633408 -284.310764)
			(xy 406.586137 -284.324456) (xy 406.537282 -284.330388) (xy 406.488107 -284.328407) (xy 406.439888 -284.318563)
			(xy 406.393872 -284.301111) (xy 406.351251 -284.276504) (xy 406.31313 -284.245379) (xy 406.280495 -284.208542)
			(xy 406.254192 -284.166946) (xy 406.234901 -284.12167) (xy 406.223124 -284.073886) (xy 406.219164 -284.024832)
			(xy 405.880316 -284.024832) (xy 405.879821 -284.049439) (xy 405.871926 -284.098016) (xy 405.856342 -284.144697)
			(xy 405.833471 -284.188274) (xy 405.803906 -284.227618) (xy 405.768413 -284.26171) (xy 405.72791 -284.289666)
			(xy 405.683448 -284.310764) (xy 405.636177 -284.324456) (xy 405.587322 -284.330388) (xy 405.538147 -284.328407)
			(xy 405.489928 -284.318563) (xy 405.443912 -284.301111) (xy 405.401291 -284.276504) (xy 405.36317 -284.245379)
			(xy 405.330535 -284.208542) (xy 405.304232 -284.166946) (xy 405.284941 -284.12167) (xy 405.273164 -284.073886)
			(xy 405.269204 -284.024832) (xy 404.930102 -284.024832) (xy 404.929607 -284.049439) (xy 404.921712 -284.098016)
			(xy 404.906128 -284.144697) (xy 404.883257 -284.188274) (xy 404.853692 -284.227618) (xy 404.818199 -284.26171)
			(xy 404.777696 -284.289666) (xy 404.733234 -284.310764) (xy 404.685963 -284.324456) (xy 404.637108 -284.330388)
			(xy 404.587933 -284.328407) (xy 404.539714 -284.318563) (xy 404.493698 -284.301111) (xy 404.451077 -284.276504)
			(xy 404.412956 -284.245379) (xy 404.380321 -284.208542) (xy 404.354018 -284.166946) (xy 404.334727 -284.12167)
			(xy 404.32295 -284.073886) (xy 404.31899 -284.024832) (xy 403.980142 -284.024832) (xy 403.979647 -284.049439)
			(xy 403.971752 -284.098016) (xy 403.956168 -284.144697) (xy 403.933297 -284.188274) (xy 403.903732 -284.227618)
			(xy 403.868239 -284.26171) (xy 403.827736 -284.289666) (xy 403.783274 -284.310764) (xy 403.736003 -284.324456)
			(xy 403.687148 -284.330388) (xy 403.637973 -284.328407) (xy 403.589754 -284.318563) (xy 403.543738 -284.301111)
			(xy 403.501117 -284.276504) (xy 403.462996 -284.245379) (xy 403.430361 -284.208542) (xy 403.404058 -284.166946)
			(xy 403.384767 -284.12167) (xy 403.37299 -284.073886) (xy 403.36903 -284.024832) (xy 403.030182 -284.024832)
			(xy 403.029687 -284.049439) (xy 403.021792 -284.098016) (xy 403.006208 -284.144697) (xy 402.983337 -284.188274)
			(xy 402.953772 -284.227618) (xy 402.918279 -284.26171) (xy 402.877776 -284.289666) (xy 402.833314 -284.310764)
			(xy 402.786043 -284.324456) (xy 402.737188 -284.330388) (xy 402.688013 -284.328407) (xy 402.639794 -284.318563)
			(xy 402.593778 -284.301111) (xy 402.551157 -284.276504) (xy 402.513036 -284.245379) (xy 402.480401 -284.208542)
			(xy 402.454098 -284.166946) (xy 402.434807 -284.12167) (xy 402.42303 -284.073886) (xy 402.41907 -284.024832)
			(xy 402.080222 -284.024832) (xy 402.079727 -284.049439) (xy 402.071832 -284.098016) (xy 402.056248 -284.144697)
			(xy 402.033377 -284.188274) (xy 402.003812 -284.227618) (xy 401.968319 -284.26171) (xy 401.927816 -284.289666)
			(xy 401.883354 -284.310764) (xy 401.836083 -284.324456) (xy 401.787228 -284.330388) (xy 401.738053 -284.328407)
			(xy 401.689834 -284.318563) (xy 401.643818 -284.301111) (xy 401.601197 -284.276504) (xy 401.563076 -284.245379)
			(xy 401.530441 -284.208542) (xy 401.504138 -284.166946) (xy 401.484847 -284.12167) (xy 401.47307 -284.073886)
			(xy 401.46911 -284.024832) (xy 401.130262 -284.024832) (xy 401.129767 -284.049439) (xy 401.121872 -284.098016)
			(xy 401.106288 -284.144697) (xy 401.083417 -284.188274) (xy 401.053852 -284.227618) (xy 401.018359 -284.26171)
			(xy 400.977856 -284.289666) (xy 400.933394 -284.310764) (xy 400.886123 -284.324456) (xy 400.837268 -284.330388)
			(xy 400.788093 -284.328407) (xy 400.739874 -284.318563) (xy 400.693858 -284.301111) (xy 400.651237 -284.276504)
			(xy 400.613116 -284.245379) (xy 400.580481 -284.208542) (xy 400.554178 -284.166946) (xy 400.534887 -284.12167)
			(xy 400.52311 -284.073886) (xy 400.51915 -284.024832) (xy 400.180302 -284.024832) (xy 400.179807 -284.049439)
			(xy 400.171912 -284.098016) (xy 400.156328 -284.144697) (xy 400.133457 -284.188274) (xy 400.103892 -284.227618)
			(xy 400.068399 -284.26171) (xy 400.027896 -284.289666) (xy 399.983434 -284.310764) (xy 399.936163 -284.324456)
			(xy 399.887308 -284.330388) (xy 399.838133 -284.328407) (xy 399.789914 -284.318563) (xy 399.743898 -284.301111)
			(xy 399.701277 -284.276504) (xy 399.663156 -284.245379) (xy 399.630521 -284.208542) (xy 399.604218 -284.166946)
			(xy 399.584927 -284.12167) (xy 399.57315 -284.073886) (xy 399.56919 -284.024832) (xy 399.230342 -284.024832)
			(xy 399.229847 -284.049439) (xy 399.221952 -284.098016) (xy 399.206368 -284.144697) (xy 399.183497 -284.188274)
			(xy 399.153932 -284.227618) (xy 399.118439 -284.26171) (xy 399.077936 -284.289666) (xy 399.033474 -284.310764)
			(xy 398.986203 -284.324456) (xy 398.937348 -284.330388) (xy 398.888173 -284.328407) (xy 398.839954 -284.318563)
			(xy 398.793938 -284.301111) (xy 398.751317 -284.276504) (xy 398.713196 -284.245379) (xy 398.680561 -284.208542)
			(xy 398.654258 -284.166946) (xy 398.634967 -284.12167) (xy 398.62319 -284.073886) (xy 398.61923 -284.024832)
			(xy 398.280128 -284.024832) (xy 398.279633 -284.049439) (xy 398.271738 -284.098016) (xy 398.256154 -284.144697)
			(xy 398.233283 -284.188274) (xy 398.203718 -284.227618) (xy 398.168225 -284.26171) (xy 398.127722 -284.289666)
			(xy 398.08326 -284.310764) (xy 398.035989 -284.324456) (xy 397.987134 -284.330388) (xy 397.937959 -284.328407)
			(xy 397.88974 -284.318563) (xy 397.843724 -284.301111) (xy 397.801103 -284.276504) (xy 397.762982 -284.245379)
			(xy 397.730347 -284.208542) (xy 397.704044 -284.166946) (xy 397.684753 -284.12167) (xy 397.672976 -284.073886)
			(xy 397.669016 -284.024832) (xy 397.330168 -284.024832) (xy 397.329673 -284.049439) (xy 397.321778 -284.098016)
			(xy 397.306194 -284.144697) (xy 397.283323 -284.188274) (xy 397.253758 -284.227618) (xy 397.218265 -284.26171)
			(xy 397.177762 -284.289666) (xy 397.1333 -284.310764) (xy 397.086029 -284.324456) (xy 397.037174 -284.330388)
			(xy 396.987999 -284.328407) (xy 396.93978 -284.318563) (xy 396.893764 -284.301111) (xy 396.851143 -284.276504)
			(xy 396.813022 -284.245379) (xy 396.780387 -284.208542) (xy 396.754084 -284.166946) (xy 396.734793 -284.12167)
			(xy 396.723016 -284.073886) (xy 396.719056 -284.024832) (xy 396.380208 -284.024832) (xy 396.379713 -284.049439)
			(xy 396.371818 -284.098016) (xy 396.356234 -284.144697) (xy 396.333363 -284.188274) (xy 396.303798 -284.227618)
			(xy 396.268305 -284.26171) (xy 396.227802 -284.289666) (xy 396.18334 -284.310764) (xy 396.136069 -284.324456)
			(xy 396.087214 -284.330388) (xy 396.038039 -284.328407) (xy 395.98982 -284.318563) (xy 395.943804 -284.301111)
			(xy 395.901183 -284.276504) (xy 395.863062 -284.245379) (xy 395.830427 -284.208542) (xy 395.804124 -284.166946)
			(xy 395.784833 -284.12167) (xy 395.773056 -284.073886) (xy 395.769096 -284.024832) (xy 395.430248 -284.024832)
			(xy 395.429753 -284.049439) (xy 395.421858 -284.098016) (xy 395.406274 -284.144697) (xy 395.383403 -284.188274)
			(xy 395.353838 -284.227618) (xy 395.318345 -284.26171) (xy 395.277842 -284.289666) (xy 395.23338 -284.310764)
			(xy 395.186109 -284.324456) (xy 395.137254 -284.330388) (xy 395.088079 -284.328407) (xy 395.03986 -284.318563)
			(xy 394.993844 -284.301111) (xy 394.951223 -284.276504) (xy 394.913102 -284.245379) (xy 394.880467 -284.208542)
			(xy 394.854164 -284.166946) (xy 394.834873 -284.12167) (xy 394.823096 -284.073886) (xy 394.819136 -284.024832)
			(xy 394.480288 -284.024832) (xy 394.479793 -284.049439) (xy 394.471898 -284.098016) (xy 394.456314 -284.144697)
			(xy 394.433443 -284.188274) (xy 394.403878 -284.227618) (xy 394.368385 -284.26171) (xy 394.327882 -284.289666)
			(xy 394.28342 -284.310764) (xy 394.236149 -284.324456) (xy 394.187294 -284.330388) (xy 394.138119 -284.328407)
			(xy 394.0899 -284.318563) (xy 394.043884 -284.301111) (xy 394.001263 -284.276504) (xy 393.963142 -284.245379)
			(xy 393.930507 -284.208542) (xy 393.904204 -284.166946) (xy 393.884913 -284.12167) (xy 393.873136 -284.073886)
			(xy 393.869176 -284.024832) (xy 393.530328 -284.024832) (xy 393.529833 -284.049439) (xy 393.521938 -284.098016)
			(xy 393.506354 -284.144697) (xy 393.483483 -284.188274) (xy 393.453918 -284.227618) (xy 393.418425 -284.26171)
			(xy 393.377922 -284.289666) (xy 393.33346 -284.310764) (xy 393.286189 -284.324456) (xy 393.237334 -284.330388)
			(xy 393.188159 -284.328407) (xy 393.13994 -284.318563) (xy 393.093924 -284.301111) (xy 393.051303 -284.276504)
			(xy 393.013182 -284.245379) (xy 392.980547 -284.208542) (xy 392.954244 -284.166946) (xy 392.934953 -284.12167)
			(xy 392.923176 -284.073886) (xy 392.919216 -284.024832) (xy 392.580114 -284.024832) (xy 392.579619 -284.049439)
			(xy 392.571724 -284.098016) (xy 392.55614 -284.144697) (xy 392.533269 -284.188274) (xy 392.503704 -284.227618)
			(xy 392.468211 -284.26171) (xy 392.427708 -284.289666) (xy 392.383246 -284.310764) (xy 392.335975 -284.324456)
			(xy 392.28712 -284.330388) (xy 392.237945 -284.328407) (xy 392.189726 -284.318563) (xy 392.14371 -284.301111)
			(xy 392.101089 -284.276504) (xy 392.062968 -284.245379) (xy 392.030333 -284.208542) (xy 392.00403 -284.166946)
			(xy 391.984739 -284.12167) (xy 391.972962 -284.073886) (xy 391.969002 -284.024832) (xy 391.630154 -284.024832)
			(xy 391.629659 -284.049439) (xy 391.621764 -284.098016) (xy 391.60618 -284.144697) (xy 391.583309 -284.188274)
			(xy 391.553744 -284.227618) (xy 391.518251 -284.26171) (xy 391.477748 -284.289666) (xy 391.433286 -284.310764)
			(xy 391.386015 -284.324456) (xy 391.33716 -284.330388) (xy 391.287985 -284.328407) (xy 391.239766 -284.318563)
			(xy 391.19375 -284.301111) (xy 391.151129 -284.276504) (xy 391.113008 -284.245379) (xy 391.080373 -284.208542)
			(xy 391.05407 -284.166946) (xy 391.034779 -284.12167) (xy 391.023002 -284.073886) (xy 391.019042 -284.024832)
			(xy 390.680194 -284.024832) (xy 390.679699 -284.049439) (xy 390.671804 -284.098016) (xy 390.65622 -284.144697)
			(xy 390.633349 -284.188274) (xy 390.603784 -284.227618) (xy 390.568291 -284.26171) (xy 390.527788 -284.289666)
			(xy 390.483326 -284.310764) (xy 390.436055 -284.324456) (xy 390.3872 -284.330388) (xy 390.338025 -284.328407)
			(xy 390.289806 -284.318563) (xy 390.24379 -284.301111) (xy 390.201169 -284.276504) (xy 390.163048 -284.245379)
			(xy 390.130413 -284.208542) (xy 390.10411 -284.166946) (xy 390.084819 -284.12167) (xy 390.073042 -284.073886)
			(xy 390.069082 -284.024832) (xy 389.730234 -284.024832) (xy 389.729739 -284.049439) (xy 389.721844 -284.098016)
			(xy 389.70626 -284.144697) (xy 389.683389 -284.188274) (xy 389.653824 -284.227618) (xy 389.618331 -284.26171)
			(xy 389.577828 -284.289666) (xy 389.533366 -284.310764) (xy 389.486095 -284.324456) (xy 389.43724 -284.330388)
			(xy 389.388065 -284.328407) (xy 389.339846 -284.318563) (xy 389.29383 -284.301111) (xy 389.251209 -284.276504)
			(xy 389.213088 -284.245379) (xy 389.180453 -284.208542) (xy 389.15415 -284.166946) (xy 389.134859 -284.12167)
			(xy 389.123082 -284.073886) (xy 389.119122 -284.024832) (xy 388.780274 -284.024832) (xy 388.779779 -284.049439)
			(xy 388.771884 -284.098016) (xy 388.7563 -284.144697) (xy 388.733429 -284.188274) (xy 388.703864 -284.227618)
			(xy 388.668371 -284.26171) (xy 388.627868 -284.289666) (xy 388.583406 -284.310764) (xy 388.536135 -284.324456)
			(xy 388.48728 -284.330388) (xy 388.438105 -284.328407) (xy 388.389886 -284.318563) (xy 388.34387 -284.301111)
			(xy 388.301249 -284.276504) (xy 388.263128 -284.245379) (xy 388.230493 -284.208542) (xy 388.20419 -284.166946)
			(xy 388.184899 -284.12167) (xy 388.173122 -284.073886) (xy 388.169162 -284.024832) (xy 387.830314 -284.024832)
			(xy 387.829819 -284.049439) (xy 387.821924 -284.098016) (xy 387.80634 -284.144697) (xy 387.783469 -284.188274)
			(xy 387.753904 -284.227618) (xy 387.718411 -284.26171) (xy 387.677908 -284.289666) (xy 387.633446 -284.310764)
			(xy 387.586175 -284.324456) (xy 387.53732 -284.330388) (xy 387.488145 -284.328407) (xy 387.439926 -284.318563)
			(xy 387.39391 -284.301111) (xy 387.351289 -284.276504) (xy 387.313168 -284.245379) (xy 387.280533 -284.208542)
			(xy 387.25423 -284.166946) (xy 387.234939 -284.12167) (xy 387.223162 -284.073886) (xy 387.219202 -284.024832)
			(xy 386.880354 -284.024832) (xy 386.879859 -284.049439) (xy 386.871964 -284.098016) (xy 386.85638 -284.144697)
			(xy 386.833509 -284.188274) (xy 386.803944 -284.227618) (xy 386.768451 -284.26171) (xy 386.727948 -284.289666)
			(xy 386.683486 -284.310764) (xy 386.636215 -284.324456) (xy 386.58736 -284.330388) (xy 386.538185 -284.328407)
			(xy 386.489966 -284.318563) (xy 386.44395 -284.301111) (xy 386.401329 -284.276504) (xy 386.363208 -284.245379)
			(xy 386.330573 -284.208542) (xy 386.30427 -284.166946) (xy 386.284979 -284.12167) (xy 386.273202 -284.073886)
			(xy 386.269242 -284.024832) (xy 385.93014 -284.024832) (xy 385.929645 -284.049439) (xy 385.92175 -284.098016)
			(xy 385.906166 -284.144697) (xy 385.883295 -284.188274) (xy 385.85373 -284.227618) (xy 385.818237 -284.26171)
			(xy 385.777734 -284.289666) (xy 385.733272 -284.310764) (xy 385.686001 -284.324456) (xy 385.637146 -284.330388)
			(xy 385.587971 -284.328407) (xy 385.539752 -284.318563) (xy 385.493736 -284.301111) (xy 385.451115 -284.276504)
			(xy 385.412994 -284.245379) (xy 385.380359 -284.208542) (xy 385.354056 -284.166946) (xy 385.334765 -284.12167)
			(xy 385.322988 -284.073886) (xy 385.319028 -284.024832) (xy 384.98018 -284.024832) (xy 384.979707 -284.048821)
			(xy 384.972197 -284.096207) (xy 384.957366 -284.141835) (xy 384.93558 -284.184581) (xy 384.907376 -284.223393)
			(xy 384.873447 -284.257315) (xy 384.83463 -284.285512) (xy 384.791879 -284.307289) (xy 384.746249 -284.322111)
			(xy 384.698861 -284.329612) (xy 384.674872 -284.33014) (xy 384.651019 -284.329678) (xy 384.603895 -284.322255)
			(xy 384.558498 -284.307593) (xy 384.515934 -284.286049) (xy 384.49631 -284.272482) (xy 384.489198 -284.267402)
			(xy 384.472688 -284.262576) (xy 384.434334 -284.264608) (xy 384.42503 -284.265484) (xy 384.407953 -284.273032)
			(xy 384.40106 -284.27934) (xy 384.266186 -284.414214) (xy 384.259332 -284.421609) (xy 384.25159 -284.440208)
			(xy 384.2512 -284.450282) (xy 384.2512 -284.974792) (xy 384.369068 -284.974792) (xy 384.373028 -284.925738)
			(xy 384.384805 -284.877954) (xy 384.404096 -284.832678) (xy 384.430399 -284.791082) (xy 384.463034 -284.754245)
			(xy 384.501155 -284.72312) (xy 384.543776 -284.698513) (xy 384.589792 -284.681061) (xy 384.638011 -284.671217)
			(xy 384.687186 -284.669236) (xy 384.736041 -284.675168) (xy 384.783312 -284.68886) (xy 384.827774 -284.709958)
			(xy 384.868277 -284.737914) (xy 384.90377 -284.772006) (xy 384.933335 -284.81135) (xy 384.956206 -284.854927)
			(xy 384.97179 -284.901608) (xy 384.979685 -284.950185) (xy 384.98018 -284.974792) (xy 385.319028 -284.974792)
			(xy 385.322988 -284.925738) (xy 385.334765 -284.877954) (xy 385.354056 -284.832678) (xy 385.380359 -284.791082)
			(xy 385.412994 -284.754245) (xy 385.451115 -284.72312) (xy 385.493736 -284.698513) (xy 385.539752 -284.681061)
			(xy 385.587971 -284.671217) (xy 385.637146 -284.669236) (xy 385.686001 -284.675168) (xy 385.733272 -284.68886)
			(xy 385.777734 -284.709958) (xy 385.818237 -284.737914) (xy 385.85373 -284.772006) (xy 385.883295 -284.81135)
			(xy 385.906166 -284.854927) (xy 385.92175 -284.901608) (xy 385.929645 -284.950185) (xy 385.93014 -284.974792)
			(xy 386.269242 -284.974792) (xy 386.273202 -284.925738) (xy 386.284979 -284.877954) (xy 386.30427 -284.832678)
			(xy 386.330573 -284.791082) (xy 386.363208 -284.754245) (xy 386.401329 -284.72312) (xy 386.44395 -284.698513)
			(xy 386.489966 -284.681061) (xy 386.538185 -284.671217) (xy 386.58736 -284.669236) (xy 386.636215 -284.675168)
			(xy 386.683486 -284.68886) (xy 386.727948 -284.709958) (xy 386.768451 -284.737914) (xy 386.803944 -284.772006)
			(xy 386.833509 -284.81135) (xy 386.85638 -284.854927) (xy 386.871964 -284.901608) (xy 386.879859 -284.950185)
			(xy 386.880354 -284.974792) (xy 387.219202 -284.974792) (xy 387.223162 -284.925738) (xy 387.234939 -284.877954)
			(xy 387.25423 -284.832678) (xy 387.280533 -284.791082) (xy 387.313168 -284.754245) (xy 387.351289 -284.72312)
			(xy 387.39391 -284.698513) (xy 387.439926 -284.681061) (xy 387.488145 -284.671217) (xy 387.53732 -284.669236)
			(xy 387.586175 -284.675168) (xy 387.633446 -284.68886) (xy 387.677908 -284.709958) (xy 387.718411 -284.737914)
			(xy 387.753904 -284.772006) (xy 387.783469 -284.81135) (xy 387.80634 -284.854927) (xy 387.821924 -284.901608)
			(xy 387.829819 -284.950185) (xy 387.830314 -284.974792) (xy 388.169162 -284.974792) (xy 388.173122 -284.925738)
			(xy 388.184899 -284.877954) (xy 388.20419 -284.832678) (xy 388.230493 -284.791082) (xy 388.263128 -284.754245)
			(xy 388.301249 -284.72312) (xy 388.34387 -284.698513) (xy 388.389886 -284.681061) (xy 388.438105 -284.671217)
			(xy 388.48728 -284.669236) (xy 388.536135 -284.675168) (xy 388.583406 -284.68886) (xy 388.627868 -284.709958)
			(xy 388.668371 -284.737914) (xy 388.703864 -284.772006) (xy 388.733429 -284.81135) (xy 388.7563 -284.854927)
			(xy 388.771884 -284.901608) (xy 388.779779 -284.950185) (xy 388.780274 -284.974792) (xy 389.119122 -284.974792)
			(xy 389.123082 -284.925738) (xy 389.134859 -284.877954) (xy 389.15415 -284.832678) (xy 389.180453 -284.791082)
			(xy 389.213088 -284.754245) (xy 389.251209 -284.72312) (xy 389.29383 -284.698513) (xy 389.339846 -284.681061)
			(xy 389.388065 -284.671217) (xy 389.43724 -284.669236) (xy 389.486095 -284.675168) (xy 389.533366 -284.68886)
			(xy 389.577828 -284.709958) (xy 389.618331 -284.737914) (xy 389.653824 -284.772006) (xy 389.683389 -284.81135)
			(xy 389.70626 -284.854927) (xy 389.721844 -284.901608) (xy 389.729739 -284.950185) (xy 389.730234 -284.974792)
			(xy 391.019042 -284.974792) (xy 391.023002 -284.925738) (xy 391.034779 -284.877954) (xy 391.05407 -284.832678)
			(xy 391.080373 -284.791082) (xy 391.113008 -284.754245) (xy 391.151129 -284.72312) (xy 391.19375 -284.698513)
			(xy 391.239766 -284.681061) (xy 391.287985 -284.671217) (xy 391.33716 -284.669236) (xy 391.386015 -284.675168)
			(xy 391.433286 -284.68886) (xy 391.477748 -284.709958) (xy 391.518251 -284.737914) (xy 391.553744 -284.772006)
			(xy 391.583309 -284.81135) (xy 391.60618 -284.854927) (xy 391.621764 -284.901608) (xy 391.629659 -284.950185)
			(xy 391.630154 -284.974792) (xy 392.919216 -284.974792) (xy 392.923176 -284.925738) (xy 392.934953 -284.877954)
			(xy 392.954244 -284.832678) (xy 392.980547 -284.791082) (xy 393.013182 -284.754245) (xy 393.051303 -284.72312)
			(xy 393.093924 -284.698513) (xy 393.13994 -284.681061) (xy 393.188159 -284.671217) (xy 393.237334 -284.669236)
			(xy 393.286189 -284.675168) (xy 393.33346 -284.68886) (xy 393.377922 -284.709958) (xy 393.418425 -284.737914)
			(xy 393.453918 -284.772006) (xy 393.483483 -284.81135) (xy 393.506354 -284.854927) (xy 393.521938 -284.901608)
			(xy 393.529833 -284.950185) (xy 393.530328 -284.974792) (xy 393.869176 -284.974792) (xy 393.873136 -284.925738)
			(xy 393.884913 -284.877954) (xy 393.904204 -284.832678) (xy 393.930507 -284.791082) (xy 393.963142 -284.754245)
			(xy 394.001263 -284.72312) (xy 394.043884 -284.698513) (xy 394.0899 -284.681061) (xy 394.138119 -284.671217)
			(xy 394.187294 -284.669236) (xy 394.236149 -284.675168) (xy 394.28342 -284.68886) (xy 394.327882 -284.709958)
			(xy 394.368385 -284.737914) (xy 394.403878 -284.772006) (xy 394.433443 -284.81135) (xy 394.456314 -284.854927)
			(xy 394.471898 -284.901608) (xy 394.479793 -284.950185) (xy 394.480288 -284.974792) (xy 394.819136 -284.974792)
			(xy 394.823096 -284.925738) (xy 394.834873 -284.877954) (xy 394.854164 -284.832678) (xy 394.880467 -284.791082)
			(xy 394.913102 -284.754245) (xy 394.951223 -284.72312) (xy 394.993844 -284.698513) (xy 395.03986 -284.681061)
			(xy 395.088079 -284.671217) (xy 395.137254 -284.669236) (xy 395.186109 -284.675168) (xy 395.23338 -284.68886)
			(xy 395.277842 -284.709958) (xy 395.318345 -284.737914) (xy 395.353838 -284.772006) (xy 395.383403 -284.81135)
			(xy 395.406274 -284.854927) (xy 395.421858 -284.901608) (xy 395.429753 -284.950185) (xy 395.430248 -284.974792)
			(xy 395.769096 -284.974792) (xy 395.773056 -284.925738) (xy 395.784833 -284.877954) (xy 395.804124 -284.832678)
			(xy 395.830427 -284.791082) (xy 395.863062 -284.754245) (xy 395.901183 -284.72312) (xy 395.943804 -284.698513)
			(xy 395.98982 -284.681061) (xy 396.038039 -284.671217) (xy 396.087214 -284.669236) (xy 396.136069 -284.675168)
			(xy 396.18334 -284.68886) (xy 396.227802 -284.709958) (xy 396.268305 -284.737914) (xy 396.303798 -284.772006)
			(xy 396.333363 -284.81135) (xy 396.356234 -284.854927) (xy 396.371818 -284.901608) (xy 396.379713 -284.950185)
			(xy 396.380208 -284.974792) (xy 396.719056 -284.974792) (xy 396.723016 -284.925738) (xy 396.734793 -284.877954)
			(xy 396.754084 -284.832678) (xy 396.780387 -284.791082) (xy 396.813022 -284.754245) (xy 396.851143 -284.72312)
			(xy 396.893764 -284.698513) (xy 396.93978 -284.681061) (xy 396.987999 -284.671217) (xy 397.037174 -284.669236)
			(xy 397.086029 -284.675168) (xy 397.1333 -284.68886) (xy 397.177762 -284.709958) (xy 397.218265 -284.737914)
			(xy 397.253758 -284.772006) (xy 397.283323 -284.81135) (xy 397.306194 -284.854927) (xy 397.321778 -284.901608)
			(xy 397.329673 -284.950185) (xy 397.330168 -284.974792) (xy 397.669016 -284.974792) (xy 397.672976 -284.925738)
			(xy 397.684753 -284.877954) (xy 397.704044 -284.832678) (xy 397.730347 -284.791082) (xy 397.762982 -284.754245)
			(xy 397.801103 -284.72312) (xy 397.843724 -284.698513) (xy 397.88974 -284.681061) (xy 397.937959 -284.671217)
			(xy 397.987134 -284.669236) (xy 398.035989 -284.675168) (xy 398.08326 -284.68886) (xy 398.127722 -284.709958)
			(xy 398.168225 -284.737914) (xy 398.203718 -284.772006) (xy 398.233283 -284.81135) (xy 398.256154 -284.854927)
			(xy 398.271738 -284.901608) (xy 398.279633 -284.950185) (xy 398.280128 -284.974792) (xy 398.61923 -284.974792)
			(xy 398.62319 -284.925738) (xy 398.634967 -284.877954) (xy 398.654258 -284.832678) (xy 398.680561 -284.791082)
			(xy 398.713196 -284.754245) (xy 398.751317 -284.72312) (xy 398.793938 -284.698513) (xy 398.839954 -284.681061)
			(xy 398.888173 -284.671217) (xy 398.937348 -284.669236) (xy 398.986203 -284.675168) (xy 399.033474 -284.68886)
			(xy 399.077936 -284.709958) (xy 399.118439 -284.737914) (xy 399.153932 -284.772006) (xy 399.183497 -284.81135)
			(xy 399.206368 -284.854927) (xy 399.221952 -284.901608) (xy 399.229847 -284.950185) (xy 399.230342 -284.974792)
			(xy 399.56919 -284.974792) (xy 399.57315 -284.925738) (xy 399.584927 -284.877954) (xy 399.604218 -284.832678)
			(xy 399.630521 -284.791082) (xy 399.663156 -284.754245) (xy 399.701277 -284.72312) (xy 399.743898 -284.698513)
			(xy 399.789914 -284.681061) (xy 399.838133 -284.671217) (xy 399.887308 -284.669236) (xy 399.936163 -284.675168)
			(xy 399.983434 -284.68886) (xy 400.027896 -284.709958) (xy 400.068399 -284.737914) (xy 400.103892 -284.772006)
			(xy 400.133457 -284.81135) (xy 400.156328 -284.854927) (xy 400.171912 -284.901608) (xy 400.179807 -284.950185)
			(xy 400.180302 -284.974792) (xy 400.51915 -284.974792) (xy 400.52311 -284.925738) (xy 400.534887 -284.877954)
			(xy 400.554178 -284.832678) (xy 400.580481 -284.791082) (xy 400.613116 -284.754245) (xy 400.651237 -284.72312)
			(xy 400.693858 -284.698513) (xy 400.739874 -284.681061) (xy 400.788093 -284.671217) (xy 400.837268 -284.669236)
			(xy 400.886123 -284.675168) (xy 400.933394 -284.68886) (xy 400.977856 -284.709958) (xy 401.018359 -284.737914)
			(xy 401.053852 -284.772006) (xy 401.083417 -284.81135) (xy 401.106288 -284.854927) (xy 401.121872 -284.901608)
			(xy 401.129767 -284.950185) (xy 401.130262 -284.974792) (xy 401.46911 -284.974792) (xy 401.47307 -284.925738)
			(xy 401.484847 -284.877954) (xy 401.504138 -284.832678) (xy 401.530441 -284.791082) (xy 401.563076 -284.754245)
			(xy 401.601197 -284.72312) (xy 401.643818 -284.698513) (xy 401.689834 -284.681061) (xy 401.738053 -284.671217)
			(xy 401.787228 -284.669236) (xy 401.836083 -284.675168) (xy 401.883354 -284.68886) (xy 401.927816 -284.709958)
			(xy 401.968319 -284.737914) (xy 402.003812 -284.772006) (xy 402.033377 -284.81135) (xy 402.056248 -284.854927)
			(xy 402.071832 -284.901608) (xy 402.079727 -284.950185) (xy 402.080222 -284.974792) (xy 402.41907 -284.974792)
			(xy 402.42303 -284.925738) (xy 402.434807 -284.877954) (xy 402.454098 -284.832678) (xy 402.480401 -284.791082)
			(xy 402.513036 -284.754245) (xy 402.551157 -284.72312) (xy 402.593778 -284.698513) (xy 402.639794 -284.681061)
			(xy 402.688013 -284.671217) (xy 402.737188 -284.669236) (xy 402.786043 -284.675168) (xy 402.833314 -284.68886)
			(xy 402.877776 -284.709958) (xy 402.918279 -284.737914) (xy 402.953772 -284.772006) (xy 402.983337 -284.81135)
			(xy 403.006208 -284.854927) (xy 403.021792 -284.901608) (xy 403.029687 -284.950185) (xy 403.030182 -284.974792)
			(xy 403.36903 -284.974792) (xy 403.37299 -284.925738) (xy 403.384767 -284.877954) (xy 403.404058 -284.832678)
			(xy 403.430361 -284.791082) (xy 403.462996 -284.754245) (xy 403.501117 -284.72312) (xy 403.543738 -284.698513)
			(xy 403.589754 -284.681061) (xy 403.637973 -284.671217) (xy 403.687148 -284.669236) (xy 403.736003 -284.675168)
			(xy 403.783274 -284.68886) (xy 403.827736 -284.709958) (xy 403.868239 -284.737914) (xy 403.903732 -284.772006)
			(xy 403.933297 -284.81135) (xy 403.956168 -284.854927) (xy 403.971752 -284.901608) (xy 403.979647 -284.950185)
			(xy 403.980142 -284.974792) (xy 404.31899 -284.974792) (xy 404.32295 -284.925738) (xy 404.334727 -284.877954)
			(xy 404.354018 -284.832678) (xy 404.380321 -284.791082) (xy 404.412956 -284.754245) (xy 404.451077 -284.72312)
			(xy 404.493698 -284.698513) (xy 404.539714 -284.681061) (xy 404.587933 -284.671217) (xy 404.637108 -284.669236)
			(xy 404.685963 -284.675168) (xy 404.733234 -284.68886) (xy 404.777696 -284.709958) (xy 404.818199 -284.737914)
			(xy 404.853692 -284.772006) (xy 404.883257 -284.81135) (xy 404.906128 -284.854927) (xy 404.921712 -284.901608)
			(xy 404.929607 -284.950185) (xy 404.930102 -284.974792) (xy 405.269204 -284.974792) (xy 405.273164 -284.925738)
			(xy 405.284941 -284.877954) (xy 405.304232 -284.832678) (xy 405.330535 -284.791082) (xy 405.36317 -284.754245)
			(xy 405.401291 -284.72312) (xy 405.443912 -284.698513) (xy 405.489928 -284.681061) (xy 405.538147 -284.671217)
			(xy 405.587322 -284.669236) (xy 405.636177 -284.675168) (xy 405.683448 -284.68886) (xy 405.72791 -284.709958)
			(xy 405.768413 -284.737914) (xy 405.803906 -284.772006) (xy 405.833471 -284.81135) (xy 405.856342 -284.854927)
			(xy 405.871926 -284.901608) (xy 405.879821 -284.950185) (xy 405.880316 -284.974792) (xy 406.219164 -284.974792)
			(xy 406.223124 -284.925738) (xy 406.234901 -284.877954) (xy 406.254192 -284.832678) (xy 406.280495 -284.791082)
			(xy 406.31313 -284.754245) (xy 406.351251 -284.72312) (xy 406.393872 -284.698513) (xy 406.439888 -284.681061)
			(xy 406.488107 -284.671217) (xy 406.537282 -284.669236) (xy 406.586137 -284.675168) (xy 406.633408 -284.68886)
			(xy 406.67787 -284.709958) (xy 406.718373 -284.737914) (xy 406.753866 -284.772006) (xy 406.783431 -284.81135)
			(xy 406.806302 -284.854927) (xy 406.821886 -284.901608) (xy 406.829781 -284.950185) (xy 406.830276 -284.974792)
			(xy 408.119084 -284.974792) (xy 408.123044 -284.925738) (xy 408.134821 -284.877954) (xy 408.154112 -284.832678)
			(xy 408.180415 -284.791082) (xy 408.21305 -284.754245) (xy 408.251171 -284.72312) (xy 408.293792 -284.698513)
			(xy 408.339808 -284.681061) (xy 408.388027 -284.671217) (xy 408.437202 -284.669236) (xy 408.486057 -284.675168)
			(xy 408.533328 -284.68886) (xy 408.57779 -284.709958) (xy 408.618293 -284.737914) (xy 408.653786 -284.772006)
			(xy 408.683351 -284.81135) (xy 408.706222 -284.854927) (xy 408.721806 -284.901608) (xy 408.729701 -284.950185)
			(xy 408.730196 -284.974792) (xy 409.069044 -284.974792) (xy 409.073004 -284.925738) (xy 409.084781 -284.877954)
			(xy 409.104072 -284.832678) (xy 409.130375 -284.791082) (xy 409.16301 -284.754245) (xy 409.201131 -284.72312)
			(xy 409.243752 -284.698513) (xy 409.289768 -284.681061) (xy 409.337987 -284.671217) (xy 409.387162 -284.669236)
			(xy 409.436017 -284.675168) (xy 409.483288 -284.68886) (xy 409.52775 -284.709958) (xy 409.568253 -284.737914)
			(xy 409.603746 -284.772006) (xy 409.633311 -284.81135) (xy 409.656182 -284.854927) (xy 409.671766 -284.901608)
			(xy 409.679661 -284.950185) (xy 409.680156 -284.974792) (xy 410.019004 -284.974792) (xy 410.022964 -284.925738)
			(xy 410.034741 -284.877954) (xy 410.054032 -284.832678) (xy 410.080335 -284.791082) (xy 410.11297 -284.754245)
			(xy 410.151091 -284.72312) (xy 410.193712 -284.698513) (xy 410.239728 -284.681061) (xy 410.287947 -284.671217)
			(xy 410.337122 -284.669236) (xy 410.385977 -284.675168) (xy 410.433248 -284.68886) (xy 410.47771 -284.709958)
			(xy 410.518213 -284.737914) (xy 410.553706 -284.772006) (xy 410.583271 -284.81135) (xy 410.606142 -284.854927)
			(xy 410.621726 -284.901608) (xy 410.629621 -284.950185) (xy 410.630116 -284.974792) (xy 410.969218 -284.974792)
			(xy 410.973178 -284.925738) (xy 410.984955 -284.877954) (xy 411.004246 -284.832678) (xy 411.030549 -284.791082)
			(xy 411.063184 -284.754245) (xy 411.101305 -284.72312) (xy 411.143926 -284.698513) (xy 411.189942 -284.681061)
			(xy 411.238161 -284.671217) (xy 411.287336 -284.669236) (xy 411.336191 -284.675168) (xy 411.383462 -284.68886)
			(xy 411.427924 -284.709958) (xy 411.468427 -284.737914) (xy 411.50392 -284.772006) (xy 411.533485 -284.81135)
			(xy 411.556356 -284.854927) (xy 411.57194 -284.901608) (xy 411.579835 -284.950185) (xy 411.58033 -284.974792)
			(xy 411.919178 -284.974792) (xy 411.923138 -284.925738) (xy 411.934915 -284.877954) (xy 411.954206 -284.832678)
			(xy 411.980509 -284.791082) (xy 412.013144 -284.754245) (xy 412.051265 -284.72312) (xy 412.093886 -284.698513)
			(xy 412.139902 -284.681061) (xy 412.188121 -284.671217) (xy 412.237296 -284.669236) (xy 412.286151 -284.675168)
			(xy 412.333422 -284.68886) (xy 412.377884 -284.709958) (xy 412.418387 -284.737914) (xy 412.45388 -284.772006)
			(xy 412.483445 -284.81135) (xy 412.506316 -284.854927) (xy 412.5219 -284.901608) (xy 412.529795 -284.950185)
			(xy 412.53029 -284.974792) (xy 412.869138 -284.974792) (xy 412.873098 -284.925738) (xy 412.884875 -284.877954)
			(xy 412.904166 -284.832678) (xy 412.930469 -284.791082) (xy 412.963104 -284.754245) (xy 413.001225 -284.72312)
			(xy 413.043846 -284.698513) (xy 413.089862 -284.681061) (xy 413.138081 -284.671217) (xy 413.187256 -284.669236)
			(xy 413.236111 -284.675168) (xy 413.283382 -284.68886) (xy 413.327844 -284.709958) (xy 413.368347 -284.737914)
			(xy 413.40384 -284.772006) (xy 413.433405 -284.81135) (xy 413.456276 -284.854927) (xy 413.47186 -284.901608)
			(xy 413.479755 -284.950185) (xy 413.48025 -284.974792) (xy 413.819098 -284.974792) (xy 413.823058 -284.925738)
			(xy 413.834835 -284.877954) (xy 413.854126 -284.832678) (xy 413.880429 -284.791082) (xy 413.913064 -284.754245)
			(xy 413.951185 -284.72312) (xy 413.993806 -284.698513) (xy 414.039822 -284.681061) (xy 414.088041 -284.671217)
			(xy 414.137216 -284.669236) (xy 414.186071 -284.675168) (xy 414.233342 -284.68886) (xy 414.277804 -284.709958)
			(xy 414.318307 -284.737914) (xy 414.3538 -284.772006) (xy 414.383365 -284.81135) (xy 414.406236 -284.854927)
			(xy 414.42182 -284.901608) (xy 414.429715 -284.950185) (xy 414.43021 -284.974792) (xy 414.769058 -284.974792)
			(xy 414.773018 -284.925738) (xy 414.784795 -284.877954) (xy 414.804086 -284.832678) (xy 414.830389 -284.791082)
			(xy 414.863024 -284.754245) (xy 414.901145 -284.72312) (xy 414.943766 -284.698513) (xy 414.989782 -284.681061)
			(xy 415.038001 -284.671217) (xy 415.087176 -284.669236) (xy 415.136031 -284.675168) (xy 415.183302 -284.68886)
			(xy 415.227764 -284.709958) (xy 415.268267 -284.737914) (xy 415.30376 -284.772006) (xy 415.333325 -284.81135)
			(xy 415.356196 -284.854927) (xy 415.37178 -284.901608) (xy 415.379675 -284.950185) (xy 415.38017 -284.974792)
			(xy 415.719018 -284.974792) (xy 415.722978 -284.925738) (xy 415.734755 -284.877954) (xy 415.754046 -284.832678)
			(xy 415.780349 -284.791082) (xy 415.812984 -284.754245) (xy 415.851105 -284.72312) (xy 415.893726 -284.698513)
			(xy 415.939742 -284.681061) (xy 415.987961 -284.671217) (xy 416.037136 -284.669236) (xy 416.085991 -284.675168)
			(xy 416.133262 -284.68886) (xy 416.177724 -284.709958) (xy 416.218227 -284.737914) (xy 416.25372 -284.772006)
			(xy 416.283285 -284.81135) (xy 416.306156 -284.854927) (xy 416.32174 -284.901608) (xy 416.329635 -284.950185)
			(xy 416.33013 -284.974792) (xy 416.668978 -284.974792) (xy 416.672938 -284.925738) (xy 416.684715 -284.877954)
			(xy 416.704006 -284.832678) (xy 416.730309 -284.791082) (xy 416.762944 -284.754245) (xy 416.801065 -284.72312)
			(xy 416.843686 -284.698513) (xy 416.889702 -284.681061) (xy 416.937921 -284.671217) (xy 416.987096 -284.669236)
			(xy 417.035951 -284.675168) (xy 417.083222 -284.68886) (xy 417.127684 -284.709958) (xy 417.168187 -284.737914)
			(xy 417.20368 -284.772006) (xy 417.233245 -284.81135) (xy 417.256116 -284.854927) (xy 417.2717 -284.901608)
			(xy 417.279595 -284.950185) (xy 417.28009 -284.974792) (xy 417.619192 -284.974792) (xy 417.623152 -284.925738)
			(xy 417.634929 -284.877954) (xy 417.65422 -284.832678) (xy 417.680523 -284.791082) (xy 417.713158 -284.754245)
			(xy 417.751279 -284.72312) (xy 417.7939 -284.698513) (xy 417.839916 -284.681061) (xy 417.888135 -284.671217)
			(xy 417.93731 -284.669236) (xy 417.986165 -284.675168) (xy 418.033436 -284.68886) (xy 418.077898 -284.709958)
			(xy 418.118401 -284.737914) (xy 418.153894 -284.772006) (xy 418.183459 -284.81135) (xy 418.20633 -284.854927)
			(xy 418.221914 -284.901608) (xy 418.229809 -284.950185) (xy 418.230304 -284.974792) (xy 418.569152 -284.974792)
			(xy 418.573112 -284.925738) (xy 418.584889 -284.877954) (xy 418.60418 -284.832678) (xy 418.630483 -284.791082)
			(xy 418.663118 -284.754245) (xy 418.701239 -284.72312) (xy 418.74386 -284.698513) (xy 418.789876 -284.681061)
			(xy 418.838095 -284.671217) (xy 418.88727 -284.669236) (xy 418.936125 -284.675168) (xy 418.983396 -284.68886)
			(xy 419.027858 -284.709958) (xy 419.068361 -284.737914) (xy 419.103854 -284.772006) (xy 419.133419 -284.81135)
			(xy 419.15629 -284.854927) (xy 419.171874 -284.901608) (xy 419.179769 -284.950185) (xy 419.180264 -284.974792)
			(xy 419.179769 -284.999399) (xy 419.171874 -285.047976) (xy 419.15629 -285.094657) (xy 419.133419 -285.138234)
			(xy 419.103854 -285.177578) (xy 419.068361 -285.21167) (xy 419.027858 -285.239626) (xy 418.983396 -285.260724)
			(xy 418.936125 -285.274416) (xy 418.88727 -285.280348) (xy 418.838095 -285.278367) (xy 418.789876 -285.268523)
			(xy 418.74386 -285.251071) (xy 418.701239 -285.226464) (xy 418.663118 -285.195339) (xy 418.630483 -285.158502)
			(xy 418.60418 -285.116906) (xy 418.584889 -285.07163) (xy 418.573112 -285.023846) (xy 418.569152 -284.974792)
			(xy 418.230304 -284.974792) (xy 418.229809 -284.999399) (xy 418.221914 -285.047976) (xy 418.20633 -285.094657)
			(xy 418.183459 -285.138234) (xy 418.153894 -285.177578) (xy 418.118401 -285.21167) (xy 418.077898 -285.239626)
			(xy 418.033436 -285.260724) (xy 417.986165 -285.274416) (xy 417.93731 -285.280348) (xy 417.888135 -285.278367)
			(xy 417.839916 -285.268523) (xy 417.7939 -285.251071) (xy 417.751279 -285.226464) (xy 417.713158 -285.195339)
			(xy 417.680523 -285.158502) (xy 417.65422 -285.116906) (xy 417.634929 -285.07163) (xy 417.623152 -285.023846)
			(xy 417.619192 -284.974792) (xy 417.28009 -284.974792) (xy 417.279595 -284.999399) (xy 417.2717 -285.047976)
			(xy 417.256116 -285.094657) (xy 417.233245 -285.138234) (xy 417.20368 -285.177578) (xy 417.168187 -285.21167)
			(xy 417.127684 -285.239626) (xy 417.083222 -285.260724) (xy 417.035951 -285.274416) (xy 416.987096 -285.280348)
			(xy 416.937921 -285.278367) (xy 416.889702 -285.268523) (xy 416.843686 -285.251071) (xy 416.801065 -285.226464)
			(xy 416.762944 -285.195339) (xy 416.730309 -285.158502) (xy 416.704006 -285.116906) (xy 416.684715 -285.07163)
			(xy 416.672938 -285.023846) (xy 416.668978 -284.974792) (xy 416.33013 -284.974792) (xy 416.329635 -284.999399)
			(xy 416.32174 -285.047976) (xy 416.306156 -285.094657) (xy 416.283285 -285.138234) (xy 416.25372 -285.177578)
			(xy 416.218227 -285.21167) (xy 416.177724 -285.239626) (xy 416.133262 -285.260724) (xy 416.085991 -285.274416)
			(xy 416.037136 -285.280348) (xy 415.987961 -285.278367) (xy 415.939742 -285.268523) (xy 415.893726 -285.251071)
			(xy 415.851105 -285.226464) (xy 415.812984 -285.195339) (xy 415.780349 -285.158502) (xy 415.754046 -285.116906)
			(xy 415.734755 -285.07163) (xy 415.722978 -285.023846) (xy 415.719018 -284.974792) (xy 415.38017 -284.974792)
			(xy 415.379675 -284.999399) (xy 415.37178 -285.047976) (xy 415.356196 -285.094657) (xy 415.333325 -285.138234)
			(xy 415.30376 -285.177578) (xy 415.268267 -285.21167) (xy 415.227764 -285.239626) (xy 415.183302 -285.260724)
			(xy 415.136031 -285.274416) (xy 415.087176 -285.280348) (xy 415.038001 -285.278367) (xy 414.989782 -285.268523)
			(xy 414.943766 -285.251071) (xy 414.901145 -285.226464) (xy 414.863024 -285.195339) (xy 414.830389 -285.158502)
			(xy 414.804086 -285.116906) (xy 414.784795 -285.07163) (xy 414.773018 -285.023846) (xy 414.769058 -284.974792)
			(xy 414.43021 -284.974792) (xy 414.429715 -284.999399) (xy 414.42182 -285.047976) (xy 414.406236 -285.094657)
			(xy 414.383365 -285.138234) (xy 414.3538 -285.177578) (xy 414.318307 -285.21167) (xy 414.277804 -285.239626)
			(xy 414.233342 -285.260724) (xy 414.186071 -285.274416) (xy 414.137216 -285.280348) (xy 414.088041 -285.278367)
			(xy 414.039822 -285.268523) (xy 413.993806 -285.251071) (xy 413.951185 -285.226464) (xy 413.913064 -285.195339)
			(xy 413.880429 -285.158502) (xy 413.854126 -285.116906) (xy 413.834835 -285.07163) (xy 413.823058 -285.023846)
			(xy 413.819098 -284.974792) (xy 413.48025 -284.974792) (xy 413.479755 -284.999399) (xy 413.47186 -285.047976)
			(xy 413.456276 -285.094657) (xy 413.433405 -285.138234) (xy 413.40384 -285.177578) (xy 413.368347 -285.21167)
			(xy 413.327844 -285.239626) (xy 413.283382 -285.260724) (xy 413.236111 -285.274416) (xy 413.187256 -285.280348)
			(xy 413.138081 -285.278367) (xy 413.089862 -285.268523) (xy 413.043846 -285.251071) (xy 413.001225 -285.226464)
			(xy 412.963104 -285.195339) (xy 412.930469 -285.158502) (xy 412.904166 -285.116906) (xy 412.884875 -285.07163)
			(xy 412.873098 -285.023846) (xy 412.869138 -284.974792) (xy 412.53029 -284.974792) (xy 412.529795 -284.999399)
			(xy 412.5219 -285.047976) (xy 412.506316 -285.094657) (xy 412.483445 -285.138234) (xy 412.45388 -285.177578)
			(xy 412.418387 -285.21167) (xy 412.377884 -285.239626) (xy 412.333422 -285.260724) (xy 412.286151 -285.274416)
			(xy 412.237296 -285.280348) (xy 412.188121 -285.278367) (xy 412.139902 -285.268523) (xy 412.093886 -285.251071)
			(xy 412.051265 -285.226464) (xy 412.013144 -285.195339) (xy 411.980509 -285.158502) (xy 411.954206 -285.116906)
			(xy 411.934915 -285.07163) (xy 411.923138 -285.023846) (xy 411.919178 -284.974792) (xy 411.58033 -284.974792)
			(xy 411.579835 -284.999399) (xy 411.57194 -285.047976) (xy 411.556356 -285.094657) (xy 411.533485 -285.138234)
			(xy 411.50392 -285.177578) (xy 411.468427 -285.21167) (xy 411.427924 -285.239626) (xy 411.383462 -285.260724)
			(xy 411.336191 -285.274416) (xy 411.287336 -285.280348) (xy 411.238161 -285.278367) (xy 411.189942 -285.268523)
			(xy 411.143926 -285.251071) (xy 411.101305 -285.226464) (xy 411.063184 -285.195339) (xy 411.030549 -285.158502)
			(xy 411.004246 -285.116906) (xy 410.984955 -285.07163) (xy 410.973178 -285.023846) (xy 410.969218 -284.974792)
			(xy 410.630116 -284.974792) (xy 410.629621 -284.999399) (xy 410.621726 -285.047976) (xy 410.606142 -285.094657)
			(xy 410.583271 -285.138234) (xy 410.553706 -285.177578) (xy 410.518213 -285.21167) (xy 410.47771 -285.239626)
			(xy 410.433248 -285.260724) (xy 410.385977 -285.274416) (xy 410.337122 -285.280348) (xy 410.287947 -285.278367)
			(xy 410.239728 -285.268523) (xy 410.193712 -285.251071) (xy 410.151091 -285.226464) (xy 410.11297 -285.195339)
			(xy 410.080335 -285.158502) (xy 410.054032 -285.116906) (xy 410.034741 -285.07163) (xy 410.022964 -285.023846)
			(xy 410.019004 -284.974792) (xy 409.680156 -284.974792) (xy 409.679661 -284.999399) (xy 409.671766 -285.047976)
			(xy 409.656182 -285.094657) (xy 409.633311 -285.138234) (xy 409.603746 -285.177578) (xy 409.568253 -285.21167)
			(xy 409.52775 -285.239626) (xy 409.483288 -285.260724) (xy 409.436017 -285.274416) (xy 409.387162 -285.280348)
			(xy 409.337987 -285.278367) (xy 409.289768 -285.268523) (xy 409.243752 -285.251071) (xy 409.201131 -285.226464)
			(xy 409.16301 -285.195339) (xy 409.130375 -285.158502) (xy 409.104072 -285.116906) (xy 409.084781 -285.07163)
			(xy 409.073004 -285.023846) (xy 409.069044 -284.974792) (xy 408.730196 -284.974792) (xy 408.729701 -284.999399)
			(xy 408.721806 -285.047976) (xy 408.706222 -285.094657) (xy 408.683351 -285.138234) (xy 408.653786 -285.177578)
			(xy 408.618293 -285.21167) (xy 408.57779 -285.239626) (xy 408.533328 -285.260724) (xy 408.486057 -285.274416)
			(xy 408.437202 -285.280348) (xy 408.388027 -285.278367) (xy 408.339808 -285.268523) (xy 408.293792 -285.251071)
			(xy 408.251171 -285.226464) (xy 408.21305 -285.195339) (xy 408.180415 -285.158502) (xy 408.154112 -285.116906)
			(xy 408.134821 -285.07163) (xy 408.123044 -285.023846) (xy 408.119084 -284.974792) (xy 406.830276 -284.974792)
			(xy 406.829781 -284.999399) (xy 406.821886 -285.047976) (xy 406.806302 -285.094657) (xy 406.783431 -285.138234)
			(xy 406.753866 -285.177578) (xy 406.718373 -285.21167) (xy 406.67787 -285.239626) (xy 406.633408 -285.260724)
			(xy 406.586137 -285.274416) (xy 406.537282 -285.280348) (xy 406.488107 -285.278367) (xy 406.439888 -285.268523)
			(xy 406.393872 -285.251071) (xy 406.351251 -285.226464) (xy 406.31313 -285.195339) (xy 406.280495 -285.158502)
			(xy 406.254192 -285.116906) (xy 406.234901 -285.07163) (xy 406.223124 -285.023846) (xy 406.219164 -284.974792)
			(xy 405.880316 -284.974792) (xy 405.879821 -284.999399) (xy 405.871926 -285.047976) (xy 405.856342 -285.094657)
			(xy 405.833471 -285.138234) (xy 405.803906 -285.177578) (xy 405.768413 -285.21167) (xy 405.72791 -285.239626)
			(xy 405.683448 -285.260724) (xy 405.636177 -285.274416) (xy 405.587322 -285.280348) (xy 405.538147 -285.278367)
			(xy 405.489928 -285.268523) (xy 405.443912 -285.251071) (xy 405.401291 -285.226464) (xy 405.36317 -285.195339)
			(xy 405.330535 -285.158502) (xy 405.304232 -285.116906) (xy 405.284941 -285.07163) (xy 405.273164 -285.023846)
			(xy 405.269204 -284.974792) (xy 404.930102 -284.974792) (xy 404.929607 -284.999399) (xy 404.921712 -285.047976)
			(xy 404.906128 -285.094657) (xy 404.883257 -285.138234) (xy 404.853692 -285.177578) (xy 404.818199 -285.21167)
			(xy 404.777696 -285.239626) (xy 404.733234 -285.260724) (xy 404.685963 -285.274416) (xy 404.637108 -285.280348)
			(xy 404.587933 -285.278367) (xy 404.539714 -285.268523) (xy 404.493698 -285.251071) (xy 404.451077 -285.226464)
			(xy 404.412956 -285.195339) (xy 404.380321 -285.158502) (xy 404.354018 -285.116906) (xy 404.334727 -285.07163)
			(xy 404.32295 -285.023846) (xy 404.31899 -284.974792) (xy 403.980142 -284.974792) (xy 403.979647 -284.999399)
			(xy 403.971752 -285.047976) (xy 403.956168 -285.094657) (xy 403.933297 -285.138234) (xy 403.903732 -285.177578)
			(xy 403.868239 -285.21167) (xy 403.827736 -285.239626) (xy 403.783274 -285.260724) (xy 403.736003 -285.274416)
			(xy 403.687148 -285.280348) (xy 403.637973 -285.278367) (xy 403.589754 -285.268523) (xy 403.543738 -285.251071)
			(xy 403.501117 -285.226464) (xy 403.462996 -285.195339) (xy 403.430361 -285.158502) (xy 403.404058 -285.116906)
			(xy 403.384767 -285.07163) (xy 403.37299 -285.023846) (xy 403.36903 -284.974792) (xy 403.030182 -284.974792)
			(xy 403.029687 -284.999399) (xy 403.021792 -285.047976) (xy 403.006208 -285.094657) (xy 402.983337 -285.138234)
			(xy 402.953772 -285.177578) (xy 402.918279 -285.21167) (xy 402.877776 -285.239626) (xy 402.833314 -285.260724)
			(xy 402.786043 -285.274416) (xy 402.737188 -285.280348) (xy 402.688013 -285.278367) (xy 402.639794 -285.268523)
			(xy 402.593778 -285.251071) (xy 402.551157 -285.226464) (xy 402.513036 -285.195339) (xy 402.480401 -285.158502)
			(xy 402.454098 -285.116906) (xy 402.434807 -285.07163) (xy 402.42303 -285.023846) (xy 402.41907 -284.974792)
			(xy 402.080222 -284.974792) (xy 402.079727 -284.999399) (xy 402.071832 -285.047976) (xy 402.056248 -285.094657)
			(xy 402.033377 -285.138234) (xy 402.003812 -285.177578) (xy 401.968319 -285.21167) (xy 401.927816 -285.239626)
			(xy 401.883354 -285.260724) (xy 401.836083 -285.274416) (xy 401.787228 -285.280348) (xy 401.738053 -285.278367)
			(xy 401.689834 -285.268523) (xy 401.643818 -285.251071) (xy 401.601197 -285.226464) (xy 401.563076 -285.195339)
			(xy 401.530441 -285.158502) (xy 401.504138 -285.116906) (xy 401.484847 -285.07163) (xy 401.47307 -285.023846)
			(xy 401.46911 -284.974792) (xy 401.130262 -284.974792) (xy 401.129767 -284.999399) (xy 401.121872 -285.047976)
			(xy 401.106288 -285.094657) (xy 401.083417 -285.138234) (xy 401.053852 -285.177578) (xy 401.018359 -285.21167)
			(xy 400.977856 -285.239626) (xy 400.933394 -285.260724) (xy 400.886123 -285.274416) (xy 400.837268 -285.280348)
			(xy 400.788093 -285.278367) (xy 400.739874 -285.268523) (xy 400.693858 -285.251071) (xy 400.651237 -285.226464)
			(xy 400.613116 -285.195339) (xy 400.580481 -285.158502) (xy 400.554178 -285.116906) (xy 400.534887 -285.07163)
			(xy 400.52311 -285.023846) (xy 400.51915 -284.974792) (xy 400.180302 -284.974792) (xy 400.179807 -284.999399)
			(xy 400.171912 -285.047976) (xy 400.156328 -285.094657) (xy 400.133457 -285.138234) (xy 400.103892 -285.177578)
			(xy 400.068399 -285.21167) (xy 400.027896 -285.239626) (xy 399.983434 -285.260724) (xy 399.936163 -285.274416)
			(xy 399.887308 -285.280348) (xy 399.838133 -285.278367) (xy 399.789914 -285.268523) (xy 399.743898 -285.251071)
			(xy 399.701277 -285.226464) (xy 399.663156 -285.195339) (xy 399.630521 -285.158502) (xy 399.604218 -285.116906)
			(xy 399.584927 -285.07163) (xy 399.57315 -285.023846) (xy 399.56919 -284.974792) (xy 399.230342 -284.974792)
			(xy 399.229847 -284.999399) (xy 399.221952 -285.047976) (xy 399.206368 -285.094657) (xy 399.183497 -285.138234)
			(xy 399.153932 -285.177578) (xy 399.118439 -285.21167) (xy 399.077936 -285.239626) (xy 399.033474 -285.260724)
			(xy 398.986203 -285.274416) (xy 398.937348 -285.280348) (xy 398.888173 -285.278367) (xy 398.839954 -285.268523)
			(xy 398.793938 -285.251071) (xy 398.751317 -285.226464) (xy 398.713196 -285.195339) (xy 398.680561 -285.158502)
			(xy 398.654258 -285.116906) (xy 398.634967 -285.07163) (xy 398.62319 -285.023846) (xy 398.61923 -284.974792)
			(xy 398.280128 -284.974792) (xy 398.279633 -284.999399) (xy 398.271738 -285.047976) (xy 398.256154 -285.094657)
			(xy 398.233283 -285.138234) (xy 398.203718 -285.177578) (xy 398.168225 -285.21167) (xy 398.127722 -285.239626)
			(xy 398.08326 -285.260724) (xy 398.035989 -285.274416) (xy 397.987134 -285.280348) (xy 397.937959 -285.278367)
			(xy 397.88974 -285.268523) (xy 397.843724 -285.251071) (xy 397.801103 -285.226464) (xy 397.762982 -285.195339)
			(xy 397.730347 -285.158502) (xy 397.704044 -285.116906) (xy 397.684753 -285.07163) (xy 397.672976 -285.023846)
			(xy 397.669016 -284.974792) (xy 397.330168 -284.974792) (xy 397.329673 -284.999399) (xy 397.321778 -285.047976)
			(xy 397.306194 -285.094657) (xy 397.283323 -285.138234) (xy 397.253758 -285.177578) (xy 397.218265 -285.21167)
			(xy 397.177762 -285.239626) (xy 397.1333 -285.260724) (xy 397.086029 -285.274416) (xy 397.037174 -285.280348)
			(xy 396.987999 -285.278367) (xy 396.93978 -285.268523) (xy 396.893764 -285.251071) (xy 396.851143 -285.226464)
			(xy 396.813022 -285.195339) (xy 396.780387 -285.158502) (xy 396.754084 -285.116906) (xy 396.734793 -285.07163)
			(xy 396.723016 -285.023846) (xy 396.719056 -284.974792) (xy 396.380208 -284.974792) (xy 396.379713 -284.999399)
			(xy 396.371818 -285.047976) (xy 396.356234 -285.094657) (xy 396.333363 -285.138234) (xy 396.303798 -285.177578)
			(xy 396.268305 -285.21167) (xy 396.227802 -285.239626) (xy 396.18334 -285.260724) (xy 396.136069 -285.274416)
			(xy 396.087214 -285.280348) (xy 396.038039 -285.278367) (xy 395.98982 -285.268523) (xy 395.943804 -285.251071)
			(xy 395.901183 -285.226464) (xy 395.863062 -285.195339) (xy 395.830427 -285.158502) (xy 395.804124 -285.116906)
			(xy 395.784833 -285.07163) (xy 395.773056 -285.023846) (xy 395.769096 -284.974792) (xy 395.430248 -284.974792)
			(xy 395.429753 -284.999399) (xy 395.421858 -285.047976) (xy 395.406274 -285.094657) (xy 395.383403 -285.138234)
			(xy 395.353838 -285.177578) (xy 395.318345 -285.21167) (xy 395.277842 -285.239626) (xy 395.23338 -285.260724)
			(xy 395.186109 -285.274416) (xy 395.137254 -285.280348) (xy 395.088079 -285.278367) (xy 395.03986 -285.268523)
			(xy 394.993844 -285.251071) (xy 394.951223 -285.226464) (xy 394.913102 -285.195339) (xy 394.880467 -285.158502)
			(xy 394.854164 -285.116906) (xy 394.834873 -285.07163) (xy 394.823096 -285.023846) (xy 394.819136 -284.974792)
			(xy 394.480288 -284.974792) (xy 394.479793 -284.999399) (xy 394.471898 -285.047976) (xy 394.456314 -285.094657)
			(xy 394.433443 -285.138234) (xy 394.403878 -285.177578) (xy 394.368385 -285.21167) (xy 394.327882 -285.239626)
			(xy 394.28342 -285.260724) (xy 394.236149 -285.274416) (xy 394.187294 -285.280348) (xy 394.138119 -285.278367)
			(xy 394.0899 -285.268523) (xy 394.043884 -285.251071) (xy 394.001263 -285.226464) (xy 393.963142 -285.195339)
			(xy 393.930507 -285.158502) (xy 393.904204 -285.116906) (xy 393.884913 -285.07163) (xy 393.873136 -285.023846)
			(xy 393.869176 -284.974792) (xy 393.530328 -284.974792) (xy 393.529833 -284.999399) (xy 393.521938 -285.047976)
			(xy 393.506354 -285.094657) (xy 393.483483 -285.138234) (xy 393.453918 -285.177578) (xy 393.418425 -285.21167)
			(xy 393.377922 -285.239626) (xy 393.33346 -285.260724) (xy 393.286189 -285.274416) (xy 393.237334 -285.280348)
			(xy 393.188159 -285.278367) (xy 393.13994 -285.268523) (xy 393.093924 -285.251071) (xy 393.051303 -285.226464)
			(xy 393.013182 -285.195339) (xy 392.980547 -285.158502) (xy 392.954244 -285.116906) (xy 392.934953 -285.07163)
			(xy 392.923176 -285.023846) (xy 392.919216 -284.974792) (xy 391.630154 -284.974792) (xy 391.629659 -284.999399)
			(xy 391.621764 -285.047976) (xy 391.60618 -285.094657) (xy 391.583309 -285.138234) (xy 391.553744 -285.177578)
			(xy 391.518251 -285.21167) (xy 391.477748 -285.239626) (xy 391.433286 -285.260724) (xy 391.386015 -285.274416)
			(xy 391.33716 -285.280348) (xy 391.287985 -285.278367) (xy 391.239766 -285.268523) (xy 391.19375 -285.251071)
			(xy 391.151129 -285.226464) (xy 391.113008 -285.195339) (xy 391.080373 -285.158502) (xy 391.05407 -285.116906)
			(xy 391.034779 -285.07163) (xy 391.023002 -285.023846) (xy 391.019042 -284.974792) (xy 389.730234 -284.974792)
			(xy 389.729739 -284.999399) (xy 389.721844 -285.047976) (xy 389.70626 -285.094657) (xy 389.683389 -285.138234)
			(xy 389.653824 -285.177578) (xy 389.618331 -285.21167) (xy 389.577828 -285.239626) (xy 389.533366 -285.260724)
			(xy 389.486095 -285.274416) (xy 389.43724 -285.280348) (xy 389.388065 -285.278367) (xy 389.339846 -285.268523)
			(xy 389.29383 -285.251071) (xy 389.251209 -285.226464) (xy 389.213088 -285.195339) (xy 389.180453 -285.158502)
			(xy 389.15415 -285.116906) (xy 389.134859 -285.07163) (xy 389.123082 -285.023846) (xy 389.119122 -284.974792)
			(xy 388.780274 -284.974792) (xy 388.779779 -284.999399) (xy 388.771884 -285.047976) (xy 388.7563 -285.094657)
			(xy 388.733429 -285.138234) (xy 388.703864 -285.177578) (xy 388.668371 -285.21167) (xy 388.627868 -285.239626)
			(xy 388.583406 -285.260724) (xy 388.536135 -285.274416) (xy 388.48728 -285.280348) (xy 388.438105 -285.278367)
			(xy 388.389886 -285.268523) (xy 388.34387 -285.251071) (xy 388.301249 -285.226464) (xy 388.263128 -285.195339)
			(xy 388.230493 -285.158502) (xy 388.20419 -285.116906) (xy 388.184899 -285.07163) (xy 388.173122 -285.023846)
			(xy 388.169162 -284.974792) (xy 387.830314 -284.974792) (xy 387.829819 -284.999399) (xy 387.821924 -285.047976)
			(xy 387.80634 -285.094657) (xy 387.783469 -285.138234) (xy 387.753904 -285.177578) (xy 387.718411 -285.21167)
			(xy 387.677908 -285.239626) (xy 387.633446 -285.260724) (xy 387.586175 -285.274416) (xy 387.53732 -285.280348)
			(xy 387.488145 -285.278367) (xy 387.439926 -285.268523) (xy 387.39391 -285.251071) (xy 387.351289 -285.226464)
			(xy 387.313168 -285.195339) (xy 387.280533 -285.158502) (xy 387.25423 -285.116906) (xy 387.234939 -285.07163)
			(xy 387.223162 -285.023846) (xy 387.219202 -284.974792) (xy 386.880354 -284.974792) (xy 386.879859 -284.999399)
			(xy 386.871964 -285.047976) (xy 386.85638 -285.094657) (xy 386.833509 -285.138234) (xy 386.803944 -285.177578)
			(xy 386.768451 -285.21167) (xy 386.727948 -285.239626) (xy 386.683486 -285.260724) (xy 386.636215 -285.274416)
			(xy 386.58736 -285.280348) (xy 386.538185 -285.278367) (xy 386.489966 -285.268523) (xy 386.44395 -285.251071)
			(xy 386.401329 -285.226464) (xy 386.363208 -285.195339) (xy 386.330573 -285.158502) (xy 386.30427 -285.116906)
			(xy 386.284979 -285.07163) (xy 386.273202 -285.023846) (xy 386.269242 -284.974792) (xy 385.93014 -284.974792)
			(xy 385.929645 -284.999399) (xy 385.92175 -285.047976) (xy 385.906166 -285.094657) (xy 385.883295 -285.138234)
			(xy 385.85373 -285.177578) (xy 385.818237 -285.21167) (xy 385.777734 -285.239626) (xy 385.733272 -285.260724)
			(xy 385.686001 -285.274416) (xy 385.637146 -285.280348) (xy 385.587971 -285.278367) (xy 385.539752 -285.268523)
			(xy 385.493736 -285.251071) (xy 385.451115 -285.226464) (xy 385.412994 -285.195339) (xy 385.380359 -285.158502)
			(xy 385.354056 -285.116906) (xy 385.334765 -285.07163) (xy 385.322988 -285.023846) (xy 385.319028 -284.974792)
			(xy 384.98018 -284.974792) (xy 384.979685 -284.999399) (xy 384.97179 -285.047976) (xy 384.956206 -285.094657)
			(xy 384.933335 -285.138234) (xy 384.90377 -285.177578) (xy 384.868277 -285.21167) (xy 384.827774 -285.239626)
			(xy 384.783312 -285.260724) (xy 384.736041 -285.274416) (xy 384.687186 -285.280348) (xy 384.638011 -285.278367)
			(xy 384.589792 -285.268523) (xy 384.543776 -285.251071) (xy 384.501155 -285.226464) (xy 384.463034 -285.195339)
			(xy 384.430399 -285.158502) (xy 384.404096 -285.116906) (xy 384.384805 -285.07163) (xy 384.373028 -285.023846)
			(xy 384.369068 -284.974792) (xy 384.2512 -284.974792) (xy 384.2512 -285.924752) (xy 384.369068 -285.924752)
			(xy 384.373028 -285.875698) (xy 384.384805 -285.827914) (xy 384.404096 -285.782638) (xy 384.430399 -285.741042)
			(xy 384.463034 -285.704205) (xy 384.501155 -285.67308) (xy 384.543776 -285.648473) (xy 384.589792 -285.631021)
			(xy 384.638011 -285.621177) (xy 384.687186 -285.619196) (xy 384.736041 -285.625128) (xy 384.783312 -285.63882)
			(xy 384.827774 -285.659918) (xy 384.868277 -285.687874) (xy 384.90377 -285.721966) (xy 384.933335 -285.76131)
			(xy 384.956206 -285.804887) (xy 384.97179 -285.851568) (xy 384.979685 -285.900145) (xy 384.98018 -285.924752)
			(xy 385.319028 -285.924752) (xy 385.322988 -285.875698) (xy 385.334765 -285.827914) (xy 385.354056 -285.782638)
			(xy 385.380359 -285.741042) (xy 385.412994 -285.704205) (xy 385.451115 -285.67308) (xy 385.493736 -285.648473)
			(xy 385.539752 -285.631021) (xy 385.587971 -285.621177) (xy 385.637146 -285.619196) (xy 385.686001 -285.625128)
			(xy 385.733272 -285.63882) (xy 385.777734 -285.659918) (xy 385.818237 -285.687874) (xy 385.85373 -285.721966)
			(xy 385.883295 -285.76131) (xy 385.906166 -285.804887) (xy 385.92175 -285.851568) (xy 385.929645 -285.900145)
			(xy 385.93014 -285.924752) (xy 386.269242 -285.924752) (xy 386.273202 -285.875698) (xy 386.284979 -285.827914)
			(xy 386.30427 -285.782638) (xy 386.330573 -285.741042) (xy 386.363208 -285.704205) (xy 386.401329 -285.67308)
			(xy 386.44395 -285.648473) (xy 386.489966 -285.631021) (xy 386.538185 -285.621177) (xy 386.58736 -285.619196)
			(xy 386.636215 -285.625128) (xy 386.683486 -285.63882) (xy 386.727948 -285.659918) (xy 386.768451 -285.687874)
			(xy 386.803944 -285.721966) (xy 386.833509 -285.76131) (xy 386.85638 -285.804887) (xy 386.871964 -285.851568)
			(xy 386.879859 -285.900145) (xy 386.880354 -285.924752) (xy 387.219202 -285.924752) (xy 387.223162 -285.875698)
			(xy 387.234939 -285.827914) (xy 387.25423 -285.782638) (xy 387.280533 -285.741042) (xy 387.313168 -285.704205)
			(xy 387.351289 -285.67308) (xy 387.39391 -285.648473) (xy 387.439926 -285.631021) (xy 387.488145 -285.621177)
			(xy 387.53732 -285.619196) (xy 387.586175 -285.625128) (xy 387.633446 -285.63882) (xy 387.677908 -285.659918)
			(xy 387.718411 -285.687874) (xy 387.753904 -285.721966) (xy 387.783469 -285.76131) (xy 387.80634 -285.804887)
			(xy 387.821924 -285.851568) (xy 387.829819 -285.900145) (xy 387.830314 -285.924752) (xy 388.169162 -285.924752)
			(xy 388.173122 -285.875698) (xy 388.184899 -285.827914) (xy 388.20419 -285.782638) (xy 388.230493 -285.741042)
			(xy 388.263128 -285.704205) (xy 388.301249 -285.67308) (xy 388.34387 -285.648473) (xy 388.389886 -285.631021)
			(xy 388.438105 -285.621177) (xy 388.48728 -285.619196) (xy 388.536135 -285.625128) (xy 388.583406 -285.63882)
			(xy 388.627868 -285.659918) (xy 388.668371 -285.687874) (xy 388.703864 -285.721966) (xy 388.733429 -285.76131)
			(xy 388.7563 -285.804887) (xy 388.771884 -285.851568) (xy 388.779779 -285.900145) (xy 388.780274 -285.924752)
			(xy 389.119122 -285.924752) (xy 389.123082 -285.875698) (xy 389.134859 -285.827914) (xy 389.15415 -285.782638)
			(xy 389.180453 -285.741042) (xy 389.213088 -285.704205) (xy 389.251209 -285.67308) (xy 389.29383 -285.648473)
			(xy 389.339846 -285.631021) (xy 389.388065 -285.621177) (xy 389.43724 -285.619196) (xy 389.486095 -285.625128)
			(xy 389.533366 -285.63882) (xy 389.577828 -285.659918) (xy 389.618331 -285.687874) (xy 389.653824 -285.721966)
			(xy 389.683389 -285.76131) (xy 389.70626 -285.804887) (xy 389.721844 -285.851568) (xy 389.729739 -285.900145)
			(xy 389.730234 -285.924752) (xy 392.919216 -285.924752) (xy 392.923176 -285.875698) (xy 392.934953 -285.827914)
			(xy 392.954244 -285.782638) (xy 392.980547 -285.741042) (xy 393.013182 -285.704205) (xy 393.051303 -285.67308)
			(xy 393.093924 -285.648473) (xy 393.13994 -285.631021) (xy 393.188159 -285.621177) (xy 393.237334 -285.619196)
			(xy 393.286189 -285.625128) (xy 393.33346 -285.63882) (xy 393.377922 -285.659918) (xy 393.418425 -285.687874)
			(xy 393.453918 -285.721966) (xy 393.483483 -285.76131) (xy 393.506354 -285.804887) (xy 393.521938 -285.851568)
			(xy 393.529833 -285.900145) (xy 393.530328 -285.924752) (xy 393.869176 -285.924752) (xy 393.873136 -285.875698)
			(xy 393.884913 -285.827914) (xy 393.904204 -285.782638) (xy 393.930507 -285.741042) (xy 393.963142 -285.704205)
			(xy 394.001263 -285.67308) (xy 394.043884 -285.648473) (xy 394.0899 -285.631021) (xy 394.138119 -285.621177)
			(xy 394.187294 -285.619196) (xy 394.236149 -285.625128) (xy 394.28342 -285.63882) (xy 394.327882 -285.659918)
			(xy 394.368385 -285.687874) (xy 394.403878 -285.721966) (xy 394.433443 -285.76131) (xy 394.456314 -285.804887)
			(xy 394.471898 -285.851568) (xy 394.479793 -285.900145) (xy 394.480288 -285.924752) (xy 394.819136 -285.924752)
			(xy 394.823096 -285.875698) (xy 394.834873 -285.827914) (xy 394.854164 -285.782638) (xy 394.880467 -285.741042)
			(xy 394.913102 -285.704205) (xy 394.951223 -285.67308) (xy 394.993844 -285.648473) (xy 395.03986 -285.631021)
			(xy 395.088079 -285.621177) (xy 395.137254 -285.619196) (xy 395.186109 -285.625128) (xy 395.23338 -285.63882)
			(xy 395.277842 -285.659918) (xy 395.318345 -285.687874) (xy 395.353838 -285.721966) (xy 395.383403 -285.76131)
			(xy 395.406274 -285.804887) (xy 395.421858 -285.851568) (xy 395.429753 -285.900145) (xy 395.430248 -285.924752)
			(xy 395.769096 -285.924752) (xy 395.773056 -285.875698) (xy 395.784833 -285.827914) (xy 395.804124 -285.782638)
			(xy 395.830427 -285.741042) (xy 395.863062 -285.704205) (xy 395.901183 -285.67308) (xy 395.943804 -285.648473)
			(xy 395.98982 -285.631021) (xy 396.038039 -285.621177) (xy 396.087214 -285.619196) (xy 396.136069 -285.625128)
			(xy 396.18334 -285.63882) (xy 396.227802 -285.659918) (xy 396.268305 -285.687874) (xy 396.303798 -285.721966)
			(xy 396.333363 -285.76131) (xy 396.356234 -285.804887) (xy 396.371818 -285.851568) (xy 396.379713 -285.900145)
			(xy 396.380208 -285.924752) (xy 396.719056 -285.924752) (xy 396.723016 -285.875698) (xy 396.734793 -285.827914)
			(xy 396.754084 -285.782638) (xy 396.780387 -285.741042) (xy 396.813022 -285.704205) (xy 396.851143 -285.67308)
			(xy 396.893764 -285.648473) (xy 396.93978 -285.631021) (xy 396.987999 -285.621177) (xy 397.037174 -285.619196)
			(xy 397.086029 -285.625128) (xy 397.1333 -285.63882) (xy 397.177762 -285.659918) (xy 397.218265 -285.687874)
			(xy 397.253758 -285.721966) (xy 397.283323 -285.76131) (xy 397.306194 -285.804887) (xy 397.321778 -285.851568)
			(xy 397.329673 -285.900145) (xy 397.330168 -285.924752) (xy 397.669016 -285.924752) (xy 397.672976 -285.875698)
			(xy 397.684753 -285.827914) (xy 397.704044 -285.782638) (xy 397.730347 -285.741042) (xy 397.762982 -285.704205)
			(xy 397.801103 -285.67308) (xy 397.843724 -285.648473) (xy 397.88974 -285.631021) (xy 397.937959 -285.621177)
			(xy 397.987134 -285.619196) (xy 398.035989 -285.625128) (xy 398.08326 -285.63882) (xy 398.127722 -285.659918)
			(xy 398.168225 -285.687874) (xy 398.203718 -285.721966) (xy 398.233283 -285.76131) (xy 398.256154 -285.804887)
			(xy 398.271738 -285.851568) (xy 398.279633 -285.900145) (xy 398.280128 -285.924752) (xy 398.61923 -285.924752)
			(xy 398.62319 -285.875698) (xy 398.634967 -285.827914) (xy 398.654258 -285.782638) (xy 398.680561 -285.741042)
			(xy 398.713196 -285.704205) (xy 398.751317 -285.67308) (xy 398.793938 -285.648473) (xy 398.839954 -285.631021)
			(xy 398.888173 -285.621177) (xy 398.937348 -285.619196) (xy 398.986203 -285.625128) (xy 399.033474 -285.63882)
			(xy 399.077936 -285.659918) (xy 399.118439 -285.687874) (xy 399.153932 -285.721966) (xy 399.183497 -285.76131)
			(xy 399.206368 -285.804887) (xy 399.221952 -285.851568) (xy 399.229847 -285.900145) (xy 399.230342 -285.924752)
			(xy 399.56919 -285.924752) (xy 399.57315 -285.875698) (xy 399.584927 -285.827914) (xy 399.604218 -285.782638)
			(xy 399.630521 -285.741042) (xy 399.663156 -285.704205) (xy 399.701277 -285.67308) (xy 399.743898 -285.648473)
			(xy 399.789914 -285.631021) (xy 399.838133 -285.621177) (xy 399.887308 -285.619196) (xy 399.936163 -285.625128)
			(xy 399.983434 -285.63882) (xy 400.027896 -285.659918) (xy 400.068399 -285.687874) (xy 400.103892 -285.721966)
			(xy 400.133457 -285.76131) (xy 400.156328 -285.804887) (xy 400.171912 -285.851568) (xy 400.179807 -285.900145)
			(xy 400.180302 -285.924752) (xy 400.51915 -285.924752) (xy 400.52311 -285.875698) (xy 400.534887 -285.827914)
			(xy 400.554178 -285.782638) (xy 400.580481 -285.741042) (xy 400.613116 -285.704205) (xy 400.651237 -285.67308)
			(xy 400.693858 -285.648473) (xy 400.739874 -285.631021) (xy 400.788093 -285.621177) (xy 400.837268 -285.619196)
			(xy 400.886123 -285.625128) (xy 400.933394 -285.63882) (xy 400.977856 -285.659918) (xy 401.018359 -285.687874)
			(xy 401.053852 -285.721966) (xy 401.083417 -285.76131) (xy 401.106288 -285.804887) (xy 401.121872 -285.851568)
			(xy 401.129767 -285.900145) (xy 401.130262 -285.924752) (xy 401.46911 -285.924752) (xy 401.47307 -285.875698)
			(xy 401.484847 -285.827914) (xy 401.504138 -285.782638) (xy 401.530441 -285.741042) (xy 401.563076 -285.704205)
			(xy 401.601197 -285.67308) (xy 401.643818 -285.648473) (xy 401.689834 -285.631021) (xy 401.738053 -285.621177)
			(xy 401.787228 -285.619196) (xy 401.836083 -285.625128) (xy 401.883354 -285.63882) (xy 401.927816 -285.659918)
			(xy 401.968319 -285.687874) (xy 402.003812 -285.721966) (xy 402.033377 -285.76131) (xy 402.056248 -285.804887)
			(xy 402.071832 -285.851568) (xy 402.079727 -285.900145) (xy 402.080222 -285.924752) (xy 402.41907 -285.924752)
			(xy 402.42303 -285.875698) (xy 402.434807 -285.827914) (xy 402.454098 -285.782638) (xy 402.480401 -285.741042)
			(xy 402.513036 -285.704205) (xy 402.551157 -285.67308) (xy 402.593778 -285.648473) (xy 402.639794 -285.631021)
			(xy 402.688013 -285.621177) (xy 402.737188 -285.619196) (xy 402.786043 -285.625128) (xy 402.833314 -285.63882)
			(xy 402.877776 -285.659918) (xy 402.918279 -285.687874) (xy 402.953772 -285.721966) (xy 402.983337 -285.76131)
			(xy 403.006208 -285.804887) (xy 403.021792 -285.851568) (xy 403.029687 -285.900145) (xy 403.030182 -285.924752)
			(xy 403.36903 -285.924752) (xy 403.37299 -285.875698) (xy 403.384767 -285.827914) (xy 403.404058 -285.782638)
			(xy 403.430361 -285.741042) (xy 403.462996 -285.704205) (xy 403.501117 -285.67308) (xy 403.543738 -285.648473)
			(xy 403.589754 -285.631021) (xy 403.637973 -285.621177) (xy 403.687148 -285.619196) (xy 403.736003 -285.625128)
			(xy 403.783274 -285.63882) (xy 403.827736 -285.659918) (xy 403.868239 -285.687874) (xy 403.903732 -285.721966)
			(xy 403.933297 -285.76131) (xy 403.956168 -285.804887) (xy 403.971752 -285.851568) (xy 403.979647 -285.900145)
			(xy 403.980142 -285.924752) (xy 404.31899 -285.924752) (xy 404.32295 -285.875698) (xy 404.334727 -285.827914)
			(xy 404.354018 -285.782638) (xy 404.380321 -285.741042) (xy 404.412956 -285.704205) (xy 404.451077 -285.67308)
			(xy 404.493698 -285.648473) (xy 404.539714 -285.631021) (xy 404.587933 -285.621177) (xy 404.637108 -285.619196)
			(xy 404.685963 -285.625128) (xy 404.733234 -285.63882) (xy 404.777696 -285.659918) (xy 404.818199 -285.687874)
			(xy 404.853692 -285.721966) (xy 404.883257 -285.76131) (xy 404.906128 -285.804887) (xy 404.921712 -285.851568)
			(xy 404.929607 -285.900145) (xy 404.930102 -285.924752) (xy 405.269204 -285.924752) (xy 405.273164 -285.875698)
			(xy 405.284941 -285.827914) (xy 405.304232 -285.782638) (xy 405.330535 -285.741042) (xy 405.36317 -285.704205)
			(xy 405.401291 -285.67308) (xy 405.443912 -285.648473) (xy 405.489928 -285.631021) (xy 405.538147 -285.621177)
			(xy 405.587322 -285.619196) (xy 405.636177 -285.625128) (xy 405.683448 -285.63882) (xy 405.72791 -285.659918)
			(xy 405.768413 -285.687874) (xy 405.803906 -285.721966) (xy 405.833471 -285.76131) (xy 405.856342 -285.804887)
			(xy 405.871926 -285.851568) (xy 405.879821 -285.900145) (xy 405.880316 -285.924752) (xy 406.219164 -285.924752)
			(xy 406.223124 -285.875698) (xy 406.234901 -285.827914) (xy 406.254192 -285.782638) (xy 406.280495 -285.741042)
			(xy 406.31313 -285.704205) (xy 406.351251 -285.67308) (xy 406.393872 -285.648473) (xy 406.439888 -285.631021)
			(xy 406.488107 -285.621177) (xy 406.537282 -285.619196) (xy 406.586137 -285.625128) (xy 406.633408 -285.63882)
			(xy 406.67787 -285.659918) (xy 406.718373 -285.687874) (xy 406.753866 -285.721966) (xy 406.783431 -285.76131)
			(xy 406.806302 -285.804887) (xy 406.821886 -285.851568) (xy 406.829781 -285.900145) (xy 406.830276 -285.924752)
			(xy 408.119084 -285.924752) (xy 408.123044 -285.875698) (xy 408.134821 -285.827914) (xy 408.154112 -285.782638)
			(xy 408.180415 -285.741042) (xy 408.21305 -285.704205) (xy 408.251171 -285.67308) (xy 408.293792 -285.648473)
			(xy 408.339808 -285.631021) (xy 408.388027 -285.621177) (xy 408.437202 -285.619196) (xy 408.486057 -285.625128)
			(xy 408.533328 -285.63882) (xy 408.57779 -285.659918) (xy 408.618293 -285.687874) (xy 408.653786 -285.721966)
			(xy 408.683351 -285.76131) (xy 408.706222 -285.804887) (xy 408.721806 -285.851568) (xy 408.729701 -285.900145)
			(xy 408.730196 -285.924752) (xy 409.069044 -285.924752) (xy 409.073004 -285.875698) (xy 409.084781 -285.827914)
			(xy 409.104072 -285.782638) (xy 409.130375 -285.741042) (xy 409.16301 -285.704205) (xy 409.201131 -285.67308)
			(xy 409.243752 -285.648473) (xy 409.289768 -285.631021) (xy 409.337987 -285.621177) (xy 409.387162 -285.619196)
			(xy 409.436017 -285.625128) (xy 409.483288 -285.63882) (xy 409.52775 -285.659918) (xy 409.568253 -285.687874)
			(xy 409.603746 -285.721966) (xy 409.633311 -285.76131) (xy 409.656182 -285.804887) (xy 409.671766 -285.851568)
			(xy 409.679661 -285.900145) (xy 409.680156 -285.924752) (xy 410.019004 -285.924752) (xy 410.022964 -285.875698)
			(xy 410.034741 -285.827914) (xy 410.054032 -285.782638) (xy 410.080335 -285.741042) (xy 410.11297 -285.704205)
			(xy 410.151091 -285.67308) (xy 410.193712 -285.648473) (xy 410.239728 -285.631021) (xy 410.287947 -285.621177)
			(xy 410.337122 -285.619196) (xy 410.385977 -285.625128) (xy 410.433248 -285.63882) (xy 410.47771 -285.659918)
			(xy 410.518213 -285.687874) (xy 410.553706 -285.721966) (xy 410.583271 -285.76131) (xy 410.606142 -285.804887)
			(xy 410.621726 -285.851568) (xy 410.629621 -285.900145) (xy 410.630116 -285.924752) (xy 410.969218 -285.924752)
			(xy 410.973178 -285.875698) (xy 410.984955 -285.827914) (xy 411.004246 -285.782638) (xy 411.030549 -285.741042)
			(xy 411.063184 -285.704205) (xy 411.101305 -285.67308) (xy 411.143926 -285.648473) (xy 411.189942 -285.631021)
			(xy 411.238161 -285.621177) (xy 411.287336 -285.619196) (xy 411.336191 -285.625128) (xy 411.383462 -285.63882)
			(xy 411.427924 -285.659918) (xy 411.468427 -285.687874) (xy 411.50392 -285.721966) (xy 411.533485 -285.76131)
			(xy 411.556356 -285.804887) (xy 411.57194 -285.851568) (xy 411.579835 -285.900145) (xy 411.58033 -285.924752)
			(xy 411.919178 -285.924752) (xy 411.923138 -285.875698) (xy 411.934915 -285.827914) (xy 411.954206 -285.782638)
			(xy 411.980509 -285.741042) (xy 412.013144 -285.704205) (xy 412.051265 -285.67308) (xy 412.093886 -285.648473)
			(xy 412.139902 -285.631021) (xy 412.188121 -285.621177) (xy 412.237296 -285.619196) (xy 412.286151 -285.625128)
			(xy 412.333422 -285.63882) (xy 412.377884 -285.659918) (xy 412.418387 -285.687874) (xy 412.45388 -285.721966)
			(xy 412.483445 -285.76131) (xy 412.506316 -285.804887) (xy 412.5219 -285.851568) (xy 412.529795 -285.900145)
			(xy 412.53029 -285.924752) (xy 412.869138 -285.924752) (xy 412.873098 -285.875698) (xy 412.884875 -285.827914)
			(xy 412.904166 -285.782638) (xy 412.930469 -285.741042) (xy 412.963104 -285.704205) (xy 413.001225 -285.67308)
			(xy 413.043846 -285.648473) (xy 413.089862 -285.631021) (xy 413.138081 -285.621177) (xy 413.187256 -285.619196)
			(xy 413.236111 -285.625128) (xy 413.283382 -285.63882) (xy 413.327844 -285.659918) (xy 413.368347 -285.687874)
			(xy 413.40384 -285.721966) (xy 413.433405 -285.76131) (xy 413.456276 -285.804887) (xy 413.47186 -285.851568)
			(xy 413.479755 -285.900145) (xy 413.48025 -285.924752) (xy 413.819098 -285.924752) (xy 413.823058 -285.875698)
			(xy 413.834835 -285.827914) (xy 413.854126 -285.782638) (xy 413.880429 -285.741042) (xy 413.913064 -285.704205)
			(xy 413.951185 -285.67308) (xy 413.993806 -285.648473) (xy 414.039822 -285.631021) (xy 414.088041 -285.621177)
			(xy 414.137216 -285.619196) (xy 414.186071 -285.625128) (xy 414.233342 -285.63882) (xy 414.277804 -285.659918)
			(xy 414.318307 -285.687874) (xy 414.3538 -285.721966) (xy 414.383365 -285.76131) (xy 414.406236 -285.804887)
			(xy 414.42182 -285.851568) (xy 414.429715 -285.900145) (xy 414.43021 -285.924752) (xy 414.769058 -285.924752)
			(xy 414.773018 -285.875698) (xy 414.784795 -285.827914) (xy 414.804086 -285.782638) (xy 414.830389 -285.741042)
			(xy 414.863024 -285.704205) (xy 414.901145 -285.67308) (xy 414.943766 -285.648473) (xy 414.989782 -285.631021)
			(xy 415.038001 -285.621177) (xy 415.087176 -285.619196) (xy 415.136031 -285.625128) (xy 415.183302 -285.63882)
			(xy 415.227764 -285.659918) (xy 415.268267 -285.687874) (xy 415.30376 -285.721966) (xy 415.333325 -285.76131)
			(xy 415.356196 -285.804887) (xy 415.37178 -285.851568) (xy 415.379675 -285.900145) (xy 415.38017 -285.924752)
			(xy 415.719018 -285.924752) (xy 415.722978 -285.875698) (xy 415.734755 -285.827914) (xy 415.754046 -285.782638)
			(xy 415.780349 -285.741042) (xy 415.812984 -285.704205) (xy 415.851105 -285.67308) (xy 415.893726 -285.648473)
			(xy 415.939742 -285.631021) (xy 415.987961 -285.621177) (xy 416.037136 -285.619196) (xy 416.085991 -285.625128)
			(xy 416.133262 -285.63882) (xy 416.177724 -285.659918) (xy 416.218227 -285.687874) (xy 416.25372 -285.721966)
			(xy 416.283285 -285.76131) (xy 416.306156 -285.804887) (xy 416.32174 -285.851568) (xy 416.329635 -285.900145)
			(xy 416.33013 -285.924752) (xy 416.668978 -285.924752) (xy 416.672938 -285.875698) (xy 416.684715 -285.827914)
			(xy 416.704006 -285.782638) (xy 416.730309 -285.741042) (xy 416.762944 -285.704205) (xy 416.801065 -285.67308)
			(xy 416.843686 -285.648473) (xy 416.889702 -285.631021) (xy 416.937921 -285.621177) (xy 416.987096 -285.619196)
			(xy 417.035951 -285.625128) (xy 417.083222 -285.63882) (xy 417.127684 -285.659918) (xy 417.168187 -285.687874)
			(xy 417.20368 -285.721966) (xy 417.233245 -285.76131) (xy 417.256116 -285.804887) (xy 417.2717 -285.851568)
			(xy 417.279595 -285.900145) (xy 417.28009 -285.924752) (xy 417.619192 -285.924752) (xy 417.623152 -285.875698)
			(xy 417.634929 -285.827914) (xy 417.65422 -285.782638) (xy 417.680523 -285.741042) (xy 417.713158 -285.704205)
			(xy 417.751279 -285.67308) (xy 417.7939 -285.648473) (xy 417.839916 -285.631021) (xy 417.888135 -285.621177)
			(xy 417.93731 -285.619196) (xy 417.986165 -285.625128) (xy 418.033436 -285.63882) (xy 418.077898 -285.659918)
			(xy 418.118401 -285.687874) (xy 418.153894 -285.721966) (xy 418.183459 -285.76131) (xy 418.20633 -285.804887)
			(xy 418.221914 -285.851568) (xy 418.229809 -285.900145) (xy 418.230304 -285.924752) (xy 418.569152 -285.924752)
			(xy 418.573112 -285.875698) (xy 418.584889 -285.827914) (xy 418.60418 -285.782638) (xy 418.630483 -285.741042)
			(xy 418.663118 -285.704205) (xy 418.701239 -285.67308) (xy 418.74386 -285.648473) (xy 418.789876 -285.631021)
			(xy 418.838095 -285.621177) (xy 418.88727 -285.619196) (xy 418.936125 -285.625128) (xy 418.983396 -285.63882)
			(xy 419.027858 -285.659918) (xy 419.068361 -285.687874) (xy 419.103854 -285.721966) (xy 419.133419 -285.76131)
			(xy 419.15629 -285.804887) (xy 419.171874 -285.851568) (xy 419.179769 -285.900145) (xy 419.180264 -285.924752)
			(xy 419.179769 -285.949359) (xy 419.171874 -285.997936) (xy 419.15629 -286.044617) (xy 419.133419 -286.088194)
			(xy 419.103854 -286.127538) (xy 419.068361 -286.16163) (xy 419.027858 -286.189586) (xy 418.983396 -286.210684)
			(xy 418.936125 -286.224376) (xy 418.88727 -286.230308) (xy 418.838095 -286.228327) (xy 418.789876 -286.218483)
			(xy 418.74386 -286.201031) (xy 418.701239 -286.176424) (xy 418.663118 -286.145299) (xy 418.630483 -286.108462)
			(xy 418.60418 -286.066866) (xy 418.584889 -286.02159) (xy 418.573112 -285.973806) (xy 418.569152 -285.924752)
			(xy 418.230304 -285.924752) (xy 418.229809 -285.949359) (xy 418.221914 -285.997936) (xy 418.20633 -286.044617)
			(xy 418.183459 -286.088194) (xy 418.153894 -286.127538) (xy 418.118401 -286.16163) (xy 418.077898 -286.189586)
			(xy 418.033436 -286.210684) (xy 417.986165 -286.224376) (xy 417.93731 -286.230308) (xy 417.888135 -286.228327)
			(xy 417.839916 -286.218483) (xy 417.7939 -286.201031) (xy 417.751279 -286.176424) (xy 417.713158 -286.145299)
			(xy 417.680523 -286.108462) (xy 417.65422 -286.066866) (xy 417.634929 -286.02159) (xy 417.623152 -285.973806)
			(xy 417.619192 -285.924752) (xy 417.28009 -285.924752) (xy 417.279595 -285.949359) (xy 417.2717 -285.997936)
			(xy 417.256116 -286.044617) (xy 417.233245 -286.088194) (xy 417.20368 -286.127538) (xy 417.168187 -286.16163)
			(xy 417.127684 -286.189586) (xy 417.083222 -286.210684) (xy 417.035951 -286.224376) (xy 416.987096 -286.230308)
			(xy 416.937921 -286.228327) (xy 416.889702 -286.218483) (xy 416.843686 -286.201031) (xy 416.801065 -286.176424)
			(xy 416.762944 -286.145299) (xy 416.730309 -286.108462) (xy 416.704006 -286.066866) (xy 416.684715 -286.02159)
			(xy 416.672938 -285.973806) (xy 416.668978 -285.924752) (xy 416.33013 -285.924752) (xy 416.329635 -285.949359)
			(xy 416.32174 -285.997936) (xy 416.306156 -286.044617) (xy 416.283285 -286.088194) (xy 416.25372 -286.127538)
			(xy 416.218227 -286.16163) (xy 416.177724 -286.189586) (xy 416.133262 -286.210684) (xy 416.085991 -286.224376)
			(xy 416.037136 -286.230308) (xy 415.987961 -286.228327) (xy 415.939742 -286.218483) (xy 415.893726 -286.201031)
			(xy 415.851105 -286.176424) (xy 415.812984 -286.145299) (xy 415.780349 -286.108462) (xy 415.754046 -286.066866)
			(xy 415.734755 -286.02159) (xy 415.722978 -285.973806) (xy 415.719018 -285.924752) (xy 415.38017 -285.924752)
			(xy 415.379675 -285.949359) (xy 415.37178 -285.997936) (xy 415.356196 -286.044617) (xy 415.333325 -286.088194)
			(xy 415.30376 -286.127538) (xy 415.268267 -286.16163) (xy 415.227764 -286.189586) (xy 415.183302 -286.210684)
			(xy 415.136031 -286.224376) (xy 415.087176 -286.230308) (xy 415.038001 -286.228327) (xy 414.989782 -286.218483)
			(xy 414.943766 -286.201031) (xy 414.901145 -286.176424) (xy 414.863024 -286.145299) (xy 414.830389 -286.108462)
			(xy 414.804086 -286.066866) (xy 414.784795 -286.02159) (xy 414.773018 -285.973806) (xy 414.769058 -285.924752)
			(xy 414.43021 -285.924752) (xy 414.429715 -285.949359) (xy 414.42182 -285.997936) (xy 414.406236 -286.044617)
			(xy 414.383365 -286.088194) (xy 414.3538 -286.127538) (xy 414.318307 -286.16163) (xy 414.277804 -286.189586)
			(xy 414.233342 -286.210684) (xy 414.186071 -286.224376) (xy 414.137216 -286.230308) (xy 414.088041 -286.228327)
			(xy 414.039822 -286.218483) (xy 413.993806 -286.201031) (xy 413.951185 -286.176424) (xy 413.913064 -286.145299)
			(xy 413.880429 -286.108462) (xy 413.854126 -286.066866) (xy 413.834835 -286.02159) (xy 413.823058 -285.973806)
			(xy 413.819098 -285.924752) (xy 413.48025 -285.924752) (xy 413.479755 -285.949359) (xy 413.47186 -285.997936)
			(xy 413.456276 -286.044617) (xy 413.433405 -286.088194) (xy 413.40384 -286.127538) (xy 413.368347 -286.16163)
			(xy 413.327844 -286.189586) (xy 413.283382 -286.210684) (xy 413.236111 -286.224376) (xy 413.187256 -286.230308)
			(xy 413.138081 -286.228327) (xy 413.089862 -286.218483) (xy 413.043846 -286.201031) (xy 413.001225 -286.176424)
			(xy 412.963104 -286.145299) (xy 412.930469 -286.108462) (xy 412.904166 -286.066866) (xy 412.884875 -286.02159)
			(xy 412.873098 -285.973806) (xy 412.869138 -285.924752) (xy 412.53029 -285.924752) (xy 412.529795 -285.949359)
			(xy 412.5219 -285.997936) (xy 412.506316 -286.044617) (xy 412.483445 -286.088194) (xy 412.45388 -286.127538)
			(xy 412.418387 -286.16163) (xy 412.377884 -286.189586) (xy 412.333422 -286.210684) (xy 412.286151 -286.224376)
			(xy 412.237296 -286.230308) (xy 412.188121 -286.228327) (xy 412.139902 -286.218483) (xy 412.093886 -286.201031)
			(xy 412.051265 -286.176424) (xy 412.013144 -286.145299) (xy 411.980509 -286.108462) (xy 411.954206 -286.066866)
			(xy 411.934915 -286.02159) (xy 411.923138 -285.973806) (xy 411.919178 -285.924752) (xy 411.58033 -285.924752)
			(xy 411.579835 -285.949359) (xy 411.57194 -285.997936) (xy 411.556356 -286.044617) (xy 411.533485 -286.088194)
			(xy 411.50392 -286.127538) (xy 411.468427 -286.16163) (xy 411.427924 -286.189586) (xy 411.383462 -286.210684)
			(xy 411.336191 -286.224376) (xy 411.287336 -286.230308) (xy 411.238161 -286.228327) (xy 411.189942 -286.218483)
			(xy 411.143926 -286.201031) (xy 411.101305 -286.176424) (xy 411.063184 -286.145299) (xy 411.030549 -286.108462)
			(xy 411.004246 -286.066866) (xy 410.984955 -286.02159) (xy 410.973178 -285.973806) (xy 410.969218 -285.924752)
			(xy 410.630116 -285.924752) (xy 410.629621 -285.949359) (xy 410.621726 -285.997936) (xy 410.606142 -286.044617)
			(xy 410.583271 -286.088194) (xy 410.553706 -286.127538) (xy 410.518213 -286.16163) (xy 410.47771 -286.189586)
			(xy 410.433248 -286.210684) (xy 410.385977 -286.224376) (xy 410.337122 -286.230308) (xy 410.287947 -286.228327)
			(xy 410.239728 -286.218483) (xy 410.193712 -286.201031) (xy 410.151091 -286.176424) (xy 410.11297 -286.145299)
			(xy 410.080335 -286.108462) (xy 410.054032 -286.066866) (xy 410.034741 -286.02159) (xy 410.022964 -285.973806)
			(xy 410.019004 -285.924752) (xy 409.680156 -285.924752) (xy 409.679661 -285.949359) (xy 409.671766 -285.997936)
			(xy 409.656182 -286.044617) (xy 409.633311 -286.088194) (xy 409.603746 -286.127538) (xy 409.568253 -286.16163)
			(xy 409.52775 -286.189586) (xy 409.483288 -286.210684) (xy 409.436017 -286.224376) (xy 409.387162 -286.230308)
			(xy 409.337987 -286.228327) (xy 409.289768 -286.218483) (xy 409.243752 -286.201031) (xy 409.201131 -286.176424)
			(xy 409.16301 -286.145299) (xy 409.130375 -286.108462) (xy 409.104072 -286.066866) (xy 409.084781 -286.02159)
			(xy 409.073004 -285.973806) (xy 409.069044 -285.924752) (xy 408.730196 -285.924752) (xy 408.729701 -285.949359)
			(xy 408.721806 -285.997936) (xy 408.706222 -286.044617) (xy 408.683351 -286.088194) (xy 408.653786 -286.127538)
			(xy 408.618293 -286.16163) (xy 408.57779 -286.189586) (xy 408.533328 -286.210684) (xy 408.486057 -286.224376)
			(xy 408.437202 -286.230308) (xy 408.388027 -286.228327) (xy 408.339808 -286.218483) (xy 408.293792 -286.201031)
			(xy 408.251171 -286.176424) (xy 408.21305 -286.145299) (xy 408.180415 -286.108462) (xy 408.154112 -286.066866)
			(xy 408.134821 -286.02159) (xy 408.123044 -285.973806) (xy 408.119084 -285.924752) (xy 406.830276 -285.924752)
			(xy 406.829781 -285.949359) (xy 406.821886 -285.997936) (xy 406.806302 -286.044617) (xy 406.783431 -286.088194)
			(xy 406.753866 -286.127538) (xy 406.718373 -286.16163) (xy 406.67787 -286.189586) (xy 406.633408 -286.210684)
			(xy 406.586137 -286.224376) (xy 406.537282 -286.230308) (xy 406.488107 -286.228327) (xy 406.439888 -286.218483)
			(xy 406.393872 -286.201031) (xy 406.351251 -286.176424) (xy 406.31313 -286.145299) (xy 406.280495 -286.108462)
			(xy 406.254192 -286.066866) (xy 406.234901 -286.02159) (xy 406.223124 -285.973806) (xy 406.219164 -285.924752)
			(xy 405.880316 -285.924752) (xy 405.879821 -285.949359) (xy 405.871926 -285.997936) (xy 405.856342 -286.044617)
			(xy 405.833471 -286.088194) (xy 405.803906 -286.127538) (xy 405.768413 -286.16163) (xy 405.72791 -286.189586)
			(xy 405.683448 -286.210684) (xy 405.636177 -286.224376) (xy 405.587322 -286.230308) (xy 405.538147 -286.228327)
			(xy 405.489928 -286.218483) (xy 405.443912 -286.201031) (xy 405.401291 -286.176424) (xy 405.36317 -286.145299)
			(xy 405.330535 -286.108462) (xy 405.304232 -286.066866) (xy 405.284941 -286.02159) (xy 405.273164 -285.973806)
			(xy 405.269204 -285.924752) (xy 404.930102 -285.924752) (xy 404.929607 -285.949359) (xy 404.921712 -285.997936)
			(xy 404.906128 -286.044617) (xy 404.883257 -286.088194) (xy 404.853692 -286.127538) (xy 404.818199 -286.16163)
			(xy 404.777696 -286.189586) (xy 404.733234 -286.210684) (xy 404.685963 -286.224376) (xy 404.637108 -286.230308)
			(xy 404.587933 -286.228327) (xy 404.539714 -286.218483) (xy 404.493698 -286.201031) (xy 404.451077 -286.176424)
			(xy 404.412956 -286.145299) (xy 404.380321 -286.108462) (xy 404.354018 -286.066866) (xy 404.334727 -286.02159)
			(xy 404.32295 -285.973806) (xy 404.31899 -285.924752) (xy 403.980142 -285.924752) (xy 403.979647 -285.949359)
			(xy 403.971752 -285.997936) (xy 403.956168 -286.044617) (xy 403.933297 -286.088194) (xy 403.903732 -286.127538)
			(xy 403.868239 -286.16163) (xy 403.827736 -286.189586) (xy 403.783274 -286.210684) (xy 403.736003 -286.224376)
			(xy 403.687148 -286.230308) (xy 403.637973 -286.228327) (xy 403.589754 -286.218483) (xy 403.543738 -286.201031)
			(xy 403.501117 -286.176424) (xy 403.462996 -286.145299) (xy 403.430361 -286.108462) (xy 403.404058 -286.066866)
			(xy 403.384767 -286.02159) (xy 403.37299 -285.973806) (xy 403.36903 -285.924752) (xy 403.030182 -285.924752)
			(xy 403.029687 -285.949359) (xy 403.021792 -285.997936) (xy 403.006208 -286.044617) (xy 402.983337 -286.088194)
			(xy 402.953772 -286.127538) (xy 402.918279 -286.16163) (xy 402.877776 -286.189586) (xy 402.833314 -286.210684)
			(xy 402.786043 -286.224376) (xy 402.737188 -286.230308) (xy 402.688013 -286.228327) (xy 402.639794 -286.218483)
			(xy 402.593778 -286.201031) (xy 402.551157 -286.176424) (xy 402.513036 -286.145299) (xy 402.480401 -286.108462)
			(xy 402.454098 -286.066866) (xy 402.434807 -286.02159) (xy 402.42303 -285.973806) (xy 402.41907 -285.924752)
			(xy 402.080222 -285.924752) (xy 402.079727 -285.949359) (xy 402.071832 -285.997936) (xy 402.056248 -286.044617)
			(xy 402.033377 -286.088194) (xy 402.003812 -286.127538) (xy 401.968319 -286.16163) (xy 401.927816 -286.189586)
			(xy 401.883354 -286.210684) (xy 401.836083 -286.224376) (xy 401.787228 -286.230308) (xy 401.738053 -286.228327)
			(xy 401.689834 -286.218483) (xy 401.643818 -286.201031) (xy 401.601197 -286.176424) (xy 401.563076 -286.145299)
			(xy 401.530441 -286.108462) (xy 401.504138 -286.066866) (xy 401.484847 -286.02159) (xy 401.47307 -285.973806)
			(xy 401.46911 -285.924752) (xy 401.130262 -285.924752) (xy 401.129767 -285.949359) (xy 401.121872 -285.997936)
			(xy 401.106288 -286.044617) (xy 401.083417 -286.088194) (xy 401.053852 -286.127538) (xy 401.018359 -286.16163)
			(xy 400.977856 -286.189586) (xy 400.933394 -286.210684) (xy 400.886123 -286.224376) (xy 400.837268 -286.230308)
			(xy 400.788093 -286.228327) (xy 400.739874 -286.218483) (xy 400.693858 -286.201031) (xy 400.651237 -286.176424)
			(xy 400.613116 -286.145299) (xy 400.580481 -286.108462) (xy 400.554178 -286.066866) (xy 400.534887 -286.02159)
			(xy 400.52311 -285.973806) (xy 400.51915 -285.924752) (xy 400.180302 -285.924752) (xy 400.179807 -285.949359)
			(xy 400.171912 -285.997936) (xy 400.156328 -286.044617) (xy 400.133457 -286.088194) (xy 400.103892 -286.127538)
			(xy 400.068399 -286.16163) (xy 400.027896 -286.189586) (xy 399.983434 -286.210684) (xy 399.936163 -286.224376)
			(xy 399.887308 -286.230308) (xy 399.838133 -286.228327) (xy 399.789914 -286.218483) (xy 399.743898 -286.201031)
			(xy 399.701277 -286.176424) (xy 399.663156 -286.145299) (xy 399.630521 -286.108462) (xy 399.604218 -286.066866)
			(xy 399.584927 -286.02159) (xy 399.57315 -285.973806) (xy 399.56919 -285.924752) (xy 399.230342 -285.924752)
			(xy 399.229847 -285.949359) (xy 399.221952 -285.997936) (xy 399.206368 -286.044617) (xy 399.183497 -286.088194)
			(xy 399.153932 -286.127538) (xy 399.118439 -286.16163) (xy 399.077936 -286.189586) (xy 399.033474 -286.210684)
			(xy 398.986203 -286.224376) (xy 398.937348 -286.230308) (xy 398.888173 -286.228327) (xy 398.839954 -286.218483)
			(xy 398.793938 -286.201031) (xy 398.751317 -286.176424) (xy 398.713196 -286.145299) (xy 398.680561 -286.108462)
			(xy 398.654258 -286.066866) (xy 398.634967 -286.02159) (xy 398.62319 -285.973806) (xy 398.61923 -285.924752)
			(xy 398.280128 -285.924752) (xy 398.279633 -285.949359) (xy 398.271738 -285.997936) (xy 398.256154 -286.044617)
			(xy 398.233283 -286.088194) (xy 398.203718 -286.127538) (xy 398.168225 -286.16163) (xy 398.127722 -286.189586)
			(xy 398.08326 -286.210684) (xy 398.035989 -286.224376) (xy 397.987134 -286.230308) (xy 397.937959 -286.228327)
			(xy 397.88974 -286.218483) (xy 397.843724 -286.201031) (xy 397.801103 -286.176424) (xy 397.762982 -286.145299)
			(xy 397.730347 -286.108462) (xy 397.704044 -286.066866) (xy 397.684753 -286.02159) (xy 397.672976 -285.973806)
			(xy 397.669016 -285.924752) (xy 397.330168 -285.924752) (xy 397.329673 -285.949359) (xy 397.321778 -285.997936)
			(xy 397.306194 -286.044617) (xy 397.283323 -286.088194) (xy 397.253758 -286.127538) (xy 397.218265 -286.16163)
			(xy 397.177762 -286.189586) (xy 397.1333 -286.210684) (xy 397.086029 -286.224376) (xy 397.037174 -286.230308)
			(xy 396.987999 -286.228327) (xy 396.93978 -286.218483) (xy 396.893764 -286.201031) (xy 396.851143 -286.176424)
			(xy 396.813022 -286.145299) (xy 396.780387 -286.108462) (xy 396.754084 -286.066866) (xy 396.734793 -286.02159)
			(xy 396.723016 -285.973806) (xy 396.719056 -285.924752) (xy 396.380208 -285.924752) (xy 396.379713 -285.949359)
			(xy 396.371818 -285.997936) (xy 396.356234 -286.044617) (xy 396.333363 -286.088194) (xy 396.303798 -286.127538)
			(xy 396.268305 -286.16163) (xy 396.227802 -286.189586) (xy 396.18334 -286.210684) (xy 396.136069 -286.224376)
			(xy 396.087214 -286.230308) (xy 396.038039 -286.228327) (xy 395.98982 -286.218483) (xy 395.943804 -286.201031)
			(xy 395.901183 -286.176424) (xy 395.863062 -286.145299) (xy 395.830427 -286.108462) (xy 395.804124 -286.066866)
			(xy 395.784833 -286.02159) (xy 395.773056 -285.973806) (xy 395.769096 -285.924752) (xy 395.430248 -285.924752)
			(xy 395.429753 -285.949359) (xy 395.421858 -285.997936) (xy 395.406274 -286.044617) (xy 395.383403 -286.088194)
			(xy 395.353838 -286.127538) (xy 395.318345 -286.16163) (xy 395.277842 -286.189586) (xy 395.23338 -286.210684)
			(xy 395.186109 -286.224376) (xy 395.137254 -286.230308) (xy 395.088079 -286.228327) (xy 395.03986 -286.218483)
			(xy 394.993844 -286.201031) (xy 394.951223 -286.176424) (xy 394.913102 -286.145299) (xy 394.880467 -286.108462)
			(xy 394.854164 -286.066866) (xy 394.834873 -286.02159) (xy 394.823096 -285.973806) (xy 394.819136 -285.924752)
			(xy 394.480288 -285.924752) (xy 394.479793 -285.949359) (xy 394.471898 -285.997936) (xy 394.456314 -286.044617)
			(xy 394.433443 -286.088194) (xy 394.403878 -286.127538) (xy 394.368385 -286.16163) (xy 394.327882 -286.189586)
			(xy 394.28342 -286.210684) (xy 394.236149 -286.224376) (xy 394.187294 -286.230308) (xy 394.138119 -286.228327)
			(xy 394.0899 -286.218483) (xy 394.043884 -286.201031) (xy 394.001263 -286.176424) (xy 393.963142 -286.145299)
			(xy 393.930507 -286.108462) (xy 393.904204 -286.066866) (xy 393.884913 -286.02159) (xy 393.873136 -285.973806)
			(xy 393.869176 -285.924752) (xy 393.530328 -285.924752) (xy 393.529833 -285.949359) (xy 393.521938 -285.997936)
			(xy 393.506354 -286.044617) (xy 393.483483 -286.088194) (xy 393.453918 -286.127538) (xy 393.418425 -286.16163)
			(xy 393.377922 -286.189586) (xy 393.33346 -286.210684) (xy 393.286189 -286.224376) (xy 393.237334 -286.230308)
			(xy 393.188159 -286.228327) (xy 393.13994 -286.218483) (xy 393.093924 -286.201031) (xy 393.051303 -286.176424)
			(xy 393.013182 -286.145299) (xy 392.980547 -286.108462) (xy 392.954244 -286.066866) (xy 392.934953 -286.02159)
			(xy 392.923176 -285.973806) (xy 392.919216 -285.924752) (xy 389.730234 -285.924752) (xy 389.729739 -285.949359)
			(xy 389.721844 -285.997936) (xy 389.70626 -286.044617) (xy 389.683389 -286.088194) (xy 389.653824 -286.127538)
			(xy 389.618331 -286.16163) (xy 389.577828 -286.189586) (xy 389.533366 -286.210684) (xy 389.486095 -286.224376)
			(xy 389.43724 -286.230308) (xy 389.388065 -286.228327) (xy 389.339846 -286.218483) (xy 389.29383 -286.201031)
			(xy 389.251209 -286.176424) (xy 389.213088 -286.145299) (xy 389.180453 -286.108462) (xy 389.15415 -286.066866)
			(xy 389.134859 -286.02159) (xy 389.123082 -285.973806) (xy 389.119122 -285.924752) (xy 388.780274 -285.924752)
			(xy 388.779779 -285.949359) (xy 388.771884 -285.997936) (xy 388.7563 -286.044617) (xy 388.733429 -286.088194)
			(xy 388.703864 -286.127538) (xy 388.668371 -286.16163) (xy 388.627868 -286.189586) (xy 388.583406 -286.210684)
			(xy 388.536135 -286.224376) (xy 388.48728 -286.230308) (xy 388.438105 -286.228327) (xy 388.389886 -286.218483)
			(xy 388.34387 -286.201031) (xy 388.301249 -286.176424) (xy 388.263128 -286.145299) (xy 388.230493 -286.108462)
			(xy 388.20419 -286.066866) (xy 388.184899 -286.02159) (xy 388.173122 -285.973806) (xy 388.169162 -285.924752)
			(xy 387.830314 -285.924752) (xy 387.829819 -285.949359) (xy 387.821924 -285.997936) (xy 387.80634 -286.044617)
			(xy 387.783469 -286.088194) (xy 387.753904 -286.127538) (xy 387.718411 -286.16163) (xy 387.677908 -286.189586)
			(xy 387.633446 -286.210684) (xy 387.586175 -286.224376) (xy 387.53732 -286.230308) (xy 387.488145 -286.228327)
			(xy 387.439926 -286.218483) (xy 387.39391 -286.201031) (xy 387.351289 -286.176424) (xy 387.313168 -286.145299)
			(xy 387.280533 -286.108462) (xy 387.25423 -286.066866) (xy 387.234939 -286.02159) (xy 387.223162 -285.973806)
			(xy 387.219202 -285.924752) (xy 386.880354 -285.924752) (xy 386.879859 -285.949359) (xy 386.871964 -285.997936)
			(xy 386.85638 -286.044617) (xy 386.833509 -286.088194) (xy 386.803944 -286.127538) (xy 386.768451 -286.16163)
			(xy 386.727948 -286.189586) (xy 386.683486 -286.210684) (xy 386.636215 -286.224376) (xy 386.58736 -286.230308)
			(xy 386.538185 -286.228327) (xy 386.489966 -286.218483) (xy 386.44395 -286.201031) (xy 386.401329 -286.176424)
			(xy 386.363208 -286.145299) (xy 386.330573 -286.108462) (xy 386.30427 -286.066866) (xy 386.284979 -286.02159)
			(xy 386.273202 -285.973806) (xy 386.269242 -285.924752) (xy 385.93014 -285.924752) (xy 385.929645 -285.949359)
			(xy 385.92175 -285.997936) (xy 385.906166 -286.044617) (xy 385.883295 -286.088194) (xy 385.85373 -286.127538)
			(xy 385.818237 -286.16163) (xy 385.777734 -286.189586) (xy 385.733272 -286.210684) (xy 385.686001 -286.224376)
			(xy 385.637146 -286.230308) (xy 385.587971 -286.228327) (xy 385.539752 -286.218483) (xy 385.493736 -286.201031)
			(xy 385.451115 -286.176424) (xy 385.412994 -286.145299) (xy 385.380359 -286.108462) (xy 385.354056 -286.066866)
			(xy 385.334765 -286.02159) (xy 385.322988 -285.973806) (xy 385.319028 -285.924752) (xy 384.98018 -285.924752)
			(xy 384.979685 -285.949359) (xy 384.97179 -285.997936) (xy 384.956206 -286.044617) (xy 384.933335 -286.088194)
			(xy 384.90377 -286.127538) (xy 384.868277 -286.16163) (xy 384.827774 -286.189586) (xy 384.783312 -286.210684)
			(xy 384.736041 -286.224376) (xy 384.687186 -286.230308) (xy 384.638011 -286.228327) (xy 384.589792 -286.218483)
			(xy 384.543776 -286.201031) (xy 384.501155 -286.176424) (xy 384.463034 -286.145299) (xy 384.430399 -286.108462)
			(xy 384.404096 -286.066866) (xy 384.384805 -286.02159) (xy 384.373028 -285.973806) (xy 384.369068 -285.924752)
			(xy 384.2512 -285.924752) (xy 384.2512 -286.874966) (xy 384.369068 -286.874966) (xy 384.373028 -286.825912)
			(xy 384.384805 -286.778128) (xy 384.404096 -286.732852) (xy 384.430399 -286.691256) (xy 384.463034 -286.654419)
			(xy 384.501155 -286.623294) (xy 384.543776 -286.598687) (xy 384.589792 -286.581235) (xy 384.638011 -286.571391)
			(xy 384.687186 -286.56941) (xy 384.736041 -286.575342) (xy 384.783312 -286.589034) (xy 384.827774 -286.610132)
			(xy 384.868277 -286.638088) (xy 384.90377 -286.67218) (xy 384.933335 -286.711524) (xy 384.956206 -286.755101)
			(xy 384.97179 -286.801782) (xy 384.979685 -286.850359) (xy 384.98018 -286.874966) (xy 385.319028 -286.874966)
			(xy 385.322988 -286.825912) (xy 385.334765 -286.778128) (xy 385.354056 -286.732852) (xy 385.380359 -286.691256)
			(xy 385.412994 -286.654419) (xy 385.451115 -286.623294) (xy 385.493736 -286.598687) (xy 385.539752 -286.581235)
			(xy 385.587971 -286.571391) (xy 385.637146 -286.56941) (xy 385.686001 -286.575342) (xy 385.733272 -286.589034)
			(xy 385.777734 -286.610132) (xy 385.818237 -286.638088) (xy 385.85373 -286.67218) (xy 385.883295 -286.711524)
			(xy 385.906166 -286.755101) (xy 385.92175 -286.801782) (xy 385.929645 -286.850359) (xy 385.93014 -286.874966)
			(xy 386.269242 -286.874966) (xy 386.273202 -286.825912) (xy 386.284979 -286.778128) (xy 386.30427 -286.732852)
			(xy 386.330573 -286.691256) (xy 386.363208 -286.654419) (xy 386.401329 -286.623294) (xy 386.44395 -286.598687)
			(xy 386.489966 -286.581235) (xy 386.538185 -286.571391) (xy 386.58736 -286.56941) (xy 386.636215 -286.575342)
			(xy 386.683486 -286.589034) (xy 386.727948 -286.610132) (xy 386.768451 -286.638088) (xy 386.803944 -286.67218)
			(xy 386.833509 -286.711524) (xy 386.85638 -286.755101) (xy 386.871964 -286.801782) (xy 386.879859 -286.850359)
			(xy 386.880354 -286.874966) (xy 387.219202 -286.874966) (xy 387.223162 -286.825912) (xy 387.234939 -286.778128)
			(xy 387.25423 -286.732852) (xy 387.280533 -286.691256) (xy 387.313168 -286.654419) (xy 387.351289 -286.623294)
			(xy 387.39391 -286.598687) (xy 387.439926 -286.581235) (xy 387.488145 -286.571391) (xy 387.53732 -286.56941)
			(xy 387.586175 -286.575342) (xy 387.633446 -286.589034) (xy 387.677908 -286.610132) (xy 387.718411 -286.638088)
			(xy 387.753904 -286.67218) (xy 387.783469 -286.711524) (xy 387.80634 -286.755101) (xy 387.821924 -286.801782)
			(xy 387.829819 -286.850359) (xy 387.830314 -286.874966) (xy 388.169162 -286.874966) (xy 388.173122 -286.825912)
			(xy 388.184899 -286.778128) (xy 388.20419 -286.732852) (xy 388.230493 -286.691256) (xy 388.263128 -286.654419)
			(xy 388.301249 -286.623294) (xy 388.34387 -286.598687) (xy 388.389886 -286.581235) (xy 388.438105 -286.571391)
			(xy 388.48728 -286.56941) (xy 388.536135 -286.575342) (xy 388.583406 -286.589034) (xy 388.627868 -286.610132)
			(xy 388.668371 -286.638088) (xy 388.703864 -286.67218) (xy 388.733429 -286.711524) (xy 388.7563 -286.755101)
			(xy 388.771884 -286.801782) (xy 388.779779 -286.850359) (xy 388.780274 -286.874966) (xy 389.119122 -286.874966)
			(xy 389.123082 -286.825912) (xy 389.134859 -286.778128) (xy 389.15415 -286.732852) (xy 389.180453 -286.691256)
			(xy 389.213088 -286.654419) (xy 389.251209 -286.623294) (xy 389.29383 -286.598687) (xy 389.339846 -286.581235)
			(xy 389.388065 -286.571391) (xy 389.43724 -286.56941) (xy 389.486095 -286.575342) (xy 389.533366 -286.589034)
			(xy 389.577828 -286.610132) (xy 389.618331 -286.638088) (xy 389.653824 -286.67218) (xy 389.683389 -286.711524)
			(xy 389.70626 -286.755101) (xy 389.721844 -286.801782) (xy 389.729739 -286.850359) (xy 389.730234 -286.874966)
			(xy 390.069082 -286.874966) (xy 390.073042 -286.825912) (xy 390.084819 -286.778128) (xy 390.10411 -286.732852)
			(xy 390.130413 -286.691256) (xy 390.163048 -286.654419) (xy 390.201169 -286.623294) (xy 390.24379 -286.598687)
			(xy 390.289806 -286.581235) (xy 390.338025 -286.571391) (xy 390.3872 -286.56941) (xy 390.436055 -286.575342)
			(xy 390.483326 -286.589034) (xy 390.527788 -286.610132) (xy 390.568291 -286.638088) (xy 390.603784 -286.67218)
			(xy 390.633349 -286.711524) (xy 390.65622 -286.755101) (xy 390.671804 -286.801782) (xy 390.679699 -286.850359)
			(xy 390.680189 -286.874712) (xy 391.019042 -286.874712) (xy 391.023002 -286.825658) (xy 391.034779 -286.777874)
			(xy 391.05407 -286.732598) (xy 391.080373 -286.691002) (xy 391.113008 -286.654165) (xy 391.151129 -286.62304)
			(xy 391.19375 -286.598433) (xy 391.239766 -286.580981) (xy 391.287985 -286.571137) (xy 391.33716 -286.569156)
			(xy 391.386015 -286.575088) (xy 391.433286 -286.58878) (xy 391.477748 -286.609878) (xy 391.518251 -286.637834)
			(xy 391.553744 -286.671926) (xy 391.583309 -286.71127) (xy 391.60618 -286.754847) (xy 391.621764 -286.801528)
			(xy 391.629659 -286.850105) (xy 391.630154 -286.874712) (xy 391.969002 -286.874712) (xy 391.972962 -286.825658)
			(xy 391.984739 -286.777874) (xy 392.00403 -286.732598) (xy 392.030333 -286.691002) (xy 392.062968 -286.654165)
			(xy 392.101089 -286.62304) (xy 392.14371 -286.598433) (xy 392.189726 -286.580981) (xy 392.237945 -286.571137)
			(xy 392.28712 -286.569156) (xy 392.335975 -286.575088) (xy 392.383246 -286.58878) (xy 392.427708 -286.609878)
			(xy 392.468211 -286.637834) (xy 392.503704 -286.671926) (xy 392.533269 -286.71127) (xy 392.55614 -286.754847)
			(xy 392.571724 -286.801528) (xy 392.579619 -286.850105) (xy 392.580114 -286.874712) (xy 392.580109 -286.874966)
			(xy 392.919216 -286.874966) (xy 392.923176 -286.825912) (xy 392.934953 -286.778128) (xy 392.954244 -286.732852)
			(xy 392.980547 -286.691256) (xy 393.013182 -286.654419) (xy 393.051303 -286.623294) (xy 393.093924 -286.598687)
			(xy 393.13994 -286.581235) (xy 393.188159 -286.571391) (xy 393.237334 -286.56941) (xy 393.286189 -286.575342)
			(xy 393.33346 -286.589034) (xy 393.377922 -286.610132) (xy 393.418425 -286.638088) (xy 393.453918 -286.67218)
			(xy 393.483483 -286.711524) (xy 393.506354 -286.755101) (xy 393.521938 -286.801782) (xy 393.529833 -286.850359)
			(xy 393.530328 -286.874966) (xy 393.869176 -286.874966) (xy 393.873136 -286.825912) (xy 393.884913 -286.778128)
			(xy 393.904204 -286.732852) (xy 393.930507 -286.691256) (xy 393.963142 -286.654419) (xy 394.001263 -286.623294)
			(xy 394.043884 -286.598687) (xy 394.0899 -286.581235) (xy 394.138119 -286.571391) (xy 394.187294 -286.56941)
			(xy 394.236149 -286.575342) (xy 394.28342 -286.589034) (xy 394.327882 -286.610132) (xy 394.368385 -286.638088)
			(xy 394.403878 -286.67218) (xy 394.433443 -286.711524) (xy 394.456314 -286.755101) (xy 394.471898 -286.801782)
			(xy 394.479793 -286.850359) (xy 394.480288 -286.874966) (xy 394.819136 -286.874966) (xy 394.823096 -286.825912)
			(xy 394.834873 -286.778128) (xy 394.854164 -286.732852) (xy 394.880467 -286.691256) (xy 394.913102 -286.654419)
			(xy 394.951223 -286.623294) (xy 394.993844 -286.598687) (xy 395.03986 -286.581235) (xy 395.088079 -286.571391)
			(xy 395.137254 -286.56941) (xy 395.186109 -286.575342) (xy 395.23338 -286.589034) (xy 395.277842 -286.610132)
			(xy 395.318345 -286.638088) (xy 395.353838 -286.67218) (xy 395.383403 -286.711524) (xy 395.406274 -286.755101)
			(xy 395.421858 -286.801782) (xy 395.429753 -286.850359) (xy 395.430248 -286.874966) (xy 395.769096 -286.874966)
			(xy 395.773056 -286.825912) (xy 395.784833 -286.778128) (xy 395.804124 -286.732852) (xy 395.830427 -286.691256)
			(xy 395.863062 -286.654419) (xy 395.901183 -286.623294) (xy 395.943804 -286.598687) (xy 395.98982 -286.581235)
			(xy 396.038039 -286.571391) (xy 396.087214 -286.56941) (xy 396.136069 -286.575342) (xy 396.18334 -286.589034)
			(xy 396.227802 -286.610132) (xy 396.268305 -286.638088) (xy 396.303798 -286.67218) (xy 396.333363 -286.711524)
			(xy 396.356234 -286.755101) (xy 396.371818 -286.801782) (xy 396.379713 -286.850359) (xy 396.380208 -286.874966)
			(xy 396.719056 -286.874966) (xy 396.723016 -286.825912) (xy 396.734793 -286.778128) (xy 396.754084 -286.732852)
			(xy 396.780387 -286.691256) (xy 396.813022 -286.654419) (xy 396.851143 -286.623294) (xy 396.893764 -286.598687)
			(xy 396.93978 -286.581235) (xy 396.987999 -286.571391) (xy 397.037174 -286.56941) (xy 397.086029 -286.575342)
			(xy 397.1333 -286.589034) (xy 397.177762 -286.610132) (xy 397.218265 -286.638088) (xy 397.253758 -286.67218)
			(xy 397.283323 -286.711524) (xy 397.306194 -286.755101) (xy 397.321778 -286.801782) (xy 397.329673 -286.850359)
			(xy 397.330168 -286.874966) (xy 397.669016 -286.874966) (xy 397.672976 -286.825912) (xy 397.684753 -286.778128)
			(xy 397.704044 -286.732852) (xy 397.730347 -286.691256) (xy 397.762982 -286.654419) (xy 397.801103 -286.623294)
			(xy 397.843724 -286.598687) (xy 397.88974 -286.581235) (xy 397.937959 -286.571391) (xy 397.987134 -286.56941)
			(xy 398.035989 -286.575342) (xy 398.08326 -286.589034) (xy 398.127722 -286.610132) (xy 398.168225 -286.638088)
			(xy 398.203718 -286.67218) (xy 398.233283 -286.711524) (xy 398.256154 -286.755101) (xy 398.271738 -286.801782)
			(xy 398.279633 -286.850359) (xy 398.280128 -286.874966) (xy 398.61923 -286.874966) (xy 398.62319 -286.825912)
			(xy 398.634967 -286.778128) (xy 398.654258 -286.732852) (xy 398.680561 -286.691256) (xy 398.713196 -286.654419)
			(xy 398.751317 -286.623294) (xy 398.793938 -286.598687) (xy 398.839954 -286.581235) (xy 398.888173 -286.571391)
			(xy 398.937348 -286.56941) (xy 398.986203 -286.575342) (xy 399.033474 -286.589034) (xy 399.077936 -286.610132)
			(xy 399.118439 -286.638088) (xy 399.153932 -286.67218) (xy 399.183497 -286.711524) (xy 399.206368 -286.755101)
			(xy 399.221952 -286.801782) (xy 399.229847 -286.850359) (xy 399.230342 -286.874966) (xy 399.56919 -286.874966)
			(xy 399.57315 -286.825912) (xy 399.584927 -286.778128) (xy 399.604218 -286.732852) (xy 399.630521 -286.691256)
			(xy 399.663156 -286.654419) (xy 399.701277 -286.623294) (xy 399.743898 -286.598687) (xy 399.789914 -286.581235)
			(xy 399.838133 -286.571391) (xy 399.887308 -286.56941) (xy 399.936163 -286.575342) (xy 399.983434 -286.589034)
			(xy 400.027896 -286.610132) (xy 400.068399 -286.638088) (xy 400.103892 -286.67218) (xy 400.133457 -286.711524)
			(xy 400.156328 -286.755101) (xy 400.171912 -286.801782) (xy 400.179807 -286.850359) (xy 400.180302 -286.874966)
			(xy 400.51915 -286.874966) (xy 400.52311 -286.825912) (xy 400.534887 -286.778128) (xy 400.554178 -286.732852)
			(xy 400.580481 -286.691256) (xy 400.613116 -286.654419) (xy 400.651237 -286.623294) (xy 400.693858 -286.598687)
			(xy 400.739874 -286.581235) (xy 400.788093 -286.571391) (xy 400.837268 -286.56941) (xy 400.886123 -286.575342)
			(xy 400.933394 -286.589034) (xy 400.977856 -286.610132) (xy 401.018359 -286.638088) (xy 401.053852 -286.67218)
			(xy 401.083417 -286.711524) (xy 401.106288 -286.755101) (xy 401.121872 -286.801782) (xy 401.129767 -286.850359)
			(xy 401.130262 -286.874966) (xy 401.46911 -286.874966) (xy 401.47307 -286.825912) (xy 401.484847 -286.778128)
			(xy 401.504138 -286.732852) (xy 401.530441 -286.691256) (xy 401.563076 -286.654419) (xy 401.601197 -286.623294)
			(xy 401.643818 -286.598687) (xy 401.689834 -286.581235) (xy 401.738053 -286.571391) (xy 401.787228 -286.56941)
			(xy 401.836083 -286.575342) (xy 401.883354 -286.589034) (xy 401.927816 -286.610132) (xy 401.968319 -286.638088)
			(xy 402.003812 -286.67218) (xy 402.033377 -286.711524) (xy 402.056248 -286.755101) (xy 402.071832 -286.801782)
			(xy 402.079727 -286.850359) (xy 402.080222 -286.874966) (xy 402.41907 -286.874966) (xy 402.42303 -286.825912)
			(xy 402.434807 -286.778128) (xy 402.454098 -286.732852) (xy 402.480401 -286.691256) (xy 402.513036 -286.654419)
			(xy 402.551157 -286.623294) (xy 402.593778 -286.598687) (xy 402.639794 -286.581235) (xy 402.688013 -286.571391)
			(xy 402.737188 -286.56941) (xy 402.786043 -286.575342) (xy 402.833314 -286.589034) (xy 402.877776 -286.610132)
			(xy 402.918279 -286.638088) (xy 402.953772 -286.67218) (xy 402.983337 -286.711524) (xy 403.006208 -286.755101)
			(xy 403.021792 -286.801782) (xy 403.029687 -286.850359) (xy 403.030182 -286.874966) (xy 403.36903 -286.874966)
			(xy 403.37299 -286.825912) (xy 403.384767 -286.778128) (xy 403.404058 -286.732852) (xy 403.430361 -286.691256)
			(xy 403.462996 -286.654419) (xy 403.501117 -286.623294) (xy 403.543738 -286.598687) (xy 403.589754 -286.581235)
			(xy 403.637973 -286.571391) (xy 403.687148 -286.56941) (xy 403.736003 -286.575342) (xy 403.783274 -286.589034)
			(xy 403.827736 -286.610132) (xy 403.868239 -286.638088) (xy 403.903732 -286.67218) (xy 403.933297 -286.711524)
			(xy 403.956168 -286.755101) (xy 403.971752 -286.801782) (xy 403.979647 -286.850359) (xy 403.980142 -286.874966)
			(xy 404.31899 -286.874966) (xy 404.32295 -286.825912) (xy 404.334727 -286.778128) (xy 404.354018 -286.732852)
			(xy 404.380321 -286.691256) (xy 404.412956 -286.654419) (xy 404.451077 -286.623294) (xy 404.493698 -286.598687)
			(xy 404.539714 -286.581235) (xy 404.587933 -286.571391) (xy 404.637108 -286.56941) (xy 404.685963 -286.575342)
			(xy 404.733234 -286.589034) (xy 404.777696 -286.610132) (xy 404.818199 -286.638088) (xy 404.853692 -286.67218)
			(xy 404.883257 -286.711524) (xy 404.906128 -286.755101) (xy 404.921712 -286.801782) (xy 404.929607 -286.850359)
			(xy 404.930102 -286.874966) (xy 405.269204 -286.874966) (xy 405.273164 -286.825912) (xy 405.284941 -286.778128)
			(xy 405.304232 -286.732852) (xy 405.330535 -286.691256) (xy 405.36317 -286.654419) (xy 405.401291 -286.623294)
			(xy 405.443912 -286.598687) (xy 405.489928 -286.581235) (xy 405.538147 -286.571391) (xy 405.587322 -286.56941)
			(xy 405.636177 -286.575342) (xy 405.683448 -286.589034) (xy 405.72791 -286.610132) (xy 405.768413 -286.638088)
			(xy 405.803906 -286.67218) (xy 405.833471 -286.711524) (xy 405.856342 -286.755101) (xy 405.871926 -286.801782)
			(xy 405.879821 -286.850359) (xy 405.880316 -286.874966) (xy 406.219164 -286.874966) (xy 406.223124 -286.825912)
			(xy 406.234901 -286.778128) (xy 406.254192 -286.732852) (xy 406.280495 -286.691256) (xy 406.31313 -286.654419)
			(xy 406.351251 -286.623294) (xy 406.393872 -286.598687) (xy 406.439888 -286.581235) (xy 406.488107 -286.571391)
			(xy 406.537282 -286.56941) (xy 406.586137 -286.575342) (xy 406.633408 -286.589034) (xy 406.67787 -286.610132)
			(xy 406.718373 -286.638088) (xy 406.753866 -286.67218) (xy 406.783431 -286.711524) (xy 406.806302 -286.755101)
			(xy 406.821886 -286.801782) (xy 406.829781 -286.850359) (xy 406.830276 -286.874966) (xy 408.119084 -286.874966)
			(xy 408.123044 -286.825912) (xy 408.134821 -286.778128) (xy 408.154112 -286.732852) (xy 408.180415 -286.691256)
			(xy 408.21305 -286.654419) (xy 408.251171 -286.623294) (xy 408.293792 -286.598687) (xy 408.339808 -286.581235)
			(xy 408.388027 -286.571391) (xy 408.437202 -286.56941) (xy 408.486057 -286.575342) (xy 408.533328 -286.589034)
			(xy 408.57779 -286.610132) (xy 408.618293 -286.638088) (xy 408.653786 -286.67218) (xy 408.683351 -286.711524)
			(xy 408.706222 -286.755101) (xy 408.721806 -286.801782) (xy 408.729701 -286.850359) (xy 408.730196 -286.874966)
			(xy 409.069044 -286.874966) (xy 409.073004 -286.825912) (xy 409.084781 -286.778128) (xy 409.104072 -286.732852)
			(xy 409.130375 -286.691256) (xy 409.16301 -286.654419) (xy 409.201131 -286.623294) (xy 409.243752 -286.598687)
			(xy 409.289768 -286.581235) (xy 409.337987 -286.571391) (xy 409.387162 -286.56941) (xy 409.436017 -286.575342)
			(xy 409.483288 -286.589034) (xy 409.52775 -286.610132) (xy 409.568253 -286.638088) (xy 409.603746 -286.67218)
			(xy 409.633311 -286.711524) (xy 409.656182 -286.755101) (xy 409.671766 -286.801782) (xy 409.679661 -286.850359)
			(xy 409.680156 -286.874966) (xy 410.019004 -286.874966) (xy 410.022964 -286.825912) (xy 410.034741 -286.778128)
			(xy 410.054032 -286.732852) (xy 410.080335 -286.691256) (xy 410.11297 -286.654419) (xy 410.151091 -286.623294)
			(xy 410.193712 -286.598687) (xy 410.239728 -286.581235) (xy 410.287947 -286.571391) (xy 410.337122 -286.56941)
			(xy 410.385977 -286.575342) (xy 410.433248 -286.589034) (xy 410.47771 -286.610132) (xy 410.518213 -286.638088)
			(xy 410.553706 -286.67218) (xy 410.583271 -286.711524) (xy 410.606142 -286.755101) (xy 410.621726 -286.801782)
			(xy 410.629621 -286.850359) (xy 410.630116 -286.874966) (xy 410.969218 -286.874966) (xy 410.973178 -286.825912)
			(xy 410.984955 -286.778128) (xy 411.004246 -286.732852) (xy 411.030549 -286.691256) (xy 411.063184 -286.654419)
			(xy 411.101305 -286.623294) (xy 411.143926 -286.598687) (xy 411.189942 -286.581235) (xy 411.238161 -286.571391)
			(xy 411.287336 -286.56941) (xy 411.336191 -286.575342) (xy 411.383462 -286.589034) (xy 411.427924 -286.610132)
			(xy 411.468427 -286.638088) (xy 411.50392 -286.67218) (xy 411.533485 -286.711524) (xy 411.556356 -286.755101)
			(xy 411.57194 -286.801782) (xy 411.579835 -286.850359) (xy 411.58033 -286.874966) (xy 411.919178 -286.874966)
			(xy 411.923138 -286.825912) (xy 411.934915 -286.778128) (xy 411.954206 -286.732852) (xy 411.980509 -286.691256)
			(xy 412.013144 -286.654419) (xy 412.051265 -286.623294) (xy 412.093886 -286.598687) (xy 412.139902 -286.581235)
			(xy 412.188121 -286.571391) (xy 412.237296 -286.56941) (xy 412.286151 -286.575342) (xy 412.333422 -286.589034)
			(xy 412.377884 -286.610132) (xy 412.418387 -286.638088) (xy 412.45388 -286.67218) (xy 412.483445 -286.711524)
			(xy 412.506316 -286.755101) (xy 412.5219 -286.801782) (xy 412.529795 -286.850359) (xy 412.53029 -286.874966)
			(xy 412.869138 -286.874966) (xy 412.873098 -286.825912) (xy 412.884875 -286.778128) (xy 412.904166 -286.732852)
			(xy 412.930469 -286.691256) (xy 412.963104 -286.654419) (xy 413.001225 -286.623294) (xy 413.043846 -286.598687)
			(xy 413.089862 -286.581235) (xy 413.138081 -286.571391) (xy 413.187256 -286.56941) (xy 413.236111 -286.575342)
			(xy 413.283382 -286.589034) (xy 413.327844 -286.610132) (xy 413.368347 -286.638088) (xy 413.40384 -286.67218)
			(xy 413.433405 -286.711524) (xy 413.456276 -286.755101) (xy 413.47186 -286.801782) (xy 413.479755 -286.850359)
			(xy 413.48025 -286.874966) (xy 413.819098 -286.874966) (xy 413.823058 -286.825912) (xy 413.834835 -286.778128)
			(xy 413.854126 -286.732852) (xy 413.880429 -286.691256) (xy 413.913064 -286.654419) (xy 413.951185 -286.623294)
			(xy 413.993806 -286.598687) (xy 414.039822 -286.581235) (xy 414.088041 -286.571391) (xy 414.137216 -286.56941)
			(xy 414.186071 -286.575342) (xy 414.233342 -286.589034) (xy 414.277804 -286.610132) (xy 414.318307 -286.638088)
			(xy 414.3538 -286.67218) (xy 414.383365 -286.711524) (xy 414.406236 -286.755101) (xy 414.42182 -286.801782)
			(xy 414.429715 -286.850359) (xy 414.43021 -286.874966) (xy 414.769058 -286.874966) (xy 414.773018 -286.825912)
			(xy 414.784795 -286.778128) (xy 414.804086 -286.732852) (xy 414.830389 -286.691256) (xy 414.863024 -286.654419)
			(xy 414.901145 -286.623294) (xy 414.943766 -286.598687) (xy 414.989782 -286.581235) (xy 415.038001 -286.571391)
			(xy 415.087176 -286.56941) (xy 415.136031 -286.575342) (xy 415.183302 -286.589034) (xy 415.227764 -286.610132)
			(xy 415.268267 -286.638088) (xy 415.30376 -286.67218) (xy 415.333325 -286.711524) (xy 415.356196 -286.755101)
			(xy 415.37178 -286.801782) (xy 415.379675 -286.850359) (xy 415.38017 -286.874966) (xy 415.719018 -286.874966)
			(xy 415.722978 -286.825912) (xy 415.734755 -286.778128) (xy 415.754046 -286.732852) (xy 415.780349 -286.691256)
			(xy 415.812984 -286.654419) (xy 415.851105 -286.623294) (xy 415.893726 -286.598687) (xy 415.939742 -286.581235)
			(xy 415.987961 -286.571391) (xy 416.037136 -286.56941) (xy 416.085991 -286.575342) (xy 416.133262 -286.589034)
			(xy 416.177724 -286.610132) (xy 416.218227 -286.638088) (xy 416.25372 -286.67218) (xy 416.283285 -286.711524)
			(xy 416.306156 -286.755101) (xy 416.32174 -286.801782) (xy 416.329635 -286.850359) (xy 416.33013 -286.874966)
			(xy 416.668978 -286.874966) (xy 416.672938 -286.825912) (xy 416.684715 -286.778128) (xy 416.704006 -286.732852)
			(xy 416.730309 -286.691256) (xy 416.762944 -286.654419) (xy 416.801065 -286.623294) (xy 416.843686 -286.598687)
			(xy 416.889702 -286.581235) (xy 416.937921 -286.571391) (xy 416.987096 -286.56941) (xy 417.035951 -286.575342)
			(xy 417.083222 -286.589034) (xy 417.127684 -286.610132) (xy 417.168187 -286.638088) (xy 417.20368 -286.67218)
			(xy 417.233245 -286.711524) (xy 417.256116 -286.755101) (xy 417.2717 -286.801782) (xy 417.279595 -286.850359)
			(xy 417.28009 -286.874966) (xy 418.569152 -286.874966) (xy 418.573112 -286.825912) (xy 418.584889 -286.778128)
			(xy 418.60418 -286.732852) (xy 418.630483 -286.691256) (xy 418.663118 -286.654419) (xy 418.701239 -286.623294)
			(xy 418.74386 -286.598687) (xy 418.789876 -286.581235) (xy 418.838095 -286.571391) (xy 418.88727 -286.56941)
			(xy 418.936125 -286.575342) (xy 418.983396 -286.589034) (xy 419.027858 -286.610132) (xy 419.068361 -286.638088)
			(xy 419.103854 -286.67218) (xy 419.133419 -286.711524) (xy 419.15629 -286.755101) (xy 419.171874 -286.801782)
			(xy 419.179769 -286.850359) (xy 419.180264 -286.874966) (xy 419.179769 -286.899573) (xy 419.171874 -286.94815)
			(xy 419.15629 -286.994831) (xy 419.133419 -287.038408) (xy 419.103854 -287.077752) (xy 419.068361 -287.111844)
			(xy 419.027858 -287.1398) (xy 418.983396 -287.160898) (xy 418.936125 -287.17459) (xy 418.88727 -287.180522)
			(xy 418.838095 -287.178541) (xy 418.789876 -287.168697) (xy 418.74386 -287.151245) (xy 418.701239 -287.126638)
			(xy 418.663118 -287.095513) (xy 418.630483 -287.058676) (xy 418.60418 -287.01708) (xy 418.584889 -286.971804)
			(xy 418.573112 -286.92402) (xy 418.569152 -286.874966) (xy 417.28009 -286.874966) (xy 417.279595 -286.899573)
			(xy 417.2717 -286.94815) (xy 417.256116 -286.994831) (xy 417.233245 -287.038408) (xy 417.20368 -287.077752)
			(xy 417.168187 -287.111844) (xy 417.127684 -287.1398) (xy 417.083222 -287.160898) (xy 417.035951 -287.17459)
			(xy 416.987096 -287.180522) (xy 416.937921 -287.178541) (xy 416.889702 -287.168697) (xy 416.843686 -287.151245)
			(xy 416.801065 -287.126638) (xy 416.762944 -287.095513) (xy 416.730309 -287.058676) (xy 416.704006 -287.01708)
			(xy 416.684715 -286.971804) (xy 416.672938 -286.92402) (xy 416.668978 -286.874966) (xy 416.33013 -286.874966)
			(xy 416.329635 -286.899573) (xy 416.32174 -286.94815) (xy 416.306156 -286.994831) (xy 416.283285 -287.038408)
			(xy 416.25372 -287.077752) (xy 416.218227 -287.111844) (xy 416.177724 -287.1398) (xy 416.133262 -287.160898)
			(xy 416.085991 -287.17459) (xy 416.037136 -287.180522) (xy 415.987961 -287.178541) (xy 415.939742 -287.168697)
			(xy 415.893726 -287.151245) (xy 415.851105 -287.126638) (xy 415.812984 -287.095513) (xy 415.780349 -287.058676)
			(xy 415.754046 -287.01708) (xy 415.734755 -286.971804) (xy 415.722978 -286.92402) (xy 415.719018 -286.874966)
			(xy 415.38017 -286.874966) (xy 415.379675 -286.899573) (xy 415.37178 -286.94815) (xy 415.356196 -286.994831)
			(xy 415.333325 -287.038408) (xy 415.30376 -287.077752) (xy 415.268267 -287.111844) (xy 415.227764 -287.1398)
			(xy 415.183302 -287.160898) (xy 415.136031 -287.17459) (xy 415.087176 -287.180522) (xy 415.038001 -287.178541)
			(xy 414.989782 -287.168697) (xy 414.943766 -287.151245) (xy 414.901145 -287.126638) (xy 414.863024 -287.095513)
			(xy 414.830389 -287.058676) (xy 414.804086 -287.01708) (xy 414.784795 -286.971804) (xy 414.773018 -286.92402)
			(xy 414.769058 -286.874966) (xy 414.43021 -286.874966) (xy 414.429715 -286.899573) (xy 414.42182 -286.94815)
			(xy 414.406236 -286.994831) (xy 414.383365 -287.038408) (xy 414.3538 -287.077752) (xy 414.318307 -287.111844)
			(xy 414.277804 -287.1398) (xy 414.233342 -287.160898) (xy 414.186071 -287.17459) (xy 414.137216 -287.180522)
			(xy 414.088041 -287.178541) (xy 414.039822 -287.168697) (xy 413.993806 -287.151245) (xy 413.951185 -287.126638)
			(xy 413.913064 -287.095513) (xy 413.880429 -287.058676) (xy 413.854126 -287.01708) (xy 413.834835 -286.971804)
			(xy 413.823058 -286.92402) (xy 413.819098 -286.874966) (xy 413.48025 -286.874966) (xy 413.479755 -286.899573)
			(xy 413.47186 -286.94815) (xy 413.456276 -286.994831) (xy 413.433405 -287.038408) (xy 413.40384 -287.077752)
			(xy 413.368347 -287.111844) (xy 413.327844 -287.1398) (xy 413.283382 -287.160898) (xy 413.236111 -287.17459)
			(xy 413.187256 -287.180522) (xy 413.138081 -287.178541) (xy 413.089862 -287.168697) (xy 413.043846 -287.151245)
			(xy 413.001225 -287.126638) (xy 412.963104 -287.095513) (xy 412.930469 -287.058676) (xy 412.904166 -287.01708)
			(xy 412.884875 -286.971804) (xy 412.873098 -286.92402) (xy 412.869138 -286.874966) (xy 412.53029 -286.874966)
			(xy 412.529795 -286.899573) (xy 412.5219 -286.94815) (xy 412.506316 -286.994831) (xy 412.483445 -287.038408)
			(xy 412.45388 -287.077752) (xy 412.418387 -287.111844) (xy 412.377884 -287.1398) (xy 412.333422 -287.160898)
			(xy 412.286151 -287.17459) (xy 412.237296 -287.180522) (xy 412.188121 -287.178541) (xy 412.139902 -287.168697)
			(xy 412.093886 -287.151245) (xy 412.051265 -287.126638) (xy 412.013144 -287.095513) (xy 411.980509 -287.058676)
			(xy 411.954206 -287.01708) (xy 411.934915 -286.971804) (xy 411.923138 -286.92402) (xy 411.919178 -286.874966)
			(xy 411.58033 -286.874966) (xy 411.579835 -286.899573) (xy 411.57194 -286.94815) (xy 411.556356 -286.994831)
			(xy 411.533485 -287.038408) (xy 411.50392 -287.077752) (xy 411.468427 -287.111844) (xy 411.427924 -287.1398)
			(xy 411.383462 -287.160898) (xy 411.336191 -287.17459) (xy 411.287336 -287.180522) (xy 411.238161 -287.178541)
			(xy 411.189942 -287.168697) (xy 411.143926 -287.151245) (xy 411.101305 -287.126638) (xy 411.063184 -287.095513)
			(xy 411.030549 -287.058676) (xy 411.004246 -287.01708) (xy 410.984955 -286.971804) (xy 410.973178 -286.92402)
			(xy 410.969218 -286.874966) (xy 410.630116 -286.874966) (xy 410.629621 -286.899573) (xy 410.621726 -286.94815)
			(xy 410.606142 -286.994831) (xy 410.583271 -287.038408) (xy 410.553706 -287.077752) (xy 410.518213 -287.111844)
			(xy 410.47771 -287.1398) (xy 410.433248 -287.160898) (xy 410.385977 -287.17459) (xy 410.337122 -287.180522)
			(xy 410.287947 -287.178541) (xy 410.239728 -287.168697) (xy 410.193712 -287.151245) (xy 410.151091 -287.126638)
			(xy 410.11297 -287.095513) (xy 410.080335 -287.058676) (xy 410.054032 -287.01708) (xy 410.034741 -286.971804)
			(xy 410.022964 -286.92402) (xy 410.019004 -286.874966) (xy 409.680156 -286.874966) (xy 409.679661 -286.899573)
			(xy 409.671766 -286.94815) (xy 409.656182 -286.994831) (xy 409.633311 -287.038408) (xy 409.603746 -287.077752)
			(xy 409.568253 -287.111844) (xy 409.52775 -287.1398) (xy 409.483288 -287.160898) (xy 409.436017 -287.17459)
			(xy 409.387162 -287.180522) (xy 409.337987 -287.178541) (xy 409.289768 -287.168697) (xy 409.243752 -287.151245)
			(xy 409.201131 -287.126638) (xy 409.16301 -287.095513) (xy 409.130375 -287.058676) (xy 409.104072 -287.01708)
			(xy 409.084781 -286.971804) (xy 409.073004 -286.92402) (xy 409.069044 -286.874966) (xy 408.730196 -286.874966)
			(xy 408.729701 -286.899573) (xy 408.721806 -286.94815) (xy 408.706222 -286.994831) (xy 408.683351 -287.038408)
			(xy 408.653786 -287.077752) (xy 408.618293 -287.111844) (xy 408.57779 -287.1398) (xy 408.533328 -287.160898)
			(xy 408.486057 -287.17459) (xy 408.437202 -287.180522) (xy 408.388027 -287.178541) (xy 408.339808 -287.168697)
			(xy 408.293792 -287.151245) (xy 408.251171 -287.126638) (xy 408.21305 -287.095513) (xy 408.180415 -287.058676)
			(xy 408.154112 -287.01708) (xy 408.134821 -286.971804) (xy 408.123044 -286.92402) (xy 408.119084 -286.874966)
			(xy 406.830276 -286.874966) (xy 406.829781 -286.899573) (xy 406.821886 -286.94815) (xy 406.806302 -286.994831)
			(xy 406.783431 -287.038408) (xy 406.753866 -287.077752) (xy 406.718373 -287.111844) (xy 406.67787 -287.1398)
			(xy 406.633408 -287.160898) (xy 406.586137 -287.17459) (xy 406.537282 -287.180522) (xy 406.488107 -287.178541)
			(xy 406.439888 -287.168697) (xy 406.393872 -287.151245) (xy 406.351251 -287.126638) (xy 406.31313 -287.095513)
			(xy 406.280495 -287.058676) (xy 406.254192 -287.01708) (xy 406.234901 -286.971804) (xy 406.223124 -286.92402)
			(xy 406.219164 -286.874966) (xy 405.880316 -286.874966) (xy 405.879821 -286.899573) (xy 405.871926 -286.94815)
			(xy 405.856342 -286.994831) (xy 405.833471 -287.038408) (xy 405.803906 -287.077752) (xy 405.768413 -287.111844)
			(xy 405.72791 -287.1398) (xy 405.683448 -287.160898) (xy 405.636177 -287.17459) (xy 405.587322 -287.180522)
			(xy 405.538147 -287.178541) (xy 405.489928 -287.168697) (xy 405.443912 -287.151245) (xy 405.401291 -287.126638)
			(xy 405.36317 -287.095513) (xy 405.330535 -287.058676) (xy 405.304232 -287.01708) (xy 405.284941 -286.971804)
			(xy 405.273164 -286.92402) (xy 405.269204 -286.874966) (xy 404.930102 -286.874966) (xy 404.929607 -286.899573)
			(xy 404.921712 -286.94815) (xy 404.906128 -286.994831) (xy 404.883257 -287.038408) (xy 404.853692 -287.077752)
			(xy 404.818199 -287.111844) (xy 404.777696 -287.1398) (xy 404.733234 -287.160898) (xy 404.685963 -287.17459)
			(xy 404.637108 -287.180522) (xy 404.587933 -287.178541) (xy 404.539714 -287.168697) (xy 404.493698 -287.151245)
			(xy 404.451077 -287.126638) (xy 404.412956 -287.095513) (xy 404.380321 -287.058676) (xy 404.354018 -287.01708)
			(xy 404.334727 -286.971804) (xy 404.32295 -286.92402) (xy 404.31899 -286.874966) (xy 403.980142 -286.874966)
			(xy 403.979647 -286.899573) (xy 403.971752 -286.94815) (xy 403.956168 -286.994831) (xy 403.933297 -287.038408)
			(xy 403.903732 -287.077752) (xy 403.868239 -287.111844) (xy 403.827736 -287.1398) (xy 403.783274 -287.160898)
			(xy 403.736003 -287.17459) (xy 403.687148 -287.180522) (xy 403.637973 -287.178541) (xy 403.589754 -287.168697)
			(xy 403.543738 -287.151245) (xy 403.501117 -287.126638) (xy 403.462996 -287.095513) (xy 403.430361 -287.058676)
			(xy 403.404058 -287.01708) (xy 403.384767 -286.971804) (xy 403.37299 -286.92402) (xy 403.36903 -286.874966)
			(xy 403.030182 -286.874966) (xy 403.029687 -286.899573) (xy 403.021792 -286.94815) (xy 403.006208 -286.994831)
			(xy 402.983337 -287.038408) (xy 402.953772 -287.077752) (xy 402.918279 -287.111844) (xy 402.877776 -287.1398)
			(xy 402.833314 -287.160898) (xy 402.786043 -287.17459) (xy 402.737188 -287.180522) (xy 402.688013 -287.178541)
			(xy 402.639794 -287.168697) (xy 402.593778 -287.151245) (xy 402.551157 -287.126638) (xy 402.513036 -287.095513)
			(xy 402.480401 -287.058676) (xy 402.454098 -287.01708) (xy 402.434807 -286.971804) (xy 402.42303 -286.92402)
			(xy 402.41907 -286.874966) (xy 402.080222 -286.874966) (xy 402.079727 -286.899573) (xy 402.071832 -286.94815)
			(xy 402.056248 -286.994831) (xy 402.033377 -287.038408) (xy 402.003812 -287.077752) (xy 401.968319 -287.111844)
			(xy 401.927816 -287.1398) (xy 401.883354 -287.160898) (xy 401.836083 -287.17459) (xy 401.787228 -287.180522)
			(xy 401.738053 -287.178541) (xy 401.689834 -287.168697) (xy 401.643818 -287.151245) (xy 401.601197 -287.126638)
			(xy 401.563076 -287.095513) (xy 401.530441 -287.058676) (xy 401.504138 -287.01708) (xy 401.484847 -286.971804)
			(xy 401.47307 -286.92402) (xy 401.46911 -286.874966) (xy 401.130262 -286.874966) (xy 401.129767 -286.899573)
			(xy 401.121872 -286.94815) (xy 401.106288 -286.994831) (xy 401.083417 -287.038408) (xy 401.053852 -287.077752)
			(xy 401.018359 -287.111844) (xy 400.977856 -287.1398) (xy 400.933394 -287.160898) (xy 400.886123 -287.17459)
			(xy 400.837268 -287.180522) (xy 400.788093 -287.178541) (xy 400.739874 -287.168697) (xy 400.693858 -287.151245)
			(xy 400.651237 -287.126638) (xy 400.613116 -287.095513) (xy 400.580481 -287.058676) (xy 400.554178 -287.01708)
			(xy 400.534887 -286.971804) (xy 400.52311 -286.92402) (xy 400.51915 -286.874966) (xy 400.180302 -286.874966)
			(xy 400.179807 -286.899573) (xy 400.171912 -286.94815) (xy 400.156328 -286.994831) (xy 400.133457 -287.038408)
			(xy 400.103892 -287.077752) (xy 400.068399 -287.111844) (xy 400.027896 -287.1398) (xy 399.983434 -287.160898)
			(xy 399.936163 -287.17459) (xy 399.887308 -287.180522) (xy 399.838133 -287.178541) (xy 399.789914 -287.168697)
			(xy 399.743898 -287.151245) (xy 399.701277 -287.126638) (xy 399.663156 -287.095513) (xy 399.630521 -287.058676)
			(xy 399.604218 -287.01708) (xy 399.584927 -286.971804) (xy 399.57315 -286.92402) (xy 399.56919 -286.874966)
			(xy 399.230342 -286.874966) (xy 399.229847 -286.899573) (xy 399.221952 -286.94815) (xy 399.206368 -286.994831)
			(xy 399.183497 -287.038408) (xy 399.153932 -287.077752) (xy 399.118439 -287.111844) (xy 399.077936 -287.1398)
			(xy 399.033474 -287.160898) (xy 398.986203 -287.17459) (xy 398.937348 -287.180522) (xy 398.888173 -287.178541)
			(xy 398.839954 -287.168697) (xy 398.793938 -287.151245) (xy 398.751317 -287.126638) (xy 398.713196 -287.095513)
			(xy 398.680561 -287.058676) (xy 398.654258 -287.01708) (xy 398.634967 -286.971804) (xy 398.62319 -286.92402)
			(xy 398.61923 -286.874966) (xy 398.280128 -286.874966) (xy 398.279633 -286.899573) (xy 398.271738 -286.94815)
			(xy 398.256154 -286.994831) (xy 398.233283 -287.038408) (xy 398.203718 -287.077752) (xy 398.168225 -287.111844)
			(xy 398.127722 -287.1398) (xy 398.08326 -287.160898) (xy 398.035989 -287.17459) (xy 397.987134 -287.180522)
			(xy 397.937959 -287.178541) (xy 397.88974 -287.168697) (xy 397.843724 -287.151245) (xy 397.801103 -287.126638)
			(xy 397.762982 -287.095513) (xy 397.730347 -287.058676) (xy 397.704044 -287.01708) (xy 397.684753 -286.971804)
			(xy 397.672976 -286.92402) (xy 397.669016 -286.874966) (xy 397.330168 -286.874966) (xy 397.329673 -286.899573)
			(xy 397.321778 -286.94815) (xy 397.306194 -286.994831) (xy 397.283323 -287.038408) (xy 397.253758 -287.077752)
			(xy 397.218265 -287.111844) (xy 397.177762 -287.1398) (xy 397.1333 -287.160898) (xy 397.086029 -287.17459)
			(xy 397.037174 -287.180522) (xy 396.987999 -287.178541) (xy 396.93978 -287.168697) (xy 396.893764 -287.151245)
			(xy 396.851143 -287.126638) (xy 396.813022 -287.095513) (xy 396.780387 -287.058676) (xy 396.754084 -287.01708)
			(xy 396.734793 -286.971804) (xy 396.723016 -286.92402) (xy 396.719056 -286.874966) (xy 396.380208 -286.874966)
			(xy 396.379713 -286.899573) (xy 396.371818 -286.94815) (xy 396.356234 -286.994831) (xy 396.333363 -287.038408)
			(xy 396.303798 -287.077752) (xy 396.268305 -287.111844) (xy 396.227802 -287.1398) (xy 396.18334 -287.160898)
			(xy 396.136069 -287.17459) (xy 396.087214 -287.180522) (xy 396.038039 -287.178541) (xy 395.98982 -287.168697)
			(xy 395.943804 -287.151245) (xy 395.901183 -287.126638) (xy 395.863062 -287.095513) (xy 395.830427 -287.058676)
			(xy 395.804124 -287.01708) (xy 395.784833 -286.971804) (xy 395.773056 -286.92402) (xy 395.769096 -286.874966)
			(xy 395.430248 -286.874966) (xy 395.429753 -286.899573) (xy 395.421858 -286.94815) (xy 395.406274 -286.994831)
			(xy 395.383403 -287.038408) (xy 395.353838 -287.077752) (xy 395.318345 -287.111844) (xy 395.277842 -287.1398)
			(xy 395.23338 -287.160898) (xy 395.186109 -287.17459) (xy 395.137254 -287.180522) (xy 395.088079 -287.178541)
			(xy 395.03986 -287.168697) (xy 394.993844 -287.151245) (xy 394.951223 -287.126638) (xy 394.913102 -287.095513)
			(xy 394.880467 -287.058676) (xy 394.854164 -287.01708) (xy 394.834873 -286.971804) (xy 394.823096 -286.92402)
			(xy 394.819136 -286.874966) (xy 394.480288 -286.874966) (xy 394.479793 -286.899573) (xy 394.471898 -286.94815)
			(xy 394.456314 -286.994831) (xy 394.433443 -287.038408) (xy 394.403878 -287.077752) (xy 394.368385 -287.111844)
			(xy 394.327882 -287.1398) (xy 394.28342 -287.160898) (xy 394.236149 -287.17459) (xy 394.187294 -287.180522)
			(xy 394.138119 -287.178541) (xy 394.0899 -287.168697) (xy 394.043884 -287.151245) (xy 394.001263 -287.126638)
			(xy 393.963142 -287.095513) (xy 393.930507 -287.058676) (xy 393.904204 -287.01708) (xy 393.884913 -286.971804)
			(xy 393.873136 -286.92402) (xy 393.869176 -286.874966) (xy 393.530328 -286.874966) (xy 393.529833 -286.899573)
			(xy 393.521938 -286.94815) (xy 393.506354 -286.994831) (xy 393.483483 -287.038408) (xy 393.453918 -287.077752)
			(xy 393.418425 -287.111844) (xy 393.377922 -287.1398) (xy 393.33346 -287.160898) (xy 393.286189 -287.17459)
			(xy 393.237334 -287.180522) (xy 393.188159 -287.178541) (xy 393.13994 -287.168697) (xy 393.093924 -287.151245)
			(xy 393.051303 -287.126638) (xy 393.013182 -287.095513) (xy 392.980547 -287.058676) (xy 392.954244 -287.01708)
			(xy 392.934953 -286.971804) (xy 392.923176 -286.92402) (xy 392.919216 -286.874966) (xy 392.580109 -286.874966)
			(xy 392.579619 -286.899319) (xy 392.571724 -286.947896) (xy 392.55614 -286.994577) (xy 392.533269 -287.038154)
			(xy 392.503704 -287.077498) (xy 392.468211 -287.11159) (xy 392.427708 -287.139546) (xy 392.383246 -287.160644)
			(xy 392.335975 -287.174336) (xy 392.28712 -287.180268) (xy 392.237945 -287.178287) (xy 392.189726 -287.168443)
			(xy 392.14371 -287.150991) (xy 392.101089 -287.126384) (xy 392.062968 -287.095259) (xy 392.030333 -287.058422)
			(xy 392.00403 -287.016826) (xy 391.984739 -286.97155) (xy 391.972962 -286.923766) (xy 391.969002 -286.874712)
			(xy 391.630154 -286.874712) (xy 391.629659 -286.899319) (xy 391.621764 -286.947896) (xy 391.60618 -286.994577)
			(xy 391.583309 -287.038154) (xy 391.553744 -287.077498) (xy 391.518251 -287.11159) (xy 391.477748 -287.139546)
			(xy 391.433286 -287.160644) (xy 391.386015 -287.174336) (xy 391.33716 -287.180268) (xy 391.287985 -287.178287)
			(xy 391.239766 -287.168443) (xy 391.19375 -287.150991) (xy 391.151129 -287.126384) (xy 391.113008 -287.095259)
			(xy 391.080373 -287.058422) (xy 391.05407 -287.016826) (xy 391.034779 -286.97155) (xy 391.023002 -286.923766)
			(xy 391.019042 -286.874712) (xy 390.680189 -286.874712) (xy 390.680194 -286.874966) (xy 390.679699 -286.899573)
			(xy 390.671804 -286.94815) (xy 390.65622 -286.994831) (xy 390.633349 -287.038408) (xy 390.603784 -287.077752)
			(xy 390.568291 -287.111844) (xy 390.527788 -287.1398) (xy 390.483326 -287.160898) (xy 390.436055 -287.17459)
			(xy 390.3872 -287.180522) (xy 390.338025 -287.178541) (xy 390.289806 -287.168697) (xy 390.24379 -287.151245)
			(xy 390.201169 -287.126638) (xy 390.163048 -287.095513) (xy 390.130413 -287.058676) (xy 390.10411 -287.01708)
			(xy 390.084819 -286.971804) (xy 390.073042 -286.92402) (xy 390.069082 -286.874966) (xy 389.730234 -286.874966)
			(xy 389.729739 -286.899573) (xy 389.721844 -286.94815) (xy 389.70626 -286.994831) (xy 389.683389 -287.038408)
			(xy 389.653824 -287.077752) (xy 389.618331 -287.111844) (xy 389.577828 -287.1398) (xy 389.533366 -287.160898)
			(xy 389.486095 -287.17459) (xy 389.43724 -287.180522) (xy 389.388065 -287.178541) (xy 389.339846 -287.168697)
			(xy 389.29383 -287.151245) (xy 389.251209 -287.126638) (xy 389.213088 -287.095513) (xy 389.180453 -287.058676)
			(xy 389.15415 -287.01708) (xy 389.134859 -286.971804) (xy 389.123082 -286.92402) (xy 389.119122 -286.874966)
			(xy 388.780274 -286.874966) (xy 388.779779 -286.899573) (xy 388.771884 -286.94815) (xy 388.7563 -286.994831)
			(xy 388.733429 -287.038408) (xy 388.703864 -287.077752) (xy 388.668371 -287.111844) (xy 388.627868 -287.1398)
			(xy 388.583406 -287.160898) (xy 388.536135 -287.17459) (xy 388.48728 -287.180522) (xy 388.438105 -287.178541)
			(xy 388.389886 -287.168697) (xy 388.34387 -287.151245) (xy 388.301249 -287.126638) (xy 388.263128 -287.095513)
			(xy 388.230493 -287.058676) (xy 388.20419 -287.01708) (xy 388.184899 -286.971804) (xy 388.173122 -286.92402)
			(xy 388.169162 -286.874966) (xy 387.830314 -286.874966) (xy 387.829819 -286.899573) (xy 387.821924 -286.94815)
			(xy 387.80634 -286.994831) (xy 387.783469 -287.038408) (xy 387.753904 -287.077752) (xy 387.718411 -287.111844)
			(xy 387.677908 -287.1398) (xy 387.633446 -287.160898) (xy 387.586175 -287.17459) (xy 387.53732 -287.180522)
			(xy 387.488145 -287.178541) (xy 387.439926 -287.168697) (xy 387.39391 -287.151245) (xy 387.351289 -287.126638)
			(xy 387.313168 -287.095513) (xy 387.280533 -287.058676) (xy 387.25423 -287.01708) (xy 387.234939 -286.971804)
			(xy 387.223162 -286.92402) (xy 387.219202 -286.874966) (xy 386.880354 -286.874966) (xy 386.879859 -286.899573)
			(xy 386.871964 -286.94815) (xy 386.85638 -286.994831) (xy 386.833509 -287.038408) (xy 386.803944 -287.077752)
			(xy 386.768451 -287.111844) (xy 386.727948 -287.1398) (xy 386.683486 -287.160898) (xy 386.636215 -287.17459)
			(xy 386.58736 -287.180522) (xy 386.538185 -287.178541) (xy 386.489966 -287.168697) (xy 386.44395 -287.151245)
			(xy 386.401329 -287.126638) (xy 386.363208 -287.095513) (xy 386.330573 -287.058676) (xy 386.30427 -287.01708)
			(xy 386.284979 -286.971804) (xy 386.273202 -286.92402) (xy 386.269242 -286.874966) (xy 385.93014 -286.874966)
			(xy 385.929645 -286.899573) (xy 385.92175 -286.94815) (xy 385.906166 -286.994831) (xy 385.883295 -287.038408)
			(xy 385.85373 -287.077752) (xy 385.818237 -287.111844) (xy 385.777734 -287.1398) (xy 385.733272 -287.160898)
			(xy 385.686001 -287.17459) (xy 385.637146 -287.180522) (xy 385.587971 -287.178541) (xy 385.539752 -287.168697)
			(xy 385.493736 -287.151245) (xy 385.451115 -287.126638) (xy 385.412994 -287.095513) (xy 385.380359 -287.058676)
			(xy 385.354056 -287.01708) (xy 385.334765 -286.971804) (xy 385.322988 -286.92402) (xy 385.319028 -286.874966)
			(xy 384.98018 -286.874966) (xy 384.979685 -286.899573) (xy 384.97179 -286.94815) (xy 384.956206 -286.994831)
			(xy 384.933335 -287.038408) (xy 384.90377 -287.077752) (xy 384.868277 -287.111844) (xy 384.827774 -287.1398)
			(xy 384.783312 -287.160898) (xy 384.736041 -287.17459) (xy 384.687186 -287.180522) (xy 384.638011 -287.178541)
			(xy 384.589792 -287.168697) (xy 384.543776 -287.151245) (xy 384.501155 -287.126638) (xy 384.463034 -287.095513)
			(xy 384.430399 -287.058676) (xy 384.404096 -287.01708) (xy 384.384805 -286.971804) (xy 384.373028 -286.92402)
			(xy 384.369068 -286.874966) (xy 384.2512 -286.874966) (xy 384.2512 -287.824926) (xy 384.369068 -287.824926)
			(xy 384.373028 -287.775872) (xy 384.384805 -287.728088) (xy 384.404096 -287.682812) (xy 384.430399 -287.641216)
			(xy 384.463034 -287.604379) (xy 384.501155 -287.573254) (xy 384.543776 -287.548647) (xy 384.589792 -287.531195)
			(xy 384.638011 -287.521351) (xy 384.687186 -287.51937) (xy 384.736041 -287.525302) (xy 384.783312 -287.538994)
			(xy 384.827774 -287.560092) (xy 384.868277 -287.588048) (xy 384.90377 -287.62214) (xy 384.933335 -287.661484)
			(xy 384.956206 -287.705061) (xy 384.97179 -287.751742) (xy 384.979685 -287.800319) (xy 384.98018 -287.824926)
			(xy 385.319028 -287.824926) (xy 385.322988 -287.775872) (xy 385.334765 -287.728088) (xy 385.354056 -287.682812)
			(xy 385.380359 -287.641216) (xy 385.412994 -287.604379) (xy 385.451115 -287.573254) (xy 385.493736 -287.548647)
			(xy 385.539752 -287.531195) (xy 385.587971 -287.521351) (xy 385.637146 -287.51937) (xy 385.686001 -287.525302)
			(xy 385.733272 -287.538994) (xy 385.777734 -287.560092) (xy 385.818237 -287.588048) (xy 385.85373 -287.62214)
			(xy 385.883295 -287.661484) (xy 385.906166 -287.705061) (xy 385.92175 -287.751742) (xy 385.929645 -287.800319)
			(xy 385.93014 -287.824926) (xy 386.269242 -287.824926) (xy 386.273202 -287.775872) (xy 386.284979 -287.728088)
			(xy 386.30427 -287.682812) (xy 386.330573 -287.641216) (xy 386.363208 -287.604379) (xy 386.401329 -287.573254)
			(xy 386.44395 -287.548647) (xy 386.489966 -287.531195) (xy 386.538185 -287.521351) (xy 386.58736 -287.51937)
			(xy 386.636215 -287.525302) (xy 386.683486 -287.538994) (xy 386.727948 -287.560092) (xy 386.768451 -287.588048)
			(xy 386.803944 -287.62214) (xy 386.833509 -287.661484) (xy 386.85638 -287.705061) (xy 386.871964 -287.751742)
			(xy 386.879859 -287.800319) (xy 386.880354 -287.824926) (xy 389.119122 -287.824926) (xy 389.123082 -287.775872)
			(xy 389.134859 -287.728088) (xy 389.15415 -287.682812) (xy 389.180453 -287.641216) (xy 389.213088 -287.604379)
			(xy 389.251209 -287.573254) (xy 389.29383 -287.548647) (xy 389.339846 -287.531195) (xy 389.388065 -287.521351)
			(xy 389.43724 -287.51937) (xy 389.486095 -287.525302) (xy 389.533366 -287.538994) (xy 389.577828 -287.560092)
			(xy 389.618331 -287.588048) (xy 389.653824 -287.62214) (xy 389.683389 -287.661484) (xy 389.70626 -287.705061)
			(xy 389.721844 -287.751742) (xy 389.729739 -287.800319) (xy 389.730234 -287.824926) (xy 392.919216 -287.824926)
			(xy 392.923176 -287.775872) (xy 392.934953 -287.728088) (xy 392.954244 -287.682812) (xy 392.980547 -287.641216)
			(xy 393.013182 -287.604379) (xy 393.051303 -287.573254) (xy 393.093924 -287.548647) (xy 393.13994 -287.531195)
			(xy 393.188159 -287.521351) (xy 393.237334 -287.51937) (xy 393.286189 -287.525302) (xy 393.33346 -287.538994)
			(xy 393.377922 -287.560092) (xy 393.418425 -287.588048) (xy 393.453918 -287.62214) (xy 393.483483 -287.661484)
			(xy 393.506354 -287.705061) (xy 393.521938 -287.751742) (xy 393.529833 -287.800319) (xy 393.530328 -287.824926)
			(xy 393.869176 -287.824926) (xy 393.873136 -287.775872) (xy 393.884913 -287.728088) (xy 393.904204 -287.682812)
			(xy 393.930507 -287.641216) (xy 393.963142 -287.604379) (xy 394.001263 -287.573254) (xy 394.043884 -287.548647)
			(xy 394.0899 -287.531195) (xy 394.138119 -287.521351) (xy 394.187294 -287.51937) (xy 394.236149 -287.525302)
			(xy 394.28342 -287.538994) (xy 394.327882 -287.560092) (xy 394.368385 -287.588048) (xy 394.403878 -287.62214)
			(xy 394.433443 -287.661484) (xy 394.456314 -287.705061) (xy 394.471898 -287.751742) (xy 394.479793 -287.800319)
			(xy 394.480288 -287.824926) (xy 394.819136 -287.824926) (xy 394.823096 -287.775872) (xy 394.834873 -287.728088)
			(xy 394.854164 -287.682812) (xy 394.880467 -287.641216) (xy 394.913102 -287.604379) (xy 394.951223 -287.573254)
			(xy 394.993844 -287.548647) (xy 395.03986 -287.531195) (xy 395.088079 -287.521351) (xy 395.137254 -287.51937)
			(xy 395.186109 -287.525302) (xy 395.23338 -287.538994) (xy 395.277842 -287.560092) (xy 395.318345 -287.588048)
			(xy 395.353838 -287.62214) (xy 395.383403 -287.661484) (xy 395.406274 -287.705061) (xy 395.421858 -287.751742)
			(xy 395.429753 -287.800319) (xy 395.430248 -287.824926) (xy 395.769096 -287.824926) (xy 395.773056 -287.775872)
			(xy 395.784833 -287.728088) (xy 395.804124 -287.682812) (xy 395.830427 -287.641216) (xy 395.863062 -287.604379)
			(xy 395.901183 -287.573254) (xy 395.943804 -287.548647) (xy 395.98982 -287.531195) (xy 396.038039 -287.521351)
			(xy 396.087214 -287.51937) (xy 396.136069 -287.525302) (xy 396.18334 -287.538994) (xy 396.227802 -287.560092)
			(xy 396.268305 -287.588048) (xy 396.303798 -287.62214) (xy 396.333363 -287.661484) (xy 396.356234 -287.705061)
			(xy 396.371818 -287.751742) (xy 396.379713 -287.800319) (xy 396.380208 -287.824926) (xy 396.719056 -287.824926)
			(xy 396.723016 -287.775872) (xy 396.734793 -287.728088) (xy 396.754084 -287.682812) (xy 396.780387 -287.641216)
			(xy 396.813022 -287.604379) (xy 396.851143 -287.573254) (xy 396.893764 -287.548647) (xy 396.93978 -287.531195)
			(xy 396.987999 -287.521351) (xy 397.037174 -287.51937) (xy 397.086029 -287.525302) (xy 397.1333 -287.538994)
			(xy 397.177762 -287.560092) (xy 397.218265 -287.588048) (xy 397.253758 -287.62214) (xy 397.283323 -287.661484)
			(xy 397.306194 -287.705061) (xy 397.321778 -287.751742) (xy 397.329673 -287.800319) (xy 397.330168 -287.824926)
			(xy 397.669016 -287.824926) (xy 397.672976 -287.775872) (xy 397.684753 -287.728088) (xy 397.704044 -287.682812)
			(xy 397.730347 -287.641216) (xy 397.762982 -287.604379) (xy 397.801103 -287.573254) (xy 397.843724 -287.548647)
			(xy 397.88974 -287.531195) (xy 397.937959 -287.521351) (xy 397.987134 -287.51937) (xy 398.035989 -287.525302)
			(xy 398.08326 -287.538994) (xy 398.127722 -287.560092) (xy 398.168225 -287.588048) (xy 398.203718 -287.62214)
			(xy 398.233283 -287.661484) (xy 398.256154 -287.705061) (xy 398.271738 -287.751742) (xy 398.279633 -287.800319)
			(xy 398.280128 -287.824926) (xy 398.279633 -287.849533) (xy 398.271738 -287.89811) (xy 398.256154 -287.944791)
			(xy 398.233283 -287.988368) (xy 398.203718 -288.027712) (xy 398.168225 -288.061804) (xy 398.127722 -288.08976)
			(xy 398.08326 -288.110858) (xy 398.035989 -288.12455) (xy 397.987134 -288.130482) (xy 397.937959 -288.128501)
			(xy 397.88974 -288.118657) (xy 397.843724 -288.101205) (xy 397.801103 -288.076598) (xy 397.762982 -288.045473)
			(xy 397.730347 -288.008636) (xy 397.704044 -287.96704) (xy 397.684753 -287.921764) (xy 397.672976 -287.87398)
			(xy 397.669016 -287.824926) (xy 397.330168 -287.824926) (xy 397.329673 -287.849533) (xy 397.321778 -287.89811)
			(xy 397.306194 -287.944791) (xy 397.283323 -287.988368) (xy 397.253758 -288.027712) (xy 397.218265 -288.061804)
			(xy 397.177762 -288.08976) (xy 397.1333 -288.110858) (xy 397.086029 -288.12455) (xy 397.037174 -288.130482)
			(xy 396.987999 -288.128501) (xy 396.93978 -288.118657) (xy 396.893764 -288.101205) (xy 396.851143 -288.076598)
			(xy 396.813022 -288.045473) (xy 396.780387 -288.008636) (xy 396.754084 -287.96704) (xy 396.734793 -287.921764)
			(xy 396.723016 -287.87398) (xy 396.719056 -287.824926) (xy 396.380208 -287.824926) (xy 396.379713 -287.849533)
			(xy 396.371818 -287.89811) (xy 396.356234 -287.944791) (xy 396.333363 -287.988368) (xy 396.303798 -288.027712)
			(xy 396.268305 -288.061804) (xy 396.227802 -288.08976) (xy 396.18334 -288.110858) (xy 396.136069 -288.12455)
			(xy 396.087214 -288.130482) (xy 396.038039 -288.128501) (xy 395.98982 -288.118657) (xy 395.943804 -288.101205)
			(xy 395.901183 -288.076598) (xy 395.863062 -288.045473) (xy 395.830427 -288.008636) (xy 395.804124 -287.96704)
			(xy 395.784833 -287.921764) (xy 395.773056 -287.87398) (xy 395.769096 -287.824926) (xy 395.430248 -287.824926)
			(xy 395.429753 -287.849533) (xy 395.421858 -287.89811) (xy 395.406274 -287.944791) (xy 395.383403 -287.988368)
			(xy 395.353838 -288.027712) (xy 395.318345 -288.061804) (xy 395.277842 -288.08976) (xy 395.23338 -288.110858)
			(xy 395.186109 -288.12455) (xy 395.137254 -288.130482) (xy 395.088079 -288.128501) (xy 395.03986 -288.118657)
			(xy 394.993844 -288.101205) (xy 394.951223 -288.076598) (xy 394.913102 -288.045473) (xy 394.880467 -288.008636)
			(xy 394.854164 -287.96704) (xy 394.834873 -287.921764) (xy 394.823096 -287.87398) (xy 394.819136 -287.824926)
			(xy 394.480288 -287.824926) (xy 394.479793 -287.849533) (xy 394.471898 -287.89811) (xy 394.456314 -287.944791)
			(xy 394.433443 -287.988368) (xy 394.403878 -288.027712) (xy 394.368385 -288.061804) (xy 394.327882 -288.08976)
			(xy 394.28342 -288.110858) (xy 394.236149 -288.12455) (xy 394.187294 -288.130482) (xy 394.138119 -288.128501)
			(xy 394.0899 -288.118657) (xy 394.043884 -288.101205) (xy 394.001263 -288.076598) (xy 393.963142 -288.045473)
			(xy 393.930507 -288.008636) (xy 393.904204 -287.96704) (xy 393.884913 -287.921764) (xy 393.873136 -287.87398)
			(xy 393.869176 -287.824926) (xy 393.530328 -287.824926) (xy 393.529833 -287.849533) (xy 393.521938 -287.89811)
			(xy 393.506354 -287.944791) (xy 393.483483 -287.988368) (xy 393.453918 -288.027712) (xy 393.418425 -288.061804)
			(xy 393.377922 -288.08976) (xy 393.33346 -288.110858) (xy 393.286189 -288.12455) (xy 393.237334 -288.130482)
			(xy 393.188159 -288.128501) (xy 393.13994 -288.118657) (xy 393.093924 -288.101205) (xy 393.051303 -288.076598)
			(xy 393.013182 -288.045473) (xy 392.980547 -288.008636) (xy 392.954244 -287.96704) (xy 392.934953 -287.921764)
			(xy 392.923176 -287.87398) (xy 392.919216 -287.824926) (xy 389.730234 -287.824926) (xy 389.729739 -287.849533)
			(xy 389.721844 -287.89811) (xy 389.70626 -287.944791) (xy 389.683389 -287.988368) (xy 389.653824 -288.027712)
			(xy 389.618331 -288.061804) (xy 389.577828 -288.08976) (xy 389.533366 -288.110858) (xy 389.486095 -288.12455)
			(xy 389.43724 -288.130482) (xy 389.388065 -288.128501) (xy 389.339846 -288.118657) (xy 389.29383 -288.101205)
			(xy 389.251209 -288.076598) (xy 389.213088 -288.045473) (xy 389.180453 -288.008636) (xy 389.15415 -287.96704)
			(xy 389.134859 -287.921764) (xy 389.123082 -287.87398) (xy 389.119122 -287.824926) (xy 386.880354 -287.824926)
			(xy 386.879859 -287.849533) (xy 386.871964 -287.89811) (xy 386.85638 -287.944791) (xy 386.833509 -287.988368)
			(xy 386.803944 -288.027712) (xy 386.768451 -288.061804) (xy 386.727948 -288.08976) (xy 386.683486 -288.110858)
			(xy 386.636215 -288.12455) (xy 386.58736 -288.130482) (xy 386.538185 -288.128501) (xy 386.489966 -288.118657)
			(xy 386.44395 -288.101205) (xy 386.401329 -288.076598) (xy 386.363208 -288.045473) (xy 386.330573 -288.008636)
			(xy 386.30427 -287.96704) (xy 386.284979 -287.921764) (xy 386.273202 -287.87398) (xy 386.269242 -287.824926)
			(xy 385.93014 -287.824926) (xy 385.929645 -287.849533) (xy 385.92175 -287.89811) (xy 385.906166 -287.944791)
			(xy 385.883295 -287.988368) (xy 385.85373 -288.027712) (xy 385.818237 -288.061804) (xy 385.777734 -288.08976)
			(xy 385.733272 -288.110858) (xy 385.686001 -288.12455) (xy 385.637146 -288.130482) (xy 385.587971 -288.128501)
			(xy 385.539752 -288.118657) (xy 385.493736 -288.101205) (xy 385.451115 -288.076598) (xy 385.412994 -288.045473)
			(xy 385.380359 -288.008636) (xy 385.354056 -287.96704) (xy 385.334765 -287.921764) (xy 385.322988 -287.87398)
			(xy 385.319028 -287.824926) (xy 384.98018 -287.824926) (xy 384.979685 -287.849533) (xy 384.97179 -287.89811)
			(xy 384.956206 -287.944791) (xy 384.933335 -287.988368) (xy 384.90377 -288.027712) (xy 384.868277 -288.061804)
			(xy 384.827774 -288.08976) (xy 384.783312 -288.110858) (xy 384.736041 -288.12455) (xy 384.687186 -288.130482)
			(xy 384.638011 -288.128501) (xy 384.589792 -288.118657) (xy 384.543776 -288.101205) (xy 384.501155 -288.076598)
			(xy 384.463034 -288.045473) (xy 384.430399 -288.008636) (xy 384.404096 -287.96704) (xy 384.384805 -287.921764)
			(xy 384.373028 -287.87398) (xy 384.369068 -287.824926) (xy 384.2512 -287.824926) (xy 384.2512 -288.774886)
			(xy 384.369068 -288.774886) (xy 384.373028 -288.725832) (xy 384.384805 -288.678048) (xy 384.404096 -288.632772)
			(xy 384.430399 -288.591176) (xy 384.463034 -288.554339) (xy 384.501155 -288.523214) (xy 384.543776 -288.498607)
			(xy 384.589792 -288.481155) (xy 384.638011 -288.471311) (xy 384.687186 -288.46933) (xy 384.736041 -288.475262)
			(xy 384.783312 -288.488954) (xy 384.827774 -288.510052) (xy 384.868277 -288.538008) (xy 384.90377 -288.5721)
			(xy 384.933335 -288.611444) (xy 384.956206 -288.655021) (xy 384.97179 -288.701702) (xy 384.979685 -288.750279)
			(xy 384.98018 -288.774886) (xy 385.319028 -288.774886) (xy 385.322988 -288.725832) (xy 385.334765 -288.678048)
			(xy 385.354056 -288.632772) (xy 385.380359 -288.591176) (xy 385.412994 -288.554339) (xy 385.451115 -288.523214)
			(xy 385.493736 -288.498607) (xy 385.539752 -288.481155) (xy 385.587971 -288.471311) (xy 385.637146 -288.46933)
			(xy 385.686001 -288.475262) (xy 385.733272 -288.488954) (xy 385.777734 -288.510052) (xy 385.818237 -288.538008)
			(xy 385.85373 -288.5721) (xy 385.883295 -288.611444) (xy 385.906166 -288.655021) (xy 385.92175 -288.701702)
			(xy 385.929645 -288.750279) (xy 385.93014 -288.774886) (xy 386.269242 -288.774886) (xy 386.273202 -288.725832)
			(xy 386.284979 -288.678048) (xy 386.30427 -288.632772) (xy 386.330573 -288.591176) (xy 386.363208 -288.554339)
			(xy 386.401329 -288.523214) (xy 386.44395 -288.498607) (xy 386.489966 -288.481155) (xy 386.538185 -288.471311)
			(xy 386.58736 -288.46933) (xy 386.636215 -288.475262) (xy 386.683486 -288.488954) (xy 386.727948 -288.510052)
			(xy 386.768451 -288.538008) (xy 386.803944 -288.5721) (xy 386.833509 -288.611444) (xy 386.85638 -288.655021)
			(xy 386.871964 -288.701702) (xy 386.879859 -288.750279) (xy 386.880354 -288.774886) (xy 386.879859 -288.799493)
			(xy 386.871964 -288.84807) (xy 386.85638 -288.894751) (xy 386.833509 -288.938328) (xy 386.803944 -288.977672)
			(xy 386.768451 -289.011764) (xy 386.727948 -289.03972) (xy 386.683486 -289.060818) (xy 386.636215 -289.07451)
			(xy 386.58736 -289.080442) (xy 386.538185 -289.078461) (xy 386.489966 -289.068617) (xy 386.44395 -289.051165)
			(xy 386.401329 -289.026558) (xy 386.363208 -288.995433) (xy 386.330573 -288.958596) (xy 386.30427 -288.917)
			(xy 386.284979 -288.871724) (xy 386.273202 -288.82394) (xy 386.269242 -288.774886) (xy 385.93014 -288.774886)
			(xy 385.929645 -288.799493) (xy 385.92175 -288.84807) (xy 385.906166 -288.894751) (xy 385.883295 -288.938328)
			(xy 385.85373 -288.977672) (xy 385.818237 -289.011764) (xy 385.777734 -289.03972) (xy 385.733272 -289.060818)
			(xy 385.686001 -289.07451) (xy 385.637146 -289.080442) (xy 385.587971 -289.078461) (xy 385.539752 -289.068617)
			(xy 385.493736 -289.051165) (xy 385.451115 -289.026558) (xy 385.412994 -288.995433) (xy 385.380359 -288.958596)
			(xy 385.354056 -288.917) (xy 385.334765 -288.871724) (xy 385.322988 -288.82394) (xy 385.319028 -288.774886)
			(xy 384.98018 -288.774886) (xy 384.979685 -288.799493) (xy 384.97179 -288.84807) (xy 384.956206 -288.894751)
			(xy 384.933335 -288.938328) (xy 384.90377 -288.977672) (xy 384.868277 -289.011764) (xy 384.827774 -289.03972)
			(xy 384.783312 -289.060818) (xy 384.736041 -289.07451) (xy 384.687186 -289.080442) (xy 384.638011 -289.078461)
			(xy 384.589792 -289.068617) (xy 384.543776 -289.051165) (xy 384.501155 -289.026558) (xy 384.463034 -288.995433)
			(xy 384.430399 -288.958596) (xy 384.404096 -288.917) (xy 384.384805 -288.871724) (xy 384.373028 -288.82394)
			(xy 384.369068 -288.774886) (xy 384.2512 -288.774886) (xy 384.2512 -289.724846) (xy 384.369068 -289.724846)
			(xy 384.373028 -289.675792) (xy 384.384805 -289.628008) (xy 384.404096 -289.582732) (xy 384.430399 -289.541136)
			(xy 384.463034 -289.504299) (xy 384.501155 -289.473174) (xy 384.543776 -289.448567) (xy 384.589792 -289.431115)
			(xy 384.638011 -289.421271) (xy 384.687186 -289.41929) (xy 384.736041 -289.425222) (xy 384.783312 -289.438914)
			(xy 384.827774 -289.460012) (xy 384.868277 -289.487968) (xy 384.90377 -289.52206) (xy 384.933335 -289.561404)
			(xy 384.956206 -289.604981) (xy 384.97179 -289.651662) (xy 384.979685 -289.700239) (xy 384.98018 -289.724846)
			(xy 385.319028 -289.724846) (xy 385.322988 -289.675792) (xy 385.334765 -289.628008) (xy 385.354056 -289.582732)
			(xy 385.380359 -289.541136) (xy 385.412994 -289.504299) (xy 385.451115 -289.473174) (xy 385.493736 -289.448567)
			(xy 385.539752 -289.431115) (xy 385.587971 -289.421271) (xy 385.637146 -289.41929) (xy 385.686001 -289.425222)
			(xy 385.733272 -289.438914) (xy 385.777734 -289.460012) (xy 385.818237 -289.487968) (xy 385.85373 -289.52206)
			(xy 385.883295 -289.561404) (xy 385.906166 -289.604981) (xy 385.92175 -289.651662) (xy 385.929645 -289.700239)
			(xy 385.93014 -289.724846) (xy 386.269242 -289.724846) (xy 386.273202 -289.675792) (xy 386.284979 -289.628008)
			(xy 386.30427 -289.582732) (xy 386.330573 -289.541136) (xy 386.363208 -289.504299) (xy 386.401329 -289.473174)
			(xy 386.44395 -289.448567) (xy 386.489966 -289.431115) (xy 386.538185 -289.421271) (xy 386.58736 -289.41929)
			(xy 386.636215 -289.425222) (xy 386.683486 -289.438914) (xy 386.727948 -289.460012) (xy 386.768451 -289.487968)
			(xy 386.803944 -289.52206) (xy 386.833509 -289.561404) (xy 386.85638 -289.604981) (xy 386.871964 -289.651662)
			(xy 386.879859 -289.700239) (xy 386.880354 -289.724846) (xy 387.219202 -289.724846) (xy 387.223162 -289.675792)
			(xy 387.234939 -289.628008) (xy 387.25423 -289.582732) (xy 387.280533 -289.541136) (xy 387.313168 -289.504299)
			(xy 387.351289 -289.473174) (xy 387.39391 -289.448567) (xy 387.439926 -289.431115) (xy 387.488145 -289.421271)
			(xy 387.53732 -289.41929) (xy 387.586175 -289.425222) (xy 387.633446 -289.438914) (xy 387.677908 -289.460012)
			(xy 387.718411 -289.487968) (xy 387.753904 -289.52206) (xy 387.783469 -289.561404) (xy 387.80634 -289.604981)
			(xy 387.821924 -289.651662) (xy 387.829819 -289.700239) (xy 387.830314 -289.724846) (xy 388.169162 -289.724846)
			(xy 388.173122 -289.675792) (xy 388.184899 -289.628008) (xy 388.20419 -289.582732) (xy 388.230493 -289.541136)
			(xy 388.263128 -289.504299) (xy 388.301249 -289.473174) (xy 388.34387 -289.448567) (xy 388.389886 -289.431115)
			(xy 388.438105 -289.421271) (xy 388.48728 -289.41929) (xy 388.536135 -289.425222) (xy 388.583406 -289.438914)
			(xy 388.627868 -289.460012) (xy 388.668371 -289.487968) (xy 388.703864 -289.52206) (xy 388.733429 -289.561404)
			(xy 388.7563 -289.604981) (xy 388.771884 -289.651662) (xy 388.779779 -289.700239) (xy 388.780274 -289.724846)
			(xy 389.119122 -289.724846) (xy 389.123082 -289.675792) (xy 389.134859 -289.628008) (xy 389.15415 -289.582732)
			(xy 389.180453 -289.541136) (xy 389.213088 -289.504299) (xy 389.251209 -289.473174) (xy 389.29383 -289.448567)
			(xy 389.339846 -289.431115) (xy 389.388065 -289.421271) (xy 389.43724 -289.41929) (xy 389.486095 -289.425222)
			(xy 389.533366 -289.438914) (xy 389.577828 -289.460012) (xy 389.618331 -289.487968) (xy 389.653824 -289.52206)
			(xy 389.683389 -289.561404) (xy 389.70626 -289.604981) (xy 389.721844 -289.651662) (xy 389.729739 -289.700239)
			(xy 389.730234 -289.724846) (xy 390.069082 -289.724846) (xy 390.073042 -289.675792) (xy 390.084819 -289.628008)
			(xy 390.10411 -289.582732) (xy 390.130413 -289.541136) (xy 390.163048 -289.504299) (xy 390.201169 -289.473174)
			(xy 390.24379 -289.448567) (xy 390.289806 -289.431115) (xy 390.338025 -289.421271) (xy 390.3872 -289.41929)
			(xy 390.436055 -289.425222) (xy 390.483326 -289.438914) (xy 390.527788 -289.460012) (xy 390.568291 -289.487968)
			(xy 390.603784 -289.52206) (xy 390.633349 -289.561404) (xy 390.65622 -289.604981) (xy 390.671804 -289.651662)
			(xy 390.679699 -289.700239) (xy 390.680194 -289.724846) (xy 390.679699 -289.749453) (xy 390.671804 -289.79803)
			(xy 390.65622 -289.844711) (xy 390.633349 -289.888288) (xy 390.603784 -289.927632) (xy 390.568291 -289.961724)
			(xy 390.527788 -289.98968) (xy 390.483326 -290.010778) (xy 390.436055 -290.02447) (xy 390.3872 -290.030402)
			(xy 390.338025 -290.028421) (xy 390.289806 -290.018577) (xy 390.24379 -290.001125) (xy 390.201169 -289.976518)
			(xy 390.163048 -289.945393) (xy 390.130413 -289.908556) (xy 390.10411 -289.86696) (xy 390.084819 -289.821684)
			(xy 390.073042 -289.7739) (xy 390.069082 -289.724846) (xy 389.730234 -289.724846) (xy 389.729739 -289.749453)
			(xy 389.721844 -289.79803) (xy 389.70626 -289.844711) (xy 389.683389 -289.888288) (xy 389.653824 -289.927632)
			(xy 389.618331 -289.961724) (xy 389.577828 -289.98968) (xy 389.533366 -290.010778) (xy 389.486095 -290.02447)
			(xy 389.43724 -290.030402) (xy 389.388065 -290.028421) (xy 389.339846 -290.018577) (xy 389.29383 -290.001125)
			(xy 389.251209 -289.976518) (xy 389.213088 -289.945393) (xy 389.180453 -289.908556) (xy 389.15415 -289.86696)
			(xy 389.134859 -289.821684) (xy 389.123082 -289.7739) (xy 389.119122 -289.724846) (xy 388.780274 -289.724846)
			(xy 388.779779 -289.749453) (xy 388.771884 -289.79803) (xy 388.7563 -289.844711) (xy 388.733429 -289.888288)
			(xy 388.703864 -289.927632) (xy 388.668371 -289.961724) (xy 388.627868 -289.98968) (xy 388.583406 -290.010778)
			(xy 388.536135 -290.02447) (xy 388.48728 -290.030402) (xy 388.438105 -290.028421) (xy 388.389886 -290.018577)
			(xy 388.34387 -290.001125) (xy 388.301249 -289.976518) (xy 388.263128 -289.945393) (xy 388.230493 -289.908556)
			(xy 388.20419 -289.86696) (xy 388.184899 -289.821684) (xy 388.173122 -289.7739) (xy 388.169162 -289.724846)
			(xy 387.830314 -289.724846) (xy 387.829819 -289.749453) (xy 387.821924 -289.79803) (xy 387.80634 -289.844711)
			(xy 387.783469 -289.888288) (xy 387.753904 -289.927632) (xy 387.718411 -289.961724) (xy 387.677908 -289.98968)
			(xy 387.633446 -290.010778) (xy 387.586175 -290.02447) (xy 387.53732 -290.030402) (xy 387.488145 -290.028421)
			(xy 387.439926 -290.018577) (xy 387.39391 -290.001125) (xy 387.351289 -289.976518) (xy 387.313168 -289.945393)
			(xy 387.280533 -289.908556) (xy 387.25423 -289.86696) (xy 387.234939 -289.821684) (xy 387.223162 -289.7739)
			(xy 387.219202 -289.724846) (xy 386.880354 -289.724846) (xy 386.879859 -289.749453) (xy 386.871964 -289.79803)
			(xy 386.85638 -289.844711) (xy 386.833509 -289.888288) (xy 386.803944 -289.927632) (xy 386.768451 -289.961724)
			(xy 386.727948 -289.98968) (xy 386.683486 -290.010778) (xy 386.636215 -290.02447) (xy 386.58736 -290.030402)
			(xy 386.538185 -290.028421) (xy 386.489966 -290.018577) (xy 386.44395 -290.001125) (xy 386.401329 -289.976518)
			(xy 386.363208 -289.945393) (xy 386.330573 -289.908556) (xy 386.30427 -289.86696) (xy 386.284979 -289.821684)
			(xy 386.273202 -289.7739) (xy 386.269242 -289.724846) (xy 385.93014 -289.724846) (xy 385.929645 -289.749453)
			(xy 385.92175 -289.79803) (xy 385.906166 -289.844711) (xy 385.883295 -289.888288) (xy 385.85373 -289.927632)
			(xy 385.818237 -289.961724) (xy 385.777734 -289.98968) (xy 385.733272 -290.010778) (xy 385.686001 -290.02447)
			(xy 385.637146 -290.030402) (xy 385.587971 -290.028421) (xy 385.539752 -290.018577) (xy 385.493736 -290.001125)
			(xy 385.451115 -289.976518) (xy 385.412994 -289.945393) (xy 385.380359 -289.908556) (xy 385.354056 -289.86696)
			(xy 385.334765 -289.821684) (xy 385.322988 -289.7739) (xy 385.319028 -289.724846) (xy 384.98018 -289.724846)
			(xy 384.979685 -289.749453) (xy 384.97179 -289.79803) (xy 384.956206 -289.844711) (xy 384.933335 -289.888288)
			(xy 384.90377 -289.927632) (xy 384.868277 -289.961724) (xy 384.827774 -289.98968) (xy 384.783312 -290.010778)
			(xy 384.736041 -290.02447) (xy 384.687186 -290.030402) (xy 384.638011 -290.028421) (xy 384.589792 -290.018577)
			(xy 384.543776 -290.001125) (xy 384.501155 -289.976518) (xy 384.463034 -289.945393) (xy 384.430399 -289.908556)
			(xy 384.404096 -289.86696) (xy 384.384805 -289.821684) (xy 384.373028 -289.7739) (xy 384.369068 -289.724846)
			(xy 384.2512 -289.724846) (xy 384.2512 -290.674806) (xy 384.369068 -290.674806) (xy 384.373028 -290.625752)
			(xy 384.384805 -290.577968) (xy 384.404096 -290.532692) (xy 384.430399 -290.491096) (xy 384.463034 -290.454259)
			(xy 384.501155 -290.423134) (xy 384.543776 -290.398527) (xy 384.589792 -290.381075) (xy 384.638011 -290.371231)
			(xy 384.687186 -290.36925) (xy 384.736041 -290.375182) (xy 384.783312 -290.388874) (xy 384.827774 -290.409972)
			(xy 384.868277 -290.437928) (xy 384.90377 -290.47202) (xy 384.933335 -290.511364) (xy 384.956206 -290.554941)
			(xy 384.97179 -290.601622) (xy 384.979685 -290.650199) (xy 384.98018 -290.674806) (xy 385.319028 -290.674806)
			(xy 385.322988 -290.625752) (xy 385.334765 -290.577968) (xy 385.354056 -290.532692) (xy 385.380359 -290.491096)
			(xy 385.412994 -290.454259) (xy 385.451115 -290.423134) (xy 385.493736 -290.398527) (xy 385.539752 -290.381075)
			(xy 385.587971 -290.371231) (xy 385.637146 -290.36925) (xy 385.686001 -290.375182) (xy 385.733272 -290.388874)
			(xy 385.777734 -290.409972) (xy 385.818237 -290.437928) (xy 385.85373 -290.47202) (xy 385.883295 -290.511364)
			(xy 385.906166 -290.554941) (xy 385.92175 -290.601622) (xy 385.929645 -290.650199) (xy 385.93014 -290.674806)
			(xy 386.269242 -290.674806) (xy 386.273202 -290.625752) (xy 386.284979 -290.577968) (xy 386.30427 -290.532692)
			(xy 386.330573 -290.491096) (xy 386.363208 -290.454259) (xy 386.401329 -290.423134) (xy 386.44395 -290.398527)
			(xy 386.489966 -290.381075) (xy 386.538185 -290.371231) (xy 386.58736 -290.36925) (xy 386.636215 -290.375182)
			(xy 386.683486 -290.388874) (xy 386.727948 -290.409972) (xy 386.768451 -290.437928) (xy 386.803944 -290.47202)
			(xy 386.833509 -290.511364) (xy 386.85638 -290.554941) (xy 386.871964 -290.601622) (xy 386.879859 -290.650199)
			(xy 386.880354 -290.674806) (xy 389.119122 -290.674806) (xy 389.123082 -290.625752) (xy 389.134859 -290.577968)
			(xy 389.15415 -290.532692) (xy 389.180453 -290.491096) (xy 389.213088 -290.454259) (xy 389.251209 -290.423134)
			(xy 389.29383 -290.398527) (xy 389.339846 -290.381075) (xy 389.388065 -290.371231) (xy 389.43724 -290.36925)
			(xy 389.486095 -290.375182) (xy 389.533366 -290.388874) (xy 389.577828 -290.409972) (xy 389.618331 -290.437928)
			(xy 389.653824 -290.47202) (xy 389.683389 -290.511364) (xy 389.70626 -290.554941) (xy 389.721844 -290.601622)
			(xy 389.729739 -290.650199) (xy 389.730234 -290.674806) (xy 390.069082 -290.674806) (xy 390.073042 -290.625752)
			(xy 390.084819 -290.577968) (xy 390.10411 -290.532692) (xy 390.130413 -290.491096) (xy 390.163048 -290.454259)
			(xy 390.201169 -290.423134) (xy 390.24379 -290.398527) (xy 390.289806 -290.381075) (xy 390.338025 -290.371231)
			(xy 390.3872 -290.36925) (xy 390.436055 -290.375182) (xy 390.483326 -290.388874) (xy 390.527788 -290.409972)
			(xy 390.568291 -290.437928) (xy 390.603784 -290.47202) (xy 390.633349 -290.511364) (xy 390.65622 -290.554941)
			(xy 390.671804 -290.601622) (xy 390.679699 -290.650199) (xy 390.680194 -290.674806) (xy 390.679699 -290.699413)
			(xy 390.671804 -290.74799) (xy 390.65622 -290.794671) (xy 390.633349 -290.838248) (xy 390.603784 -290.877592)
			(xy 390.568291 -290.911684) (xy 390.527788 -290.93964) (xy 390.483326 -290.960738) (xy 390.436055 -290.97443)
			(xy 390.3872 -290.980362) (xy 390.338025 -290.978381) (xy 390.289806 -290.968537) (xy 390.24379 -290.951085)
			(xy 390.201169 -290.926478) (xy 390.163048 -290.895353) (xy 390.130413 -290.858516) (xy 390.10411 -290.81692)
			(xy 390.084819 -290.771644) (xy 390.073042 -290.72386) (xy 390.069082 -290.674806) (xy 389.730234 -290.674806)
			(xy 389.729739 -290.699413) (xy 389.721844 -290.74799) (xy 389.70626 -290.794671) (xy 389.683389 -290.838248)
			(xy 389.653824 -290.877592) (xy 389.618331 -290.911684) (xy 389.577828 -290.93964) (xy 389.533366 -290.960738)
			(xy 389.486095 -290.97443) (xy 389.43724 -290.980362) (xy 389.388065 -290.978381) (xy 389.339846 -290.968537)
			(xy 389.29383 -290.951085) (xy 389.251209 -290.926478) (xy 389.213088 -290.895353) (xy 389.180453 -290.858516)
			(xy 389.15415 -290.81692) (xy 389.134859 -290.771644) (xy 389.123082 -290.72386) (xy 389.119122 -290.674806)
			(xy 386.880354 -290.674806) (xy 386.879859 -290.699413) (xy 386.871964 -290.74799) (xy 386.85638 -290.794671)
			(xy 386.833509 -290.838248) (xy 386.803944 -290.877592) (xy 386.768451 -290.911684) (xy 386.727948 -290.93964)
			(xy 386.683486 -290.960738) (xy 386.636215 -290.97443) (xy 386.58736 -290.980362) (xy 386.538185 -290.978381)
			(xy 386.489966 -290.968537) (xy 386.44395 -290.951085) (xy 386.401329 -290.926478) (xy 386.363208 -290.895353)
			(xy 386.330573 -290.858516) (xy 386.30427 -290.81692) (xy 386.284979 -290.771644) (xy 386.273202 -290.72386)
			(xy 386.269242 -290.674806) (xy 385.93014 -290.674806) (xy 385.929645 -290.699413) (xy 385.92175 -290.74799)
			(xy 385.906166 -290.794671) (xy 385.883295 -290.838248) (xy 385.85373 -290.877592) (xy 385.818237 -290.911684)
			(xy 385.777734 -290.93964) (xy 385.733272 -290.960738) (xy 385.686001 -290.97443) (xy 385.637146 -290.980362)
			(xy 385.587971 -290.978381) (xy 385.539752 -290.968537) (xy 385.493736 -290.951085) (xy 385.451115 -290.926478)
			(xy 385.412994 -290.895353) (xy 385.380359 -290.858516) (xy 385.354056 -290.81692) (xy 385.334765 -290.771644)
			(xy 385.322988 -290.72386) (xy 385.319028 -290.674806) (xy 384.98018 -290.674806) (xy 384.979685 -290.699413)
			(xy 384.97179 -290.74799) (xy 384.956206 -290.794671) (xy 384.933335 -290.838248) (xy 384.90377 -290.877592)
			(xy 384.868277 -290.911684) (xy 384.827774 -290.93964) (xy 384.783312 -290.960738) (xy 384.736041 -290.97443)
			(xy 384.687186 -290.980362) (xy 384.638011 -290.978381) (xy 384.589792 -290.968537) (xy 384.543776 -290.951085)
			(xy 384.501155 -290.926478) (xy 384.463034 -290.895353) (xy 384.430399 -290.858516) (xy 384.404096 -290.81692)
			(xy 384.384805 -290.771644) (xy 384.373028 -290.72386) (xy 384.369068 -290.674806) (xy 384.2512 -290.674806)
			(xy 384.2512 -291.624766) (xy 384.369068 -291.624766) (xy 384.373028 -291.575712) (xy 384.384805 -291.527928)
			(xy 384.404096 -291.482652) (xy 384.430399 -291.441056) (xy 384.463034 -291.404219) (xy 384.501155 -291.373094)
			(xy 384.543776 -291.348487) (xy 384.589792 -291.331035) (xy 384.638011 -291.321191) (xy 384.687186 -291.31921)
			(xy 384.736041 -291.325142) (xy 384.783312 -291.338834) (xy 384.827774 -291.359932) (xy 384.868277 -291.387888)
			(xy 384.90377 -291.42198) (xy 384.933335 -291.461324) (xy 384.956206 -291.504901) (xy 384.97179 -291.551582)
			(xy 384.979685 -291.600159) (xy 384.98018 -291.624766) (xy 385.319028 -291.624766) (xy 385.322988 -291.575712)
			(xy 385.334765 -291.527928) (xy 385.354056 -291.482652) (xy 385.380359 -291.441056) (xy 385.412994 -291.404219)
			(xy 385.451115 -291.373094) (xy 385.493736 -291.348487) (xy 385.539752 -291.331035) (xy 385.587971 -291.321191)
			(xy 385.637146 -291.31921) (xy 385.686001 -291.325142) (xy 385.733272 -291.338834) (xy 385.777734 -291.359932)
			(xy 385.818237 -291.387888) (xy 385.85373 -291.42198) (xy 385.883295 -291.461324) (xy 385.906166 -291.504901)
			(xy 385.92175 -291.551582) (xy 385.929645 -291.600159) (xy 385.93014 -291.624766) (xy 386.269242 -291.624766)
			(xy 386.273202 -291.575712) (xy 386.284979 -291.527928) (xy 386.30427 -291.482652) (xy 386.330573 -291.441056)
			(xy 386.363208 -291.404219) (xy 386.401329 -291.373094) (xy 386.44395 -291.348487) (xy 386.489966 -291.331035)
			(xy 386.538185 -291.321191) (xy 386.58736 -291.31921) (xy 386.636215 -291.325142) (xy 386.683486 -291.338834)
			(xy 386.727948 -291.359932) (xy 386.768451 -291.387888) (xy 386.803944 -291.42198) (xy 386.833509 -291.461324)
			(xy 386.85638 -291.504901) (xy 386.871964 -291.551582) (xy 386.879859 -291.600159) (xy 386.880354 -291.624766)
			(xy 389.119122 -291.624766) (xy 389.123082 -291.575712) (xy 389.134859 -291.527928) (xy 389.15415 -291.482652)
			(xy 389.180453 -291.441056) (xy 389.213088 -291.404219) (xy 389.251209 -291.373094) (xy 389.29383 -291.348487)
			(xy 389.339846 -291.331035) (xy 389.388065 -291.321191) (xy 389.43724 -291.31921) (xy 389.486095 -291.325142)
			(xy 389.533366 -291.338834) (xy 389.577828 -291.359932) (xy 389.618331 -291.387888) (xy 389.653824 -291.42198)
			(xy 389.683389 -291.461324) (xy 389.70626 -291.504901) (xy 389.721844 -291.551582) (xy 389.729739 -291.600159)
			(xy 389.730234 -291.624766) (xy 390.069082 -291.624766) (xy 390.073042 -291.575712) (xy 390.084819 -291.527928)
			(xy 390.10411 -291.482652) (xy 390.130413 -291.441056) (xy 390.163048 -291.404219) (xy 390.201169 -291.373094)
			(xy 390.24379 -291.348487) (xy 390.289806 -291.331035) (xy 390.338025 -291.321191) (xy 390.3872 -291.31921)
			(xy 390.436055 -291.325142) (xy 390.483326 -291.338834) (xy 390.527788 -291.359932) (xy 390.568291 -291.387888)
			(xy 390.603784 -291.42198) (xy 390.633349 -291.461324) (xy 390.65622 -291.504901) (xy 390.671804 -291.551582)
			(xy 390.679699 -291.600159) (xy 390.680194 -291.624766) (xy 390.679699 -291.649373) (xy 390.671804 -291.69795)
			(xy 390.65622 -291.744631) (xy 390.633349 -291.788208) (xy 390.603784 -291.827552) (xy 390.568291 -291.861644)
			(xy 390.527788 -291.8896) (xy 390.483326 -291.910698) (xy 390.436055 -291.92439) (xy 390.3872 -291.930322)
			(xy 390.338025 -291.928341) (xy 390.289806 -291.918497) (xy 390.24379 -291.901045) (xy 390.201169 -291.876438)
			(xy 390.163048 -291.845313) (xy 390.130413 -291.808476) (xy 390.10411 -291.76688) (xy 390.084819 -291.721604)
			(xy 390.073042 -291.67382) (xy 390.069082 -291.624766) (xy 389.730234 -291.624766) (xy 389.729739 -291.649373)
			(xy 389.721844 -291.69795) (xy 389.70626 -291.744631) (xy 389.683389 -291.788208) (xy 389.653824 -291.827552)
			(xy 389.618331 -291.861644) (xy 389.577828 -291.8896) (xy 389.533366 -291.910698) (xy 389.486095 -291.92439)
			(xy 389.43724 -291.930322) (xy 389.388065 -291.928341) (xy 389.339846 -291.918497) (xy 389.29383 -291.901045)
			(xy 389.251209 -291.876438) (xy 389.213088 -291.845313) (xy 389.180453 -291.808476) (xy 389.15415 -291.76688)
			(xy 389.134859 -291.721604) (xy 389.123082 -291.67382) (xy 389.119122 -291.624766) (xy 386.880354 -291.624766)
			(xy 386.879859 -291.649373) (xy 386.871964 -291.69795) (xy 386.85638 -291.744631) (xy 386.833509 -291.788208)
			(xy 386.803944 -291.827552) (xy 386.768451 -291.861644) (xy 386.727948 -291.8896) (xy 386.683486 -291.910698)
			(xy 386.636215 -291.92439) (xy 386.58736 -291.930322) (xy 386.538185 -291.928341) (xy 386.489966 -291.918497)
			(xy 386.44395 -291.901045) (xy 386.401329 -291.876438) (xy 386.363208 -291.845313) (xy 386.330573 -291.808476)
			(xy 386.30427 -291.76688) (xy 386.284979 -291.721604) (xy 386.273202 -291.67382) (xy 386.269242 -291.624766)
			(xy 385.93014 -291.624766) (xy 385.929645 -291.649373) (xy 385.92175 -291.69795) (xy 385.906166 -291.744631)
			(xy 385.883295 -291.788208) (xy 385.85373 -291.827552) (xy 385.818237 -291.861644) (xy 385.777734 -291.8896)
			(xy 385.733272 -291.910698) (xy 385.686001 -291.92439) (xy 385.637146 -291.930322) (xy 385.587971 -291.928341)
			(xy 385.539752 -291.918497) (xy 385.493736 -291.901045) (xy 385.451115 -291.876438) (xy 385.412994 -291.845313)
			(xy 385.380359 -291.808476) (xy 385.354056 -291.76688) (xy 385.334765 -291.721604) (xy 385.322988 -291.67382)
			(xy 385.319028 -291.624766) (xy 384.98018 -291.624766) (xy 384.979685 -291.649373) (xy 384.97179 -291.69795)
			(xy 384.956206 -291.744631) (xy 384.933335 -291.788208) (xy 384.90377 -291.827552) (xy 384.868277 -291.861644)
			(xy 384.827774 -291.8896) (xy 384.783312 -291.910698) (xy 384.736041 -291.92439) (xy 384.687186 -291.930322)
			(xy 384.638011 -291.928341) (xy 384.589792 -291.918497) (xy 384.543776 -291.901045) (xy 384.501155 -291.876438)
			(xy 384.463034 -291.845313) (xy 384.430399 -291.808476) (xy 384.404096 -291.76688) (xy 384.384805 -291.721604)
			(xy 384.373028 -291.67382) (xy 384.369068 -291.624766) (xy 384.2512 -291.624766) (xy 384.2512 -292.57498)
			(xy 384.369068 -292.57498) (xy 384.373028 -292.525926) (xy 384.384805 -292.478142) (xy 384.404096 -292.432866)
			(xy 384.430399 -292.39127) (xy 384.463034 -292.354433) (xy 384.501155 -292.323308) (xy 384.543776 -292.298701)
			(xy 384.589792 -292.281249) (xy 384.638011 -292.271405) (xy 384.687186 -292.269424) (xy 384.736041 -292.275356)
			(xy 384.783312 -292.289048) (xy 384.827774 -292.310146) (xy 384.868277 -292.338102) (xy 384.90377 -292.372194)
			(xy 384.933335 -292.411538) (xy 384.956206 -292.455115) (xy 384.97179 -292.501796) (xy 384.979685 -292.550373)
			(xy 384.98018 -292.57498) (xy 385.319028 -292.57498) (xy 385.322988 -292.525926) (xy 385.334765 -292.478142)
			(xy 385.354056 -292.432866) (xy 385.380359 -292.39127) (xy 385.412994 -292.354433) (xy 385.451115 -292.323308)
			(xy 385.493736 -292.298701) (xy 385.539752 -292.281249) (xy 385.587971 -292.271405) (xy 385.637146 -292.269424)
			(xy 385.686001 -292.275356) (xy 385.733272 -292.289048) (xy 385.777734 -292.310146) (xy 385.818237 -292.338102)
			(xy 385.85373 -292.372194) (xy 385.883295 -292.411538) (xy 385.906166 -292.455115) (xy 385.92175 -292.501796)
			(xy 385.929645 -292.550373) (xy 385.93014 -292.57498) (xy 386.269242 -292.57498) (xy 386.273202 -292.525926)
			(xy 386.284979 -292.478142) (xy 386.30427 -292.432866) (xy 386.330573 -292.39127) (xy 386.363208 -292.354433)
			(xy 386.401329 -292.323308) (xy 386.44395 -292.298701) (xy 386.489966 -292.281249) (xy 386.538185 -292.271405)
			(xy 386.58736 -292.269424) (xy 386.636215 -292.275356) (xy 386.683486 -292.289048) (xy 386.727948 -292.310146)
			(xy 386.768451 -292.338102) (xy 386.803944 -292.372194) (xy 386.833509 -292.411538) (xy 386.85638 -292.455115)
			(xy 386.871964 -292.501796) (xy 386.879859 -292.550373) (xy 386.880349 -292.574726) (xy 387.219202 -292.574726)
			(xy 387.223162 -292.525672) (xy 387.234939 -292.477888) (xy 387.25423 -292.432612) (xy 387.280533 -292.391016)
			(xy 387.313168 -292.354179) (xy 387.351289 -292.323054) (xy 387.39391 -292.298447) (xy 387.439926 -292.280995)
			(xy 387.488145 -292.271151) (xy 387.53732 -292.26917) (xy 387.586175 -292.275102) (xy 387.633446 -292.288794)
			(xy 387.677908 -292.309892) (xy 387.718411 -292.337848) (xy 387.753904 -292.37194) (xy 387.783469 -292.411284)
			(xy 387.80634 -292.454861) (xy 387.821924 -292.501542) (xy 387.829819 -292.550119) (xy 387.830314 -292.574726)
			(xy 388.169162 -292.574726) (xy 388.173122 -292.525672) (xy 388.184899 -292.477888) (xy 388.20419 -292.432612)
			(xy 388.230493 -292.391016) (xy 388.263128 -292.354179) (xy 388.301249 -292.323054) (xy 388.34387 -292.298447)
			(xy 388.389886 -292.280995) (xy 388.438105 -292.271151) (xy 388.48728 -292.26917) (xy 388.536135 -292.275102)
			(xy 388.583406 -292.288794) (xy 388.627868 -292.309892) (xy 388.668371 -292.337848) (xy 388.703864 -292.37194)
			(xy 388.733429 -292.411284) (xy 388.7563 -292.454861) (xy 388.771884 -292.501542) (xy 388.779779 -292.550119)
			(xy 388.780274 -292.574726) (xy 388.780269 -292.57498) (xy 389.119122 -292.57498) (xy 389.123082 -292.525926)
			(xy 389.134859 -292.478142) (xy 389.15415 -292.432866) (xy 389.180453 -292.39127) (xy 389.213088 -292.354433)
			(xy 389.251209 -292.323308) (xy 389.29383 -292.298701) (xy 389.339846 -292.281249) (xy 389.388065 -292.271405)
			(xy 389.43724 -292.269424) (xy 389.486095 -292.275356) (xy 389.533366 -292.289048) (xy 389.577828 -292.310146)
			(xy 389.618331 -292.338102) (xy 389.653824 -292.372194) (xy 389.683389 -292.411538) (xy 389.70626 -292.455115)
			(xy 389.721844 -292.501796) (xy 389.729739 -292.550373) (xy 389.730234 -292.57498) (xy 389.729739 -292.599587)
			(xy 389.729407 -292.601629) (xy 390.019276 -292.601629) (xy 390.019276 -292.548331) (xy 390.027219 -292.495627)
			(xy 390.042929 -292.444697) (xy 390.066055 -292.396676) (xy 390.096079 -292.352639) (xy 390.132331 -292.313568)
			(xy 390.174002 -292.280337) (xy 390.22016 -292.253688) (xy 390.269774 -292.234216) (xy 390.321736 -292.222356)
			(xy 390.374886 -292.218373) (xy 390.428036 -292.222356) (xy 390.479998 -292.234216) (xy 390.529612 -292.253688)
			(xy 390.57577 -292.280337) (xy 390.617441 -292.313568) (xy 390.653693 -292.352639) (xy 390.683717 -292.396676)
			(xy 390.706843 -292.444697) (xy 390.722553 -292.495627) (xy 390.730496 -292.548331) (xy 390.730994 -292.57498)
			(xy 390.730496 -292.601629) (xy 390.722553 -292.654333) (xy 390.706843 -292.705263) (xy 390.683717 -292.753284)
			(xy 390.653693 -292.797321) (xy 390.617441 -292.836392) (xy 390.57577 -292.869623) (xy 390.529612 -292.896272)
			(xy 390.479998 -292.915744) (xy 390.428036 -292.927604) (xy 390.374886 -292.931588) (xy 390.321736 -292.927604)
			(xy 390.269774 -292.915744) (xy 390.22016 -292.896272) (xy 390.174002 -292.869623) (xy 390.132331 -292.836392)
			(xy 390.096079 -292.797321) (xy 390.066055 -292.753284) (xy 390.042929 -292.705263) (xy 390.027219 -292.654333)
			(xy 390.019276 -292.601629) (xy 389.729407 -292.601629) (xy 389.721844 -292.648164) (xy 389.70626 -292.694845)
			(xy 389.683389 -292.738422) (xy 389.653824 -292.777766) (xy 389.618331 -292.811858) (xy 389.577828 -292.839814)
			(xy 389.533366 -292.860912) (xy 389.486095 -292.874604) (xy 389.43724 -292.880536) (xy 389.388065 -292.878555)
			(xy 389.339846 -292.868711) (xy 389.29383 -292.851259) (xy 389.251209 -292.826652) (xy 389.213088 -292.795527)
			(xy 389.180453 -292.75869) (xy 389.15415 -292.717094) (xy 389.134859 -292.671818) (xy 389.123082 -292.624034)
			(xy 389.119122 -292.57498) (xy 388.780269 -292.57498) (xy 388.779779 -292.599333) (xy 388.771884 -292.64791)
			(xy 388.7563 -292.694591) (xy 388.733429 -292.738168) (xy 388.703864 -292.777512) (xy 388.668371 -292.811604)
			(xy 388.627868 -292.83956) (xy 388.583406 -292.860658) (xy 388.536135 -292.87435) (xy 388.48728 -292.880282)
			(xy 388.438105 -292.878301) (xy 388.389886 -292.868457) (xy 388.34387 -292.851005) (xy 388.301249 -292.826398)
			(xy 388.263128 -292.795273) (xy 388.230493 -292.758436) (xy 388.20419 -292.71684) (xy 388.184899 -292.671564)
			(xy 388.173122 -292.62378) (xy 388.169162 -292.574726) (xy 387.830314 -292.574726) (xy 387.829819 -292.599333)
			(xy 387.821924 -292.64791) (xy 387.80634 -292.694591) (xy 387.783469 -292.738168) (xy 387.753904 -292.777512)
			(xy 387.718411 -292.811604) (xy 387.677908 -292.83956) (xy 387.633446 -292.860658) (xy 387.586175 -292.87435)
			(xy 387.53732 -292.880282) (xy 387.488145 -292.878301) (xy 387.439926 -292.868457) (xy 387.39391 -292.851005)
			(xy 387.351289 -292.826398) (xy 387.313168 -292.795273) (xy 387.280533 -292.758436) (xy 387.25423 -292.71684)
			(xy 387.234939 -292.671564) (xy 387.223162 -292.62378) (xy 387.219202 -292.574726) (xy 386.880349 -292.574726)
			(xy 386.880354 -292.57498) (xy 386.879859 -292.599587) (xy 386.871964 -292.648164) (xy 386.85638 -292.694845)
			(xy 386.833509 -292.738422) (xy 386.803944 -292.777766) (xy 386.768451 -292.811858) (xy 386.727948 -292.839814)
			(xy 386.683486 -292.860912) (xy 386.636215 -292.874604) (xy 386.58736 -292.880536) (xy 386.538185 -292.878555)
			(xy 386.489966 -292.868711) (xy 386.44395 -292.851259) (xy 386.401329 -292.826652) (xy 386.363208 -292.795527)
			(xy 386.330573 -292.75869) (xy 386.30427 -292.717094) (xy 386.284979 -292.671818) (xy 386.273202 -292.624034)
			(xy 386.269242 -292.57498) (xy 385.93014 -292.57498) (xy 385.929645 -292.599587) (xy 385.92175 -292.648164)
			(xy 385.906166 -292.694845) (xy 385.883295 -292.738422) (xy 385.85373 -292.777766) (xy 385.818237 -292.811858)
			(xy 385.777734 -292.839814) (xy 385.733272 -292.860912) (xy 385.686001 -292.874604) (xy 385.637146 -292.880536)
			(xy 385.587971 -292.878555) (xy 385.539752 -292.868711) (xy 385.493736 -292.851259) (xy 385.451115 -292.826652)
			(xy 385.412994 -292.795527) (xy 385.380359 -292.75869) (xy 385.354056 -292.717094) (xy 385.334765 -292.671818)
			(xy 385.322988 -292.624034) (xy 385.319028 -292.57498) (xy 384.98018 -292.57498) (xy 384.979685 -292.599587)
			(xy 384.97179 -292.648164) (xy 384.956206 -292.694845) (xy 384.933335 -292.738422) (xy 384.90377 -292.777766)
			(xy 384.868277 -292.811858) (xy 384.827774 -292.839814) (xy 384.783312 -292.860912) (xy 384.736041 -292.874604)
			(xy 384.687186 -292.880536) (xy 384.638011 -292.878555) (xy 384.589792 -292.868711) (xy 384.543776 -292.851259)
			(xy 384.501155 -292.826652) (xy 384.463034 -292.795527) (xy 384.430399 -292.75869) (xy 384.404096 -292.717094)
			(xy 384.384805 -292.671818) (xy 384.373028 -292.624034) (xy 384.369068 -292.57498) (xy 384.2512 -292.57498)
			(xy 384.2512 -293.52494) (xy 384.369068 -293.52494) (xy 384.373028 -293.475886) (xy 384.384805 -293.428102)
			(xy 384.404096 -293.382826) (xy 384.430399 -293.34123) (xy 384.463034 -293.304393) (xy 384.501155 -293.273268)
			(xy 384.543776 -293.248661) (xy 384.589792 -293.231209) (xy 384.638011 -293.221365) (xy 384.687186 -293.219384)
			(xy 384.736041 -293.225316) (xy 384.783312 -293.239008) (xy 384.827774 -293.260106) (xy 384.868277 -293.288062)
			(xy 384.90377 -293.322154) (xy 384.933335 -293.361498) (xy 384.956206 -293.405075) (xy 384.97179 -293.451756)
			(xy 384.979685 -293.500333) (xy 384.98018 -293.52494) (xy 385.319028 -293.52494) (xy 385.322988 -293.475886)
			(xy 385.334765 -293.428102) (xy 385.354056 -293.382826) (xy 385.380359 -293.34123) (xy 385.412994 -293.304393)
			(xy 385.451115 -293.273268) (xy 385.493736 -293.248661) (xy 385.539752 -293.231209) (xy 385.587971 -293.221365)
			(xy 385.637146 -293.219384) (xy 385.686001 -293.225316) (xy 385.733272 -293.239008) (xy 385.777734 -293.260106)
			(xy 385.818237 -293.288062) (xy 385.85373 -293.322154) (xy 385.883295 -293.361498) (xy 385.906166 -293.405075)
			(xy 385.92175 -293.451756) (xy 385.929645 -293.500333) (xy 385.93014 -293.52494) (xy 386.269242 -293.52494)
			(xy 386.273202 -293.475886) (xy 386.284979 -293.428102) (xy 386.30427 -293.382826) (xy 386.330573 -293.34123)
			(xy 386.363208 -293.304393) (xy 386.401329 -293.273268) (xy 386.44395 -293.248661) (xy 386.489966 -293.231209)
			(xy 386.538185 -293.221365) (xy 386.58736 -293.219384) (xy 386.636215 -293.225316) (xy 386.683486 -293.239008)
			(xy 386.727948 -293.260106) (xy 386.768451 -293.288062) (xy 386.803944 -293.322154) (xy 386.833509 -293.361498)
			(xy 386.85638 -293.405075) (xy 386.871964 -293.451756) (xy 386.879859 -293.500333) (xy 386.880354 -293.52494)
			(xy 387.219202 -293.52494) (xy 387.223162 -293.475886) (xy 387.234939 -293.428102) (xy 387.25423 -293.382826)
			(xy 387.280533 -293.34123) (xy 387.313168 -293.304393) (xy 387.351289 -293.273268) (xy 387.39391 -293.248661)
			(xy 387.439926 -293.231209) (xy 387.488145 -293.221365) (xy 387.53732 -293.219384) (xy 387.586175 -293.225316)
			(xy 387.633446 -293.239008) (xy 387.677908 -293.260106) (xy 387.718411 -293.288062) (xy 387.753904 -293.322154)
			(xy 387.783469 -293.361498) (xy 387.80634 -293.405075) (xy 387.821924 -293.451756) (xy 387.829819 -293.500333)
			(xy 387.830314 -293.52494) (xy 388.169162 -293.52494) (xy 388.173122 -293.475886) (xy 388.184899 -293.428102)
			(xy 388.20419 -293.382826) (xy 388.230493 -293.34123) (xy 388.263128 -293.304393) (xy 388.301249 -293.273268)
			(xy 388.34387 -293.248661) (xy 388.389886 -293.231209) (xy 388.438105 -293.221365) (xy 388.48728 -293.219384)
			(xy 388.536135 -293.225316) (xy 388.583406 -293.239008) (xy 388.627868 -293.260106) (xy 388.668371 -293.288062)
			(xy 388.703864 -293.322154) (xy 388.733429 -293.361498) (xy 388.7563 -293.405075) (xy 388.771884 -293.451756)
			(xy 388.779779 -293.500333) (xy 388.780274 -293.52494) (xy 389.119122 -293.52494) (xy 389.123082 -293.475886)
			(xy 389.134859 -293.428102) (xy 389.15415 -293.382826) (xy 389.180453 -293.34123) (xy 389.213088 -293.304393)
			(xy 389.251209 -293.273268) (xy 389.29383 -293.248661) (xy 389.339846 -293.231209) (xy 389.388065 -293.221365)
			(xy 389.43724 -293.219384) (xy 389.486095 -293.225316) (xy 389.533366 -293.239008) (xy 389.577828 -293.260106)
			(xy 389.618331 -293.288062) (xy 389.653824 -293.322154) (xy 389.683389 -293.361498) (xy 389.70626 -293.405075)
			(xy 389.721844 -293.451756) (xy 389.729739 -293.500333) (xy 389.730234 -293.52494) (xy 390.069082 -293.52494)
			(xy 390.073042 -293.475886) (xy 390.084819 -293.428102) (xy 390.10411 -293.382826) (xy 390.130413 -293.34123)
			(xy 390.163048 -293.304393) (xy 390.201169 -293.273268) (xy 390.24379 -293.248661) (xy 390.289806 -293.231209)
			(xy 390.338025 -293.221365) (xy 390.3872 -293.219384) (xy 390.436055 -293.225316) (xy 390.483326 -293.239008)
			(xy 390.527788 -293.260106) (xy 390.568291 -293.288062) (xy 390.603784 -293.322154) (xy 390.633349 -293.361498)
			(xy 390.65622 -293.405075) (xy 390.671804 -293.451756) (xy 390.679699 -293.500333) (xy 390.680194 -293.524923)
			(xy 390.968323 -293.524923) (xy 390.972173 -293.472666) (xy 390.983646 -293.421539) (xy 391.002494 -293.372648)
			(xy 391.028309 -293.327049) (xy 391.060533 -293.285731) (xy 391.098469 -293.249586) (xy 391.119614 -293.23411)
			(xy 391.129173 -293.226514) (xy 391.140442 -293.204894) (xy 391.141204 -293.192708) (xy 391.141204 -292.930834)
			(xy 391.141396 -292.913362) (xy 391.145089 -292.878615) (xy 391.14857 -292.861492) (xy 391.150207 -292.852274)
			(xy 391.147441 -292.833771) (xy 391.138241 -292.817482) (xy 391.131298 -292.8112) (xy 391.112585 -292.795274)
			(xy 391.080053 -292.758452) (xy 391.053836 -292.716895) (xy 391.034611 -292.671677) (xy 391.022876 -292.623964)
			(xy 391.018931 -292.574987) (xy 391.02288 -292.526011) (xy 391.034619 -292.478299) (xy 391.053848 -292.433082)
			(xy 391.080068 -292.391528) (xy 391.112604 -292.354708) (xy 391.131298 -292.33876) (xy 391.138295 -292.332525)
			(xy 391.147519 -292.316225) (xy 391.150232 -292.297694) (xy 391.14857 -292.288468) (xy 391.145074 -292.271347)
			(xy 391.14138 -292.236599) (xy 391.141204 -292.219126) (xy 391.141204 -291.98062) (xy 391.141394 -291.963148)
			(xy 391.145088 -291.928401) (xy 391.14857 -291.911278) (xy 391.150138 -291.902051) (xy 391.147401 -291.883559)
			(xy 391.138229 -291.867271) (xy 391.131298 -291.860986) (xy 391.112572 -291.845076) (xy 391.080039 -291.808251)
			(xy 391.053822 -291.766693) (xy 391.034598 -291.721472) (xy 391.022863 -291.673757) (xy 391.01892 -291.624778)
			(xy 391.02287 -291.5758) (xy 391.034612 -291.528087) (xy 391.053842 -291.482869) (xy 391.080065 -291.441314)
			(xy 391.112603 -291.404494) (xy 391.131298 -291.388546) (xy 391.138242 -291.382258) (xy 391.147478 -291.365984)
			(xy 391.150216 -291.347474) (xy 391.14857 -291.338254) (xy 391.145072 -291.321134) (xy 391.141379 -291.286385)
			(xy 391.141204 -291.268912) (xy 391.141204 -291.03066) (xy 391.1414 -291.013188) (xy 391.14509 -290.978441)
			(xy 391.14857 -290.961318) (xy 391.150186 -290.952097) (xy 391.147429 -290.933598) (xy 391.138238 -290.917309)
			(xy 391.131298 -290.911026) (xy 391.112611 -290.895071) (xy 391.080079 -290.858253) (xy 391.053861 -290.816701)
			(xy 391.034636 -290.771486) (xy 391.022898 -290.723777) (xy 391.018951 -290.674804) (xy 391.022897 -290.62583)
			(xy 391.034633 -290.578121) (xy 391.053858 -290.532906) (xy 391.080074 -290.491353) (xy 391.112606 -290.454534)
			(xy 391.131298 -290.438586) (xy 391.138279 -290.432335) (xy 391.147506 -290.416043) (xy 391.150227 -290.397518)
			(xy 391.14857 -290.388294) (xy 391.145062 -290.371176) (xy 391.141376 -290.336425) (xy 391.141204 -290.318952)
			(xy 391.141204 -290.191698) (xy 391.141327 -290.186807) (xy 391.143255 -290.177214) (xy 391.145014 -290.172648)
			(xy 391.152126 -290.154868) (xy 391.153892 -290.150305) (xy 391.155803 -290.140709) (xy 391.155936 -290.135818)
			(xy 391.155936 -290.00577) (xy 391.155388 -289.994236) (xy 391.145343 -289.973471) (xy 391.136632 -289.965892)
			(xy 391.118715 -289.951269) (xy 391.087072 -289.917543) (xy 391.06085 -289.879449) (xy 391.040643 -289.837851)
			(xy 391.02691 -289.793691) (xy 391.019961 -289.747969) (xy 391.019538 -289.724846) (xy 391.020046 -289.700042)
			(xy 391.028054 -289.651084) (xy 391.043865 -289.604063) (xy 391.067065 -289.560214) (xy 391.097044 -289.520689)
			(xy 391.133015 -289.486527) (xy 391.174032 -289.458625) (xy 391.196322 -289.447732) (xy 391.204677 -289.443492)
			(xy 391.21776 -289.4301) (xy 391.225105 -289.41288) (xy 391.225786 -289.403536) (xy 391.227042 -289.379455)
			(xy 391.235906 -289.332057) (xy 391.251747 -289.286514) (xy 391.274208 -289.243845) (xy 391.302788 -289.205008)
			(xy 391.319512 -289.187636) (xy 391.324592 -289.182556) (xy 391.339324 -289.168586) (xy 391.344658 -289.163506)
			(xy 391.350505 -289.156033) (xy 391.356784 -289.138147) (xy 391.356135 -289.119201) (xy 391.348645 -289.101786)
			(xy 391.33534 -289.088283) (xy 391.318038 -289.080537) (xy 391.30859 -289.079686) (xy 391.282905 -289.077743)
			(xy 391.232659 -289.066429) (xy 391.185026 -289.046841) (xy 391.141357 -289.019534) (xy 391.102891 -288.985285)
			(xy 391.070721 -288.945064) (xy 391.04576 -288.900013) (xy 391.028716 -288.851411) (xy 391.020072 -288.800638)
			(xy 391.019538 -288.774886) (xy 391.02006 -288.749631) (xy 391.028373 -288.699809) (xy 391.044774 -288.652035)
			(xy 391.068815 -288.607612) (xy 391.099839 -288.567752) (xy 391.137001 -288.533542) (xy 391.179287 -288.505916)
			(xy 391.225543 -288.485626) (xy 391.274508 -288.473226) (xy 391.324846 -288.469055) (xy 391.375184 -288.473226)
			(xy 391.424149 -288.485626) (xy 391.470405 -288.505916) (xy 391.512691 -288.533542) (xy 391.549853 -288.567752)
			(xy 391.580877 -288.607612) (xy 391.604918 -288.652035) (xy 391.621319 -288.699809) (xy 391.629632 -288.749631)
			(xy 391.630154 -288.774886) (xy 391.62953 -288.802726) (xy 391.619447 -288.857487) (xy 391.599631 -288.909522)
			(xy 391.585704 -288.933636) (xy 391.581326 -288.941507) (xy 391.577783 -288.95915) (xy 391.580596 -288.976923)
			(xy 391.584688 -288.984944) (xy 391.628122 -289.06216) (xy 391.632773 -289.069859) (xy 391.64645 -289.081529)
			(xy 391.663327 -289.087729) (xy 391.672318 -289.088068) (xy 391.933176 -289.088068) (xy 391.961604 -289.088728)
			(xy 392.01756 -289.098822) (xy 392.044428 -289.108134) (xy 392.054378 -289.111321) (xy 392.075222 -289.110282)
			(xy 392.093931 -289.101033) (xy 392.107411 -289.085101) (xy 392.113436 -289.06512) (xy 392.111009 -289.044391)
			(xy 392.100532 -289.026342) (xy 392.092434 -289.019742) (xy 392.073697 -289.005238) (xy 392.040527 -288.971404)
			(xy 392.012982 -288.932853) (xy 391.991723 -288.890509) (xy 391.977262 -288.845389) (xy 391.969944 -288.798576)
			(xy 391.969498 -288.774886) (xy 391.97002 -288.749631) (xy 391.978333 -288.699809) (xy 391.994734 -288.652035)
			(xy 392.018775 -288.607612) (xy 392.049799 -288.567752) (xy 392.086961 -288.533542) (xy 392.129247 -288.505916)
			(xy 392.175503 -288.485626) (xy 392.224468 -288.473226) (xy 392.274806 -288.469055) (xy 392.325144 -288.473226)
			(xy 392.374109 -288.485626) (xy 392.420365 -288.505916) (xy 392.462651 -288.533542) (xy 392.499813 -288.567752)
			(xy 392.530837 -288.607612) (xy 392.554878 -288.652035) (xy 392.571279 -288.699809) (xy 392.579592 -288.749631)
			(xy 392.580114 -288.774886) (xy 392.579656 -288.798576) (xy 392.572339 -288.845387) (xy 392.557878 -288.890505)
			(xy 392.536621 -288.932848) (xy 392.509077 -288.971399) (xy 392.475909 -289.005232) (xy 392.457178 -289.019742)
			(xy 392.449033 -289.026275) (xy 392.438592 -289.044341) (xy 392.43619 -289.065069) (xy 392.442223 -289.085044)
			(xy 392.455698 -289.100977) (xy 392.474395 -289.110242) (xy 392.495234 -289.111313) (xy 392.505184 -289.108134)
			(xy 392.53205 -289.098815) (xy 392.588007 -289.08872) (xy 392.616436 -289.088068) (xy 392.88339 -289.088068)
			(xy 392.911818 -289.088724) (xy 392.967774 -289.098821) (xy 392.994642 -289.108134) (xy 393.004588 -289.11133)
			(xy 393.025432 -289.110288) (xy 393.044139 -289.101037) (xy 393.057619 -289.085104) (xy 393.063644 -289.065123)
			(xy 393.061219 -289.044395) (xy 393.050745 -289.026344) (xy 393.042648 -289.019742) (xy 393.023914 -289.005234)
			(xy 392.990743 -288.971402) (xy 392.963198 -288.932851) (xy 392.941938 -288.890508) (xy 392.927476 -288.845388)
			(xy 392.920158 -288.798576) (xy 392.919712 -288.774886) (xy 392.920234 -288.749631) (xy 392.928547 -288.699809)
			(xy 392.944948 -288.652035) (xy 392.968989 -288.607612) (xy 393.000013 -288.567752) (xy 393.037175 -288.533542)
			(xy 393.079461 -288.505916) (xy 393.125717 -288.485626) (xy 393.174682 -288.473226) (xy 393.22502 -288.469055)
			(xy 393.275358 -288.473226) (xy 393.324323 -288.485626) (xy 393.370579 -288.505916) (xy 393.412865 -288.533542)
			(xy 393.450027 -288.567752) (xy 393.481051 -288.607612) (xy 393.505092 -288.652035) (xy 393.521493 -288.699809)
			(xy 393.529806 -288.749631) (xy 393.530328 -288.774886) (xy 393.529864 -288.798575) (xy 393.522548 -288.845386)
			(xy 393.508088 -288.890504) (xy 393.486831 -288.932847) (xy 393.459289 -288.971398) (xy 393.426123 -289.005232)
			(xy 393.407392 -289.019742) (xy 393.399317 -289.026339) (xy 393.388909 -289.044386) (xy 393.386522 -289.065082)
			(xy 393.392547 -289.085025) (xy 393.405995 -289.100936) (xy 393.424655 -289.1102) (xy 393.44546 -289.111294)
			(xy 393.455398 -289.108134) (xy 393.482263 -289.098811) (xy 393.538221 -289.088719) (xy 393.56665 -289.088068)
			(xy 393.83335 -289.088068) (xy 393.861778 -289.088734) (xy 393.917734 -289.098824) (xy 393.944602 -289.108134)
			(xy 393.954559 -289.111302) (xy 393.975404 -289.110271) (xy 393.994115 -289.101026) (xy 394.007597 -289.085095)
			(xy 394.013621 -289.065114) (xy 394.011191 -289.044386) (xy 394.000709 -289.026339) (xy 393.992608 -289.019742)
			(xy 393.973866 -289.005245) (xy 393.940697 -288.971409) (xy 393.913154 -288.932856) (xy 393.891896 -288.890511)
			(xy 393.877435 -288.84539) (xy 393.870118 -288.798577) (xy 393.869672 -288.774886) (xy 393.870194 -288.749631)
			(xy 393.878507 -288.699809) (xy 393.894908 -288.652035) (xy 393.918949 -288.607612) (xy 393.949973 -288.567752)
			(xy 393.987135 -288.533542) (xy 394.029421 -288.505916) (xy 394.075677 -288.485626) (xy 394.124642 -288.473226)
			(xy 394.17498 -288.469055) (xy 394.225318 -288.473226) (xy 394.274283 -288.485626) (xy 394.320539 -288.505916)
			(xy 394.362825 -288.533542) (xy 394.399987 -288.567752) (xy 394.431011 -288.607612) (xy 394.455052 -288.652035)
			(xy 394.471453 -288.699809) (xy 394.479766 -288.749631) (xy 394.480288 -288.774886) (xy 394.47984 -288.798576)
			(xy 394.472523 -288.845388) (xy 394.45806 -288.890507) (xy 394.436801 -288.932851) (xy 394.409255 -288.971401)
			(xy 394.376085 -289.005233) (xy 394.357352 -289.019742) (xy 394.349228 -289.026294) (xy 394.338797 -289.044355)
			(xy 394.336399 -289.065073) (xy 394.34243 -289.085038) (xy 394.355897 -289.100964) (xy 394.374583 -289.110229)
			(xy 394.395412 -289.111307) (xy 394.405358 -289.108134) (xy 394.432226 -289.098821) (xy 394.488181 -289.088722)
			(xy 394.51661 -289.088068) (xy 394.78331 -289.088068) (xy 394.811739 -289.088719) (xy 394.867695 -289.098819)
			(xy 394.894562 -289.108134) (xy 394.904502 -289.111345) (xy 394.925346 -289.110298) (xy 394.944052 -289.101043)
			(xy 394.95753 -289.085109) (xy 394.963556 -289.065128) (xy 394.961134 -289.044399) (xy 394.950663 -289.026346)
			(xy 394.942568 -289.019742) (xy 394.923839 -289.005229) (xy 394.890666 -288.971398) (xy 394.863119 -288.932849)
			(xy 394.841859 -288.890507) (xy 394.827396 -288.845388) (xy 394.820078 -288.798576) (xy 394.819632 -288.774886)
			(xy 394.820154 -288.749631) (xy 394.828467 -288.699809) (xy 394.844868 -288.652035) (xy 394.868909 -288.607612)
			(xy 394.899933 -288.567752) (xy 394.937095 -288.533542) (xy 394.979381 -288.505916) (xy 395.025637 -288.485626)
			(xy 395.074602 -288.473226) (xy 395.12494 -288.469055) (xy 395.175278 -288.473226) (xy 395.224243 -288.485626)
			(xy 395.270499 -288.505916) (xy 395.312785 -288.533542) (xy 395.349947 -288.567752) (xy 395.380971 -288.607612)
			(xy 395.405012 -288.652035) (xy 395.421413 -288.699809) (xy 395.429726 -288.749631) (xy 395.430248 -288.774886)
			(xy 395.429777 -288.798575) (xy 395.42246 -288.845385) (xy 395.408001 -288.890502) (xy 395.386746 -288.932845)
			(xy 395.359206 -288.971396) (xy 395.326041 -289.005231) (xy 395.307312 -289.019742) (xy 395.299221 -289.026324)
			(xy 395.288805 -289.044376) (xy 395.286414 -289.065079) (xy 395.292442 -289.085029) (xy 395.305896 -289.100945)
			(xy 395.324565 -289.110209) (xy 395.345377 -289.111298) (xy 395.355318 -289.108134) (xy 395.382182 -289.098806)
			(xy 395.43814 -289.088717) (xy 395.46657 -289.088068) (xy 395.73327 -289.088068) (xy 395.761698 -289.088729)
			(xy 395.817654 -289.098822) (xy 395.844522 -289.108134) (xy 395.854474 -289.111316) (xy 395.875318 -289.11028)
			(xy 395.894027 -289.101031) (xy 395.907508 -289.0851) (xy 395.913533 -289.065118) (xy 395.911105 -289.04439)
			(xy 395.900627 -289.026341) (xy 395.892528 -289.019742) (xy 395.87379 -289.005239) (xy 395.84062 -288.971406)
			(xy 395.813076 -288.932854) (xy 395.791817 -288.890509) (xy 395.777356 -288.845389) (xy 395.770038 -288.798577)
			(xy 395.769592 -288.774886) (xy 395.770114 -288.749631) (xy 395.778427 -288.699809) (xy 395.794828 -288.652035)
			(xy 395.818869 -288.607612) (xy 395.849893 -288.567752) (xy 395.887055 -288.533542) (xy 395.929341 -288.505916)
			(xy 395.975597 -288.485626) (xy 396.024562 -288.473226) (xy 396.0749 -288.469055) (xy 396.125238 -288.473226)
			(xy 396.174203 -288.485626) (xy 396.220459 -288.505916) (xy 396.262745 -288.533542) (xy 396.299907 -288.567752)
			(xy 396.330931 -288.607612) (xy 396.354972 -288.652035) (xy 396.371373 -288.699809) (xy 396.379686 -288.749631)
			(xy 396.380208 -288.774886) (xy 396.379752 -288.798576) (xy 396.372435 -288.845387) (xy 396.357974 -288.890506)
			(xy 396.336716 -288.932849) (xy 396.309172 -288.971399) (xy 396.276004 -289.005232) (xy 396.257272 -289.019742)
			(xy 396.249132 -289.026279) (xy 396.238693 -289.044344) (xy 396.236292 -289.06507) (xy 396.242325 -289.085043)
			(xy 396.255798 -289.100974) (xy 396.274492 -289.110239) (xy 396.295329 -289.111312) (xy 396.305278 -289.108134)
			(xy 396.332145 -289.098816) (xy 396.388101 -289.08872) (xy 396.41653 -289.088068) (xy 396.68323 -289.088068)
			(xy 396.708794 -289.088604) (xy 396.759264 -289.096805) (xy 396.807801 -289.112885) (xy 396.853183 -289.13644)
			(xy 396.894269 -289.166876) (xy 396.930025 -289.203426) (xy 396.959549 -289.245172) (xy 396.971266 -289.2679)
			(xy 396.985744 -289.297364) (xy 397.010382 -289.312604) (xy 397.02486 -289.312604) (xy 397.034279 -289.312187)
			(xy 397.051839 -289.305362) (xy 397.065748 -289.292654) (xy 397.070326 -289.28441) (xy 397.078454 -289.2679)
			(xy 397.09011 -289.245255) (xy 397.119495 -289.203659) (xy 397.155078 -289.167224) (xy 397.195969 -289.136865)
			(xy 397.241139 -289.113343) (xy 397.265144 -289.104832) (xy 397.27632 -289.101022) (xy 397.593312 -288.78403)
			(xy 397.599963 -288.777925) (xy 397.616353 -288.770378) (xy 397.625316 -288.769298) (xy 397.627348 -288.769298)
			(xy 397.638679 -288.767971) (xy 397.658447 -288.756619) (xy 397.67133 -288.737813) (xy 397.673576 -288.726626)
			(xy 397.677791 -288.703089) (xy 397.692629 -288.657635) (xy 397.714377 -288.615052) (xy 397.742501 -288.576384)
			(xy 397.776313 -288.542576) (xy 397.814986 -288.514457) (xy 397.857571 -288.492714) (xy 397.903027 -288.477881)
			(xy 397.92656 -288.473642) (xy 397.937675 -288.471269) (xy 397.956343 -288.458342) (xy 397.9677 -288.43868)
			(xy 397.969232 -288.427414) (xy 397.969232 -288.425382) (xy 397.970291 -288.416411) (xy 397.977833 -288.400012)
			(xy 397.983964 -288.393378) (xy 398.15516 -288.222182) (xy 398.173351 -288.204637) (xy 398.214225 -288.174916)
			(xy 398.259247 -288.151959) (xy 398.307307 -288.136332) (xy 398.357221 -288.12842) (xy 398.38249 -288.127948)
			(xy 398.591532 -288.127948) (xy 398.61228 -288.128277) (xy 398.65343 -288.133632) (xy 398.673574 -288.138616)
			(xy 398.676368 -288.139124) (xy 398.685728 -288.140735) (xy 398.704432 -288.137469) (xy 398.720669 -288.127628)
			(xy 398.73222 -288.112558) (xy 398.737503 -288.094321) (xy 398.735797 -288.075411) (xy 398.727334 -288.058414)
			(xy 398.720564 -288.051748) (xy 398.701944 -288.034205) (xy 398.670199 -287.994093) (xy 398.645579 -287.949254)
			(xy 398.628772 -287.900941) (xy 398.620247 -287.850503) (xy 398.619726 -287.824926) (xy 398.620248 -287.799671)
			(xy 398.628561 -287.749849) (xy 398.644962 -287.702075) (xy 398.669003 -287.657652) (xy 398.700027 -287.617792)
			(xy 398.737189 -287.583582) (xy 398.779475 -287.555956) (xy 398.825731 -287.535666) (xy 398.874696 -287.523266)
			(xy 398.925034 -287.519095) (xy 398.975372 -287.523266) (xy 399.024337 -287.535666) (xy 399.070593 -287.555956)
			(xy 399.112879 -287.583582) (xy 399.150041 -287.617792) (xy 399.181065 -287.657652) (xy 399.205106 -287.702075)
			(xy 399.221507 -287.749849) (xy 399.22982 -287.799671) (xy 399.230342 -287.824926) (xy 399.229802 -287.850503)
			(xy 399.221281 -287.900941) (xy 399.204482 -287.949257) (xy 399.179873 -287.994102) (xy 399.148141 -288.034224)
			(xy 399.129504 -288.051748) (xy 399.122695 -288.058381) (xy 399.1142 -288.075373) (xy 399.112478 -288.094292)
			(xy 399.117764 -288.112539) (xy 399.129332 -288.127607) (xy 399.145595 -288.137427) (xy 399.164317 -288.14065)
			(xy 399.1737 -288.139124) (xy 399.176494 -288.138616) (xy 399.196637 -288.133628) (xy 399.237787 -288.128274)
			(xy 399.258536 -288.127948) (xy 399.541492 -288.127948) (xy 399.56224 -288.128284) (xy 399.60339 -288.133634)
			(xy 399.623534 -288.138616) (xy 399.626328 -288.139124) (xy 399.635693 -288.140708) (xy 399.654399 -288.137452)
			(xy 399.67064 -288.127618) (xy 399.682193 -288.11255) (xy 399.687477 -288.094314) (xy 399.685767 -288.075404)
			(xy 399.677298 -288.058411) (xy 399.670524 -288.051748) (xy 399.651896 -288.034213) (xy 399.620154 -287.994098)
			(xy 399.595536 -287.949257) (xy 399.57873 -287.900942) (xy 399.570206 -287.850503) (xy 399.569686 -287.824926)
			(xy 399.570208 -287.799671) (xy 399.578521 -287.749849) (xy 399.594922 -287.702075) (xy 399.618963 -287.657652)
			(xy 399.649987 -287.617792) (xy 399.687149 -287.583582) (xy 399.729435 -287.555956) (xy 399.775691 -287.535666)
			(xy 399.824656 -287.523266) (xy 399.874994 -287.519095) (xy 399.925332 -287.523266) (xy 399.974297 -287.535666)
			(xy 400.020553 -287.555956) (xy 400.062839 -287.583582) (xy 400.100001 -287.617792) (xy 400.131025 -287.657652)
			(xy 400.155066 -287.702075) (xy 400.171467 -287.749849) (xy 400.17978 -287.799671) (xy 400.180302 -287.824926)
			(xy 400.179775 -287.850503) (xy 400.171253 -287.900943) (xy 400.154451 -287.94926) (xy 400.129839 -287.994105)
			(xy 400.098104 -288.034225) (xy 400.079464 -288.051748) (xy 400.072687 -288.058406) (xy 400.064204 -288.07539)
			(xy 400.062486 -288.094296) (xy 400.067769 -288.112531) (xy 400.079327 -288.127591) (xy 400.095574 -288.137411)
			(xy 400.114282 -288.140642) (xy 400.12366 -288.139124) (xy 400.126454 -288.138616) (xy 400.146594 -288.133617)
			(xy 400.187747 -288.12827) (xy 400.208496 -288.127948) (xy 400.491452 -288.127948) (xy 400.5122 -288.128292)
			(xy 400.55335 -288.133637) (xy 400.573494 -288.138616) (xy 400.576288 -288.139124) (xy 400.585659 -288.14068)
			(xy 400.604366 -288.137435) (xy 400.620611 -288.127607) (xy 400.632167 -288.112542) (xy 400.63745 -288.094306)
			(xy 400.635736 -288.075397) (xy 400.627261 -288.058407) (xy 400.620484 -288.051748) (xy 400.601867 -288.034201)
			(xy 400.570121 -287.994091) (xy 400.5455 -287.949253) (xy 400.528692 -287.90094) (xy 400.520167 -287.850502)
			(xy 400.519646 -287.824926) (xy 400.520168 -287.799671) (xy 400.528481 -287.749849) (xy 400.544882 -287.702075)
			(xy 400.568923 -287.657652) (xy 400.599947 -287.617792) (xy 400.637109 -287.583582) (xy 400.679395 -287.555956)
			(xy 400.725651 -287.535666) (xy 400.774616 -287.523266) (xy 400.824954 -287.519095) (xy 400.875292 -287.523266)
			(xy 400.924257 -287.535666) (xy 400.970513 -287.555956) (xy 401.012799 -287.583582) (xy 401.049961 -287.617792)
			(xy 401.080985 -287.657652) (xy 401.105026 -287.702075) (xy 401.121427 -287.749849) (xy 401.12974 -287.799671)
			(xy 401.130262 -287.824926) (xy 401.129715 -287.850502) (xy 401.121195 -287.90094) (xy 401.104397 -287.949256)
			(xy 401.07979 -287.994101) (xy 401.04806 -288.034224) (xy 401.029424 -288.051748) (xy 401.022599 -288.058368)
			(xy 401.014098 -288.075364) (xy 401.012373 -288.09429) (xy 401.017661 -288.112543) (xy 401.029235 -288.127616)
			(xy 401.045505 -288.137436) (xy 401.064234 -288.140654) (xy 401.07362 -288.139124) (xy 401.076414 -288.138616)
			(xy 401.096556 -288.133624) (xy 401.137707 -288.128273) (xy 401.158456 -288.127948) (xy 401.441412 -288.127948)
			(xy 401.46216 -288.128281) (xy 401.50331 -288.133633) (xy 401.523454 -288.138616) (xy 401.526248 -288.139124)
			(xy 401.535611 -288.140721) (xy 401.554315 -288.13746) (xy 401.570555 -288.127623) (xy 401.582107 -288.112554)
			(xy 401.58739 -288.094317) (xy 401.585682 -288.075407) (xy 401.577216 -288.058412) (xy 401.570444 -288.051748)
			(xy 401.55182 -288.034209) (xy 401.520076 -287.994096) (xy 401.495457 -287.949256) (xy 401.478651 -287.900942)
			(xy 401.470126 -287.850503) (xy 401.469606 -287.824926) (xy 401.470128 -287.799671) (xy 401.478441 -287.749849)
			(xy 401.494842 -287.702075) (xy 401.518883 -287.657652) (xy 401.549907 -287.617792) (xy 401.587069 -287.583582)
			(xy 401.629355 -287.555956) (xy 401.675611 -287.535666) (xy 401.724576 -287.523266) (xy 401.774914 -287.519095)
			(xy 401.825252 -287.523266) (xy 401.874217 -287.535666) (xy 401.920473 -287.555956) (xy 401.962759 -287.583582)
			(xy 401.999921 -287.617792) (xy 402.030945 -287.657652) (xy 402.054986 -287.702075) (xy 402.071387 -287.749849)
			(xy 402.0797 -287.799671) (xy 402.080222 -287.824926) (xy 402.079688 -287.850503) (xy 402.071167 -287.900942)
			(xy 402.054367 -287.949259) (xy 402.029756 -287.994104) (xy 401.998022 -288.034225) (xy 401.979384 -288.051748)
			(xy 401.972591 -288.058393) (xy 401.964102 -288.075381) (xy 401.962382 -288.094294) (xy 401.967666 -288.112535)
			(xy 401.97923 -288.127599) (xy 401.995485 -288.137419) (xy 402.014199 -288.140646) (xy 402.02358 -288.139124)
			(xy 402.026374 -288.138616) (xy 402.046518 -288.133632) (xy 402.087668 -288.128275) (xy 402.108416 -288.127948)
			(xy 402.391372 -288.127948) (xy 402.41212 -288.128288) (xy 402.45327 -288.133635) (xy 402.473414 -288.138616)
			(xy 402.476208 -288.139124) (xy 402.485576 -288.140694) (xy 402.504283 -288.137444) (xy 402.520525 -288.127612)
			(xy 402.53208 -288.112546) (xy 402.537363 -288.09431) (xy 402.535651 -288.0754) (xy 402.527179 -288.058409)
			(xy 402.520404 -288.051748) (xy 402.501772 -288.034217) (xy 402.470031 -287.994101) (xy 402.445415 -287.949258)
			(xy 402.42861 -287.900943) (xy 402.420086 -287.850503) (xy 402.419566 -287.824926) (xy 402.420088 -287.799671)
			(xy 402.428401 -287.749849) (xy 402.444802 -287.702075) (xy 402.468843 -287.657652) (xy 402.499867 -287.617792)
			(xy 402.537029 -287.583582) (xy 402.579315 -287.555956) (xy 402.625571 -287.535666) (xy 402.674536 -287.523266)
			(xy 402.724874 -287.519095) (xy 402.775212 -287.523266) (xy 402.824177 -287.535666) (xy 402.870433 -287.555956)
			(xy 402.912719 -287.583582) (xy 402.949881 -287.617792) (xy 402.980905 -287.657652) (xy 403.004946 -287.702075)
			(xy 403.021347 -287.749849) (xy 403.02966 -287.799671) (xy 403.030182 -287.824926) (xy 403.029662 -287.850504)
			(xy 403.021139 -287.900944) (xy 403.004336 -287.949261) (xy 402.979722 -287.994106) (xy 402.947985 -288.034226)
			(xy 402.929344 -288.051748) (xy 402.922504 -288.058356) (xy 402.913996 -288.075356) (xy 402.912269 -288.094288)
			(xy 402.917558 -288.112547) (xy 402.929138 -288.127623) (xy 402.945415 -288.137444) (xy 402.964151 -288.140658)
			(xy 402.97354 -288.139124) (xy 402.976334 -288.138616) (xy 402.996475 -288.13362) (xy 403.037627 -288.128272)
			(xy 403.058376 -288.127948) (xy 403.341332 -288.127948) (xy 403.36208 -288.128277) (xy 403.40323 -288.133632)
			(xy 403.423374 -288.138616) (xy 403.426168 -288.139124) (xy 403.435528 -288.140735) (xy 403.454232 -288.137469)
			(xy 403.470469 -288.127628) (xy 403.48202 -288.112558) (xy 403.487303 -288.094321) (xy 403.485597 -288.075411)
			(xy 403.477134 -288.058414) (xy 403.470364 -288.051748) (xy 403.451744 -288.034205) (xy 403.419999 -287.994093)
			(xy 403.395379 -287.949254) (xy 403.378572 -287.900941) (xy 403.370047 -287.850503) (xy 403.369526 -287.824926)
			(xy 403.370048 -287.799671) (xy 403.378361 -287.749849) (xy 403.394762 -287.702075) (xy 403.418803 -287.657652)
			(xy 403.449827 -287.617792) (xy 403.486989 -287.583582) (xy 403.529275 -287.555956) (xy 403.575531 -287.535666)
			(xy 403.624496 -287.523266) (xy 403.674834 -287.519095) (xy 403.725172 -287.523266) (xy 403.774137 -287.535666)
			(xy 403.820393 -287.555956) (xy 403.862679 -287.583582) (xy 403.899841 -287.617792) (xy 403.930865 -287.657652)
			(xy 403.954906 -287.702075) (xy 403.971307 -287.749849) (xy 403.97962 -287.799671) (xy 403.980142 -287.824926)
			(xy 403.979602 -287.850503) (xy 403.971081 -287.900941) (xy 403.954282 -287.949257) (xy 403.929673 -287.994102)
			(xy 403.897941 -288.034224) (xy 403.879304 -288.051748) (xy 403.872495 -288.058381) (xy 403.864 -288.075373)
			(xy 403.862278 -288.094292) (xy 403.867564 -288.112539) (xy 403.879132 -288.127607) (xy 403.895395 -288.137427)
			(xy 403.914117 -288.14065) (xy 403.9235 -288.139124) (xy 403.926294 -288.138616) (xy 403.946437 -288.133628)
			(xy 403.987587 -288.128274) (xy 404.008336 -288.127948) (xy 404.291292 -288.127948) (xy 404.31204 -288.128284)
			(xy 404.35319 -288.133634) (xy 404.373334 -288.138616) (xy 404.376128 -288.139124) (xy 404.385493 -288.140708)
			(xy 404.404199 -288.137452) (xy 404.42044 -288.127618) (xy 404.431993 -288.11255) (xy 404.437277 -288.094314)
			(xy 404.435567 -288.075404) (xy 404.427098 -288.058411) (xy 404.420324 -288.051748) (xy 404.401696 -288.034213)
			(xy 404.369954 -287.994098) (xy 404.345336 -287.949257) (xy 404.32853 -287.900942) (xy 404.320006 -287.850503)
			(xy 404.319486 -287.824926) (xy 404.320008 -287.799671) (xy 404.328321 -287.749849) (xy 404.344722 -287.702075)
			(xy 404.368763 -287.657652) (xy 404.399787 -287.617792) (xy 404.436949 -287.583582) (xy 404.479235 -287.555956)
			(xy 404.525491 -287.535666) (xy 404.574456 -287.523266) (xy 404.624794 -287.519095) (xy 404.675132 -287.523266)
			(xy 404.724097 -287.535666) (xy 404.770353 -287.555956) (xy 404.812639 -287.583582) (xy 404.849801 -287.617792)
			(xy 404.880825 -287.657652) (xy 404.904866 -287.702075) (xy 404.921267 -287.749849) (xy 404.92958 -287.799671)
			(xy 404.930102 -287.824926) (xy 404.929575 -287.850503) (xy 404.921053 -287.900943) (xy 404.904251 -287.94926)
			(xy 404.879639 -287.994105) (xy 404.847904 -288.034225) (xy 404.829264 -288.051748) (xy 404.822487 -288.058406)
			(xy 404.814004 -288.07539) (xy 404.812286 -288.094296) (xy 404.817569 -288.112531) (xy 404.829127 -288.127591)
			(xy 404.845374 -288.137411) (xy 404.864082 -288.140642) (xy 404.87346 -288.139124) (xy 404.876254 -288.138616)
			(xy 404.896394 -288.133617) (xy 404.937547 -288.12827) (xy 404.958296 -288.127948) (xy 405.241506 -288.127948)
			(xy 405.262254 -288.128282) (xy 405.303404 -288.133633) (xy 405.323548 -288.138616) (xy 405.326342 -288.139124)
			(xy 405.335705 -288.140717) (xy 405.35441 -288.137458) (xy 405.37065 -288.127621) (xy 405.382203 -288.112553)
			(xy 405.387486 -288.094316) (xy 405.385777 -288.075406) (xy 405.377311 -288.058412) (xy 405.370538 -288.051748)
			(xy 405.351912 -288.03421) (xy 405.320169 -287.994097) (xy 405.295551 -287.949256) (xy 405.278745 -287.900942)
			(xy 405.27022 -287.850503) (xy 405.2697 -287.824926) (xy 405.270222 -287.799671) (xy 405.278535 -287.749849)
			(xy 405.294936 -287.702075) (xy 405.318977 -287.657652) (xy 405.350001 -287.617792) (xy 405.387163 -287.583582)
			(xy 405.429449 -287.555956) (xy 405.475705 -287.535666) (xy 405.52467 -287.523266) (xy 405.575008 -287.519095)
			(xy 405.625346 -287.523266) (xy 405.674311 -287.535666) (xy 405.720567 -287.555956) (xy 405.762853 -287.583582)
			(xy 405.800015 -287.617792) (xy 405.831039 -287.657652) (xy 405.853934 -287.699958) (xy 406.244056 -287.699958)
			(xy 406.248016 -287.650904) (xy 406.259793 -287.60312) (xy 406.279084 -287.557844) (xy 406.305387 -287.516248)
			(xy 406.338022 -287.479411) (xy 406.376143 -287.448286) (xy 406.418764 -287.423679) (xy 406.46478 -287.406227)
			(xy 406.512999 -287.396383) (xy 406.562174 -287.394402) (xy 406.611029 -287.400334) (xy 406.6583 -287.414026)
			(xy 406.702762 -287.435124) (xy 406.743265 -287.46308) (xy 406.778758 -287.497172) (xy 406.808323 -287.536516)
			(xy 406.831194 -287.580093) (xy 406.846778 -287.626774) (xy 406.854673 -287.675351) (xy 406.855168 -287.699958)
			(xy 406.854673 -287.724565) (xy 406.846778 -287.773142) (xy 406.831194 -287.819823) (xy 406.808323 -287.8634)
			(xy 406.778758 -287.902744) (xy 406.743265 -287.936836) (xy 406.702762 -287.964792) (xy 406.6583 -287.98589)
			(xy 406.611029 -287.999582) (xy 406.562174 -288.005514) (xy 406.512999 -288.003533) (xy 406.46478 -287.993689)
			(xy 406.418764 -287.976237) (xy 406.376143 -287.95163) (xy 406.338022 -287.920505) (xy 406.305387 -287.883668)
			(xy 406.279084 -287.842072) (xy 406.259793 -287.796796) (xy 406.248016 -287.749012) (xy 406.244056 -287.699958)
			(xy 405.853934 -287.699958) (xy 405.85508 -287.702075) (xy 405.871481 -287.749849) (xy 405.879794 -287.799671)
			(xy 405.880316 -287.824926) (xy 405.879784 -287.850503) (xy 405.871263 -287.900943) (xy 405.854462 -287.949259)
			(xy 405.829851 -287.994104) (xy 405.798117 -288.034225) (xy 405.779478 -288.051748) (xy 405.77269 -288.058397)
			(xy 405.764203 -288.075384) (xy 405.762483 -288.094295) (xy 405.767767 -288.112534) (xy 405.779329 -288.127597)
			(xy 405.795582 -288.137417) (xy 405.814294 -288.140645) (xy 405.823674 -288.139124) (xy 405.826468 -288.138616)
			(xy 405.846608 -288.133614) (xy 405.887761 -288.128269) (xy 405.90851 -288.127948) (xy 406.191212 -288.127948)
			(xy 406.215567 -288.128422) (xy 406.263718 -288.135789) (xy 406.310206 -288.150336) (xy 406.353967 -288.171731)
			(xy 406.393999 -288.199485) (xy 406.429384 -288.23296) (xy 406.444704 -288.2519) (xy 406.452319 -288.260699)
			(xy 406.473214 -288.270887) (xy 406.484836 -288.271458) (xy 406.5651 -288.271458) (xy 406.576732 -288.270919)
			(xy 406.597643 -288.260732) (xy 406.605232 -288.2519) (xy 406.620565 -288.232968) (xy 406.655935 -288.199472)
			(xy 406.695959 -288.171703) (xy 406.73972 -288.1503) (xy 406.786211 -288.135753) (xy 406.834367 -288.128398)
			(xy 406.858724 -288.127948) (xy 408.091132 -288.127948) (xy 408.112976 -288.12871) (xy 408.122882 -288.128456)
			(xy 408.132766 -288.126644) (xy 408.150162 -288.116636) (xy 408.162406 -288.100733) (xy 408.167634 -288.081357)
			(xy 408.165051 -288.061454) (xy 408.160474 -288.05251) (xy 408.147668 -288.029169) (xy 408.129456 -287.979147)
			(xy 408.120183 -287.926727) (xy 408.11958 -287.90011) (xy 408.11958 -287.899856) (xy 408.120102 -287.874601)
			(xy 408.128415 -287.824779) (xy 408.144816 -287.777005) (xy 408.168857 -287.732582) (xy 408.199881 -287.692722)
			(xy 408.237043 -287.658512) (xy 408.279329 -287.630886) (xy 408.325585 -287.610596) (xy 408.37455 -287.598196)
			(xy 408.424888 -287.594025) (xy 408.475226 -287.598196) (xy 408.524191 -287.610596) (xy 408.570447 -287.630886)
			(xy 408.612733 -287.658512) (xy 408.649895 -287.692722) (xy 408.680919 -287.732582) (xy 408.70496 -287.777005)
			(xy 408.721361 -287.824779) (xy 408.729674 -287.874601) (xy 408.730196 -287.899856) (xy 408.730196 -287.90011)
			(xy 408.729642 -287.926732) (xy 408.720384 -287.979164) (xy 408.702153 -288.029189) (xy 408.689302 -288.05251)
			(xy 408.684583 -288.061423) (xy 408.681903 -288.081397) (xy 408.687123 -288.100862) (xy 408.699437 -288.116815)
			(xy 408.716946 -288.126794) (xy 408.726894 -288.128456) (xy 408.7368 -288.12871) (xy 408.758644 -288.127948)
			(xy 409.041346 -288.127948) (xy 409.062094 -288.128274) (xy 409.103245 -288.133631) (xy 409.123388 -288.138616)
			(xy 409.126182 -288.139124) (xy 409.135554 -288.140676) (xy 409.154261 -288.137433) (xy 409.170507 -288.127606)
			(xy 409.182063 -288.112541) (xy 409.187346 -288.094305) (xy 409.185632 -288.075396) (xy 409.177156 -288.058407)
			(xy 409.170378 -288.051748) (xy 409.15176 -288.034202) (xy 409.120015 -287.994092) (xy 409.095394 -287.949253)
			(xy 409.078586 -287.90094) (xy 409.070061 -287.850503) (xy 409.06954 -287.824926) (xy 409.070062 -287.799671)
			(xy 409.078375 -287.749849) (xy 409.094776 -287.702075) (xy 409.118817 -287.657652) (xy 409.149841 -287.617792)
			(xy 409.187003 -287.583582) (xy 409.229289 -287.555956) (xy 409.275545 -287.535666) (xy 409.32451 -287.523266)
			(xy 409.374848 -287.519095) (xy 409.425186 -287.523266) (xy 409.474151 -287.535666) (xy 409.520407 -287.555956)
			(xy 409.562693 -287.583582) (xy 409.599855 -287.617792) (xy 409.630879 -287.657652) (xy 409.65492 -287.702075)
			(xy 409.671321 -287.749849) (xy 409.679634 -287.799671) (xy 409.680156 -287.824926) (xy 409.679611 -287.850502)
			(xy 409.671091 -287.900941) (xy 409.654293 -287.949256) (xy 409.629685 -287.994101) (xy 409.597955 -288.034224)
			(xy 409.579318 -288.051748) (xy 409.572498 -288.058372) (xy 409.563999 -288.075367) (xy 409.562275 -288.09429)
			(xy 409.567562 -288.112542) (xy 409.579134 -288.127613) (xy 409.595402 -288.137433) (xy 409.614129 -288.140653)
			(xy 409.623514 -288.139124) (xy 409.626308 -288.138616) (xy 409.64645 -288.133625) (xy 409.687601 -288.128273)
			(xy 409.70835 -288.127948) (xy 409.991306 -288.127948) (xy 410.012054 -288.128282) (xy 410.053204 -288.133633)
			(xy 410.073348 -288.138616) (xy 410.076142 -288.139124) (xy 410.085505 -288.140717) (xy 410.10421 -288.137458)
			(xy 410.12045 -288.127621) (xy 410.132003 -288.112553) (xy 410.137286 -288.094316) (xy 410.135577 -288.075406)
			(xy 410.127111 -288.058412) (xy 410.120338 -288.051748) (xy 410.101712 -288.03421) (xy 410.069969 -287.994097)
			(xy 410.045351 -287.949256) (xy 410.028545 -287.900942) (xy 410.02002 -287.850503) (xy 410.0195 -287.824926)
			(xy 410.020022 -287.799671) (xy 410.028335 -287.749849) (xy 410.044736 -287.702075) (xy 410.068777 -287.657652)
			(xy 410.099801 -287.617792) (xy 410.136963 -287.583582) (xy 410.179249 -287.555956) (xy 410.225505 -287.535666)
			(xy 410.27447 -287.523266) (xy 410.324808 -287.519095) (xy 410.375146 -287.523266) (xy 410.424111 -287.535666)
			(xy 410.470367 -287.555956) (xy 410.512653 -287.583582) (xy 410.549815 -287.617792) (xy 410.580839 -287.657652)
			(xy 410.60488 -287.702075) (xy 410.621281 -287.749849) (xy 410.629594 -287.799671) (xy 410.630116 -287.824926)
			(xy 410.629584 -287.850503) (xy 410.621063 -287.900943) (xy 410.604262 -287.949259) (xy 410.579651 -287.994104)
			(xy 410.547917 -288.034225) (xy 410.529278 -288.051748) (xy 410.52249 -288.058397) (xy 410.514003 -288.075384)
			(xy 410.512283 -288.094295) (xy 410.517567 -288.112534) (xy 410.529129 -288.127597) (xy 410.545382 -288.137417)
			(xy 410.564094 -288.140645) (xy 410.573474 -288.139124) (xy 410.576268 -288.138616) (xy 410.596408 -288.133614)
			(xy 410.637561 -288.128269) (xy 410.65831 -288.127948) (xy 410.94152 -288.127948) (xy 410.962268 -288.128279)
			(xy 411.003418 -288.133632) (xy 411.023562 -288.138616) (xy 411.026356 -288.139124) (xy 411.035717 -288.140727)
			(xy 411.054422 -288.137464) (xy 411.070661 -288.127625) (xy 411.082212 -288.112556) (xy 411.087495 -288.094319)
			(xy 411.085788 -288.075409) (xy 411.077323 -288.058413) (xy 411.070552 -288.051748) (xy 411.051929 -288.034207)
			(xy 411.020185 -287.994095) (xy 410.995566 -287.949255) (xy 410.978759 -287.900941) (xy 410.970235 -287.850503)
			(xy 410.969714 -287.824926) (xy 410.970236 -287.799671) (xy 410.978549 -287.749849) (xy 410.99495 -287.702075)
			(xy 411.018991 -287.657652) (xy 411.050015 -287.617792) (xy 411.087177 -287.583582) (xy 411.129463 -287.555956)
			(xy 411.175719 -287.535666) (xy 411.224684 -287.523266) (xy 411.275022 -287.519095) (xy 411.32536 -287.523266)
			(xy 411.374325 -287.535666) (xy 411.420581 -287.555956) (xy 411.462867 -287.583582) (xy 411.500029 -287.617792)
			(xy 411.531053 -287.657652) (xy 411.555094 -287.702075) (xy 411.571495 -287.749849) (xy 411.579808 -287.799671)
			(xy 411.58033 -287.824926) (xy 411.579794 -287.850503) (xy 411.571273 -287.900942) (xy 411.554473 -287.949258)
			(xy 411.529863 -287.994103) (xy 411.49813 -288.034225) (xy 411.479492 -288.051748) (xy 411.472693 -288.058388)
			(xy 411.464201 -288.075378) (xy 411.46248 -288.094293) (xy 411.467765 -288.112536) (xy 411.479331 -288.127603)
			(xy 411.495589 -288.137422) (xy 411.514306 -288.140648) (xy 411.523688 -288.139124) (xy 411.526482 -288.138616)
			(xy 411.546625 -288.13363) (xy 411.587775 -288.128275) (xy 411.608524 -288.127948) (xy 411.89148 -288.127948)
			(xy 411.912228 -288.128287) (xy 411.953378 -288.133635) (xy 411.973522 -288.138616) (xy 411.976316 -288.139124)
			(xy 411.985683 -288.140699) (xy 412.004389 -288.137447) (xy 412.020631 -288.127614) (xy 412.032185 -288.112548)
			(xy 412.037468 -288.094311) (xy 412.035757 -288.075402) (xy 412.027287 -288.05841) (xy 412.020512 -288.051748)
			(xy 412.001882 -288.034215) (xy 411.97014 -287.9941) (xy 411.945523 -287.949258) (xy 411.928718 -287.900943)
			(xy 411.920194 -287.850503) (xy 411.919674 -287.824926) (xy 411.920196 -287.799671) (xy 411.928509 -287.749849)
			(xy 411.94491 -287.702075) (xy 411.968951 -287.657652) (xy 411.999975 -287.617792) (xy 412.037137 -287.583582)
			(xy 412.079423 -287.555956) (xy 412.125679 -287.535666) (xy 412.174644 -287.523266) (xy 412.224982 -287.519095)
			(xy 412.27532 -287.523266) (xy 412.324285 -287.535666) (xy 412.370541 -287.555956) (xy 412.412827 -287.583582)
			(xy 412.449989 -287.617792) (xy 412.481013 -287.657652) (xy 412.505054 -287.702075) (xy 412.521455 -287.749849)
			(xy 412.529768 -287.799671) (xy 412.53029 -287.824926) (xy 412.529767 -287.850504) (xy 412.521245 -287.900944)
			(xy 412.504442 -287.949261) (xy 412.479829 -287.994106) (xy 412.448092 -288.034226) (xy 412.429452 -288.051748)
			(xy 412.422684 -288.058413) (xy 412.414205 -288.075395) (xy 412.412489 -288.094297) (xy 412.41777 -288.112529)
			(xy 412.429325 -288.127587) (xy 412.445568 -288.137406) (xy 412.464271 -288.14064) (xy 412.473648 -288.139124)
			(xy 412.476442 -288.138616) (xy 412.496583 -288.133619) (xy 412.537735 -288.128271) (xy 412.558484 -288.127948)
			(xy 412.84144 -288.127948) (xy 412.862188 -288.128275) (xy 412.903339 -288.133631) (xy 412.923482 -288.138616)
			(xy 412.926276 -288.139124) (xy 412.935649 -288.140672) (xy 412.954356 -288.13743) (xy 412.970602 -288.127604)
			(xy 412.982159 -288.11254) (xy 412.987442 -288.094304) (xy 412.985727 -288.075395) (xy 412.97725 -288.058406)
			(xy 412.970472 -288.051748) (xy 412.951853 -288.034203) (xy 412.920108 -287.994092) (xy 412.895487 -287.949254)
			(xy 412.87868 -287.900941) (xy 412.870155 -287.850503) (xy 412.869634 -287.824926) (xy 412.870156 -287.799671)
			(xy 412.878469 -287.749849) (xy 412.89487 -287.702075) (xy 412.918911 -287.657652) (xy 412.949935 -287.617792)
			(xy 412.987097 -287.583582) (xy 413.029383 -287.555956) (xy 413.075639 -287.535666) (xy 413.124604 -287.523266)
			(xy 413.174942 -287.519095) (xy 413.22528 -287.523266) (xy 413.274245 -287.535666) (xy 413.320501 -287.555956)
			(xy 413.362787 -287.583582) (xy 413.399949 -287.617792) (xy 413.430973 -287.657652) (xy 413.455014 -287.702075)
			(xy 413.471415 -287.749849) (xy 413.479728 -287.799671) (xy 413.48025 -287.824926) (xy 413.479707 -287.850502)
			(xy 413.471187 -287.900941) (xy 413.454388 -287.949257) (xy 413.42978 -287.994102) (xy 413.398049 -288.034224)
			(xy 413.379412 -288.051748) (xy 413.372597 -288.058376) (xy 413.3641 -288.07537) (xy 413.362376 -288.094291)
			(xy 413.367663 -288.11254) (xy 413.379234 -288.12761) (xy 413.395499 -288.137431) (xy 413.414224 -288.140651)
			(xy 413.423608 -288.139124) (xy 413.426402 -288.138616) (xy 413.446545 -288.133626) (xy 413.487695 -288.128274)
			(xy 413.508444 -288.127948) (xy 413.7914 -288.127948) (xy 413.812148 -288.128283) (xy 413.853298 -288.133634)
			(xy 413.873442 -288.138616) (xy 413.876236 -288.139124) (xy 413.8856 -288.140713) (xy 413.904306 -288.137456)
			(xy 413.920546 -288.12762) (xy 413.932099 -288.112552) (xy 413.937382 -288.094315) (xy 413.935673 -288.075405)
			(xy 413.927205 -288.058411) (xy 413.920432 -288.051748) (xy 413.901805 -288.034211) (xy 413.870063 -287.994097)
			(xy 413.845444 -287.949257) (xy 413.828638 -287.900942) (xy 413.820114 -287.850503) (xy 413.819594 -287.824926)
			(xy 413.820116 -287.799671) (xy 413.828429 -287.749849) (xy 413.84483 -287.702075) (xy 413.868871 -287.657652)
			(xy 413.899895 -287.617792) (xy 413.937057 -287.583582) (xy 413.979343 -287.555956) (xy 414.025599 -287.535666)
			(xy 414.074564 -287.523266) (xy 414.124902 -287.519095) (xy 414.17524 -287.523266) (xy 414.224205 -287.535666)
			(xy 414.270461 -287.555956) (xy 414.312747 -287.583582) (xy 414.349909 -287.617792) (xy 414.380933 -287.657652)
			(xy 414.404974 -287.702075) (xy 414.421375 -287.749849) (xy 414.429688 -287.799671) (xy 414.43021 -287.824926)
			(xy 414.42968 -287.850503) (xy 414.421159 -287.900943) (xy 414.404358 -287.94926) (xy 414.379746 -287.994104)
			(xy 414.348011 -288.034225) (xy 414.329372 -288.051748) (xy 414.322588 -288.058401) (xy 414.314103 -288.075386)
			(xy 414.312384 -288.094295) (xy 414.317668 -288.112532) (xy 414.329228 -288.127595) (xy 414.345478 -288.137414)
			(xy 414.364189 -288.140644) (xy 414.373568 -288.139124) (xy 414.376362 -288.138616) (xy 414.396502 -288.133615)
			(xy 414.437655 -288.12827) (xy 414.458404 -288.127948) (xy 414.74136 -288.127948) (xy 414.762108 -288.12829)
			(xy 414.803258 -288.133636) (xy 414.823402 -288.138616) (xy 414.826196 -288.139124) (xy 414.835566 -288.140685)
			(xy 414.854273 -288.137439) (xy 414.870517 -288.127609) (xy 414.882072 -288.112544) (xy 414.887355 -288.094307)
			(xy 414.885642 -288.075398) (xy 414.877168 -288.058408) (xy 414.870392 -288.051748) (xy 414.851777 -288.034199)
			(xy 414.82003 -287.99409) (xy 414.795409 -287.949252) (xy 414.7786 -287.90094) (xy 414.770075 -287.850502)
			(xy 414.769554 -287.824926) (xy 414.770076 -287.799671) (xy 414.778389 -287.749849) (xy 414.79479 -287.702075)
			(xy 414.818831 -287.657652) (xy 414.849855 -287.617792) (xy 414.887017 -287.583582) (xy 414.929303 -287.555956)
			(xy 414.975559 -287.535666) (xy 415.024524 -287.523266) (xy 415.074862 -287.519095) (xy 415.1252 -287.523266)
			(xy 415.174165 -287.535666) (xy 415.220421 -287.555956) (xy 415.262707 -287.583582) (xy 415.299869 -287.617792)
			(xy 415.330893 -287.657652) (xy 415.354934 -287.702075) (xy 415.371335 -287.749849) (xy 415.379648 -287.799671)
			(xy 415.38017 -287.824926) (xy 415.379621 -287.850502) (xy 415.371101 -287.90094) (xy 415.354303 -287.949256)
			(xy 415.329697 -287.994101) (xy 415.297968 -288.034223) (xy 415.279332 -288.051748) (xy 415.272501 -288.058363)
			(xy 415.263997 -288.075361) (xy 415.262271 -288.094289) (xy 415.26756 -288.112545) (xy 415.279136 -288.127619)
			(xy 415.295409 -288.137439) (xy 415.314141 -288.140656) (xy 415.323528 -288.139124) (xy 415.326322 -288.138616)
			(xy 415.346464 -288.133623) (xy 415.387615 -288.128272) (xy 415.408364 -288.127948) (xy 415.69132 -288.127948)
			(xy 415.712068 -288.128279) (xy 415.753218 -288.133632) (xy 415.773362 -288.138616) (xy 415.776156 -288.139124)
			(xy 415.785517 -288.140727) (xy 415.804222 -288.137464) (xy 415.820461 -288.127625) (xy 415.832012 -288.112556)
			(xy 415.837295 -288.094319) (xy 415.835588 -288.075409) (xy 415.827123 -288.058413) (xy 415.820352 -288.051748)
			(xy 415.801729 -288.034207) (xy 415.769985 -287.994095) (xy 415.745366 -287.949255) (xy 415.728559 -287.900941)
			(xy 415.720035 -287.850503) (xy 415.719514 -287.824926) (xy 415.720036 -287.799671) (xy 415.728349 -287.749849)
			(xy 415.74475 -287.702075) (xy 415.768791 -287.657652) (xy 415.799815 -287.617792) (xy 415.836977 -287.583582)
			(xy 415.879263 -287.555956) (xy 415.925519 -287.535666) (xy 415.974484 -287.523266) (xy 416.024822 -287.519095)
			(xy 416.07516 -287.523266) (xy 416.124125 -287.535666) (xy 416.170381 -287.555956) (xy 416.212667 -287.583582)
			(xy 416.249829 -287.617792) (xy 416.280853 -287.657652) (xy 416.304894 -287.702075) (xy 416.321295 -287.749849)
			(xy 416.329608 -287.799671) (xy 416.33013 -287.824926) (xy 416.329594 -287.850503) (xy 416.321073 -287.900942)
			(xy 416.304273 -287.949258) (xy 416.279663 -287.994103) (xy 416.24793 -288.034225) (xy 416.229292 -288.051748)
			(xy 416.222493 -288.058388) (xy 416.214001 -288.075378) (xy 416.21228 -288.094293) (xy 416.217565 -288.112536)
			(xy 416.229131 -288.127603) (xy 416.245389 -288.137422) (xy 416.264106 -288.140648) (xy 416.273488 -288.139124)
			(xy 416.276282 -288.138616) (xy 416.296425 -288.13363) (xy 416.337575 -288.128275) (xy 416.358324 -288.127948)
			(xy 416.64128 -288.127948) (xy 416.662028 -288.128287) (xy 416.703178 -288.133635) (xy 416.723322 -288.138616)
			(xy 416.732816 -288.140794) (xy 416.752143 -288.138445) (xy 416.769204 -288.129066) (xy 416.781544 -288.114007)
			(xy 416.787386 -288.095436) (xy 416.785891 -288.076024) (xy 416.777273 -288.058567) (xy 416.770312 -288.051748)
			(xy 416.751682 -288.034215) (xy 416.71994 -287.9941) (xy 416.695323 -287.949258) (xy 416.678518 -287.900943)
			(xy 416.669994 -287.850503) (xy 416.669474 -287.824926) (xy 416.669996 -287.799671) (xy 416.678309 -287.749849)
			(xy 416.69471 -287.702075) (xy 416.718751 -287.657652) (xy 416.749775 -287.617792) (xy 416.786937 -287.583582)
			(xy 416.829223 -287.555956) (xy 416.875479 -287.535666) (xy 416.924444 -287.523266) (xy 416.974782 -287.519095)
			(xy 417.02512 -287.523266) (xy 417.074085 -287.535666) (xy 417.120341 -287.555956) (xy 417.162627 -287.583582)
			(xy 417.199789 -287.617792) (xy 417.230813 -287.657652) (xy 417.254854 -287.702075) (xy 417.271255 -287.749849)
			(xy 417.279568 -287.799671) (xy 417.28009 -287.824926) (xy 418.569152 -287.824926) (xy 418.573112 -287.775872)
			(xy 418.584889 -287.728088) (xy 418.60418 -287.682812) (xy 418.630483 -287.641216) (xy 418.663118 -287.604379)
			(xy 418.701239 -287.573254) (xy 418.74386 -287.548647) (xy 418.789876 -287.531195) (xy 418.838095 -287.521351)
			(xy 418.88727 -287.51937) (xy 418.936125 -287.525302) (xy 418.983396 -287.538994) (xy 419.027858 -287.560092)
			(xy 419.068361 -287.588048) (xy 419.103854 -287.62214) (xy 419.133419 -287.661484) (xy 419.15629 -287.705061)
			(xy 419.171874 -287.751742) (xy 419.179769 -287.800319) (xy 419.180264 -287.824926) (xy 420.469072 -287.824926)
			(xy 420.473032 -287.775872) (xy 420.484809 -287.728088) (xy 420.5041 -287.682812) (xy 420.530403 -287.641216)
			(xy 420.563038 -287.604379) (xy 420.601159 -287.573254) (xy 420.64378 -287.548647) (xy 420.689796 -287.531195)
			(xy 420.738015 -287.521351) (xy 420.78719 -287.51937) (xy 420.836045 -287.525302) (xy 420.883316 -287.538994)
			(xy 420.927778 -287.560092) (xy 420.968281 -287.588048) (xy 421.003774 -287.62214) (xy 421.033339 -287.661484)
			(xy 421.05621 -287.705061) (xy 421.071794 -287.751742) (xy 421.079689 -287.800319) (xy 421.080184 -287.824926)
			(xy 421.079689 -287.849533) (xy 421.071794 -287.89811) (xy 421.05621 -287.944791) (xy 421.033339 -287.988368)
			(xy 421.003774 -288.027712) (xy 420.968281 -288.061804) (xy 420.927778 -288.08976) (xy 420.883316 -288.110858)
			(xy 420.836045 -288.12455) (xy 420.78719 -288.130482) (xy 420.738015 -288.128501) (xy 420.689796 -288.118657)
			(xy 420.64378 -288.101205) (xy 420.601159 -288.076598) (xy 420.563038 -288.045473) (xy 420.530403 -288.008636)
			(xy 420.5041 -287.96704) (xy 420.484809 -287.921764) (xy 420.473032 -287.87398) (xy 420.469072 -287.824926)
			(xy 419.180264 -287.824926) (xy 419.179769 -287.849533) (xy 419.171874 -287.89811) (xy 419.15629 -287.944791)
			(xy 419.133419 -287.988368) (xy 419.103854 -288.027712) (xy 419.068361 -288.061804) (xy 419.027858 -288.08976)
			(xy 418.983396 -288.110858) (xy 418.936125 -288.12455) (xy 418.88727 -288.130482) (xy 418.838095 -288.128501)
			(xy 418.789876 -288.118657) (xy 418.74386 -288.101205) (xy 418.701239 -288.076598) (xy 418.663118 -288.045473)
			(xy 418.630483 -288.008636) (xy 418.60418 -287.96704) (xy 418.584889 -287.921764) (xy 418.573112 -287.87398)
			(xy 418.569152 -287.824926) (xy 417.28009 -287.824926) (xy 417.279567 -287.850504) (xy 417.271045 -287.900944)
			(xy 417.254242 -287.949261) (xy 417.229629 -287.994106) (xy 417.197892 -288.034226) (xy 417.179252 -288.051748)
			(xy 417.17233 -288.058556) (xy 417.163819 -288.075992) (xy 417.162383 -288.09534) (xy 417.168226 -288.113841)
			(xy 417.180515 -288.128854) (xy 417.197497 -288.138238) (xy 417.216748 -288.140653) (xy 417.226242 -288.138616)
			(xy 417.246383 -288.133619) (xy 417.287535 -288.128271) (xy 417.308284 -288.127948) (xy 418.34562 -288.127948)
			(xy 418.35051 -288.128098) (xy 418.360102 -288.130008) (xy 418.36467 -288.131758) (xy 418.46627 -288.172652)
			(xy 418.471235 -288.174779) (xy 418.480201 -288.1808) (xy 418.48405 -288.18459) (xy 418.521388 -288.223452)
			(xy 418.521896 -288.22396) (xy 418.73678 -288.438844) (xy 418.756338 -288.46018) (xy 418.762676 -288.467043)
			(xy 418.778968 -288.476141) (xy 418.797434 -288.478832) (xy 418.80663 -288.477198) (xy 418.82342 -288.47362)
			(xy 418.857537 -288.469798) (xy 418.874702 -288.469578) (xy 418.874956 -288.469578) (xy 418.898947 -288.470079)
			(xy 418.94634 -288.477578) (xy 418.991976 -288.4924) (xy 419.034731 -288.514179) (xy 419.073552 -288.542378)
			(xy 419.107484 -288.576303) (xy 419.135691 -288.61512) (xy 419.157478 -288.657871) (xy 419.172308 -288.703504)
			(xy 419.179817 -288.750895) (xy 419.180264 -288.774886) (xy 419.519112 -288.774886) (xy 419.523072 -288.725832)
			(xy 419.534849 -288.678048) (xy 419.55414 -288.632772) (xy 419.580443 -288.591176) (xy 419.613078 -288.554339)
			(xy 419.651199 -288.523214) (xy 419.69382 -288.498607) (xy 419.739836 -288.481155) (xy 419.788055 -288.471311)
			(xy 419.83723 -288.46933) (xy 419.886085 -288.475262) (xy 419.933356 -288.488954) (xy 419.977818 -288.510052)
			(xy 420.018321 -288.538008) (xy 420.053814 -288.5721) (xy 420.083379 -288.611444) (xy 420.10625 -288.655021)
			(xy 420.121834 -288.701702) (xy 420.129729 -288.750279) (xy 420.130224 -288.774886) (xy 420.469072 -288.774886)
			(xy 420.473032 -288.725832) (xy 420.484809 -288.678048) (xy 420.5041 -288.632772) (xy 420.530403 -288.591176)
			(xy 420.563038 -288.554339) (xy 420.601159 -288.523214) (xy 420.64378 -288.498607) (xy 420.689796 -288.481155)
			(xy 420.738015 -288.471311) (xy 420.78719 -288.46933) (xy 420.836045 -288.475262) (xy 420.883316 -288.488954)
			(xy 420.927778 -288.510052) (xy 420.968281 -288.538008) (xy 421.003774 -288.5721) (xy 421.033339 -288.611444)
			(xy 421.05621 -288.655021) (xy 421.071794 -288.701702) (xy 421.079689 -288.750279) (xy 421.080184 -288.774886)
			(xy 421.079689 -288.799493) (xy 421.071794 -288.84807) (xy 421.05621 -288.894751) (xy 421.033339 -288.938328)
			(xy 421.003774 -288.977672) (xy 420.968281 -289.011764) (xy 420.927778 -289.03972) (xy 420.883316 -289.060818)
			(xy 420.836045 -289.07451) (xy 420.78719 -289.080442) (xy 420.738015 -289.078461) (xy 420.689796 -289.068617)
			(xy 420.64378 -289.051165) (xy 420.601159 -289.026558) (xy 420.563038 -288.995433) (xy 420.530403 -288.958596)
			(xy 420.5041 -288.917) (xy 420.484809 -288.871724) (xy 420.473032 -288.82394) (xy 420.469072 -288.774886)
			(xy 420.130224 -288.774886) (xy 420.129729 -288.799493) (xy 420.121834 -288.84807) (xy 420.10625 -288.894751)
			(xy 420.083379 -288.938328) (xy 420.053814 -288.977672) (xy 420.018321 -289.011764) (xy 419.977818 -289.03972)
			(xy 419.933356 -289.060818) (xy 419.886085 -289.07451) (xy 419.83723 -289.080442) (xy 419.788055 -289.078461)
			(xy 419.739836 -289.068617) (xy 419.69382 -289.051165) (xy 419.651199 -289.026558) (xy 419.613078 -288.995433)
			(xy 419.580443 -288.958596) (xy 419.55414 -288.917) (xy 419.534849 -288.871724) (xy 419.523072 -288.82394)
			(xy 419.519112 -288.774886) (xy 419.180264 -288.774886) (xy 419.179866 -288.797806) (xy 419.173009 -288.843131)
			(xy 419.15946 -288.886923) (xy 419.139524 -288.928202) (xy 419.126924 -288.947352) (xy 419.116764 -288.96183)
			(xy 419.11905 -288.996628) (xy 419.137338 -289.017202) (xy 419.14324 -289.024375) (xy 419.149887 -289.041704)
			(xy 419.150292 -289.050984) (xy 419.150292 -289.448748) (xy 419.149823 -289.458017) (xy 419.143198 -289.475335)
			(xy 419.137338 -289.48253) (xy 419.11905 -289.503104) (xy 419.116764 -289.537902) (xy 419.126924 -289.55238)
			(xy 419.141307 -289.574284) (xy 419.163068 -289.621951) (xy 419.176383 -289.67263) (xy 419.180861 -289.724838)
			(xy 419.18086 -289.724846) (xy 419.519112 -289.724846) (xy 419.523072 -289.675792) (xy 419.534849 -289.628008)
			(xy 419.55414 -289.582732) (xy 419.580443 -289.541136) (xy 419.613078 -289.504299) (xy 419.651199 -289.473174)
			(xy 419.69382 -289.448567) (xy 419.739836 -289.431115) (xy 419.788055 -289.421271) (xy 419.83723 -289.41929)
			(xy 419.886085 -289.425222) (xy 419.933356 -289.438914) (xy 419.977818 -289.460012) (xy 420.018321 -289.487968)
			(xy 420.053814 -289.52206) (xy 420.083379 -289.561404) (xy 420.10625 -289.604981) (xy 420.121834 -289.651662)
			(xy 420.129729 -289.700239) (xy 420.130224 -289.724846) (xy 420.469072 -289.724846) (xy 420.473032 -289.675792)
			(xy 420.484809 -289.628008) (xy 420.5041 -289.582732) (xy 420.530403 -289.541136) (xy 420.563038 -289.504299)
			(xy 420.601159 -289.473174) (xy 420.64378 -289.448567) (xy 420.689796 -289.431115) (xy 420.738015 -289.421271)
			(xy 420.78719 -289.41929) (xy 420.836045 -289.425222) (xy 420.883316 -289.438914) (xy 420.927778 -289.460012)
			(xy 420.968281 -289.487968) (xy 421.003774 -289.52206) (xy 421.033339 -289.561404) (xy 421.05621 -289.604981)
			(xy 421.071794 -289.651662) (xy 421.079689 -289.700239) (xy 421.080184 -289.724846) (xy 421.079689 -289.749453)
			(xy 421.071794 -289.79803) (xy 421.05621 -289.844711) (xy 421.033339 -289.888288) (xy 421.003774 -289.927632)
			(xy 420.968281 -289.961724) (xy 420.927778 -289.98968) (xy 420.883316 -290.010778) (xy 420.836045 -290.02447)
			(xy 420.78719 -290.030402) (xy 420.738015 -290.028421) (xy 420.689796 -290.018577) (xy 420.64378 -290.001125)
			(xy 420.601159 -289.976518) (xy 420.563038 -289.945393) (xy 420.530403 -289.908556) (xy 420.5041 -289.86696)
			(xy 420.484809 -289.821684) (xy 420.473032 -289.7739) (xy 420.469072 -289.724846) (xy 420.130224 -289.724846)
			(xy 420.129729 -289.749453) (xy 420.121834 -289.79803) (xy 420.10625 -289.844711) (xy 420.083379 -289.888288)
			(xy 420.053814 -289.927632) (xy 420.018321 -289.961724) (xy 419.977818 -289.98968) (xy 419.933356 -290.010778)
			(xy 419.886085 -290.02447) (xy 419.83723 -290.030402) (xy 419.788055 -290.028421) (xy 419.739836 -290.018577)
			(xy 419.69382 -290.001125) (xy 419.651199 -289.976518) (xy 419.613078 -289.945393) (xy 419.580443 -289.908556)
			(xy 419.55414 -289.86696) (xy 419.534849 -289.821684) (xy 419.523072 -289.7739) (xy 419.519112 -289.724846)
			(xy 419.18086 -289.724846) (xy 419.17637 -289.777045) (xy 419.163043 -289.827721) (xy 419.14127 -289.875382)
			(xy 419.126924 -289.897312) (xy 419.116764 -289.91179) (xy 419.11905 -289.946588) (xy 419.137338 -289.967162)
			(xy 419.143266 -289.974317) (xy 419.149897 -289.991659) (xy 419.150292 -290.000944) (xy 419.150292 -290.398708)
			(xy 419.149852 -290.40798) (xy 419.143207 -290.425298) (xy 419.137338 -290.43249) (xy 419.11905 -290.453064)
			(xy 419.116764 -290.487862) (xy 419.126924 -290.50234) (xy 419.141271 -290.524266) (xy 419.163036 -290.571927)
			(xy 419.176355 -290.622602) (xy 419.180838 -290.674805) (xy 419.180838 -290.674806) (xy 419.519112 -290.674806)
			(xy 419.523072 -290.625752) (xy 419.534849 -290.577968) (xy 419.55414 -290.532692) (xy 419.580443 -290.491096)
			(xy 419.613078 -290.454259) (xy 419.651199 -290.423134) (xy 419.69382 -290.398527) (xy 419.739836 -290.381075)
			(xy 419.788055 -290.371231) (xy 419.83723 -290.36925) (xy 419.886085 -290.375182) (xy 419.933356 -290.388874)
			(xy 419.977818 -290.409972) (xy 420.018321 -290.437928) (xy 420.053814 -290.47202) (xy 420.083379 -290.511364)
			(xy 420.10625 -290.554941) (xy 420.121834 -290.601622) (xy 420.129729 -290.650199) (xy 420.130224 -290.674806)
			(xy 420.469072 -290.674806) (xy 420.473032 -290.625752) (xy 420.484809 -290.577968) (xy 420.5041 -290.532692)
			(xy 420.530403 -290.491096) (xy 420.563038 -290.454259) (xy 420.601159 -290.423134) (xy 420.64378 -290.398527)
			(xy 420.689796 -290.381075) (xy 420.738015 -290.371231) (xy 420.78719 -290.36925) (xy 420.836045 -290.375182)
			(xy 420.883316 -290.388874) (xy 420.927778 -290.409972) (xy 420.968281 -290.437928) (xy 421.003774 -290.47202)
			(xy 421.033339 -290.511364) (xy 421.05621 -290.554941) (xy 421.071794 -290.601622) (xy 421.079689 -290.650199)
			(xy 421.080184 -290.674806) (xy 421.419032 -290.674806) (xy 421.422992 -290.625752) (xy 421.434769 -290.577968)
			(xy 421.45406 -290.532692) (xy 421.480363 -290.491096) (xy 421.512998 -290.454259) (xy 421.551119 -290.423134)
			(xy 421.59374 -290.398527) (xy 421.639756 -290.381075) (xy 421.687975 -290.371231) (xy 421.73715 -290.36925)
			(xy 421.786005 -290.375182) (xy 421.833276 -290.388874) (xy 421.877738 -290.409972) (xy 421.918241 -290.437928)
			(xy 421.953734 -290.47202) (xy 421.983299 -290.511364) (xy 422.00617 -290.554941) (xy 422.021754 -290.601622)
			(xy 422.029649 -290.650199) (xy 422.030144 -290.674806) (xy 422.368992 -290.674806) (xy 422.372952 -290.625752)
			(xy 422.384729 -290.577968) (xy 422.40402 -290.532692) (xy 422.430323 -290.491096) (xy 422.462958 -290.454259)
			(xy 422.501079 -290.423134) (xy 422.5437 -290.398527) (xy 422.589716 -290.381075) (xy 422.637935 -290.371231)
			(xy 422.68711 -290.36925) (xy 422.735965 -290.375182) (xy 422.783236 -290.388874) (xy 422.827698 -290.409972)
			(xy 422.868201 -290.437928) (xy 422.903694 -290.47202) (xy 422.933259 -290.511364) (xy 422.95613 -290.554941)
			(xy 422.971714 -290.601622) (xy 422.979609 -290.650199) (xy 422.980104 -290.674806) (xy 423.319206 -290.674806)
			(xy 423.323166 -290.625752) (xy 423.334943 -290.577968) (xy 423.354234 -290.532692) (xy 423.380537 -290.491096)
			(xy 423.413172 -290.454259) (xy 423.451293 -290.423134) (xy 423.493914 -290.398527) (xy 423.53993 -290.381075)
			(xy 423.588149 -290.371231) (xy 423.637324 -290.36925) (xy 423.686179 -290.375182) (xy 423.73345 -290.388874)
			(xy 423.777912 -290.409972) (xy 423.818415 -290.437928) (xy 423.853908 -290.47202) (xy 423.883473 -290.511364)
			(xy 423.906344 -290.554941) (xy 423.921928 -290.601622) (xy 423.929823 -290.650199) (xy 423.930318 -290.674806)
			(xy 424.269166 -290.674806) (xy 424.273126 -290.625752) (xy 424.284903 -290.577968) (xy 424.304194 -290.532692)
			(xy 424.330497 -290.491096) (xy 424.363132 -290.454259) (xy 424.401253 -290.423134) (xy 424.443874 -290.398527)
			(xy 424.48989 -290.381075) (xy 424.538109 -290.371231) (xy 424.587284 -290.36925) (xy 424.636139 -290.375182)
			(xy 424.68341 -290.388874) (xy 424.727872 -290.409972) (xy 424.768375 -290.437928) (xy 424.803868 -290.47202)
			(xy 424.833433 -290.511364) (xy 424.856304 -290.554941) (xy 424.871888 -290.601622) (xy 424.879783 -290.650199)
			(xy 424.880278 -290.674806) (xy 424.879783 -290.699413) (xy 424.871888 -290.74799) (xy 424.856304 -290.794671)
			(xy 424.833433 -290.838248) (xy 424.803868 -290.877592) (xy 424.768375 -290.911684) (xy 424.727872 -290.93964)
			(xy 424.68341 -290.960738) (xy 424.636139 -290.97443) (xy 424.587284 -290.980362) (xy 424.538109 -290.978381)
			(xy 424.48989 -290.968537) (xy 424.443874 -290.951085) (xy 424.401253 -290.926478) (xy 424.363132 -290.895353)
			(xy 424.330497 -290.858516) (xy 424.304194 -290.81692) (xy 424.284903 -290.771644) (xy 424.273126 -290.72386)
			(xy 424.269166 -290.674806) (xy 423.930318 -290.674806) (xy 423.929823 -290.699413) (xy 423.921928 -290.74799)
			(xy 423.906344 -290.794671) (xy 423.883473 -290.838248) (xy 423.853908 -290.877592) (xy 423.818415 -290.911684)
			(xy 423.777912 -290.93964) (xy 423.73345 -290.960738) (xy 423.686179 -290.97443) (xy 423.637324 -290.980362)
			(xy 423.588149 -290.978381) (xy 423.53993 -290.968537) (xy 423.493914 -290.951085) (xy 423.451293 -290.926478)
			(xy 423.413172 -290.895353) (xy 423.380537 -290.858516) (xy 423.354234 -290.81692) (xy 423.334943 -290.771644)
			(xy 423.323166 -290.72386) (xy 423.319206 -290.674806) (xy 422.980104 -290.674806) (xy 422.979609 -290.699413)
			(xy 422.971714 -290.74799) (xy 422.95613 -290.794671) (xy 422.933259 -290.838248) (xy 422.903694 -290.877592)
			(xy 422.868201 -290.911684) (xy 422.827698 -290.93964) (xy 422.783236 -290.960738) (xy 422.735965 -290.97443)
			(xy 422.68711 -290.980362) (xy 422.637935 -290.978381) (xy 422.589716 -290.968537) (xy 422.5437 -290.951085)
			(xy 422.501079 -290.926478) (xy 422.462958 -290.895353) (xy 422.430323 -290.858516) (xy 422.40402 -290.81692)
			(xy 422.384729 -290.771644) (xy 422.372952 -290.72386) (xy 422.368992 -290.674806) (xy 422.030144 -290.674806)
			(xy 422.029649 -290.699413) (xy 422.021754 -290.74799) (xy 422.00617 -290.794671) (xy 421.983299 -290.838248)
			(xy 421.953734 -290.877592) (xy 421.918241 -290.911684) (xy 421.877738 -290.93964) (xy 421.833276 -290.960738)
			(xy 421.786005 -290.97443) (xy 421.73715 -290.980362) (xy 421.687975 -290.978381) (xy 421.639756 -290.968537)
			(xy 421.59374 -290.951085) (xy 421.551119 -290.926478) (xy 421.512998 -290.895353) (xy 421.480363 -290.858516)
			(xy 421.45406 -290.81692) (xy 421.434769 -290.771644) (xy 421.422992 -290.72386) (xy 421.419032 -290.674806)
			(xy 421.080184 -290.674806) (xy 421.079689 -290.699413) (xy 421.071794 -290.74799) (xy 421.05621 -290.794671)
			(xy 421.033339 -290.838248) (xy 421.003774 -290.877592) (xy 420.968281 -290.911684) (xy 420.927778 -290.93964)
			(xy 420.883316 -290.960738) (xy 420.836045 -290.97443) (xy 420.78719 -290.980362) (xy 420.738015 -290.978381)
			(xy 420.689796 -290.968537) (xy 420.64378 -290.951085) (xy 420.601159 -290.926478) (xy 420.563038 -290.895353)
			(xy 420.530403 -290.858516) (xy 420.5041 -290.81692) (xy 420.484809 -290.771644) (xy 420.473032 -290.72386)
			(xy 420.469072 -290.674806) (xy 420.130224 -290.674806) (xy 420.129729 -290.699413) (xy 420.121834 -290.74799)
			(xy 420.10625 -290.794671) (xy 420.083379 -290.838248) (xy 420.053814 -290.877592) (xy 420.018321 -290.911684)
			(xy 419.977818 -290.93964) (xy 419.933356 -290.960738) (xy 419.886085 -290.97443) (xy 419.83723 -290.980362)
			(xy 419.788055 -290.978381) (xy 419.739836 -290.968537) (xy 419.69382 -290.951085) (xy 419.651199 -290.926478)
			(xy 419.613078 -290.895353) (xy 419.580443 -290.858516) (xy 419.55414 -290.81692) (xy 419.534849 -290.771644)
			(xy 419.523072 -290.72386) (xy 419.519112 -290.674806) (xy 419.180838 -290.674806) (xy 419.176353 -290.727008)
			(xy 419.163033 -290.777682) (xy 419.141266 -290.825342) (xy 419.126924 -290.847272) (xy 419.116764 -290.86175)
			(xy 419.11905 -290.896548) (xy 419.137338 -290.917122) (xy 419.143249 -290.924289) (xy 419.14989 -290.941622)
			(xy 419.150292 -290.950904) (xy 419.150292 -291.348668) (xy 419.149833 -291.357938) (xy 419.143201 -291.375256)
			(xy 419.137338 -291.38245) (xy 419.11905 -291.403024) (xy 419.116764 -291.437822) (xy 419.126924 -291.4523)
			(xy 419.141235 -291.474249) (xy 419.163004 -291.521904) (xy 419.176327 -291.572573) (xy 419.180814 -291.624766)
			(xy 419.519112 -291.624766) (xy 419.523072 -291.575712) (xy 419.534849 -291.527928) (xy 419.55414 -291.482652)
			(xy 419.580443 -291.441056) (xy 419.613078 -291.404219) (xy 419.651199 -291.373094) (xy 419.69382 -291.348487)
			(xy 419.739836 -291.331035) (xy 419.788055 -291.321191) (xy 419.83723 -291.31921) (xy 419.886085 -291.325142)
			(xy 419.933356 -291.338834) (xy 419.977818 -291.359932) (xy 420.018321 -291.387888) (xy 420.053814 -291.42198)
			(xy 420.083379 -291.461324) (xy 420.10625 -291.504901) (xy 420.121834 -291.551582) (xy 420.129729 -291.600159)
			(xy 420.130224 -291.624766) (xy 420.469072 -291.624766) (xy 420.473032 -291.575712) (xy 420.484809 -291.527928)
			(xy 420.5041 -291.482652) (xy 420.530403 -291.441056) (xy 420.563038 -291.404219) (xy 420.601159 -291.373094)
			(xy 420.64378 -291.348487) (xy 420.689796 -291.331035) (xy 420.738015 -291.321191) (xy 420.78719 -291.31921)
			(xy 420.836045 -291.325142) (xy 420.883316 -291.338834) (xy 420.927778 -291.359932) (xy 420.968281 -291.387888)
			(xy 421.003774 -291.42198) (xy 421.033339 -291.461324) (xy 421.05621 -291.504901) (xy 421.071794 -291.551582)
			(xy 421.079689 -291.600159) (xy 421.080184 -291.624766) (xy 421.419032 -291.624766) (xy 421.422992 -291.575712)
			(xy 421.434769 -291.527928) (xy 421.45406 -291.482652) (xy 421.480363 -291.441056) (xy 421.512998 -291.404219)
			(xy 421.551119 -291.373094) (xy 421.59374 -291.348487) (xy 421.639756 -291.331035) (xy 421.687975 -291.321191)
			(xy 421.73715 -291.31921) (xy 421.786005 -291.325142) (xy 421.833276 -291.338834) (xy 421.877738 -291.359932)
			(xy 421.918241 -291.387888) (xy 421.953734 -291.42198) (xy 421.983299 -291.461324) (xy 422.00617 -291.504901)
			(xy 422.021754 -291.551582) (xy 422.029649 -291.600159) (xy 422.030144 -291.624766) (xy 422.369246 -291.624766)
			(xy 422.373206 -291.575712) (xy 422.384983 -291.527928) (xy 422.404274 -291.482652) (xy 422.430577 -291.441056)
			(xy 422.463212 -291.404219) (xy 422.501333 -291.373094) (xy 422.543954 -291.348487) (xy 422.58997 -291.331035)
			(xy 422.638189 -291.321191) (xy 422.687364 -291.31921) (xy 422.736219 -291.325142) (xy 422.78349 -291.338834)
			(xy 422.827952 -291.359932) (xy 422.868455 -291.387888) (xy 422.903948 -291.42198) (xy 422.933513 -291.461324)
			(xy 422.956384 -291.504901) (xy 422.971968 -291.551582) (xy 422.979863 -291.600159) (xy 422.980358 -291.624766)
			(xy 424.269166 -291.624766) (xy 424.273126 -291.575712) (xy 424.284903 -291.527928) (xy 424.304194 -291.482652)
			(xy 424.330497 -291.441056) (xy 424.363132 -291.404219) (xy 424.401253 -291.373094) (xy 424.443874 -291.348487)
			(xy 424.48989 -291.331035) (xy 424.538109 -291.321191) (xy 424.587284 -291.31921) (xy 424.636139 -291.325142)
			(xy 424.68341 -291.338834) (xy 424.727872 -291.359932) (xy 424.768375 -291.387888) (xy 424.803868 -291.42198)
			(xy 424.833433 -291.461324) (xy 424.856304 -291.504901) (xy 424.871888 -291.551582) (xy 424.879783 -291.600159)
			(xy 424.880278 -291.624766) (xy 424.879783 -291.649373) (xy 424.871888 -291.69795) (xy 424.856304 -291.744631)
			(xy 424.833433 -291.788208) (xy 424.803868 -291.827552) (xy 424.768375 -291.861644) (xy 424.727872 -291.8896)
			(xy 424.68341 -291.910698) (xy 424.636139 -291.92439) (xy 424.587284 -291.930322) (xy 424.538109 -291.928341)
			(xy 424.48989 -291.918497) (xy 424.443874 -291.901045) (xy 424.401253 -291.876438) (xy 424.363132 -291.845313)
			(xy 424.330497 -291.808476) (xy 424.304194 -291.76688) (xy 424.284903 -291.721604) (xy 424.273126 -291.67382)
			(xy 424.269166 -291.624766) (xy 422.980358 -291.624766) (xy 422.979863 -291.649373) (xy 422.971968 -291.69795)
			(xy 422.956384 -291.744631) (xy 422.933513 -291.788208) (xy 422.903948 -291.827552) (xy 422.868455 -291.861644)
			(xy 422.827952 -291.8896) (xy 422.78349 -291.910698) (xy 422.736219 -291.92439) (xy 422.687364 -291.930322)
			(xy 422.638189 -291.928341) (xy 422.58997 -291.918497) (xy 422.543954 -291.901045) (xy 422.501333 -291.876438)
			(xy 422.463212 -291.845313) (xy 422.430577 -291.808476) (xy 422.404274 -291.76688) (xy 422.384983 -291.721604)
			(xy 422.373206 -291.67382) (xy 422.369246 -291.624766) (xy 422.030144 -291.624766) (xy 422.029649 -291.649373)
			(xy 422.021754 -291.69795) (xy 422.00617 -291.744631) (xy 421.983299 -291.788208) (xy 421.953734 -291.827552)
			(xy 421.918241 -291.861644) (xy 421.877738 -291.8896) (xy 421.833276 -291.910698) (xy 421.786005 -291.92439)
			(xy 421.73715 -291.930322) (xy 421.687975 -291.928341) (xy 421.639756 -291.918497) (xy 421.59374 -291.901045)
			(xy 421.551119 -291.876438) (xy 421.512998 -291.845313) (xy 421.480363 -291.808476) (xy 421.45406 -291.76688)
			(xy 421.434769 -291.721604) (xy 421.422992 -291.67382) (xy 421.419032 -291.624766) (xy 421.080184 -291.624766)
			(xy 421.079689 -291.649373) (xy 421.071794 -291.69795) (xy 421.05621 -291.744631) (xy 421.033339 -291.788208)
			(xy 421.003774 -291.827552) (xy 420.968281 -291.861644) (xy 420.927778 -291.8896) (xy 420.883316 -291.910698)
			(xy 420.836045 -291.92439) (xy 420.78719 -291.930322) (xy 420.738015 -291.928341) (xy 420.689796 -291.918497)
			(xy 420.64378 -291.901045) (xy 420.601159 -291.876438) (xy 420.563038 -291.845313) (xy 420.530403 -291.808476)
			(xy 420.5041 -291.76688) (xy 420.484809 -291.721604) (xy 420.473032 -291.67382) (xy 420.469072 -291.624766)
			(xy 420.130224 -291.624766) (xy 420.129729 -291.649373) (xy 420.121834 -291.69795) (xy 420.10625 -291.744631)
			(xy 420.083379 -291.788208) (xy 420.053814 -291.827552) (xy 420.018321 -291.861644) (xy 419.977818 -291.8896)
			(xy 419.933356 -291.910698) (xy 419.886085 -291.92439) (xy 419.83723 -291.930322) (xy 419.788055 -291.928341)
			(xy 419.739836 -291.918497) (xy 419.69382 -291.901045) (xy 419.651199 -291.876438) (xy 419.613078 -291.845313)
			(xy 419.580443 -291.808476) (xy 419.55414 -291.76688) (xy 419.534849 -291.721604) (xy 419.523072 -291.67382)
			(xy 419.519112 -291.624766) (xy 419.180814 -291.624766) (xy 419.180815 -291.624772) (xy 419.176337 -291.676972)
			(xy 419.163023 -291.727643) (xy 419.141263 -291.775302) (xy 419.126924 -291.797232) (xy 419.116764 -291.81171)
			(xy 419.11905 -291.846508) (xy 419.137338 -291.867082) (xy 419.143232 -291.874261) (xy 419.149884 -291.891585)
			(xy 419.150292 -291.900864) (xy 419.150292 -292.298882) (xy 419.149839 -292.308153) (xy 419.143203 -292.32547)
			(xy 419.137338 -292.332664) (xy 419.11905 -292.353238) (xy 419.116764 -292.388036) (xy 419.126924 -292.402514)
			(xy 419.141248 -292.424455) (xy 419.163015 -292.472112) (xy 419.176337 -292.522783) (xy 419.180801 -292.574726)
			(xy 419.519112 -292.574726) (xy 419.523072 -292.525672) (xy 419.534849 -292.477888) (xy 419.55414 -292.432612)
			(xy 419.580443 -292.391016) (xy 419.613078 -292.354179) (xy 419.651199 -292.323054) (xy 419.69382 -292.298447)
			(xy 419.739836 -292.280995) (xy 419.788055 -292.271151) (xy 419.83723 -292.26917) (xy 419.886085 -292.275102)
			(xy 419.933356 -292.288794) (xy 419.977818 -292.309892) (xy 420.018321 -292.337848) (xy 420.053814 -292.37194)
			(xy 420.083379 -292.411284) (xy 420.10625 -292.454861) (xy 420.121834 -292.501542) (xy 420.129729 -292.550119)
			(xy 420.130224 -292.574726) (xy 420.469072 -292.574726) (xy 420.473032 -292.525672) (xy 420.484809 -292.477888)
			(xy 420.5041 -292.432612) (xy 420.530403 -292.391016) (xy 420.563038 -292.354179) (xy 420.601159 -292.323054)
			(xy 420.64378 -292.298447) (xy 420.689796 -292.280995) (xy 420.738015 -292.271151) (xy 420.78719 -292.26917)
			(xy 420.836045 -292.275102) (xy 420.883316 -292.288794) (xy 420.927778 -292.309892) (xy 420.968281 -292.337848)
			(xy 421.003774 -292.37194) (xy 421.033339 -292.411284) (xy 421.05621 -292.454861) (xy 421.071794 -292.501542)
			(xy 421.079689 -292.550119) (xy 421.080184 -292.574726) (xy 421.419032 -292.574726) (xy 421.422992 -292.525672)
			(xy 421.434769 -292.477888) (xy 421.45406 -292.432612) (xy 421.480363 -292.391016) (xy 421.512998 -292.354179)
			(xy 421.551119 -292.323054) (xy 421.59374 -292.298447) (xy 421.639756 -292.280995) (xy 421.687975 -292.271151)
			(xy 421.73715 -292.26917) (xy 421.786005 -292.275102) (xy 421.833276 -292.288794) (xy 421.877738 -292.309892)
			(xy 421.918241 -292.337848) (xy 421.953734 -292.37194) (xy 421.983299 -292.411284) (xy 422.00617 -292.454861)
			(xy 422.021754 -292.501542) (xy 422.029649 -292.550119) (xy 422.030144 -292.574726) (xy 422.368992 -292.574726)
			(xy 422.372952 -292.525672) (xy 422.384729 -292.477888) (xy 422.40402 -292.432612) (xy 422.430323 -292.391016)
			(xy 422.462958 -292.354179) (xy 422.501079 -292.323054) (xy 422.5437 -292.298447) (xy 422.589716 -292.280995)
			(xy 422.637935 -292.271151) (xy 422.68711 -292.26917) (xy 422.735965 -292.275102) (xy 422.783236 -292.288794)
			(xy 422.827698 -292.309892) (xy 422.868201 -292.337848) (xy 422.903694 -292.37194) (xy 422.933259 -292.411284)
			(xy 422.95613 -292.454861) (xy 422.971714 -292.501542) (xy 422.979609 -292.550119) (xy 422.980104 -292.574726)
			(xy 423.319206 -292.574726) (xy 423.323166 -292.525672) (xy 423.334943 -292.477888) (xy 423.354234 -292.432612)
			(xy 423.380537 -292.391016) (xy 423.413172 -292.354179) (xy 423.451293 -292.323054) (xy 423.493914 -292.298447)
			(xy 423.53993 -292.280995) (xy 423.588149 -292.271151) (xy 423.637324 -292.26917) (xy 423.686179 -292.275102)
			(xy 423.73345 -292.288794) (xy 423.777912 -292.309892) (xy 423.818415 -292.337848) (xy 423.853908 -292.37194)
			(xy 423.883473 -292.411284) (xy 423.906344 -292.454861) (xy 423.921928 -292.501542) (xy 423.929823 -292.550119)
			(xy 423.930318 -292.574726) (xy 424.269166 -292.574726) (xy 424.273126 -292.525672) (xy 424.284903 -292.477888)
			(xy 424.304194 -292.432612) (xy 424.330497 -292.391016) (xy 424.363132 -292.354179) (xy 424.401253 -292.323054)
			(xy 424.443874 -292.298447) (xy 424.48989 -292.280995) (xy 424.538109 -292.271151) (xy 424.587284 -292.26917)
			(xy 424.636139 -292.275102) (xy 424.68341 -292.288794) (xy 424.727872 -292.309892) (xy 424.768375 -292.337848)
			(xy 424.803868 -292.37194) (xy 424.833433 -292.411284) (xy 424.856304 -292.454861) (xy 424.871888 -292.501542)
			(xy 424.879783 -292.550119) (xy 424.880278 -292.574726) (xy 424.879783 -292.599333) (xy 424.871888 -292.64791)
			(xy 424.856304 -292.694591) (xy 424.833433 -292.738168) (xy 424.803868 -292.777512) (xy 424.768375 -292.811604)
			(xy 424.727872 -292.83956) (xy 424.68341 -292.860658) (xy 424.636139 -292.87435) (xy 424.587284 -292.880282)
			(xy 424.538109 -292.878301) (xy 424.48989 -292.868457) (xy 424.443874 -292.851005) (xy 424.401253 -292.826398)
			(xy 424.363132 -292.795273) (xy 424.330497 -292.758436) (xy 424.304194 -292.71684) (xy 424.284903 -292.671564)
			(xy 424.273126 -292.62378) (xy 424.269166 -292.574726) (xy 423.930318 -292.574726) (xy 423.929823 -292.599333)
			(xy 423.921928 -292.64791) (xy 423.906344 -292.694591) (xy 423.883473 -292.738168) (xy 423.853908 -292.777512)
			(xy 423.818415 -292.811604) (xy 423.777912 -292.83956) (xy 423.73345 -292.860658) (xy 423.686179 -292.87435)
			(xy 423.637324 -292.880282) (xy 423.588149 -292.878301) (xy 423.53993 -292.868457) (xy 423.493914 -292.851005)
			(xy 423.451293 -292.826398) (xy 423.413172 -292.795273) (xy 423.380537 -292.758436) (xy 423.354234 -292.71684)
			(xy 423.334943 -292.671564) (xy 423.323166 -292.62378) (xy 423.319206 -292.574726) (xy 422.980104 -292.574726)
			(xy 422.979609 -292.599333) (xy 422.971714 -292.64791) (xy 422.95613 -292.694591) (xy 422.933259 -292.738168)
			(xy 422.903694 -292.777512) (xy 422.868201 -292.811604) (xy 422.827698 -292.83956) (xy 422.783236 -292.860658)
			(xy 422.735965 -292.87435) (xy 422.68711 -292.880282) (xy 422.637935 -292.878301) (xy 422.589716 -292.868457)
			(xy 422.5437 -292.851005) (xy 422.501079 -292.826398) (xy 422.462958 -292.795273) (xy 422.430323 -292.758436)
			(xy 422.40402 -292.71684) (xy 422.384729 -292.671564) (xy 422.372952 -292.62378) (xy 422.368992 -292.574726)
			(xy 422.030144 -292.574726) (xy 422.029649 -292.599333) (xy 422.021754 -292.64791) (xy 422.00617 -292.694591)
			(xy 421.983299 -292.738168) (xy 421.953734 -292.777512) (xy 421.918241 -292.811604) (xy 421.877738 -292.83956)
			(xy 421.833276 -292.860658) (xy 421.786005 -292.87435) (xy 421.73715 -292.880282) (xy 421.687975 -292.878301)
			(xy 421.639756 -292.868457) (xy 421.59374 -292.851005) (xy 421.551119 -292.826398) (xy 421.512998 -292.795273)
			(xy 421.480363 -292.758436) (xy 421.45406 -292.71684) (xy 421.434769 -292.671564) (xy 421.422992 -292.62378)
			(xy 421.419032 -292.574726) (xy 421.080184 -292.574726) (xy 421.079689 -292.599333) (xy 421.071794 -292.64791)
			(xy 421.05621 -292.694591) (xy 421.033339 -292.738168) (xy 421.003774 -292.777512) (xy 420.968281 -292.811604)
			(xy 420.927778 -292.83956) (xy 420.883316 -292.860658) (xy 420.836045 -292.87435) (xy 420.78719 -292.880282)
			(xy 420.738015 -292.878301) (xy 420.689796 -292.868457) (xy 420.64378 -292.851005) (xy 420.601159 -292.826398)
			(xy 420.563038 -292.795273) (xy 420.530403 -292.758436) (xy 420.5041 -292.71684) (xy 420.484809 -292.671564)
			(xy 420.473032 -292.62378) (xy 420.469072 -292.574726) (xy 420.130224 -292.574726) (xy 420.129729 -292.599333)
			(xy 420.121834 -292.64791) (xy 420.10625 -292.694591) (xy 420.083379 -292.738168) (xy 420.053814 -292.777512)
			(xy 420.018321 -292.811604) (xy 419.977818 -292.83956) (xy 419.933356 -292.860658) (xy 419.886085 -292.87435)
			(xy 419.83723 -292.880282) (xy 419.788055 -292.878301) (xy 419.739836 -292.868457) (xy 419.69382 -292.851005)
			(xy 419.651199 -292.826398) (xy 419.613078 -292.795273) (xy 419.580443 -292.758436) (xy 419.55414 -292.71684)
			(xy 419.534849 -292.671564) (xy 419.523072 -292.62378) (xy 419.519112 -292.574726) (xy 419.180801 -292.574726)
			(xy 419.180823 -292.574983) (xy 419.176343 -292.627184) (xy 419.163026 -292.677857) (xy 419.141264 -292.725516)
			(xy 419.126924 -292.747446) (xy 419.116764 -292.761924) (xy 419.11905 -292.796722) (xy 419.137338 -292.817296)
			(xy 419.143238 -292.824471) (xy 419.149886 -292.841798) (xy 419.150292 -292.851078) (xy 419.150292 -293.248842)
			(xy 419.14982 -293.258111) (xy 419.143197 -293.275429) (xy 419.137338 -293.282624) (xy 419.11905 -293.303198)
			(xy 419.116764 -293.337996) (xy 419.126924 -293.352474) (xy 419.141302 -293.374381) (xy 419.163064 -293.422047)
			(xy 419.176379 -293.472726) (xy 419.180857 -293.524933) (xy 419.180856 -293.52494) (xy 419.519112 -293.52494)
			(xy 419.523072 -293.475886) (xy 419.534849 -293.428102) (xy 419.55414 -293.382826) (xy 419.580443 -293.34123)
			(xy 419.613078 -293.304393) (xy 419.651199 -293.273268) (xy 419.69382 -293.248661) (xy 419.739836 -293.231209)
			(xy 419.788055 -293.221365) (xy 419.83723 -293.219384) (xy 419.886085 -293.225316) (xy 419.933356 -293.239008)
			(xy 419.977818 -293.260106) (xy 420.018321 -293.288062) (xy 420.053814 -293.322154) (xy 420.083379 -293.361498)
			(xy 420.10625 -293.405075) (xy 420.121834 -293.451756) (xy 420.129729 -293.500333) (xy 420.130224 -293.52494)
			(xy 420.469072 -293.52494) (xy 420.473032 -293.475886) (xy 420.484809 -293.428102) (xy 420.5041 -293.382826)
			(xy 420.530403 -293.34123) (xy 420.563038 -293.304393) (xy 420.601159 -293.273268) (xy 420.64378 -293.248661)
			(xy 420.689796 -293.231209) (xy 420.738015 -293.221365) (xy 420.78719 -293.219384) (xy 420.836045 -293.225316)
			(xy 420.883316 -293.239008) (xy 420.927778 -293.260106) (xy 420.968281 -293.288062) (xy 421.003774 -293.322154)
			(xy 421.033339 -293.361498) (xy 421.05621 -293.405075) (xy 421.071794 -293.451756) (xy 421.079689 -293.500333)
			(xy 421.080184 -293.52494) (xy 421.419032 -293.52494) (xy 421.422992 -293.475886) (xy 421.434769 -293.428102)
			(xy 421.45406 -293.382826) (xy 421.480363 -293.34123) (xy 421.512998 -293.304393) (xy 421.551119 -293.273268)
			(xy 421.59374 -293.248661) (xy 421.639756 -293.231209) (xy 421.687975 -293.221365) (xy 421.73715 -293.219384)
			(xy 421.786005 -293.225316) (xy 421.833276 -293.239008) (xy 421.877738 -293.260106) (xy 421.918241 -293.288062)
			(xy 421.953734 -293.322154) (xy 421.983299 -293.361498) (xy 422.00617 -293.405075) (xy 422.021754 -293.451756)
			(xy 422.029649 -293.500333) (xy 422.030144 -293.52494) (xy 422.369246 -293.52494) (xy 422.373206 -293.475886)
			(xy 422.384983 -293.428102) (xy 422.404274 -293.382826) (xy 422.430577 -293.34123) (xy 422.463212 -293.304393)
			(xy 422.501333 -293.273268) (xy 422.543954 -293.248661) (xy 422.58997 -293.231209) (xy 422.638189 -293.221365)
			(xy 422.687364 -293.219384) (xy 422.736219 -293.225316) (xy 422.78349 -293.239008) (xy 422.827952 -293.260106)
			(xy 422.868455 -293.288062) (xy 422.903948 -293.322154) (xy 422.933513 -293.361498) (xy 422.956384 -293.405075)
			(xy 422.971968 -293.451756) (xy 422.979863 -293.500333) (xy 422.980358 -293.52494) (xy 423.319206 -293.52494)
			(xy 423.323166 -293.475886) (xy 423.334943 -293.428102) (xy 423.354234 -293.382826) (xy 423.380537 -293.34123)
			(xy 423.413172 -293.304393) (xy 423.451293 -293.273268) (xy 423.493914 -293.248661) (xy 423.53993 -293.231209)
			(xy 423.588149 -293.221365) (xy 423.637324 -293.219384) (xy 423.686179 -293.225316) (xy 423.73345 -293.239008)
			(xy 423.777912 -293.260106) (xy 423.818415 -293.288062) (xy 423.853908 -293.322154) (xy 423.883473 -293.361498)
			(xy 423.906344 -293.405075) (xy 423.921928 -293.451756) (xy 423.929823 -293.500333) (xy 423.930318 -293.52494)
			(xy 424.269166 -293.52494) (xy 424.273126 -293.475886) (xy 424.284903 -293.428102) (xy 424.304194 -293.382826)
			(xy 424.330497 -293.34123) (xy 424.363132 -293.304393) (xy 424.401253 -293.273268) (xy 424.443874 -293.248661)
			(xy 424.48989 -293.231209) (xy 424.538109 -293.221365) (xy 424.587284 -293.219384) (xy 424.636139 -293.225316)
			(xy 424.68341 -293.239008) (xy 424.727872 -293.260106) (xy 424.768375 -293.288062) (xy 424.803868 -293.322154)
			(xy 424.833433 -293.361498) (xy 424.856304 -293.405075) (xy 424.871888 -293.451756) (xy 424.879783 -293.500333)
			(xy 424.880278 -293.52494) (xy 424.879783 -293.549547) (xy 424.871888 -293.598124) (xy 424.856304 -293.644805)
			(xy 424.833433 -293.688382) (xy 424.803868 -293.727726) (xy 424.768375 -293.761818) (xy 424.727872 -293.789774)
			(xy 424.68341 -293.810872) (xy 424.636139 -293.824564) (xy 424.587284 -293.830496) (xy 424.538109 -293.828515)
			(xy 424.48989 -293.818671) (xy 424.443874 -293.801219) (xy 424.401253 -293.776612) (xy 424.363132 -293.745487)
			(xy 424.330497 -293.70865) (xy 424.304194 -293.667054) (xy 424.284903 -293.621778) (xy 424.273126 -293.573994)
			(xy 424.269166 -293.52494) (xy 423.930318 -293.52494) (xy 423.929823 -293.549547) (xy 423.921928 -293.598124)
			(xy 423.906344 -293.644805) (xy 423.883473 -293.688382) (xy 423.853908 -293.727726) (xy 423.818415 -293.761818)
			(xy 423.777912 -293.789774) (xy 423.73345 -293.810872) (xy 423.686179 -293.824564) (xy 423.637324 -293.830496)
			(xy 423.588149 -293.828515) (xy 423.53993 -293.818671) (xy 423.493914 -293.801219) (xy 423.451293 -293.776612)
			(xy 423.413172 -293.745487) (xy 423.380537 -293.70865) (xy 423.354234 -293.667054) (xy 423.334943 -293.621778)
			(xy 423.323166 -293.573994) (xy 423.319206 -293.52494) (xy 422.980358 -293.52494) (xy 422.979863 -293.549547)
			(xy 422.971968 -293.598124) (xy 422.956384 -293.644805) (xy 422.933513 -293.688382) (xy 422.903948 -293.727726)
			(xy 422.868455 -293.761818) (xy 422.827952 -293.789774) (xy 422.78349 -293.810872) (xy 422.736219 -293.824564)
			(xy 422.687364 -293.830496) (xy 422.638189 -293.828515) (xy 422.58997 -293.818671) (xy 422.543954 -293.801219)
			(xy 422.501333 -293.776612) (xy 422.463212 -293.745487) (xy 422.430577 -293.70865) (xy 422.404274 -293.667054)
			(xy 422.384983 -293.621778) (xy 422.373206 -293.573994) (xy 422.369246 -293.52494) (xy 422.030144 -293.52494)
			(xy 422.029649 -293.549547) (xy 422.021754 -293.598124) (xy 422.00617 -293.644805) (xy 421.983299 -293.688382)
			(xy 421.953734 -293.727726) (xy 421.918241 -293.761818) (xy 421.877738 -293.789774) (xy 421.833276 -293.810872)
			(xy 421.786005 -293.824564) (xy 421.73715 -293.830496) (xy 421.687975 -293.828515) (xy 421.639756 -293.818671)
			(xy 421.59374 -293.801219) (xy 421.551119 -293.776612) (xy 421.512998 -293.745487) (xy 421.480363 -293.70865)
			(xy 421.45406 -293.667054) (xy 421.434769 -293.621778) (xy 421.422992 -293.573994) (xy 421.419032 -293.52494)
			(xy 421.080184 -293.52494) (xy 421.079689 -293.549547) (xy 421.071794 -293.598124) (xy 421.05621 -293.644805)
			(xy 421.033339 -293.688382) (xy 421.003774 -293.727726) (xy 420.968281 -293.761818) (xy 420.927778 -293.789774)
			(xy 420.883316 -293.810872) (xy 420.836045 -293.824564) (xy 420.78719 -293.830496) (xy 420.738015 -293.828515)
			(xy 420.689796 -293.818671) (xy 420.64378 -293.801219) (xy 420.601159 -293.776612) (xy 420.563038 -293.745487)
			(xy 420.530403 -293.70865) (xy 420.5041 -293.667054) (xy 420.484809 -293.621778) (xy 420.473032 -293.573994)
			(xy 420.469072 -293.52494) (xy 420.130224 -293.52494) (xy 420.129729 -293.549547) (xy 420.121834 -293.598124)
			(xy 420.10625 -293.644805) (xy 420.083379 -293.688382) (xy 420.053814 -293.727726) (xy 420.018321 -293.761818)
			(xy 419.977818 -293.789774) (xy 419.933356 -293.810872) (xy 419.886085 -293.824564) (xy 419.83723 -293.830496)
			(xy 419.788055 -293.828515) (xy 419.739836 -293.818671) (xy 419.69382 -293.801219) (xy 419.651199 -293.776612)
			(xy 419.613078 -293.745487) (xy 419.580443 -293.70865) (xy 419.55414 -293.667054) (xy 419.534849 -293.621778)
			(xy 419.523072 -293.573994) (xy 419.519112 -293.52494) (xy 419.180856 -293.52494) (xy 419.176368 -293.577139)
			(xy 419.163041 -293.627815) (xy 419.141269 -293.675476) (xy 419.126924 -293.697406) (xy 419.116764 -293.711884)
			(xy 419.11905 -293.746682) (xy 419.137338 -293.767256) (xy 419.143263 -293.774413) (xy 419.149896 -293.791754)
			(xy 419.150292 -293.801038) (xy 419.150292 -294.198802) (xy 419.149849 -294.208074) (xy 419.143206 -294.225392)
			(xy 419.137338 -294.232584) (xy 419.11905 -294.253158) (xy 419.116764 -294.287956) (xy 419.126924 -294.302434)
			(xy 419.141266 -294.324364) (xy 419.163031 -294.372024) (xy 419.176351 -294.422697) (xy 419.180835 -294.4749)
			(xy 419.519112 -294.4749) (xy 419.523072 -294.425846) (xy 419.534849 -294.378062) (xy 419.55414 -294.332786)
			(xy 419.580443 -294.29119) (xy 419.613078 -294.254353) (xy 419.651199 -294.223228) (xy 419.69382 -294.198621)
			(xy 419.739836 -294.181169) (xy 419.788055 -294.171325) (xy 419.83723 -294.169344) (xy 419.886085 -294.175276)
			(xy 419.933356 -294.188968) (xy 419.977818 -294.210066) (xy 420.018321 -294.238022) (xy 420.053814 -294.272114)
			(xy 420.083379 -294.311458) (xy 420.10625 -294.355035) (xy 420.121834 -294.401716) (xy 420.129729 -294.450293)
			(xy 420.130224 -294.4749) (xy 420.469072 -294.4749) (xy 420.473032 -294.425846) (xy 420.484809 -294.378062)
			(xy 420.5041 -294.332786) (xy 420.530403 -294.29119) (xy 420.563038 -294.254353) (xy 420.601159 -294.223228)
			(xy 420.64378 -294.198621) (xy 420.689796 -294.181169) (xy 420.738015 -294.171325) (xy 420.78719 -294.169344)
			(xy 420.836045 -294.175276) (xy 420.883316 -294.188968) (xy 420.927778 -294.210066) (xy 420.968281 -294.238022)
			(xy 421.003774 -294.272114) (xy 421.033339 -294.311458) (xy 421.05621 -294.355035) (xy 421.071794 -294.401716)
			(xy 421.079689 -294.450293) (xy 421.080184 -294.4749) (xy 421.419032 -294.4749) (xy 421.422992 -294.425846)
			(xy 421.434769 -294.378062) (xy 421.45406 -294.332786) (xy 421.480363 -294.29119) (xy 421.512998 -294.254353)
			(xy 421.551119 -294.223228) (xy 421.59374 -294.198621) (xy 421.639756 -294.181169) (xy 421.687975 -294.171325)
			(xy 421.73715 -294.169344) (xy 421.786005 -294.175276) (xy 421.833276 -294.188968) (xy 421.877738 -294.210066)
			(xy 421.918241 -294.238022) (xy 421.953734 -294.272114) (xy 421.983299 -294.311458) (xy 422.00617 -294.355035)
			(xy 422.021754 -294.401716) (xy 422.029649 -294.450293) (xy 422.030144 -294.4749) (xy 422.368992 -294.4749)
			(xy 422.372952 -294.425846) (xy 422.384729 -294.378062) (xy 422.40402 -294.332786) (xy 422.430323 -294.29119)
			(xy 422.462958 -294.254353) (xy 422.501079 -294.223228) (xy 422.5437 -294.198621) (xy 422.589716 -294.181169)
			(xy 422.637935 -294.171325) (xy 422.68711 -294.169344) (xy 422.735965 -294.175276) (xy 422.783236 -294.188968)
			(xy 422.827698 -294.210066) (xy 422.868201 -294.238022) (xy 422.903694 -294.272114) (xy 422.933259 -294.311458)
			(xy 422.95613 -294.355035) (xy 422.971714 -294.401716) (xy 422.979609 -294.450293) (xy 422.980104 -294.4749)
			(xy 423.319206 -294.4749) (xy 423.323166 -294.425846) (xy 423.334943 -294.378062) (xy 423.354234 -294.332786)
			(xy 423.380537 -294.29119) (xy 423.413172 -294.254353) (xy 423.451293 -294.223228) (xy 423.493914 -294.198621)
			(xy 423.53993 -294.181169) (xy 423.588149 -294.171325) (xy 423.637324 -294.169344) (xy 423.686179 -294.175276)
			(xy 423.73345 -294.188968) (xy 423.777912 -294.210066) (xy 423.818415 -294.238022) (xy 423.853908 -294.272114)
			(xy 423.883473 -294.311458) (xy 423.906344 -294.355035) (xy 423.921928 -294.401716) (xy 423.929823 -294.450293)
			(xy 423.930318 -294.4749) (xy 424.269166 -294.4749) (xy 424.273126 -294.425846) (xy 424.284903 -294.378062)
			(xy 424.304194 -294.332786) (xy 424.330497 -294.29119) (xy 424.363132 -294.254353) (xy 424.401253 -294.223228)
			(xy 424.443874 -294.198621) (xy 424.48989 -294.181169) (xy 424.538109 -294.171325) (xy 424.587284 -294.169344)
			(xy 424.636139 -294.175276) (xy 424.68341 -294.188968) (xy 424.727872 -294.210066) (xy 424.768375 -294.238022)
			(xy 424.803868 -294.272114) (xy 424.833433 -294.311458) (xy 424.856304 -294.355035) (xy 424.871888 -294.401716)
			(xy 424.879783 -294.450293) (xy 424.880278 -294.4749) (xy 424.879783 -294.499507) (xy 424.871888 -294.548084)
			(xy 424.856304 -294.594765) (xy 424.833433 -294.638342) (xy 424.803868 -294.677686) (xy 424.768375 -294.711778)
			(xy 424.727872 -294.739734) (xy 424.68341 -294.760832) (xy 424.636139 -294.774524) (xy 424.587284 -294.780456)
			(xy 424.538109 -294.778475) (xy 424.48989 -294.768631) (xy 424.443874 -294.751179) (xy 424.401253 -294.726572)
			(xy 424.363132 -294.695447) (xy 424.330497 -294.65861) (xy 424.304194 -294.617014) (xy 424.284903 -294.571738)
			(xy 424.273126 -294.523954) (xy 424.269166 -294.4749) (xy 423.930318 -294.4749) (xy 423.929823 -294.499507)
			(xy 423.921928 -294.548084) (xy 423.906344 -294.594765) (xy 423.883473 -294.638342) (xy 423.853908 -294.677686)
			(xy 423.818415 -294.711778) (xy 423.777912 -294.739734) (xy 423.73345 -294.760832) (xy 423.686179 -294.774524)
			(xy 423.637324 -294.780456) (xy 423.588149 -294.778475) (xy 423.53993 -294.768631) (xy 423.493914 -294.751179)
			(xy 423.451293 -294.726572) (xy 423.413172 -294.695447) (xy 423.380537 -294.65861) (xy 423.354234 -294.617014)
			(xy 423.334943 -294.571738) (xy 423.323166 -294.523954) (xy 423.319206 -294.4749) (xy 422.980104 -294.4749)
			(xy 422.979609 -294.499507) (xy 422.971714 -294.548084) (xy 422.95613 -294.594765) (xy 422.933259 -294.638342)
			(xy 422.903694 -294.677686) (xy 422.868201 -294.711778) (xy 422.827698 -294.739734) (xy 422.783236 -294.760832)
			(xy 422.735965 -294.774524) (xy 422.68711 -294.780456) (xy 422.637935 -294.778475) (xy 422.589716 -294.768631)
			(xy 422.5437 -294.751179) (xy 422.501079 -294.726572) (xy 422.462958 -294.695447) (xy 422.430323 -294.65861)
			(xy 422.40402 -294.617014) (xy 422.384729 -294.571738) (xy 422.372952 -294.523954) (xy 422.368992 -294.4749)
			(xy 422.030144 -294.4749) (xy 422.029649 -294.499507) (xy 422.021754 -294.548084) (xy 422.00617 -294.594765)
			(xy 421.983299 -294.638342) (xy 421.953734 -294.677686) (xy 421.918241 -294.711778) (xy 421.877738 -294.739734)
			(xy 421.833276 -294.760832) (xy 421.786005 -294.774524) (xy 421.73715 -294.780456) (xy 421.687975 -294.778475)
			(xy 421.639756 -294.768631) (xy 421.59374 -294.751179) (xy 421.551119 -294.726572) (xy 421.512998 -294.695447)
			(xy 421.480363 -294.65861) (xy 421.45406 -294.617014) (xy 421.434769 -294.571738) (xy 421.422992 -294.523954)
			(xy 421.419032 -294.4749) (xy 421.080184 -294.4749) (xy 421.079689 -294.499507) (xy 421.071794 -294.548084)
			(xy 421.05621 -294.594765) (xy 421.033339 -294.638342) (xy 421.003774 -294.677686) (xy 420.968281 -294.711778)
			(xy 420.927778 -294.739734) (xy 420.883316 -294.760832) (xy 420.836045 -294.774524) (xy 420.78719 -294.780456)
			(xy 420.738015 -294.778475) (xy 420.689796 -294.768631) (xy 420.64378 -294.751179) (xy 420.601159 -294.726572)
			(xy 420.563038 -294.695447) (xy 420.530403 -294.65861) (xy 420.5041 -294.617014) (xy 420.484809 -294.571738)
			(xy 420.473032 -294.523954) (xy 420.469072 -294.4749) (xy 420.130224 -294.4749) (xy 420.129729 -294.499507)
			(xy 420.121834 -294.548084) (xy 420.10625 -294.594765) (xy 420.083379 -294.638342) (xy 420.053814 -294.677686)
			(xy 420.018321 -294.711778) (xy 419.977818 -294.739734) (xy 419.933356 -294.760832) (xy 419.886085 -294.774524)
			(xy 419.83723 -294.780456) (xy 419.788055 -294.778475) (xy 419.739836 -294.768631) (xy 419.69382 -294.751179)
			(xy 419.651199 -294.726572) (xy 419.613078 -294.695447) (xy 419.580443 -294.65861) (xy 419.55414 -294.617014)
			(xy 419.534849 -294.571738) (xy 419.523072 -294.523954) (xy 419.519112 -294.4749) (xy 419.180835 -294.4749)
			(xy 419.176351 -294.527103) (xy 419.163031 -294.577776) (xy 419.141266 -294.625436) (xy 419.126924 -294.647366)
			(xy 419.116764 -294.661844) (xy 419.11905 -294.696642) (xy 419.137338 -294.717216) (xy 419.143246 -294.724385)
			(xy 419.149889 -294.741717) (xy 419.150292 -294.750998) (xy 419.150292 -296.098722) (xy 419.149859 -296.107995)
			(xy 419.143209 -296.125312) (xy 419.137338 -296.132504) (xy 419.11905 -296.153078) (xy 419.116764 -296.187876)
			(xy 419.126924 -296.202354) (xy 419.141284 -296.224273) (xy 419.163047 -296.271936) (xy 419.176365 -296.322612)
			(xy 419.180846 -296.374817) (xy 419.180846 -296.37482) (xy 419.519112 -296.37482) (xy 419.523072 -296.325766)
			(xy 419.534849 -296.277982) (xy 419.55414 -296.232706) (xy 419.580443 -296.19111) (xy 419.613078 -296.154273)
			(xy 419.651199 -296.123148) (xy 419.69382 -296.098541) (xy 419.739836 -296.081089) (xy 419.788055 -296.071245)
			(xy 419.83723 -296.069264) (xy 419.886085 -296.075196) (xy 419.933356 -296.088888) (xy 419.977818 -296.109986)
			(xy 420.018321 -296.137942) (xy 420.053814 -296.172034) (xy 420.083379 -296.211378) (xy 420.10625 -296.254955)
			(xy 420.121834 -296.301636) (xy 420.129729 -296.350213) (xy 420.130224 -296.37482) (xy 420.469072 -296.37482)
			(xy 420.473032 -296.325766) (xy 420.484809 -296.277982) (xy 420.5041 -296.232706) (xy 420.530403 -296.19111)
			(xy 420.563038 -296.154273) (xy 420.601159 -296.123148) (xy 420.64378 -296.098541) (xy 420.689796 -296.081089)
			(xy 420.738015 -296.071245) (xy 420.78719 -296.069264) (xy 420.836045 -296.075196) (xy 420.883316 -296.088888)
			(xy 420.927778 -296.109986) (xy 420.968281 -296.137942) (xy 421.003774 -296.172034) (xy 421.033339 -296.211378)
			(xy 421.05621 -296.254955) (xy 421.071794 -296.301636) (xy 421.079689 -296.350213) (xy 421.080184 -296.37482)
			(xy 421.419032 -296.37482) (xy 421.422992 -296.325766) (xy 421.434769 -296.277982) (xy 421.45406 -296.232706)
			(xy 421.480363 -296.19111) (xy 421.512998 -296.154273) (xy 421.551119 -296.123148) (xy 421.59374 -296.098541)
			(xy 421.639756 -296.081089) (xy 421.687975 -296.071245) (xy 421.73715 -296.069264) (xy 421.786005 -296.075196)
			(xy 421.833276 -296.088888) (xy 421.877738 -296.109986) (xy 421.918241 -296.137942) (xy 421.953734 -296.172034)
			(xy 421.983299 -296.211378) (xy 422.00617 -296.254955) (xy 422.021754 -296.301636) (xy 422.029649 -296.350213)
			(xy 422.030144 -296.37482) (xy 422.368992 -296.37482) (xy 422.372952 -296.325766) (xy 422.384729 -296.277982)
			(xy 422.40402 -296.232706) (xy 422.430323 -296.19111) (xy 422.462958 -296.154273) (xy 422.501079 -296.123148)
			(xy 422.5437 -296.098541) (xy 422.589716 -296.081089) (xy 422.637935 -296.071245) (xy 422.68711 -296.069264)
			(xy 422.735965 -296.075196) (xy 422.783236 -296.088888) (xy 422.827698 -296.109986) (xy 422.868201 -296.137942)
			(xy 422.903694 -296.172034) (xy 422.933259 -296.211378) (xy 422.95613 -296.254955) (xy 422.971714 -296.301636)
			(xy 422.979609 -296.350213) (xy 422.980104 -296.37482) (xy 423.319206 -296.37482) (xy 423.323166 -296.325766)
			(xy 423.334943 -296.277982) (xy 423.354234 -296.232706) (xy 423.380537 -296.19111) (xy 423.413172 -296.154273)
			(xy 423.451293 -296.123148) (xy 423.493914 -296.098541) (xy 423.53993 -296.081089) (xy 423.588149 -296.071245)
			(xy 423.637324 -296.069264) (xy 423.686179 -296.075196) (xy 423.73345 -296.088888) (xy 423.777912 -296.109986)
			(xy 423.818415 -296.137942) (xy 423.853908 -296.172034) (xy 423.883473 -296.211378) (xy 423.906344 -296.254955)
			(xy 423.921928 -296.301636) (xy 423.929823 -296.350213) (xy 423.930318 -296.37482) (xy 424.269166 -296.37482)
			(xy 424.273126 -296.325766) (xy 424.284903 -296.277982) (xy 424.304194 -296.232706) (xy 424.330497 -296.19111)
			(xy 424.363132 -296.154273) (xy 424.401253 -296.123148) (xy 424.443874 -296.098541) (xy 424.48989 -296.081089)
			(xy 424.538109 -296.071245) (xy 424.587284 -296.069264) (xy 424.636139 -296.075196) (xy 424.68341 -296.088888)
			(xy 424.727872 -296.109986) (xy 424.768375 -296.137942) (xy 424.803868 -296.172034) (xy 424.833433 -296.211378)
			(xy 424.856304 -296.254955) (xy 424.871888 -296.301636) (xy 424.879783 -296.350213) (xy 424.880278 -296.37482)
			(xy 424.879783 -296.399427) (xy 424.871888 -296.448004) (xy 424.856304 -296.494685) (xy 424.833433 -296.538262)
			(xy 424.803868 -296.577606) (xy 424.768375 -296.611698) (xy 424.727872 -296.639654) (xy 424.68341 -296.660752)
			(xy 424.636139 -296.674444) (xy 424.587284 -296.680376) (xy 424.538109 -296.678395) (xy 424.48989 -296.668551)
			(xy 424.443874 -296.651099) (xy 424.401253 -296.626492) (xy 424.363132 -296.595367) (xy 424.330497 -296.55853)
			(xy 424.304194 -296.516934) (xy 424.284903 -296.471658) (xy 424.273126 -296.423874) (xy 424.269166 -296.37482)
			(xy 423.930318 -296.37482) (xy 423.929823 -296.399427) (xy 423.921928 -296.448004) (xy 423.906344 -296.494685)
			(xy 423.883473 -296.538262) (xy 423.853908 -296.577606) (xy 423.818415 -296.611698) (xy 423.777912 -296.639654)
			(xy 423.73345 -296.660752) (xy 423.686179 -296.674444) (xy 423.637324 -296.680376) (xy 423.588149 -296.678395)
			(xy 423.53993 -296.668551) (xy 423.493914 -296.651099) (xy 423.451293 -296.626492) (xy 423.413172 -296.595367)
			(xy 423.380537 -296.55853) (xy 423.354234 -296.516934) (xy 423.334943 -296.471658) (xy 423.323166 -296.423874)
			(xy 423.319206 -296.37482) (xy 422.980104 -296.37482) (xy 422.979609 -296.399427) (xy 422.971714 -296.448004)
			(xy 422.95613 -296.494685) (xy 422.933259 -296.538262) (xy 422.903694 -296.577606) (xy 422.868201 -296.611698)
			(xy 422.827698 -296.639654) (xy 422.783236 -296.660752) (xy 422.735965 -296.674444) (xy 422.68711 -296.680376)
			(xy 422.637935 -296.678395) (xy 422.589716 -296.668551) (xy 422.5437 -296.651099) (xy 422.501079 -296.626492)
			(xy 422.462958 -296.595367) (xy 422.430323 -296.55853) (xy 422.40402 -296.516934) (xy 422.384729 -296.471658)
			(xy 422.372952 -296.423874) (xy 422.368992 -296.37482) (xy 422.030144 -296.37482) (xy 422.029649 -296.399427)
			(xy 422.021754 -296.448004) (xy 422.00617 -296.494685) (xy 421.983299 -296.538262) (xy 421.953734 -296.577606)
			(xy 421.918241 -296.611698) (xy 421.877738 -296.639654) (xy 421.833276 -296.660752) (xy 421.786005 -296.674444)
			(xy 421.73715 -296.680376) (xy 421.687975 -296.678395) (xy 421.639756 -296.668551) (xy 421.59374 -296.651099)
			(xy 421.551119 -296.626492) (xy 421.512998 -296.595367) (xy 421.480363 -296.55853) (xy 421.45406 -296.516934)
			(xy 421.434769 -296.471658) (xy 421.422992 -296.423874) (xy 421.419032 -296.37482) (xy 421.080184 -296.37482)
			(xy 421.079689 -296.399427) (xy 421.071794 -296.448004) (xy 421.05621 -296.494685) (xy 421.033339 -296.538262)
			(xy 421.003774 -296.577606) (xy 420.968281 -296.611698) (xy 420.927778 -296.639654) (xy 420.883316 -296.660752)
			(xy 420.836045 -296.674444) (xy 420.78719 -296.680376) (xy 420.738015 -296.678395) (xy 420.689796 -296.668551)
			(xy 420.64378 -296.651099) (xy 420.601159 -296.626492) (xy 420.563038 -296.595367) (xy 420.530403 -296.55853)
			(xy 420.5041 -296.516934) (xy 420.484809 -296.471658) (xy 420.473032 -296.423874) (xy 420.469072 -296.37482)
			(xy 420.130224 -296.37482) (xy 420.129729 -296.399427) (xy 420.121834 -296.448004) (xy 420.10625 -296.494685)
			(xy 420.083379 -296.538262) (xy 420.053814 -296.577606) (xy 420.018321 -296.611698) (xy 419.977818 -296.639654)
			(xy 419.933356 -296.660752) (xy 419.886085 -296.674444) (xy 419.83723 -296.680376) (xy 419.788055 -296.678395)
			(xy 419.739836 -296.668551) (xy 419.69382 -296.651099) (xy 419.651199 -296.626492) (xy 419.613078 -296.595367)
			(xy 419.580443 -296.55853) (xy 419.55414 -296.516934) (xy 419.534849 -296.471658) (xy 419.523072 -296.423874)
			(xy 419.519112 -296.37482) (xy 419.180846 -296.37482) (xy 419.176359 -296.427021) (xy 419.163036 -296.477696)
			(xy 419.141267 -296.525356) (xy 419.126924 -296.547286) (xy 419.116764 -296.561764) (xy 419.11905 -296.596562)
			(xy 419.137338 -296.617136) (xy 419.143255 -296.624299) (xy 419.149893 -296.641635) (xy 419.150292 -296.650918)
			(xy 419.150292 -297.048682) (xy 419.149839 -297.057953) (xy 419.143203 -297.07527) (xy 419.137338 -297.082464)
			(xy 419.11905 -297.103038) (xy 419.116764 -297.137836) (xy 419.126924 -297.152314) (xy 419.139513 -297.171471)
			(xy 419.159452 -297.212746) (xy 419.173 -297.256537) (xy 419.179852 -297.301861) (xy 419.180264 -297.32478)
			(xy 419.519112 -297.32478) (xy 419.523072 -297.275726) (xy 419.534849 -297.227942) (xy 419.55414 -297.182666)
			(xy 419.580443 -297.14107) (xy 419.613078 -297.104233) (xy 419.651199 -297.073108) (xy 419.69382 -297.048501)
			(xy 419.739836 -297.031049) (xy 419.788055 -297.021205) (xy 419.83723 -297.019224) (xy 419.886085 -297.025156)
			(xy 419.933356 -297.038848) (xy 419.977818 -297.059946) (xy 420.018321 -297.087902) (xy 420.053814 -297.121994)
			(xy 420.083379 -297.161338) (xy 420.10625 -297.204915) (xy 420.121834 -297.251596) (xy 420.129729 -297.300173)
			(xy 420.130224 -297.32478) (xy 420.469072 -297.32478) (xy 420.473032 -297.275726) (xy 420.484809 -297.227942)
			(xy 420.5041 -297.182666) (xy 420.530403 -297.14107) (xy 420.563038 -297.104233) (xy 420.601159 -297.073108)
			(xy 420.64378 -297.048501) (xy 420.689796 -297.031049) (xy 420.738015 -297.021205) (xy 420.78719 -297.019224)
			(xy 420.836045 -297.025156) (xy 420.883316 -297.038848) (xy 420.927778 -297.059946) (xy 420.968281 -297.087902)
			(xy 421.003774 -297.121994) (xy 421.033339 -297.161338) (xy 421.05621 -297.204915) (xy 421.071794 -297.251596)
			(xy 421.079689 -297.300173) (xy 421.080184 -297.32478) (xy 421.419032 -297.32478) (xy 421.422992 -297.275726)
			(xy 421.434769 -297.227942) (xy 421.45406 -297.182666) (xy 421.480363 -297.14107) (xy 421.512998 -297.104233)
			(xy 421.551119 -297.073108) (xy 421.59374 -297.048501) (xy 421.639756 -297.031049) (xy 421.687975 -297.021205)
			(xy 421.73715 -297.019224) (xy 421.786005 -297.025156) (xy 421.833276 -297.038848) (xy 421.877738 -297.059946)
			(xy 421.918241 -297.087902) (xy 421.953734 -297.121994) (xy 421.983299 -297.161338) (xy 422.00617 -297.204915)
			(xy 422.021754 -297.251596) (xy 422.029649 -297.300173) (xy 422.030144 -297.32478) (xy 422.369246 -297.32478)
			(xy 422.373206 -297.275726) (xy 422.384983 -297.227942) (xy 422.404274 -297.182666) (xy 422.430577 -297.14107)
			(xy 422.463212 -297.104233) (xy 422.501333 -297.073108) (xy 422.543954 -297.048501) (xy 422.58997 -297.031049)
			(xy 422.638189 -297.021205) (xy 422.687364 -297.019224) (xy 422.736219 -297.025156) (xy 422.78349 -297.038848)
			(xy 422.827952 -297.059946) (xy 422.868455 -297.087902) (xy 422.903948 -297.121994) (xy 422.933513 -297.161338)
			(xy 422.956384 -297.204915) (xy 422.971968 -297.251596) (xy 422.979863 -297.300173) (xy 422.980358 -297.32478)
			(xy 423.319206 -297.32478) (xy 423.323166 -297.275726) (xy 423.334943 -297.227942) (xy 423.354234 -297.182666)
			(xy 423.380537 -297.14107) (xy 423.413172 -297.104233) (xy 423.451293 -297.073108) (xy 423.493914 -297.048501)
			(xy 423.53993 -297.031049) (xy 423.588149 -297.021205) (xy 423.637324 -297.019224) (xy 423.686179 -297.025156)
			(xy 423.73345 -297.038848) (xy 423.777912 -297.059946) (xy 423.818415 -297.087902) (xy 423.853908 -297.121994)
			(xy 423.883473 -297.161338) (xy 423.906344 -297.204915) (xy 423.921928 -297.251596) (xy 423.929823 -297.300173)
			(xy 423.930318 -297.32478) (xy 424.269166 -297.32478) (xy 424.273126 -297.275726) (xy 424.284903 -297.227942)
			(xy 424.304194 -297.182666) (xy 424.330497 -297.14107) (xy 424.363132 -297.104233) (xy 424.401253 -297.073108)
			(xy 424.443874 -297.048501) (xy 424.48989 -297.031049) (xy 424.538109 -297.021205) (xy 424.587284 -297.019224)
			(xy 424.636139 -297.025156) (xy 424.68341 -297.038848) (xy 424.727872 -297.059946) (xy 424.768375 -297.087902)
			(xy 424.803868 -297.121994) (xy 424.833433 -297.161338) (xy 424.856304 -297.204915) (xy 424.871888 -297.251596)
			(xy 424.879783 -297.300173) (xy 424.880278 -297.32478) (xy 424.879783 -297.349387) (xy 424.871888 -297.397964)
			(xy 424.856304 -297.444645) (xy 424.833433 -297.488222) (xy 424.803868 -297.527566) (xy 424.768375 -297.561658)
			(xy 424.727872 -297.589614) (xy 424.68341 -297.610712) (xy 424.636139 -297.624404) (xy 424.587284 -297.630336)
			(xy 424.538109 -297.628355) (xy 424.48989 -297.618511) (xy 424.443874 -297.601059) (xy 424.401253 -297.576452)
			(xy 424.363132 -297.545327) (xy 424.330497 -297.50849) (xy 424.304194 -297.466894) (xy 424.284903 -297.421618)
			(xy 424.273126 -297.373834) (xy 424.269166 -297.32478) (xy 423.930318 -297.32478) (xy 423.929823 -297.349387)
			(xy 423.921928 -297.397964) (xy 423.906344 -297.444645) (xy 423.883473 -297.488222) (xy 423.853908 -297.527566)
			(xy 423.818415 -297.561658) (xy 423.777912 -297.589614) (xy 423.73345 -297.610712) (xy 423.686179 -297.624404)
			(xy 423.637324 -297.630336) (xy 423.588149 -297.628355) (xy 423.53993 -297.618511) (xy 423.493914 -297.601059)
			(xy 423.451293 -297.576452) (xy 423.413172 -297.545327) (xy 423.380537 -297.50849) (xy 423.354234 -297.466894)
			(xy 423.334943 -297.421618) (xy 423.323166 -297.373834) (xy 423.319206 -297.32478) (xy 422.980358 -297.32478)
			(xy 422.979863 -297.349387) (xy 422.971968 -297.397964) (xy 422.956384 -297.444645) (xy 422.933513 -297.488222)
			(xy 422.903948 -297.527566) (xy 422.868455 -297.561658) (xy 422.827952 -297.589614) (xy 422.78349 -297.610712)
			(xy 422.736219 -297.624404) (xy 422.687364 -297.630336) (xy 422.638189 -297.628355) (xy 422.58997 -297.618511)
			(xy 422.543954 -297.601059) (xy 422.501333 -297.576452) (xy 422.463212 -297.545327) (xy 422.430577 -297.50849)
			(xy 422.404274 -297.466894) (xy 422.384983 -297.421618) (xy 422.373206 -297.373834) (xy 422.369246 -297.32478)
			(xy 422.030144 -297.32478) (xy 422.029649 -297.349387) (xy 422.021754 -297.397964) (xy 422.00617 -297.444645)
			(xy 421.983299 -297.488222) (xy 421.953734 -297.527566) (xy 421.918241 -297.561658) (xy 421.877738 -297.589614)
			(xy 421.833276 -297.610712) (xy 421.786005 -297.624404) (xy 421.73715 -297.630336) (xy 421.687975 -297.628355)
			(xy 421.639756 -297.618511) (xy 421.59374 -297.601059) (xy 421.551119 -297.576452) (xy 421.512998 -297.545327)
			(xy 421.480363 -297.50849) (xy 421.45406 -297.466894) (xy 421.434769 -297.421618) (xy 421.422992 -297.373834)
			(xy 421.419032 -297.32478) (xy 421.080184 -297.32478) (xy 421.079689 -297.349387) (xy 421.071794 -297.397964)
			(xy 421.05621 -297.444645) (xy 421.033339 -297.488222) (xy 421.003774 -297.527566) (xy 420.968281 -297.561658)
			(xy 420.927778 -297.589614) (xy 420.883316 -297.610712) (xy 420.836045 -297.624404) (xy 420.78719 -297.630336)
			(xy 420.738015 -297.628355) (xy 420.689796 -297.618511) (xy 420.64378 -297.601059) (xy 420.601159 -297.576452)
			(xy 420.563038 -297.545327) (xy 420.530403 -297.50849) (xy 420.5041 -297.466894) (xy 420.484809 -297.421618)
			(xy 420.473032 -297.373834) (xy 420.469072 -297.32478) (xy 420.130224 -297.32478) (xy 420.129729 -297.349387)
			(xy 420.121834 -297.397964) (xy 420.10625 -297.444645) (xy 420.083379 -297.488222) (xy 420.053814 -297.527566)
			(xy 420.018321 -297.561658) (xy 419.977818 -297.589614) (xy 419.933356 -297.610712) (xy 419.886085 -297.624404)
			(xy 419.83723 -297.630336) (xy 419.788055 -297.628355) (xy 419.739836 -297.618511) (xy 419.69382 -297.601059)
			(xy 419.651199 -297.576452) (xy 419.613078 -297.545327) (xy 419.580443 -297.50849) (xy 419.55414 -297.466894)
			(xy 419.534849 -297.421618) (xy 419.523072 -297.373834) (xy 419.519112 -297.32478) (xy 419.180264 -297.32478)
			(xy 419.179843 -297.348775) (xy 419.172338 -297.396174) (xy 419.15751 -297.441815) (xy 419.135723 -297.484574)
			(xy 419.107515 -297.523398) (xy 419.07358 -297.55733) (xy 419.034754 -297.585535) (xy 418.991993 -297.607319)
			(xy 418.94635 -297.622144) (xy 418.898951 -297.629645) (xy 418.874956 -297.630088) (xy 418.847428 -297.629421)
			(xy 418.793276 -297.619475) (xy 418.741777 -297.600001) (xy 418.694593 -297.571628) (xy 418.673534 -297.553888)
			(xy 418.654484 -297.537378) (xy 418.629338 -297.536362) (xy 418.622533 -297.54121) (xy 418.606702 -297.546529)
			(xy 418.59835 -297.546776) (xy 418.15385 -297.546776) (xy 418.144917 -297.547101) (xy 418.128132 -297.553216)
			(xy 418.121084 -297.558714) (xy 418.100311 -297.575401) (xy 418.05417 -297.602037) (xy 418.004104 -297.620258)
			(xy 417.951635 -297.629508) (xy 417.924996 -297.630088) (xy 417.897467 -297.629455) (xy 417.843313 -297.619498)
			(xy 417.791814 -297.600014) (xy 417.744632 -297.571632) (xy 417.723574 -297.553888) (xy 417.704524 -297.537378)
			(xy 417.679378 -297.536362) (xy 417.672562 -297.541194) (xy 417.65674 -297.546523) (xy 417.64839 -297.546776)
			(xy 417.203636 -297.546776) (xy 417.194702 -297.547094) (xy 417.177918 -297.553214) (xy 417.17087 -297.558714)
			(xy 417.150102 -297.575407) (xy 417.103959 -297.602042) (xy 417.053892 -297.620261) (xy 417.001421 -297.629509)
			(xy 416.974782 -297.630088) (xy 416.959888 -297.629889) (xy 416.930244 -297.626967) (xy 416.9156 -297.624246)
			(xy 416.915346 -297.624246) (xy 416.904303 -297.622689) (xy 416.882693 -297.62808) (xy 416.87369 -297.63466)
			(xy 416.82924 -297.670728) (xy 416.820803 -297.678315) (xy 416.811045 -297.698767) (xy 416.810444 -297.710098)
			(xy 416.810444 -297.889422) (xy 416.811077 -297.900742) (xy 416.82084 -297.921176) (xy 416.82924 -297.928792)
			(xy 416.87369 -297.96486) (xy 416.882696 -297.971434) (xy 416.904305 -297.976832) (xy 416.915346 -297.975274)
			(xy 416.9156 -297.975274) (xy 416.930243 -297.972546) (xy 416.959888 -297.969622) (xy 416.974782 -297.969432)
			(xy 417.000044 -297.969843) (xy 417.049879 -297.978157) (xy 417.097666 -297.99456) (xy 417.142102 -298.018605)
			(xy 417.181973 -298.049636) (xy 417.216193 -298.086806) (xy 417.243828 -298.129103) (xy 417.264124 -298.175371)
			(xy 417.276528 -298.224349) (xy 417.2807 -298.2747) (xy 417.280697 -298.27474) (xy 417.619192 -298.27474)
			(xy 417.623152 -298.225686) (xy 417.634929 -298.177902) (xy 417.65422 -298.132626) (xy 417.680523 -298.09103)
			(xy 417.713158 -298.054193) (xy 417.751279 -298.023068) (xy 417.7939 -297.998461) (xy 417.839916 -297.981009)
			(xy 417.888135 -297.971165) (xy 417.93731 -297.969184) (xy 417.986165 -297.975116) (xy 418.033436 -297.988808)
			(xy 418.077898 -298.009906) (xy 418.118401 -298.037862) (xy 418.153894 -298.071954) (xy 418.183459 -298.111298)
			(xy 418.20633 -298.154875) (xy 418.221914 -298.201556) (xy 418.229809 -298.250133) (xy 418.230304 -298.27474)
			(xy 418.569152 -298.27474) (xy 418.573112 -298.225686) (xy 418.584889 -298.177902) (xy 418.60418 -298.132626)
			(xy 418.630483 -298.09103) (xy 418.663118 -298.054193) (xy 418.701239 -298.023068) (xy 418.74386 -297.998461)
			(xy 418.789876 -297.981009) (xy 418.838095 -297.971165) (xy 418.88727 -297.969184) (xy 418.936125 -297.975116)
			(xy 418.983396 -297.988808) (xy 419.027858 -298.009906) (xy 419.068361 -298.037862) (xy 419.103854 -298.071954)
			(xy 419.133419 -298.111298) (xy 419.15629 -298.154875) (xy 419.171874 -298.201556) (xy 419.179769 -298.250133)
			(xy 419.180264 -298.27474) (xy 419.519112 -298.27474) (xy 419.523072 -298.225686) (xy 419.534849 -298.177902)
			(xy 419.55414 -298.132626) (xy 419.580443 -298.09103) (xy 419.613078 -298.054193) (xy 419.651199 -298.023068)
			(xy 419.69382 -297.998461) (xy 419.739836 -297.981009) (xy 419.788055 -297.971165) (xy 419.83723 -297.969184)
			(xy 419.886085 -297.975116) (xy 419.933356 -297.988808) (xy 419.977818 -298.009906) (xy 420.018321 -298.037862)
			(xy 420.053814 -298.071954) (xy 420.083379 -298.111298) (xy 420.10625 -298.154875) (xy 420.121834 -298.201556)
			(xy 420.129729 -298.250133) (xy 420.130224 -298.27474) (xy 420.469072 -298.27474) (xy 420.473032 -298.225686)
			(xy 420.484809 -298.177902) (xy 420.5041 -298.132626) (xy 420.530403 -298.09103) (xy 420.563038 -298.054193)
			(xy 420.601159 -298.023068) (xy 420.64378 -297.998461) (xy 420.689796 -297.981009) (xy 420.738015 -297.971165)
			(xy 420.78719 -297.969184) (xy 420.836045 -297.975116) (xy 420.883316 -297.988808) (xy 420.927778 -298.009906)
			(xy 420.968281 -298.037862) (xy 421.003774 -298.071954) (xy 421.033339 -298.111298) (xy 421.05621 -298.154875)
			(xy 421.071794 -298.201556) (xy 421.079689 -298.250133) (xy 421.080184 -298.27474) (xy 421.419032 -298.27474)
			(xy 421.422992 -298.225686) (xy 421.434769 -298.177902) (xy 421.45406 -298.132626) (xy 421.480363 -298.09103)
			(xy 421.512998 -298.054193) (xy 421.551119 -298.023068) (xy 421.59374 -297.998461) (xy 421.639756 -297.981009)
			(xy 421.687975 -297.971165) (xy 421.73715 -297.969184) (xy 421.786005 -297.975116) (xy 421.833276 -297.988808)
			(xy 421.877738 -298.009906) (xy 421.918241 -298.037862) (xy 421.953734 -298.071954) (xy 421.983299 -298.111298)
			(xy 422.00617 -298.154875) (xy 422.021754 -298.201556) (xy 422.029649 -298.250133) (xy 422.030144 -298.27474)
			(xy 422.368992 -298.27474) (xy 422.372952 -298.225686) (xy 422.384729 -298.177902) (xy 422.40402 -298.132626)
			(xy 422.430323 -298.09103) (xy 422.462958 -298.054193) (xy 422.501079 -298.023068) (xy 422.5437 -297.998461)
			(xy 422.589716 -297.981009) (xy 422.637935 -297.971165) (xy 422.68711 -297.969184) (xy 422.735965 -297.975116)
			(xy 422.783236 -297.988808) (xy 422.827698 -298.009906) (xy 422.868201 -298.037862) (xy 422.903694 -298.071954)
			(xy 422.933259 -298.111298) (xy 422.95613 -298.154875) (xy 422.971714 -298.201556) (xy 422.979609 -298.250133)
			(xy 422.980104 -298.27474) (xy 423.319206 -298.27474) (xy 423.323166 -298.225686) (xy 423.334943 -298.177902)
			(xy 423.354234 -298.132626) (xy 423.380537 -298.09103) (xy 423.413172 -298.054193) (xy 423.451293 -298.023068)
			(xy 423.493914 -297.998461) (xy 423.53993 -297.981009) (xy 423.588149 -297.971165) (xy 423.637324 -297.969184)
			(xy 423.686179 -297.975116) (xy 423.73345 -297.988808) (xy 423.777912 -298.009906) (xy 423.818415 -298.037862)
			(xy 423.853908 -298.071954) (xy 423.883473 -298.111298) (xy 423.906344 -298.154875) (xy 423.921928 -298.201556)
			(xy 423.929823 -298.250133) (xy 423.930318 -298.27474) (xy 424.269166 -298.27474) (xy 424.273126 -298.225686)
			(xy 424.284903 -298.177902) (xy 424.304194 -298.132626) (xy 424.330497 -298.09103) (xy 424.363132 -298.054193)
			(xy 424.401253 -298.023068) (xy 424.443874 -297.998461) (xy 424.48989 -297.981009) (xy 424.538109 -297.971165)
			(xy 424.587284 -297.969184) (xy 424.636139 -297.975116) (xy 424.68341 -297.988808) (xy 424.727872 -298.009906)
			(xy 424.768375 -298.037862) (xy 424.803868 -298.071954) (xy 424.833433 -298.111298) (xy 424.856304 -298.154875)
			(xy 424.871888 -298.201556) (xy 424.879783 -298.250133) (xy 424.880278 -298.27474) (xy 424.879783 -298.299347)
			(xy 424.871888 -298.347924) (xy 424.856304 -298.394605) (xy 424.833433 -298.438182) (xy 424.803868 -298.477526)
			(xy 424.768375 -298.511618) (xy 424.727872 -298.539574) (xy 424.68341 -298.560672) (xy 424.636139 -298.574364)
			(xy 424.587284 -298.580296) (xy 424.538109 -298.578315) (xy 424.48989 -298.568471) (xy 424.443874 -298.551019)
			(xy 424.401253 -298.526412) (xy 424.363132 -298.495287) (xy 424.330497 -298.45845) (xy 424.304194 -298.416854)
			(xy 424.284903 -298.371578) (xy 424.273126 -298.323794) (xy 424.269166 -298.27474) (xy 423.930318 -298.27474)
			(xy 423.929823 -298.299347) (xy 423.921928 -298.347924) (xy 423.906344 -298.394605) (xy 423.883473 -298.438182)
			(xy 423.853908 -298.477526) (xy 423.818415 -298.511618) (xy 423.777912 -298.539574) (xy 423.73345 -298.560672)
			(xy 423.686179 -298.574364) (xy 423.637324 -298.580296) (xy 423.588149 -298.578315) (xy 423.53993 -298.568471)
			(xy 423.493914 -298.551019) (xy 423.451293 -298.526412) (xy 423.413172 -298.495287) (xy 423.380537 -298.45845)
			(xy 423.354234 -298.416854) (xy 423.334943 -298.371578) (xy 423.323166 -298.323794) (xy 423.319206 -298.27474)
			(xy 422.980104 -298.27474) (xy 422.979609 -298.299347) (xy 422.971714 -298.347924) (xy 422.95613 -298.394605)
			(xy 422.933259 -298.438182) (xy 422.903694 -298.477526) (xy 422.868201 -298.511618) (xy 422.827698 -298.539574)
			(xy 422.783236 -298.560672) (xy 422.735965 -298.574364) (xy 422.68711 -298.580296) (xy 422.637935 -298.578315)
			(xy 422.589716 -298.568471) (xy 422.5437 -298.551019) (xy 422.501079 -298.526412) (xy 422.462958 -298.495287)
			(xy 422.430323 -298.45845) (xy 422.40402 -298.416854) (xy 422.384729 -298.371578) (xy 422.372952 -298.323794)
			(xy 422.368992 -298.27474) (xy 422.030144 -298.27474) (xy 422.029649 -298.299347) (xy 422.021754 -298.347924)
			(xy 422.00617 -298.394605) (xy 421.983299 -298.438182) (xy 421.953734 -298.477526) (xy 421.918241 -298.511618)
			(xy 421.877738 -298.539574) (xy 421.833276 -298.560672) (xy 421.786005 -298.574364) (xy 421.73715 -298.580296)
			(xy 421.687975 -298.578315) (xy 421.639756 -298.568471) (xy 421.59374 -298.551019) (xy 421.551119 -298.526412)
			(xy 421.512998 -298.495287) (xy 421.480363 -298.45845) (xy 421.45406 -298.416854) (xy 421.434769 -298.371578)
			(xy 421.422992 -298.323794) (xy 421.419032 -298.27474) (xy 421.080184 -298.27474) (xy 421.079689 -298.299347)
			(xy 421.071794 -298.347924) (xy 421.05621 -298.394605) (xy 421.033339 -298.438182) (xy 421.003774 -298.477526)
			(xy 420.968281 -298.511618) (xy 420.927778 -298.539574) (xy 420.883316 -298.560672) (xy 420.836045 -298.574364)
			(xy 420.78719 -298.580296) (xy 420.738015 -298.578315) (xy 420.689796 -298.568471) (xy 420.64378 -298.551019)
			(xy 420.601159 -298.526412) (xy 420.563038 -298.495287) (xy 420.530403 -298.45845) (xy 420.5041 -298.416854)
			(xy 420.484809 -298.371578) (xy 420.473032 -298.323794) (xy 420.469072 -298.27474) (xy 420.130224 -298.27474)
			(xy 420.129729 -298.299347) (xy 420.121834 -298.347924) (xy 420.10625 -298.394605) (xy 420.083379 -298.438182)
			(xy 420.053814 -298.477526) (xy 420.018321 -298.511618) (xy 419.977818 -298.539574) (xy 419.933356 -298.560672)
			(xy 419.886085 -298.574364) (xy 419.83723 -298.580296) (xy 419.788055 -298.578315) (xy 419.739836 -298.568471)
			(xy 419.69382 -298.551019) (xy 419.651199 -298.526412) (xy 419.613078 -298.495287) (xy 419.580443 -298.45845)
			(xy 419.55414 -298.416854) (xy 419.534849 -298.371578) (xy 419.523072 -298.323794) (xy 419.519112 -298.27474)
			(xy 419.180264 -298.27474) (xy 419.179769 -298.299347) (xy 419.171874 -298.347924) (xy 419.15629 -298.394605)
			(xy 419.133419 -298.438182) (xy 419.103854 -298.477526) (xy 419.068361 -298.511618) (xy 419.027858 -298.539574)
			(xy 418.983396 -298.560672) (xy 418.936125 -298.574364) (xy 418.88727 -298.580296) (xy 418.838095 -298.578315)
			(xy 418.789876 -298.568471) (xy 418.74386 -298.551019) (xy 418.701239 -298.526412) (xy 418.663118 -298.495287)
			(xy 418.630483 -298.45845) (xy 418.60418 -298.416854) (xy 418.584889 -298.371578) (xy 418.573112 -298.323794)
			(xy 418.569152 -298.27474) (xy 418.230304 -298.27474) (xy 418.229809 -298.299347) (xy 418.221914 -298.347924)
			(xy 418.20633 -298.394605) (xy 418.183459 -298.438182) (xy 418.153894 -298.477526) (xy 418.118401 -298.511618)
			(xy 418.077898 -298.539574) (xy 418.033436 -298.560672) (xy 417.986165 -298.574364) (xy 417.93731 -298.580296)
			(xy 417.888135 -298.578315) (xy 417.839916 -298.568471) (xy 417.7939 -298.551019) (xy 417.751279 -298.526412)
			(xy 417.713158 -298.495287) (xy 417.680523 -298.45845) (xy 417.65422 -298.416854) (xy 417.634929 -298.371578)
			(xy 417.623152 -298.323794) (xy 417.619192 -298.27474) (xy 417.280697 -298.27474) (xy 417.276528 -298.325051)
			(xy 417.264124 -298.374029) (xy 417.243828 -298.420297) (xy 417.216193 -298.462594) (xy 417.181973 -298.499764)
			(xy 417.142102 -298.530795) (xy 417.097666 -298.55484) (xy 417.049879 -298.571243) (xy 417.000044 -298.579557)
			(xy 416.974782 -298.580048) (xy 416.959888 -298.57985) (xy 416.930244 -298.576928) (xy 416.9156 -298.574206)
			(xy 416.915346 -298.574206) (xy 416.904303 -298.572658) (xy 416.882694 -298.578044) (xy 416.87369 -298.58462)
			(xy 416.82924 -298.620688) (xy 416.820821 -298.628292) (xy 416.811053 -298.648731) (xy 416.810444 -298.660058)
			(xy 416.810444 -298.839636) (xy 416.811069 -298.850957) (xy 416.820837 -298.871391) (xy 416.82924 -298.879006)
			(xy 416.87369 -298.915074) (xy 416.882701 -298.921641) (xy 416.904306 -298.927047) (xy 416.915346 -298.925488)
			(xy 416.9156 -298.925488) (xy 416.930243 -298.92276) (xy 416.959888 -298.919836) (xy 416.974782 -298.919646)
			(xy 417.000037 -298.920229) (xy 417.049858 -298.92854) (xy 417.097632 -298.944938) (xy 417.142055 -298.968977)
			(xy 417.181915 -298.999999) (xy 417.216126 -299.037159) (xy 417.243753 -299.079444) (xy 417.264043 -299.125699)
			(xy 417.276443 -299.174663) (xy 417.28061 -299.224954) (xy 417.619192 -299.224954) (xy 417.623152 -299.1759)
			(xy 417.634929 -299.128116) (xy 417.65422 -299.08284) (xy 417.680523 -299.041244) (xy 417.713158 -299.004407)
			(xy 417.751279 -298.973282) (xy 417.7939 -298.948675) (xy 417.839916 -298.931223) (xy 417.888135 -298.921379)
			(xy 417.93731 -298.919398) (xy 417.986165 -298.92533) (xy 418.033436 -298.939022) (xy 418.077898 -298.96012)
			(xy 418.118401 -298.988076) (xy 418.153894 -299.022168) (xy 418.183459 -299.061512) (xy 418.20633 -299.105089)
			(xy 418.221914 -299.15177) (xy 418.229809 -299.200347) (xy 418.230304 -299.224954) (xy 418.569152 -299.224954)
			(xy 418.573112 -299.1759) (xy 418.584889 -299.128116) (xy 418.60418 -299.08284) (xy 418.630483 -299.041244)
			(xy 418.663118 -299.004407) (xy 418.701239 -298.973282) (xy 418.74386 -298.948675) (xy 418.789876 -298.931223)
			(xy 418.838095 -298.921379) (xy 418.88727 -298.919398) (xy 418.936125 -298.92533) (xy 418.983396 -298.939022)
			(xy 419.027858 -298.96012) (xy 419.068361 -298.988076) (xy 419.103854 -299.022168) (xy 419.133419 -299.061512)
			(xy 419.15629 -299.105089) (xy 419.171874 -299.15177) (xy 419.179769 -299.200347) (xy 419.180264 -299.224954)
			(xy 419.519112 -299.224954) (xy 419.523072 -299.1759) (xy 419.534849 -299.128116) (xy 419.55414 -299.08284)
			(xy 419.580443 -299.041244) (xy 419.613078 -299.004407) (xy 419.651199 -298.973282) (xy 419.69382 -298.948675)
			(xy 419.739836 -298.931223) (xy 419.788055 -298.921379) (xy 419.83723 -298.919398) (xy 419.886085 -298.92533)
			(xy 419.933356 -298.939022) (xy 419.977818 -298.96012) (xy 420.018321 -298.988076) (xy 420.053814 -299.022168)
			(xy 420.083379 -299.061512) (xy 420.10625 -299.105089) (xy 420.121834 -299.15177) (xy 420.129729 -299.200347)
			(xy 420.130224 -299.224954) (xy 420.469072 -299.224954) (xy 420.473032 -299.1759) (xy 420.484809 -299.128116)
			(xy 420.5041 -299.08284) (xy 420.530403 -299.041244) (xy 420.563038 -299.004407) (xy 420.601159 -298.973282)
			(xy 420.64378 -298.948675) (xy 420.689796 -298.931223) (xy 420.738015 -298.921379) (xy 420.78719 -298.919398)
			(xy 420.836045 -298.92533) (xy 420.883316 -298.939022) (xy 420.927778 -298.96012) (xy 420.968281 -298.988076)
			(xy 421.003774 -299.022168) (xy 421.033339 -299.061512) (xy 421.05621 -299.105089) (xy 421.071794 -299.15177)
			(xy 421.079689 -299.200347) (xy 421.080184 -299.224954) (xy 421.419032 -299.224954) (xy 421.422992 -299.1759)
			(xy 421.434769 -299.128116) (xy 421.45406 -299.08284) (xy 421.480363 -299.041244) (xy 421.512998 -299.004407)
			(xy 421.551119 -298.973282) (xy 421.59374 -298.948675) (xy 421.639756 -298.931223) (xy 421.687975 -298.921379)
			(xy 421.73715 -298.919398) (xy 421.786005 -298.92533) (xy 421.833276 -298.939022) (xy 421.877738 -298.96012)
			(xy 421.918241 -298.988076) (xy 421.953734 -299.022168) (xy 421.983299 -299.061512) (xy 422.00617 -299.105089)
			(xy 422.021754 -299.15177) (xy 422.029649 -299.200347) (xy 422.030144 -299.224954) (xy 424.269166 -299.224954)
			(xy 424.273126 -299.1759) (xy 424.284903 -299.128116) (xy 424.304194 -299.08284) (xy 424.330497 -299.041244)
			(xy 424.363132 -299.004407) (xy 424.401253 -298.973282) (xy 424.443874 -298.948675) (xy 424.48989 -298.931223)
			(xy 424.538109 -298.921379) (xy 424.587284 -298.919398) (xy 424.636139 -298.92533) (xy 424.68341 -298.939022)
			(xy 424.727872 -298.96012) (xy 424.768375 -298.988076) (xy 424.803868 -299.022168) (xy 424.833433 -299.061512)
			(xy 424.856304 -299.105089) (xy 424.871888 -299.15177) (xy 424.879783 -299.200347) (xy 424.880278 -299.224954)
			(xy 424.879783 -299.249561) (xy 424.871888 -299.298138) (xy 424.856304 -299.344819) (xy 424.833433 -299.388396)
			(xy 424.803868 -299.42774) (xy 424.768375 -299.461832) (xy 424.727872 -299.489788) (xy 424.68341 -299.510886)
			(xy 424.636139 -299.524578) (xy 424.587284 -299.53051) (xy 424.538109 -299.528529) (xy 424.48989 -299.518685)
			(xy 424.443874 -299.501233) (xy 424.401253 -299.476626) (xy 424.363132 -299.445501) (xy 424.330497 -299.408664)
			(xy 424.304194 -299.367068) (xy 424.284903 -299.321792) (xy 424.273126 -299.274008) (xy 424.269166 -299.224954)
			(xy 422.030144 -299.224954) (xy 422.029649 -299.249561) (xy 422.021754 -299.298138) (xy 422.00617 -299.344819)
			(xy 421.983299 -299.388396) (xy 421.953734 -299.42774) (xy 421.918241 -299.461832) (xy 421.877738 -299.489788)
			(xy 421.833276 -299.510886) (xy 421.786005 -299.524578) (xy 421.73715 -299.53051) (xy 421.687975 -299.528529)
			(xy 421.639756 -299.518685) (xy 421.59374 -299.501233) (xy 421.551119 -299.476626) (xy 421.512998 -299.445501)
			(xy 421.480363 -299.408664) (xy 421.45406 -299.367068) (xy 421.434769 -299.321792) (xy 421.422992 -299.274008)
			(xy 421.419032 -299.224954) (xy 421.080184 -299.224954) (xy 421.079689 -299.249561) (xy 421.071794 -299.298138)
			(xy 421.05621 -299.344819) (xy 421.033339 -299.388396) (xy 421.003774 -299.42774) (xy 420.968281 -299.461832)
			(xy 420.927778 -299.489788) (xy 420.883316 -299.510886) (xy 420.836045 -299.524578) (xy 420.78719 -299.53051)
			(xy 420.738015 -299.528529) (xy 420.689796 -299.518685) (xy 420.64378 -299.501233) (xy 420.601159 -299.476626)
			(xy 420.563038 -299.445501) (xy 420.530403 -299.408664) (xy 420.5041 -299.367068) (xy 420.484809 -299.321792)
			(xy 420.473032 -299.274008) (xy 420.469072 -299.224954) (xy 420.130224 -299.224954) (xy 420.129729 -299.249561)
			(xy 420.121834 -299.298138) (xy 420.10625 -299.344819) (xy 420.083379 -299.388396) (xy 420.053814 -299.42774)
			(xy 420.018321 -299.461832) (xy 419.977818 -299.489788) (xy 419.933356 -299.510886) (xy 419.886085 -299.524578)
			(xy 419.83723 -299.53051) (xy 419.788055 -299.528529) (xy 419.739836 -299.518685) (xy 419.69382 -299.501233)
			(xy 419.651199 -299.476626) (xy 419.613078 -299.445501) (xy 419.580443 -299.408664) (xy 419.55414 -299.367068)
			(xy 419.534849 -299.321792) (xy 419.523072 -299.274008) (xy 419.519112 -299.224954) (xy 419.180264 -299.224954)
			(xy 419.179769 -299.249561) (xy 419.171874 -299.298138) (xy 419.15629 -299.344819) (xy 419.133419 -299.388396)
			(xy 419.103854 -299.42774) (xy 419.068361 -299.461832) (xy 419.027858 -299.489788) (xy 418.983396 -299.510886)
			(xy 418.936125 -299.524578) (xy 418.88727 -299.53051) (xy 418.838095 -299.528529) (xy 418.789876 -299.518685)
			(xy 418.74386 -299.501233) (xy 418.701239 -299.476626) (xy 418.663118 -299.445501) (xy 418.630483 -299.408664)
			(xy 418.60418 -299.367068) (xy 418.584889 -299.321792) (xy 418.573112 -299.274008) (xy 418.569152 -299.224954)
			(xy 418.230304 -299.224954) (xy 418.229809 -299.249561) (xy 418.221914 -299.298138) (xy 418.20633 -299.344819)
			(xy 418.183459 -299.388396) (xy 418.153894 -299.42774) (xy 418.118401 -299.461832) (xy 418.077898 -299.489788)
			(xy 418.033436 -299.510886) (xy 417.986165 -299.524578) (xy 417.93731 -299.53051) (xy 417.888135 -299.528529)
			(xy 417.839916 -299.518685) (xy 417.7939 -299.501233) (xy 417.751279 -299.476626) (xy 417.713158 -299.445501)
			(xy 417.680523 -299.408664) (xy 417.65422 -299.367068) (xy 417.634929 -299.321792) (xy 417.623152 -299.274008)
			(xy 417.619192 -299.224954) (xy 417.28061 -299.224954) (xy 417.280614 -299.225) (xy 417.276443 -299.275337)
			(xy 417.264043 -299.324301) (xy 417.243753 -299.370556) (xy 417.216126 -299.412841) (xy 417.181915 -299.450001)
			(xy 417.142055 -299.481023) (xy 417.097632 -299.505062) (xy 417.049858 -299.52146) (xy 417.000037 -299.529771)
			(xy 416.974782 -299.530262) (xy 416.959888 -299.530063) (xy 416.930244 -299.527141) (xy 416.9156 -299.52442)
			(xy 416.915346 -299.52442) (xy 416.904303 -299.522869) (xy 416.882694 -299.528257) (xy 416.87369 -299.534834)
			(xy 416.82924 -299.570902) (xy 416.820815 -299.5785) (xy 416.81105 -299.598943) (xy 416.810444 -299.610272)
			(xy 416.810444 -300.281848) (xy 416.81085 -300.291864) (xy 416.818533 -300.310365) (xy 416.832712 -300.324518)
			(xy 416.851227 -300.332168) (xy 416.861244 -300.332648) (xy 417.5379 -300.332648) (xy 417.549014 -300.332113)
			(xy 417.569174 -300.322753) (xy 417.576762 -300.314614) (xy 417.620704 -300.262036) (xy 417.626546 -300.240446)
			(xy 417.624514 -300.22927) (xy 417.62227 -300.215921) (xy 417.619851 -300.188958) (xy 417.619688 -300.175422)
			(xy 417.619688 -300.174914) (xy 417.62021 -300.149659) (xy 417.628523 -300.099837) (xy 417.644924 -300.052063)
			(xy 417.668965 -300.00764) (xy 417.699989 -299.96778) (xy 417.737151 -299.93357) (xy 417.779437 -299.905944)
			(xy 417.825693 -299.885654) (xy 417.874658 -299.873254) (xy 417.924996 -299.869083) (xy 417.975334 -299.873254)
			(xy 418.024299 -299.885654) (xy 418.070555 -299.905944) (xy 418.112841 -299.93357) (xy 418.150003 -299.96778)
			(xy 418.181027 -300.00764) (xy 418.205068 -300.052063) (xy 418.221469 -300.099837) (xy 418.229782 -300.149659)
			(xy 418.230304 -300.174914) (xy 418.569152 -300.174914) (xy 418.573112 -300.12586) (xy 418.584889 -300.078076)
			(xy 418.60418 -300.0328) (xy 418.630483 -299.991204) (xy 418.663118 -299.954367) (xy 418.701239 -299.923242)
			(xy 418.74386 -299.898635) (xy 418.789876 -299.881183) (xy 418.838095 -299.871339) (xy 418.88727 -299.869358)
			(xy 418.936125 -299.87529) (xy 418.983396 -299.888982) (xy 419.027858 -299.91008) (xy 419.068361 -299.938036)
			(xy 419.103854 -299.972128) (xy 419.133419 -300.011472) (xy 419.15629 -300.055049) (xy 419.171874 -300.10173)
			(xy 419.179769 -300.150307) (xy 419.180264 -300.174914) (xy 420.469072 -300.174914) (xy 420.473032 -300.12586)
			(xy 420.484809 -300.078076) (xy 420.5041 -300.0328) (xy 420.530403 -299.991204) (xy 420.563038 -299.954367)
			(xy 420.601159 -299.923242) (xy 420.64378 -299.898635) (xy 420.689796 -299.881183) (xy 420.738015 -299.871339)
			(xy 420.78719 -299.869358) (xy 420.836045 -299.87529) (xy 420.883316 -299.888982) (xy 420.927778 -299.91008)
			(xy 420.968281 -299.938036) (xy 421.003774 -299.972128) (xy 421.033339 -300.011472) (xy 421.05621 -300.055049)
			(xy 421.071794 -300.10173) (xy 421.079689 -300.150307) (xy 421.080184 -300.174914) (xy 421.419032 -300.174914)
			(xy 421.422992 -300.12586) (xy 421.434769 -300.078076) (xy 421.45406 -300.0328) (xy 421.480363 -299.991204)
			(xy 421.512998 -299.954367) (xy 421.551119 -299.923242) (xy 421.59374 -299.898635) (xy 421.639756 -299.881183)
			(xy 421.687975 -299.871339) (xy 421.73715 -299.869358) (xy 421.786005 -299.87529) (xy 421.833276 -299.888982)
			(xy 421.877738 -299.91008) (xy 421.918241 -299.938036) (xy 421.953734 -299.972128) (xy 421.983299 -300.011472)
			(xy 422.00617 -300.055049) (xy 422.021754 -300.10173) (xy 422.029649 -300.150307) (xy 422.030144 -300.174914)
			(xy 422.368992 -300.174914) (xy 422.372952 -300.12586) (xy 422.384729 -300.078076) (xy 422.40402 -300.0328)
			(xy 422.430323 -299.991204) (xy 422.462958 -299.954367) (xy 422.501079 -299.923242) (xy 422.5437 -299.898635)
			(xy 422.589716 -299.881183) (xy 422.637935 -299.871339) (xy 422.68711 -299.869358) (xy 422.735965 -299.87529)
			(xy 422.783236 -299.888982) (xy 422.827698 -299.91008) (xy 422.868201 -299.938036) (xy 422.903694 -299.972128)
			(xy 422.933259 -300.011472) (xy 422.95613 -300.055049) (xy 422.971714 -300.10173) (xy 422.979609 -300.150307)
			(xy 422.980104 -300.174914) (xy 423.319206 -300.174914) (xy 423.323166 -300.12586) (xy 423.334943 -300.078076)
			(xy 423.354234 -300.0328) (xy 423.380537 -299.991204) (xy 423.413172 -299.954367) (xy 423.451293 -299.923242)
			(xy 423.493914 -299.898635) (xy 423.53993 -299.881183) (xy 423.588149 -299.871339) (xy 423.637324 -299.869358)
			(xy 423.686179 -299.87529) (xy 423.73345 -299.888982) (xy 423.777912 -299.91008) (xy 423.818415 -299.938036)
			(xy 423.853908 -299.972128) (xy 423.883473 -300.011472) (xy 423.906344 -300.055049) (xy 423.921928 -300.10173)
			(xy 423.929823 -300.150307) (xy 423.930318 -300.174914) (xy 424.269166 -300.174914) (xy 424.273126 -300.12586)
			(xy 424.284903 -300.078076) (xy 424.304194 -300.0328) (xy 424.330497 -299.991204) (xy 424.363132 -299.954367)
			(xy 424.401253 -299.923242) (xy 424.443874 -299.898635) (xy 424.48989 -299.881183) (xy 424.538109 -299.871339)
			(xy 424.587284 -299.869358) (xy 424.636139 -299.87529) (xy 424.68341 -299.888982) (xy 424.727872 -299.91008)
			(xy 424.768375 -299.938036) (xy 424.803868 -299.972128) (xy 424.833433 -300.011472) (xy 424.856304 -300.055049)
			(xy 424.871888 -300.10173) (xy 424.879783 -300.150307) (xy 424.880278 -300.174914) (xy 424.879783 -300.199521)
			(xy 424.871888 -300.248098) (xy 424.856304 -300.294779) (xy 424.833433 -300.338356) (xy 424.803868 -300.3777)
			(xy 424.768375 -300.411792) (xy 424.727872 -300.439748) (xy 424.68341 -300.460846) (xy 424.636139 -300.474538)
			(xy 424.587284 -300.48047) (xy 424.538109 -300.478489) (xy 424.48989 -300.468645) (xy 424.443874 -300.451193)
			(xy 424.401253 -300.426586) (xy 424.363132 -300.395461) (xy 424.330497 -300.358624) (xy 424.304194 -300.317028)
			(xy 424.284903 -300.271752) (xy 424.273126 -300.223968) (xy 424.269166 -300.174914) (xy 423.930318 -300.174914)
			(xy 423.929823 -300.199521) (xy 423.921928 -300.248098) (xy 423.906344 -300.294779) (xy 423.883473 -300.338356)
			(xy 423.853908 -300.3777) (xy 423.818415 -300.411792) (xy 423.777912 -300.439748) (xy 423.73345 -300.460846)
			(xy 423.686179 -300.474538) (xy 423.637324 -300.48047) (xy 423.588149 -300.478489) (xy 423.53993 -300.468645)
			(xy 423.493914 -300.451193) (xy 423.451293 -300.426586) (xy 423.413172 -300.395461) (xy 423.380537 -300.358624)
			(xy 423.354234 -300.317028) (xy 423.334943 -300.271752) (xy 423.323166 -300.223968) (xy 423.319206 -300.174914)
			(xy 422.980104 -300.174914) (xy 422.979609 -300.199521) (xy 422.971714 -300.248098) (xy 422.95613 -300.294779)
			(xy 422.933259 -300.338356) (xy 422.903694 -300.3777) (xy 422.868201 -300.411792) (xy 422.827698 -300.439748)
			(xy 422.783236 -300.460846) (xy 422.735965 -300.474538) (xy 422.68711 -300.48047) (xy 422.637935 -300.478489)
			(xy 422.589716 -300.468645) (xy 422.5437 -300.451193) (xy 422.501079 -300.426586) (xy 422.462958 -300.395461)
			(xy 422.430323 -300.358624) (xy 422.40402 -300.317028) (xy 422.384729 -300.271752) (xy 422.372952 -300.223968)
			(xy 422.368992 -300.174914) (xy 422.030144 -300.174914) (xy 422.029649 -300.199521) (xy 422.021754 -300.248098)
			(xy 422.00617 -300.294779) (xy 421.983299 -300.338356) (xy 421.953734 -300.3777) (xy 421.918241 -300.411792)
			(xy 421.877738 -300.439748) (xy 421.833276 -300.460846) (xy 421.786005 -300.474538) (xy 421.73715 -300.48047)
			(xy 421.687975 -300.478489) (xy 421.639756 -300.468645) (xy 421.59374 -300.451193) (xy 421.551119 -300.426586)
			(xy 421.512998 -300.395461) (xy 421.480363 -300.358624) (xy 421.45406 -300.317028) (xy 421.434769 -300.271752)
			(xy 421.422992 -300.223968) (xy 421.419032 -300.174914) (xy 421.080184 -300.174914) (xy 421.079689 -300.199521)
			(xy 421.071794 -300.248098) (xy 421.05621 -300.294779) (xy 421.033339 -300.338356) (xy 421.003774 -300.3777)
			(xy 420.968281 -300.411792) (xy 420.927778 -300.439748) (xy 420.883316 -300.460846) (xy 420.836045 -300.474538)
			(xy 420.78719 -300.48047) (xy 420.738015 -300.478489) (xy 420.689796 -300.468645) (xy 420.64378 -300.451193)
			(xy 420.601159 -300.426586) (xy 420.563038 -300.395461) (xy 420.530403 -300.358624) (xy 420.5041 -300.317028)
			(xy 420.484809 -300.271752) (xy 420.473032 -300.223968) (xy 420.469072 -300.174914) (xy 419.180264 -300.174914)
			(xy 419.179769 -300.199521) (xy 419.171874 -300.248098) (xy 419.15629 -300.294779) (xy 419.133419 -300.338356)
			(xy 419.103854 -300.3777) (xy 419.068361 -300.411792) (xy 419.027858 -300.439748) (xy 418.983396 -300.460846)
			(xy 418.936125 -300.474538) (xy 418.88727 -300.48047) (xy 418.838095 -300.478489) (xy 418.789876 -300.468645)
			(xy 418.74386 -300.451193) (xy 418.701239 -300.426586) (xy 418.663118 -300.395461) (xy 418.630483 -300.358624)
			(xy 418.60418 -300.317028) (xy 418.584889 -300.271752) (xy 418.573112 -300.223968) (xy 418.569152 -300.174914)
			(xy 418.230304 -300.174914) (xy 418.229773 -300.200328) (xy 418.221331 -300.250451) (xy 418.204699 -300.298481)
			(xy 418.180337 -300.343091) (xy 418.165026 -300.363382) (xy 418.159438 -300.370494) (xy 418.15385 -300.387258)
			(xy 418.154358 -300.403006) (xy 418.155105 -300.412603) (xy 418.16281 -300.430227) (xy 418.169344 -300.437296)
			(xy 418.482526 -300.750478) (xy 418.503691 -300.772671) (xy 418.538088 -300.823431) (xy 418.550852 -300.851316)
			(xy 418.556135 -300.862049) (xy 418.574423 -300.87742) (xy 418.585904 -300.88078) (xy 418.643562 -300.894242)
			(xy 418.654754 -300.896174) (xy 418.676905 -300.891318) (xy 418.686234 -300.884844) (xy 418.686488 -300.884844)
			(xy 418.706802 -300.869566) (xy 418.751408 -300.845207) (xy 418.799431 -300.828565) (xy 418.849545 -300.820099)
			(xy 418.874956 -300.819566) (xy 418.900214 -300.820107) (xy 418.950042 -300.828415) (xy 418.997822 -300.844812)
			(xy 419.042252 -300.868851) (xy 419.082119 -300.899875) (xy 419.116335 -300.937038) (xy 419.143966 -300.979327)
			(xy 419.16426 -301.025587) (xy 419.176662 -301.074557) (xy 419.180832 -301.124874) (xy 419.519112 -301.124874)
			(xy 419.523072 -301.07582) (xy 419.534849 -301.028036) (xy 419.55414 -300.98276) (xy 419.580443 -300.941164)
			(xy 419.613078 -300.904327) (xy 419.651199 -300.873202) (xy 419.69382 -300.848595) (xy 419.739836 -300.831143)
			(xy 419.788055 -300.821299) (xy 419.83723 -300.819318) (xy 419.886085 -300.82525) (xy 419.933356 -300.838942)
			(xy 419.977818 -300.86004) (xy 420.018321 -300.887996) (xy 420.053814 -300.922088) (xy 420.083379 -300.961432)
			(xy 420.10625 -301.005009) (xy 420.121834 -301.05169) (xy 420.129729 -301.100267) (xy 420.130224 -301.124874)
			(xy 420.469072 -301.124874) (xy 420.473032 -301.07582) (xy 420.484809 -301.028036) (xy 420.5041 -300.98276)
			(xy 420.530403 -300.941164) (xy 420.563038 -300.904327) (xy 420.601159 -300.873202) (xy 420.64378 -300.848595)
			(xy 420.689796 -300.831143) (xy 420.738015 -300.821299) (xy 420.78719 -300.819318) (xy 420.836045 -300.82525)
			(xy 420.883316 -300.838942) (xy 420.927778 -300.86004) (xy 420.968281 -300.887996) (xy 421.003774 -300.922088)
			(xy 421.033339 -300.961432) (xy 421.05621 -301.005009) (xy 421.071794 -301.05169) (xy 421.079689 -301.100267)
			(xy 421.080184 -301.124874) (xy 421.419032 -301.124874) (xy 421.422992 -301.07582) (xy 421.434769 -301.028036)
			(xy 421.45406 -300.98276) (xy 421.480363 -300.941164) (xy 421.512998 -300.904327) (xy 421.551119 -300.873202)
			(xy 421.59374 -300.848595) (xy 421.639756 -300.831143) (xy 421.687975 -300.821299) (xy 421.73715 -300.819318)
			(xy 421.786005 -300.82525) (xy 421.833276 -300.838942) (xy 421.877738 -300.86004) (xy 421.918241 -300.887996)
			(xy 421.953734 -300.922088) (xy 421.983299 -300.961432) (xy 422.00617 -301.005009) (xy 422.021754 -301.05169)
			(xy 422.029649 -301.100267) (xy 422.030144 -301.124874) (xy 424.269166 -301.124874) (xy 424.273126 -301.07582)
			(xy 424.284903 -301.028036) (xy 424.304194 -300.98276) (xy 424.330497 -300.941164) (xy 424.363132 -300.904327)
			(xy 424.401253 -300.873202) (xy 424.443874 -300.848595) (xy 424.48989 -300.831143) (xy 424.538109 -300.821299)
			(xy 424.587284 -300.819318) (xy 424.636139 -300.82525) (xy 424.68341 -300.838942) (xy 424.727872 -300.86004)
			(xy 424.768375 -300.887996) (xy 424.803868 -300.922088) (xy 424.833433 -300.961432) (xy 424.856304 -301.005009)
			(xy 424.871888 -301.05169) (xy 424.879783 -301.100267) (xy 424.880278 -301.124874) (xy 424.879783 -301.149481)
			(xy 424.871888 -301.198058) (xy 424.856304 -301.244739) (xy 424.833433 -301.288316) (xy 424.803868 -301.32766)
			(xy 424.768375 -301.361752) (xy 424.727872 -301.389708) (xy 424.68341 -301.410806) (xy 424.636139 -301.424498)
			(xy 424.587284 -301.43043) (xy 424.538109 -301.428449) (xy 424.48989 -301.418605) (xy 424.443874 -301.401153)
			(xy 424.401253 -301.376546) (xy 424.363132 -301.345421) (xy 424.330497 -301.308584) (xy 424.304194 -301.266988)
			(xy 424.284903 -301.221712) (xy 424.273126 -301.173928) (xy 424.269166 -301.124874) (xy 422.030144 -301.124874)
			(xy 422.029649 -301.149481) (xy 422.021754 -301.198058) (xy 422.00617 -301.244739) (xy 421.983299 -301.288316)
			(xy 421.953734 -301.32766) (xy 421.918241 -301.361752) (xy 421.877738 -301.389708) (xy 421.833276 -301.410806)
			(xy 421.786005 -301.424498) (xy 421.73715 -301.43043) (xy 421.687975 -301.428449) (xy 421.639756 -301.418605)
			(xy 421.59374 -301.401153) (xy 421.551119 -301.376546) (xy 421.512998 -301.345421) (xy 421.480363 -301.308584)
			(xy 421.45406 -301.266988) (xy 421.434769 -301.221712) (xy 421.422992 -301.173928) (xy 421.419032 -301.124874)
			(xy 421.080184 -301.124874) (xy 421.079689 -301.149481) (xy 421.071794 -301.198058) (xy 421.05621 -301.244739)
			(xy 421.033339 -301.288316) (xy 421.003774 -301.32766) (xy 420.968281 -301.361752) (xy 420.927778 -301.389708)
			(xy 420.883316 -301.410806) (xy 420.836045 -301.424498) (xy 420.78719 -301.43043) (xy 420.738015 -301.428449)
			(xy 420.689796 -301.418605) (xy 420.64378 -301.401153) (xy 420.601159 -301.376546) (xy 420.563038 -301.345421)
			(xy 420.530403 -301.308584) (xy 420.5041 -301.266988) (xy 420.484809 -301.221712) (xy 420.473032 -301.173928)
			(xy 420.469072 -301.124874) (xy 420.130224 -301.124874) (xy 420.129729 -301.149481) (xy 420.121834 -301.198058)
			(xy 420.10625 -301.244739) (xy 420.083379 -301.288316) (xy 420.053814 -301.32766) (xy 420.018321 -301.361752)
			(xy 419.977818 -301.389708) (xy 419.933356 -301.410806) (xy 419.886085 -301.424498) (xy 419.83723 -301.43043)
			(xy 419.788055 -301.428449) (xy 419.739836 -301.418605) (xy 419.69382 -301.401153) (xy 419.651199 -301.376546)
			(xy 419.613078 -301.345421) (xy 419.580443 -301.308584) (xy 419.55414 -301.266988) (xy 419.534849 -301.221712)
			(xy 419.523072 -301.173928) (xy 419.519112 -301.124874) (xy 419.180832 -301.124874) (xy 419.180834 -301.1249)
			(xy 419.176662 -301.175243) (xy 419.16426 -301.224213) (xy 419.143966 -301.270473) (xy 419.116335 -301.312762)
			(xy 419.082119 -301.349925) (xy 419.042252 -301.380949) (xy 418.997822 -301.404988) (xy 418.950042 -301.421385)
			(xy 418.900214 -301.429693) (xy 418.874956 -301.430182) (xy 418.846966 -301.429527) (xy 418.79192 -301.419334)
			(xy 418.739648 -301.399296) (xy 418.715444 -301.385224) (xy 418.707575 -301.380751) (xy 418.689849 -301.377141)
			(xy 418.671969 -301.379887) (xy 418.663882 -301.383954) (xy 418.602922 -301.41799) (xy 418.595217 -301.422738)
			(xy 418.583429 -301.436449) (xy 418.577133 -301.4534) (xy 418.57676 -301.46244) (xy 418.57676 -301.737268)
			(xy 418.577096 -301.746318) (xy 418.583383 -301.763291) (xy 418.595181 -301.777016) (xy 418.602922 -301.781718)
			(xy 418.663882 -301.815754) (xy 418.671966 -301.819835) (xy 418.689849 -301.822601) (xy 418.707575 -301.818964)
			(xy 418.715444 -301.814484) (xy 418.739637 -301.800388) (xy 418.791911 -301.780339) (xy 418.846963 -301.77015)
			(xy 418.874956 -301.769526) (xy 418.900219 -301.769947) (xy 418.950057 -301.778257) (xy 418.997846 -301.794657)
			(xy 419.042285 -301.818701) (xy 419.082159 -301.849731) (xy 419.116382 -301.886901) (xy 419.144019 -301.929198)
			(xy 419.164317 -301.975468) (xy 419.176721 -302.024447) (xy 419.180894 -302.0748) (xy 419.180891 -302.074834)
			(xy 419.519112 -302.074834) (xy 419.523072 -302.02578) (xy 419.534849 -301.977996) (xy 419.55414 -301.93272)
			(xy 419.580443 -301.891124) (xy 419.613078 -301.854287) (xy 419.651199 -301.823162) (xy 419.69382 -301.798555)
			(xy 419.739836 -301.781103) (xy 419.788055 -301.771259) (xy 419.83723 -301.769278) (xy 419.886085 -301.77521)
			(xy 419.933356 -301.788902) (xy 419.977818 -301.81) (xy 420.018321 -301.837956) (xy 420.053814 -301.872048)
			(xy 420.083379 -301.911392) (xy 420.10625 -301.954969) (xy 420.121834 -302.00165) (xy 420.129729 -302.050227)
			(xy 420.130224 -302.074834) (xy 420.469072 -302.074834) (xy 420.473032 -302.02578) (xy 420.484809 -301.977996)
			(xy 420.5041 -301.93272) (xy 420.530403 -301.891124) (xy 420.563038 -301.854287) (xy 420.601159 -301.823162)
			(xy 420.64378 -301.798555) (xy 420.689796 -301.781103) (xy 420.738015 -301.771259) (xy 420.78719 -301.769278)
			(xy 420.836045 -301.77521) (xy 420.883316 -301.788902) (xy 420.927778 -301.81) (xy 420.968281 -301.837956)
			(xy 421.003774 -301.872048) (xy 421.033339 -301.911392) (xy 421.05621 -301.954969) (xy 421.071794 -302.00165)
			(xy 421.079689 -302.050227) (xy 421.080184 -302.074834) (xy 421.419032 -302.074834) (xy 421.422992 -302.02578)
			(xy 421.434769 -301.977996) (xy 421.45406 -301.93272) (xy 421.480363 -301.891124) (xy 421.512998 -301.854287)
			(xy 421.551119 -301.823162) (xy 421.59374 -301.798555) (xy 421.639756 -301.781103) (xy 421.687975 -301.771259)
			(xy 421.73715 -301.769278) (xy 421.786005 -301.77521) (xy 421.833276 -301.788902) (xy 421.877738 -301.81)
			(xy 421.918241 -301.837956) (xy 421.953734 -301.872048) (xy 421.983299 -301.911392) (xy 422.00617 -301.954969)
			(xy 422.021754 -302.00165) (xy 422.029649 -302.050227) (xy 422.030144 -302.074834) (xy 422.368992 -302.074834)
			(xy 422.372952 -302.02578) (xy 422.384729 -301.977996) (xy 422.40402 -301.93272) (xy 422.430323 -301.891124)
			(xy 422.462958 -301.854287) (xy 422.501079 -301.823162) (xy 422.5437 -301.798555) (xy 422.589716 -301.781103)
			(xy 422.637935 -301.771259) (xy 422.68711 -301.769278) (xy 422.735965 -301.77521) (xy 422.783236 -301.788902)
			(xy 422.827698 -301.81) (xy 422.868201 -301.837956) (xy 422.903694 -301.872048) (xy 422.933259 -301.911392)
			(xy 422.95613 -301.954969) (xy 422.971714 -302.00165) (xy 422.979609 -302.050227) (xy 422.980104 -302.074834)
			(xy 423.319206 -302.074834) (xy 423.323166 -302.02578) (xy 423.334943 -301.977996) (xy 423.354234 -301.93272)
			(xy 423.380537 -301.891124) (xy 423.413172 -301.854287) (xy 423.451293 -301.823162) (xy 423.493914 -301.798555)
			(xy 423.53993 -301.781103) (xy 423.588149 -301.771259) (xy 423.637324 -301.769278) (xy 423.686179 -301.77521)
			(xy 423.73345 -301.788902) (xy 423.777912 -301.81) (xy 423.818415 -301.837956) (xy 423.853908 -301.872048)
			(xy 423.883473 -301.911392) (xy 423.906344 -301.954969) (xy 423.921928 -302.00165) (xy 423.929823 -302.050227)
			(xy 423.930318 -302.074834) (xy 424.269166 -302.074834) (xy 424.273126 -302.02578) (xy 424.284903 -301.977996)
			(xy 424.304194 -301.93272) (xy 424.330497 -301.891124) (xy 424.363132 -301.854287) (xy 424.401253 -301.823162)
			(xy 424.443874 -301.798555) (xy 424.48989 -301.781103) (xy 424.538109 -301.771259) (xy 424.587284 -301.769278)
			(xy 424.636139 -301.77521) (xy 424.68341 -301.788902) (xy 424.727872 -301.81) (xy 424.768375 -301.837956)
			(xy 424.803868 -301.872048) (xy 424.833433 -301.911392) (xy 424.856304 -301.954969) (xy 424.871888 -302.00165)
			(xy 424.879783 -302.050227) (xy 424.880278 -302.074834) (xy 424.879783 -302.099441) (xy 424.871888 -302.148018)
			(xy 424.856304 -302.194699) (xy 424.833433 -302.238276) (xy 424.803868 -302.27762) (xy 424.768375 -302.311712)
			(xy 424.727872 -302.339668) (xy 424.68341 -302.360766) (xy 424.636139 -302.374458) (xy 424.587284 -302.38039)
			(xy 424.538109 -302.378409) (xy 424.48989 -302.368565) (xy 424.443874 -302.351113) (xy 424.401253 -302.326506)
			(xy 424.363132 -302.295381) (xy 424.330497 -302.258544) (xy 424.304194 -302.216948) (xy 424.284903 -302.171672)
			(xy 424.273126 -302.123888) (xy 424.269166 -302.074834) (xy 423.930318 -302.074834) (xy 423.929823 -302.099441)
			(xy 423.921928 -302.148018) (xy 423.906344 -302.194699) (xy 423.883473 -302.238276) (xy 423.853908 -302.27762)
			(xy 423.818415 -302.311712) (xy 423.777912 -302.339668) (xy 423.73345 -302.360766) (xy 423.686179 -302.374458)
			(xy 423.637324 -302.38039) (xy 423.588149 -302.378409) (xy 423.53993 -302.368565) (xy 423.493914 -302.351113)
			(xy 423.451293 -302.326506) (xy 423.413172 -302.295381) (xy 423.380537 -302.258544) (xy 423.354234 -302.216948)
			(xy 423.334943 -302.171672) (xy 423.323166 -302.123888) (xy 423.319206 -302.074834) (xy 422.980104 -302.074834)
			(xy 422.979609 -302.099441) (xy 422.971714 -302.148018) (xy 422.95613 -302.194699) (xy 422.933259 -302.238276)
			(xy 422.903694 -302.27762) (xy 422.868201 -302.311712) (xy 422.827698 -302.339668) (xy 422.783236 -302.360766)
			(xy 422.735965 -302.374458) (xy 422.68711 -302.38039) (xy 422.637935 -302.378409) (xy 422.589716 -302.368565)
			(xy 422.5437 -302.351113) (xy 422.501079 -302.326506) (xy 422.462958 -302.295381) (xy 422.430323 -302.258544)
			(xy 422.40402 -302.216948) (xy 422.384729 -302.171672) (xy 422.372952 -302.123888) (xy 422.368992 -302.074834)
			(xy 422.030144 -302.074834) (xy 422.029649 -302.099441) (xy 422.021754 -302.148018) (xy 422.00617 -302.194699)
			(xy 421.983299 -302.238276) (xy 421.953734 -302.27762) (xy 421.918241 -302.311712) (xy 421.877738 -302.339668)
			(xy 421.833276 -302.360766) (xy 421.786005 -302.374458) (xy 421.73715 -302.38039) (xy 421.687975 -302.378409)
			(xy 421.639756 -302.368565) (xy 421.59374 -302.351113) (xy 421.551119 -302.326506) (xy 421.512998 -302.295381)
			(xy 421.480363 -302.258544) (xy 421.45406 -302.216948) (xy 421.434769 -302.171672) (xy 421.422992 -302.123888)
			(xy 421.419032 -302.074834) (xy 421.080184 -302.074834) (xy 421.079689 -302.099441) (xy 421.071794 -302.148018)
			(xy 421.05621 -302.194699) (xy 421.033339 -302.238276) (xy 421.003774 -302.27762) (xy 420.968281 -302.311712)
			(xy 420.927778 -302.339668) (xy 420.883316 -302.360766) (xy 420.836045 -302.374458) (xy 420.78719 -302.38039)
			(xy 420.738015 -302.378409) (xy 420.689796 -302.368565) (xy 420.64378 -302.351113) (xy 420.601159 -302.326506)
			(xy 420.563038 -302.295381) (xy 420.530403 -302.258544) (xy 420.5041 -302.216948) (xy 420.484809 -302.171672)
			(xy 420.473032 -302.123888) (xy 420.469072 -302.074834) (xy 420.130224 -302.074834) (xy 420.129729 -302.099441)
			(xy 420.121834 -302.148018) (xy 420.10625 -302.194699) (xy 420.083379 -302.238276) (xy 420.053814 -302.27762)
			(xy 420.018321 -302.311712) (xy 419.977818 -302.339668) (xy 419.933356 -302.360766) (xy 419.886085 -302.374458)
			(xy 419.83723 -302.38039) (xy 419.788055 -302.378409) (xy 419.739836 -302.368565) (xy 419.69382 -302.351113)
			(xy 419.651199 -302.326506) (xy 419.613078 -302.295381) (xy 419.580443 -302.258544) (xy 419.55414 -302.216948)
			(xy 419.534849 -302.171672) (xy 419.523072 -302.123888) (xy 419.519112 -302.074834) (xy 419.180891 -302.074834)
			(xy 419.176721 -302.125153) (xy 419.164317 -302.174132) (xy 419.144019 -302.220402) (xy 419.116382 -302.262699)
			(xy 419.082159 -302.299869) (xy 419.042285 -302.330899) (xy 418.997846 -302.354943) (xy 418.950057 -302.371343)
			(xy 418.900219 -302.379653) (xy 418.874956 -302.380142) (xy 418.846965 -302.379492) (xy 418.791919 -302.369298)
			(xy 418.739647 -302.349258) (xy 418.715444 -302.335184) (xy 418.707575 -302.330713) (xy 418.689849 -302.327106)
			(xy 418.67197 -302.329849) (xy 418.663882 -302.333914) (xy 418.602922 -302.36795) (xy 418.59519 -302.37266)
			(xy 418.583407 -302.386388) (xy 418.577124 -302.403354) (xy 418.57676 -302.4124) (xy 418.57676 -302.687228)
			(xy 418.577124 -302.696275) (xy 418.583398 -302.713247) (xy 418.595185 -302.726974) (xy 418.602922 -302.731678)
			(xy 418.663882 -302.765714) (xy 418.671965 -302.769798) (xy 418.689849 -302.772567) (xy 418.707576 -302.768927)
			(xy 418.715444 -302.764444) (xy 418.73964 -302.750353) (xy 418.791912 -302.730301) (xy 418.846963 -302.72011)
			(xy 418.874956 -302.719486) (xy 418.900216 -302.719987) (xy 418.950047 -302.728296) (xy 418.99783 -302.744694)
			(xy 419.042263 -302.768734) (xy 419.082132 -302.79976) (xy 419.11635 -302.836926) (xy 419.143984 -302.879217)
			(xy 419.164279 -302.925481) (xy 419.176682 -302.974454) (xy 419.180854 -303.024794) (xy 419.519112 -303.024794)
			(xy 419.523072 -302.97574) (xy 419.534849 -302.927956) (xy 419.55414 -302.88268) (xy 419.580443 -302.841084)
			(xy 419.613078 -302.804247) (xy 419.651199 -302.773122) (xy 419.69382 -302.748515) (xy 419.739836 -302.731063)
			(xy 419.788055 -302.721219) (xy 419.83723 -302.719238) (xy 419.886085 -302.72517) (xy 419.933356 -302.738862)
			(xy 419.977818 -302.75996) (xy 420.018321 -302.787916) (xy 420.053814 -302.822008) (xy 420.083379 -302.861352)
			(xy 420.10625 -302.904929) (xy 420.121834 -302.95161) (xy 420.129729 -303.000187) (xy 420.130224 -303.024794)
			(xy 420.469072 -303.024794) (xy 420.473032 -302.97574) (xy 420.484809 -302.927956) (xy 420.5041 -302.88268)
			(xy 420.530403 -302.841084) (xy 420.563038 -302.804247) (xy 420.601159 -302.773122) (xy 420.64378 -302.748515)
			(xy 420.689796 -302.731063) (xy 420.738015 -302.721219) (xy 420.78719 -302.719238) (xy 420.836045 -302.72517)
			(xy 420.883316 -302.738862) (xy 420.927778 -302.75996) (xy 420.968281 -302.787916) (xy 421.003774 -302.822008)
			(xy 421.033339 -302.861352) (xy 421.05621 -302.904929) (xy 421.071794 -302.95161) (xy 421.079689 -303.000187)
			(xy 421.080184 -303.024794) (xy 421.419032 -303.024794) (xy 421.422992 -302.97574) (xy 421.434769 -302.927956)
			(xy 421.45406 -302.88268) (xy 421.480363 -302.841084) (xy 421.512998 -302.804247) (xy 421.551119 -302.773122)
			(xy 421.59374 -302.748515) (xy 421.639756 -302.731063) (xy 421.687975 -302.721219) (xy 421.73715 -302.719238)
			(xy 421.786005 -302.72517) (xy 421.833276 -302.738862) (xy 421.877738 -302.75996) (xy 421.918241 -302.787916)
			(xy 421.953734 -302.822008) (xy 421.983299 -302.861352) (xy 422.00617 -302.904929) (xy 422.021754 -302.95161)
			(xy 422.029649 -303.000187) (xy 422.030144 -303.024794) (xy 422.029649 -303.049401) (xy 422.021754 -303.097978)
			(xy 422.00617 -303.144659) (xy 421.983299 -303.188236) (xy 421.953734 -303.22758) (xy 421.918241 -303.261672)
			(xy 421.877738 -303.289628) (xy 421.833276 -303.310726) (xy 421.786005 -303.324418) (xy 421.73715 -303.33035)
			(xy 421.687975 -303.328369) (xy 421.639756 -303.318525) (xy 421.59374 -303.301073) (xy 421.551119 -303.276466)
			(xy 421.512998 -303.245341) (xy 421.480363 -303.208504) (xy 421.45406 -303.166908) (xy 421.434769 -303.121632)
			(xy 421.422992 -303.073848) (xy 421.419032 -303.024794) (xy 421.080184 -303.024794) (xy 421.079689 -303.049401)
			(xy 421.071794 -303.097978) (xy 421.05621 -303.144659) (xy 421.033339 -303.188236) (xy 421.003774 -303.22758)
			(xy 420.968281 -303.261672) (xy 420.927778 -303.289628) (xy 420.883316 -303.310726) (xy 420.836045 -303.324418)
			(xy 420.78719 -303.33035) (xy 420.738015 -303.328369) (xy 420.689796 -303.318525) (xy 420.64378 -303.301073)
			(xy 420.601159 -303.276466) (xy 420.563038 -303.245341) (xy 420.530403 -303.208504) (xy 420.5041 -303.166908)
			(xy 420.484809 -303.121632) (xy 420.473032 -303.073848) (xy 420.469072 -303.024794) (xy 420.130224 -303.024794)
			(xy 420.129729 -303.049401) (xy 420.121834 -303.097978) (xy 420.10625 -303.144659) (xy 420.083379 -303.188236)
			(xy 420.053814 -303.22758) (xy 420.018321 -303.261672) (xy 419.977818 -303.289628) (xy 419.933356 -303.310726)
			(xy 419.886085 -303.324418) (xy 419.83723 -303.33035) (xy 419.788055 -303.328369) (xy 419.739836 -303.318525)
			(xy 419.69382 -303.301073) (xy 419.651199 -303.276466) (xy 419.613078 -303.245341) (xy 419.580443 -303.208504)
			(xy 419.55414 -303.166908) (xy 419.534849 -303.121632) (xy 419.523072 -303.073848) (xy 419.519112 -303.024794)
			(xy 419.180854 -303.024794) (xy 419.180854 -303.0248) (xy 419.176682 -303.075146) (xy 419.164279 -303.124119)
			(xy 419.143984 -303.170383) (xy 419.11635 -303.212674) (xy 419.082132 -303.24984) (xy 419.042263 -303.280866)
			(xy 418.99783 -303.304906) (xy 418.950047 -303.321304) (xy 418.900216 -303.329613) (xy 418.874956 -303.330102)
			(xy 418.846966 -303.329444) (xy 418.791921 -303.319252) (xy 418.739648 -303.299216) (xy 418.715444 -303.285144)
			(xy 418.707574 -303.280675) (xy 418.689849 -303.277071) (xy 418.67197 -303.279812) (xy 418.663882 -303.283874)
			(xy 418.602922 -303.31791) (xy 418.595208 -303.322645) (xy 418.583422 -303.336362) (xy 418.57713 -303.353318)
			(xy 418.57676 -303.36236) (xy 418.57676 -303.499774) (xy 422.844226 -303.499774) (xy 422.848186 -303.45072)
			(xy 422.859963 -303.402936) (xy 422.879254 -303.35766) (xy 422.905557 -303.316064) (xy 422.938192 -303.279227)
			(xy 422.976313 -303.248102) (xy 423.018934 -303.223495) (xy 423.06495 -303.206043) (xy 423.113169 -303.196199)
			(xy 423.162344 -303.194218) (xy 423.211199 -303.20015) (xy 423.25847 -303.213842) (xy 423.302932 -303.23494)
			(xy 423.343435 -303.262896) (xy 423.378928 -303.296988) (xy 423.408493 -303.336332) (xy 423.431364 -303.379909)
			(xy 423.446948 -303.42659) (xy 423.454843 -303.475167) (xy 423.455172 -303.491533) (xy 423.794255 -303.491533)
			(xy 423.79962 -303.442177) (xy 423.8129 -303.39434) (xy 423.833744 -303.349281) (xy 423.861603 -303.308188)
			(xy 423.895743 -303.272143) (xy 423.935265 -303.242097) (xy 423.979128 -303.21884) (xy 424.026175 -303.202986)
			(xy 424.075167 -303.194953) (xy 424.09999 -303.194466) (xy 424.114173 -303.194644) (xy 424.142413 -303.197315)
			(xy 424.156378 -303.1998) (xy 424.170345 -303.201961) (xy 424.198479 -303.199387) (xy 424.224829 -303.1892)
			(xy 424.247378 -303.17218) (xy 424.264398 -303.149632) (xy 424.274586 -303.123282) (xy 424.277161 -303.095148)
			(xy 424.274996 -303.081182) (xy 424.272521 -303.067216) (xy 424.269848 -303.038976) (xy 424.269662 -303.024794)
			(xy 424.270184 -302.999973) (xy 424.278217 -302.950986) (xy 424.294068 -302.903943) (xy 424.317322 -302.860085)
			(xy 424.347365 -302.820567) (xy 424.383406 -302.786429) (xy 424.424495 -302.758573) (xy 424.469549 -302.73773)
			(xy 424.517382 -302.724452) (xy 424.566732 -302.719087) (xy 424.616301 -302.721777) (xy 424.664781 -302.73245)
			(xy 424.710896 -302.750827) (xy 424.753431 -302.776422) (xy 424.791264 -302.808562) (xy 424.823399 -302.846399)
			(xy 424.848989 -302.888936) (xy 424.86736 -302.935053) (xy 424.878028 -302.983535) (xy 424.880712 -303.033104)
			(xy 424.875341 -303.082454) (xy 424.862057 -303.130285) (xy 424.84121 -303.175337) (xy 424.813348 -303.216422)
			(xy 424.779207 -303.252459) (xy 424.739685 -303.282497) (xy 424.695824 -303.305746) (xy 424.648779 -303.321592)
			(xy 424.599791 -303.329619) (xy 424.57497 -303.330102) (xy 424.560787 -303.32993) (xy 424.532547 -303.327255)
			(xy 424.518582 -303.324768) (xy 424.504617 -303.322603) (xy 424.476487 -303.325186) (xy 424.450141 -303.335378)
			(xy 424.427596 -303.352398) (xy 424.410576 -303.374944) (xy 424.400386 -303.40129) (xy 424.397803 -303.42942)
			(xy 424.399964 -303.443386) (xy 424.402434 -303.457353) (xy 424.40511 -303.485592) (xy 424.405298 -303.499774)
			(xy 424.40485 -303.524597) (xy 424.396822 -303.57359) (xy 424.380974 -303.620639) (xy 424.357723 -303.664504)
			(xy 424.327681 -303.70403) (xy 424.29164 -303.738175) (xy 424.250551 -303.766039) (xy 424.205494 -303.786888)
			(xy 424.157658 -303.800173) (xy 424.108303 -303.805544) (xy 424.058729 -303.80286) (xy 424.010243 -303.79219)
			(xy 423.964121 -303.773817) (xy 423.92158 -303.748224) (xy 423.883739 -303.716086) (xy 423.851597 -303.67825)
			(xy 423.825999 -303.635711) (xy 423.80762 -303.589592) (xy 423.796945 -303.541106) (xy 423.794255 -303.491533)
			(xy 423.455172 -303.491533) (xy 423.455338 -303.499774) (xy 423.454843 -303.524381) (xy 423.446948 -303.572958)
			(xy 423.431364 -303.619639) (xy 423.408493 -303.663216) (xy 423.378928 -303.70256) (xy 423.343435 -303.736652)
			(xy 423.302932 -303.764608) (xy 423.25847 -303.785706) (xy 423.211199 -303.799398) (xy 423.162344 -303.80533)
			(xy 423.113169 -303.803349) (xy 423.06495 -303.793505) (xy 423.018934 -303.776053) (xy 422.976313 -303.751446)
			(xy 422.938192 -303.720321) (xy 422.905557 -303.683484) (xy 422.879254 -303.641888) (xy 422.859963 -303.596612)
			(xy 422.848186 -303.548828) (xy 422.844226 -303.499774) (xy 418.57676 -303.499774) (xy 418.57676 -303.646078)
			(xy 418.576505 -303.663881) (xy 418.572554 -303.699267) (xy 418.568886 -303.71669) (xy 418.567145 -303.725982)
			(xy 418.570002 -303.744661) (xy 418.57943 -303.761038) (xy 418.59415 -303.772888) (xy 418.612162 -303.778603)
			(xy 418.631021 -303.777407) (xy 418.648166 -303.769462) (xy 418.654992 -303.762918) (xy 418.672418 -303.745593)
			(xy 418.711741 -303.71613) (xy 418.755271 -303.69334) (xy 418.801887 -303.67781) (xy 418.850388 -303.66994)
			(xy 418.874956 -303.669446) (xy 418.900212 -303.670027) (xy 418.950037 -303.678335) (xy 418.997814 -303.694731)
			(xy 419.042241 -303.718768) (xy 419.082105 -303.74979) (xy 419.116319 -303.786951) (xy 419.143949 -303.829236)
			(xy 419.164241 -303.875494) (xy 419.176642 -303.92446) (xy 419.18081 -303.974754) (xy 419.519112 -303.974754)
			(xy 419.523072 -303.9257) (xy 419.534849 -303.877916) (xy 419.55414 -303.83264) (xy 419.580443 -303.791044)
			(xy 419.613078 -303.754207) (xy 419.651199 -303.723082) (xy 419.69382 -303.698475) (xy 419.739836 -303.681023)
			(xy 419.788055 -303.671179) (xy 419.83723 -303.669198) (xy 419.886085 -303.67513) (xy 419.933356 -303.688822)
			(xy 419.977818 -303.70992) (xy 420.018321 -303.737876) (xy 420.053814 -303.771968) (xy 420.083379 -303.811312)
			(xy 420.10625 -303.854889) (xy 420.121834 -303.90157) (xy 420.129729 -303.950147) (xy 420.130224 -303.974754)
			(xy 420.469072 -303.974754) (xy 420.473032 -303.9257) (xy 420.484809 -303.877916) (xy 420.5041 -303.83264)
			(xy 420.530403 -303.791044) (xy 420.563038 -303.754207) (xy 420.601159 -303.723082) (xy 420.64378 -303.698475)
			(xy 420.689796 -303.681023) (xy 420.738015 -303.671179) (xy 420.78719 -303.669198) (xy 420.836045 -303.67513)
			(xy 420.883316 -303.688822) (xy 420.927778 -303.70992) (xy 420.968281 -303.737876) (xy 421.003774 -303.771968)
			(xy 421.033339 -303.811312) (xy 421.05621 -303.854889) (xy 421.071794 -303.90157) (xy 421.079689 -303.950147)
			(xy 421.080184 -303.974754) (xy 421.419032 -303.974754) (xy 421.422992 -303.9257) (xy 421.434769 -303.877916)
			(xy 421.45406 -303.83264) (xy 421.480363 -303.791044) (xy 421.512998 -303.754207) (xy 421.551119 -303.723082)
			(xy 421.59374 -303.698475) (xy 421.639756 -303.681023) (xy 421.687975 -303.671179) (xy 421.73715 -303.669198)
			(xy 421.786005 -303.67513) (xy 421.833276 -303.688822) (xy 421.877738 -303.70992) (xy 421.918241 -303.737876)
			(xy 421.953734 -303.771968) (xy 421.983299 -303.811312) (xy 422.00617 -303.854889) (xy 422.021754 -303.90157)
			(xy 422.029649 -303.950147) (xy 422.030144 -303.974754) (xy 422.029649 -303.999361) (xy 422.021754 -304.047938)
			(xy 422.00617 -304.094619) (xy 421.983299 -304.138196) (xy 421.953734 -304.17754) (xy 421.918241 -304.211632)
			(xy 421.877738 -304.239588) (xy 421.833276 -304.260686) (xy 421.786005 -304.274378) (xy 421.73715 -304.28031)
			(xy 421.687975 -304.278329) (xy 421.639756 -304.268485) (xy 421.59374 -304.251033) (xy 421.551119 -304.226426)
			(xy 421.512998 -304.195301) (xy 421.480363 -304.158464) (xy 421.45406 -304.116868) (xy 421.434769 -304.071592)
			(xy 421.422992 -304.023808) (xy 421.419032 -303.974754) (xy 421.080184 -303.974754) (xy 421.079689 -303.999361)
			(xy 421.071794 -304.047938) (xy 421.05621 -304.094619) (xy 421.033339 -304.138196) (xy 421.003774 -304.17754)
			(xy 420.968281 -304.211632) (xy 420.927778 -304.239588) (xy 420.883316 -304.260686) (xy 420.836045 -304.274378)
			(xy 420.78719 -304.28031) (xy 420.738015 -304.278329) (xy 420.689796 -304.268485) (xy 420.64378 -304.251033)
			(xy 420.601159 -304.226426) (xy 420.563038 -304.195301) (xy 420.530403 -304.158464) (xy 420.5041 -304.116868)
			(xy 420.484809 -304.071592) (xy 420.473032 -304.023808) (xy 420.469072 -303.974754) (xy 420.130224 -303.974754)
			(xy 420.129729 -303.999361) (xy 420.121834 -304.047938) (xy 420.10625 -304.094619) (xy 420.083379 -304.138196)
			(xy 420.053814 -304.17754) (xy 420.018321 -304.211632) (xy 419.977818 -304.239588) (xy 419.933356 -304.260686)
			(xy 419.886085 -304.274378) (xy 419.83723 -304.28031) (xy 419.788055 -304.278329) (xy 419.739836 -304.268485)
			(xy 419.69382 -304.251033) (xy 419.651199 -304.226426) (xy 419.613078 -304.195301) (xy 419.580443 -304.158464)
			(xy 419.55414 -304.116868) (xy 419.534849 -304.071592) (xy 419.523072 -304.023808) (xy 419.519112 -303.974754)
			(xy 419.18081 -303.974754) (xy 419.180814 -303.9748) (xy 419.176642 -304.02514) (xy 419.164241 -304.074106)
			(xy 419.143949 -304.120364) (xy 419.116319 -304.162649) (xy 419.082105 -304.19981) (xy 419.042241 -304.230832)
			(xy 418.997814 -304.254869) (xy 418.950037 -304.271265) (xy 418.900212 -304.279573) (xy 418.874956 -304.280062)
			(xy 418.849012 -304.279556) (xy 418.797869 -304.270795) (xy 418.748943 -304.253514) (xy 418.703642 -304.228212)
			(xy 418.663271 -304.195616) (xy 418.62899 -304.156665) (xy 418.601786 -304.112479) (xy 418.582444 -304.064332)
			(xy 418.571518 -304.013607) (xy 418.569902 -303.987708) (xy 418.569902 -303.987454) (xy 418.569141 -303.978655)
			(xy 418.562445 -303.962327) (xy 418.550596 -303.949249) (xy 418.542978 -303.944782) (xy 418.469826 -303.906174)
			(xy 418.44214 -303.90719) (xy 418.43071 -303.91481) (xy 418.420967 -303.920958) (xy 418.400755 -303.932017)
			(xy 418.390324 -303.936908) (xy 418.24148 -304.005742) (xy 418.226748 -304.024538) (xy 418.224208 -304.036476)
			(xy 418.218392 -304.061942) (xy 418.199258 -304.110543) (xy 418.17214 -304.155185) (xy 418.137828 -304.194566)
			(xy 418.097321 -304.227542) (xy 418.051798 -304.253153) (xy 418.002584 -304.270652) (xy 417.951112 -304.27953)
			(xy 417.924996 -304.280062) (xy 417.921186 -304.280062) (xy 417.912309 -304.280369) (xy 417.89557 -304.286265)
			(xy 417.881848 -304.297519) (xy 417.87699 -304.304954) (xy 417.822126 -304.397156) (xy 417.809635 -304.417392)
			(xy 417.779602 -304.454261) (xy 417.756382 -304.475442) (xy 422.823382 -304.475442) (xy 422.823382 -304.424026)
			(xy 422.831425 -304.373244) (xy 422.847313 -304.324345) (xy 422.870656 -304.278533) (xy 422.900877 -304.236937)
			(xy 422.937233 -304.200581) (xy 422.978829 -304.17036) (xy 423.024641 -304.147017) (xy 423.07354 -304.131129)
			(xy 423.124322 -304.123086) (xy 423.175738 -304.123086) (xy 423.22652 -304.131129) (xy 423.275419 -304.147017)
			(xy 423.321231 -304.17036) (xy 423.362827 -304.200581) (xy 423.399183 -304.236937) (xy 423.429404 -304.278533)
			(xy 423.452747 -304.324345) (xy 423.468635 -304.373244) (xy 423.476678 -304.424026) (xy 423.477182 -304.449734)
			(xy 423.476678 -304.475442) (xy 423.773342 -304.475442) (xy 423.773342 -304.424026) (xy 423.781385 -304.373244)
			(xy 423.797273 -304.324345) (xy 423.820616 -304.278533) (xy 423.850837 -304.236937) (xy 423.887193 -304.200581)
			(xy 423.928789 -304.17036) (xy 423.974601 -304.147017) (xy 424.0235 -304.131129) (xy 424.074282 -304.123086)
			(xy 424.125698 -304.123086) (xy 424.17648 -304.131129) (xy 424.225379 -304.147017) (xy 424.271191 -304.17036)
			(xy 424.312787 -304.200581) (xy 424.349143 -304.236937) (xy 424.379364 -304.278533) (xy 424.402707 -304.324345)
			(xy 424.418595 -304.373244) (xy 424.426638 -304.424026) (xy 424.427142 -304.449734) (xy 424.426638 -304.475442)
			(xy 424.418595 -304.526224) (xy 424.402707 -304.575123) (xy 424.379364 -304.620935) (xy 424.349143 -304.662531)
			(xy 424.312787 -304.698887) (xy 424.271191 -304.729108) (xy 424.225379 -304.752451) (xy 424.17648 -304.768339)
			(xy 424.125698 -304.776382) (xy 424.074282 -304.776382) (xy 424.0235 -304.768339) (xy 423.974601 -304.752451)
			(xy 423.928789 -304.729108) (xy 423.887193 -304.698887) (xy 423.850837 -304.662531) (xy 423.820616 -304.620935)
			(xy 423.797273 -304.575123) (xy 423.781385 -304.526224) (xy 423.773342 -304.475442) (xy 423.476678 -304.475442)
			(xy 423.468635 -304.526224) (xy 423.452747 -304.575123) (xy 423.429404 -304.620935) (xy 423.399183 -304.662531)
			(xy 423.362827 -304.698887) (xy 423.321231 -304.729108) (xy 423.275419 -304.752451) (xy 423.22652 -304.768339)
			(xy 423.175738 -304.776382) (xy 423.124322 -304.776382) (xy 423.07354 -304.768339) (xy 423.024641 -304.752451)
			(xy 422.978829 -304.729108) (xy 422.937233 -304.698887) (xy 422.900877 -304.662531) (xy 422.870656 -304.620935)
			(xy 422.847313 -304.575123) (xy 422.831425 -304.526224) (xy 422.823382 -304.475442) (xy 417.756382 -304.475442)
			(xy 417.74447 -304.486308) (xy 417.705003 -304.512835) (xy 417.662061 -304.533263) (xy 417.61658 -304.547149)
			(xy 417.56955 -304.554188) (xy 417.545774 -304.554636) (xy 417.356036 -304.554636) (xy 417.332133 -304.554161)
			(xy 417.284861 -304.547014) (xy 417.23917 -304.532946) (xy 417.196065 -304.512267) (xy 417.156497 -304.485434)
			(xy 417.121338 -304.453038) (xy 417.091364 -304.415793) (xy 417.078922 -304.395378) (xy 417.016692 -304.289206)
			(xy 416.993324 -304.275744) (xy 416.980116 -304.275744) (xy 416.971245 -304.276029) (xy 416.954551 -304.282033)
			(xy 416.940924 -304.293391) (xy 416.936174 -304.30089) (xy 416.880802 -304.395378) (xy 416.868382 -304.415807)
			(xy 416.838401 -304.453048) (xy 416.803236 -304.48544) (xy 416.763665 -304.512269) (xy 416.720557 -304.532946)
			(xy 416.674864 -304.547014) (xy 416.627592 -304.554162) (xy 416.603688 -304.554636) (xy 416.404044 -304.554636)
			(xy 416.380265 -304.554222) (xy 416.33323 -304.547193) (xy 416.287743 -304.53331) (xy 416.244798 -304.512877)
			(xy 416.205333 -304.48634) (xy 416.170207 -304.454278) (xy 416.140189 -304.417391) (xy 416.127692 -304.397156)
			(xy 416.072828 -304.304954) (xy 416.067937 -304.297541) (xy 416.054234 -304.286272) (xy 416.037506 -304.280364)
			(xy 416.028632 -304.280062) (xy 416.021012 -304.280062) (xy 416.012137 -304.280387) (xy 415.995399 -304.286275)
			(xy 415.981675 -304.297522) (xy 415.976816 -304.304954) (xy 415.921952 -304.397156) (xy 415.909443 -304.41738)
			(xy 415.879413 -304.454249) (xy 415.844284 -304.486297) (xy 415.80482 -304.512825) (xy 415.761881 -304.533256)
			(xy 415.716402 -304.547144) (xy 415.669375 -304.554186) (xy 415.6456 -304.554636) (xy 415.454084 -304.554636)
			(xy 415.430306 -304.554191) (xy 415.383272 -304.547167) (xy 415.337786 -304.53329) (xy 415.294842 -304.512862)
			(xy 415.255375 -304.48633) (xy 415.220249 -304.454272) (xy 415.19023 -304.417389) (xy 415.177732 -304.397156)
			(xy 415.122868 -304.304954) (xy 415.118014 -304.297513) (xy 415.104295 -304.286249) (xy 415.087551 -304.280354)
			(xy 415.078672 -304.280062) (xy 415.071052 -304.280062) (xy 415.062173 -304.280345) (xy 415.045433 -304.286252)
			(xy 415.031712 -304.297515) (xy 415.026856 -304.304954) (xy 414.971992 -304.397156) (xy 414.959456 -304.417362)
			(xy 414.92943 -304.454231) (xy 414.894305 -304.48628) (xy 414.854846 -304.51281) (xy 414.811912 -304.533244)
			(xy 414.766437 -304.547136) (xy 414.719414 -304.554184) (xy 414.69564 -304.554636) (xy 414.504124 -304.554636)
			(xy 414.480347 -304.554159) (xy 414.433315 -304.547141) (xy 414.38783 -304.53327) (xy 414.344885 -304.512847)
			(xy 414.305418 -304.48632) (xy 414.270291 -304.454267) (xy 414.24027 -304.417387) (xy 414.227772 -304.397156)
			(xy 414.172908 -304.304954) (xy 414.168029 -304.297532) (xy 414.154321 -304.286265) (xy 414.137587 -304.280361)
			(xy 414.128712 -304.280062) (xy 414.121092 -304.280062) (xy 414.112216 -304.280373) (xy 414.095477 -304.286267)
			(xy 414.081754 -304.29752) (xy 414.076896 -304.304954) (xy 414.022032 -304.397156) (xy 414.009537 -304.417389)
			(xy 413.979505 -304.454258) (xy 413.944373 -304.486305) (xy 413.904906 -304.512833) (xy 413.861965 -304.533262)
			(xy 413.816485 -304.547147) (xy 413.769456 -304.554188) (xy 413.74568 -304.554636) (xy 413.554164 -304.554636)
			(xy 413.530386 -304.554206) (xy 413.483351 -304.54718) (xy 413.437865 -304.5333) (xy 413.39492 -304.512869)
			(xy 413.355454 -304.486335) (xy 413.320328 -304.454275) (xy 413.290309 -304.41739) (xy 413.277812 -304.397156)
			(xy 413.222948 -304.304954) (xy 413.218106 -304.297504) (xy 413.204381 -304.286242) (xy 413.187633 -304.280351)
			(xy 413.178752 -304.280062) (xy 413.171132 -304.280062) (xy 413.162252 -304.280331) (xy 413.145512 -304.286244)
			(xy 413.131792 -304.297513) (xy 413.126936 -304.304954) (xy 413.072072 -304.397156) (xy 413.05955 -304.417371)
			(xy 413.029522 -304.45424) (xy 412.994394 -304.486289) (xy 412.954933 -304.512818) (xy 412.911996 -304.53325)
			(xy 412.86652 -304.54714) (xy 412.819495 -304.554185) (xy 412.79572 -304.554636) (xy 412.604204 -304.554636)
			(xy 412.580427 -304.554175) (xy 412.533394 -304.547154) (xy 412.487908 -304.53328) (xy 412.444963 -304.512855)
			(xy 412.405497 -304.486325) (xy 412.37037 -304.454269) (xy 412.34035 -304.417388) (xy 412.327852 -304.397156)
			(xy 412.272988 -304.304954) (xy 412.268121 -304.297523) (xy 412.254408 -304.286257) (xy 412.237669 -304.280358)
			(xy 412.228792 -304.280062) (xy 412.221172 -304.280062) (xy 412.212295 -304.280359) (xy 412.195555 -304.28626)
			(xy 412.181834 -304.297517) (xy 412.176976 -304.304954) (xy 412.122112 -304.397156) (xy 412.109631 -304.417398)
			(xy 412.079596 -304.454267) (xy 412.044462 -304.486314) (xy 412.004993 -304.51284) (xy 411.96205 -304.533268)
			(xy 411.916567 -304.547151) (xy 411.869537 -304.554189) (xy 411.84576 -304.554636) (xy 411.654244 -304.554636)
			(xy 411.630465 -304.554222) (xy 411.58343 -304.547193) (xy 411.537943 -304.53331) (xy 411.494998 -304.512877)
			(xy 411.455533 -304.48634) (xy 411.420407 -304.454278) (xy 411.390389 -304.417391) (xy 411.377892 -304.397156)
			(xy 411.323028 -304.304954) (xy 411.318137 -304.297541) (xy 411.304434 -304.286272) (xy 411.287706 -304.280364)
			(xy 411.278832 -304.280062) (xy 411.271212 -304.280062) (xy 411.262337 -304.280387) (xy 411.245599 -304.286275)
			(xy 411.231875 -304.297522) (xy 411.227016 -304.304954) (xy 411.172152 -304.397156) (xy 411.159643 -304.41738)
			(xy 411.129613 -304.454249) (xy 411.094484 -304.486297) (xy 411.05502 -304.512825) (xy 411.012081 -304.533256)
			(xy 410.966602 -304.547144) (xy 410.919575 -304.554186) (xy 410.8958 -304.554636) (xy 410.70403 -304.554636)
			(xy 410.680251 -304.554233) (xy 410.633215 -304.547201) (xy 410.587728 -304.533317) (xy 410.544783 -304.512882)
			(xy 410.505318 -304.486343) (xy 410.470193 -304.45428) (xy 410.440175 -304.417391) (xy 410.427678 -304.397156)
			(xy 410.372814 -304.304954) (xy 410.367931 -304.297535) (xy 410.354225 -304.286267) (xy 410.337493 -304.280362)
			(xy 410.328618 -304.280062) (xy 410.320998 -304.280062) (xy 410.312122 -304.280378) (xy 410.295384 -304.28627)
			(xy 410.281661 -304.29752) (xy 410.276802 -304.304954) (xy 410.221938 -304.397156) (xy 410.209439 -304.417386)
			(xy 410.179407 -304.454256) (xy 410.144276 -304.486303) (xy 410.10481 -304.51283) (xy 410.06187 -304.53326)
			(xy 410.01639 -304.547146) (xy 409.969362 -304.554187) (xy 409.945586 -304.554636) (xy 409.75407 -304.554636)
			(xy 409.730292 -304.554202) (xy 409.683257 -304.547176) (xy 409.637771 -304.533297) (xy 409.594826 -304.512867)
			(xy 409.55536 -304.486333) (xy 409.520234 -304.454274) (xy 409.490215 -304.41739) (xy 409.477718 -304.397156)
			(xy 409.422854 -304.304954) (xy 409.418009 -304.297507) (xy 409.404285 -304.286244) (xy 409.387538 -304.280352)
			(xy 409.378658 -304.280062) (xy 409.371038 -304.280062) (xy 409.362159 -304.280335) (xy 409.345418 -304.286247)
			(xy 409.331698 -304.297513) (xy 409.326842 -304.304954) (xy 409.271978 -304.397156) (xy 409.259452 -304.417368)
			(xy 409.229424 -304.454238) (xy 409.194298 -304.486286) (xy 409.154837 -304.512815) (xy 409.111901 -304.533248)
			(xy 409.066425 -304.547138) (xy 409.0194 -304.554185) (xy 408.995626 -304.554636) (xy 408.80411 -304.554636)
			(xy 408.780333 -304.55417) (xy 408.7333 -304.54715) (xy 408.687814 -304.533277) (xy 408.64487 -304.512852)
			(xy 408.605403 -304.486323) (xy 408.570276 -304.454269) (xy 408.540256 -304.417388) (xy 408.527758 -304.397156)
			(xy 408.472894 -304.304954) (xy 408.468024 -304.297525) (xy 408.454312 -304.286259) (xy 408.437575 -304.280359)
			(xy 408.428698 -304.280062) (xy 408.421078 -304.280062) (xy 408.412201 -304.280364) (xy 408.395462 -304.286262)
			(xy 408.38174 -304.297518) (xy 408.376882 -304.304954) (xy 408.322018 -304.397156) (xy 408.309533 -304.417395)
			(xy 408.279499 -304.454264) (xy 408.244365 -304.486311) (xy 408.204897 -304.512838) (xy 408.161955 -304.533266)
			(xy 408.116473 -304.54715) (xy 408.069443 -304.554189) (xy 408.045666 -304.554636) (xy 406.90419 -304.554636)
			(xy 406.880412 -304.554186) (xy 406.833379 -304.547163) (xy 406.787893 -304.533287) (xy 406.744948 -304.51286)
			(xy 406.705482 -304.486328) (xy 406.670355 -304.454271) (xy 406.640336 -304.417389) (xy 406.627838 -304.397156)
			(xy 406.572974 -304.304954) (xy 406.568116 -304.297516) (xy 406.554399 -304.286252) (xy 406.537656 -304.280355)
			(xy 406.528778 -304.280062) (xy 406.521158 -304.280062) (xy 406.51228 -304.280349) (xy 406.49554 -304.286254)
			(xy 406.481819 -304.297516) (xy 406.476962 -304.304954) (xy 406.422098 -304.397156) (xy 406.409558 -304.417359)
			(xy 406.379533 -304.454229) (xy 406.344409 -304.486278) (xy 406.30495 -304.512808) (xy 406.262016 -304.533242)
			(xy 406.216543 -304.547134) (xy 406.16952 -304.554183) (xy 406.145746 -304.554636) (xy 405.95423 -304.554636)
			(xy 405.930451 -304.554233) (xy 405.883415 -304.547201) (xy 405.837928 -304.533317) (xy 405.794983 -304.512882)
			(xy 405.755518 -304.486343) (xy 405.720393 -304.45428) (xy 405.690375 -304.417391) (xy 405.677878 -304.397156)
			(xy 405.623014 -304.304954) (xy 405.618131 -304.297535) (xy 405.604425 -304.286267) (xy 405.587693 -304.280362)
			(xy 405.578818 -304.280062) (xy 405.571198 -304.280062) (xy 405.562322 -304.280378) (xy 405.545584 -304.28627)
			(xy 405.531861 -304.29752) (xy 405.527002 -304.304954) (xy 405.472138 -304.397156) (xy 405.459639 -304.417386)
			(xy 405.429607 -304.454256) (xy 405.394476 -304.486303) (xy 405.35501 -304.51283) (xy 405.31207 -304.53326)
			(xy 405.26659 -304.547146) (xy 405.219562 -304.554187) (xy 405.195786 -304.554636) (xy 405.004016 -304.554636)
			(xy 404.980239 -304.554166) (xy 404.933206 -304.547146) (xy 404.887721 -304.533274) (xy 404.844776 -304.51285)
			(xy 404.80531 -304.486322) (xy 404.770183 -304.454268) (xy 404.740162 -304.417388) (xy 404.727664 -304.397156)
			(xy 404.6728 -304.304954) (xy 404.667926 -304.297528) (xy 404.654216 -304.286262) (xy 404.63748 -304.280359)
			(xy 404.628604 -304.280062) (xy 404.620984 -304.280062) (xy 404.612107 -304.280368) (xy 404.595368 -304.286264)
			(xy 404.581646 -304.297519) (xy 404.576788 -304.304954) (xy 404.521924 -304.397156) (xy 404.509435 -304.417392)
			(xy 404.479401 -304.454262) (xy 404.444269 -304.486309) (xy 404.404801 -304.512836) (xy 404.361859 -304.533264)
			(xy 404.316378 -304.547149) (xy 404.269348 -304.554188) (xy 404.245572 -304.554636) (xy 404.054056 -304.554636)
			(xy 404.030278 -304.554213) (xy 403.983242 -304.547185) (xy 403.937756 -304.533304) (xy 403.894811 -304.512872)
			(xy 403.855345 -304.486337) (xy 403.82022 -304.454276) (xy 403.790201 -304.41739) (xy 403.777704 -304.397156)
			(xy 403.72284 -304.304954) (xy 403.718003 -304.297501) (xy 403.704276 -304.286239) (xy 403.687526 -304.28035)
			(xy 403.678644 -304.280062) (xy 403.671024 -304.280062) (xy 403.662149 -304.280396) (xy 403.645412 -304.286279)
			(xy 403.631688 -304.297523) (xy 403.626828 -304.304954) (xy 403.571964 -304.397156) (xy 403.559447 -304.417375)
			(xy 403.529418 -304.454244) (xy 403.49429 -304.486292) (xy 403.454828 -304.512821) (xy 403.41189 -304.533252)
			(xy 403.366413 -304.547141) (xy 403.319387 -304.554186) (xy 403.295612 -304.554636) (xy 403.104096 -304.554636)
			(xy 403.080319 -304.554181) (xy 403.033285 -304.547159) (xy 402.987799 -304.533284) (xy 402.944855 -304.512858)
			(xy 402.905388 -304.486327) (xy 402.870262 -304.454271) (xy 402.840242 -304.417389) (xy 402.827744 -304.397156)
			(xy 402.77288 -304.304954) (xy 402.768018 -304.297519) (xy 402.754303 -304.286254) (xy 402.737562 -304.280356)
			(xy 402.728684 -304.280062) (xy 402.721064 -304.280062) (xy 402.712186 -304.280354) (xy 402.695447 -304.286257)
			(xy 402.681725 -304.297516) (xy 402.676868 -304.304954) (xy 402.622004 -304.397156) (xy 402.60946 -304.417357)
			(xy 402.579435 -304.454226) (xy 402.544312 -304.486275) (xy 402.504854 -304.512806) (xy 402.461921 -304.53324)
			(xy 402.416448 -304.547133) (xy 402.369425 -304.554183) (xy 402.345652 -304.554636) (xy 402.154136 -304.554636)
			(xy 402.130357 -304.554228) (xy 402.083321 -304.547198) (xy 402.037834 -304.533314) (xy 401.99489 -304.51288)
			(xy 401.955424 -304.486342) (xy 401.920299 -304.454279) (xy 401.890281 -304.417391) (xy 401.877784 -304.397156)
			(xy 401.82292 -304.304954) (xy 401.818034 -304.297537) (xy 401.804329 -304.286269) (xy 401.787598 -304.280363)
			(xy 401.778724 -304.280062) (xy 401.771104 -304.280062) (xy 401.762228 -304.280382) (xy 401.74549 -304.286272)
			(xy 401.731767 -304.297521) (xy 401.726908 -304.304954) (xy 401.672044 -304.397156) (xy 401.659541 -304.417384)
			(xy 401.62951 -304.454253) (xy 401.594379 -304.4863) (xy 401.554914 -304.512828) (xy 401.511975 -304.533258)
			(xy 401.466495 -304.547145) (xy 401.419468 -304.554187) (xy 401.395692 -304.554636) (xy 401.204176 -304.554636)
			(xy 401.180398 -304.554197) (xy 401.133364 -304.547172) (xy 401.087878 -304.533294) (xy 401.044933 -304.512865)
			(xy 401.005467 -304.486332) (xy 400.970341 -304.454273) (xy 400.940322 -304.417389) (xy 400.927824 -304.397156)
			(xy 400.87296 -304.304954) (xy 400.868111 -304.29751) (xy 400.854389 -304.286246) (xy 400.837644 -304.280353)
			(xy 400.828764 -304.280062) (xy 400.821144 -304.280062) (xy 400.812265 -304.280339) (xy 400.795525 -304.286249)
			(xy 400.781804 -304.297514) (xy 400.776948 -304.304954) (xy 400.722084 -304.397156) (xy 400.709553 -304.417366)
			(xy 400.679527 -304.454235) (xy 400.644401 -304.486283) (xy 400.604941 -304.512813) (xy 400.562005 -304.533246)
			(xy 400.51653 -304.547137) (xy 400.469506 -304.554184) (xy 400.445732 -304.554636) (xy 400.254216 -304.554636)
			(xy 400.230439 -304.554166) (xy 400.183406 -304.547146) (xy 400.137921 -304.533274) (xy 400.094976 -304.51285)
			(xy 400.05551 -304.486322) (xy 400.020383 -304.454268) (xy 399.990362 -304.417388) (xy 399.977864 -304.397156)
			(xy 399.923 -304.304954) (xy 399.918126 -304.297528) (xy 399.904416 -304.286262) (xy 399.88768 -304.280359)
			(xy 399.878804 -304.280062) (xy 399.871184 -304.280062) (xy 399.862307 -304.280368) (xy 399.845568 -304.286264)
			(xy 399.831846 -304.297519) (xy 399.826988 -304.304954) (xy 399.772124 -304.397156) (xy 399.759635 -304.417392)
			(xy 399.729601 -304.454262) (xy 399.694469 -304.486309) (xy 399.655001 -304.512836) (xy 399.612059 -304.533264)
			(xy 399.566578 -304.547149) (xy 399.519548 -304.554188) (xy 399.495772 -304.554636) (xy 399.304256 -304.554636)
			(xy 399.280478 -304.554213) (xy 399.233442 -304.547185) (xy 399.187956 -304.533304) (xy 399.145011 -304.512872)
			(xy 399.105545 -304.486337) (xy 399.07042 -304.454276) (xy 399.040401 -304.41739) (xy 399.027904 -304.397156)
			(xy 398.97304 -304.304954) (xy 398.968203 -304.297501) (xy 398.954476 -304.286239) (xy 398.937726 -304.28035)
			(xy 398.928844 -304.280062) (xy 398.921224 -304.280062) (xy 398.912349 -304.280396) (xy 398.895612 -304.286279)
			(xy 398.881888 -304.297523) (xy 398.877028 -304.304954) (xy 398.822164 -304.397156) (xy 398.809647 -304.417375)
			(xy 398.779618 -304.454244) (xy 398.74449 -304.486292) (xy 398.705028 -304.512821) (xy 398.66209 -304.533252)
			(xy 398.616613 -304.547141) (xy 398.569587 -304.554186) (xy 398.545812 -304.554636) (xy 398.354042 -304.554636)
			(xy 398.330263 -304.554224) (xy 398.283228 -304.547194) (xy 398.237741 -304.533311) (xy 398.194796 -304.512878)
			(xy 398.15533 -304.48634) (xy 398.120205 -304.454278) (xy 398.090187 -304.417391) (xy 398.07769 -304.397156)
			(xy 398.022826 -304.304954) (xy 398.017936 -304.29754) (xy 398.004233 -304.286271) (xy 397.987504 -304.280364)
			(xy 397.97863 -304.280062) (xy 397.97482 -304.280062) (xy 397.950825 -304.279643) (xy 397.903426 -304.272138)
			(xy 397.857785 -304.257309) (xy 397.815025 -304.235523) (xy 397.776201 -304.207314) (xy 397.742269 -304.173379)
			(xy 397.714064 -304.134552) (xy 397.692281 -304.091791) (xy 397.677456 -304.046149) (xy 397.669955 -303.998749)
			(xy 397.669512 -303.974754) (xy 397.669512 -303.973992) (xy 397.669632 -303.965142) (xy 397.670778 -303.947478)
			(xy 397.671798 -303.938686) (xy 397.671798 -303.938432) (xy 397.672503 -303.92909) (xy 397.667863 -303.910953)
			(xy 397.657016 -303.895695) (xy 397.649446 -303.890172) (xy 397.578834 -303.843436) (xy 397.55727 -303.828352)
			(xy 397.518859 -303.792386) (xy 397.48681 -303.750651) (xy 397.461976 -303.70426) (xy 397.445019 -303.654446)
			(xy 397.436391 -303.602538) (xy 397.435832 -303.576228) (xy 397.435832 -303.42332) (xy 397.436327 -303.397)
			(xy 397.444899 -303.345063) (xy 397.461832 -303.295221) (xy 397.486674 -303.248811) (xy 397.518757 -303.207078)
			(xy 397.557221 -303.171141) (xy 397.578834 -303.156112) (xy 397.649446 -303.109376) (xy 397.656971 -303.10381)
			(xy 397.667789 -303.08856) (xy 397.672446 -303.070451) (xy 397.671798 -303.061116) (xy 397.671798 -303.060608)
			(xy 397.669512 -303.027588) (xy 397.668989 -303.018261) (xy 397.66211 -303.000911) (xy 397.649485 -302.987164)
			(xy 397.641318 -302.98263) (xy 397.635222 -302.979582) (xy 397.542004 -302.931322) (xy 397.5359 -302.927937)
			(xy 397.525721 -302.918393) (xy 397.521938 -302.912526) (xy 397.453358 -302.79975) (xy 397.445738 -302.790098)
			(xy 397.29664 -302.641) (xy 397.289177 -302.634284) (xy 397.270603 -302.626709) (xy 397.260572 -302.626268)
			(xy 396.35303 -302.626268) (xy 396.342867 -302.626794) (xy 396.324138 -302.634696) (xy 396.309932 -302.649236)
			(xy 396.305786 -302.658526) (xy 396.271242 -302.74641) (xy 396.267903 -302.755994) (xy 396.26832 -302.776268)
			(xy 396.276588 -302.794784) (xy 396.283688 -302.802036) (xy 396.30157 -302.819488) (xy 396.331975 -302.859134)
			(xy 396.355518 -302.903203) (xy 396.371572 -302.950516) (xy 396.379709 -302.999812) (xy 396.380208 -303.024794)
			(xy 396.379686 -303.050049) (xy 396.371373 -303.099871) (xy 396.354972 -303.147645) (xy 396.330931 -303.192068)
			(xy 396.299907 -303.231928) (xy 396.262745 -303.266138) (xy 396.220459 -303.293764) (xy 396.174203 -303.314054)
			(xy 396.125238 -303.326454) (xy 396.0749 -303.330625) (xy 396.024562 -303.326454) (xy 395.975597 -303.314054)
			(xy 395.929341 -303.293764) (xy 395.887055 -303.266138) (xy 395.849893 -303.231928) (xy 395.818869 -303.192068)
			(xy 395.794828 -303.147645) (xy 395.778427 -303.099871) (xy 395.770114 -303.050049) (xy 395.769592 -303.024794)
			(xy 395.770086 -302.999812) (xy 395.778222 -302.950515) (xy 395.794277 -302.903201) (xy 395.817821 -302.859131)
			(xy 395.848226 -302.819484) (xy 395.866112 -302.802036) (xy 395.873184 -302.794774) (xy 395.881391 -302.776253)
			(xy 395.881842 -302.756001) (xy 395.878558 -302.74641) (xy 395.844014 -302.658526) (xy 395.839871 -302.649222)
			(xy 395.825689 -302.634631) (xy 395.806944 -302.626717) (xy 395.79677 -302.626268) (xy 395.40307 -302.626268)
			(xy 395.392902 -302.62675) (xy 395.374172 -302.634672) (xy 395.359969 -302.649229) (xy 395.355826 -302.658526)
			(xy 395.321282 -302.74641) (xy 395.31796 -302.755997) (xy 395.318377 -302.776266) (xy 395.326635 -302.794781)
			(xy 395.333728 -302.802036) (xy 395.351618 -302.81948) (xy 395.38202 -302.85913) (xy 395.405561 -302.9032)
			(xy 395.421613 -302.950515) (xy 395.429749 -302.999812) (xy 395.430248 -303.024794) (xy 395.429726 -303.050049)
			(xy 395.421413 -303.099871) (xy 395.405012 -303.147645) (xy 395.380971 -303.192068) (xy 395.349947 -303.231928)
			(xy 395.312785 -303.266138) (xy 395.270499 -303.293764) (xy 395.224243 -303.314054) (xy 395.175278 -303.326454)
			(xy 395.12494 -303.330625) (xy 395.074602 -303.326454) (xy 395.025637 -303.314054) (xy 394.979381 -303.293764)
			(xy 394.937095 -303.266138) (xy 394.899933 -303.231928) (xy 394.868909 -303.192068) (xy 394.844868 -303.147645)
			(xy 394.828467 -303.099871) (xy 394.820154 -303.050049) (xy 394.819632 -303.024794) (xy 394.820114 -302.999811)
			(xy 394.828251 -302.950513) (xy 394.844308 -302.903198) (xy 394.867855 -302.859129) (xy 394.898264 -302.819483)
			(xy 394.916152 -302.802036) (xy 394.923227 -302.794777) (xy 394.93143 -302.776255) (xy 394.931881 -302.756002)
			(xy 394.928598 -302.74641) (xy 394.894054 -302.658526) (xy 394.889955 -302.649198) (xy 394.875755 -302.634608)
			(xy 394.856991 -302.626707) (xy 394.84681 -302.626268) (xy 394.792962 -302.626268) (xy 394.768144 -302.625717)
			(xy 394.719111 -302.617998) (xy 394.671844 -302.602842) (xy 394.627464 -302.580609) (xy 394.587025 -302.551825)
			(xy 394.568934 -302.534828) (xy 394.56741 -302.533304) (xy 394.565378 -302.531526) (xy 394.37183 -302.337978)
			(xy 394.338302 -302.333406) (xy 394.32357 -302.341788) (xy 394.300713 -302.353821) (xy 394.251974 -302.370915)
			(xy 394.201059 -302.379597) (xy 394.175234 -302.380142) (xy 394.17498 -302.380142) (xy 394.160861 -302.379951)
			(xy 394.132748 -302.377283) (xy 394.118846 -302.374808) (xy 394.118592 -302.374808) (xy 394.106361 -302.373358)
			(xy 394.082876 -302.380639) (xy 394.073634 -302.388778) (xy 394.013944 -302.448468) (xy 394.005796 -302.457712)
			(xy 393.998481 -302.481196) (xy 393.999974 -302.493426) (xy 393.999974 -302.493934) (xy 394.00242 -302.507712)
			(xy 394.005092 -302.535569) (xy 394.005308 -302.54956) (xy 394.005308 -302.550068) (xy 394.005097 -302.56406)
			(xy 394.002427 -302.591917) (xy 393.999974 -302.605694) (xy 393.999974 -302.606202) (xy 393.998537 -302.618433)
			(xy 394.005811 -302.641916) (xy 394.013944 -302.65116) (xy 394.073634 -302.71085) (xy 394.082781 -302.719151)
			(xy 394.106349 -302.726464) (xy 394.118592 -302.72482) (xy 394.1191 -302.72482) (xy 394.132941 -302.72237)
			(xy 394.160925 -302.719695) (xy 394.17498 -302.719486) (xy 394.200238 -302.719989) (xy 394.250066 -302.728301)
			(xy 394.297847 -302.744701) (xy 394.342276 -302.768742) (xy 394.382142 -302.799769) (xy 394.416357 -302.836934)
			(xy 394.443988 -302.879224) (xy 394.464281 -302.925485) (xy 394.476682 -302.974456) (xy 394.480854 -303.0248)
			(xy 394.476682 -303.075144) (xy 394.464281 -303.124115) (xy 394.443988 -303.170376) (xy 394.416357 -303.212666)
			(xy 394.382142 -303.249831) (xy 394.342276 -303.280858) (xy 394.297847 -303.304899) (xy 394.250066 -303.321299)
			(xy 394.200238 -303.329611) (xy 394.17498 -303.330102) (xy 394.160861 -303.329912) (xy 394.132748 -303.327243)
			(xy 394.118846 -303.324768) (xy 394.118592 -303.324768) (xy 394.106361 -303.323329) (xy 394.082878 -303.330604)
			(xy 394.073634 -303.338738) (xy 394.013944 -303.398428) (xy 394.005762 -303.407647) (xy 393.998467 -303.431151)
			(xy 393.999974 -303.443386) (xy 393.999974 -303.443894) (xy 394.002423 -303.457736) (xy 394.005098 -303.485719)
			(xy 394.005308 -303.499774) (xy 394.00485 -303.524597) (xy 393.996822 -303.573591) (xy 393.980974 -303.62064)
			(xy 393.957722 -303.664505) (xy 393.92768 -303.704031) (xy 393.891639 -303.738176) (xy 393.850549 -303.76604)
			(xy 393.805492 -303.786889) (xy 393.757655 -303.800174) (xy 393.7083 -303.805544) (xy 393.658726 -303.802859)
			(xy 393.610239 -303.792189) (xy 393.564117 -303.773815) (xy 393.521576 -303.748222) (xy 393.483736 -303.716083)
			(xy 393.451593 -303.678245) (xy 393.425996 -303.635706) (xy 393.407618 -303.589586) (xy 393.396944 -303.5411)
			(xy 393.394255 -303.491526) (xy 393.399621 -303.44217) (xy 393.412902 -303.394333) (xy 393.433747 -303.349274)
			(xy 393.461608 -303.308181) (xy 393.495749 -303.272138) (xy 393.535273 -303.242092) (xy 393.579136 -303.218837)
			(xy 393.626184 -303.202984) (xy 393.675177 -303.194952) (xy 393.7 -303.194466) (xy 393.71412 -303.194646)
			(xy 393.742232 -303.197322) (xy 393.756134 -303.1998) (xy 393.756388 -303.1998) (xy 393.768617 -303.2013)
			(xy 393.792107 -303.193984) (xy 393.801346 -303.18583) (xy 393.861036 -303.12614) (xy 393.869188 -303.1169)
			(xy 393.876497 -303.093412) (xy 393.875006 -303.081182) (xy 393.875006 -303.080674) (xy 393.872561 -303.066896)
			(xy 393.869889 -303.039039) (xy 393.869672 -303.025048) (xy 393.869672 -303.02454) (xy 393.869883 -303.010548)
			(xy 393.872553 -302.982691) (xy 393.875006 -302.968914) (xy 393.875006 -302.968406) (xy 393.876509 -302.956177)
			(xy 393.869191 -302.932687) (xy 393.861036 -302.923448) (xy 393.801346 -302.863758) (xy 393.792104 -302.855609)
			(xy 393.768618 -302.848299) (xy 393.756388 -302.849788) (xy 393.75588 -302.849788) (xy 393.742039 -302.852241)
			(xy 393.714055 -302.854914) (xy 393.7 -302.855122) (xy 393.674746 -302.854572) (xy 393.624926 -302.846259)
			(xy 393.577155 -302.829859) (xy 393.532734 -302.80582) (xy 393.492876 -302.774797) (xy 393.458667 -302.737637)
			(xy 393.431042 -302.695353) (xy 393.410753 -302.649099) (xy 393.398354 -302.600136) (xy 393.394183 -302.5498)
			(xy 393.398354 -302.499464) (xy 393.410753 -302.450501) (xy 393.431042 -302.404247) (xy 393.458667 -302.361963)
			(xy 393.492876 -302.324803) (xy 393.532734 -302.29378) (xy 393.577155 -302.269741) (xy 393.624926 -302.253341)
			(xy 393.674746 -302.245028) (xy 393.7 -302.244506) (xy 393.71412 -302.244685) (xy 393.742232 -302.247361)
			(xy 393.756134 -302.24984) (xy 393.756388 -302.24984) (xy 393.768617 -302.251357) (xy 393.79211 -302.244032)
			(xy 393.801346 -302.23587) (xy 393.861036 -302.17618) (xy 393.869222 -302.166965) (xy 393.876512 -302.143457)
			(xy 393.875006 -302.131222) (xy 393.875006 -302.130714) (xy 393.872553 -302.116937) (xy 393.869886 -302.08908)
			(xy 393.869672 -302.075088) (xy 393.869672 -302.07458) (xy 393.869875 -302.060588) (xy 393.87255 -302.032731)
			(xy 393.875006 -302.018954) (xy 393.875006 -302.018446) (xy 393.876482 -302.006216) (xy 393.869183 -301.982728)
			(xy 393.861036 -301.973488) (xy 393.801346 -301.913798) (xy 393.7921 -301.905653) (xy 393.768617 -301.898338)
			(xy 393.756388 -301.899828) (xy 393.75588 -301.899828) (xy 393.742039 -301.902281) (xy 393.714055 -301.904954)
			(xy 393.7 -301.905162) (xy 393.676005 -301.904762) (xy 393.628605 -301.897253) (xy 393.582963 -301.882422)
			(xy 393.540204 -301.860633) (xy 393.50138 -301.832422) (xy 393.467448 -301.798485) (xy 393.439243 -301.759657)
			(xy 393.41746 -301.716894) (xy 393.402636 -301.671251) (xy 393.395135 -301.62385) (xy 393.394692 -301.599854)
			(xy 393.394883 -301.585798) (xy 393.397558 -301.557813) (xy 393.400026 -301.543974) (xy 393.400026 -301.543466)
			(xy 393.401484 -301.531235) (xy 393.394196 -301.50775) (xy 393.386056 -301.498508) (xy 393.326366 -301.438818)
			(xy 393.317152 -301.43063) (xy 393.293644 -301.423339) (xy 393.281408 -301.424848) (xy 393.2809 -301.424848)
			(xy 393.267059 -301.427299) (xy 393.239075 -301.429973) (xy 393.22502 -301.430182) (xy 393.210837 -301.430003)
			(xy 393.182597 -301.427333) (xy 393.168632 -301.424848) (xy 393.168378 -301.424848) (xy 393.156147 -301.423378)
			(xy 393.132659 -301.430671) (xy 393.12342 -301.438818) (xy 393.06373 -301.498254) (xy 393.055588 -301.507503)
			(xy 393.04827 -301.530983) (xy 393.04976 -301.543212) (xy 393.04976 -301.54372) (xy 393.052223 -301.557624)
			(xy 393.054894 -301.585735) (xy 393.055094 -301.599854) (xy 393.054672 -301.624679) (xy 393.046647 -301.673677)
			(xy 393.0308 -301.72073) (xy 393.00755 -301.7646) (xy 392.977508 -301.804131) (xy 392.941466 -301.83828)
			(xy 392.900375 -301.866148) (xy 392.855316 -301.887002) (xy 392.807477 -301.90029) (xy 392.758119 -301.905664)
			(xy 392.708541 -301.902982) (xy 392.66005 -301.892314) (xy 392.613924 -301.873942) (xy 392.571378 -301.848348)
			(xy 392.533533 -301.816209) (xy 392.501387 -301.778371) (xy 392.475785 -301.73583) (xy 392.457404 -301.689708)
			(xy 392.446726 -301.641219) (xy 392.444034 -301.591642) (xy 392.449398 -301.542282) (xy 392.462678 -301.49444)
			(xy 392.483522 -301.449377) (xy 392.511382 -301.40828) (xy 392.545525 -301.372232) (xy 392.585049 -301.342183)
			(xy 392.628914 -301.318924) (xy 392.675965 -301.303068) (xy 392.724961 -301.295033) (xy 392.749786 -301.294546)
			(xy 392.763969 -301.294725) (xy 392.792209 -301.297396) (xy 392.806174 -301.29988) (xy 392.806428 -301.29988)
			(xy 392.818659 -301.301347) (xy 392.842146 -301.294055) (xy 392.851386 -301.28591) (xy 392.911076 -301.226474)
			(xy 392.919259 -301.217256) (xy 392.926553 -301.193751) (xy 392.925046 -301.181516) (xy 392.925046 -301.181008)
			(xy 392.922587 -301.167104) (xy 392.919913 -301.138993) (xy 392.919712 -301.124874) (xy 392.920234 -301.099619)
			(xy 392.928547 -301.049797) (xy 392.944948 -301.002023) (xy 392.968989 -300.9576) (xy 393.000013 -300.91774)
			(xy 393.037175 -300.88353) (xy 393.079461 -300.855904) (xy 393.125717 -300.835614) (xy 393.174682 -300.823214)
			(xy 393.22502 -300.819043) (xy 393.275358 -300.823214) (xy 393.324323 -300.835614) (xy 393.370579 -300.855904)
			(xy 393.412865 -300.88353) (xy 393.450027 -300.91774) (xy 393.481051 -300.9576) (xy 393.505092 -301.002023)
			(xy 393.521493 -301.049797) (xy 393.529806 -301.099619) (xy 393.530328 -301.124874) (xy 393.530126 -301.13893)
			(xy 393.527459 -301.166915) (xy 393.524994 -301.180754) (xy 393.524994 -301.181262) (xy 393.523512 -301.193492)
			(xy 393.530816 -301.21698) (xy 393.538964 -301.22622) (xy 393.598654 -301.28591) (xy 393.607899 -301.294056)
			(xy 393.631383 -301.301369) (xy 393.643612 -301.29988) (xy 393.64412 -301.29988) (xy 393.657898 -301.297437)
			(xy 393.685755 -301.294764) (xy 393.699746 -301.294546) (xy 393.700254 -301.294546) (xy 393.71431 -301.294735)
			(xy 393.742295 -301.297411) (xy 393.756134 -301.29988) (xy 393.756388 -301.29988) (xy 393.768617 -301.301386)
			(xy 393.792108 -301.294067) (xy 393.801346 -301.28591) (xy 393.861036 -301.22622) (xy 393.869199 -301.216988)
			(xy 393.876502 -301.193494) (xy 393.875006 -301.181262) (xy 393.875006 -301.180754) (xy 393.87255 -301.166914)
			(xy 393.869879 -301.138929) (xy 393.869672 -301.124874) (xy 393.869672 -301.12462) (xy 393.870246 -301.098553)
			(xy 393.879143 -301.047183) (xy 393.896632 -300.99807) (xy 393.922205 -300.952638) (xy 393.938252 -300.932088)
			(xy 393.949682 -300.917864) (xy 393.949936 -300.882304) (xy 393.947396 -300.879256) (xy 393.942286 -300.872328)
			(xy 393.936562 -300.856107) (xy 393.93622 -300.847506) (xy 393.93622 -300.452282) (xy 393.936562 -300.443681)
			(xy 393.942279 -300.427454) (xy 393.947396 -300.420532) (xy 393.949682 -300.417738) (xy 393.949428 -300.38167)
			(xy 393.938252 -300.367954) (xy 393.922172 -300.347388) (xy 393.896568 -300.301896) (xy 393.879075 -300.252712)
			(xy 393.870202 -300.201269) (xy 393.869672 -300.175168) (xy 393.869672 -300.17466) (xy 393.870213 -300.148592)
			(xy 393.879121 -300.09722) (xy 393.896619 -300.048107) (xy 393.922201 -300.002676) (xy 393.938252 -299.982128)
			(xy 393.949682 -299.967904) (xy 393.949936 -299.932344) (xy 393.947396 -299.929296) (xy 393.942261 -299.922384)
			(xy 393.936552 -299.90615) (xy 393.93622 -299.897546) (xy 393.93622 -299.502322) (xy 393.936581 -299.493723)
			(xy 393.942285 -299.477496) (xy 393.947396 -299.470572) (xy 393.949682 -299.467778) (xy 393.949428 -299.43171)
			(xy 393.938252 -299.417994) (xy 393.92219 -299.397415) (xy 393.896583 -299.351927) (xy 393.879085 -299.302747)
			(xy 393.870205 -299.251308) (xy 393.869672 -299.225208) (xy 393.869672 -299.2247) (xy 393.870235 -299.198633)
			(xy 393.879136 -299.147262) (xy 393.896628 -299.098149) (xy 393.922204 -299.052717) (xy 393.938252 -299.032168)
			(xy 393.949682 -299.017944) (xy 393.949936 -298.982384) (xy 393.947396 -298.979336) (xy 393.942278 -298.972413)
			(xy 393.936559 -298.956188) (xy 393.93622 -298.947586) (xy 393.93622 -298.552108) (xy 393.936575 -298.543508)
			(xy 393.942283 -298.527282) (xy 393.947396 -298.520358) (xy 393.949682 -298.517564) (xy 393.949428 -298.481496)
			(xy 393.938252 -298.46778) (xy 393.922183 -298.447205) (xy 393.896578 -298.401716) (xy 393.879081 -298.352535)
			(xy 393.870204 -298.301094) (xy 393.869672 -298.274994) (xy 393.869672 -298.274486) (xy 393.870227 -298.248418)
			(xy 393.879131 -298.197048) (xy 393.896625 -298.147934) (xy 393.922203 -298.102503) (xy 393.938252 -298.081954)
			(xy 393.949682 -298.06773) (xy 393.949936 -298.03217) (xy 393.947396 -298.029122) (xy 393.942272 -298.022203)
			(xy 393.936556 -298.005975) (xy 393.93622 -297.997372) (xy 393.93622 -297.664124) (xy 393.92479 -297.64228)
			(xy 393.914122 -297.635168) (xy 393.903459 -297.628696) (xy 393.878707 -297.625884) (xy 393.866878 -297.629834)
			(xy 393.8143 -297.650408) (xy 393.809849 -297.652081) (xy 393.800512 -297.653869) (xy 393.795758 -297.653964)
			(xy 393.654788 -297.653964) (xy 393.627503 -297.653322) (xy 393.573734 -297.643978) (xy 393.522308 -297.625711)
			(xy 393.474693 -297.599044) (xy 393.453112 -297.582336) (xy 393.444374 -297.576086) (xy 393.423617 -297.570658)
			(xy 393.402443 -297.574124) (xy 393.393168 -297.579542) (xy 393.374368 -297.591495) (xy 393.33403 -297.610401)
			(xy 393.291369 -297.623229) (xy 393.247294 -297.629706) (xy 393.22502 -297.630088) (xy 393.224766 -297.630088)
			(xy 393.202568 -297.629647) (xy 393.158643 -297.623194) (xy 393.116117 -297.610444) (xy 393.075888 -297.591667)
			(xy 393.057126 -297.579796) (xy 393.047556 -297.574134) (xy 393.025572 -297.570949) (xy 393.004308 -297.577377)
			(xy 392.995658 -297.584368) (xy 392.972798 -297.604434) (xy 392.969382 -297.607371) (xy 392.961717 -297.612102)
			(xy 392.957558 -297.613832) (xy 392.86434 -297.650408) (xy 392.859886 -297.65207) (xy 392.850551 -297.653865)
			(xy 392.845798 -297.653964) (xy 392.704574 -297.653964) (xy 392.677288 -297.65333) (xy 392.62352 -297.643984)
			(xy 392.572094 -297.625714) (xy 392.524479 -297.599045) (xy 392.502898 -297.582336) (xy 392.494168 -297.576074)
			(xy 392.473406 -297.57065) (xy 392.45223 -297.574121) (xy 392.442954 -297.579542) (xy 392.424158 -297.591501)
			(xy 392.383819 -297.610405) (xy 392.341156 -297.623232) (xy 392.297081 -297.629707) (xy 392.274806 -297.630088)
			(xy 392.252576 -297.62967) (xy 392.208584 -297.623233) (xy 392.165992 -297.610481) (xy 392.125701 -297.591683)
			(xy 392.106912 -297.579796) (xy 392.097272 -297.574055) (xy 392.075098 -297.570797) (xy 392.053648 -297.577295)
			(xy 392.044936 -297.584368) (xy 392.009376 -297.616372) (xy 392.004668 -297.620377) (xy 391.993743 -297.626153)
			(xy 391.987786 -297.627802) (xy 391.859262 -297.660314) (xy 391.853309 -297.661645) (xy 391.841114 -297.661766)
			(xy 391.835132 -297.660568) (xy 391.768838 -297.64482) (xy 391.740381 -297.637291) (xy 391.686649 -297.613264)
			(xy 391.638193 -297.57985) (xy 391.616946 -297.559476) (xy 391.605262 -297.547792) (xy 391.59802 -297.541191)
			(xy 391.579993 -297.533555) (xy 391.560418 -297.533205) (xy 391.542128 -297.54019) (xy 391.53465 -297.546522)
			(xy 391.534396 -297.546776) (xy 391.517309 -297.562342) (xy 391.479306 -297.58865) (xy 391.437769 -297.608925)
			(xy 391.39365 -297.622702) (xy 391.347956 -297.629666) (xy 391.324846 -297.630088) (xy 391.300853 -297.629619)
			(xy 391.253457 -297.622119) (xy 391.207819 -297.607295) (xy 391.165061 -297.585514) (xy 391.126238 -297.557311)
			(xy 391.092306 -297.523382) (xy 391.0641 -297.484561) (xy 391.042315 -297.441805) (xy 391.027487 -297.396168)
			(xy 391.019983 -297.348773) (xy 391.019538 -297.32478) (xy 391.019982 -297.301905) (xy 391.026799 -297.256666)
			(xy 391.04028 -297.212948) (xy 391.060122 -297.171725) (xy 391.085883 -297.133918) (xy 391.116988 -297.10037)
			(xy 391.1346 -297.085766) (xy 391.14192 -297.079258) (xy 391.151459 -297.062174) (xy 391.153926 -297.042763)
			(xy 391.151872 -297.033188) (xy 391.146867 -297.012984) (xy 391.141516 -296.971705) (xy 391.141204 -296.950892)
			(xy 391.141204 -294.830754) (xy 391.141399 -294.813282) (xy 391.14509 -294.778535) (xy 391.14857 -294.761412)
			(xy 391.150191 -294.752192) (xy 391.147432 -294.733692) (xy 391.138239 -294.717402) (xy 391.131298 -294.71112)
			(xy 391.112605 -294.695172) (xy 391.080073 -294.658353) (xy 391.053856 -294.616799) (xy 391.03463 -294.571584)
			(xy 391.022893 -294.523874) (xy 391.018946 -294.4749) (xy 391.022893 -294.425926) (xy 391.03463 -294.378216)
			(xy 391.053856 -294.333001) (xy 391.080073 -294.291447) (xy 391.112605 -294.254628) (xy 391.131298 -294.23868)
			(xy 391.138283 -294.232433) (xy 391.147509 -294.216139) (xy 391.150228 -294.197612) (xy 391.14857 -294.188388)
			(xy 391.145077 -294.171267) (xy 391.141381 -294.136519) (xy 391.141204 -294.119046) (xy 391.141204 -293.857172)
			(xy 391.140499 -293.844972) (xy 391.129209 -293.82334) (xy 391.119614 -293.81577) (xy 391.098504 -293.800244)
			(xy 391.060564 -293.764103) (xy 391.028334 -293.722789) (xy 391.002513 -293.677194) (xy 390.983659 -293.628305)
			(xy 390.972179 -293.57718) (xy 390.968323 -293.524923) (xy 390.680194 -293.524923) (xy 390.680194 -293.52494)
			(xy 390.679699 -293.549547) (xy 390.671804 -293.598124) (xy 390.65622 -293.644805) (xy 390.633349 -293.688382)
			(xy 390.603784 -293.727726) (xy 390.568291 -293.761818) (xy 390.527788 -293.789774) (xy 390.483326 -293.810872)
			(xy 390.436055 -293.824564) (xy 390.3872 -293.830496) (xy 390.338025 -293.828515) (xy 390.289806 -293.818671)
			(xy 390.24379 -293.801219) (xy 390.201169 -293.776612) (xy 390.163048 -293.745487) (xy 390.130413 -293.70865)
			(xy 390.10411 -293.667054) (xy 390.084819 -293.621778) (xy 390.073042 -293.573994) (xy 390.069082 -293.52494)
			(xy 389.730234 -293.52494) (xy 389.729739 -293.549547) (xy 389.721844 -293.598124) (xy 389.70626 -293.644805)
			(xy 389.683389 -293.688382) (xy 389.653824 -293.727726) (xy 389.618331 -293.761818) (xy 389.577828 -293.789774)
			(xy 389.533366 -293.810872) (xy 389.486095 -293.824564) (xy 389.43724 -293.830496) (xy 389.388065 -293.828515)
			(xy 389.339846 -293.818671) (xy 389.29383 -293.801219) (xy 389.251209 -293.776612) (xy 389.213088 -293.745487)
			(xy 389.180453 -293.70865) (xy 389.15415 -293.667054) (xy 389.134859 -293.621778) (xy 389.123082 -293.573994)
			(xy 389.119122 -293.52494) (xy 388.780274 -293.52494) (xy 388.779779 -293.549547) (xy 388.771884 -293.598124)
			(xy 388.7563 -293.644805) (xy 388.733429 -293.688382) (xy 388.703864 -293.727726) (xy 388.668371 -293.761818)
			(xy 388.627868 -293.789774) (xy 388.583406 -293.810872) (xy 388.536135 -293.824564) (xy 388.48728 -293.830496)
			(xy 388.438105 -293.828515) (xy 388.389886 -293.818671) (xy 388.34387 -293.801219) (xy 388.301249 -293.776612)
			(xy 388.263128 -293.745487) (xy 388.230493 -293.70865) (xy 388.20419 -293.667054) (xy 388.184899 -293.621778)
			(xy 388.173122 -293.573994) (xy 388.169162 -293.52494) (xy 387.830314 -293.52494) (xy 387.829819 -293.549547)
			(xy 387.821924 -293.598124) (xy 387.80634 -293.644805) (xy 387.783469 -293.688382) (xy 387.753904 -293.727726)
			(xy 387.718411 -293.761818) (xy 387.677908 -293.789774) (xy 387.633446 -293.810872) (xy 387.586175 -293.824564)
			(xy 387.53732 -293.830496) (xy 387.488145 -293.828515) (xy 387.439926 -293.818671) (xy 387.39391 -293.801219)
			(xy 387.351289 -293.776612) (xy 387.313168 -293.745487) (xy 387.280533 -293.70865) (xy 387.25423 -293.667054)
			(xy 387.234939 -293.621778) (xy 387.223162 -293.573994) (xy 387.219202 -293.52494) (xy 386.880354 -293.52494)
			(xy 386.879859 -293.549547) (xy 386.871964 -293.598124) (xy 386.85638 -293.644805) (xy 386.833509 -293.688382)
			(xy 386.803944 -293.727726) (xy 386.768451 -293.761818) (xy 386.727948 -293.789774) (xy 386.683486 -293.810872)
			(xy 386.636215 -293.824564) (xy 386.58736 -293.830496) (xy 386.538185 -293.828515) (xy 386.489966 -293.818671)
			(xy 386.44395 -293.801219) (xy 386.401329 -293.776612) (xy 386.363208 -293.745487) (xy 386.330573 -293.70865)
			(xy 386.30427 -293.667054) (xy 386.284979 -293.621778) (xy 386.273202 -293.573994) (xy 386.269242 -293.52494)
			(xy 385.93014 -293.52494) (xy 385.929645 -293.549547) (xy 385.92175 -293.598124) (xy 385.906166 -293.644805)
			(xy 385.883295 -293.688382) (xy 385.85373 -293.727726) (xy 385.818237 -293.761818) (xy 385.777734 -293.789774)
			(xy 385.733272 -293.810872) (xy 385.686001 -293.824564) (xy 385.637146 -293.830496) (xy 385.587971 -293.828515)
			(xy 385.539752 -293.818671) (xy 385.493736 -293.801219) (xy 385.451115 -293.776612) (xy 385.412994 -293.745487)
			(xy 385.380359 -293.70865) (xy 385.354056 -293.667054) (xy 385.334765 -293.621778) (xy 385.322988 -293.573994)
			(xy 385.319028 -293.52494) (xy 384.98018 -293.52494) (xy 384.979685 -293.549547) (xy 384.97179 -293.598124)
			(xy 384.956206 -293.644805) (xy 384.933335 -293.688382) (xy 384.90377 -293.727726) (xy 384.868277 -293.761818)
			(xy 384.827774 -293.789774) (xy 384.783312 -293.810872) (xy 384.736041 -293.824564) (xy 384.687186 -293.830496)
			(xy 384.638011 -293.828515) (xy 384.589792 -293.818671) (xy 384.543776 -293.801219) (xy 384.501155 -293.776612)
			(xy 384.463034 -293.745487) (xy 384.430399 -293.70865) (xy 384.404096 -293.667054) (xy 384.384805 -293.621778)
			(xy 384.373028 -293.573994) (xy 384.369068 -293.52494) (xy 384.2512 -293.52494) (xy 384.2512 -294.4749)
			(xy 384.369068 -294.4749) (xy 384.373028 -294.425846) (xy 384.384805 -294.378062) (xy 384.404096 -294.332786)
			(xy 384.430399 -294.29119) (xy 384.463034 -294.254353) (xy 384.501155 -294.223228) (xy 384.543776 -294.198621)
			(xy 384.589792 -294.181169) (xy 384.638011 -294.171325) (xy 384.687186 -294.169344) (xy 384.736041 -294.175276)
			(xy 384.783312 -294.188968) (xy 384.827774 -294.210066) (xy 384.868277 -294.238022) (xy 384.90377 -294.272114)
			(xy 384.933335 -294.311458) (xy 384.956206 -294.355035) (xy 384.97179 -294.401716) (xy 384.979685 -294.450293)
			(xy 384.98018 -294.4749) (xy 385.319028 -294.4749) (xy 385.322988 -294.425846) (xy 385.334765 -294.378062)
			(xy 385.354056 -294.332786) (xy 385.380359 -294.29119) (xy 385.412994 -294.254353) (xy 385.451115 -294.223228)
			(xy 385.493736 -294.198621) (xy 385.539752 -294.181169) (xy 385.587971 -294.171325) (xy 385.637146 -294.169344)
			(xy 385.686001 -294.175276) (xy 385.733272 -294.188968) (xy 385.777734 -294.210066) (xy 385.818237 -294.238022)
			(xy 385.85373 -294.272114) (xy 385.883295 -294.311458) (xy 385.906166 -294.355035) (xy 385.92175 -294.401716)
			(xy 385.929645 -294.450293) (xy 385.93014 -294.4749) (xy 386.269242 -294.4749) (xy 386.273202 -294.425846)
			(xy 386.284979 -294.378062) (xy 386.30427 -294.332786) (xy 386.330573 -294.29119) (xy 386.363208 -294.254353)
			(xy 386.401329 -294.223228) (xy 386.44395 -294.198621) (xy 386.489966 -294.181169) (xy 386.538185 -294.171325)
			(xy 386.58736 -294.169344) (xy 386.636215 -294.175276) (xy 386.683486 -294.188968) (xy 386.727948 -294.210066)
			(xy 386.768451 -294.238022) (xy 386.803944 -294.272114) (xy 386.833509 -294.311458) (xy 386.85638 -294.355035)
			(xy 386.871964 -294.401716) (xy 386.879859 -294.450293) (xy 386.880354 -294.4749) (xy 389.119122 -294.4749)
			(xy 389.123082 -294.425846) (xy 389.134859 -294.378062) (xy 389.15415 -294.332786) (xy 389.180453 -294.29119)
			(xy 389.213088 -294.254353) (xy 389.251209 -294.223228) (xy 389.29383 -294.198621) (xy 389.339846 -294.181169)
			(xy 389.388065 -294.171325) (xy 389.43724 -294.169344) (xy 389.486095 -294.175276) (xy 389.533366 -294.188968)
			(xy 389.577828 -294.210066) (xy 389.618331 -294.238022) (xy 389.653824 -294.272114) (xy 389.683389 -294.311458)
			(xy 389.70626 -294.355035) (xy 389.721844 -294.401716) (xy 389.729739 -294.450293) (xy 389.730234 -294.4749)
			(xy 389.729739 -294.499507) (xy 389.729407 -294.501549) (xy 390.019276 -294.501549) (xy 390.019276 -294.448251)
			(xy 390.027219 -294.395547) (xy 390.042929 -294.344617) (xy 390.066055 -294.296596) (xy 390.096079 -294.252559)
			(xy 390.132331 -294.213488) (xy 390.174002 -294.180257) (xy 390.22016 -294.153608) (xy 390.269774 -294.134136)
			(xy 390.321736 -294.122276) (xy 390.374886 -294.118293) (xy 390.428036 -294.122276) (xy 390.479998 -294.134136)
			(xy 390.529612 -294.153608) (xy 390.57577 -294.180257) (xy 390.617441 -294.213488) (xy 390.653693 -294.252559)
			(xy 390.683717 -294.296596) (xy 390.706843 -294.344617) (xy 390.722553 -294.395547) (xy 390.730496 -294.448251)
			(xy 390.730994 -294.4749) (xy 390.730496 -294.501549) (xy 390.722553 -294.554253) (xy 390.706843 -294.605183)
			(xy 390.683717 -294.653204) (xy 390.653693 -294.697241) (xy 390.617441 -294.736312) (xy 390.57577 -294.769543)
			(xy 390.529612 -294.796192) (xy 390.479998 -294.815664) (xy 390.428036 -294.827524) (xy 390.374886 -294.831508)
			(xy 390.321736 -294.827524) (xy 390.269774 -294.815664) (xy 390.22016 -294.796192) (xy 390.174002 -294.769543)
			(xy 390.132331 -294.736312) (xy 390.096079 -294.697241) (xy 390.066055 -294.653204) (xy 390.042929 -294.605183)
			(xy 390.027219 -294.554253) (xy 390.019276 -294.501549) (xy 389.729407 -294.501549) (xy 389.721844 -294.548084)
			(xy 389.70626 -294.594765) (xy 389.683389 -294.638342) (xy 389.653824 -294.677686) (xy 389.618331 -294.711778)
			(xy 389.577828 -294.739734) (xy 389.533366 -294.760832) (xy 389.486095 -294.774524) (xy 389.43724 -294.780456)
			(xy 389.388065 -294.778475) (xy 389.339846 -294.768631) (xy 389.29383 -294.751179) (xy 389.251209 -294.726572)
			(xy 389.213088 -294.695447) (xy 389.180453 -294.65861) (xy 389.15415 -294.617014) (xy 389.134859 -294.571738)
			(xy 389.123082 -294.523954) (xy 389.119122 -294.4749) (xy 386.880354 -294.4749) (xy 386.879859 -294.499507)
			(xy 386.871964 -294.548084) (xy 386.85638 -294.594765) (xy 386.833509 -294.638342) (xy 386.803944 -294.677686)
			(xy 386.768451 -294.711778) (xy 386.727948 -294.739734) (xy 386.683486 -294.760832) (xy 386.636215 -294.774524)
			(xy 386.58736 -294.780456) (xy 386.538185 -294.778475) (xy 386.489966 -294.768631) (xy 386.44395 -294.751179)
			(xy 386.401329 -294.726572) (xy 386.363208 -294.695447) (xy 386.330573 -294.65861) (xy 386.30427 -294.617014)
			(xy 386.284979 -294.571738) (xy 386.273202 -294.523954) (xy 386.269242 -294.4749) (xy 385.93014 -294.4749)
			(xy 385.929645 -294.499507) (xy 385.92175 -294.548084) (xy 385.906166 -294.594765) (xy 385.883295 -294.638342)
			(xy 385.85373 -294.677686) (xy 385.818237 -294.711778) (xy 385.777734 -294.739734) (xy 385.733272 -294.760832)
			(xy 385.686001 -294.774524) (xy 385.637146 -294.780456) (xy 385.587971 -294.778475) (xy 385.539752 -294.768631)
			(xy 385.493736 -294.751179) (xy 385.451115 -294.726572) (xy 385.412994 -294.695447) (xy 385.380359 -294.65861)
			(xy 385.354056 -294.617014) (xy 385.334765 -294.571738) (xy 385.322988 -294.523954) (xy 385.319028 -294.4749)
			(xy 384.98018 -294.4749) (xy 384.979685 -294.499507) (xy 384.97179 -294.548084) (xy 384.956206 -294.594765)
			(xy 384.933335 -294.638342) (xy 384.90377 -294.677686) (xy 384.868277 -294.711778) (xy 384.827774 -294.739734)
			(xy 384.783312 -294.760832) (xy 384.736041 -294.774524) (xy 384.687186 -294.780456) (xy 384.638011 -294.778475)
			(xy 384.589792 -294.768631) (xy 384.543776 -294.751179) (xy 384.501155 -294.726572) (xy 384.463034 -294.695447)
			(xy 384.430399 -294.65861) (xy 384.404096 -294.617014) (xy 384.384805 -294.571738) (xy 384.373028 -294.523954)
			(xy 384.369068 -294.4749) (xy 384.2512 -294.4749) (xy 384.2512 -296.374566) (xy 384.369068 -296.374566)
			(xy 384.373028 -296.325512) (xy 384.384805 -296.277728) (xy 384.404096 -296.232452) (xy 384.430399 -296.190856)
			(xy 384.463034 -296.154019) (xy 384.501155 -296.122894) (xy 384.543776 -296.098287) (xy 384.589792 -296.080835)
			(xy 384.638011 -296.070991) (xy 384.687186 -296.06901) (xy 384.736041 -296.074942) (xy 384.783312 -296.088634)
			(xy 384.827774 -296.109732) (xy 384.868277 -296.137688) (xy 384.90377 -296.17178) (xy 384.933335 -296.211124)
			(xy 384.956206 -296.254701) (xy 384.97179 -296.301382) (xy 384.979685 -296.349959) (xy 384.98018 -296.374566)
			(xy 384.980175 -296.37482) (xy 385.319282 -296.37482) (xy 385.323242 -296.325766) (xy 385.335019 -296.277982)
			(xy 385.35431 -296.232706) (xy 385.380613 -296.19111) (xy 385.413248 -296.154273) (xy 385.451369 -296.123148)
			(xy 385.49399 -296.098541) (xy 385.540006 -296.081089) (xy 385.588225 -296.071245) (xy 385.6374 -296.069264)
			(xy 385.686255 -296.075196) (xy 385.733526 -296.088888) (xy 385.777988 -296.109986) (xy 385.818491 -296.137942)
			(xy 385.853984 -296.172034) (xy 385.883549 -296.211378) (xy 385.90642 -296.254955) (xy 385.922004 -296.301636)
			(xy 385.929899 -296.350213) (xy 385.930394 -296.37482) (xy 386.268988 -296.37482) (xy 386.272948 -296.325766)
			(xy 386.284725 -296.277982) (xy 386.304016 -296.232706) (xy 386.330319 -296.19111) (xy 386.362954 -296.154273)
			(xy 386.401075 -296.123148) (xy 386.443696 -296.098541) (xy 386.489712 -296.081089) (xy 386.537931 -296.071245)
			(xy 386.587106 -296.069264) (xy 386.635961 -296.075196) (xy 386.683232 -296.088888) (xy 386.727694 -296.109986)
			(xy 386.768197 -296.137942) (xy 386.80369 -296.172034) (xy 386.833255 -296.211378) (xy 386.856126 -296.254955)
			(xy 386.87171 -296.301636) (xy 386.879605 -296.350213) (xy 386.8801 -296.37482) (xy 387.219202 -296.37482)
			(xy 387.223162 -296.325766) (xy 387.234939 -296.277982) (xy 387.25423 -296.232706) (xy 387.280533 -296.19111)
			(xy 387.313168 -296.154273) (xy 387.351289 -296.123148) (xy 387.39391 -296.098541) (xy 387.439926 -296.081089)
			(xy 387.488145 -296.071245) (xy 387.53732 -296.069264) (xy 387.586175 -296.075196) (xy 387.633446 -296.088888)
			(xy 387.677908 -296.109986) (xy 387.718411 -296.137942) (xy 387.753904 -296.172034) (xy 387.783469 -296.211378)
			(xy 387.80634 -296.254955) (xy 387.821924 -296.301636) (xy 387.829819 -296.350213) (xy 387.830314 -296.37482)
			(xy 388.169162 -296.37482) (xy 388.173122 -296.325766) (xy 388.184899 -296.277982) (xy 388.20419 -296.232706)
			(xy 388.230493 -296.19111) (xy 388.263128 -296.154273) (xy 388.301249 -296.123148) (xy 388.34387 -296.098541)
			(xy 388.389886 -296.081089) (xy 388.438105 -296.071245) (xy 388.48728 -296.069264) (xy 388.536135 -296.075196)
			(xy 388.583406 -296.088888) (xy 388.627868 -296.109986) (xy 388.668371 -296.137942) (xy 388.703864 -296.172034)
			(xy 388.733429 -296.211378) (xy 388.7563 -296.254955) (xy 388.771884 -296.301636) (xy 388.779779 -296.350213)
			(xy 388.780274 -296.37482) (xy 390.069082 -296.37482) (xy 390.073042 -296.325766) (xy 390.084819 -296.277982)
			(xy 390.10411 -296.232706) (xy 390.130413 -296.19111) (xy 390.163048 -296.154273) (xy 390.201169 -296.123148)
			(xy 390.24379 -296.098541) (xy 390.289806 -296.081089) (xy 390.338025 -296.071245) (xy 390.3872 -296.069264)
			(xy 390.436055 -296.075196) (xy 390.483326 -296.088888) (xy 390.527788 -296.109986) (xy 390.568291 -296.137942)
			(xy 390.603784 -296.172034) (xy 390.633349 -296.211378) (xy 390.65622 -296.254955) (xy 390.671804 -296.301636)
			(xy 390.679699 -296.350213) (xy 390.680194 -296.37482) (xy 390.679699 -296.399427) (xy 390.671804 -296.448004)
			(xy 390.65622 -296.494685) (xy 390.633349 -296.538262) (xy 390.603784 -296.577606) (xy 390.568291 -296.611698)
			(xy 390.527788 -296.639654) (xy 390.483326 -296.660752) (xy 390.436055 -296.674444) (xy 390.3872 -296.680376)
			(xy 390.338025 -296.678395) (xy 390.289806 -296.668551) (xy 390.24379 -296.651099) (xy 390.201169 -296.626492)
			(xy 390.163048 -296.595367) (xy 390.130413 -296.55853) (xy 390.10411 -296.516934) (xy 390.084819 -296.471658)
			(xy 390.073042 -296.423874) (xy 390.069082 -296.37482) (xy 388.780274 -296.37482) (xy 388.779779 -296.399427)
			(xy 388.771884 -296.448004) (xy 388.7563 -296.494685) (xy 388.733429 -296.538262) (xy 388.703864 -296.577606)
			(xy 388.668371 -296.611698) (xy 388.627868 -296.639654) (xy 388.583406 -296.660752) (xy 388.536135 -296.674444)
			(xy 388.48728 -296.680376) (xy 388.438105 -296.678395) (xy 388.389886 -296.668551) (xy 388.34387 -296.651099)
			(xy 388.301249 -296.626492) (xy 388.263128 -296.595367) (xy 388.230493 -296.55853) (xy 388.20419 -296.516934)
			(xy 388.184899 -296.471658) (xy 388.173122 -296.423874) (xy 388.169162 -296.37482) (xy 387.830314 -296.37482)
			(xy 387.829819 -296.399427) (xy 387.821924 -296.448004) (xy 387.80634 -296.494685) (xy 387.783469 -296.538262)
			(xy 387.753904 -296.577606) (xy 387.718411 -296.611698) (xy 387.677908 -296.639654) (xy 387.633446 -296.660752)
			(xy 387.586175 -296.674444) (xy 387.53732 -296.680376) (xy 387.488145 -296.678395) (xy 387.439926 -296.668551)
			(xy 387.39391 -296.651099) (xy 387.351289 -296.626492) (xy 387.313168 -296.595367) (xy 387.280533 -296.55853)
			(xy 387.25423 -296.516934) (xy 387.234939 -296.471658) (xy 387.223162 -296.423874) (xy 387.219202 -296.37482)
			(xy 386.8801 -296.37482) (xy 386.879605 -296.399427) (xy 386.87171 -296.448004) (xy 386.856126 -296.494685)
			(xy 386.833255 -296.538262) (xy 386.80369 -296.577606) (xy 386.768197 -296.611698) (xy 386.727694 -296.639654)
			(xy 386.683232 -296.660752) (xy 386.635961 -296.674444) (xy 386.587106 -296.680376) (xy 386.537931 -296.678395)
			(xy 386.489712 -296.668551) (xy 386.443696 -296.651099) (xy 386.401075 -296.626492) (xy 386.362954 -296.595367)
			(xy 386.330319 -296.55853) (xy 386.304016 -296.516934) (xy 386.284725 -296.471658) (xy 386.272948 -296.423874)
			(xy 386.268988 -296.37482) (xy 385.930394 -296.37482) (xy 385.929899 -296.399427) (xy 385.922004 -296.448004)
			(xy 385.90642 -296.494685) (xy 385.883549 -296.538262) (xy 385.853984 -296.577606) (xy 385.818491 -296.611698)
			(xy 385.777988 -296.639654) (xy 385.733526 -296.660752) (xy 385.686255 -296.674444) (xy 385.6374 -296.680376)
			(xy 385.588225 -296.678395) (xy 385.540006 -296.668551) (xy 385.49399 -296.651099) (xy 385.451369 -296.626492)
			(xy 385.413248 -296.595367) (xy 385.380613 -296.55853) (xy 385.35431 -296.516934) (xy 385.335019 -296.471658)
			(xy 385.323242 -296.423874) (xy 385.319282 -296.37482) (xy 384.980175 -296.37482) (xy 384.979685 -296.399173)
			(xy 384.97179 -296.44775) (xy 384.956206 -296.494431) (xy 384.933335 -296.538008) (xy 384.90377 -296.577352)
			(xy 384.868277 -296.611444) (xy 384.827774 -296.6394) (xy 384.783312 -296.660498) (xy 384.736041 -296.67419)
			(xy 384.687186 -296.680122) (xy 384.638011 -296.678141) (xy 384.589792 -296.668297) (xy 384.543776 -296.650845)
			(xy 384.501155 -296.626238) (xy 384.463034 -296.595113) (xy 384.430399 -296.558276) (xy 384.404096 -296.51668)
			(xy 384.384805 -296.471404) (xy 384.373028 -296.42362) (xy 384.369068 -296.374566) (xy 384.2512 -296.374566)
			(xy 384.2512 -297.075606) (xy 384.251665 -297.085239) (xy 384.258843 -297.103125) (xy 384.26517 -297.110404)
			(xy 384.270504 -297.116246) (xy 384.274206 -297.120136) (xy 384.282913 -297.126416) (xy 384.287776 -297.128692)
			(xy 384.292348 -297.130724) (xy 384.297547 -297.132861) (xy 384.308571 -297.135038) (xy 384.314192 -297.135042)
			(xy 384.370072 -297.133518) (xy 384.37546 -297.133297) (xy 384.38596 -297.130856) (xy 384.3909 -297.128692)
			(xy 384.418586 -297.11523) (xy 384.42519 -297.107356) (xy 384.444218 -297.086452) (xy 384.488095 -297.050818)
			(xy 384.537383 -297.023148) (xy 384.590652 -297.004244) (xy 384.646356 -296.994654) (xy 384.674618 -296.994072)
			(xy 385.624578 -296.994072) (xy 385.65057 -296.994554) (xy 385.701914 -297.002683) (xy 385.751355 -297.018744)
			(xy 385.797674 -297.042342) (xy 385.839731 -297.072895) (xy 385.87649 -297.109652) (xy 385.907047 -297.151707)
			(xy 385.930648 -297.198025) (xy 385.946712 -297.247464) (xy 385.954845 -297.298808) (xy 385.954845 -297.32478)
			(xy 386.268988 -297.32478) (xy 386.272948 -297.275726) (xy 386.284725 -297.227942) (xy 386.304016 -297.182666)
			(xy 386.330319 -297.14107) (xy 386.362954 -297.104233) (xy 386.401075 -297.073108) (xy 386.443696 -297.048501)
			(xy 386.489712 -297.031049) (xy 386.537931 -297.021205) (xy 386.587106 -297.019224) (xy 386.635961 -297.025156)
			(xy 386.683232 -297.038848) (xy 386.727694 -297.059946) (xy 386.768197 -297.087902) (xy 386.80369 -297.121994)
			(xy 386.833255 -297.161338) (xy 386.856126 -297.204915) (xy 386.87171 -297.251596) (xy 386.879605 -297.300173)
			(xy 386.8801 -297.32478) (xy 387.219202 -297.32478) (xy 387.223162 -297.275726) (xy 387.234939 -297.227942)
			(xy 387.25423 -297.182666) (xy 387.280533 -297.14107) (xy 387.313168 -297.104233) (xy 387.351289 -297.073108)
			(xy 387.39391 -297.048501) (xy 387.439926 -297.031049) (xy 387.488145 -297.021205) (xy 387.53732 -297.019224)
			(xy 387.586175 -297.025156) (xy 387.633446 -297.038848) (xy 387.677908 -297.059946) (xy 387.718411 -297.087902)
			(xy 387.753904 -297.121994) (xy 387.783469 -297.161338) (xy 387.80634 -297.204915) (xy 387.821924 -297.251596)
			(xy 387.829819 -297.300173) (xy 387.830314 -297.32478) (xy 390.069082 -297.32478) (xy 390.073042 -297.275726)
			(xy 390.084819 -297.227942) (xy 390.10411 -297.182666) (xy 390.130413 -297.14107) (xy 390.163048 -297.104233)
			(xy 390.201169 -297.073108) (xy 390.24379 -297.048501) (xy 390.289806 -297.031049) (xy 390.338025 -297.021205)
			(xy 390.3872 -297.019224) (xy 390.436055 -297.025156) (xy 390.483326 -297.038848) (xy 390.527788 -297.059946)
			(xy 390.568291 -297.087902) (xy 390.603784 -297.121994) (xy 390.633349 -297.161338) (xy 390.65622 -297.204915)
			(xy 390.671804 -297.251596) (xy 390.679699 -297.300173) (xy 390.680194 -297.32478) (xy 390.679699 -297.349387)
			(xy 390.671804 -297.397964) (xy 390.65622 -297.444645) (xy 390.633349 -297.488222) (xy 390.603784 -297.527566)
			(xy 390.568291 -297.561658) (xy 390.527788 -297.589614) (xy 390.483326 -297.610712) (xy 390.436055 -297.624404)
			(xy 390.3872 -297.630336) (xy 390.338025 -297.628355) (xy 390.289806 -297.618511) (xy 390.24379 -297.601059)
			(xy 390.201169 -297.576452) (xy 390.163048 -297.545327) (xy 390.130413 -297.50849) (xy 390.10411 -297.466894)
			(xy 390.084819 -297.421618) (xy 390.073042 -297.373834) (xy 390.069082 -297.32478) (xy 387.830314 -297.32478)
			(xy 387.829819 -297.349387) (xy 387.821924 -297.397964) (xy 387.80634 -297.444645) (xy 387.783469 -297.488222)
			(xy 387.753904 -297.527566) (xy 387.718411 -297.561658) (xy 387.677908 -297.589614) (xy 387.633446 -297.610712)
			(xy 387.586175 -297.624404) (xy 387.53732 -297.630336) (xy 387.488145 -297.628355) (xy 387.439926 -297.618511)
			(xy 387.39391 -297.601059) (xy 387.351289 -297.576452) (xy 387.313168 -297.545327) (xy 387.280533 -297.50849)
			(xy 387.25423 -297.466894) (xy 387.234939 -297.421618) (xy 387.223162 -297.373834) (xy 387.219202 -297.32478)
			(xy 386.8801 -297.32478) (xy 386.879605 -297.349387) (xy 386.87171 -297.397964) (xy 386.856126 -297.444645)
			(xy 386.833255 -297.488222) (xy 386.80369 -297.527566) (xy 386.768197 -297.561658) (xy 386.727694 -297.589614)
			(xy 386.683232 -297.610712) (xy 386.635961 -297.624404) (xy 386.587106 -297.630336) (xy 386.537931 -297.628355)
			(xy 386.489712 -297.618511) (xy 386.443696 -297.601059) (xy 386.401075 -297.576452) (xy 386.362954 -297.545327)
			(xy 386.330319 -297.50849) (xy 386.304016 -297.466894) (xy 386.284725 -297.421618) (xy 386.272948 -297.373834)
			(xy 386.268988 -297.32478) (xy 385.954845 -297.32478) (xy 385.954845 -297.350792) (xy 385.946712 -297.402136)
			(xy 385.930648 -297.451575) (xy 385.907047 -297.497893) (xy 385.87649 -297.539948) (xy 385.839731 -297.576705)
			(xy 385.797674 -297.607258) (xy 385.751355 -297.630856) (xy 385.701914 -297.646917) (xy 385.65057 -297.655046)
			(xy 385.624578 -297.655488) (xy 384.66903 -297.655488) (xy 384.668522 -297.655488) (xy 384.653282 -297.655234)
			(xy 384.627628 -297.671998) (xy 384.584702 -297.773344) (xy 384.58117 -297.782771) (xy 384.581022 -297.802888)
			(xy 384.588593 -297.821526) (xy 384.59537 -297.82897) (xy 384.738372 -297.971972) (xy 384.749294 -297.978322)
			(xy 384.755898 -297.9801) (xy 384.781128 -297.987613) (xy 384.828735 -298.01007) (xy 384.871788 -298.040355)
			(xy 384.909011 -298.077573) (xy 384.939304 -298.12062) (xy 384.961769 -298.168224) (xy 384.969258 -298.19346)
			(xy 384.971036 -298.200064) (xy 384.977386 -298.210986) (xy 385.04114 -298.27474) (xy 385.318774 -298.27474)
			(xy 385.322734 -298.225686) (xy 385.334511 -298.177902) (xy 385.353802 -298.132626) (xy 385.380105 -298.09103)
			(xy 385.41274 -298.054193) (xy 385.450861 -298.023068) (xy 385.493482 -297.998461) (xy 385.539498 -297.981009)
			(xy 385.587717 -297.971165) (xy 385.636892 -297.969184) (xy 385.685747 -297.975116) (xy 385.733018 -297.988808)
			(xy 385.77748 -298.009906) (xy 385.817983 -298.037862) (xy 385.853476 -298.071954) (xy 385.883041 -298.111298)
			(xy 385.905912 -298.154875) (xy 385.921496 -298.201556) (xy 385.929391 -298.250133) (xy 385.929886 -298.27474)
			(xy 386.268988 -298.27474) (xy 386.272948 -298.225686) (xy 386.284725 -298.177902) (xy 386.304016 -298.132626)
			(xy 386.330319 -298.09103) (xy 386.362954 -298.054193) (xy 386.401075 -298.023068) (xy 386.443696 -297.998461)
			(xy 386.489712 -297.981009) (xy 386.537931 -297.971165) (xy 386.587106 -297.969184) (xy 386.635961 -297.975116)
			(xy 386.683232 -297.988808) (xy 386.727694 -298.009906) (xy 386.768197 -298.037862) (xy 386.80369 -298.071954)
			(xy 386.833255 -298.111298) (xy 386.856126 -298.154875) (xy 386.87171 -298.201556) (xy 386.879605 -298.250133)
			(xy 386.8801 -298.27474) (xy 386.879934 -298.282973) (xy 387.219275 -298.282973) (xy 387.221964 -298.233401)
			(xy 387.232638 -298.184918) (xy 387.251015 -298.138801) (xy 387.276612 -298.096264) (xy 387.308753 -298.058429)
			(xy 387.346591 -298.026292) (xy 387.389131 -298.0007) (xy 387.435251 -297.982328) (xy 387.483735 -297.97166)
			(xy 387.533307 -297.968976) (xy 387.58266 -297.974347) (xy 387.630493 -297.987633) (xy 387.675547 -298.008482)
			(xy 387.716634 -298.036346) (xy 387.752672 -298.07049) (xy 387.782711 -298.110015) (xy 387.80596 -298.153879)
			(xy 387.821806 -298.200927) (xy 387.829831 -298.249918) (xy 387.830314 -298.27474) (xy 387.830224 -298.283844)
			(xy 387.829078 -298.302018) (xy 387.828028 -298.311062) (xy 387.828028 -298.311316) (xy 387.827371 -298.322986)
			(xy 387.835283 -298.344948) (xy 387.843268 -298.35348) (xy 387.911086 -298.41825) (xy 387.933946 -298.425362)
			(xy 387.94563 -298.42333) (xy 387.959123 -298.42127) (xy 387.986336 -298.41911) (xy 387.999986 -298.419012)
			(xy 388.070344 -298.419012) (xy 388.081068 -298.41859) (xy 388.100673 -298.409908) (xy 388.10819 -298.402248)
			(xy 388.165848 -298.337732) (xy 388.172452 -298.317412) (xy 388.171436 -298.306998) (xy 388.171436 -298.30649)
			(xy 388.169658 -298.27474) (xy 388.17018 -298.249485) (xy 388.178493 -298.199663) (xy 388.194894 -298.151889)
			(xy 388.218935 -298.107466) (xy 388.249959 -298.067606) (xy 388.287121 -298.033396) (xy 388.329407 -298.00577)
			(xy 388.375663 -297.98548) (xy 388.424628 -297.97308) (xy 388.474966 -297.968909) (xy 388.525304 -297.97308)
			(xy 388.574269 -297.98548) (xy 388.620525 -298.00577) (xy 388.662811 -298.033396) (xy 388.699973 -298.067606)
			(xy 388.730997 -298.107466) (xy 388.755038 -298.151889) (xy 388.771439 -298.199663) (xy 388.779752 -298.249485)
			(xy 388.780274 -298.27474) (xy 388.778496 -298.306744) (xy 388.77748 -298.317412) (xy 388.784084 -298.337732)
			(xy 388.841742 -298.402248) (xy 388.849335 -298.409797) (xy 388.868895 -298.418451) (xy 388.879588 -298.419012)
			(xy 388.949946 -298.419012) (xy 388.963596 -298.419096) (xy 388.990809 -298.421261) (xy 389.004302 -298.42333)
			(xy 389.015986 -298.425362) (xy 389.038846 -298.41825) (xy 389.115046 -298.345352) (xy 389.123174 -298.323)
			(xy 389.121904 -298.311316) (xy 389.121904 -298.310808) (xy 389.120862 -298.301827) (xy 389.119721 -298.283781)
			(xy 389.119618 -298.27474) (xy 389.12014 -298.249485) (xy 389.128453 -298.199663) (xy 389.144854 -298.151889)
			(xy 389.168895 -298.107466) (xy 389.199919 -298.067606) (xy 389.237081 -298.033396) (xy 389.279367 -298.00577)
			(xy 389.325623 -297.98548) (xy 389.374588 -297.97308) (xy 389.424926 -297.968909) (xy 389.475264 -297.97308)
			(xy 389.524229 -297.98548) (xy 389.570485 -298.00577) (xy 389.612771 -298.033396) (xy 389.649933 -298.067606)
			(xy 389.680957 -298.107466) (xy 389.704998 -298.151889) (xy 389.721399 -298.199663) (xy 389.729712 -298.249485)
			(xy 389.730234 -298.27474) (xy 389.730062 -298.288923) (xy 389.727387 -298.317163) (xy 389.7249 -298.331128)
			(xy 389.722614 -298.343574) (xy 389.72998 -298.367196) (xy 389.80745 -298.444666) (xy 389.831072 -298.452032)
			(xy 389.843518 -298.449746) (xy 389.857484 -298.447271) (xy 389.885724 -298.444598) (xy 389.899906 -298.444412)
			(xy 389.914089 -298.444587) (xy 389.942329 -298.44726) (xy 389.956294 -298.449746) (xy 389.96874 -298.452032)
			(xy 389.992362 -298.444666) (xy 390.069832 -298.367196) (xy 390.077198 -298.343574) (xy 390.074912 -298.331128)
			(xy 390.07243 -298.317163) (xy 390.069762 -298.288923) (xy 390.069578 -298.27474) (xy 390.070035 -298.249915)
			(xy 390.078061 -298.200918) (xy 390.093909 -298.153865) (xy 390.117161 -298.109996) (xy 390.147203 -298.070467)
			(xy 390.183246 -298.036319) (xy 390.224338 -298.008452) (xy 390.269397 -297.9876) (xy 390.317236 -297.974314)
			(xy 390.366595 -297.968942) (xy 390.416172 -297.971626) (xy 390.464662 -297.982296) (xy 390.510787 -298.000671)
			(xy 390.553331 -298.026266) (xy 390.591174 -298.058407) (xy 390.623319 -298.096247) (xy 390.648917 -298.13879)
			(xy 390.667296 -298.184913) (xy 390.67797 -298.233402) (xy 390.680212 -298.27474) (xy 391.019042 -298.27474)
			(xy 391.023002 -298.225686) (xy 391.034779 -298.177902) (xy 391.05407 -298.132626) (xy 391.080373 -298.09103)
			(xy 391.113008 -298.054193) (xy 391.151129 -298.023068) (xy 391.19375 -297.998461) (xy 391.239766 -297.981009)
			(xy 391.287985 -297.971165) (xy 391.33716 -297.969184) (xy 391.386015 -297.975116) (xy 391.433286 -297.988808)
			(xy 391.477748 -298.009906) (xy 391.518251 -298.037862) (xy 391.553744 -298.071954) (xy 391.583309 -298.111298)
			(xy 391.60618 -298.154875) (xy 391.621764 -298.201556) (xy 391.629659 -298.250133) (xy 391.630154 -298.27474)
			(xy 391.969002 -298.27474) (xy 391.972962 -298.225686) (xy 391.984739 -298.177902) (xy 392.00403 -298.132626)
			(xy 392.030333 -298.09103) (xy 392.062968 -298.054193) (xy 392.101089 -298.023068) (xy 392.14371 -297.998461)
			(xy 392.189726 -297.981009) (xy 392.237945 -297.971165) (xy 392.28712 -297.969184) (xy 392.335975 -297.975116)
			(xy 392.383246 -297.988808) (xy 392.427708 -298.009906) (xy 392.468211 -298.037862) (xy 392.503704 -298.071954)
			(xy 392.533269 -298.111298) (xy 392.55614 -298.154875) (xy 392.571724 -298.201556) (xy 392.579619 -298.250133)
			(xy 392.580114 -298.27474) (xy 392.579619 -298.299347) (xy 392.571724 -298.347924) (xy 392.55614 -298.394605)
			(xy 392.533269 -298.438182) (xy 392.503704 -298.477526) (xy 392.468211 -298.511618) (xy 392.427708 -298.539574)
			(xy 392.383246 -298.560672) (xy 392.335975 -298.574364) (xy 392.28712 -298.580296) (xy 392.237945 -298.578315)
			(xy 392.189726 -298.568471) (xy 392.14371 -298.551019) (xy 392.101089 -298.526412) (xy 392.062968 -298.495287)
			(xy 392.030333 -298.45845) (xy 392.00403 -298.416854) (xy 391.984739 -298.371578) (xy 391.972962 -298.323794)
			(xy 391.969002 -298.27474) (xy 391.630154 -298.27474) (xy 391.629659 -298.299347) (xy 391.621764 -298.347924)
			(xy 391.60618 -298.394605) (xy 391.583309 -298.438182) (xy 391.553744 -298.477526) (xy 391.518251 -298.511618)
			(xy 391.477748 -298.539574) (xy 391.433286 -298.560672) (xy 391.386015 -298.574364) (xy 391.33716 -298.580296)
			(xy 391.287985 -298.578315) (xy 391.239766 -298.568471) (xy 391.19375 -298.551019) (xy 391.151129 -298.526412)
			(xy 391.113008 -298.495287) (xy 391.080373 -298.45845) (xy 391.05407 -298.416854) (xy 391.034779 -298.371578)
			(xy 391.023002 -298.323794) (xy 391.019042 -298.27474) (xy 390.680212 -298.27474) (xy 390.680659 -298.282979)
			(xy 390.675291 -298.332338) (xy 390.662009 -298.380179) (xy 390.641161 -298.42524) (xy 390.613298 -298.466334)
			(xy 390.579153 -298.502379) (xy 390.539626 -298.532425) (xy 390.495759 -298.555681) (xy 390.448707 -298.571533)
			(xy 390.399711 -298.579563) (xy 390.374886 -298.580048) (xy 390.360703 -298.579873) (xy 390.332463 -298.5772)
			(xy 390.318498 -298.574714) (xy 390.306052 -298.572428) (xy 390.28243 -298.579794) (xy 390.20496 -298.657264)
			(xy 390.197594 -298.680886) (xy 390.19988 -298.693332) (xy 390.202357 -298.707298) (xy 390.205028 -298.735537)
			(xy 390.205214 -298.74972) (xy 390.204756 -298.773711) (xy 390.197247 -298.821103) (xy 390.182417 -298.866737)
			(xy 390.160632 -298.909489) (xy 390.132427 -298.948308) (xy 390.098497 -298.982236) (xy 390.059677 -299.010439)
			(xy 390.016924 -299.032223) (xy 389.97129 -299.04705) (xy 389.923897 -299.054557) (xy 389.899906 -299.055028)
			(xy 389.885723 -299.05485) (xy 389.857483 -299.052179) (xy 389.843518 -299.049694) (xy 389.843264 -299.049694)
			(xy 389.831034 -299.04823) (xy 389.807547 -299.055521) (xy 389.798306 -299.063664) (xy 389.72998 -299.132244)
			(xy 389.722614 -299.155866) (xy 389.7249 -299.168312) (xy 389.727384 -299.182341) (xy 389.730056 -299.210708)
			(xy 389.730234 -299.224954) (xy 389.729719 -299.248945) (xy 389.72222 -299.296336) (xy 389.7074 -299.341971)
			(xy 389.685622 -299.384725) (xy 389.657425 -299.423546) (xy 389.623501 -299.457478) (xy 389.584687 -299.485685)
			(xy 389.541937 -299.507472) (xy 389.496306 -299.522304) (xy 389.448916 -299.529814) (xy 389.424926 -299.530262)
			(xy 389.410743 -299.530082) (xy 389.382503 -299.527412) (xy 389.368538 -299.524928) (xy 389.356092 -299.522642)
			(xy 389.33247 -299.530008) (xy 389.255 -299.607478) (xy 389.247634 -299.6311) (xy 389.24992 -299.643546)
			(xy 389.252399 -299.657511) (xy 389.255069 -299.685751) (xy 389.255254 -299.6999) (xy 390.544103 -299.6999)
			(xy 390.548273 -299.649571) (xy 390.56067 -299.600615) (xy 390.580954 -299.554366) (xy 390.608574 -299.512087)
			(xy 390.642776 -299.47493) (xy 390.682627 -299.443909) (xy 390.72704 -299.419869) (xy 390.774803 -299.403467)
			(xy 390.824615 -299.39515) (xy 390.849866 -299.394626) (xy 390.864049 -299.394807) (xy 390.892289 -299.397476)
			(xy 390.906254 -299.39996) (xy 390.906508 -299.39996) (xy 390.918739 -299.401419) (xy 390.942226 -299.394133)
			(xy 390.951466 -299.38599) (xy 391.019792 -299.31741) (xy 391.027158 -299.293788) (xy 391.024872 -299.281342)
			(xy 391.022382 -299.267314) (xy 391.019714 -299.238946) (xy 391.019538 -299.2247) (xy 391.019978 -299.19988)
			(xy 391.028008 -299.150894) (xy 391.043858 -299.103852) (xy 391.067109 -299.059994) (xy 391.097149 -299.020475)
			(xy 391.133187 -298.986337) (xy 391.174273 -298.958478) (xy 391.219324 -298.937633) (xy 391.267154 -298.924351)
			(xy 391.316503 -298.918982) (xy 391.366071 -298.921666) (xy 391.414551 -298.932335) (xy 391.460667 -298.950706)
			(xy 391.503203 -298.976295) (xy 391.541039 -299.008429) (xy 391.573178 -299.04626) (xy 391.598774 -299.088792)
			(xy 391.617152 -299.134905) (xy 391.627827 -299.183384) (xy 391.630086 -299.224954) (xy 391.969002 -299.224954)
			(xy 391.972962 -299.1759) (xy 391.984739 -299.128116) (xy 392.00403 -299.08284) (xy 392.030333 -299.041244)
			(xy 392.062968 -299.004407) (xy 392.101089 -298.973282) (xy 392.14371 -298.948675) (xy 392.189726 -298.931223)
			(xy 392.237945 -298.921379) (xy 392.28712 -298.919398) (xy 392.335975 -298.92533) (xy 392.383246 -298.939022)
			(xy 392.427708 -298.96012) (xy 392.468211 -298.988076) (xy 392.503704 -299.022168) (xy 392.533269 -299.061512)
			(xy 392.55614 -299.105089) (xy 392.571724 -299.15177) (xy 392.579619 -299.200347) (xy 392.580114 -299.224954)
			(xy 392.579619 -299.249561) (xy 392.571724 -299.298138) (xy 392.55614 -299.344819) (xy 392.533269 -299.388396)
			(xy 392.503704 -299.42774) (xy 392.468211 -299.461832) (xy 392.427708 -299.489788) (xy 392.383246 -299.510886)
			(xy 392.335975 -299.524578) (xy 392.28712 -299.53051) (xy 392.237945 -299.528529) (xy 392.189726 -299.518685)
			(xy 392.14371 -299.501233) (xy 392.101089 -299.476626) (xy 392.062968 -299.445501) (xy 392.030333 -299.408664)
			(xy 392.00403 -299.367068) (xy 391.984739 -299.321792) (xy 391.972962 -299.274008) (xy 391.969002 -299.224954)
			(xy 391.630086 -299.224954) (xy 391.63052 -299.232951) (xy 391.625158 -299.2823) (xy 391.611883 -299.330133)
			(xy 391.591045 -299.375187) (xy 391.563192 -299.416277) (xy 391.529059 -299.45232) (xy 391.489545 -299.482366)
			(xy 391.44569 -299.505624) (xy 391.398651 -299.52148) (xy 391.349666 -299.529518) (xy 391.324846 -299.530008)
			(xy 391.310663 -299.529825) (xy 391.282423 -299.527157) (xy 391.268458 -299.524674) (xy 391.268204 -299.524674)
			(xy 391.255972 -299.523241) (xy 391.23249 -299.530512) (xy 391.223246 -299.538644) (xy 391.15492 -299.607224)
			(xy 391.147554 -299.630846) (xy 391.14984 -299.643292) (xy 391.152321 -299.657321) (xy 391.154995 -299.685688)
			(xy 391.155174 -299.699934) (xy 391.155003 -299.714117) (xy 391.152327 -299.742357) (xy 391.14984 -299.756322)
			(xy 391.147554 -299.768768) (xy 391.15492 -299.79239) (xy 391.23239 -299.86986) (xy 391.256012 -299.877226)
			(xy 391.268458 -299.87494) (xy 391.282423 -299.87246) (xy 391.310663 -299.86979) (xy 391.324846 -299.869606)
			(xy 391.348839 -299.87002) (xy 391.396234 -299.877534) (xy 391.44187 -299.892368) (xy 391.484623 -299.914159)
			(xy 391.523442 -299.942369) (xy 391.55737 -299.976304) (xy 391.585573 -300.015128) (xy 391.607355 -300.057886)
			(xy 391.62218 -300.103525) (xy 391.629684 -300.150921) (xy 391.630154 -300.174914) (xy 391.629979 -300.189097)
			(xy 391.627306 -300.217337) (xy 391.62482 -300.231302) (xy 391.622534 -300.243748) (xy 391.6299 -300.26737)
			(xy 391.70737 -300.34484) (xy 391.730992 -300.352206) (xy 391.743438 -300.34992) (xy 391.757404 -300.347442)
			(xy 391.785643 -300.344771) (xy 391.799826 -300.344586) (xy 391.814009 -300.344759) (xy 391.842249 -300.347434)
			(xy 391.856214 -300.34992) (xy 391.86866 -300.352206) (xy 391.892282 -300.34484) (xy 391.969752 -300.26737)
			(xy 391.977118 -300.243748) (xy 391.974832 -300.231302) (xy 391.97236 -300.217335) (xy 391.969685 -300.189096)
			(xy 391.969498 -300.174914) (xy 391.969963 -300.150092) (xy 391.977992 -300.101101) (xy 391.993842 -300.054055)
			(xy 392.017093 -300.010193) (xy 392.047135 -299.97067) (xy 392.083175 -299.936528) (xy 392.124264 -299.908667)
			(xy 392.169319 -299.88782) (xy 392.217153 -299.874537) (xy 392.266507 -299.869167) (xy 392.316078 -299.871853)
			(xy 392.364562 -299.882524) (xy 392.410681 -299.900897) (xy 392.45322 -299.92649) (xy 392.491058 -299.958628)
			(xy 392.523198 -299.996464) (xy 392.548794 -300.039001) (xy 392.56717 -300.085119) (xy 392.577844 -300.133602)
			(xy 392.580533 -300.183173) (xy 392.575167 -300.232527) (xy 392.561887 -300.280362) (xy 392.541043 -300.325418)
			(xy 392.513184 -300.366509) (xy 392.479045 -300.402551) (xy 392.439524 -300.432596) (xy 392.395663 -300.455851)
			(xy 392.348618 -300.471703) (xy 392.299628 -300.479736) (xy 392.274806 -300.480222) (xy 392.260623 -300.480044)
			(xy 392.232383 -300.477373) (xy 392.218418 -300.474888) (xy 392.205972 -300.472602) (xy 392.18235 -300.479968)
			(xy 392.10488 -300.557438) (xy 392.097514 -300.58106) (xy 392.0998 -300.593506) (xy 392.102273 -300.607472)
			(xy 392.104947 -300.635712) (xy 392.105134 -300.649894) (xy 392.104612 -300.675149) (xy 392.096299 -300.724971)
			(xy 392.079898 -300.772745) (xy 392.055857 -300.817168) (xy 392.024833 -300.857028) (xy 391.987671 -300.891238)
			(xy 391.945385 -300.918864) (xy 391.899129 -300.939154) (xy 391.850164 -300.951554) (xy 391.799826 -300.955725)
			(xy 391.749488 -300.951554) (xy 391.700523 -300.939154) (xy 391.654267 -300.918864) (xy 391.611981 -300.891238)
			(xy 391.574819 -300.857028) (xy 391.543795 -300.817168) (xy 391.519754 -300.772745) (xy 391.503353 -300.724971)
			(xy 391.49504 -300.675149) (xy 391.494518 -300.649894) (xy 391.494693 -300.635711) (xy 391.497366 -300.607471)
			(xy 391.499852 -300.593506) (xy 391.502138 -300.58106) (xy 391.494772 -300.557438) (xy 391.417302 -300.479968)
			(xy 391.39368 -300.472602) (xy 391.381234 -300.474888) (xy 391.367269 -300.477369) (xy 391.339029 -300.480038)
			(xy 391.324846 -300.480222) (xy 391.310663 -300.480039) (xy 391.282423 -300.477371) (xy 391.268458 -300.474888)
			(xy 391.256012 -300.472602) (xy 391.23239 -300.479968) (xy 391.15492 -300.557438) (xy 391.147554 -300.58106)
			(xy 391.14984 -300.593506) (xy 391.152313 -300.607472) (xy 391.154987 -300.635712) (xy 391.155174 -300.649894)
			(xy 391.154729 -300.674715) (xy 391.146699 -300.723703) (xy 391.130849 -300.770746) (xy 391.107598 -300.814606)
			(xy 391.077557 -300.854126) (xy 391.041519 -300.888266) (xy 391.000432 -300.916126) (xy 390.955379 -300.936972)
			(xy 390.907548 -300.950255) (xy 390.858197 -300.955624) (xy 390.808628 -300.952939) (xy 390.760146 -300.942271)
			(xy 390.714029 -300.923899) (xy 390.671492 -300.898309) (xy 390.633655 -300.866174) (xy 390.601515 -300.828341)
			(xy 390.575919 -300.785807) (xy 390.557541 -300.739692) (xy 390.546866 -300.691212) (xy 390.544174 -300.641643)
			(xy 390.549538 -300.592292) (xy 390.562814 -300.544458) (xy 390.583654 -300.499403) (xy 390.611509 -300.458312)
			(xy 390.645644 -300.42227) (xy 390.68516 -300.392224) (xy 390.729017 -300.368967) (xy 390.776058 -300.353111)
			(xy 390.825045 -300.345075) (xy 390.849866 -300.344586) (xy 390.864049 -300.344767) (xy 390.892289 -300.347436)
			(xy 390.906254 -300.34992) (xy 390.9187 -300.352206) (xy 390.942322 -300.34484) (xy 391.019792 -300.26737)
			(xy 391.027158 -300.243748) (xy 391.024872 -300.231302) (xy 391.022399 -300.217335) (xy 391.019725 -300.189096)
			(xy 391.019538 -300.174914) (xy 391.019716 -300.160731) (xy 391.022387 -300.132491) (xy 391.024872 -300.118526)
			(xy 391.027158 -300.10608) (xy 391.019792 -300.082458) (xy 390.942322 -300.004988) (xy 390.9187 -299.997622)
			(xy 390.906254 -299.999908) (xy 390.892289 -300.002387) (xy 390.864049 -300.005057) (xy 390.849866 -300.005242)
			(xy 390.824615 -300.00465) (xy 390.774803 -299.996333) (xy 390.72704 -299.979931) (xy 390.682627 -299.955891)
			(xy 390.642776 -299.92487) (xy 390.608574 -299.887713) (xy 390.580954 -299.845434) (xy 390.56067 -299.799185)
			(xy 390.548273 -299.750229) (xy 390.544103 -299.6999) (xy 389.255254 -299.6999) (xy 389.255254 -299.699934)
			(xy 389.254685 -299.724752) (xy 389.24665 -299.773734) (xy 389.230795 -299.820771) (xy 389.20754 -299.864622)
			(xy 389.177497 -299.904134) (xy 389.141457 -299.938265) (xy 389.10037 -299.966116) (xy 389.055318 -299.986952)
			(xy 389.007489 -300.000225) (xy 388.958143 -300.005586) (xy 388.908579 -300.002892) (xy 388.860105 -299.992216)
			(xy 388.813996 -299.973838) (xy 388.771467 -299.948242) (xy 388.733641 -299.916103) (xy 388.701511 -299.878267)
			(xy 388.675927 -299.835733) (xy 388.657561 -299.789619) (xy 388.646897 -299.741141) (xy 388.644216 -299.691577)
			(xy 388.64959 -299.642232) (xy 388.662876 -299.594407) (xy 388.683724 -299.549361) (xy 388.711585 -299.508281)
			(xy 388.745725 -299.47225) (xy 388.785245 -299.442217) (xy 388.829103 -299.418973) (xy 388.876144 -299.403131)
			(xy 388.925128 -299.395108) (xy 388.949946 -299.394626) (xy 388.964129 -299.39481) (xy 388.992369 -299.397477)
			(xy 389.006334 -299.39996) (xy 389.01878 -299.402246) (xy 389.042402 -299.39488) (xy 389.119872 -299.31741)
			(xy 389.127238 -299.293788) (xy 389.124952 -299.281342) (xy 389.122472 -299.267377) (xy 389.119802 -299.239137)
			(xy 389.119618 -299.224954) (xy 389.119704 -299.215786) (xy 389.120849 -299.197486) (xy 389.121904 -299.188378)
			(xy 389.123428 -299.17644) (xy 389.1153 -299.154088) (xy 389.0391 -299.08119) (xy 389.01624 -299.074078)
			(xy 389.004302 -299.07611) (xy 388.990808 -299.078167) (xy 388.963595 -299.080329) (xy 388.949946 -299.080428)
			(xy 387.999986 -299.080428) (xy 387.973989 -299.079966) (xy 387.922636 -299.071833) (xy 387.873186 -299.055772)
			(xy 387.826856 -299.032175) (xy 387.784786 -299.001625) (xy 387.748009 -298.964871) (xy 387.717433 -298.92282)
			(xy 387.693807 -298.876504) (xy 387.677715 -298.827064) (xy 387.669551 -298.775716) (xy 387.669024 -298.74972)
			(xy 387.669178 -298.736066) (xy 387.671467 -298.708852) (xy 387.673596 -298.695364) (xy 387.675628 -298.68368)
			(xy 387.668516 -298.66082) (xy 387.595618 -298.58462) (xy 387.573266 -298.576492) (xy 387.561582 -298.577762)
			(xy 387.561074 -298.577762) (xy 387.552092 -298.578798) (xy 387.534047 -298.579943) (xy 387.525006 -298.580048)
			(xy 387.500184 -298.579529) (xy 387.451193 -298.571498) (xy 387.404148 -298.555647) (xy 387.360286 -298.532393)
			(xy 387.320765 -298.50235) (xy 387.286625 -298.466308) (xy 387.258766 -298.425217) (xy 387.237921 -298.380161)
			(xy 387.224641 -298.332326) (xy 387.219275 -298.282973) (xy 386.879934 -298.282973) (xy 386.879605 -298.299347)
			(xy 386.87171 -298.347924) (xy 386.856126 -298.394605) (xy 386.833255 -298.438182) (xy 386.80369 -298.477526)
			(xy 386.768197 -298.511618) (xy 386.727694 -298.539574) (xy 386.683232 -298.560672) (xy 386.635961 -298.574364)
			(xy 386.587106 -298.580296) (xy 386.537931 -298.578315) (xy 386.489712 -298.568471) (xy 386.443696 -298.551019)
			(xy 386.401075 -298.526412) (xy 386.362954 -298.495287) (xy 386.330319 -298.45845) (xy 386.304016 -298.416854)
			(xy 386.284725 -298.371578) (xy 386.272948 -298.323794) (xy 386.268988 -298.27474) (xy 385.929886 -298.27474)
			(xy 385.929391 -298.299347) (xy 385.921496 -298.347924) (xy 385.905912 -298.394605) (xy 385.883041 -298.438182)
			(xy 385.853476 -298.477526) (xy 385.817983 -298.511618) (xy 385.77748 -298.539574) (xy 385.733018 -298.560672)
			(xy 385.685747 -298.574364) (xy 385.636892 -298.580296) (xy 385.587717 -298.578315) (xy 385.539498 -298.568471)
			(xy 385.493482 -298.551019) (xy 385.450861 -298.526412) (xy 385.41274 -298.495287) (xy 385.380105 -298.45845)
			(xy 385.353802 -298.416854) (xy 385.334511 -298.371578) (xy 385.322734 -298.323794) (xy 385.318774 -298.27474)
			(xy 385.04114 -298.27474) (xy 385.656582 -298.890182) (xy 385.670806 -298.897294) (xy 385.678426 -298.898564)
			(xy 385.703717 -298.903235) (xy 385.752551 -298.919362) (xy 385.798303 -298.94285) (xy 385.839871 -298.973132)
			(xy 385.876254 -299.009479) (xy 385.906577 -299.051017) (xy 385.93011 -299.096745) (xy 385.946286 -299.145563)
			(xy 385.950968 -299.170852) (xy 385.950968 -299.17136) (xy 385.952591 -299.179063) (xy 385.959825 -299.193035)
			(xy 385.965192 -299.198792) (xy 386.809234 -300.042834) (xy 386.809742 -300.043342) (xy 386.817122 -300.049927)
			(xy 386.835421 -300.057383) (xy 386.845302 -300.05782) (xy 386.869432 -300.05782) (xy 386.879192 -300.057378)
			(xy 386.897302 -300.05009) (xy 386.91139 -300.036577) (xy 386.919426 -300.018787) (xy 386.920232 -300.009052)
			(xy 386.920197 -299.999846) (xy 386.914385 -299.982393) (xy 386.902802 -299.968104) (xy 386.895086 -299.963078)
			(xy 386.872601 -299.949156) (xy 386.832366 -299.914843) (xy 386.798631 -299.874122) (xy 386.772402 -299.828205)
			(xy 386.754462 -299.778462) (xy 386.745344 -299.726374) (xy 386.744718 -299.699934) (xy 386.744875 -299.686848)
			(xy 386.747167 -299.660777) (xy 386.74929 -299.647864) (xy 386.750052 -299.643546) (xy 386.750052 -299.643292)
			(xy 386.752338 -299.630846) (xy 386.744972 -299.607224) (xy 386.677408 -299.53966) (xy 386.669982 -299.532885)
			(xy 386.651386 -299.525295) (xy 386.64134 -299.524928) (xy 386.631434 -299.524928) (xy 386.627116 -299.52569)
			(xy 386.614139 -299.527812) (xy 386.587941 -299.530097) (xy 386.574792 -299.530262) (xy 386.549976 -299.529776)
			(xy 386.500997 -299.521745) (xy 386.453963 -299.505897) (xy 386.410113 -299.482648) (xy 386.370601 -299.452612)
			(xy 386.336468 -299.416579) (xy 386.308615 -299.375499) (xy 386.287774 -299.330454) (xy 386.274495 -299.282631)
			(xy 386.269127 -299.23329) (xy 386.271813 -299.18373) (xy 386.28248 -299.135258) (xy 386.300849 -299.08915)
			(xy 386.326435 -299.046621) (xy 386.358564 -299.008791) (xy 386.39639 -298.976657) (xy 386.438916 -298.951066)
			(xy 386.485022 -298.932691) (xy 386.533493 -298.922018) (xy 386.583052 -298.919326) (xy 386.632394 -298.924688)
			(xy 386.680219 -298.937961) (xy 386.725266 -298.958796) (xy 386.766349 -298.986645) (xy 386.802386 -299.020772)
			(xy 386.832428 -299.060281) (xy 386.855682 -299.104128) (xy 386.871536 -299.15116) (xy 386.879573 -299.200138)
			(xy 386.8801 -299.224954) (xy 386.879943 -299.23804) (xy 386.877653 -299.264111) (xy 386.875528 -299.277024)
			(xy 386.874766 -299.281342) (xy 386.874766 -299.281596) (xy 386.87248 -299.294042) (xy 386.879846 -299.317664)
			(xy 386.94741 -299.385228) (xy 386.954837 -299.392001) (xy 386.973433 -299.399587) (xy 386.983478 -299.39996)
			(xy 386.993384 -299.39996) (xy 386.997702 -299.399198) (xy 387.010679 -299.397073) (xy 387.036877 -299.394781)
			(xy 387.050026 -299.394626) (xy 387.074017 -299.395074) (xy 387.121407 -299.402584) (xy 387.167039 -299.417416)
			(xy 387.209789 -299.439203) (xy 387.248605 -299.46741) (xy 387.282529 -299.501341) (xy 387.310729 -299.540162)
			(xy 387.332507 -299.582916) (xy 387.34733 -299.628551) (xy 387.354831 -299.675943) (xy 387.355334 -299.699934)
			(xy 387.694182 -299.699934) (xy 387.698142 -299.65088) (xy 387.709919 -299.603096) (xy 387.72921 -299.55782)
			(xy 387.755513 -299.516224) (xy 387.788148 -299.479387) (xy 387.826269 -299.448262) (xy 387.86889 -299.423655)
			(xy 387.914906 -299.406203) (xy 387.963125 -299.396359) (xy 388.0123 -299.394378) (xy 388.061155 -299.40031)
			(xy 388.108426 -299.414002) (xy 388.152888 -299.4351) (xy 388.193391 -299.463056) (xy 388.228884 -299.497148)
			(xy 388.258449 -299.536492) (xy 388.28132 -299.580069) (xy 388.296904 -299.62675) (xy 388.304799 -299.675327)
			(xy 388.305294 -299.699934) (xy 388.304799 -299.724541) (xy 388.296904 -299.773118) (xy 388.28132 -299.819799)
			(xy 388.258449 -299.863376) (xy 388.228884 -299.90272) (xy 388.193391 -299.936812) (xy 388.152888 -299.964768)
			(xy 388.108426 -299.985866) (xy 388.061155 -299.999558) (xy 388.0123 -300.00549) (xy 387.963125 -300.003509)
			(xy 387.914906 -299.993665) (xy 387.86889 -299.976213) (xy 387.826269 -299.951606) (xy 387.788148 -299.920481)
			(xy 387.755513 -299.883644) (xy 387.72921 -299.842048) (xy 387.709919 -299.796772) (xy 387.698142 -299.748988)
			(xy 387.694182 -299.699934) (xy 387.355334 -299.699934) (xy 387.354808 -299.725947) (xy 387.345995 -299.77722)
			(xy 387.32863 -299.826262) (xy 387.303213 -299.871657) (xy 387.287262 -299.892212) (xy 387.287008 -299.892466)
			(xy 387.281306 -299.900159) (xy 387.275566 -299.918412) (xy 387.276916 -299.937499) (xy 387.280658 -299.946314)
			(xy 387.320282 -300.028864) (xy 387.324772 -300.037289) (xy 387.338733 -300.050293) (xy 387.356465 -300.057332)
			(xy 387.366002 -300.05782) (xy 387.381496 -300.05782) (xy 387.423882 -300.058294) (xy 387.50833 -300.065702)
			(xy 387.591812 -300.080436) (xy 387.673694 -300.102383) (xy 387.753353 -300.131378) (xy 387.830185 -300.1672)
			(xy 387.903606 -300.209576) (xy 387.973058 -300.258185) (xy 388.038012 -300.312657) (xy 388.068312 -300.3423)
			(xy 388.071106 -300.345094) (xy 388.095229 -300.351214) (xy 388.141293 -300.370046) (xy 388.183796 -300.395931)
			(xy 388.221669 -300.428214) (xy 388.253955 -300.466084) (xy 388.279843 -300.508586) (xy 388.298678 -300.554648)
			(xy 388.304786 -300.578774) (xy 388.312152 -300.58614) (xy 388.341068 -300.615679) (xy 388.394354 -300.678883)
			(xy 388.418578 -300.712378) (xy 388.422134 -300.717458) (xy 388.440676 -300.73346) (xy 388.445756 -300.736254)
			(xy 388.48665 -300.758606) (xy 388.492238 -300.761908) (xy 388.506716 -300.765718) (xy 388.516807 -300.767925)
			(xy 388.537241 -300.765024) (xy 388.54634 -300.76013) (xy 388.620762 -300.714918) (xy 388.628436 -300.709789)
			(xy 388.639799 -300.695262) (xy 388.645317 -300.677663) (xy 388.645146 -300.668436) (xy 388.645146 -300.666912)
			(xy 388.644638 -300.649894) (xy 388.645124 -300.625078) (xy 388.653154 -300.576099) (xy 388.669003 -300.529065)
			(xy 388.692251 -300.485214) (xy 388.722287 -300.445702) (xy 388.75832 -300.41157) (xy 388.799399 -300.383716)
			(xy 388.844444 -300.362875) (xy 388.892267 -300.349595) (xy 388.941608 -300.344227) (xy 388.991168 -300.346913)
			(xy 389.039641 -300.35758) (xy 389.085749 -300.375948) (xy 389.128279 -300.401534) (xy 389.166108 -300.433663)
			(xy 389.198242 -300.471489) (xy 389.223834 -300.514015) (xy 389.242208 -300.560121) (xy 389.252882 -300.608592)
			(xy 389.255125 -300.649894) (xy 389.594102 -300.649894) (xy 389.598062 -300.60084) (xy 389.609839 -300.553056)
			(xy 389.62913 -300.50778) (xy 389.655433 -300.466184) (xy 389.688068 -300.429347) (xy 389.726189 -300.398222)
			(xy 389.76881 -300.373615) (xy 389.814826 -300.356163) (xy 389.863045 -300.346319) (xy 389.91222 -300.344338)
			(xy 389.961075 -300.35027) (xy 390.008346 -300.363962) (xy 390.052808 -300.38506) (xy 390.093311 -300.413016)
			(xy 390.128804 -300.447108) (xy 390.158369 -300.486452) (xy 390.18124 -300.530029) (xy 390.196824 -300.57671)
			(xy 390.204719 -300.625287) (xy 390.205214 -300.649894) (xy 390.204719 -300.674501) (xy 390.196824 -300.723078)
			(xy 390.18124 -300.769759) (xy 390.158369 -300.813336) (xy 390.128804 -300.85268) (xy 390.093311 -300.886772)
			(xy 390.052808 -300.914728) (xy 390.008346 -300.935826) (xy 389.961075 -300.949518) (xy 389.91222 -300.95545)
			(xy 389.863045 -300.953469) (xy 389.814826 -300.943625) (xy 389.76881 -300.926173) (xy 389.726189 -300.901566)
			(xy 389.688068 -300.870441) (xy 389.655433 -300.833604) (xy 389.62913 -300.792008) (xy 389.609839 -300.746732)
			(xy 389.598062 -300.698948) (xy 389.594102 -300.649894) (xy 389.255125 -300.649894) (xy 389.255574 -300.658151)
			(xy 389.250212 -300.707493) (xy 389.236939 -300.755318) (xy 389.216104 -300.800366) (xy 389.188256 -300.841449)
			(xy 389.154128 -300.877486) (xy 389.11462 -300.907528) (xy 389.070772 -300.930782) (xy 389.02374 -300.946636)
			(xy 388.974762 -300.954673) (xy 388.949946 -300.955202) (xy 388.934198 -300.954694) (xy 388.928356 -300.954694)
			(xy 388.919698 -300.955079) (xy 388.903394 -300.960921) (xy 388.889963 -300.971855) (xy 388.885176 -300.979078)
			(xy 388.83971 -301.0535) (xy 388.834748 -301.062575) (xy 388.831856 -301.083033) (xy 388.834122 -301.093124)
			(xy 388.837932 -301.107602) (xy 388.841234 -301.11319) (xy 388.861416 -301.148933) (xy 388.896389 -301.2232)
			(xy 388.911084 -301.261526) (xy 388.914979 -301.270881) (xy 388.928757 -301.285719) (xy 388.947204 -301.294066)
			(xy 388.957312 -301.2948) (xy 388.980892 -301.29582) (xy 389.027333 -301.304226) (xy 389.071928 -301.319676)
			(xy 389.113615 -301.341803) (xy 389.151402 -301.370079) (xy 389.184389 -301.403833) (xy 389.211791 -301.442259)
			(xy 389.232955 -301.484443) (xy 389.247377 -301.529381) (xy 389.254714 -301.576003) (xy 389.255254 -301.5996)
			(xy 389.255254 -301.599854) (xy 389.594102 -301.599854) (xy 389.598062 -301.5508) (xy 389.609839 -301.503016)
			(xy 389.62913 -301.45774) (xy 389.655433 -301.416144) (xy 389.688068 -301.379307) (xy 389.726189 -301.348182)
			(xy 389.76881 -301.323575) (xy 389.814826 -301.306123) (xy 389.863045 -301.296279) (xy 389.91222 -301.294298)
			(xy 389.961075 -301.30023) (xy 390.008346 -301.313922) (xy 390.052808 -301.33502) (xy 390.093311 -301.362976)
			(xy 390.128804 -301.397068) (xy 390.158369 -301.436412) (xy 390.18124 -301.479989) (xy 390.196824 -301.52667)
			(xy 390.204719 -301.575247) (xy 390.205214 -301.599854) (xy 390.544062 -301.599854) (xy 390.548022 -301.5508)
			(xy 390.559799 -301.503016) (xy 390.57909 -301.45774) (xy 390.605393 -301.416144) (xy 390.638028 -301.379307)
			(xy 390.676149 -301.348182) (xy 390.71877 -301.323575) (xy 390.764786 -301.306123) (xy 390.813005 -301.296279)
			(xy 390.86218 -301.294298) (xy 390.911035 -301.30023) (xy 390.958306 -301.313922) (xy 391.002768 -301.33502)
			(xy 391.043271 -301.362976) (xy 391.078764 -301.397068) (xy 391.108329 -301.436412) (xy 391.1312 -301.479989)
			(xy 391.146784 -301.52667) (xy 391.154679 -301.575247) (xy 391.155174 -301.599854) (xy 391.494022 -301.599854)
			(xy 391.497982 -301.5508) (xy 391.509759 -301.503016) (xy 391.52905 -301.45774) (xy 391.555353 -301.416144)
			(xy 391.587988 -301.379307) (xy 391.626109 -301.348182) (xy 391.66873 -301.323575) (xy 391.714746 -301.306123)
			(xy 391.762965 -301.296279) (xy 391.81214 -301.294298) (xy 391.860995 -301.30023) (xy 391.908266 -301.313922)
			(xy 391.952728 -301.33502) (xy 391.993231 -301.362976) (xy 392.028724 -301.397068) (xy 392.058289 -301.436412)
			(xy 392.08116 -301.479989) (xy 392.096744 -301.52667) (xy 392.104639 -301.575247) (xy 392.105134 -301.599854)
			(xy 392.104639 -301.624461) (xy 392.096744 -301.673038) (xy 392.08116 -301.719719) (xy 392.058289 -301.763296)
			(xy 392.028724 -301.80264) (xy 391.993231 -301.836732) (xy 391.952728 -301.864688) (xy 391.908266 -301.885786)
			(xy 391.860995 -301.899478) (xy 391.81214 -301.90541) (xy 391.762965 -301.903429) (xy 391.714746 -301.893585)
			(xy 391.66873 -301.876133) (xy 391.626109 -301.851526) (xy 391.587988 -301.820401) (xy 391.555353 -301.783564)
			(xy 391.52905 -301.741968) (xy 391.509759 -301.696692) (xy 391.497982 -301.648908) (xy 391.494022 -301.599854)
			(xy 391.155174 -301.599854) (xy 391.154679 -301.624461) (xy 391.146784 -301.673038) (xy 391.1312 -301.719719)
			(xy 391.108329 -301.763296) (xy 391.078764 -301.80264) (xy 391.043271 -301.836732) (xy 391.002768 -301.864688)
			(xy 390.958306 -301.885786) (xy 390.911035 -301.899478) (xy 390.86218 -301.90541) (xy 390.813005 -301.903429)
			(xy 390.764786 -301.893585) (xy 390.71877 -301.876133) (xy 390.676149 -301.851526) (xy 390.638028 -301.820401)
			(xy 390.605393 -301.783564) (xy 390.57909 -301.741968) (xy 390.559799 -301.696692) (xy 390.548022 -301.648908)
			(xy 390.544062 -301.599854) (xy 390.205214 -301.599854) (xy 390.204719 -301.624461) (xy 390.196824 -301.673038)
			(xy 390.18124 -301.719719) (xy 390.158369 -301.763296) (xy 390.128804 -301.80264) (xy 390.093311 -301.836732)
			(xy 390.052808 -301.864688) (xy 390.008346 -301.885786) (xy 389.961075 -301.899478) (xy 389.91222 -301.90541)
			(xy 389.863045 -301.903429) (xy 389.814826 -301.893585) (xy 389.76881 -301.876133) (xy 389.726189 -301.851526)
			(xy 389.688068 -301.820401) (xy 389.655433 -301.783564) (xy 389.62913 -301.741968) (xy 389.609839 -301.696692)
			(xy 389.598062 -301.648908) (xy 389.594102 -301.599854) (xy 389.255254 -301.599854) (xy 389.255254 -301.600108)
			(xy 389.255 -301.608236) (xy 389.255 -302.541432) (xy 389.255254 -302.549052) (xy 389.255254 -302.549814)
			(xy 389.594102 -302.549814) (xy 389.598062 -302.50076) (xy 389.609839 -302.452976) (xy 389.62913 -302.4077)
			(xy 389.655433 -302.366104) (xy 389.688068 -302.329267) (xy 389.726189 -302.298142) (xy 389.76881 -302.273535)
			(xy 389.814826 -302.256083) (xy 389.863045 -302.246239) (xy 389.91222 -302.244258) (xy 389.961075 -302.25019)
			(xy 390.008346 -302.263882) (xy 390.052808 -302.28498) (xy 390.093311 -302.312936) (xy 390.128804 -302.347028)
			(xy 390.158369 -302.386372) (xy 390.18124 -302.429949) (xy 390.196824 -302.47663) (xy 390.204719 -302.525207)
			(xy 390.205214 -302.549814) (xy 390.544062 -302.549814) (xy 390.548022 -302.50076) (xy 390.559799 -302.452976)
			(xy 390.57909 -302.4077) (xy 390.605393 -302.366104) (xy 390.638028 -302.329267) (xy 390.676149 -302.298142)
			(xy 390.71877 -302.273535) (xy 390.764786 -302.256083) (xy 390.813005 -302.246239) (xy 390.86218 -302.244258)
			(xy 390.911035 -302.25019) (xy 390.958306 -302.263882) (xy 391.002768 -302.28498) (xy 391.043271 -302.312936)
			(xy 391.078764 -302.347028) (xy 391.108329 -302.386372) (xy 391.1312 -302.429949) (xy 391.146784 -302.47663)
			(xy 391.154679 -302.525207) (xy 391.155174 -302.549814) (xy 391.494022 -302.549814) (xy 391.497982 -302.50076)
			(xy 391.509759 -302.452976) (xy 391.52905 -302.4077) (xy 391.555353 -302.366104) (xy 391.587988 -302.329267)
			(xy 391.626109 -302.298142) (xy 391.66873 -302.273535) (xy 391.714746 -302.256083) (xy 391.762965 -302.246239)
			(xy 391.81214 -302.244258) (xy 391.860995 -302.25019) (xy 391.908266 -302.263882) (xy 391.952728 -302.28498)
			(xy 391.993231 -302.312936) (xy 392.028724 -302.347028) (xy 392.058289 -302.386372) (xy 392.08116 -302.429949)
			(xy 392.096744 -302.47663) (xy 392.104639 -302.525207) (xy 392.105134 -302.549814) (xy 392.443982 -302.549814)
			(xy 392.447942 -302.50076) (xy 392.459719 -302.452976) (xy 392.47901 -302.4077) (xy 392.505313 -302.366104)
			(xy 392.537948 -302.329267) (xy 392.576069 -302.298142) (xy 392.61869 -302.273535) (xy 392.664706 -302.256083)
			(xy 392.712925 -302.246239) (xy 392.7621 -302.244258) (xy 392.810955 -302.25019) (xy 392.858226 -302.263882)
			(xy 392.902688 -302.28498) (xy 392.943191 -302.312936) (xy 392.978684 -302.347028) (xy 393.008249 -302.386372)
			(xy 393.03112 -302.429949) (xy 393.046704 -302.47663) (xy 393.054599 -302.525207) (xy 393.055094 -302.549814)
			(xy 393.054599 -302.574421) (xy 393.046704 -302.622998) (xy 393.03112 -302.669679) (xy 393.008249 -302.713256)
			(xy 392.978684 -302.7526) (xy 392.943191 -302.786692) (xy 392.902688 -302.814648) (xy 392.858226 -302.835746)
			(xy 392.810955 -302.849438) (xy 392.7621 -302.85537) (xy 392.712925 -302.853389) (xy 392.664706 -302.843545)
			(xy 392.61869 -302.826093) (xy 392.576069 -302.801486) (xy 392.537948 -302.770361) (xy 392.505313 -302.733524)
			(xy 392.47901 -302.691928) (xy 392.459719 -302.646652) (xy 392.447942 -302.598868) (xy 392.443982 -302.549814)
			(xy 392.105134 -302.549814) (xy 392.104639 -302.574421) (xy 392.096744 -302.622998) (xy 392.08116 -302.669679)
			(xy 392.058289 -302.713256) (xy 392.028724 -302.7526) (xy 391.993231 -302.786692) (xy 391.952728 -302.814648)
			(xy 391.908266 -302.835746) (xy 391.860995 -302.849438) (xy 391.81214 -302.85537) (xy 391.762965 -302.853389)
			(xy 391.714746 -302.843545) (xy 391.66873 -302.826093) (xy 391.626109 -302.801486) (xy 391.587988 -302.770361)
			(xy 391.555353 -302.733524) (xy 391.52905 -302.691928) (xy 391.509759 -302.646652) (xy 391.497982 -302.598868)
			(xy 391.494022 -302.549814) (xy 391.155174 -302.549814) (xy 391.154679 -302.574421) (xy 391.146784 -302.622998)
			(xy 391.1312 -302.669679) (xy 391.108329 -302.713256) (xy 391.078764 -302.7526) (xy 391.043271 -302.786692)
			(xy 391.002768 -302.814648) (xy 390.958306 -302.835746) (xy 390.911035 -302.849438) (xy 390.86218 -302.85537)
			(xy 390.813005 -302.853389) (xy 390.764786 -302.843545) (xy 390.71877 -302.826093) (xy 390.676149 -302.801486)
			(xy 390.638028 -302.770361) (xy 390.605393 -302.733524) (xy 390.57909 -302.691928) (xy 390.559799 -302.646652)
			(xy 390.548022 -302.598868) (xy 390.544062 -302.549814) (xy 390.205214 -302.549814) (xy 390.204719 -302.574421)
			(xy 390.196824 -302.622998) (xy 390.18124 -302.669679) (xy 390.158369 -302.713256) (xy 390.128804 -302.7526)
			(xy 390.093311 -302.786692) (xy 390.052808 -302.814648) (xy 390.008346 -302.835746) (xy 389.961075 -302.849438)
			(xy 389.91222 -302.85537) (xy 389.863045 -302.853389) (xy 389.814826 -302.843545) (xy 389.76881 -302.826093)
			(xy 389.726189 -302.801486) (xy 389.688068 -302.770361) (xy 389.655433 -302.733524) (xy 389.62913 -302.691928)
			(xy 389.609839 -302.646652) (xy 389.598062 -302.598868) (xy 389.594102 -302.549814) (xy 389.255254 -302.549814)
			(xy 389.255254 -302.550576) (xy 389.255 -302.558196) (xy 389.255 -303.491392) (xy 389.255254 -303.499012)
			(xy 389.255254 -303.499774) (xy 389.594102 -303.499774) (xy 389.598062 -303.45072) (xy 389.609839 -303.402936)
			(xy 389.62913 -303.35766) (xy 389.655433 -303.316064) (xy 389.688068 -303.279227) (xy 389.726189 -303.248102)
			(xy 389.76881 -303.223495) (xy 389.814826 -303.206043) (xy 389.863045 -303.196199) (xy 389.91222 -303.194218)
			(xy 389.961075 -303.20015) (xy 390.008346 -303.213842) (xy 390.052808 -303.23494) (xy 390.093311 -303.262896)
			(xy 390.128804 -303.296988) (xy 390.158369 -303.336332) (xy 390.18124 -303.379909) (xy 390.196824 -303.42659)
			(xy 390.204719 -303.475167) (xy 390.205214 -303.499774) (xy 390.544062 -303.499774) (xy 390.548022 -303.45072)
			(xy 390.559799 -303.402936) (xy 390.57909 -303.35766) (xy 390.605393 -303.316064) (xy 390.638028 -303.279227)
			(xy 390.676149 -303.248102) (xy 390.71877 -303.223495) (xy 390.764786 -303.206043) (xy 390.813005 -303.196199)
			(xy 390.86218 -303.194218) (xy 390.911035 -303.20015) (xy 390.958306 -303.213842) (xy 391.002768 -303.23494)
			(xy 391.043271 -303.262896) (xy 391.078764 -303.296988) (xy 391.108329 -303.336332) (xy 391.1312 -303.379909)
			(xy 391.146784 -303.42659) (xy 391.154679 -303.475167) (xy 391.155174 -303.499774) (xy 391.494022 -303.499774)
			(xy 391.497982 -303.45072) (xy 391.509759 -303.402936) (xy 391.52905 -303.35766) (xy 391.555353 -303.316064)
			(xy 391.587988 -303.279227) (xy 391.626109 -303.248102) (xy 391.66873 -303.223495) (xy 391.714746 -303.206043)
			(xy 391.762965 -303.196199) (xy 391.81214 -303.194218) (xy 391.860995 -303.20015) (xy 391.908266 -303.213842)
			(xy 391.952728 -303.23494) (xy 391.993231 -303.262896) (xy 392.028724 -303.296988) (xy 392.058289 -303.336332)
			(xy 392.08116 -303.379909) (xy 392.096744 -303.42659) (xy 392.104639 -303.475167) (xy 392.105134 -303.499774)
			(xy 392.443982 -303.499774) (xy 392.447942 -303.45072) (xy 392.459719 -303.402936) (xy 392.47901 -303.35766)
			(xy 392.505313 -303.316064) (xy 392.537948 -303.279227) (xy 392.576069 -303.248102) (xy 392.61869 -303.223495)
			(xy 392.664706 -303.206043) (xy 392.712925 -303.196199) (xy 392.7621 -303.194218) (xy 392.810955 -303.20015)
			(xy 392.858226 -303.213842) (xy 392.902688 -303.23494) (xy 392.943191 -303.262896) (xy 392.978684 -303.296988)
			(xy 393.008249 -303.336332) (xy 393.03112 -303.379909) (xy 393.046704 -303.42659) (xy 393.054599 -303.475167)
			(xy 393.055094 -303.499774) (xy 393.054599 -303.524381) (xy 393.046704 -303.572958) (xy 393.03112 -303.619639)
			(xy 393.008249 -303.663216) (xy 392.978684 -303.70256) (xy 392.943191 -303.736652) (xy 392.902688 -303.764608)
			(xy 392.858226 -303.785706) (xy 392.810955 -303.799398) (xy 392.7621 -303.80533) (xy 392.712925 -303.803349)
			(xy 392.664706 -303.793505) (xy 392.61869 -303.776053) (xy 392.576069 -303.751446) (xy 392.537948 -303.720321)
			(xy 392.505313 -303.683484) (xy 392.47901 -303.641888) (xy 392.459719 -303.596612) (xy 392.447942 -303.548828)
			(xy 392.443982 -303.499774) (xy 392.105134 -303.499774) (xy 392.104639 -303.524381) (xy 392.096744 -303.572958)
			(xy 392.08116 -303.619639) (xy 392.058289 -303.663216) (xy 392.028724 -303.70256) (xy 391.993231 -303.736652)
			(xy 391.952728 -303.764608) (xy 391.908266 -303.785706) (xy 391.860995 -303.799398) (xy 391.81214 -303.80533)
			(xy 391.762965 -303.803349) (xy 391.714746 -303.793505) (xy 391.66873 -303.776053) (xy 391.626109 -303.751446)
			(xy 391.587988 -303.720321) (xy 391.555353 -303.683484) (xy 391.52905 -303.641888) (xy 391.509759 -303.596612)
			(xy 391.497982 -303.548828) (xy 391.494022 -303.499774) (xy 391.155174 -303.499774) (xy 391.154679 -303.524381)
			(xy 391.146784 -303.572958) (xy 391.1312 -303.619639) (xy 391.108329 -303.663216) (xy 391.078764 -303.70256)
			(xy 391.043271 -303.736652) (xy 391.002768 -303.764608) (xy 390.958306 -303.785706) (xy 390.911035 -303.799398)
			(xy 390.86218 -303.80533) (xy 390.813005 -303.803349) (xy 390.764786 -303.793505) (xy 390.71877 -303.776053)
			(xy 390.676149 -303.751446) (xy 390.638028 -303.720321) (xy 390.605393 -303.683484) (xy 390.57909 -303.641888)
			(xy 390.559799 -303.596612) (xy 390.548022 -303.548828) (xy 390.544062 -303.499774) (xy 390.205214 -303.499774)
			(xy 390.204719 -303.524381) (xy 390.196824 -303.572958) (xy 390.18124 -303.619639) (xy 390.158369 -303.663216)
			(xy 390.128804 -303.70256) (xy 390.093311 -303.736652) (xy 390.052808 -303.764608) (xy 390.008346 -303.785706)
			(xy 389.961075 -303.799398) (xy 389.91222 -303.80533) (xy 389.863045 -303.803349) (xy 389.814826 -303.793505)
			(xy 389.76881 -303.776053) (xy 389.726189 -303.751446) (xy 389.688068 -303.720321) (xy 389.655433 -303.683484)
			(xy 389.62913 -303.641888) (xy 389.609839 -303.596612) (xy 389.598062 -303.548828) (xy 389.594102 -303.499774)
			(xy 389.255254 -303.499774) (xy 389.255254 -303.500536) (xy 389.255 -303.508156) (xy 389.255 -303.974754)
			(xy 394.819136 -303.974754) (xy 394.823096 -303.9257) (xy 394.834873 -303.877916) (xy 394.854164 -303.83264)
			(xy 394.880467 -303.791044) (xy 394.913102 -303.754207) (xy 394.951223 -303.723082) (xy 394.993844 -303.698475)
			(xy 395.03986 -303.681023) (xy 395.088079 -303.671179) (xy 395.137254 -303.669198) (xy 395.186109 -303.67513)
			(xy 395.23338 -303.688822) (xy 395.277842 -303.70992) (xy 395.318345 -303.737876) (xy 395.353838 -303.771968)
			(xy 395.383403 -303.811312) (xy 395.406274 -303.854889) (xy 395.421858 -303.90157) (xy 395.429753 -303.950147)
			(xy 395.430248 -303.974754) (xy 395.769096 -303.974754) (xy 395.773056 -303.9257) (xy 395.784833 -303.877916)
			(xy 395.804124 -303.83264) (xy 395.830427 -303.791044) (xy 395.863062 -303.754207) (xy 395.901183 -303.723082)
			(xy 395.943804 -303.698475) (xy 395.98982 -303.681023) (xy 396.038039 -303.671179) (xy 396.087214 -303.669198)
			(xy 396.136069 -303.67513) (xy 396.18334 -303.688822) (xy 396.227802 -303.70992) (xy 396.268305 -303.737876)
			(xy 396.303798 -303.771968) (xy 396.333363 -303.811312) (xy 396.356234 -303.854889) (xy 396.371818 -303.90157)
			(xy 396.379713 -303.950147) (xy 396.380208 -303.974754) (xy 396.719056 -303.974754) (xy 396.723016 -303.9257)
			(xy 396.734793 -303.877916) (xy 396.754084 -303.83264) (xy 396.780387 -303.791044) (xy 396.813022 -303.754207)
			(xy 396.851143 -303.723082) (xy 396.893764 -303.698475) (xy 396.93978 -303.681023) (xy 396.987999 -303.671179)
			(xy 397.037174 -303.669198) (xy 397.086029 -303.67513) (xy 397.1333 -303.688822) (xy 397.177762 -303.70992)
			(xy 397.218265 -303.737876) (xy 397.253758 -303.771968) (xy 397.283323 -303.811312) (xy 397.306194 -303.854889)
			(xy 397.321778 -303.90157) (xy 397.329673 -303.950147) (xy 397.330168 -303.974754) (xy 397.329673 -303.999361)
			(xy 397.321778 -304.047938) (xy 397.306194 -304.094619) (xy 397.283323 -304.138196) (xy 397.253758 -304.17754)
			(xy 397.218265 -304.211632) (xy 397.177762 -304.239588) (xy 397.1333 -304.260686) (xy 397.086029 -304.274378)
			(xy 397.037174 -304.28031) (xy 396.987999 -304.278329) (xy 396.93978 -304.268485) (xy 396.893764 -304.251033)
			(xy 396.851143 -304.226426) (xy 396.813022 -304.195301) (xy 396.780387 -304.158464) (xy 396.754084 -304.116868)
			(xy 396.734793 -304.071592) (xy 396.723016 -304.023808) (xy 396.719056 -303.974754) (xy 396.380208 -303.974754)
			(xy 396.379713 -303.999361) (xy 396.371818 -304.047938) (xy 396.356234 -304.094619) (xy 396.333363 -304.138196)
			(xy 396.303798 -304.17754) (xy 396.268305 -304.211632) (xy 396.227802 -304.239588) (xy 396.18334 -304.260686)
			(xy 396.136069 -304.274378) (xy 396.087214 -304.28031) (xy 396.038039 -304.278329) (xy 395.98982 -304.268485)
			(xy 395.943804 -304.251033) (xy 395.901183 -304.226426) (xy 395.863062 -304.195301) (xy 395.830427 -304.158464)
			(xy 395.804124 -304.116868) (xy 395.784833 -304.071592) (xy 395.773056 -304.023808) (xy 395.769096 -303.974754)
			(xy 395.430248 -303.974754) (xy 395.429753 -303.999361) (xy 395.421858 -304.047938) (xy 395.406274 -304.094619)
			(xy 395.383403 -304.138196) (xy 395.353838 -304.17754) (xy 395.318345 -304.211632) (xy 395.277842 -304.239588)
			(xy 395.23338 -304.260686) (xy 395.186109 -304.274378) (xy 395.137254 -304.28031) (xy 395.088079 -304.278329)
			(xy 395.03986 -304.268485) (xy 394.993844 -304.251033) (xy 394.951223 -304.226426) (xy 394.913102 -304.195301)
			(xy 394.880467 -304.158464) (xy 394.854164 -304.116868) (xy 394.834873 -304.071592) (xy 394.823096 -304.023808)
			(xy 394.819136 -303.974754) (xy 389.255 -303.974754) (xy 389.255 -304.441352) (xy 389.255254 -304.448972)
			(xy 389.255254 -304.449734) (xy 389.594102 -304.449734) (xy 389.598062 -304.40068) (xy 389.609839 -304.352896)
			(xy 389.62913 -304.30762) (xy 389.655433 -304.266024) (xy 389.688068 -304.229187) (xy 389.726189 -304.198062)
			(xy 389.76881 -304.173455) (xy 389.814826 -304.156003) (xy 389.863045 -304.146159) (xy 389.91222 -304.144178)
			(xy 389.961075 -304.15011) (xy 390.008346 -304.163802) (xy 390.052808 -304.1849) (xy 390.093311 -304.212856)
			(xy 390.128804 -304.246948) (xy 390.158369 -304.286292) (xy 390.18124 -304.329869) (xy 390.196824 -304.37655)
			(xy 390.204719 -304.425127) (xy 390.205214 -304.449734) (xy 390.544062 -304.449734) (xy 390.548022 -304.40068)
			(xy 390.559799 -304.352896) (xy 390.57909 -304.30762) (xy 390.605393 -304.266024) (xy 390.638028 -304.229187)
			(xy 390.676149 -304.198062) (xy 390.71877 -304.173455) (xy 390.764786 -304.156003) (xy 390.813005 -304.146159)
			(xy 390.86218 -304.144178) (xy 390.911035 -304.15011) (xy 390.958306 -304.163802) (xy 391.002768 -304.1849)
			(xy 391.043271 -304.212856) (xy 391.078764 -304.246948) (xy 391.108329 -304.286292) (xy 391.1312 -304.329869)
			(xy 391.146784 -304.37655) (xy 391.154679 -304.425127) (xy 391.155174 -304.449734) (xy 391.494022 -304.449734)
			(xy 391.497982 -304.40068) (xy 391.509759 -304.352896) (xy 391.52905 -304.30762) (xy 391.555353 -304.266024)
			(xy 391.587988 -304.229187) (xy 391.626109 -304.198062) (xy 391.66873 -304.173455) (xy 391.714746 -304.156003)
			(xy 391.762965 -304.146159) (xy 391.81214 -304.144178) (xy 391.860995 -304.15011) (xy 391.908266 -304.163802)
			(xy 391.952728 -304.1849) (xy 391.993231 -304.212856) (xy 392.028724 -304.246948) (xy 392.058289 -304.286292)
			(xy 392.08116 -304.329869) (xy 392.096744 -304.37655) (xy 392.104639 -304.425127) (xy 392.105134 -304.449734)
			(xy 392.443982 -304.449734) (xy 392.447942 -304.40068) (xy 392.459719 -304.352896) (xy 392.47901 -304.30762)
			(xy 392.505313 -304.266024) (xy 392.537948 -304.229187) (xy 392.576069 -304.198062) (xy 392.61869 -304.173455)
			(xy 392.664706 -304.156003) (xy 392.712925 -304.146159) (xy 392.7621 -304.144178) (xy 392.810955 -304.15011)
			(xy 392.858226 -304.163802) (xy 392.902688 -304.1849) (xy 392.943191 -304.212856) (xy 392.978684 -304.246948)
			(xy 393.008249 -304.286292) (xy 393.03112 -304.329869) (xy 393.046704 -304.37655) (xy 393.054599 -304.425127)
			(xy 393.055094 -304.449734) (xy 393.394196 -304.449734) (xy 393.398156 -304.40068) (xy 393.409933 -304.352896)
			(xy 393.429224 -304.30762) (xy 393.455527 -304.266024) (xy 393.488162 -304.229187) (xy 393.526283 -304.198062)
			(xy 393.568904 -304.173455) (xy 393.61492 -304.156003) (xy 393.663139 -304.146159) (xy 393.712314 -304.144178)
			(xy 393.761169 -304.15011) (xy 393.80844 -304.163802) (xy 393.852902 -304.1849) (xy 393.893405 -304.212856)
			(xy 393.928898 -304.246948) (xy 393.958463 -304.286292) (xy 393.981334 -304.329869) (xy 393.996918 -304.37655)
			(xy 394.004813 -304.425127) (xy 394.005308 -304.449734) (xy 394.004813 -304.474341) (xy 393.996918 -304.522918)
			(xy 393.981334 -304.569599) (xy 393.958463 -304.613176) (xy 393.928898 -304.65252) (xy 393.893405 -304.686612)
			(xy 393.852902 -304.714568) (xy 393.80844 -304.735666) (xy 393.761169 -304.749358) (xy 393.712314 -304.75529)
			(xy 393.663139 -304.753309) (xy 393.61492 -304.743465) (xy 393.568904 -304.726013) (xy 393.526283 -304.701406)
			(xy 393.488162 -304.670281) (xy 393.455527 -304.633444) (xy 393.429224 -304.591848) (xy 393.409933 -304.546572)
			(xy 393.398156 -304.498788) (xy 393.394196 -304.449734) (xy 393.055094 -304.449734) (xy 393.054599 -304.474341)
			(xy 393.046704 -304.522918) (xy 393.03112 -304.569599) (xy 393.008249 -304.613176) (xy 392.978684 -304.65252)
			(xy 392.943191 -304.686612) (xy 392.902688 -304.714568) (xy 392.858226 -304.735666) (xy 392.810955 -304.749358)
			(xy 392.7621 -304.75529) (xy 392.712925 -304.753309) (xy 392.664706 -304.743465) (xy 392.61869 -304.726013)
			(xy 392.576069 -304.701406) (xy 392.537948 -304.670281) (xy 392.505313 -304.633444) (xy 392.47901 -304.591848)
			(xy 392.459719 -304.546572) (xy 392.447942 -304.498788) (xy 392.443982 -304.449734) (xy 392.105134 -304.449734)
			(xy 392.104639 -304.474341) (xy 392.096744 -304.522918) (xy 392.08116 -304.569599) (xy 392.058289 -304.613176)
			(xy 392.028724 -304.65252) (xy 391.993231 -304.686612) (xy 391.952728 -304.714568) (xy 391.908266 -304.735666)
			(xy 391.860995 -304.749358) (xy 391.81214 -304.75529) (xy 391.762965 -304.753309) (xy 391.714746 -304.743465)
			(xy 391.66873 -304.726013) (xy 391.626109 -304.701406) (xy 391.587988 -304.670281) (xy 391.555353 -304.633444)
			(xy 391.52905 -304.591848) (xy 391.509759 -304.546572) (xy 391.497982 -304.498788) (xy 391.494022 -304.449734)
			(xy 391.155174 -304.449734) (xy 391.154679 -304.474341) (xy 391.146784 -304.522918) (xy 391.1312 -304.569599)
			(xy 391.108329 -304.613176) (xy 391.078764 -304.65252) (xy 391.043271 -304.686612) (xy 391.002768 -304.714568)
			(xy 390.958306 -304.735666) (xy 390.911035 -304.749358) (xy 390.86218 -304.75529) (xy 390.813005 -304.753309)
			(xy 390.764786 -304.743465) (xy 390.71877 -304.726013) (xy 390.676149 -304.701406) (xy 390.638028 -304.670281)
			(xy 390.605393 -304.633444) (xy 390.57909 -304.591848) (xy 390.559799 -304.546572) (xy 390.548022 -304.498788)
			(xy 390.544062 -304.449734) (xy 390.205214 -304.449734) (xy 390.204719 -304.474341) (xy 390.196824 -304.522918)
			(xy 390.18124 -304.569599) (xy 390.158369 -304.613176) (xy 390.128804 -304.65252) (xy 390.093311 -304.686612)
			(xy 390.052808 -304.714568) (xy 390.008346 -304.735666) (xy 389.961075 -304.749358) (xy 389.91222 -304.75529)
			(xy 389.863045 -304.753309) (xy 389.814826 -304.743465) (xy 389.76881 -304.726013) (xy 389.726189 -304.701406)
			(xy 389.688068 -304.670281) (xy 389.655433 -304.633444) (xy 389.62913 -304.591848) (xy 389.609839 -304.546572)
			(xy 389.598062 -304.498788) (xy 389.594102 -304.449734) (xy 389.255254 -304.449734) (xy 389.255254 -304.450496)
			(xy 389.255 -304.458116) (xy 389.255 -304.924714) (xy 394.819136 -304.924714) (xy 394.823096 -304.87566)
			(xy 394.834873 -304.827876) (xy 394.854164 -304.7826) (xy 394.880467 -304.741004) (xy 394.913102 -304.704167)
			(xy 394.951223 -304.673042) (xy 394.993844 -304.648435) (xy 395.03986 -304.630983) (xy 395.088079 -304.621139)
			(xy 395.137254 -304.619158) (xy 395.186109 -304.62509) (xy 395.23338 -304.638782) (xy 395.277842 -304.65988)
			(xy 395.318345 -304.687836) (xy 395.353838 -304.721928) (xy 395.383403 -304.761272) (xy 395.406274 -304.804849)
			(xy 395.421858 -304.85153) (xy 395.429753 -304.900107) (xy 395.430248 -304.924714) (xy 395.769096 -304.924714)
			(xy 395.773056 -304.87566) (xy 395.784833 -304.827876) (xy 395.804124 -304.7826) (xy 395.830427 -304.741004)
			(xy 395.863062 -304.704167) (xy 395.901183 -304.673042) (xy 395.943804 -304.648435) (xy 395.98982 -304.630983)
			(xy 396.038039 -304.621139) (xy 396.087214 -304.619158) (xy 396.136069 -304.62509) (xy 396.18334 -304.638782)
			(xy 396.227802 -304.65988) (xy 396.268305 -304.687836) (xy 396.303798 -304.721928) (xy 396.333363 -304.761272)
			(xy 396.356234 -304.804849) (xy 396.371818 -304.85153) (xy 396.379713 -304.900107) (xy 396.380208 -304.924714)
			(xy 396.719056 -304.924714) (xy 396.723016 -304.87566) (xy 396.734793 -304.827876) (xy 396.754084 -304.7826)
			(xy 396.780387 -304.741004) (xy 396.813022 -304.704167) (xy 396.851143 -304.673042) (xy 396.893764 -304.648435)
			(xy 396.93978 -304.630983) (xy 396.987999 -304.621139) (xy 397.037174 -304.619158) (xy 397.086029 -304.62509)
			(xy 397.1333 -304.638782) (xy 397.177762 -304.65988) (xy 397.218265 -304.687836) (xy 397.253758 -304.721928)
			(xy 397.283323 -304.761272) (xy 397.306194 -304.804849) (xy 397.321778 -304.85153) (xy 397.329673 -304.900107)
			(xy 397.330168 -304.924714) (xy 397.669016 -304.924714) (xy 397.672976 -304.87566) (xy 397.684753 -304.827876)
			(xy 397.704044 -304.7826) (xy 397.730347 -304.741004) (xy 397.762982 -304.704167) (xy 397.801103 -304.673042)
			(xy 397.843724 -304.648435) (xy 397.88974 -304.630983) (xy 397.937959 -304.621139) (xy 397.987134 -304.619158)
			(xy 398.035989 -304.62509) (xy 398.08326 -304.638782) (xy 398.127722 -304.65988) (xy 398.168225 -304.687836)
			(xy 398.203718 -304.721928) (xy 398.233283 -304.761272) (xy 398.256154 -304.804849) (xy 398.271738 -304.85153)
			(xy 398.279633 -304.900107) (xy 398.280128 -304.924714) (xy 398.61923 -304.924714) (xy 398.62319 -304.87566)
			(xy 398.634967 -304.827876) (xy 398.654258 -304.7826) (xy 398.680561 -304.741004) (xy 398.713196 -304.704167)
			(xy 398.751317 -304.673042) (xy 398.793938 -304.648435) (xy 398.839954 -304.630983) (xy 398.888173 -304.621139)
			(xy 398.937348 -304.619158) (xy 398.986203 -304.62509) (xy 399.033474 -304.638782) (xy 399.077936 -304.65988)
			(xy 399.118439 -304.687836) (xy 399.153932 -304.721928) (xy 399.183497 -304.761272) (xy 399.206368 -304.804849)
			(xy 399.221952 -304.85153) (xy 399.229847 -304.900107) (xy 399.230342 -304.924714) (xy 399.56919 -304.924714)
			(xy 399.57315 -304.87566) (xy 399.584927 -304.827876) (xy 399.604218 -304.7826) (xy 399.630521 -304.741004)
			(xy 399.663156 -304.704167) (xy 399.701277 -304.673042) (xy 399.743898 -304.648435) (xy 399.789914 -304.630983)
			(xy 399.838133 -304.621139) (xy 399.887308 -304.619158) (xy 399.936163 -304.62509) (xy 399.983434 -304.638782)
			(xy 400.027896 -304.65988) (xy 400.068399 -304.687836) (xy 400.103892 -304.721928) (xy 400.133457 -304.761272)
			(xy 400.156328 -304.804849) (xy 400.171912 -304.85153) (xy 400.179807 -304.900107) (xy 400.180302 -304.924714)
			(xy 400.51915 -304.924714) (xy 400.52311 -304.87566) (xy 400.534887 -304.827876) (xy 400.554178 -304.7826)
			(xy 400.580481 -304.741004) (xy 400.613116 -304.704167) (xy 400.651237 -304.673042) (xy 400.693858 -304.648435)
			(xy 400.739874 -304.630983) (xy 400.788093 -304.621139) (xy 400.837268 -304.619158) (xy 400.886123 -304.62509)
			(xy 400.933394 -304.638782) (xy 400.977856 -304.65988) (xy 401.018359 -304.687836) (xy 401.053852 -304.721928)
			(xy 401.083417 -304.761272) (xy 401.106288 -304.804849) (xy 401.121872 -304.85153) (xy 401.129767 -304.900107)
			(xy 401.130262 -304.924714) (xy 401.46911 -304.924714) (xy 401.47307 -304.87566) (xy 401.484847 -304.827876)
			(xy 401.504138 -304.7826) (xy 401.530441 -304.741004) (xy 401.563076 -304.704167) (xy 401.601197 -304.673042)
			(xy 401.643818 -304.648435) (xy 401.689834 -304.630983) (xy 401.738053 -304.621139) (xy 401.787228 -304.619158)
			(xy 401.836083 -304.62509) (xy 401.883354 -304.638782) (xy 401.927816 -304.65988) (xy 401.968319 -304.687836)
			(xy 402.003812 -304.721928) (xy 402.033377 -304.761272) (xy 402.056248 -304.804849) (xy 402.071832 -304.85153)
			(xy 402.079727 -304.900107) (xy 402.080222 -304.924714) (xy 402.41907 -304.924714) (xy 402.42303 -304.87566)
			(xy 402.434807 -304.827876) (xy 402.454098 -304.7826) (xy 402.480401 -304.741004) (xy 402.513036 -304.704167)
			(xy 402.551157 -304.673042) (xy 402.593778 -304.648435) (xy 402.639794 -304.630983) (xy 402.688013 -304.621139)
			(xy 402.737188 -304.619158) (xy 402.786043 -304.62509) (xy 402.833314 -304.638782) (xy 402.877776 -304.65988)
			(xy 402.918279 -304.687836) (xy 402.953772 -304.721928) (xy 402.983337 -304.761272) (xy 403.006208 -304.804849)
			(xy 403.021792 -304.85153) (xy 403.029687 -304.900107) (xy 403.030182 -304.924714) (xy 403.36903 -304.924714)
			(xy 403.37299 -304.87566) (xy 403.384767 -304.827876) (xy 403.404058 -304.7826) (xy 403.430361 -304.741004)
			(xy 403.462996 -304.704167) (xy 403.501117 -304.673042) (xy 403.543738 -304.648435) (xy 403.589754 -304.630983)
			(xy 403.637973 -304.621139) (xy 403.687148 -304.619158) (xy 403.736003 -304.62509) (xy 403.783274 -304.638782)
			(xy 403.827736 -304.65988) (xy 403.868239 -304.687836) (xy 403.903732 -304.721928) (xy 403.933297 -304.761272)
			(xy 403.956168 -304.804849) (xy 403.971752 -304.85153) (xy 403.979647 -304.900107) (xy 403.980142 -304.924714)
			(xy 404.31899 -304.924714) (xy 404.32295 -304.87566) (xy 404.334727 -304.827876) (xy 404.354018 -304.7826)
			(xy 404.380321 -304.741004) (xy 404.412956 -304.704167) (xy 404.451077 -304.673042) (xy 404.493698 -304.648435)
			(xy 404.539714 -304.630983) (xy 404.587933 -304.621139) (xy 404.637108 -304.619158) (xy 404.685963 -304.62509)
			(xy 404.733234 -304.638782) (xy 404.777696 -304.65988) (xy 404.818199 -304.687836) (xy 404.853692 -304.721928)
			(xy 404.883257 -304.761272) (xy 404.906128 -304.804849) (xy 404.921712 -304.85153) (xy 404.929607 -304.900107)
			(xy 404.930102 -304.924714) (xy 405.269204 -304.924714) (xy 405.273164 -304.87566) (xy 405.284941 -304.827876)
			(xy 405.304232 -304.7826) (xy 405.330535 -304.741004) (xy 405.36317 -304.704167) (xy 405.401291 -304.673042)
			(xy 405.443912 -304.648435) (xy 405.489928 -304.630983) (xy 405.538147 -304.621139) (xy 405.587322 -304.619158)
			(xy 405.636177 -304.62509) (xy 405.683448 -304.638782) (xy 405.72791 -304.65988) (xy 405.768413 -304.687836)
			(xy 405.803906 -304.721928) (xy 405.833471 -304.761272) (xy 405.856342 -304.804849) (xy 405.871926 -304.85153)
			(xy 405.879821 -304.900107) (xy 405.880316 -304.924714) (xy 406.219164 -304.924714) (xy 406.223124 -304.87566)
			(xy 406.234901 -304.827876) (xy 406.254192 -304.7826) (xy 406.280495 -304.741004) (xy 406.31313 -304.704167)
			(xy 406.351251 -304.673042) (xy 406.393872 -304.648435) (xy 406.439888 -304.630983) (xy 406.488107 -304.621139)
			(xy 406.537282 -304.619158) (xy 406.586137 -304.62509) (xy 406.633408 -304.638782) (xy 406.67787 -304.65988)
			(xy 406.718373 -304.687836) (xy 406.753866 -304.721928) (xy 406.783431 -304.761272) (xy 406.806302 -304.804849)
			(xy 406.821886 -304.85153) (xy 406.829781 -304.900107) (xy 406.830276 -304.924714) (xy 408.119084 -304.924714)
			(xy 408.123044 -304.87566) (xy 408.134821 -304.827876) (xy 408.154112 -304.7826) (xy 408.180415 -304.741004)
			(xy 408.21305 -304.704167) (xy 408.251171 -304.673042) (xy 408.293792 -304.648435) (xy 408.339808 -304.630983)
			(xy 408.388027 -304.621139) (xy 408.437202 -304.619158) (xy 408.486057 -304.62509) (xy 408.533328 -304.638782)
			(xy 408.57779 -304.65988) (xy 408.618293 -304.687836) (xy 408.653786 -304.721928) (xy 408.683351 -304.761272)
			(xy 408.706222 -304.804849) (xy 408.721806 -304.85153) (xy 408.729701 -304.900107) (xy 408.730196 -304.924714)
			(xy 409.069044 -304.924714) (xy 409.073004 -304.87566) (xy 409.084781 -304.827876) (xy 409.104072 -304.7826)
			(xy 409.130375 -304.741004) (xy 409.16301 -304.704167) (xy 409.201131 -304.673042) (xy 409.243752 -304.648435)
			(xy 409.289768 -304.630983) (xy 409.337987 -304.621139) (xy 409.387162 -304.619158) (xy 409.436017 -304.62509)
			(xy 409.483288 -304.638782) (xy 409.52775 -304.65988) (xy 409.568253 -304.687836) (xy 409.603746 -304.721928)
			(xy 409.633311 -304.761272) (xy 409.656182 -304.804849) (xy 409.671766 -304.85153) (xy 409.679661 -304.900107)
			(xy 409.680156 -304.924714) (xy 410.019004 -304.924714) (xy 410.022964 -304.87566) (xy 410.034741 -304.827876)
			(xy 410.054032 -304.7826) (xy 410.080335 -304.741004) (xy 410.11297 -304.704167) (xy 410.151091 -304.673042)
			(xy 410.193712 -304.648435) (xy 410.239728 -304.630983) (xy 410.287947 -304.621139) (xy 410.337122 -304.619158)
			(xy 410.385977 -304.62509) (xy 410.433248 -304.638782) (xy 410.47771 -304.65988) (xy 410.518213 -304.687836)
			(xy 410.553706 -304.721928) (xy 410.583271 -304.761272) (xy 410.606142 -304.804849) (xy 410.621726 -304.85153)
			(xy 410.629621 -304.900107) (xy 410.630116 -304.924714) (xy 410.969218 -304.924714) (xy 410.973178 -304.87566)
			(xy 410.984955 -304.827876) (xy 411.004246 -304.7826) (xy 411.030549 -304.741004) (xy 411.063184 -304.704167)
			(xy 411.101305 -304.673042) (xy 411.143926 -304.648435) (xy 411.189942 -304.630983) (xy 411.238161 -304.621139)
			(xy 411.287336 -304.619158) (xy 411.336191 -304.62509) (xy 411.383462 -304.638782) (xy 411.427924 -304.65988)
			(xy 411.468427 -304.687836) (xy 411.50392 -304.721928) (xy 411.533485 -304.761272) (xy 411.556356 -304.804849)
			(xy 411.57194 -304.85153) (xy 411.579835 -304.900107) (xy 411.58033 -304.924714) (xy 411.919178 -304.924714)
			(xy 411.923138 -304.87566) (xy 411.934915 -304.827876) (xy 411.954206 -304.7826) (xy 411.980509 -304.741004)
			(xy 412.013144 -304.704167) (xy 412.051265 -304.673042) (xy 412.093886 -304.648435) (xy 412.139902 -304.630983)
			(xy 412.188121 -304.621139) (xy 412.237296 -304.619158) (xy 412.286151 -304.62509) (xy 412.333422 -304.638782)
			(xy 412.377884 -304.65988) (xy 412.418387 -304.687836) (xy 412.45388 -304.721928) (xy 412.483445 -304.761272)
			(xy 412.506316 -304.804849) (xy 412.5219 -304.85153) (xy 412.529795 -304.900107) (xy 412.53029 -304.924714)
			(xy 412.869138 -304.924714) (xy 412.873098 -304.87566) (xy 412.884875 -304.827876) (xy 412.904166 -304.7826)
			(xy 412.930469 -304.741004) (xy 412.963104 -304.704167) (xy 413.001225 -304.673042) (xy 413.043846 -304.648435)
			(xy 413.089862 -304.630983) (xy 413.138081 -304.621139) (xy 413.187256 -304.619158) (xy 413.236111 -304.62509)
			(xy 413.283382 -304.638782) (xy 413.327844 -304.65988) (xy 413.368347 -304.687836) (xy 413.40384 -304.721928)
			(xy 413.433405 -304.761272) (xy 413.456276 -304.804849) (xy 413.47186 -304.85153) (xy 413.479755 -304.900107)
			(xy 413.48025 -304.924714) (xy 413.819098 -304.924714) (xy 413.823058 -304.87566) (xy 413.834835 -304.827876)
			(xy 413.854126 -304.7826) (xy 413.880429 -304.741004) (xy 413.913064 -304.704167) (xy 413.951185 -304.673042)
			(xy 413.993806 -304.648435) (xy 414.039822 -304.630983) (xy 414.088041 -304.621139) (xy 414.137216 -304.619158)
			(xy 414.186071 -304.62509) (xy 414.233342 -304.638782) (xy 414.277804 -304.65988) (xy 414.318307 -304.687836)
			(xy 414.3538 -304.721928) (xy 414.383365 -304.761272) (xy 414.406236 -304.804849) (xy 414.42182 -304.85153)
			(xy 414.429715 -304.900107) (xy 414.43021 -304.924714) (xy 414.769058 -304.924714) (xy 414.773018 -304.87566)
			(xy 414.784795 -304.827876) (xy 414.804086 -304.7826) (xy 414.830389 -304.741004) (xy 414.863024 -304.704167)
			(xy 414.901145 -304.673042) (xy 414.943766 -304.648435) (xy 414.989782 -304.630983) (xy 415.038001 -304.621139)
			(xy 415.087176 -304.619158) (xy 415.136031 -304.62509) (xy 415.183302 -304.638782) (xy 415.227764 -304.65988)
			(xy 415.268267 -304.687836) (xy 415.30376 -304.721928) (xy 415.333325 -304.761272) (xy 415.356196 -304.804849)
			(xy 415.37178 -304.85153) (xy 415.379675 -304.900107) (xy 415.38017 -304.924714) (xy 415.719018 -304.924714)
			(xy 415.722978 -304.87566) (xy 415.734755 -304.827876) (xy 415.754046 -304.7826) (xy 415.780349 -304.741004)
			(xy 415.812984 -304.704167) (xy 415.851105 -304.673042) (xy 415.893726 -304.648435) (xy 415.939742 -304.630983)
			(xy 415.987961 -304.621139) (xy 416.037136 -304.619158) (xy 416.085991 -304.62509) (xy 416.133262 -304.638782)
			(xy 416.177724 -304.65988) (xy 416.218227 -304.687836) (xy 416.25372 -304.721928) (xy 416.283285 -304.761272)
			(xy 416.306156 -304.804849) (xy 416.32174 -304.85153) (xy 416.329635 -304.900107) (xy 416.33013 -304.924714)
			(xy 416.668978 -304.924714) (xy 416.672938 -304.87566) (xy 416.684715 -304.827876) (xy 416.704006 -304.7826)
			(xy 416.730309 -304.741004) (xy 416.762944 -304.704167) (xy 416.801065 -304.673042) (xy 416.843686 -304.648435)
			(xy 416.889702 -304.630983) (xy 416.937921 -304.621139) (xy 416.987096 -304.619158) (xy 417.035951 -304.62509)
			(xy 417.083222 -304.638782) (xy 417.127684 -304.65988) (xy 417.168187 -304.687836) (xy 417.20368 -304.721928)
			(xy 417.233245 -304.761272) (xy 417.256116 -304.804849) (xy 417.2717 -304.85153) (xy 417.279595 -304.900107)
			(xy 417.28009 -304.924714) (xy 418.569152 -304.924714) (xy 418.573112 -304.87566) (xy 418.584889 -304.827876)
			(xy 418.60418 -304.7826) (xy 418.630483 -304.741004) (xy 418.663118 -304.704167) (xy 418.701239 -304.673042)
			(xy 418.74386 -304.648435) (xy 418.789876 -304.630983) (xy 418.838095 -304.621139) (xy 418.88727 -304.619158)
			(xy 418.936125 -304.62509) (xy 418.983396 -304.638782) (xy 419.027858 -304.65988) (xy 419.068361 -304.687836)
			(xy 419.103854 -304.721928) (xy 419.133419 -304.761272) (xy 419.15629 -304.804849) (xy 419.171874 -304.85153)
			(xy 419.179769 -304.900107) (xy 419.180264 -304.924714) (xy 419.519112 -304.924714) (xy 419.523072 -304.87566)
			(xy 419.534849 -304.827876) (xy 419.55414 -304.7826) (xy 419.580443 -304.741004) (xy 419.613078 -304.704167)
			(xy 419.651199 -304.673042) (xy 419.69382 -304.648435) (xy 419.739836 -304.630983) (xy 419.788055 -304.621139)
			(xy 419.83723 -304.619158) (xy 419.886085 -304.62509) (xy 419.933356 -304.638782) (xy 419.977818 -304.65988)
			(xy 420.018321 -304.687836) (xy 420.053814 -304.721928) (xy 420.083379 -304.761272) (xy 420.10625 -304.804849)
			(xy 420.121834 -304.85153) (xy 420.129729 -304.900107) (xy 420.130224 -304.924714) (xy 420.469072 -304.924714)
			(xy 420.473032 -304.87566) (xy 420.484809 -304.827876) (xy 420.5041 -304.7826) (xy 420.530403 -304.741004)
			(xy 420.563038 -304.704167) (xy 420.601159 -304.673042) (xy 420.64378 -304.648435) (xy 420.689796 -304.630983)
			(xy 420.738015 -304.621139) (xy 420.78719 -304.619158) (xy 420.836045 -304.62509) (xy 420.883316 -304.638782)
			(xy 420.927778 -304.65988) (xy 420.968281 -304.687836) (xy 421.003774 -304.721928) (xy 421.033339 -304.761272)
			(xy 421.05621 -304.804849) (xy 421.071794 -304.85153) (xy 421.079689 -304.900107) (xy 421.080184 -304.924714)
			(xy 421.419032 -304.924714) (xy 421.422992 -304.87566) (xy 421.434769 -304.827876) (xy 421.45406 -304.7826)
			(xy 421.480363 -304.741004) (xy 421.512998 -304.704167) (xy 421.551119 -304.673042) (xy 421.59374 -304.648435)
			(xy 421.639756 -304.630983) (xy 421.687975 -304.621139) (xy 421.73715 -304.619158) (xy 421.786005 -304.62509)
			(xy 421.833276 -304.638782) (xy 421.877738 -304.65988) (xy 421.918241 -304.687836) (xy 421.953734 -304.721928)
			(xy 421.983299 -304.761272) (xy 422.00617 -304.804849) (xy 422.021754 -304.85153) (xy 422.029649 -304.900107)
			(xy 422.030144 -304.924714) (xy 422.029649 -304.949321) (xy 422.021754 -304.997898) (xy 422.00617 -305.044579)
			(xy 421.983299 -305.088156) (xy 421.953734 -305.1275) (xy 421.918241 -305.161592) (xy 421.877738 -305.189548)
			(xy 421.833276 -305.210646) (xy 421.786005 -305.224338) (xy 421.73715 -305.23027) (xy 421.687975 -305.228289)
			(xy 421.639756 -305.218445) (xy 421.59374 -305.200993) (xy 421.551119 -305.176386) (xy 421.512998 -305.145261)
			(xy 421.480363 -305.108424) (xy 421.45406 -305.066828) (xy 421.434769 -305.021552) (xy 421.422992 -304.973768)
			(xy 421.419032 -304.924714) (xy 421.080184 -304.924714) (xy 421.079689 -304.949321) (xy 421.071794 -304.997898)
			(xy 421.05621 -305.044579) (xy 421.033339 -305.088156) (xy 421.003774 -305.1275) (xy 420.968281 -305.161592)
			(xy 420.927778 -305.189548) (xy 420.883316 -305.210646) (xy 420.836045 -305.224338) (xy 420.78719 -305.23027)
			(xy 420.738015 -305.228289) (xy 420.689796 -305.218445) (xy 420.64378 -305.200993) (xy 420.601159 -305.176386)
			(xy 420.563038 -305.145261) (xy 420.530403 -305.108424) (xy 420.5041 -305.066828) (xy 420.484809 -305.021552)
			(xy 420.473032 -304.973768) (xy 420.469072 -304.924714) (xy 420.130224 -304.924714) (xy 420.129729 -304.949321)
			(xy 420.121834 -304.997898) (xy 420.10625 -305.044579) (xy 420.083379 -305.088156) (xy 420.053814 -305.1275)
			(xy 420.018321 -305.161592) (xy 419.977818 -305.189548) (xy 419.933356 -305.210646) (xy 419.886085 -305.224338)
			(xy 419.83723 -305.23027) (xy 419.788055 -305.228289) (xy 419.739836 -305.218445) (xy 419.69382 -305.200993)
			(xy 419.651199 -305.176386) (xy 419.613078 -305.145261) (xy 419.580443 -305.108424) (xy 419.55414 -305.066828)
			(xy 419.534849 -305.021552) (xy 419.523072 -304.973768) (xy 419.519112 -304.924714) (xy 419.180264 -304.924714)
			(xy 419.179769 -304.949321) (xy 419.171874 -304.997898) (xy 419.15629 -305.044579) (xy 419.133419 -305.088156)
			(xy 419.103854 -305.1275) (xy 419.068361 -305.161592) (xy 419.027858 -305.189548) (xy 418.983396 -305.210646)
			(xy 418.936125 -305.224338) (xy 418.88727 -305.23027) (xy 418.838095 -305.228289) (xy 418.789876 -305.218445)
			(xy 418.74386 -305.200993) (xy 418.701239 -305.176386) (xy 418.663118 -305.145261) (xy 418.630483 -305.108424)
			(xy 418.60418 -305.066828) (xy 418.584889 -305.021552) (xy 418.573112 -304.973768) (xy 418.569152 -304.924714)
			(xy 417.28009 -304.924714) (xy 417.279595 -304.949321) (xy 417.2717 -304.997898) (xy 417.256116 -305.044579)
			(xy 417.233245 -305.088156) (xy 417.20368 -305.1275) (xy 417.168187 -305.161592) (xy 417.127684 -305.189548)
			(xy 417.083222 -305.210646) (xy 417.035951 -305.224338) (xy 416.987096 -305.23027) (xy 416.937921 -305.228289)
			(xy 416.889702 -305.218445) (xy 416.843686 -305.200993) (xy 416.801065 -305.176386) (xy 416.762944 -305.145261)
			(xy 416.730309 -305.108424) (xy 416.704006 -305.066828) (xy 416.684715 -305.021552) (xy 416.672938 -304.973768)
			(xy 416.668978 -304.924714) (xy 416.33013 -304.924714) (xy 416.329635 -304.949321) (xy 416.32174 -304.997898)
			(xy 416.306156 -305.044579) (xy 416.283285 -305.088156) (xy 416.25372 -305.1275) (xy 416.218227 -305.161592)
			(xy 416.177724 -305.189548) (xy 416.133262 -305.210646) (xy 416.085991 -305.224338) (xy 416.037136 -305.23027)
			(xy 415.987961 -305.228289) (xy 415.939742 -305.218445) (xy 415.893726 -305.200993) (xy 415.851105 -305.176386)
			(xy 415.812984 -305.145261) (xy 415.780349 -305.108424) (xy 415.754046 -305.066828) (xy 415.734755 -305.021552)
			(xy 415.722978 -304.973768) (xy 415.719018 -304.924714) (xy 415.38017 -304.924714) (xy 415.379675 -304.949321)
			(xy 415.37178 -304.997898) (xy 415.356196 -305.044579) (xy 415.333325 -305.088156) (xy 415.30376 -305.1275)
			(xy 415.268267 -305.161592) (xy 415.227764 -305.189548) (xy 415.183302 -305.210646) (xy 415.136031 -305.224338)
			(xy 415.087176 -305.23027) (xy 415.038001 -305.228289) (xy 414.989782 -305.218445) (xy 414.943766 -305.200993)
			(xy 414.901145 -305.176386) (xy 414.863024 -305.145261) (xy 414.830389 -305.108424) (xy 414.804086 -305.066828)
			(xy 414.784795 -305.021552) (xy 414.773018 -304.973768) (xy 414.769058 -304.924714) (xy 414.43021 -304.924714)
			(xy 414.429715 -304.949321) (xy 414.42182 -304.997898) (xy 414.406236 -305.044579) (xy 414.383365 -305.088156)
			(xy 414.3538 -305.1275) (xy 414.318307 -305.161592) (xy 414.277804 -305.189548) (xy 414.233342 -305.210646)
			(xy 414.186071 -305.224338) (xy 414.137216 -305.23027) (xy 414.088041 -305.228289) (xy 414.039822 -305.218445)
			(xy 413.993806 -305.200993) (xy 413.951185 -305.176386) (xy 413.913064 -305.145261) (xy 413.880429 -305.108424)
			(xy 413.854126 -305.066828) (xy 413.834835 -305.021552) (xy 413.823058 -304.973768) (xy 413.819098 -304.924714)
			(xy 413.48025 -304.924714) (xy 413.479755 -304.949321) (xy 413.47186 -304.997898) (xy 413.456276 -305.044579)
			(xy 413.433405 -305.088156) (xy 413.40384 -305.1275) (xy 413.368347 -305.161592) (xy 413.327844 -305.189548)
			(xy 413.283382 -305.210646) (xy 413.236111 -305.224338) (xy 413.187256 -305.23027) (xy 413.138081 -305.228289)
			(xy 413.089862 -305.218445) (xy 413.043846 -305.200993) (xy 413.001225 -305.176386) (xy 412.963104 -305.145261)
			(xy 412.930469 -305.108424) (xy 412.904166 -305.066828) (xy 412.884875 -305.021552) (xy 412.873098 -304.973768)
			(xy 412.869138 -304.924714) (xy 412.53029 -304.924714) (xy 412.529795 -304.949321) (xy 412.5219 -304.997898)
			(xy 412.506316 -305.044579) (xy 412.483445 -305.088156) (xy 412.45388 -305.1275) (xy 412.418387 -305.161592)
			(xy 412.377884 -305.189548) (xy 412.333422 -305.210646) (xy 412.286151 -305.224338) (xy 412.237296 -305.23027)
			(xy 412.188121 -305.228289) (xy 412.139902 -305.218445) (xy 412.093886 -305.200993) (xy 412.051265 -305.176386)
			(xy 412.013144 -305.145261) (xy 411.980509 -305.108424) (xy 411.954206 -305.066828) (xy 411.934915 -305.021552)
			(xy 411.923138 -304.973768) (xy 411.919178 -304.924714) (xy 411.58033 -304.924714) (xy 411.579835 -304.949321)
			(xy 411.57194 -304.997898) (xy 411.556356 -305.044579) (xy 411.533485 -305.088156) (xy 411.50392 -305.1275)
			(xy 411.468427 -305.161592) (xy 411.427924 -305.189548) (xy 411.383462 -305.210646) (xy 411.336191 -305.224338)
			(xy 411.287336 -305.23027) (xy 411.238161 -305.228289) (xy 411.189942 -305.218445) (xy 411.143926 -305.200993)
			(xy 411.101305 -305.176386) (xy 411.063184 -305.145261) (xy 411.030549 -305.108424) (xy 411.004246 -305.066828)
			(xy 410.984955 -305.021552) (xy 410.973178 -304.973768) (xy 410.969218 -304.924714) (xy 410.630116 -304.924714)
			(xy 410.629621 -304.949321) (xy 410.621726 -304.997898) (xy 410.606142 -305.044579) (xy 410.583271 -305.088156)
			(xy 410.553706 -305.1275) (xy 410.518213 -305.161592) (xy 410.47771 -305.189548) (xy 410.433248 -305.210646)
			(xy 410.385977 -305.224338) (xy 410.337122 -305.23027) (xy 410.287947 -305.228289) (xy 410.239728 -305.218445)
			(xy 410.193712 -305.200993) (xy 410.151091 -305.176386) (xy 410.11297 -305.145261) (xy 410.080335 -305.108424)
			(xy 410.054032 -305.066828) (xy 410.034741 -305.021552) (xy 410.022964 -304.973768) (xy 410.019004 -304.924714)
			(xy 409.680156 -304.924714) (xy 409.679661 -304.949321) (xy 409.671766 -304.997898) (xy 409.656182 -305.044579)
			(xy 409.633311 -305.088156) (xy 409.603746 -305.1275) (xy 409.568253 -305.161592) (xy 409.52775 -305.189548)
			(xy 409.483288 -305.210646) (xy 409.436017 -305.224338) (xy 409.387162 -305.23027) (xy 409.337987 -305.228289)
			(xy 409.289768 -305.218445) (xy 409.243752 -305.200993) (xy 409.201131 -305.176386) (xy 409.16301 -305.145261)
			(xy 409.130375 -305.108424) (xy 409.104072 -305.066828) (xy 409.084781 -305.021552) (xy 409.073004 -304.973768)
			(xy 409.069044 -304.924714) (xy 408.730196 -304.924714) (xy 408.729701 -304.949321) (xy 408.721806 -304.997898)
			(xy 408.706222 -305.044579) (xy 408.683351 -305.088156) (xy 408.653786 -305.1275) (xy 408.618293 -305.161592)
			(xy 408.57779 -305.189548) (xy 408.533328 -305.210646) (xy 408.486057 -305.224338) (xy 408.437202 -305.23027)
			(xy 408.388027 -305.228289) (xy 408.339808 -305.218445) (xy 408.293792 -305.200993) (xy 408.251171 -305.176386)
			(xy 408.21305 -305.145261) (xy 408.180415 -305.108424) (xy 408.154112 -305.066828) (xy 408.134821 -305.021552)
			(xy 408.123044 -304.973768) (xy 408.119084 -304.924714) (xy 406.830276 -304.924714) (xy 406.829781 -304.949321)
			(xy 406.821886 -304.997898) (xy 406.806302 -305.044579) (xy 406.783431 -305.088156) (xy 406.753866 -305.1275)
			(xy 406.718373 -305.161592) (xy 406.67787 -305.189548) (xy 406.633408 -305.210646) (xy 406.586137 -305.224338)
			(xy 406.537282 -305.23027) (xy 406.488107 -305.228289) (xy 406.439888 -305.218445) (xy 406.393872 -305.200993)
			(xy 406.351251 -305.176386) (xy 406.31313 -305.145261) (xy 406.280495 -305.108424) (xy 406.254192 -305.066828)
			(xy 406.234901 -305.021552) (xy 406.223124 -304.973768) (xy 406.219164 -304.924714) (xy 405.880316 -304.924714)
			(xy 405.879821 -304.949321) (xy 405.871926 -304.997898) (xy 405.856342 -305.044579) (xy 405.833471 -305.088156)
			(xy 405.803906 -305.1275) (xy 405.768413 -305.161592) (xy 405.72791 -305.189548) (xy 405.683448 -305.210646)
			(xy 405.636177 -305.224338) (xy 405.587322 -305.23027) (xy 405.538147 -305.228289) (xy 405.489928 -305.218445)
			(xy 405.443912 -305.200993) (xy 405.401291 -305.176386) (xy 405.36317 -305.145261) (xy 405.330535 -305.108424)
			(xy 405.304232 -305.066828) (xy 405.284941 -305.021552) (xy 405.273164 -304.973768) (xy 405.269204 -304.924714)
			(xy 404.930102 -304.924714) (xy 404.929607 -304.949321) (xy 404.921712 -304.997898) (xy 404.906128 -305.044579)
			(xy 404.883257 -305.088156) (xy 404.853692 -305.1275) (xy 404.818199 -305.161592) (xy 404.777696 -305.189548)
			(xy 404.733234 -305.210646) (xy 404.685963 -305.224338) (xy 404.637108 -305.23027) (xy 404.587933 -305.228289)
			(xy 404.539714 -305.218445) (xy 404.493698 -305.200993) (xy 404.451077 -305.176386) (xy 404.412956 -305.145261)
			(xy 404.380321 -305.108424) (xy 404.354018 -305.066828) (xy 404.334727 -305.021552) (xy 404.32295 -304.973768)
			(xy 404.31899 -304.924714) (xy 403.980142 -304.924714) (xy 403.979647 -304.949321) (xy 403.971752 -304.997898)
			(xy 403.956168 -305.044579) (xy 403.933297 -305.088156) (xy 403.903732 -305.1275) (xy 403.868239 -305.161592)
			(xy 403.827736 -305.189548) (xy 403.783274 -305.210646) (xy 403.736003 -305.224338) (xy 403.687148 -305.23027)
			(xy 403.637973 -305.228289) (xy 403.589754 -305.218445) (xy 403.543738 -305.200993) (xy 403.501117 -305.176386)
			(xy 403.462996 -305.145261) (xy 403.430361 -305.108424) (xy 403.404058 -305.066828) (xy 403.384767 -305.021552)
			(xy 403.37299 -304.973768) (xy 403.36903 -304.924714) (xy 403.030182 -304.924714) (xy 403.029687 -304.949321)
			(xy 403.021792 -304.997898) (xy 403.006208 -305.044579) (xy 402.983337 -305.088156) (xy 402.953772 -305.1275)
			(xy 402.918279 -305.161592) (xy 402.877776 -305.189548) (xy 402.833314 -305.210646) (xy 402.786043 -305.224338)
			(xy 402.737188 -305.23027) (xy 402.688013 -305.228289) (xy 402.639794 -305.218445) (xy 402.593778 -305.200993)
			(xy 402.551157 -305.176386) (xy 402.513036 -305.145261) (xy 402.480401 -305.108424) (xy 402.454098 -305.066828)
			(xy 402.434807 -305.021552) (xy 402.42303 -304.973768) (xy 402.41907 -304.924714) (xy 402.080222 -304.924714)
			(xy 402.079727 -304.949321) (xy 402.071832 -304.997898) (xy 402.056248 -305.044579) (xy 402.033377 -305.088156)
			(xy 402.003812 -305.1275) (xy 401.968319 -305.161592) (xy 401.927816 -305.189548) (xy 401.883354 -305.210646)
			(xy 401.836083 -305.224338) (xy 401.787228 -305.23027) (xy 401.738053 -305.228289) (xy 401.689834 -305.218445)
			(xy 401.643818 -305.200993) (xy 401.601197 -305.176386) (xy 401.563076 -305.145261) (xy 401.530441 -305.108424)
			(xy 401.504138 -305.066828) (xy 401.484847 -305.021552) (xy 401.47307 -304.973768) (xy 401.46911 -304.924714)
			(xy 401.130262 -304.924714) (xy 401.129767 -304.949321) (xy 401.121872 -304.997898) (xy 401.106288 -305.044579)
			(xy 401.083417 -305.088156) (xy 401.053852 -305.1275) (xy 401.018359 -305.161592) (xy 400.977856 -305.189548)
			(xy 400.933394 -305.210646) (xy 400.886123 -305.224338) (xy 400.837268 -305.23027) (xy 400.788093 -305.228289)
			(xy 400.739874 -305.218445) (xy 400.693858 -305.200993) (xy 400.651237 -305.176386) (xy 400.613116 -305.145261)
			(xy 400.580481 -305.108424) (xy 400.554178 -305.066828) (xy 400.534887 -305.021552) (xy 400.52311 -304.973768)
			(xy 400.51915 -304.924714) (xy 400.180302 -304.924714) (xy 400.179807 -304.949321) (xy 400.171912 -304.997898)
			(xy 400.156328 -305.044579) (xy 400.133457 -305.088156) (xy 400.103892 -305.1275) (xy 400.068399 -305.161592)
			(xy 400.027896 -305.189548) (xy 399.983434 -305.210646) (xy 399.936163 -305.224338) (xy 399.887308 -305.23027)
			(xy 399.838133 -305.228289) (xy 399.789914 -305.218445) (xy 399.743898 -305.200993) (xy 399.701277 -305.176386)
			(xy 399.663156 -305.145261) (xy 399.630521 -305.108424) (xy 399.604218 -305.066828) (xy 399.584927 -305.021552)
			(xy 399.57315 -304.973768) (xy 399.56919 -304.924714) (xy 399.230342 -304.924714) (xy 399.229847 -304.949321)
			(xy 399.221952 -304.997898) (xy 399.206368 -305.044579) (xy 399.183497 -305.088156) (xy 399.153932 -305.1275)
			(xy 399.118439 -305.161592) (xy 399.077936 -305.189548) (xy 399.033474 -305.210646) (xy 398.986203 -305.224338)
			(xy 398.937348 -305.23027) (xy 398.888173 -305.228289) (xy 398.839954 -305.218445) (xy 398.793938 -305.200993)
			(xy 398.751317 -305.176386) (xy 398.713196 -305.145261) (xy 398.680561 -305.108424) (xy 398.654258 -305.066828)
			(xy 398.634967 -305.021552) (xy 398.62319 -304.973768) (xy 398.61923 -304.924714) (xy 398.280128 -304.924714)
			(xy 398.279633 -304.949321) (xy 398.271738 -304.997898) (xy 398.256154 -305.044579) (xy 398.233283 -305.088156)
			(xy 398.203718 -305.1275) (xy 398.168225 -305.161592) (xy 398.127722 -305.189548) (xy 398.08326 -305.210646)
			(xy 398.035989 -305.224338) (xy 397.987134 -305.23027) (xy 397.937959 -305.228289) (xy 397.88974 -305.218445)
			(xy 397.843724 -305.200993) (xy 397.801103 -305.176386) (xy 397.762982 -305.145261) (xy 397.730347 -305.108424)
			(xy 397.704044 -305.066828) (xy 397.684753 -305.021552) (xy 397.672976 -304.973768) (xy 397.669016 -304.924714)
			(xy 397.330168 -304.924714) (xy 397.329673 -304.949321) (xy 397.321778 -304.997898) (xy 397.306194 -305.044579)
			(xy 397.283323 -305.088156) (xy 397.253758 -305.1275) (xy 397.218265 -305.161592) (xy 397.177762 -305.189548)
			(xy 397.1333 -305.210646) (xy 397.086029 -305.224338) (xy 397.037174 -305.23027) (xy 396.987999 -305.228289)
			(xy 396.93978 -305.218445) (xy 396.893764 -305.200993) (xy 396.851143 -305.176386) (xy 396.813022 -305.145261)
			(xy 396.780387 -305.108424) (xy 396.754084 -305.066828) (xy 396.734793 -305.021552) (xy 396.723016 -304.973768)
			(xy 396.719056 -304.924714) (xy 396.380208 -304.924714) (xy 396.379713 -304.949321) (xy 396.371818 -304.997898)
			(xy 396.356234 -305.044579) (xy 396.333363 -305.088156) (xy 396.303798 -305.1275) (xy 396.268305 -305.161592)
			(xy 396.227802 -305.189548) (xy 396.18334 -305.210646) (xy 396.136069 -305.224338) (xy 396.087214 -305.23027)
			(xy 396.038039 -305.228289) (xy 395.98982 -305.218445) (xy 395.943804 -305.200993) (xy 395.901183 -305.176386)
			(xy 395.863062 -305.145261) (xy 395.830427 -305.108424) (xy 395.804124 -305.066828) (xy 395.784833 -305.021552)
			(xy 395.773056 -304.973768) (xy 395.769096 -304.924714) (xy 395.430248 -304.924714) (xy 395.429753 -304.949321)
			(xy 395.421858 -304.997898) (xy 395.406274 -305.044579) (xy 395.383403 -305.088156) (xy 395.353838 -305.1275)
			(xy 395.318345 -305.161592) (xy 395.277842 -305.189548) (xy 395.23338 -305.210646) (xy 395.186109 -305.224338)
			(xy 395.137254 -305.23027) (xy 395.088079 -305.228289) (xy 395.03986 -305.218445) (xy 394.993844 -305.200993)
			(xy 394.951223 -305.176386) (xy 394.913102 -305.145261) (xy 394.880467 -305.108424) (xy 394.854164 -305.066828)
			(xy 394.834873 -305.021552) (xy 394.823096 -304.973768) (xy 394.819136 -304.924714) (xy 389.255 -304.924714)
			(xy 389.255 -305.391566) (xy 389.255254 -305.399186) (xy 389.255254 -305.399948) (xy 389.594102 -305.399948)
			(xy 389.598062 -305.350894) (xy 389.609839 -305.30311) (xy 389.62913 -305.257834) (xy 389.655433 -305.216238)
			(xy 389.688068 -305.179401) (xy 389.726189 -305.148276) (xy 389.76881 -305.123669) (xy 389.814826 -305.106217)
			(xy 389.863045 -305.096373) (xy 389.91222 -305.094392) (xy 389.961075 -305.100324) (xy 390.008346 -305.114016)
			(xy 390.052808 -305.135114) (xy 390.093311 -305.16307) (xy 390.128804 -305.197162) (xy 390.158369 -305.236506)
			(xy 390.18124 -305.280083) (xy 390.196824 -305.326764) (xy 390.204719 -305.375341) (xy 390.205214 -305.399948)
			(xy 390.544062 -305.399948) (xy 390.548022 -305.350894) (xy 390.559799 -305.30311) (xy 390.57909 -305.257834)
			(xy 390.605393 -305.216238) (xy 390.638028 -305.179401) (xy 390.676149 -305.148276) (xy 390.71877 -305.123669)
			(xy 390.764786 -305.106217) (xy 390.813005 -305.096373) (xy 390.86218 -305.094392) (xy 390.911035 -305.100324)
			(xy 390.958306 -305.114016) (xy 391.002768 -305.135114) (xy 391.043271 -305.16307) (xy 391.078764 -305.197162)
			(xy 391.108329 -305.236506) (xy 391.1312 -305.280083) (xy 391.146784 -305.326764) (xy 391.154679 -305.375341)
			(xy 391.155174 -305.399948) (xy 391.494022 -305.399948) (xy 391.497982 -305.350894) (xy 391.509759 -305.30311)
			(xy 391.52905 -305.257834) (xy 391.555353 -305.216238) (xy 391.587988 -305.179401) (xy 391.626109 -305.148276)
			(xy 391.66873 -305.123669) (xy 391.714746 -305.106217) (xy 391.762965 -305.096373) (xy 391.81214 -305.094392)
			(xy 391.860995 -305.100324) (xy 391.908266 -305.114016) (xy 391.952728 -305.135114) (xy 391.993231 -305.16307)
			(xy 392.028724 -305.197162) (xy 392.058289 -305.236506) (xy 392.08116 -305.280083) (xy 392.096744 -305.326764)
			(xy 392.104639 -305.375341) (xy 392.105134 -305.399948) (xy 392.443982 -305.399948) (xy 392.447942 -305.350894)
			(xy 392.459719 -305.30311) (xy 392.47901 -305.257834) (xy 392.505313 -305.216238) (xy 392.537948 -305.179401)
			(xy 392.576069 -305.148276) (xy 392.61869 -305.123669) (xy 392.664706 -305.106217) (xy 392.712925 -305.096373)
			(xy 392.7621 -305.094392) (xy 392.810955 -305.100324) (xy 392.858226 -305.114016) (xy 392.902688 -305.135114)
			(xy 392.943191 -305.16307) (xy 392.978684 -305.197162) (xy 393.008249 -305.236506) (xy 393.03112 -305.280083)
			(xy 393.046704 -305.326764) (xy 393.054599 -305.375341) (xy 393.055094 -305.399948) (xy 393.394196 -305.399948)
			(xy 393.398156 -305.350894) (xy 393.409933 -305.30311) (xy 393.429224 -305.257834) (xy 393.455527 -305.216238)
			(xy 393.488162 -305.179401) (xy 393.526283 -305.148276) (xy 393.568904 -305.123669) (xy 393.61492 -305.106217)
			(xy 393.663139 -305.096373) (xy 393.712314 -305.094392) (xy 393.761169 -305.100324) (xy 393.80844 -305.114016)
			(xy 393.852902 -305.135114) (xy 393.893405 -305.16307) (xy 393.928898 -305.197162) (xy 393.958463 -305.236506)
			(xy 393.981334 -305.280083) (xy 393.996918 -305.326764) (xy 394.004813 -305.375341) (xy 394.005308 -305.399948)
			(xy 394.004813 -305.424555) (xy 393.996918 -305.473132) (xy 393.981334 -305.519813) (xy 393.958463 -305.56339)
			(xy 393.928898 -305.602734) (xy 393.893405 -305.636826) (xy 393.852902 -305.664782) (xy 393.80844 -305.68588)
			(xy 393.761169 -305.699572) (xy 393.712314 -305.705504) (xy 393.663139 -305.703523) (xy 393.61492 -305.693679)
			(xy 393.568904 -305.676227) (xy 393.526283 -305.65162) (xy 393.488162 -305.620495) (xy 393.455527 -305.583658)
			(xy 393.429224 -305.542062) (xy 393.409933 -305.496786) (xy 393.398156 -305.449002) (xy 393.394196 -305.399948)
			(xy 393.055094 -305.399948) (xy 393.054599 -305.424555) (xy 393.046704 -305.473132) (xy 393.03112 -305.519813)
			(xy 393.008249 -305.56339) (xy 392.978684 -305.602734) (xy 392.943191 -305.636826) (xy 392.902688 -305.664782)
			(xy 392.858226 -305.68588) (xy 392.810955 -305.699572) (xy 392.7621 -305.705504) (xy 392.712925 -305.703523)
			(xy 392.664706 -305.693679) (xy 392.61869 -305.676227) (xy 392.576069 -305.65162) (xy 392.537948 -305.620495)
			(xy 392.505313 -305.583658) (xy 392.47901 -305.542062) (xy 392.459719 -305.496786) (xy 392.447942 -305.449002)
			(xy 392.443982 -305.399948) (xy 392.105134 -305.399948) (xy 392.104639 -305.424555) (xy 392.096744 -305.473132)
			(xy 392.08116 -305.519813) (xy 392.058289 -305.56339) (xy 392.028724 -305.602734) (xy 391.993231 -305.636826)
			(xy 391.952728 -305.664782) (xy 391.908266 -305.68588) (xy 391.860995 -305.699572) (xy 391.81214 -305.705504)
			(xy 391.762965 -305.703523) (xy 391.714746 -305.693679) (xy 391.66873 -305.676227) (xy 391.626109 -305.65162)
			(xy 391.587988 -305.620495) (xy 391.555353 -305.583658) (xy 391.52905 -305.542062) (xy 391.509759 -305.496786)
			(xy 391.497982 -305.449002) (xy 391.494022 -305.399948) (xy 391.155174 -305.399948) (xy 391.154679 -305.424555)
			(xy 391.146784 -305.473132) (xy 391.1312 -305.519813) (xy 391.108329 -305.56339) (xy 391.078764 -305.602734)
			(xy 391.043271 -305.636826) (xy 391.002768 -305.664782) (xy 390.958306 -305.68588) (xy 390.911035 -305.699572)
			(xy 390.86218 -305.705504) (xy 390.813005 -305.703523) (xy 390.764786 -305.693679) (xy 390.71877 -305.676227)
			(xy 390.676149 -305.65162) (xy 390.638028 -305.620495) (xy 390.605393 -305.583658) (xy 390.57909 -305.542062)
			(xy 390.559799 -305.496786) (xy 390.548022 -305.449002) (xy 390.544062 -305.399948) (xy 390.205214 -305.399948)
			(xy 390.204719 -305.424555) (xy 390.196824 -305.473132) (xy 390.18124 -305.519813) (xy 390.158369 -305.56339)
			(xy 390.128804 -305.602734) (xy 390.093311 -305.636826) (xy 390.052808 -305.664782) (xy 390.008346 -305.68588)
			(xy 389.961075 -305.699572) (xy 389.91222 -305.705504) (xy 389.863045 -305.703523) (xy 389.814826 -305.693679)
			(xy 389.76881 -305.676227) (xy 389.726189 -305.65162) (xy 389.688068 -305.620495) (xy 389.655433 -305.583658)
			(xy 389.62913 -305.542062) (xy 389.609839 -305.496786) (xy 389.598062 -305.449002) (xy 389.594102 -305.399948)
			(xy 389.255254 -305.399948) (xy 389.255254 -305.40071) (xy 389.255 -305.40833) (xy 389.255 -305.874928)
			(xy 394.819136 -305.874928) (xy 394.823096 -305.825874) (xy 394.834873 -305.77809) (xy 394.854164 -305.732814)
			(xy 394.880467 -305.691218) (xy 394.913102 -305.654381) (xy 394.951223 -305.623256) (xy 394.993844 -305.598649)
			(xy 395.03986 -305.581197) (xy 395.088079 -305.571353) (xy 395.137254 -305.569372) (xy 395.186109 -305.575304)
			(xy 395.23338 -305.588996) (xy 395.277842 -305.610094) (xy 395.318345 -305.63805) (xy 395.353838 -305.672142)
			(xy 395.383403 -305.711486) (xy 395.406274 -305.755063) (xy 395.421858 -305.801744) (xy 395.429753 -305.850321)
			(xy 395.430248 -305.874928) (xy 395.769096 -305.874928) (xy 395.773056 -305.825874) (xy 395.784833 -305.77809)
			(xy 395.804124 -305.732814) (xy 395.830427 -305.691218) (xy 395.863062 -305.654381) (xy 395.901183 -305.623256)
			(xy 395.943804 -305.598649) (xy 395.98982 -305.581197) (xy 396.038039 -305.571353) (xy 396.087214 -305.569372)
			(xy 396.136069 -305.575304) (xy 396.18334 -305.588996) (xy 396.227802 -305.610094) (xy 396.268305 -305.63805)
			(xy 396.303798 -305.672142) (xy 396.333363 -305.711486) (xy 396.356234 -305.755063) (xy 396.371818 -305.801744)
			(xy 396.379713 -305.850321) (xy 396.380208 -305.874928) (xy 396.719056 -305.874928) (xy 396.723016 -305.825874)
			(xy 396.734793 -305.77809) (xy 396.754084 -305.732814) (xy 396.780387 -305.691218) (xy 396.813022 -305.654381)
			(xy 396.851143 -305.623256) (xy 396.893764 -305.598649) (xy 396.93978 -305.581197) (xy 396.987999 -305.571353)
			(xy 397.037174 -305.569372) (xy 397.086029 -305.575304) (xy 397.1333 -305.588996) (xy 397.177762 -305.610094)
			(xy 397.218265 -305.63805) (xy 397.253758 -305.672142) (xy 397.283323 -305.711486) (xy 397.306194 -305.755063)
			(xy 397.321778 -305.801744) (xy 397.329673 -305.850321) (xy 397.330168 -305.874928) (xy 397.669016 -305.874928)
			(xy 397.672976 -305.825874) (xy 397.684753 -305.77809) (xy 397.704044 -305.732814) (xy 397.730347 -305.691218)
			(xy 397.762982 -305.654381) (xy 397.801103 -305.623256) (xy 397.843724 -305.598649) (xy 397.88974 -305.581197)
			(xy 397.937959 -305.571353) (xy 397.987134 -305.569372) (xy 398.035989 -305.575304) (xy 398.08326 -305.588996)
			(xy 398.127722 -305.610094) (xy 398.168225 -305.63805) (xy 398.203718 -305.672142) (xy 398.233283 -305.711486)
			(xy 398.256154 -305.755063) (xy 398.271738 -305.801744) (xy 398.279633 -305.850321) (xy 398.280128 -305.874928)
			(xy 398.61923 -305.874928) (xy 398.62319 -305.825874) (xy 398.634967 -305.77809) (xy 398.654258 -305.732814)
			(xy 398.680561 -305.691218) (xy 398.713196 -305.654381) (xy 398.751317 -305.623256) (xy 398.793938 -305.598649)
			(xy 398.839954 -305.581197) (xy 398.888173 -305.571353) (xy 398.937348 -305.569372) (xy 398.986203 -305.575304)
			(xy 399.033474 -305.588996) (xy 399.077936 -305.610094) (xy 399.118439 -305.63805) (xy 399.153932 -305.672142)
			(xy 399.183497 -305.711486) (xy 399.206368 -305.755063) (xy 399.221952 -305.801744) (xy 399.229847 -305.850321)
			(xy 399.230342 -305.874928) (xy 399.56919 -305.874928) (xy 399.57315 -305.825874) (xy 399.584927 -305.77809)
			(xy 399.604218 -305.732814) (xy 399.630521 -305.691218) (xy 399.663156 -305.654381) (xy 399.701277 -305.623256)
			(xy 399.743898 -305.598649) (xy 399.789914 -305.581197) (xy 399.838133 -305.571353) (xy 399.887308 -305.569372)
			(xy 399.936163 -305.575304) (xy 399.983434 -305.588996) (xy 400.027896 -305.610094) (xy 400.068399 -305.63805)
			(xy 400.103892 -305.672142) (xy 400.133457 -305.711486) (xy 400.156328 -305.755063) (xy 400.171912 -305.801744)
			(xy 400.179807 -305.850321) (xy 400.180302 -305.874928) (xy 400.51915 -305.874928) (xy 400.52311 -305.825874)
			(xy 400.534887 -305.77809) (xy 400.554178 -305.732814) (xy 400.580481 -305.691218) (xy 400.613116 -305.654381)
			(xy 400.651237 -305.623256) (xy 400.693858 -305.598649) (xy 400.739874 -305.581197) (xy 400.788093 -305.571353)
			(xy 400.837268 -305.569372) (xy 400.886123 -305.575304) (xy 400.933394 -305.588996) (xy 400.977856 -305.610094)
			(xy 401.018359 -305.63805) (xy 401.053852 -305.672142) (xy 401.083417 -305.711486) (xy 401.106288 -305.755063)
			(xy 401.121872 -305.801744) (xy 401.129767 -305.850321) (xy 401.130262 -305.874928) (xy 401.46911 -305.874928)
			(xy 401.47307 -305.825874) (xy 401.484847 -305.77809) (xy 401.504138 -305.732814) (xy 401.530441 -305.691218)
			(xy 401.563076 -305.654381) (xy 401.601197 -305.623256) (xy 401.643818 -305.598649) (xy 401.689834 -305.581197)
			(xy 401.738053 -305.571353) (xy 401.787228 -305.569372) (xy 401.836083 -305.575304) (xy 401.883354 -305.588996)
			(xy 401.927816 -305.610094) (xy 401.968319 -305.63805) (xy 402.003812 -305.672142) (xy 402.033377 -305.711486)
			(xy 402.056248 -305.755063) (xy 402.071832 -305.801744) (xy 402.079727 -305.850321) (xy 402.080222 -305.874928)
			(xy 402.41907 -305.874928) (xy 402.42303 -305.825874) (xy 402.434807 -305.77809) (xy 402.454098 -305.732814)
			(xy 402.480401 -305.691218) (xy 402.513036 -305.654381) (xy 402.551157 -305.623256) (xy 402.593778 -305.598649)
			(xy 402.639794 -305.581197) (xy 402.688013 -305.571353) (xy 402.737188 -305.569372) (xy 402.786043 -305.575304)
			(xy 402.833314 -305.588996) (xy 402.877776 -305.610094) (xy 402.918279 -305.63805) (xy 402.953772 -305.672142)
			(xy 402.983337 -305.711486) (xy 403.006208 -305.755063) (xy 403.021792 -305.801744) (xy 403.029687 -305.850321)
			(xy 403.030182 -305.874928) (xy 403.36903 -305.874928) (xy 403.37299 -305.825874) (xy 403.384767 -305.77809)
			(xy 403.404058 -305.732814) (xy 403.430361 -305.691218) (xy 403.462996 -305.654381) (xy 403.501117 -305.623256)
			(xy 403.543738 -305.598649) (xy 403.589754 -305.581197) (xy 403.637973 -305.571353) (xy 403.687148 -305.569372)
			(xy 403.736003 -305.575304) (xy 403.783274 -305.588996) (xy 403.827736 -305.610094) (xy 403.868239 -305.63805)
			(xy 403.903732 -305.672142) (xy 403.933297 -305.711486) (xy 403.956168 -305.755063) (xy 403.971752 -305.801744)
			(xy 403.979647 -305.850321) (xy 403.980142 -305.874928) (xy 404.31899 -305.874928) (xy 404.32295 -305.825874)
			(xy 404.334727 -305.77809) (xy 404.354018 -305.732814) (xy 404.380321 -305.691218) (xy 404.412956 -305.654381)
			(xy 404.451077 -305.623256) (xy 404.493698 -305.598649) (xy 404.539714 -305.581197) (xy 404.587933 -305.571353)
			(xy 404.637108 -305.569372) (xy 404.685963 -305.575304) (xy 404.733234 -305.588996) (xy 404.777696 -305.610094)
			(xy 404.818199 -305.63805) (xy 404.853692 -305.672142) (xy 404.883257 -305.711486) (xy 404.906128 -305.755063)
			(xy 404.921712 -305.801744) (xy 404.929607 -305.850321) (xy 404.930102 -305.874928) (xy 405.269204 -305.874928)
			(xy 405.273164 -305.825874) (xy 405.284941 -305.77809) (xy 405.304232 -305.732814) (xy 405.330535 -305.691218)
			(xy 405.36317 -305.654381) (xy 405.401291 -305.623256) (xy 405.443912 -305.598649) (xy 405.489928 -305.581197)
			(xy 405.538147 -305.571353) (xy 405.587322 -305.569372) (xy 405.636177 -305.575304) (xy 405.683448 -305.588996)
			(xy 405.72791 -305.610094) (xy 405.768413 -305.63805) (xy 405.803906 -305.672142) (xy 405.833471 -305.711486)
			(xy 405.856342 -305.755063) (xy 405.871926 -305.801744) (xy 405.879821 -305.850321) (xy 405.880316 -305.874928)
			(xy 406.219164 -305.874928) (xy 406.223124 -305.825874) (xy 406.234901 -305.77809) (xy 406.254192 -305.732814)
			(xy 406.280495 -305.691218) (xy 406.31313 -305.654381) (xy 406.351251 -305.623256) (xy 406.393872 -305.598649)
			(xy 406.439888 -305.581197) (xy 406.488107 -305.571353) (xy 406.537282 -305.569372) (xy 406.586137 -305.575304)
			(xy 406.633408 -305.588996) (xy 406.67787 -305.610094) (xy 406.718373 -305.63805) (xy 406.753866 -305.672142)
			(xy 406.783431 -305.711486) (xy 406.806302 -305.755063) (xy 406.821886 -305.801744) (xy 406.829781 -305.850321)
			(xy 406.830276 -305.874928) (xy 408.119084 -305.874928) (xy 408.123044 -305.825874) (xy 408.134821 -305.77809)
			(xy 408.154112 -305.732814) (xy 408.180415 -305.691218) (xy 408.21305 -305.654381) (xy 408.251171 -305.623256)
			(xy 408.293792 -305.598649) (xy 408.339808 -305.581197) (xy 408.388027 -305.571353) (xy 408.437202 -305.569372)
			(xy 408.486057 -305.575304) (xy 408.533328 -305.588996) (xy 408.57779 -305.610094) (xy 408.618293 -305.63805)
			(xy 408.653786 -305.672142) (xy 408.683351 -305.711486) (xy 408.706222 -305.755063) (xy 408.721806 -305.801744)
			(xy 408.729701 -305.850321) (xy 408.730196 -305.874928) (xy 409.069044 -305.874928) (xy 409.073004 -305.825874)
			(xy 409.084781 -305.77809) (xy 409.104072 -305.732814) (xy 409.130375 -305.691218) (xy 409.16301 -305.654381)
			(xy 409.201131 -305.623256) (xy 409.243752 -305.598649) (xy 409.289768 -305.581197) (xy 409.337987 -305.571353)
			(xy 409.387162 -305.569372) (xy 409.436017 -305.575304) (xy 409.483288 -305.588996) (xy 409.52775 -305.610094)
			(xy 409.568253 -305.63805) (xy 409.603746 -305.672142) (xy 409.633311 -305.711486) (xy 409.656182 -305.755063)
			(xy 409.671766 -305.801744) (xy 409.679661 -305.850321) (xy 409.680156 -305.874928) (xy 410.019004 -305.874928)
			(xy 410.022964 -305.825874) (xy 410.034741 -305.77809) (xy 410.054032 -305.732814) (xy 410.080335 -305.691218)
			(xy 410.11297 -305.654381) (xy 410.151091 -305.623256) (xy 410.193712 -305.598649) (xy 410.239728 -305.581197)
			(xy 410.287947 -305.571353) (xy 410.337122 -305.569372) (xy 410.385977 -305.575304) (xy 410.433248 -305.588996)
			(xy 410.47771 -305.610094) (xy 410.518213 -305.63805) (xy 410.553706 -305.672142) (xy 410.583271 -305.711486)
			(xy 410.606142 -305.755063) (xy 410.621726 -305.801744) (xy 410.629621 -305.850321) (xy 410.630116 -305.874928)
			(xy 410.969218 -305.874928) (xy 410.973178 -305.825874) (xy 410.984955 -305.77809) (xy 411.004246 -305.732814)
			(xy 411.030549 -305.691218) (xy 411.063184 -305.654381) (xy 411.101305 -305.623256) (xy 411.143926 -305.598649)
			(xy 411.189942 -305.581197) (xy 411.238161 -305.571353) (xy 411.287336 -305.569372) (xy 411.336191 -305.575304)
			(xy 411.383462 -305.588996) (xy 411.427924 -305.610094) (xy 411.468427 -305.63805) (xy 411.50392 -305.672142)
			(xy 411.533485 -305.711486) (xy 411.556356 -305.755063) (xy 411.57194 -305.801744) (xy 411.579835 -305.850321)
			(xy 411.58033 -305.874928) (xy 411.919178 -305.874928) (xy 411.923138 -305.825874) (xy 411.934915 -305.77809)
			(xy 411.954206 -305.732814) (xy 411.980509 -305.691218) (xy 412.013144 -305.654381) (xy 412.051265 -305.623256)
			(xy 412.093886 -305.598649) (xy 412.139902 -305.581197) (xy 412.188121 -305.571353) (xy 412.237296 -305.569372)
			(xy 412.286151 -305.575304) (xy 412.333422 -305.588996) (xy 412.377884 -305.610094) (xy 412.418387 -305.63805)
			(xy 412.45388 -305.672142) (xy 412.483445 -305.711486) (xy 412.506316 -305.755063) (xy 412.5219 -305.801744)
			(xy 412.529795 -305.850321) (xy 412.53029 -305.874928) (xy 412.869138 -305.874928) (xy 412.873098 -305.825874)
			(xy 412.884875 -305.77809) (xy 412.904166 -305.732814) (xy 412.930469 -305.691218) (xy 412.963104 -305.654381)
			(xy 413.001225 -305.623256) (xy 413.043846 -305.598649) (xy 413.089862 -305.581197) (xy 413.138081 -305.571353)
			(xy 413.187256 -305.569372) (xy 413.236111 -305.575304) (xy 413.283382 -305.588996) (xy 413.327844 -305.610094)
			(xy 413.368347 -305.63805) (xy 413.40384 -305.672142) (xy 413.433405 -305.711486) (xy 413.456276 -305.755063)
			(xy 413.47186 -305.801744) (xy 413.479755 -305.850321) (xy 413.48025 -305.874928) (xy 413.819098 -305.874928)
			(xy 413.823058 -305.825874) (xy 413.834835 -305.77809) (xy 413.854126 -305.732814) (xy 413.880429 -305.691218)
			(xy 413.913064 -305.654381) (xy 413.951185 -305.623256) (xy 413.993806 -305.598649) (xy 414.039822 -305.581197)
			(xy 414.088041 -305.571353) (xy 414.137216 -305.569372) (xy 414.186071 -305.575304) (xy 414.233342 -305.588996)
			(xy 414.277804 -305.610094) (xy 414.318307 -305.63805) (xy 414.3538 -305.672142) (xy 414.383365 -305.711486)
			(xy 414.406236 -305.755063) (xy 414.42182 -305.801744) (xy 414.429715 -305.850321) (xy 414.43021 -305.874928)
			(xy 414.769058 -305.874928) (xy 414.773018 -305.825874) (xy 414.784795 -305.77809) (xy 414.804086 -305.732814)
			(xy 414.830389 -305.691218) (xy 414.863024 -305.654381) (xy 414.901145 -305.623256) (xy 414.943766 -305.598649)
			(xy 414.989782 -305.581197) (xy 415.038001 -305.571353) (xy 415.087176 -305.569372) (xy 415.136031 -305.575304)
			(xy 415.183302 -305.588996) (xy 415.227764 -305.610094) (xy 415.268267 -305.63805) (xy 415.30376 -305.672142)
			(xy 415.333325 -305.711486) (xy 415.356196 -305.755063) (xy 415.37178 -305.801744) (xy 415.379675 -305.850321)
			(xy 415.38017 -305.874928) (xy 415.719018 -305.874928) (xy 415.722978 -305.825874) (xy 415.734755 -305.77809)
			(xy 415.754046 -305.732814) (xy 415.780349 -305.691218) (xy 415.812984 -305.654381) (xy 415.851105 -305.623256)
			(xy 415.893726 -305.598649) (xy 415.939742 -305.581197) (xy 415.987961 -305.571353) (xy 416.037136 -305.569372)
			(xy 416.085991 -305.575304) (xy 416.133262 -305.588996) (xy 416.177724 -305.610094) (xy 416.218227 -305.63805)
			(xy 416.25372 -305.672142) (xy 416.283285 -305.711486) (xy 416.306156 -305.755063) (xy 416.32174 -305.801744)
			(xy 416.329635 -305.850321) (xy 416.33013 -305.874928) (xy 416.668978 -305.874928) (xy 416.672938 -305.825874)
			(xy 416.684715 -305.77809) (xy 416.704006 -305.732814) (xy 416.730309 -305.691218) (xy 416.762944 -305.654381)
			(xy 416.801065 -305.623256) (xy 416.843686 -305.598649) (xy 416.889702 -305.581197) (xy 416.937921 -305.571353)
			(xy 416.987096 -305.569372) (xy 417.035951 -305.575304) (xy 417.083222 -305.588996) (xy 417.127684 -305.610094)
			(xy 417.168187 -305.63805) (xy 417.20368 -305.672142) (xy 417.233245 -305.711486) (xy 417.256116 -305.755063)
			(xy 417.2717 -305.801744) (xy 417.279595 -305.850321) (xy 417.28009 -305.874928) (xy 417.619192 -305.874928)
			(xy 417.623152 -305.825874) (xy 417.634929 -305.77809) (xy 417.65422 -305.732814) (xy 417.680523 -305.691218)
			(xy 417.713158 -305.654381) (xy 417.751279 -305.623256) (xy 417.7939 -305.598649) (xy 417.839916 -305.581197)
			(xy 417.888135 -305.571353) (xy 417.93731 -305.569372) (xy 417.986165 -305.575304) (xy 418.033436 -305.588996)
			(xy 418.077898 -305.610094) (xy 418.118401 -305.63805) (xy 418.153894 -305.672142) (xy 418.183459 -305.711486)
			(xy 418.20633 -305.755063) (xy 418.221914 -305.801744) (xy 418.229809 -305.850321) (xy 418.230304 -305.874928)
			(xy 418.569152 -305.874928) (xy 418.573112 -305.825874) (xy 418.584889 -305.77809) (xy 418.60418 -305.732814)
			(xy 418.630483 -305.691218) (xy 418.663118 -305.654381) (xy 418.701239 -305.623256) (xy 418.74386 -305.598649)
			(xy 418.789876 -305.581197) (xy 418.838095 -305.571353) (xy 418.88727 -305.569372) (xy 418.936125 -305.575304)
			(xy 418.983396 -305.588996) (xy 419.027858 -305.610094) (xy 419.068361 -305.63805) (xy 419.103854 -305.672142)
			(xy 419.133419 -305.711486) (xy 419.15629 -305.755063) (xy 419.171874 -305.801744) (xy 419.179769 -305.850321)
			(xy 419.180264 -305.874928) (xy 419.519112 -305.874928) (xy 419.523072 -305.825874) (xy 419.534849 -305.77809)
			(xy 419.55414 -305.732814) (xy 419.580443 -305.691218) (xy 419.613078 -305.654381) (xy 419.651199 -305.623256)
			(xy 419.69382 -305.598649) (xy 419.739836 -305.581197) (xy 419.788055 -305.571353) (xy 419.83723 -305.569372)
			(xy 419.886085 -305.575304) (xy 419.933356 -305.588996) (xy 419.977818 -305.610094) (xy 420.018321 -305.63805)
			(xy 420.053814 -305.672142) (xy 420.083379 -305.711486) (xy 420.10625 -305.755063) (xy 420.121834 -305.801744)
			(xy 420.129729 -305.850321) (xy 420.130224 -305.874928) (xy 420.469072 -305.874928) (xy 420.473032 -305.825874)
			(xy 420.484809 -305.77809) (xy 420.5041 -305.732814) (xy 420.530403 -305.691218) (xy 420.563038 -305.654381)
			(xy 420.601159 -305.623256) (xy 420.64378 -305.598649) (xy 420.689796 -305.581197) (xy 420.738015 -305.571353)
			(xy 420.78719 -305.569372) (xy 420.836045 -305.575304) (xy 420.883316 -305.588996) (xy 420.927778 -305.610094)
			(xy 420.968281 -305.63805) (xy 421.003774 -305.672142) (xy 421.033339 -305.711486) (xy 421.05621 -305.755063)
			(xy 421.071794 -305.801744) (xy 421.079689 -305.850321) (xy 421.080184 -305.874928) (xy 421.419032 -305.874928)
			(xy 421.422992 -305.825874) (xy 421.434769 -305.77809) (xy 421.45406 -305.732814) (xy 421.480363 -305.691218)
			(xy 421.512998 -305.654381) (xy 421.551119 -305.623256) (xy 421.59374 -305.598649) (xy 421.639756 -305.581197)
			(xy 421.687975 -305.571353) (xy 421.73715 -305.569372) (xy 421.786005 -305.575304) (xy 421.833276 -305.588996)
			(xy 421.877738 -305.610094) (xy 421.918241 -305.63805) (xy 421.953734 -305.672142) (xy 421.983299 -305.711486)
			(xy 422.00617 -305.755063) (xy 422.021754 -305.801744) (xy 422.029649 -305.850321) (xy 422.030143 -305.8749)
			(xy 422.368997 -305.8749) (xy 422.373168 -305.824567) (xy 422.385566 -305.775607) (xy 422.405854 -305.729355)
			(xy 422.433477 -305.687073) (xy 422.467684 -305.649915) (xy 422.507539 -305.618893) (xy 422.551958 -305.594855)
			(xy 422.599727 -305.578455) (xy 422.649543 -305.570142) (xy 422.674796 -305.56962) (xy 422.689043 -305.569789)
			(xy 422.717411 -305.572457) (xy 422.731438 -305.574954) (xy 422.743884 -305.57724) (xy 422.767506 -305.569874)
			(xy 422.836086 -305.501548) (xy 422.844229 -305.4923) (xy 422.851545 -305.468819) (xy 422.850056 -305.45659)
			(xy 422.850056 -305.456082) (xy 422.847594 -305.442178) (xy 422.844922 -305.414067) (xy 422.844722 -305.399948)
			(xy 422.845126 -305.375123) (xy 422.853151 -305.326125) (xy 422.868997 -305.279072) (xy 422.892247 -305.235202)
			(xy 422.922288 -305.195671) (xy 422.958329 -305.161521) (xy 422.99942 -305.133652) (xy 423.044478 -305.112798)
			(xy 423.092316 -305.099509) (xy 423.141675 -305.094134) (xy 423.191253 -305.096815) (xy 423.239743 -305.107482)
			(xy 423.28587 -305.125853) (xy 423.328416 -305.151445) (xy 423.366262 -305.183583) (xy 423.398409 -305.22142)
			(xy 423.424012 -305.26396) (xy 423.442395 -305.310082) (xy 423.453074 -305.35857) (xy 423.455322 -305.399948)
			(xy 423.794186 -305.399948) (xy 423.798146 -305.350894) (xy 423.809923 -305.30311) (xy 423.829214 -305.257834)
			(xy 423.855517 -305.216238) (xy 423.888152 -305.179401) (xy 423.926273 -305.148276) (xy 423.968894 -305.123669)
			(xy 424.01491 -305.106217) (xy 424.063129 -305.096373) (xy 424.112304 -305.094392) (xy 424.161159 -305.100324)
			(xy 424.20843 -305.114016) (xy 424.252892 -305.135114) (xy 424.293395 -305.16307) (xy 424.328888 -305.197162)
			(xy 424.358453 -305.236506) (xy 424.381324 -305.280083) (xy 424.396908 -305.326764) (xy 424.404803 -305.375341)
			(xy 424.405298 -305.399948) (xy 424.404803 -305.424555) (xy 424.396908 -305.473132) (xy 424.381324 -305.519813)
			(xy 424.358453 -305.56339) (xy 424.328888 -305.602734) (xy 424.293395 -305.636826) (xy 424.252892 -305.664782)
			(xy 424.20843 -305.68588) (xy 424.161159 -305.699572) (xy 424.112304 -305.705504) (xy 424.063129 -305.703523)
			(xy 424.01491 -305.693679) (xy 423.968894 -305.676227) (xy 423.926273 -305.65162) (xy 423.888152 -305.620495)
			(xy 423.855517 -305.583658) (xy 423.829214 -305.542062) (xy 423.809923 -305.496786) (xy 423.798146 -305.449002)
			(xy 423.794186 -305.399948) (xy 423.455322 -305.399948) (xy 423.455768 -305.408147) (xy 423.450406 -305.457507)
			(xy 423.437129 -305.505349) (xy 423.416286 -305.550412) (xy 423.388428 -305.59151) (xy 423.354287 -305.62756)
			(xy 423.314764 -305.657611) (xy 423.2709 -305.680872) (xy 423.22385 -305.696731) (xy 423.174855 -305.704768)
			(xy 423.15003 -305.705256) (xy 423.135783 -305.705098) (xy 423.107415 -305.702423) (xy 423.093388 -305.699922)
			(xy 423.080942 -305.697636) (xy 423.05732 -305.705002) (xy 422.98874 -305.773328) (xy 422.980558 -305.782547)
			(xy 422.973263 -305.806051) (xy 422.97477 -305.818286) (xy 422.97477 -305.818794) (xy 422.977229 -305.832698)
			(xy 422.979903 -305.860809) (xy 422.980104 -305.874928) (xy 422.980104 -305.875182) (xy 422.980027 -305.884989)
			(xy 422.978754 -305.904563) (xy 422.977564 -305.914298) (xy 422.976658 -305.926224) (xy 422.984625 -305.948748)
			(xy 422.992804 -305.957478) (xy 423.051478 -306.01412) (xy 423.060578 -306.021948) (xy 423.083498 -306.028974)
			(xy 423.09542 -306.027582) (xy 423.108902 -306.025377) (xy 423.136116 -306.022958) (xy 423.149776 -306.022756)
			(xy 423.150284 -306.022756) (xy 423.175961 -306.023357) (xy 423.226676 -306.031433) (xy 423.275505 -306.047339)
			(xy 423.321246 -306.070687) (xy 423.362772 -306.1009) (xy 423.399063 -306.137235) (xy 423.429225 -306.178799)
			(xy 423.452515 -306.224569) (xy 423.468362 -306.273417) (xy 423.476374 -306.324143) (xy 423.476356 -306.375497)
			(xy 423.476337 -306.375616) (xy 423.773342 -306.375616) (xy 423.773342 -306.3242) (xy 423.781385 -306.273418)
			(xy 423.797273 -306.224519) (xy 423.820616 -306.178707) (xy 423.850837 -306.137111) (xy 423.887193 -306.100755)
			(xy 423.928789 -306.070534) (xy 423.974601 -306.047191) (xy 424.0235 -306.031303) (xy 424.074282 -306.02326)
			(xy 424.125698 -306.02326) (xy 424.17648 -306.031303) (xy 424.225379 -306.047191) (xy 424.271191 -306.070534)
			(xy 424.312787 -306.100755) (xy 424.349143 -306.137111) (xy 424.379364 -306.178707) (xy 424.402707 -306.224519)
			(xy 424.418595 -306.273418) (xy 424.426638 -306.3242) (xy 424.427142 -306.349908) (xy 424.426638 -306.375616)
			(xy 424.418595 -306.426398) (xy 424.402707 -306.475297) (xy 424.379364 -306.521109) (xy 424.349143 -306.562705)
			(xy 424.312787 -306.599061) (xy 424.271191 -306.629282) (xy 424.225379 -306.652625) (xy 424.17648 -306.668513)
			(xy 424.125698 -306.676556) (xy 424.074282 -306.676556) (xy 424.0235 -306.668513) (xy 423.974601 -306.652625)
			(xy 423.928789 -306.629282) (xy 423.887193 -306.599061) (xy 423.850837 -306.562705) (xy 423.820616 -306.521109)
			(xy 423.797273 -306.475297) (xy 423.781385 -306.426398) (xy 423.773342 -306.375616) (xy 423.476337 -306.375616)
			(xy 423.468306 -306.426217) (xy 423.452423 -306.475054) (xy 423.429099 -306.520806) (xy 423.398907 -306.562347)
			(xy 423.362589 -306.598656) (xy 423.321041 -306.628839) (xy 423.275283 -306.652153) (xy 423.226443 -306.668024)
			(xy 423.175721 -306.676062) (xy 423.124367 -306.676068) (xy 423.073643 -306.668044) (xy 423.024798 -306.652186)
			(xy 422.979034 -306.628885) (xy 422.937478 -306.598713) (xy 422.901151 -306.562414) (xy 422.870947 -306.520881)
			(xy 422.84761 -306.475135) (xy 422.831715 -306.426302) (xy 422.823651 -306.375585) (xy 422.823132 -306.349908)
			(xy 422.823132 -306.349654) (xy 422.82329 -306.336) (xy 422.825576 -306.308786) (xy 422.827704 -306.295298)
			(xy 422.828991 -306.283501) (xy 422.82198 -306.26086) (xy 422.814242 -306.251864) (xy 422.757346 -306.192936)
			(xy 422.748635 -306.184731) (xy 422.726098 -306.176778) (xy 422.714166 -306.177696) (xy 422.70443 -306.178875)
			(xy 422.684857 -306.180147) (xy 422.67505 -306.180236) (xy 422.674796 -306.180236) (xy 422.649543 -306.179658)
			(xy 422.599727 -306.171345) (xy 422.551958 -306.154945) (xy 422.507539 -306.130907) (xy 422.467684 -306.099885)
			(xy 422.433477 -306.062727) (xy 422.405854 -306.020445) (xy 422.385566 -305.974193) (xy 422.373168 -305.925233)
			(xy 422.368997 -305.8749) (xy 422.030143 -305.8749) (xy 422.030144 -305.874928) (xy 422.029649 -305.899535)
			(xy 422.021754 -305.948112) (xy 422.00617 -305.994793) (xy 421.983299 -306.03837) (xy 421.953734 -306.077714)
			(xy 421.918241 -306.111806) (xy 421.877738 -306.139762) (xy 421.833276 -306.16086) (xy 421.786005 -306.174552)
			(xy 421.73715 -306.180484) (xy 421.687975 -306.178503) (xy 421.639756 -306.168659) (xy 421.59374 -306.151207)
			(xy 421.551119 -306.1266) (xy 421.512998 -306.095475) (xy 421.480363 -306.058638) (xy 421.45406 -306.017042)
			(xy 421.434769 -305.971766) (xy 421.422992 -305.923982) (xy 421.419032 -305.874928) (xy 421.080184 -305.874928)
			(xy 421.079689 -305.899535) (xy 421.071794 -305.948112) (xy 421.05621 -305.994793) (xy 421.033339 -306.03837)
			(xy 421.003774 -306.077714) (xy 420.968281 -306.111806) (xy 420.927778 -306.139762) (xy 420.883316 -306.16086)
			(xy 420.836045 -306.174552) (xy 420.78719 -306.180484) (xy 420.738015 -306.178503) (xy 420.689796 -306.168659)
			(xy 420.64378 -306.151207) (xy 420.601159 -306.1266) (xy 420.563038 -306.095475) (xy 420.530403 -306.058638)
			(xy 420.5041 -306.017042) (xy 420.484809 -305.971766) (xy 420.473032 -305.923982) (xy 420.469072 -305.874928)
			(xy 420.130224 -305.874928) (xy 420.129729 -305.899535) (xy 420.121834 -305.948112) (xy 420.10625 -305.994793)
			(xy 420.083379 -306.03837) (xy 420.053814 -306.077714) (xy 420.018321 -306.111806) (xy 419.977818 -306.139762)
			(xy 419.933356 -306.16086) (xy 419.886085 -306.174552) (xy 419.83723 -306.180484) (xy 419.788055 -306.178503)
			(xy 419.739836 -306.168659) (xy 419.69382 -306.151207) (xy 419.651199 -306.1266) (xy 419.613078 -306.095475)
			(xy 419.580443 -306.058638) (xy 419.55414 -306.017042) (xy 419.534849 -305.971766) (xy 419.523072 -305.923982)
			(xy 419.519112 -305.874928) (xy 419.180264 -305.874928) (xy 419.179769 -305.899535) (xy 419.171874 -305.948112)
			(xy 419.15629 -305.994793) (xy 419.133419 -306.03837) (xy 419.103854 -306.077714) (xy 419.068361 -306.111806)
			(xy 419.027858 -306.139762) (xy 418.983396 -306.16086) (xy 418.936125 -306.174552) (xy 418.88727 -306.180484)
			(xy 418.838095 -306.178503) (xy 418.789876 -306.168659) (xy 418.74386 -306.151207) (xy 418.701239 -306.1266)
			(xy 418.663118 -306.095475) (xy 418.630483 -306.058638) (xy 418.60418 -306.017042) (xy 418.584889 -305.971766)
			(xy 418.573112 -305.923982) (xy 418.569152 -305.874928) (xy 418.230304 -305.874928) (xy 418.229809 -305.899535)
			(xy 418.221914 -305.948112) (xy 418.20633 -305.994793) (xy 418.183459 -306.03837) (xy 418.153894 -306.077714)
			(xy 418.118401 -306.111806) (xy 418.077898 -306.139762) (xy 418.033436 -306.16086) (xy 417.986165 -306.174552)
			(xy 417.93731 -306.180484) (xy 417.888135 -306.178503) (xy 417.839916 -306.168659) (xy 417.7939 -306.151207)
			(xy 417.751279 -306.1266) (xy 417.713158 -306.095475) (xy 417.680523 -306.058638) (xy 417.65422 -306.017042)
			(xy 417.634929 -305.971766) (xy 417.623152 -305.923982) (xy 417.619192 -305.874928) (xy 417.28009 -305.874928)
			(xy 417.279595 -305.899535) (xy 417.2717 -305.948112) (xy 417.256116 -305.994793) (xy 417.233245 -306.03837)
			(xy 417.20368 -306.077714) (xy 417.168187 -306.111806) (xy 417.127684 -306.139762) (xy 417.083222 -306.16086)
			(xy 417.035951 -306.174552) (xy 416.987096 -306.180484) (xy 416.937921 -306.178503) (xy 416.889702 -306.168659)
			(xy 416.843686 -306.151207) (xy 416.801065 -306.1266) (xy 416.762944 -306.095475) (xy 416.730309 -306.058638)
			(xy 416.704006 -306.017042) (xy 416.684715 -305.971766) (xy 416.672938 -305.923982) (xy 416.668978 -305.874928)
			(xy 416.33013 -305.874928) (xy 416.329635 -305.899535) (xy 416.32174 -305.948112) (xy 416.306156 -305.994793)
			(xy 416.283285 -306.03837) (xy 416.25372 -306.077714) (xy 416.218227 -306.111806) (xy 416.177724 -306.139762)
			(xy 416.133262 -306.16086) (xy 416.085991 -306.174552) (xy 416.037136 -306.180484) (xy 415.987961 -306.178503)
			(xy 415.939742 -306.168659) (xy 415.893726 -306.151207) (xy 415.851105 -306.1266) (xy 415.812984 -306.095475)
			(xy 415.780349 -306.058638) (xy 415.754046 -306.017042) (xy 415.734755 -305.971766) (xy 415.722978 -305.923982)
			(xy 415.719018 -305.874928) (xy 415.38017 -305.874928) (xy 415.379675 -305.899535) (xy 415.37178 -305.948112)
			(xy 415.356196 -305.994793) (xy 415.333325 -306.03837) (xy 415.30376 -306.077714) (xy 415.268267 -306.111806)
			(xy 415.227764 -306.139762) (xy 415.183302 -306.16086) (xy 415.136031 -306.174552) (xy 415.087176 -306.180484)
			(xy 415.038001 -306.178503) (xy 414.989782 -306.168659) (xy 414.943766 -306.151207) (xy 414.901145 -306.1266)
			(xy 414.863024 -306.095475) (xy 414.830389 -306.058638) (xy 414.804086 -306.017042) (xy 414.784795 -305.971766)
			(xy 414.773018 -305.923982) (xy 414.769058 -305.874928) (xy 414.43021 -305.874928) (xy 414.429715 -305.899535)
			(xy 414.42182 -305.948112) (xy 414.406236 -305.994793) (xy 414.383365 -306.03837) (xy 414.3538 -306.077714)
			(xy 414.318307 -306.111806) (xy 414.277804 -306.139762) (xy 414.233342 -306.16086) (xy 414.186071 -306.174552)
			(xy 414.137216 -306.180484) (xy 414.088041 -306.178503) (xy 414.039822 -306.168659) (xy 413.993806 -306.151207)
			(xy 413.951185 -306.1266) (xy 413.913064 -306.095475) (xy 413.880429 -306.058638) (xy 413.854126 -306.017042)
			(xy 413.834835 -305.971766) (xy 413.823058 -305.923982) (xy 413.819098 -305.874928) (xy 413.48025 -305.874928)
			(xy 413.479755 -305.899535) (xy 413.47186 -305.948112) (xy 413.456276 -305.994793) (xy 413.433405 -306.03837)
			(xy 413.40384 -306.077714) (xy 413.368347 -306.111806) (xy 413.327844 -306.139762) (xy 413.283382 -306.16086)
			(xy 413.236111 -306.174552) (xy 413.187256 -306.180484) (xy 413.138081 -306.178503) (xy 413.089862 -306.168659)
			(xy 413.043846 -306.151207) (xy 413.001225 -306.1266) (xy 412.963104 -306.095475) (xy 412.930469 -306.058638)
			(xy 412.904166 -306.017042) (xy 412.884875 -305.971766) (xy 412.873098 -305.923982) (xy 412.869138 -305.874928)
			(xy 412.53029 -305.874928) (xy 412.529795 -305.899535) (xy 412.5219 -305.948112) (xy 412.506316 -305.994793)
			(xy 412.483445 -306.03837) (xy 412.45388 -306.077714) (xy 412.418387 -306.111806) (xy 412.377884 -306.139762)
			(xy 412.333422 -306.16086) (xy 412.286151 -306.174552) (xy 412.237296 -306.180484) (xy 412.188121 -306.178503)
			(xy 412.139902 -306.168659) (xy 412.093886 -306.151207) (xy 412.051265 -306.1266) (xy 412.013144 -306.095475)
			(xy 411.980509 -306.058638) (xy 411.954206 -306.017042) (xy 411.934915 -305.971766) (xy 411.923138 -305.923982)
			(xy 411.919178 -305.874928) (xy 411.58033 -305.874928) (xy 411.579835 -305.899535) (xy 411.57194 -305.948112)
			(xy 411.556356 -305.994793) (xy 411.533485 -306.03837) (xy 411.50392 -306.077714) (xy 411.468427 -306.111806)
			(xy 411.427924 -306.139762) (xy 411.383462 -306.16086) (xy 411.336191 -306.174552) (xy 411.287336 -306.180484)
			(xy 411.238161 -306.178503) (xy 411.189942 -306.168659) (xy 411.143926 -306.151207) (xy 411.101305 -306.1266)
			(xy 411.063184 -306.095475) (xy 411.030549 -306.058638) (xy 411.004246 -306.017042) (xy 410.984955 -305.971766)
			(xy 410.973178 -305.923982) (xy 410.969218 -305.874928) (xy 410.630116 -305.874928) (xy 410.629621 -305.899535)
			(xy 410.621726 -305.948112) (xy 410.606142 -305.994793) (xy 410.583271 -306.03837) (xy 410.553706 -306.077714)
			(xy 410.518213 -306.111806) (xy 410.47771 -306.139762) (xy 410.433248 -306.16086) (xy 410.385977 -306.174552)
			(xy 410.337122 -306.180484) (xy 410.287947 -306.178503) (xy 410.239728 -306.168659) (xy 410.193712 -306.151207)
			(xy 410.151091 -306.1266) (xy 410.11297 -306.095475) (xy 410.080335 -306.058638) (xy 410.054032 -306.017042)
			(xy 410.034741 -305.971766) (xy 410.022964 -305.923982) (xy 410.019004 -305.874928) (xy 409.680156 -305.874928)
			(xy 409.679661 -305.899535) (xy 409.671766 -305.948112) (xy 409.656182 -305.994793) (xy 409.633311 -306.03837)
			(xy 409.603746 -306.077714) (xy 409.568253 -306.111806) (xy 409.52775 -306.139762) (xy 409.483288 -306.16086)
			(xy 409.436017 -306.174552) (xy 409.387162 -306.180484) (xy 409.337987 -306.178503) (xy 409.289768 -306.168659)
			(xy 409.243752 -306.151207) (xy 409.201131 -306.1266) (xy 409.16301 -306.095475) (xy 409.130375 -306.058638)
			(xy 409.104072 -306.017042) (xy 409.084781 -305.971766) (xy 409.073004 -305.923982) (xy 409.069044 -305.874928)
			(xy 408.730196 -305.874928) (xy 408.729701 -305.899535) (xy 408.721806 -305.948112) (xy 408.706222 -305.994793)
			(xy 408.683351 -306.03837) (xy 408.653786 -306.077714) (xy 408.618293 -306.111806) (xy 408.57779 -306.139762)
			(xy 408.533328 -306.16086) (xy 408.486057 -306.174552) (xy 408.437202 -306.180484) (xy 408.388027 -306.178503)
			(xy 408.339808 -306.168659) (xy 408.293792 -306.151207) (xy 408.251171 -306.1266) (xy 408.21305 -306.095475)
			(xy 408.180415 -306.058638) (xy 408.154112 -306.017042) (xy 408.134821 -305.971766) (xy 408.123044 -305.923982)
			(xy 408.119084 -305.874928) (xy 406.830276 -305.874928) (xy 406.829781 -305.899535) (xy 406.821886 -305.948112)
			(xy 406.806302 -305.994793) (xy 406.783431 -306.03837) (xy 406.753866 -306.077714) (xy 406.718373 -306.111806)
			(xy 406.67787 -306.139762) (xy 406.633408 -306.16086) (xy 406.586137 -306.174552) (xy 406.537282 -306.180484)
			(xy 406.488107 -306.178503) (xy 406.439888 -306.168659) (xy 406.393872 -306.151207) (xy 406.351251 -306.1266)
			(xy 406.31313 -306.095475) (xy 406.280495 -306.058638) (xy 406.254192 -306.017042) (xy 406.234901 -305.971766)
			(xy 406.223124 -305.923982) (xy 406.219164 -305.874928) (xy 405.880316 -305.874928) (xy 405.879821 -305.899535)
			(xy 405.871926 -305.948112) (xy 405.856342 -305.994793) (xy 405.833471 -306.03837) (xy 405.803906 -306.077714)
			(xy 405.768413 -306.111806) (xy 405.72791 -306.139762) (xy 405.683448 -306.16086) (xy 405.636177 -306.174552)
			(xy 405.587322 -306.180484) (xy 405.538147 -306.178503) (xy 405.489928 -306.168659) (xy 405.443912 -306.151207)
			(xy 405.401291 -306.1266) (xy 405.36317 -306.095475) (xy 405.330535 -306.058638) (xy 405.304232 -306.017042)
			(xy 405.284941 -305.971766) (xy 405.273164 -305.923982) (xy 405.269204 -305.874928) (xy 404.930102 -305.874928)
			(xy 404.929607 -305.899535) (xy 404.921712 -305.948112) (xy 404.906128 -305.994793) (xy 404.883257 -306.03837)
			(xy 404.853692 -306.077714) (xy 404.818199 -306.111806) (xy 404.777696 -306.139762) (xy 404.733234 -306.16086)
			(xy 404.685963 -306.174552) (xy 404.637108 -306.180484) (xy 404.587933 -306.178503) (xy 404.539714 -306.168659)
			(xy 404.493698 -306.151207) (xy 404.451077 -306.1266) (xy 404.412956 -306.095475) (xy 404.380321 -306.058638)
			(xy 404.354018 -306.017042) (xy 404.334727 -305.971766) (xy 404.32295 -305.923982) (xy 404.31899 -305.874928)
			(xy 403.980142 -305.874928) (xy 403.979647 -305.899535) (xy 403.971752 -305.948112) (xy 403.956168 -305.994793)
			(xy 403.933297 -306.03837) (xy 403.903732 -306.077714) (xy 403.868239 -306.111806) (xy 403.827736 -306.139762)
			(xy 403.783274 -306.16086) (xy 403.736003 -306.174552) (xy 403.687148 -306.180484) (xy 403.637973 -306.178503)
			(xy 403.589754 -306.168659) (xy 403.543738 -306.151207) (xy 403.501117 -306.1266) (xy 403.462996 -306.095475)
			(xy 403.430361 -306.058638) (xy 403.404058 -306.017042) (xy 403.384767 -305.971766) (xy 403.37299 -305.923982)
			(xy 403.36903 -305.874928) (xy 403.030182 -305.874928) (xy 403.029687 -305.899535) (xy 403.021792 -305.948112)
			(xy 403.006208 -305.994793) (xy 402.983337 -306.03837) (xy 402.953772 -306.077714) (xy 402.918279 -306.111806)
			(xy 402.877776 -306.139762) (xy 402.833314 -306.16086) (xy 402.786043 -306.174552) (xy 402.737188 -306.180484)
			(xy 402.688013 -306.178503) (xy 402.639794 -306.168659) (xy 402.593778 -306.151207) (xy 402.551157 -306.1266)
			(xy 402.513036 -306.095475) (xy 402.480401 -306.058638) (xy 402.454098 -306.017042) (xy 402.434807 -305.971766)
			(xy 402.42303 -305.923982) (xy 402.41907 -305.874928) (xy 402.080222 -305.874928) (xy 402.079727 -305.899535)
			(xy 402.071832 -305.948112) (xy 402.056248 -305.994793) (xy 402.033377 -306.03837) (xy 402.003812 -306.077714)
			(xy 401.968319 -306.111806) (xy 401.927816 -306.139762) (xy 401.883354 -306.16086) (xy 401.836083 -306.174552)
			(xy 401.787228 -306.180484) (xy 401.738053 -306.178503) (xy 401.689834 -306.168659) (xy 401.643818 -306.151207)
			(xy 401.601197 -306.1266) (xy 401.563076 -306.095475) (xy 401.530441 -306.058638) (xy 401.504138 -306.017042)
			(xy 401.484847 -305.971766) (xy 401.47307 -305.923982) (xy 401.46911 -305.874928) (xy 401.130262 -305.874928)
			(xy 401.129767 -305.899535) (xy 401.121872 -305.948112) (xy 401.106288 -305.994793) (xy 401.083417 -306.03837)
			(xy 401.053852 -306.077714) (xy 401.018359 -306.111806) (xy 400.977856 -306.139762) (xy 400.933394 -306.16086)
			(xy 400.886123 -306.174552) (xy 400.837268 -306.180484) (xy 400.788093 -306.178503) (xy 400.739874 -306.168659)
			(xy 400.693858 -306.151207) (xy 400.651237 -306.1266) (xy 400.613116 -306.095475) (xy 400.580481 -306.058638)
			(xy 400.554178 -306.017042) (xy 400.534887 -305.971766) (xy 400.52311 -305.923982) (xy 400.51915 -305.874928)
			(xy 400.180302 -305.874928) (xy 400.179807 -305.899535) (xy 400.171912 -305.948112) (xy 400.156328 -305.994793)
			(xy 400.133457 -306.03837) (xy 400.103892 -306.077714) (xy 400.068399 -306.111806) (xy 400.027896 -306.139762)
			(xy 399.983434 -306.16086) (xy 399.936163 -306.174552) (xy 399.887308 -306.180484) (xy 399.838133 -306.178503)
			(xy 399.789914 -306.168659) (xy 399.743898 -306.151207) (xy 399.701277 -306.1266) (xy 399.663156 -306.095475)
			(xy 399.630521 -306.058638) (xy 399.604218 -306.017042) (xy 399.584927 -305.971766) (xy 399.57315 -305.923982)
			(xy 399.56919 -305.874928) (xy 399.230342 -305.874928) (xy 399.229847 -305.899535) (xy 399.221952 -305.948112)
			(xy 399.206368 -305.994793) (xy 399.183497 -306.03837) (xy 399.153932 -306.077714) (xy 399.118439 -306.111806)
			(xy 399.077936 -306.139762) (xy 399.033474 -306.16086) (xy 398.986203 -306.174552) (xy 398.937348 -306.180484)
			(xy 398.888173 -306.178503) (xy 398.839954 -306.168659) (xy 398.793938 -306.151207) (xy 398.751317 -306.1266)
			(xy 398.713196 -306.095475) (xy 398.680561 -306.058638) (xy 398.654258 -306.017042) (xy 398.634967 -305.971766)
			(xy 398.62319 -305.923982) (xy 398.61923 -305.874928) (xy 398.280128 -305.874928) (xy 398.279633 -305.899535)
			(xy 398.271738 -305.948112) (xy 398.256154 -305.994793) (xy 398.233283 -306.03837) (xy 398.203718 -306.077714)
			(xy 398.168225 -306.111806) (xy 398.127722 -306.139762) (xy 398.08326 -306.16086) (xy 398.035989 -306.174552)
			(xy 397.987134 -306.180484) (xy 397.937959 -306.178503) (xy 397.88974 -306.168659) (xy 397.843724 -306.151207)
			(xy 397.801103 -306.1266) (xy 397.762982 -306.095475) (xy 397.730347 -306.058638) (xy 397.704044 -306.017042)
			(xy 397.684753 -305.971766) (xy 397.672976 -305.923982) (xy 397.669016 -305.874928) (xy 397.330168 -305.874928)
			(xy 397.329673 -305.899535) (xy 397.321778 -305.948112) (xy 397.306194 -305.994793) (xy 397.283323 -306.03837)
			(xy 397.253758 -306.077714) (xy 397.218265 -306.111806) (xy 397.177762 -306.139762) (xy 397.1333 -306.16086)
			(xy 397.086029 -306.174552) (xy 397.037174 -306.180484) (xy 396.987999 -306.178503) (xy 396.93978 -306.168659)
			(xy 396.893764 -306.151207) (xy 396.851143 -306.1266) (xy 396.813022 -306.095475) (xy 396.780387 -306.058638)
			(xy 396.754084 -306.017042) (xy 396.734793 -305.971766) (xy 396.723016 -305.923982) (xy 396.719056 -305.874928)
			(xy 396.380208 -305.874928) (xy 396.379713 -305.899535) (xy 396.371818 -305.948112) (xy 396.356234 -305.994793)
			(xy 396.333363 -306.03837) (xy 396.303798 -306.077714) (xy 396.268305 -306.111806) (xy 396.227802 -306.139762)
			(xy 396.18334 -306.16086) (xy 396.136069 -306.174552) (xy 396.087214 -306.180484) (xy 396.038039 -306.178503)
			(xy 395.98982 -306.168659) (xy 395.943804 -306.151207) (xy 395.901183 -306.1266) (xy 395.863062 -306.095475)
			(xy 395.830427 -306.058638) (xy 395.804124 -306.017042) (xy 395.784833 -305.971766) (xy 395.773056 -305.923982)
			(xy 395.769096 -305.874928) (xy 395.430248 -305.874928) (xy 395.429753 -305.899535) (xy 395.421858 -305.948112)
			(xy 395.406274 -305.994793) (xy 395.383403 -306.03837) (xy 395.353838 -306.077714) (xy 395.318345 -306.111806)
			(xy 395.277842 -306.139762) (xy 395.23338 -306.16086) (xy 395.186109 -306.174552) (xy 395.137254 -306.180484)
			(xy 395.088079 -306.178503) (xy 395.03986 -306.168659) (xy 394.993844 -306.151207) (xy 394.951223 -306.1266)
			(xy 394.913102 -306.095475) (xy 394.880467 -306.058638) (xy 394.854164 -306.017042) (xy 394.834873 -305.971766)
			(xy 394.823096 -305.923982) (xy 394.819136 -305.874928) (xy 389.255 -305.874928) (xy 389.255 -306.341526)
			(xy 389.255254 -306.349146) (xy 389.255254 -306.349908) (xy 389.594102 -306.349908) (xy 389.598062 -306.300854)
			(xy 389.609839 -306.25307) (xy 389.62913 -306.207794) (xy 389.655433 -306.166198) (xy 389.688068 -306.129361)
			(xy 389.726189 -306.098236) (xy 389.76881 -306.073629) (xy 389.814826 -306.056177) (xy 389.863045 -306.046333)
			(xy 389.91222 -306.044352) (xy 389.961075 -306.050284) (xy 390.008346 -306.063976) (xy 390.052808 -306.085074)
			(xy 390.093311 -306.11303) (xy 390.128804 -306.147122) (xy 390.158369 -306.186466) (xy 390.18124 -306.230043)
			(xy 390.196824 -306.276724) (xy 390.204719 -306.325301) (xy 390.205214 -306.349908) (xy 390.544062 -306.349908)
			(xy 390.548022 -306.300854) (xy 390.559799 -306.25307) (xy 390.57909 -306.207794) (xy 390.605393 -306.166198)
			(xy 390.638028 -306.129361) (xy 390.676149 -306.098236) (xy 390.71877 -306.073629) (xy 390.764786 -306.056177)
			(xy 390.813005 -306.046333) (xy 390.86218 -306.044352) (xy 390.911035 -306.050284) (xy 390.958306 -306.063976)
			(xy 391.002768 -306.085074) (xy 391.043271 -306.11303) (xy 391.078764 -306.147122) (xy 391.108329 -306.186466)
			(xy 391.1312 -306.230043) (xy 391.146784 -306.276724) (xy 391.154679 -306.325301) (xy 391.155174 -306.349908)
			(xy 391.494022 -306.349908) (xy 391.497982 -306.300854) (xy 391.509759 -306.25307) (xy 391.52905 -306.207794)
			(xy 391.555353 -306.166198) (xy 391.587988 -306.129361) (xy 391.626109 -306.098236) (xy 391.66873 -306.073629)
			(xy 391.714746 -306.056177) (xy 391.762965 -306.046333) (xy 391.81214 -306.044352) (xy 391.860995 -306.050284)
			(xy 391.908266 -306.063976) (xy 391.952728 -306.085074) (xy 391.993231 -306.11303) (xy 392.028724 -306.147122)
			(xy 392.058289 -306.186466) (xy 392.08116 -306.230043) (xy 392.096744 -306.276724) (xy 392.104639 -306.325301)
			(xy 392.105134 -306.349908) (xy 392.443982 -306.349908) (xy 392.447942 -306.300854) (xy 392.459719 -306.25307)
			(xy 392.47901 -306.207794) (xy 392.505313 -306.166198) (xy 392.537948 -306.129361) (xy 392.576069 -306.098236)
			(xy 392.61869 -306.073629) (xy 392.664706 -306.056177) (xy 392.712925 -306.046333) (xy 392.7621 -306.044352)
			(xy 392.810955 -306.050284) (xy 392.858226 -306.063976) (xy 392.902688 -306.085074) (xy 392.943191 -306.11303)
			(xy 392.978684 -306.147122) (xy 393.008249 -306.186466) (xy 393.03112 -306.230043) (xy 393.046704 -306.276724)
			(xy 393.054599 -306.325301) (xy 393.055094 -306.349908) (xy 393.394196 -306.349908) (xy 393.398156 -306.300854)
			(xy 393.409933 -306.25307) (xy 393.429224 -306.207794) (xy 393.455527 -306.166198) (xy 393.488162 -306.129361)
			(xy 393.526283 -306.098236) (xy 393.568904 -306.073629) (xy 393.61492 -306.056177) (xy 393.663139 -306.046333)
			(xy 393.712314 -306.044352) (xy 393.761169 -306.050284) (xy 393.80844 -306.063976) (xy 393.852902 -306.085074)
			(xy 393.893405 -306.11303) (xy 393.928898 -306.147122) (xy 393.958463 -306.186466) (xy 393.981334 -306.230043)
			(xy 393.996918 -306.276724) (xy 394.004813 -306.325301) (xy 394.005308 -306.349908) (xy 394.004813 -306.374515)
			(xy 393.996918 -306.423092) (xy 393.981334 -306.469773) (xy 393.958463 -306.51335) (xy 393.928898 -306.552694)
			(xy 393.893405 -306.586786) (xy 393.852902 -306.614742) (xy 393.80844 -306.63584) (xy 393.761169 -306.649532)
			(xy 393.712314 -306.655464) (xy 393.663139 -306.653483) (xy 393.61492 -306.643639) (xy 393.568904 -306.626187)
			(xy 393.526283 -306.60158) (xy 393.488162 -306.570455) (xy 393.455527 -306.533618) (xy 393.429224 -306.492022)
			(xy 393.409933 -306.446746) (xy 393.398156 -306.398962) (xy 393.394196 -306.349908) (xy 393.055094 -306.349908)
			(xy 393.054599 -306.374515) (xy 393.046704 -306.423092) (xy 393.03112 -306.469773) (xy 393.008249 -306.51335)
			(xy 392.978684 -306.552694) (xy 392.943191 -306.586786) (xy 392.902688 -306.614742) (xy 392.858226 -306.63584)
			(xy 392.810955 -306.649532) (xy 392.7621 -306.655464) (xy 392.712925 -306.653483) (xy 392.664706 -306.643639)
			(xy 392.61869 -306.626187) (xy 392.576069 -306.60158) (xy 392.537948 -306.570455) (xy 392.505313 -306.533618)
			(xy 392.47901 -306.492022) (xy 392.459719 -306.446746) (xy 392.447942 -306.398962) (xy 392.443982 -306.349908)
			(xy 392.105134 -306.349908) (xy 392.104639 -306.374515) (xy 392.096744 -306.423092) (xy 392.08116 -306.469773)
			(xy 392.058289 -306.51335) (xy 392.028724 -306.552694) (xy 391.993231 -306.586786) (xy 391.952728 -306.614742)
			(xy 391.908266 -306.63584) (xy 391.860995 -306.649532) (xy 391.81214 -306.655464) (xy 391.762965 -306.653483)
			(xy 391.714746 -306.643639) (xy 391.66873 -306.626187) (xy 391.626109 -306.60158) (xy 391.587988 -306.570455)
			(xy 391.555353 -306.533618) (xy 391.52905 -306.492022) (xy 391.509759 -306.446746) (xy 391.497982 -306.398962)
			(xy 391.494022 -306.349908) (xy 391.155174 -306.349908) (xy 391.154679 -306.374515) (xy 391.146784 -306.423092)
			(xy 391.1312 -306.469773) (xy 391.108329 -306.51335) (xy 391.078764 -306.552694) (xy 391.043271 -306.586786)
			(xy 391.002768 -306.614742) (xy 390.958306 -306.63584) (xy 390.911035 -306.649532) (xy 390.86218 -306.655464)
			(xy 390.813005 -306.653483) (xy 390.764786 -306.643639) (xy 390.71877 -306.626187) (xy 390.676149 -306.60158)
			(xy 390.638028 -306.570455) (xy 390.605393 -306.533618) (xy 390.57909 -306.492022) (xy 390.559799 -306.446746)
			(xy 390.548022 -306.398962) (xy 390.544062 -306.349908) (xy 390.205214 -306.349908) (xy 390.204719 -306.374515)
			(xy 390.196824 -306.423092) (xy 390.18124 -306.469773) (xy 390.158369 -306.51335) (xy 390.128804 -306.552694)
			(xy 390.093311 -306.586786) (xy 390.052808 -306.614742) (xy 390.008346 -306.63584) (xy 389.961075 -306.649532)
			(xy 389.91222 -306.655464) (xy 389.863045 -306.653483) (xy 389.814826 -306.643639) (xy 389.76881 -306.626187)
			(xy 389.726189 -306.60158) (xy 389.688068 -306.570455) (xy 389.655433 -306.533618) (xy 389.62913 -306.492022)
			(xy 389.609839 -306.446746) (xy 389.598062 -306.398962) (xy 389.594102 -306.349908) (xy 389.255254 -306.349908)
			(xy 389.255254 -306.35067) (xy 389.255 -306.35829) (xy 389.255 -306.824888) (xy 394.819136 -306.824888)
			(xy 394.823096 -306.775834) (xy 394.834873 -306.72805) (xy 394.854164 -306.682774) (xy 394.880467 -306.641178)
			(xy 394.913102 -306.604341) (xy 394.951223 -306.573216) (xy 394.993844 -306.548609) (xy 395.03986 -306.531157)
			(xy 395.088079 -306.521313) (xy 395.137254 -306.519332) (xy 395.186109 -306.525264) (xy 395.23338 -306.538956)
			(xy 395.277842 -306.560054) (xy 395.318345 -306.58801) (xy 395.353838 -306.622102) (xy 395.383403 -306.661446)
			(xy 395.406274 -306.705023) (xy 395.421858 -306.751704) (xy 395.429753 -306.800281) (xy 395.430248 -306.824888)
			(xy 395.769096 -306.824888) (xy 395.773056 -306.775834) (xy 395.784833 -306.72805) (xy 395.804124 -306.682774)
			(xy 395.830427 -306.641178) (xy 395.863062 -306.604341) (xy 395.901183 -306.573216) (xy 395.943804 -306.548609)
			(xy 395.98982 -306.531157) (xy 396.038039 -306.521313) (xy 396.087214 -306.519332) (xy 396.136069 -306.525264)
			(xy 396.18334 -306.538956) (xy 396.227802 -306.560054) (xy 396.268305 -306.58801) (xy 396.303798 -306.622102)
			(xy 396.333363 -306.661446) (xy 396.356234 -306.705023) (xy 396.371818 -306.751704) (xy 396.379713 -306.800281)
			(xy 396.380208 -306.824888) (xy 396.719056 -306.824888) (xy 396.723016 -306.775834) (xy 396.734793 -306.72805)
			(xy 396.754084 -306.682774) (xy 396.780387 -306.641178) (xy 396.813022 -306.604341) (xy 396.851143 -306.573216)
			(xy 396.893764 -306.548609) (xy 396.93978 -306.531157) (xy 396.987999 -306.521313) (xy 397.037174 -306.519332)
			(xy 397.086029 -306.525264) (xy 397.1333 -306.538956) (xy 397.177762 -306.560054) (xy 397.218265 -306.58801)
			(xy 397.253758 -306.622102) (xy 397.283323 -306.661446) (xy 397.306194 -306.705023) (xy 397.321778 -306.751704)
			(xy 397.329673 -306.800281) (xy 397.330168 -306.824888) (xy 397.669016 -306.824888) (xy 397.672976 -306.775834)
			(xy 397.684753 -306.72805) (xy 397.704044 -306.682774) (xy 397.730347 -306.641178) (xy 397.762982 -306.604341)
			(xy 397.801103 -306.573216) (xy 397.843724 -306.548609) (xy 397.88974 -306.531157) (xy 397.937959 -306.521313)
			(xy 397.987134 -306.519332) (xy 398.035989 -306.525264) (xy 398.08326 -306.538956) (xy 398.127722 -306.560054)
			(xy 398.168225 -306.58801) (xy 398.203718 -306.622102) (xy 398.233283 -306.661446) (xy 398.256154 -306.705023)
			(xy 398.271738 -306.751704) (xy 398.279633 -306.800281) (xy 398.280128 -306.824888) (xy 398.61923 -306.824888)
			(xy 398.62319 -306.775834) (xy 398.634967 -306.72805) (xy 398.654258 -306.682774) (xy 398.680561 -306.641178)
			(xy 398.713196 -306.604341) (xy 398.751317 -306.573216) (xy 398.793938 -306.548609) (xy 398.839954 -306.531157)
			(xy 398.888173 -306.521313) (xy 398.937348 -306.519332) (xy 398.986203 -306.525264) (xy 399.033474 -306.538956)
			(xy 399.077936 -306.560054) (xy 399.118439 -306.58801) (xy 399.153932 -306.622102) (xy 399.183497 -306.661446)
			(xy 399.206368 -306.705023) (xy 399.221952 -306.751704) (xy 399.229847 -306.800281) (xy 399.230342 -306.824888)
			(xy 399.56919 -306.824888) (xy 399.57315 -306.775834) (xy 399.584927 -306.72805) (xy 399.604218 -306.682774)
			(xy 399.630521 -306.641178) (xy 399.663156 -306.604341) (xy 399.701277 -306.573216) (xy 399.743898 -306.548609)
			(xy 399.789914 -306.531157) (xy 399.838133 -306.521313) (xy 399.887308 -306.519332) (xy 399.936163 -306.525264)
			(xy 399.983434 -306.538956) (xy 400.027896 -306.560054) (xy 400.068399 -306.58801) (xy 400.103892 -306.622102)
			(xy 400.133457 -306.661446) (xy 400.156328 -306.705023) (xy 400.171912 -306.751704) (xy 400.179807 -306.800281)
			(xy 400.180302 -306.824888) (xy 400.51915 -306.824888) (xy 400.52311 -306.775834) (xy 400.534887 -306.72805)
			(xy 400.554178 -306.682774) (xy 400.580481 -306.641178) (xy 400.613116 -306.604341) (xy 400.651237 -306.573216)
			(xy 400.693858 -306.548609) (xy 400.739874 -306.531157) (xy 400.788093 -306.521313) (xy 400.837268 -306.519332)
			(xy 400.886123 -306.525264) (xy 400.933394 -306.538956) (xy 400.977856 -306.560054) (xy 401.018359 -306.58801)
			(xy 401.053852 -306.622102) (xy 401.083417 -306.661446) (xy 401.106288 -306.705023) (xy 401.121872 -306.751704)
			(xy 401.129767 -306.800281) (xy 401.130262 -306.824888) (xy 401.46911 -306.824888) (xy 401.47307 -306.775834)
			(xy 401.484847 -306.72805) (xy 401.504138 -306.682774) (xy 401.530441 -306.641178) (xy 401.563076 -306.604341)
			(xy 401.601197 -306.573216) (xy 401.643818 -306.548609) (xy 401.689834 -306.531157) (xy 401.738053 -306.521313)
			(xy 401.787228 -306.519332) (xy 401.836083 -306.525264) (xy 401.883354 -306.538956) (xy 401.927816 -306.560054)
			(xy 401.968319 -306.58801) (xy 402.003812 -306.622102) (xy 402.033377 -306.661446) (xy 402.056248 -306.705023)
			(xy 402.071832 -306.751704) (xy 402.079727 -306.800281) (xy 402.080222 -306.824888) (xy 402.41907 -306.824888)
			(xy 402.42303 -306.775834) (xy 402.434807 -306.72805) (xy 402.454098 -306.682774) (xy 402.480401 -306.641178)
			(xy 402.513036 -306.604341) (xy 402.551157 -306.573216) (xy 402.593778 -306.548609) (xy 402.639794 -306.531157)
			(xy 402.688013 -306.521313) (xy 402.737188 -306.519332) (xy 402.786043 -306.525264) (xy 402.833314 -306.538956)
			(xy 402.877776 -306.560054) (xy 402.918279 -306.58801) (xy 402.953772 -306.622102) (xy 402.983337 -306.661446)
			(xy 403.006208 -306.705023) (xy 403.021792 -306.751704) (xy 403.029687 -306.800281) (xy 403.030182 -306.824888)
			(xy 403.36903 -306.824888) (xy 403.37299 -306.775834) (xy 403.384767 -306.72805) (xy 403.404058 -306.682774)
			(xy 403.430361 -306.641178) (xy 403.462996 -306.604341) (xy 403.501117 -306.573216) (xy 403.543738 -306.548609)
			(xy 403.589754 -306.531157) (xy 403.637973 -306.521313) (xy 403.687148 -306.519332) (xy 403.736003 -306.525264)
			(xy 403.783274 -306.538956) (xy 403.827736 -306.560054) (xy 403.868239 -306.58801) (xy 403.903732 -306.622102)
			(xy 403.933297 -306.661446) (xy 403.956168 -306.705023) (xy 403.971752 -306.751704) (xy 403.979647 -306.800281)
			(xy 403.980142 -306.824888) (xy 404.31899 -306.824888) (xy 404.32295 -306.775834) (xy 404.334727 -306.72805)
			(xy 404.354018 -306.682774) (xy 404.380321 -306.641178) (xy 404.412956 -306.604341) (xy 404.451077 -306.573216)
			(xy 404.493698 -306.548609) (xy 404.539714 -306.531157) (xy 404.587933 -306.521313) (xy 404.637108 -306.519332)
			(xy 404.685963 -306.525264) (xy 404.733234 -306.538956) (xy 404.777696 -306.560054) (xy 404.818199 -306.58801)
			(xy 404.853692 -306.622102) (xy 404.883257 -306.661446) (xy 404.906128 -306.705023) (xy 404.921712 -306.751704)
			(xy 404.929607 -306.800281) (xy 404.930102 -306.824888) (xy 405.269204 -306.824888) (xy 405.273164 -306.775834)
			(xy 405.284941 -306.72805) (xy 405.304232 -306.682774) (xy 405.330535 -306.641178) (xy 405.36317 -306.604341)
			(xy 405.401291 -306.573216) (xy 405.443912 -306.548609) (xy 405.489928 -306.531157) (xy 405.538147 -306.521313)
			(xy 405.587322 -306.519332) (xy 405.636177 -306.525264) (xy 405.683448 -306.538956) (xy 405.72791 -306.560054)
			(xy 405.768413 -306.58801) (xy 405.803906 -306.622102) (xy 405.833471 -306.661446) (xy 405.856342 -306.705023)
			(xy 405.871926 -306.751704) (xy 405.879821 -306.800281) (xy 405.880316 -306.824888) (xy 406.219164 -306.824888)
			(xy 406.223124 -306.775834) (xy 406.234901 -306.72805) (xy 406.254192 -306.682774) (xy 406.280495 -306.641178)
			(xy 406.31313 -306.604341) (xy 406.351251 -306.573216) (xy 406.393872 -306.548609) (xy 406.439888 -306.531157)
			(xy 406.488107 -306.521313) (xy 406.537282 -306.519332) (xy 406.586137 -306.525264) (xy 406.633408 -306.538956)
			(xy 406.67787 -306.560054) (xy 406.718373 -306.58801) (xy 406.753866 -306.622102) (xy 406.783431 -306.661446)
			(xy 406.806302 -306.705023) (xy 406.821886 -306.751704) (xy 406.829781 -306.800281) (xy 406.830276 -306.824888)
			(xy 408.119084 -306.824888) (xy 408.123044 -306.775834) (xy 408.134821 -306.72805) (xy 408.154112 -306.682774)
			(xy 408.180415 -306.641178) (xy 408.21305 -306.604341) (xy 408.251171 -306.573216) (xy 408.293792 -306.548609)
			(xy 408.339808 -306.531157) (xy 408.388027 -306.521313) (xy 408.437202 -306.519332) (xy 408.486057 -306.525264)
			(xy 408.533328 -306.538956) (xy 408.57779 -306.560054) (xy 408.618293 -306.58801) (xy 408.653786 -306.622102)
			(xy 408.683351 -306.661446) (xy 408.706222 -306.705023) (xy 408.721806 -306.751704) (xy 408.729701 -306.800281)
			(xy 408.730196 -306.824888) (xy 409.069044 -306.824888) (xy 409.073004 -306.775834) (xy 409.084781 -306.72805)
			(xy 409.104072 -306.682774) (xy 409.130375 -306.641178) (xy 409.16301 -306.604341) (xy 409.201131 -306.573216)
			(xy 409.243752 -306.548609) (xy 409.289768 -306.531157) (xy 409.337987 -306.521313) (xy 409.387162 -306.519332)
			(xy 409.436017 -306.525264) (xy 409.483288 -306.538956) (xy 409.52775 -306.560054) (xy 409.568253 -306.58801)
			(xy 409.603746 -306.622102) (xy 409.633311 -306.661446) (xy 409.656182 -306.705023) (xy 409.671766 -306.751704)
			(xy 409.679661 -306.800281) (xy 409.680156 -306.824888) (xy 410.019004 -306.824888) (xy 410.022964 -306.775834)
			(xy 410.034741 -306.72805) (xy 410.054032 -306.682774) (xy 410.080335 -306.641178) (xy 410.11297 -306.604341)
			(xy 410.151091 -306.573216) (xy 410.193712 -306.548609) (xy 410.239728 -306.531157) (xy 410.287947 -306.521313)
			(xy 410.337122 -306.519332) (xy 410.385977 -306.525264) (xy 410.433248 -306.538956) (xy 410.47771 -306.560054)
			(xy 410.518213 -306.58801) (xy 410.553706 -306.622102) (xy 410.583271 -306.661446) (xy 410.606142 -306.705023)
			(xy 410.621726 -306.751704) (xy 410.629621 -306.800281) (xy 410.630116 -306.824888) (xy 410.969218 -306.824888)
			(xy 410.973178 -306.775834) (xy 410.984955 -306.72805) (xy 411.004246 -306.682774) (xy 411.030549 -306.641178)
			(xy 411.063184 -306.604341) (xy 411.101305 -306.573216) (xy 411.143926 -306.548609) (xy 411.189942 -306.531157)
			(xy 411.238161 -306.521313) (xy 411.287336 -306.519332) (xy 411.336191 -306.525264) (xy 411.383462 -306.538956)
			(xy 411.427924 -306.560054) (xy 411.468427 -306.58801) (xy 411.50392 -306.622102) (xy 411.533485 -306.661446)
			(xy 411.556356 -306.705023) (xy 411.57194 -306.751704) (xy 411.579835 -306.800281) (xy 411.58033 -306.824888)
			(xy 411.919178 -306.824888) (xy 411.923138 -306.775834) (xy 411.934915 -306.72805) (xy 411.954206 -306.682774)
			(xy 411.980509 -306.641178) (xy 412.013144 -306.604341) (xy 412.051265 -306.573216) (xy 412.093886 -306.548609)
			(xy 412.139902 -306.531157) (xy 412.188121 -306.521313) (xy 412.237296 -306.519332) (xy 412.286151 -306.525264)
			(xy 412.333422 -306.538956) (xy 412.377884 -306.560054) (xy 412.418387 -306.58801) (xy 412.45388 -306.622102)
			(xy 412.483445 -306.661446) (xy 412.506316 -306.705023) (xy 412.5219 -306.751704) (xy 412.529795 -306.800281)
			(xy 412.53029 -306.824888) (xy 412.869138 -306.824888) (xy 412.873098 -306.775834) (xy 412.884875 -306.72805)
			(xy 412.904166 -306.682774) (xy 412.930469 -306.641178) (xy 412.963104 -306.604341) (xy 413.001225 -306.573216)
			(xy 413.043846 -306.548609) (xy 413.089862 -306.531157) (xy 413.138081 -306.521313) (xy 413.187256 -306.519332)
			(xy 413.236111 -306.525264) (xy 413.283382 -306.538956) (xy 413.327844 -306.560054) (xy 413.368347 -306.58801)
			(xy 413.40384 -306.622102) (xy 413.433405 -306.661446) (xy 413.456276 -306.705023) (xy 413.47186 -306.751704)
			(xy 413.479755 -306.800281) (xy 413.48025 -306.824888) (xy 413.819098 -306.824888) (xy 413.823058 -306.775834)
			(xy 413.834835 -306.72805) (xy 413.854126 -306.682774) (xy 413.880429 -306.641178) (xy 413.913064 -306.604341)
			(xy 413.951185 -306.573216) (xy 413.993806 -306.548609) (xy 414.039822 -306.531157) (xy 414.088041 -306.521313)
			(xy 414.137216 -306.519332) (xy 414.186071 -306.525264) (xy 414.233342 -306.538956) (xy 414.277804 -306.560054)
			(xy 414.318307 -306.58801) (xy 414.3538 -306.622102) (xy 414.383365 -306.661446) (xy 414.406236 -306.705023)
			(xy 414.42182 -306.751704) (xy 414.429715 -306.800281) (xy 414.43021 -306.824888) (xy 414.769058 -306.824888)
			(xy 414.773018 -306.775834) (xy 414.784795 -306.72805) (xy 414.804086 -306.682774) (xy 414.830389 -306.641178)
			(xy 414.863024 -306.604341) (xy 414.901145 -306.573216) (xy 414.943766 -306.548609) (xy 414.989782 -306.531157)
			(xy 415.038001 -306.521313) (xy 415.087176 -306.519332) (xy 415.136031 -306.525264) (xy 415.183302 -306.538956)
			(xy 415.227764 -306.560054) (xy 415.268267 -306.58801) (xy 415.30376 -306.622102) (xy 415.333325 -306.661446)
			(xy 415.356196 -306.705023) (xy 415.37178 -306.751704) (xy 415.379675 -306.800281) (xy 415.38017 -306.824888)
			(xy 415.719018 -306.824888) (xy 415.722978 -306.775834) (xy 415.734755 -306.72805) (xy 415.754046 -306.682774)
			(xy 415.780349 -306.641178) (xy 415.812984 -306.604341) (xy 415.851105 -306.573216) (xy 415.893726 -306.548609)
			(xy 415.939742 -306.531157) (xy 415.987961 -306.521313) (xy 416.037136 -306.519332) (xy 416.085991 -306.525264)
			(xy 416.133262 -306.538956) (xy 416.177724 -306.560054) (xy 416.218227 -306.58801) (xy 416.25372 -306.622102)
			(xy 416.283285 -306.661446) (xy 416.306156 -306.705023) (xy 416.32174 -306.751704) (xy 416.329635 -306.800281)
			(xy 416.33013 -306.824888) (xy 416.668978 -306.824888) (xy 416.672938 -306.775834) (xy 416.684715 -306.72805)
			(xy 416.704006 -306.682774) (xy 416.730309 -306.641178) (xy 416.762944 -306.604341) (xy 416.801065 -306.573216)
			(xy 416.843686 -306.548609) (xy 416.889702 -306.531157) (xy 416.937921 -306.521313) (xy 416.987096 -306.519332)
			(xy 417.035951 -306.525264) (xy 417.083222 -306.538956) (xy 417.127684 -306.560054) (xy 417.168187 -306.58801)
			(xy 417.20368 -306.622102) (xy 417.233245 -306.661446) (xy 417.256116 -306.705023) (xy 417.2717 -306.751704)
			(xy 417.279595 -306.800281) (xy 417.28009 -306.824888) (xy 417.619192 -306.824888) (xy 417.623152 -306.775834)
			(xy 417.634929 -306.72805) (xy 417.65422 -306.682774) (xy 417.680523 -306.641178) (xy 417.713158 -306.604341)
			(xy 417.751279 -306.573216) (xy 417.7939 -306.548609) (xy 417.839916 -306.531157) (xy 417.888135 -306.521313)
			(xy 417.93731 -306.519332) (xy 417.986165 -306.525264) (xy 418.033436 -306.538956) (xy 418.077898 -306.560054)
			(xy 418.118401 -306.58801) (xy 418.153894 -306.622102) (xy 418.183459 -306.661446) (xy 418.20633 -306.705023)
			(xy 418.221914 -306.751704) (xy 418.229809 -306.800281) (xy 418.230304 -306.824888) (xy 418.569152 -306.824888)
			(xy 418.573112 -306.775834) (xy 418.584889 -306.72805) (xy 418.60418 -306.682774) (xy 418.630483 -306.641178)
			(xy 418.663118 -306.604341) (xy 418.701239 -306.573216) (xy 418.74386 -306.548609) (xy 418.789876 -306.531157)
			(xy 418.838095 -306.521313) (xy 418.88727 -306.519332) (xy 418.936125 -306.525264) (xy 418.983396 -306.538956)
			(xy 419.027858 -306.560054) (xy 419.068361 -306.58801) (xy 419.103854 -306.622102) (xy 419.133419 -306.661446)
			(xy 419.15629 -306.705023) (xy 419.171874 -306.751704) (xy 419.179769 -306.800281) (xy 419.180264 -306.824888)
			(xy 419.519112 -306.824888) (xy 419.523072 -306.775834) (xy 419.534849 -306.72805) (xy 419.55414 -306.682774)
			(xy 419.580443 -306.641178) (xy 419.613078 -306.604341) (xy 419.651199 -306.573216) (xy 419.69382 -306.548609)
			(xy 419.739836 -306.531157) (xy 419.788055 -306.521313) (xy 419.83723 -306.519332) (xy 419.886085 -306.525264)
			(xy 419.933356 -306.538956) (xy 419.977818 -306.560054) (xy 420.018321 -306.58801) (xy 420.053814 -306.622102)
			(xy 420.083379 -306.661446) (xy 420.10625 -306.705023) (xy 420.121834 -306.751704) (xy 420.129729 -306.800281)
			(xy 420.130224 -306.824888) (xy 420.469072 -306.824888) (xy 420.473032 -306.775834) (xy 420.484809 -306.72805)
			(xy 420.5041 -306.682774) (xy 420.530403 -306.641178) (xy 420.563038 -306.604341) (xy 420.601159 -306.573216)
			(xy 420.64378 -306.548609) (xy 420.689796 -306.531157) (xy 420.738015 -306.521313) (xy 420.78719 -306.519332)
			(xy 420.836045 -306.525264) (xy 420.883316 -306.538956) (xy 420.927778 -306.560054) (xy 420.968281 -306.58801)
			(xy 421.003774 -306.622102) (xy 421.033339 -306.661446) (xy 421.05621 -306.705023) (xy 421.071794 -306.751704)
			(xy 421.079689 -306.800281) (xy 421.080184 -306.824888) (xy 421.419032 -306.824888) (xy 421.422992 -306.775834)
			(xy 421.434769 -306.72805) (xy 421.45406 -306.682774) (xy 421.480363 -306.641178) (xy 421.512998 -306.604341)
			(xy 421.551119 -306.573216) (xy 421.59374 -306.548609) (xy 421.639756 -306.531157) (xy 421.687975 -306.521313)
			(xy 421.73715 -306.519332) (xy 421.786005 -306.525264) (xy 421.833276 -306.538956) (xy 421.877738 -306.560054)
			(xy 421.918241 -306.58801) (xy 421.953734 -306.622102) (xy 421.983299 -306.661446) (xy 422.00617 -306.705023)
			(xy 422.021754 -306.751704) (xy 422.029649 -306.800281) (xy 422.030144 -306.824888) (xy 422.029649 -306.849495)
			(xy 422.021754 -306.898072) (xy 422.00617 -306.944753) (xy 421.983299 -306.98833) (xy 421.953734 -307.027674)
			(xy 421.918241 -307.061766) (xy 421.877738 -307.089722) (xy 421.833276 -307.11082) (xy 421.786005 -307.124512)
			(xy 421.73715 -307.130444) (xy 421.687975 -307.128463) (xy 421.639756 -307.118619) (xy 421.59374 -307.101167)
			(xy 421.551119 -307.07656) (xy 421.512998 -307.045435) (xy 421.480363 -307.008598) (xy 421.45406 -306.967002)
			(xy 421.434769 -306.921726) (xy 421.422992 -306.873942) (xy 421.419032 -306.824888) (xy 421.080184 -306.824888)
			(xy 421.079689 -306.849495) (xy 421.071794 -306.898072) (xy 421.05621 -306.944753) (xy 421.033339 -306.98833)
			(xy 421.003774 -307.027674) (xy 420.968281 -307.061766) (xy 420.927778 -307.089722) (xy 420.883316 -307.11082)
			(xy 420.836045 -307.124512) (xy 420.78719 -307.130444) (xy 420.738015 -307.128463) (xy 420.689796 -307.118619)
			(xy 420.64378 -307.101167) (xy 420.601159 -307.07656) (xy 420.563038 -307.045435) (xy 420.530403 -307.008598)
			(xy 420.5041 -306.967002) (xy 420.484809 -306.921726) (xy 420.473032 -306.873942) (xy 420.469072 -306.824888)
			(xy 420.130224 -306.824888) (xy 420.129729 -306.849495) (xy 420.121834 -306.898072) (xy 420.10625 -306.944753)
			(xy 420.083379 -306.98833) (xy 420.053814 -307.027674) (xy 420.018321 -307.061766) (xy 419.977818 -307.089722)
			(xy 419.933356 -307.11082) (xy 419.886085 -307.124512) (xy 419.83723 -307.130444) (xy 419.788055 -307.128463)
			(xy 419.739836 -307.118619) (xy 419.69382 -307.101167) (xy 419.651199 -307.07656) (xy 419.613078 -307.045435)
			(xy 419.580443 -307.008598) (xy 419.55414 -306.967002) (xy 419.534849 -306.921726) (xy 419.523072 -306.873942)
			(xy 419.519112 -306.824888) (xy 419.180264 -306.824888) (xy 419.179769 -306.849495) (xy 419.171874 -306.898072)
			(xy 419.15629 -306.944753) (xy 419.133419 -306.98833) (xy 419.103854 -307.027674) (xy 419.068361 -307.061766)
			(xy 419.027858 -307.089722) (xy 418.983396 -307.11082) (xy 418.936125 -307.124512) (xy 418.88727 -307.130444)
			(xy 418.838095 -307.128463) (xy 418.789876 -307.118619) (xy 418.74386 -307.101167) (xy 418.701239 -307.07656)
			(xy 418.663118 -307.045435) (xy 418.630483 -307.008598) (xy 418.60418 -306.967002) (xy 418.584889 -306.921726)
			(xy 418.573112 -306.873942) (xy 418.569152 -306.824888) (xy 418.230304 -306.824888) (xy 418.229809 -306.849495)
			(xy 418.221914 -306.898072) (xy 418.20633 -306.944753) (xy 418.183459 -306.98833) (xy 418.153894 -307.027674)
			(xy 418.118401 -307.061766) (xy 418.077898 -307.089722) (xy 418.033436 -307.11082) (xy 417.986165 -307.124512)
			(xy 417.93731 -307.130444) (xy 417.888135 -307.128463) (xy 417.839916 -307.118619) (xy 417.7939 -307.101167)
			(xy 417.751279 -307.07656) (xy 417.713158 -307.045435) (xy 417.680523 -307.008598) (xy 417.65422 -306.967002)
			(xy 417.634929 -306.921726) (xy 417.623152 -306.873942) (xy 417.619192 -306.824888) (xy 417.28009 -306.824888)
			(xy 417.279595 -306.849495) (xy 417.2717 -306.898072) (xy 417.256116 -306.944753) (xy 417.233245 -306.98833)
			(xy 417.20368 -307.027674) (xy 417.168187 -307.061766) (xy 417.127684 -307.089722) (xy 417.083222 -307.11082)
			(xy 417.035951 -307.124512) (xy 416.987096 -307.130444) (xy 416.937921 -307.128463) (xy 416.889702 -307.118619)
			(xy 416.843686 -307.101167) (xy 416.801065 -307.07656) (xy 416.762944 -307.045435) (xy 416.730309 -307.008598)
			(xy 416.704006 -306.967002) (xy 416.684715 -306.921726) (xy 416.672938 -306.873942) (xy 416.668978 -306.824888)
			(xy 416.33013 -306.824888) (xy 416.329635 -306.849495) (xy 416.32174 -306.898072) (xy 416.306156 -306.944753)
			(xy 416.283285 -306.98833) (xy 416.25372 -307.027674) (xy 416.218227 -307.061766) (xy 416.177724 -307.089722)
			(xy 416.133262 -307.11082) (xy 416.085991 -307.124512) (xy 416.037136 -307.130444) (xy 415.987961 -307.128463)
			(xy 415.939742 -307.118619) (xy 415.893726 -307.101167) (xy 415.851105 -307.07656) (xy 415.812984 -307.045435)
			(xy 415.780349 -307.008598) (xy 415.754046 -306.967002) (xy 415.734755 -306.921726) (xy 415.722978 -306.873942)
			(xy 415.719018 -306.824888) (xy 415.38017 -306.824888) (xy 415.379675 -306.849495) (xy 415.37178 -306.898072)
			(xy 415.356196 -306.944753) (xy 415.333325 -306.98833) (xy 415.30376 -307.027674) (xy 415.268267 -307.061766)
			(xy 415.227764 -307.089722) (xy 415.183302 -307.11082) (xy 415.136031 -307.124512) (xy 415.087176 -307.130444)
			(xy 415.038001 -307.128463) (xy 414.989782 -307.118619) (xy 414.943766 -307.101167) (xy 414.901145 -307.07656)
			(xy 414.863024 -307.045435) (xy 414.830389 -307.008598) (xy 414.804086 -306.967002) (xy 414.784795 -306.921726)
			(xy 414.773018 -306.873942) (xy 414.769058 -306.824888) (xy 414.43021 -306.824888) (xy 414.429715 -306.849495)
			(xy 414.42182 -306.898072) (xy 414.406236 -306.944753) (xy 414.383365 -306.98833) (xy 414.3538 -307.027674)
			(xy 414.318307 -307.061766) (xy 414.277804 -307.089722) (xy 414.233342 -307.11082) (xy 414.186071 -307.124512)
			(xy 414.137216 -307.130444) (xy 414.088041 -307.128463) (xy 414.039822 -307.118619) (xy 413.993806 -307.101167)
			(xy 413.951185 -307.07656) (xy 413.913064 -307.045435) (xy 413.880429 -307.008598) (xy 413.854126 -306.967002)
			(xy 413.834835 -306.921726) (xy 413.823058 -306.873942) (xy 413.819098 -306.824888) (xy 413.48025 -306.824888)
			(xy 413.479755 -306.849495) (xy 413.47186 -306.898072) (xy 413.456276 -306.944753) (xy 413.433405 -306.98833)
			(xy 413.40384 -307.027674) (xy 413.368347 -307.061766) (xy 413.327844 -307.089722) (xy 413.283382 -307.11082)
			(xy 413.236111 -307.124512) (xy 413.187256 -307.130444) (xy 413.138081 -307.128463) (xy 413.089862 -307.118619)
			(xy 413.043846 -307.101167) (xy 413.001225 -307.07656) (xy 412.963104 -307.045435) (xy 412.930469 -307.008598)
			(xy 412.904166 -306.967002) (xy 412.884875 -306.921726) (xy 412.873098 -306.873942) (xy 412.869138 -306.824888)
			(xy 412.53029 -306.824888) (xy 412.529795 -306.849495) (xy 412.5219 -306.898072) (xy 412.506316 -306.944753)
			(xy 412.483445 -306.98833) (xy 412.45388 -307.027674) (xy 412.418387 -307.061766) (xy 412.377884 -307.089722)
			(xy 412.333422 -307.11082) (xy 412.286151 -307.124512) (xy 412.237296 -307.130444) (xy 412.188121 -307.128463)
			(xy 412.139902 -307.118619) (xy 412.093886 -307.101167) (xy 412.051265 -307.07656) (xy 412.013144 -307.045435)
			(xy 411.980509 -307.008598) (xy 411.954206 -306.967002) (xy 411.934915 -306.921726) (xy 411.923138 -306.873942)
			(xy 411.919178 -306.824888) (xy 411.58033 -306.824888) (xy 411.579835 -306.849495) (xy 411.57194 -306.898072)
			(xy 411.556356 -306.944753) (xy 411.533485 -306.98833) (xy 411.50392 -307.027674) (xy 411.468427 -307.061766)
			(xy 411.427924 -307.089722) (xy 411.383462 -307.11082) (xy 411.336191 -307.124512) (xy 411.287336 -307.130444)
			(xy 411.238161 -307.128463) (xy 411.189942 -307.118619) (xy 411.143926 -307.101167) (xy 411.101305 -307.07656)
			(xy 411.063184 -307.045435) (xy 411.030549 -307.008598) (xy 411.004246 -306.967002) (xy 410.984955 -306.921726)
			(xy 410.973178 -306.873942) (xy 410.969218 -306.824888) (xy 410.630116 -306.824888) (xy 410.629621 -306.849495)
			(xy 410.621726 -306.898072) (xy 410.606142 -306.944753) (xy 410.583271 -306.98833) (xy 410.553706 -307.027674)
			(xy 410.518213 -307.061766) (xy 410.47771 -307.089722) (xy 410.433248 -307.11082) (xy 410.385977 -307.124512)
			(xy 410.337122 -307.130444) (xy 410.287947 -307.128463) (xy 410.239728 -307.118619) (xy 410.193712 -307.101167)
			(xy 410.151091 -307.07656) (xy 410.11297 -307.045435) (xy 410.080335 -307.008598) (xy 410.054032 -306.967002)
			(xy 410.034741 -306.921726) (xy 410.022964 -306.873942) (xy 410.019004 -306.824888) (xy 409.680156 -306.824888)
			(xy 409.679661 -306.849495) (xy 409.671766 -306.898072) (xy 409.656182 -306.944753) (xy 409.633311 -306.98833)
			(xy 409.603746 -307.027674) (xy 409.568253 -307.061766) (xy 409.52775 -307.089722) (xy 409.483288 -307.11082)
			(xy 409.436017 -307.124512) (xy 409.387162 -307.130444) (xy 409.337987 -307.128463) (xy 409.289768 -307.118619)
			(xy 409.243752 -307.101167) (xy 409.201131 -307.07656) (xy 409.16301 -307.045435) (xy 409.130375 -307.008598)
			(xy 409.104072 -306.967002) (xy 409.084781 -306.921726) (xy 409.073004 -306.873942) (xy 409.069044 -306.824888)
			(xy 408.730196 -306.824888) (xy 408.729701 -306.849495) (xy 408.721806 -306.898072) (xy 408.706222 -306.944753)
			(xy 408.683351 -306.98833) (xy 408.653786 -307.027674) (xy 408.618293 -307.061766) (xy 408.57779 -307.089722)
			(xy 408.533328 -307.11082) (xy 408.486057 -307.124512) (xy 408.437202 -307.130444) (xy 408.388027 -307.128463)
			(xy 408.339808 -307.118619) (xy 408.293792 -307.101167) (xy 408.251171 -307.07656) (xy 408.21305 -307.045435)
			(xy 408.180415 -307.008598) (xy 408.154112 -306.967002) (xy 408.134821 -306.921726) (xy 408.123044 -306.873942)
			(xy 408.119084 -306.824888) (xy 406.830276 -306.824888) (xy 406.829781 -306.849495) (xy 406.821886 -306.898072)
			(xy 406.806302 -306.944753) (xy 406.783431 -306.98833) (xy 406.753866 -307.027674) (xy 406.718373 -307.061766)
			(xy 406.67787 -307.089722) (xy 406.633408 -307.11082) (xy 406.586137 -307.124512) (xy 406.537282 -307.130444)
			(xy 406.488107 -307.128463) (xy 406.439888 -307.118619) (xy 406.393872 -307.101167) (xy 406.351251 -307.07656)
			(xy 406.31313 -307.045435) (xy 406.280495 -307.008598) (xy 406.254192 -306.967002) (xy 406.234901 -306.921726)
			(xy 406.223124 -306.873942) (xy 406.219164 -306.824888) (xy 405.880316 -306.824888) (xy 405.879821 -306.849495)
			(xy 405.871926 -306.898072) (xy 405.856342 -306.944753) (xy 405.833471 -306.98833) (xy 405.803906 -307.027674)
			(xy 405.768413 -307.061766) (xy 405.72791 -307.089722) (xy 405.683448 -307.11082) (xy 405.636177 -307.124512)
			(xy 405.587322 -307.130444) (xy 405.538147 -307.128463) (xy 405.489928 -307.118619) (xy 405.443912 -307.101167)
			(xy 405.401291 -307.07656) (xy 405.36317 -307.045435) (xy 405.330535 -307.008598) (xy 405.304232 -306.967002)
			(xy 405.284941 -306.921726) (xy 405.273164 -306.873942) (xy 405.269204 -306.824888) (xy 404.930102 -306.824888)
			(xy 404.929607 -306.849495) (xy 404.921712 -306.898072) (xy 404.906128 -306.944753) (xy 404.883257 -306.98833)
			(xy 404.853692 -307.027674) (xy 404.818199 -307.061766) (xy 404.777696 -307.089722) (xy 404.733234 -307.11082)
			(xy 404.685963 -307.124512) (xy 404.637108 -307.130444) (xy 404.587933 -307.128463) (xy 404.539714 -307.118619)
			(xy 404.493698 -307.101167) (xy 404.451077 -307.07656) (xy 404.412956 -307.045435) (xy 404.380321 -307.008598)
			(xy 404.354018 -306.967002) (xy 404.334727 -306.921726) (xy 404.32295 -306.873942) (xy 404.31899 -306.824888)
			(xy 403.980142 -306.824888) (xy 403.979647 -306.849495) (xy 403.971752 -306.898072) (xy 403.956168 -306.944753)
			(xy 403.933297 -306.98833) (xy 403.903732 -307.027674) (xy 403.868239 -307.061766) (xy 403.827736 -307.089722)
			(xy 403.783274 -307.11082) (xy 403.736003 -307.124512) (xy 403.687148 -307.130444) (xy 403.637973 -307.128463)
			(xy 403.589754 -307.118619) (xy 403.543738 -307.101167) (xy 403.501117 -307.07656) (xy 403.462996 -307.045435)
			(xy 403.430361 -307.008598) (xy 403.404058 -306.967002) (xy 403.384767 -306.921726) (xy 403.37299 -306.873942)
			(xy 403.36903 -306.824888) (xy 403.030182 -306.824888) (xy 403.029687 -306.849495) (xy 403.021792 -306.898072)
			(xy 403.006208 -306.944753) (xy 402.983337 -306.98833) (xy 402.953772 -307.027674) (xy 402.918279 -307.061766)
			(xy 402.877776 -307.089722) (xy 402.833314 -307.11082) (xy 402.786043 -307.124512) (xy 402.737188 -307.130444)
			(xy 402.688013 -307.128463) (xy 402.639794 -307.118619) (xy 402.593778 -307.101167) (xy 402.551157 -307.07656)
			(xy 402.513036 -307.045435) (xy 402.480401 -307.008598) (xy 402.454098 -306.967002) (xy 402.434807 -306.921726)
			(xy 402.42303 -306.873942) (xy 402.41907 -306.824888) (xy 402.080222 -306.824888) (xy 402.079727 -306.849495)
			(xy 402.071832 -306.898072) (xy 402.056248 -306.944753) (xy 402.033377 -306.98833) (xy 402.003812 -307.027674)
			(xy 401.968319 -307.061766) (xy 401.927816 -307.089722) (xy 401.883354 -307.11082) (xy 401.836083 -307.124512)
			(xy 401.787228 -307.130444) (xy 401.738053 -307.128463) (xy 401.689834 -307.118619) (xy 401.643818 -307.101167)
			(xy 401.601197 -307.07656) (xy 401.563076 -307.045435) (xy 401.530441 -307.008598) (xy 401.504138 -306.967002)
			(xy 401.484847 -306.921726) (xy 401.47307 -306.873942) (xy 401.46911 -306.824888) (xy 401.130262 -306.824888)
			(xy 401.129767 -306.849495) (xy 401.121872 -306.898072) (xy 401.106288 -306.944753) (xy 401.083417 -306.98833)
			(xy 401.053852 -307.027674) (xy 401.018359 -307.061766) (xy 400.977856 -307.089722) (xy 400.933394 -307.11082)
			(xy 400.886123 -307.124512) (xy 400.837268 -307.130444) (xy 400.788093 -307.128463) (xy 400.739874 -307.118619)
			(xy 400.693858 -307.101167) (xy 400.651237 -307.07656) (xy 400.613116 -307.045435) (xy 400.580481 -307.008598)
			(xy 400.554178 -306.967002) (xy 400.534887 -306.921726) (xy 400.52311 -306.873942) (xy 400.51915 -306.824888)
			(xy 400.180302 -306.824888) (xy 400.179807 -306.849495) (xy 400.171912 -306.898072) (xy 400.156328 -306.944753)
			(xy 400.133457 -306.98833) (xy 400.103892 -307.027674) (xy 400.068399 -307.061766) (xy 400.027896 -307.089722)
			(xy 399.983434 -307.11082) (xy 399.936163 -307.124512) (xy 399.887308 -307.130444) (xy 399.838133 -307.128463)
			(xy 399.789914 -307.118619) (xy 399.743898 -307.101167) (xy 399.701277 -307.07656) (xy 399.663156 -307.045435)
			(xy 399.630521 -307.008598) (xy 399.604218 -306.967002) (xy 399.584927 -306.921726) (xy 399.57315 -306.873942)
			(xy 399.56919 -306.824888) (xy 399.230342 -306.824888) (xy 399.229847 -306.849495) (xy 399.221952 -306.898072)
			(xy 399.206368 -306.944753) (xy 399.183497 -306.98833) (xy 399.153932 -307.027674) (xy 399.118439 -307.061766)
			(xy 399.077936 -307.089722) (xy 399.033474 -307.11082) (xy 398.986203 -307.124512) (xy 398.937348 -307.130444)
			(xy 398.888173 -307.128463) (xy 398.839954 -307.118619) (xy 398.793938 -307.101167) (xy 398.751317 -307.07656)
			(xy 398.713196 -307.045435) (xy 398.680561 -307.008598) (xy 398.654258 -306.967002) (xy 398.634967 -306.921726)
			(xy 398.62319 -306.873942) (xy 398.61923 -306.824888) (xy 398.280128 -306.824888) (xy 398.279633 -306.849495)
			(xy 398.271738 -306.898072) (xy 398.256154 -306.944753) (xy 398.233283 -306.98833) (xy 398.203718 -307.027674)
			(xy 398.168225 -307.061766) (xy 398.127722 -307.089722) (xy 398.08326 -307.11082) (xy 398.035989 -307.124512)
			(xy 397.987134 -307.130444) (xy 397.937959 -307.128463) (xy 397.88974 -307.118619) (xy 397.843724 -307.101167)
			(xy 397.801103 -307.07656) (xy 397.762982 -307.045435) (xy 397.730347 -307.008598) (xy 397.704044 -306.967002)
			(xy 397.684753 -306.921726) (xy 397.672976 -306.873942) (xy 397.669016 -306.824888) (xy 397.330168 -306.824888)
			(xy 397.329673 -306.849495) (xy 397.321778 -306.898072) (xy 397.306194 -306.944753) (xy 397.283323 -306.98833)
			(xy 397.253758 -307.027674) (xy 397.218265 -307.061766) (xy 397.177762 -307.089722) (xy 397.1333 -307.11082)
			(xy 397.086029 -307.124512) (xy 397.037174 -307.130444) (xy 396.987999 -307.128463) (xy 396.93978 -307.118619)
			(xy 396.893764 -307.101167) (xy 396.851143 -307.07656) (xy 396.813022 -307.045435) (xy 396.780387 -307.008598)
			(xy 396.754084 -306.967002) (xy 396.734793 -306.921726) (xy 396.723016 -306.873942) (xy 396.719056 -306.824888)
			(xy 396.380208 -306.824888) (xy 396.379713 -306.849495) (xy 396.371818 -306.898072) (xy 396.356234 -306.944753)
			(xy 396.333363 -306.98833) (xy 396.303798 -307.027674) (xy 396.268305 -307.061766) (xy 396.227802 -307.089722)
			(xy 396.18334 -307.11082) (xy 396.136069 -307.124512) (xy 396.087214 -307.130444) (xy 396.038039 -307.128463)
			(xy 395.98982 -307.118619) (xy 395.943804 -307.101167) (xy 395.901183 -307.07656) (xy 395.863062 -307.045435)
			(xy 395.830427 -307.008598) (xy 395.804124 -306.967002) (xy 395.784833 -306.921726) (xy 395.773056 -306.873942)
			(xy 395.769096 -306.824888) (xy 395.430248 -306.824888) (xy 395.429753 -306.849495) (xy 395.421858 -306.898072)
			(xy 395.406274 -306.944753) (xy 395.383403 -306.98833) (xy 395.353838 -307.027674) (xy 395.318345 -307.061766)
			(xy 395.277842 -307.089722) (xy 395.23338 -307.11082) (xy 395.186109 -307.124512) (xy 395.137254 -307.130444)
			(xy 395.088079 -307.128463) (xy 395.03986 -307.118619) (xy 394.993844 -307.101167) (xy 394.951223 -307.07656)
			(xy 394.913102 -307.045435) (xy 394.880467 -307.008598) (xy 394.854164 -306.967002) (xy 394.834873 -306.921726)
			(xy 394.823096 -306.873942) (xy 394.819136 -306.824888) (xy 389.255 -306.824888) (xy 389.255 -307.291486)
			(xy 389.255254 -307.299106) (xy 389.255254 -307.299868) (xy 389.594102 -307.299868) (xy 389.598062 -307.250814)
			(xy 389.609839 -307.20303) (xy 389.62913 -307.157754) (xy 389.655433 -307.116158) (xy 389.688068 -307.079321)
			(xy 389.726189 -307.048196) (xy 389.76881 -307.023589) (xy 389.814826 -307.006137) (xy 389.863045 -306.996293)
			(xy 389.91222 -306.994312) (xy 389.961075 -307.000244) (xy 390.008346 -307.013936) (xy 390.052808 -307.035034)
			(xy 390.093311 -307.06299) (xy 390.128804 -307.097082) (xy 390.158369 -307.136426) (xy 390.18124 -307.180003)
			(xy 390.196824 -307.226684) (xy 390.204719 -307.275261) (xy 390.205214 -307.299868) (xy 390.544062 -307.299868)
			(xy 390.548022 -307.250814) (xy 390.559799 -307.20303) (xy 390.57909 -307.157754) (xy 390.605393 -307.116158)
			(xy 390.638028 -307.079321) (xy 390.676149 -307.048196) (xy 390.71877 -307.023589) (xy 390.764786 -307.006137)
			(xy 390.813005 -306.996293) (xy 390.86218 -306.994312) (xy 390.911035 -307.000244) (xy 390.958306 -307.013936)
			(xy 391.002768 -307.035034) (xy 391.043271 -307.06299) (xy 391.078764 -307.097082) (xy 391.108329 -307.136426)
			(xy 391.1312 -307.180003) (xy 391.146784 -307.226684) (xy 391.154679 -307.275261) (xy 391.155174 -307.299868)
			(xy 391.494022 -307.299868) (xy 391.497982 -307.250814) (xy 391.509759 -307.20303) (xy 391.52905 -307.157754)
			(xy 391.555353 -307.116158) (xy 391.587988 -307.079321) (xy 391.626109 -307.048196) (xy 391.66873 -307.023589)
			(xy 391.714746 -307.006137) (xy 391.762965 -306.996293) (xy 391.81214 -306.994312) (xy 391.860995 -307.000244)
			(xy 391.908266 -307.013936) (xy 391.952728 -307.035034) (xy 391.993231 -307.06299) (xy 392.028724 -307.097082)
			(xy 392.058289 -307.136426) (xy 392.08116 -307.180003) (xy 392.096744 -307.226684) (xy 392.104639 -307.275261)
			(xy 392.105134 -307.299868) (xy 392.443982 -307.299868) (xy 392.447942 -307.250814) (xy 392.459719 -307.20303)
			(xy 392.47901 -307.157754) (xy 392.505313 -307.116158) (xy 392.537948 -307.079321) (xy 392.576069 -307.048196)
			(xy 392.61869 -307.023589) (xy 392.664706 -307.006137) (xy 392.712925 -306.996293) (xy 392.7621 -306.994312)
			(xy 392.810955 -307.000244) (xy 392.858226 -307.013936) (xy 392.902688 -307.035034) (xy 392.943191 -307.06299)
			(xy 392.978684 -307.097082) (xy 393.008249 -307.136426) (xy 393.03112 -307.180003) (xy 393.046704 -307.226684)
			(xy 393.054599 -307.275261) (xy 393.055094 -307.299868) (xy 393.394196 -307.299868) (xy 393.398156 -307.250814)
			(xy 393.409933 -307.20303) (xy 393.429224 -307.157754) (xy 393.455527 -307.116158) (xy 393.488162 -307.079321)
			(xy 393.526283 -307.048196) (xy 393.568904 -307.023589) (xy 393.61492 -307.006137) (xy 393.663139 -306.996293)
			(xy 393.712314 -306.994312) (xy 393.761169 -307.000244) (xy 393.80844 -307.013936) (xy 393.852902 -307.035034)
			(xy 393.893405 -307.06299) (xy 393.928898 -307.097082) (xy 393.958463 -307.136426) (xy 393.981334 -307.180003)
			(xy 393.996918 -307.226684) (xy 394.004813 -307.275261) (xy 394.005308 -307.299868) (xy 422.844226 -307.299868)
			(xy 422.848186 -307.250814) (xy 422.859963 -307.20303) (xy 422.879254 -307.157754) (xy 422.905557 -307.116158)
			(xy 422.938192 -307.079321) (xy 422.976313 -307.048196) (xy 423.018934 -307.023589) (xy 423.06495 -307.006137)
			(xy 423.113169 -306.996293) (xy 423.162344 -306.994312) (xy 423.211199 -307.000244) (xy 423.25847 -307.013936)
			(xy 423.302932 -307.035034) (xy 423.343435 -307.06299) (xy 423.378928 -307.097082) (xy 423.408493 -307.136426)
			(xy 423.431364 -307.180003) (xy 423.446948 -307.226684) (xy 423.454843 -307.275261) (xy 423.455338 -307.299868)
			(xy 423.794186 -307.299868) (xy 423.798146 -307.250814) (xy 423.809923 -307.20303) (xy 423.829214 -307.157754)
			(xy 423.855517 -307.116158) (xy 423.888152 -307.079321) (xy 423.926273 -307.048196) (xy 423.968894 -307.023589)
			(xy 424.01491 -307.006137) (xy 424.063129 -306.996293) (xy 424.112304 -306.994312) (xy 424.161159 -307.000244)
			(xy 424.20843 -307.013936) (xy 424.252892 -307.035034) (xy 424.293395 -307.06299) (xy 424.328888 -307.097082)
			(xy 424.358453 -307.136426) (xy 424.381324 -307.180003) (xy 424.396908 -307.226684) (xy 424.404803 -307.275261)
			(xy 424.405298 -307.299868) (xy 424.404803 -307.324475) (xy 424.396908 -307.373052) (xy 424.381324 -307.419733)
			(xy 424.358453 -307.46331) (xy 424.328888 -307.502654) (xy 424.293395 -307.536746) (xy 424.252892 -307.564702)
			(xy 424.20843 -307.5858) (xy 424.161159 -307.599492) (xy 424.112304 -307.605424) (xy 424.063129 -307.603443)
			(xy 424.01491 -307.593599) (xy 423.968894 -307.576147) (xy 423.926273 -307.55154) (xy 423.888152 -307.520415)
			(xy 423.855517 -307.483578) (xy 423.829214 -307.441982) (xy 423.809923 -307.396706) (xy 423.798146 -307.348922)
			(xy 423.794186 -307.299868) (xy 423.455338 -307.299868) (xy 423.454843 -307.324475) (xy 423.446948 -307.373052)
			(xy 423.431364 -307.419733) (xy 423.408493 -307.46331) (xy 423.378928 -307.502654) (xy 423.343435 -307.536746)
			(xy 423.302932 -307.564702) (xy 423.25847 -307.5858) (xy 423.211199 -307.599492) (xy 423.162344 -307.605424)
			(xy 423.113169 -307.603443) (xy 423.06495 -307.593599) (xy 423.018934 -307.576147) (xy 422.976313 -307.55154)
			(xy 422.938192 -307.520415) (xy 422.905557 -307.483578) (xy 422.879254 -307.441982) (xy 422.859963 -307.396706)
			(xy 422.848186 -307.348922) (xy 422.844226 -307.299868) (xy 394.005308 -307.299868) (xy 394.004813 -307.324475)
			(xy 393.996918 -307.373052) (xy 393.981334 -307.419733) (xy 393.958463 -307.46331) (xy 393.928898 -307.502654)
			(xy 393.893405 -307.536746) (xy 393.852902 -307.564702) (xy 393.80844 -307.5858) (xy 393.761169 -307.599492)
			(xy 393.712314 -307.605424) (xy 393.663139 -307.603443) (xy 393.61492 -307.593599) (xy 393.568904 -307.576147)
			(xy 393.526283 -307.55154) (xy 393.488162 -307.520415) (xy 393.455527 -307.483578) (xy 393.429224 -307.441982)
			(xy 393.409933 -307.396706) (xy 393.398156 -307.348922) (xy 393.394196 -307.299868) (xy 393.055094 -307.299868)
			(xy 393.054599 -307.324475) (xy 393.046704 -307.373052) (xy 393.03112 -307.419733) (xy 393.008249 -307.46331)
			(xy 392.978684 -307.502654) (xy 392.943191 -307.536746) (xy 392.902688 -307.564702) (xy 392.858226 -307.5858)
			(xy 392.810955 -307.599492) (xy 392.7621 -307.605424) (xy 392.712925 -307.603443) (xy 392.664706 -307.593599)
			(xy 392.61869 -307.576147) (xy 392.576069 -307.55154) (xy 392.537948 -307.520415) (xy 392.505313 -307.483578)
			(xy 392.47901 -307.441982) (xy 392.459719 -307.396706) (xy 392.447942 -307.348922) (xy 392.443982 -307.299868)
			(xy 392.105134 -307.299868) (xy 392.104639 -307.324475) (xy 392.096744 -307.373052) (xy 392.08116 -307.419733)
			(xy 392.058289 -307.46331) (xy 392.028724 -307.502654) (xy 391.993231 -307.536746) (xy 391.952728 -307.564702)
			(xy 391.908266 -307.5858) (xy 391.860995 -307.599492) (xy 391.81214 -307.605424) (xy 391.762965 -307.603443)
			(xy 391.714746 -307.593599) (xy 391.66873 -307.576147) (xy 391.626109 -307.55154) (xy 391.587988 -307.520415)
			(xy 391.555353 -307.483578) (xy 391.52905 -307.441982) (xy 391.509759 -307.396706) (xy 391.497982 -307.348922)
			(xy 391.494022 -307.299868) (xy 391.155174 -307.299868) (xy 391.154679 -307.324475) (xy 391.146784 -307.373052)
			(xy 391.1312 -307.419733) (xy 391.108329 -307.46331) (xy 391.078764 -307.502654) (xy 391.043271 -307.536746)
			(xy 391.002768 -307.564702) (xy 390.958306 -307.5858) (xy 390.911035 -307.599492) (xy 390.86218 -307.605424)
			(xy 390.813005 -307.603443) (xy 390.764786 -307.593599) (xy 390.71877 -307.576147) (xy 390.676149 -307.55154)
			(xy 390.638028 -307.520415) (xy 390.605393 -307.483578) (xy 390.57909 -307.441982) (xy 390.559799 -307.396706)
			(xy 390.548022 -307.348922) (xy 390.544062 -307.299868) (xy 390.205214 -307.299868) (xy 390.204719 -307.324475)
			(xy 390.196824 -307.373052) (xy 390.18124 -307.419733) (xy 390.158369 -307.46331) (xy 390.128804 -307.502654)
			(xy 390.093311 -307.536746) (xy 390.052808 -307.564702) (xy 390.008346 -307.5858) (xy 389.961075 -307.599492)
			(xy 389.91222 -307.605424) (xy 389.863045 -307.603443) (xy 389.814826 -307.593599) (xy 389.76881 -307.576147)
			(xy 389.726189 -307.55154) (xy 389.688068 -307.520415) (xy 389.655433 -307.483578) (xy 389.62913 -307.441982)
			(xy 389.609839 -307.396706) (xy 389.598062 -307.348922) (xy 389.594102 -307.299868) (xy 389.255254 -307.299868)
			(xy 389.255254 -307.30063) (xy 389.255 -307.30825) (xy 389.255 -307.774848) (xy 394.819136 -307.774848)
			(xy 394.823096 -307.725794) (xy 394.834873 -307.67801) (xy 394.854164 -307.632734) (xy 394.880467 -307.591138)
			(xy 394.913102 -307.554301) (xy 394.951223 -307.523176) (xy 394.993844 -307.498569) (xy 395.03986 -307.481117)
			(xy 395.088079 -307.471273) (xy 395.137254 -307.469292) (xy 395.186109 -307.475224) (xy 395.23338 -307.488916)
			(xy 395.277842 -307.510014) (xy 395.318345 -307.53797) (xy 395.353838 -307.572062) (xy 395.383403 -307.611406)
			(xy 395.406274 -307.654983) (xy 395.421858 -307.701664) (xy 395.429753 -307.750241) (xy 395.430248 -307.774848)
			(xy 395.769096 -307.774848) (xy 395.773056 -307.725794) (xy 395.784833 -307.67801) (xy 395.804124 -307.632734)
			(xy 395.830427 -307.591138) (xy 395.863062 -307.554301) (xy 395.901183 -307.523176) (xy 395.943804 -307.498569)
			(xy 395.98982 -307.481117) (xy 396.038039 -307.471273) (xy 396.087214 -307.469292) (xy 396.136069 -307.475224)
			(xy 396.18334 -307.488916) (xy 396.227802 -307.510014) (xy 396.268305 -307.53797) (xy 396.303798 -307.572062)
			(xy 396.333363 -307.611406) (xy 396.356234 -307.654983) (xy 396.371818 -307.701664) (xy 396.379713 -307.750241)
			(xy 396.380208 -307.774848) (xy 396.719056 -307.774848) (xy 396.723016 -307.725794) (xy 396.734793 -307.67801)
			(xy 396.754084 -307.632734) (xy 396.780387 -307.591138) (xy 396.813022 -307.554301) (xy 396.851143 -307.523176)
			(xy 396.893764 -307.498569) (xy 396.93978 -307.481117) (xy 396.987999 -307.471273) (xy 397.037174 -307.469292)
			(xy 397.086029 -307.475224) (xy 397.1333 -307.488916) (xy 397.177762 -307.510014) (xy 397.218265 -307.53797)
			(xy 397.253758 -307.572062) (xy 397.283323 -307.611406) (xy 397.306194 -307.654983) (xy 397.321778 -307.701664)
			(xy 397.329673 -307.750241) (xy 397.330168 -307.774848) (xy 397.669016 -307.774848) (xy 397.672976 -307.725794)
			(xy 397.684753 -307.67801) (xy 397.704044 -307.632734) (xy 397.730347 -307.591138) (xy 397.762982 -307.554301)
			(xy 397.801103 -307.523176) (xy 397.843724 -307.498569) (xy 397.88974 -307.481117) (xy 397.937959 -307.471273)
			(xy 397.987134 -307.469292) (xy 398.035989 -307.475224) (xy 398.08326 -307.488916) (xy 398.127722 -307.510014)
			(xy 398.168225 -307.53797) (xy 398.203718 -307.572062) (xy 398.233283 -307.611406) (xy 398.256154 -307.654983)
			(xy 398.271738 -307.701664) (xy 398.279633 -307.750241) (xy 398.280128 -307.774848) (xy 398.61923 -307.774848)
			(xy 398.62319 -307.725794) (xy 398.634967 -307.67801) (xy 398.654258 -307.632734) (xy 398.680561 -307.591138)
			(xy 398.713196 -307.554301) (xy 398.751317 -307.523176) (xy 398.793938 -307.498569) (xy 398.839954 -307.481117)
			(xy 398.888173 -307.471273) (xy 398.937348 -307.469292) (xy 398.986203 -307.475224) (xy 399.033474 -307.488916)
			(xy 399.077936 -307.510014) (xy 399.118439 -307.53797) (xy 399.153932 -307.572062) (xy 399.183497 -307.611406)
			(xy 399.206368 -307.654983) (xy 399.221952 -307.701664) (xy 399.229847 -307.750241) (xy 399.230342 -307.774848)
			(xy 399.56919 -307.774848) (xy 399.57315 -307.725794) (xy 399.584927 -307.67801) (xy 399.604218 -307.632734)
			(xy 399.630521 -307.591138) (xy 399.663156 -307.554301) (xy 399.701277 -307.523176) (xy 399.743898 -307.498569)
			(xy 399.789914 -307.481117) (xy 399.838133 -307.471273) (xy 399.887308 -307.469292) (xy 399.936163 -307.475224)
			(xy 399.983434 -307.488916) (xy 400.027896 -307.510014) (xy 400.068399 -307.53797) (xy 400.103892 -307.572062)
			(xy 400.133457 -307.611406) (xy 400.156328 -307.654983) (xy 400.171912 -307.701664) (xy 400.179807 -307.750241)
			(xy 400.180302 -307.774848) (xy 400.51915 -307.774848) (xy 400.52311 -307.725794) (xy 400.534887 -307.67801)
			(xy 400.554178 -307.632734) (xy 400.580481 -307.591138) (xy 400.613116 -307.554301) (xy 400.651237 -307.523176)
			(xy 400.693858 -307.498569) (xy 400.739874 -307.481117) (xy 400.788093 -307.471273) (xy 400.837268 -307.469292)
			(xy 400.886123 -307.475224) (xy 400.933394 -307.488916) (xy 400.977856 -307.510014) (xy 401.018359 -307.53797)
			(xy 401.053852 -307.572062) (xy 401.083417 -307.611406) (xy 401.106288 -307.654983) (xy 401.121872 -307.701664)
			(xy 401.129767 -307.750241) (xy 401.130262 -307.774848) (xy 401.46911 -307.774848) (xy 401.47307 -307.725794)
			(xy 401.484847 -307.67801) (xy 401.504138 -307.632734) (xy 401.530441 -307.591138) (xy 401.563076 -307.554301)
			(xy 401.601197 -307.523176) (xy 401.643818 -307.498569) (xy 401.689834 -307.481117) (xy 401.738053 -307.471273)
			(xy 401.787228 -307.469292) (xy 401.836083 -307.475224) (xy 401.883354 -307.488916) (xy 401.927816 -307.510014)
			(xy 401.968319 -307.53797) (xy 402.003812 -307.572062) (xy 402.033377 -307.611406) (xy 402.056248 -307.654983)
			(xy 402.071832 -307.701664) (xy 402.079727 -307.750241) (xy 402.080222 -307.774848) (xy 402.41907 -307.774848)
			(xy 402.42303 -307.725794) (xy 402.434807 -307.67801) (xy 402.454098 -307.632734) (xy 402.480401 -307.591138)
			(xy 402.513036 -307.554301) (xy 402.551157 -307.523176) (xy 402.593778 -307.498569) (xy 402.639794 -307.481117)
			(xy 402.688013 -307.471273) (xy 402.737188 -307.469292) (xy 402.786043 -307.475224) (xy 402.833314 -307.488916)
			(xy 402.877776 -307.510014) (xy 402.918279 -307.53797) (xy 402.953772 -307.572062) (xy 402.983337 -307.611406)
			(xy 403.006208 -307.654983) (xy 403.021792 -307.701664) (xy 403.029687 -307.750241) (xy 403.030182 -307.774848)
			(xy 403.36903 -307.774848) (xy 403.37299 -307.725794) (xy 403.384767 -307.67801) (xy 403.404058 -307.632734)
			(xy 403.430361 -307.591138) (xy 403.462996 -307.554301) (xy 403.501117 -307.523176) (xy 403.543738 -307.498569)
			(xy 403.589754 -307.481117) (xy 403.637973 -307.471273) (xy 403.687148 -307.469292) (xy 403.736003 -307.475224)
			(xy 403.783274 -307.488916) (xy 403.827736 -307.510014) (xy 403.868239 -307.53797) (xy 403.903732 -307.572062)
			(xy 403.933297 -307.611406) (xy 403.956168 -307.654983) (xy 403.971752 -307.701664) (xy 403.979647 -307.750241)
			(xy 403.980142 -307.774848) (xy 404.319244 -307.774848) (xy 404.323204 -307.725794) (xy 404.334981 -307.67801)
			(xy 404.354272 -307.632734) (xy 404.380575 -307.591138) (xy 404.41321 -307.554301) (xy 404.451331 -307.523176)
			(xy 404.493952 -307.498569) (xy 404.539968 -307.481117) (xy 404.588187 -307.471273) (xy 404.637362 -307.469292)
			(xy 404.686217 -307.475224) (xy 404.733488 -307.488916) (xy 404.77795 -307.510014) (xy 404.818453 -307.53797)
			(xy 404.853946 -307.572062) (xy 404.883511 -307.611406) (xy 404.906382 -307.654983) (xy 404.921966 -307.701664)
			(xy 404.929861 -307.750241) (xy 404.930356 -307.774848) (xy 405.269204 -307.774848) (xy 405.273164 -307.725794)
			(xy 405.284941 -307.67801) (xy 405.304232 -307.632734) (xy 405.330535 -307.591138) (xy 405.36317 -307.554301)
			(xy 405.401291 -307.523176) (xy 405.443912 -307.498569) (xy 405.489928 -307.481117) (xy 405.538147 -307.471273)
			(xy 405.587322 -307.469292) (xy 405.636177 -307.475224) (xy 405.683448 -307.488916) (xy 405.72791 -307.510014)
			(xy 405.768413 -307.53797) (xy 405.803906 -307.572062) (xy 405.833471 -307.611406) (xy 405.856342 -307.654983)
			(xy 405.871926 -307.701664) (xy 405.879821 -307.750241) (xy 405.880316 -307.774848) (xy 406.219164 -307.774848)
			(xy 406.223124 -307.725794) (xy 406.234901 -307.67801) (xy 406.254192 -307.632734) (xy 406.280495 -307.591138)
			(xy 406.31313 -307.554301) (xy 406.351251 -307.523176) (xy 406.393872 -307.498569) (xy 406.439888 -307.481117)
			(xy 406.488107 -307.471273) (xy 406.537282 -307.469292) (xy 406.586137 -307.475224) (xy 406.633408 -307.488916)
			(xy 406.67787 -307.510014) (xy 406.718373 -307.53797) (xy 406.753866 -307.572062) (xy 406.783431 -307.611406)
			(xy 406.806302 -307.654983) (xy 406.821886 -307.701664) (xy 406.829781 -307.750241) (xy 406.830276 -307.774848)
			(xy 408.119084 -307.774848) (xy 408.123044 -307.725794) (xy 408.134821 -307.67801) (xy 408.154112 -307.632734)
			(xy 408.180415 -307.591138) (xy 408.21305 -307.554301) (xy 408.251171 -307.523176) (xy 408.293792 -307.498569)
			(xy 408.339808 -307.481117) (xy 408.388027 -307.471273) (xy 408.437202 -307.469292) (xy 408.486057 -307.475224)
			(xy 408.533328 -307.488916) (xy 408.57779 -307.510014) (xy 408.618293 -307.53797) (xy 408.653786 -307.572062)
			(xy 408.683351 -307.611406) (xy 408.706222 -307.654983) (xy 408.721806 -307.701664) (xy 408.729701 -307.750241)
			(xy 408.730196 -307.774848) (xy 409.069044 -307.774848) (xy 409.073004 -307.725794) (xy 409.084781 -307.67801)
			(xy 409.104072 -307.632734) (xy 409.130375 -307.591138) (xy 409.16301 -307.554301) (xy 409.201131 -307.523176)
			(xy 409.243752 -307.498569) (xy 409.289768 -307.481117) (xy 409.337987 -307.471273) (xy 409.387162 -307.469292)
			(xy 409.436017 -307.475224) (xy 409.483288 -307.488916) (xy 409.52775 -307.510014) (xy 409.568253 -307.53797)
			(xy 409.603746 -307.572062) (xy 409.633311 -307.611406) (xy 409.656182 -307.654983) (xy 409.671766 -307.701664)
			(xy 409.679661 -307.750241) (xy 409.680156 -307.774848) (xy 410.019004 -307.774848) (xy 410.022964 -307.725794)
			(xy 410.034741 -307.67801) (xy 410.054032 -307.632734) (xy 410.080335 -307.591138) (xy 410.11297 -307.554301)
			(xy 410.151091 -307.523176) (xy 410.193712 -307.498569) (xy 410.239728 -307.481117) (xy 410.287947 -307.471273)
			(xy 410.337122 -307.469292) (xy 410.385977 -307.475224) (xy 410.433248 -307.488916) (xy 410.47771 -307.510014)
			(xy 410.518213 -307.53797) (xy 410.553706 -307.572062) (xy 410.583271 -307.611406) (xy 410.606142 -307.654983)
			(xy 410.621726 -307.701664) (xy 410.629621 -307.750241) (xy 410.630111 -307.774594) (xy 410.968964 -307.774594)
			(xy 410.972924 -307.72554) (xy 410.984701 -307.677756) (xy 411.003992 -307.63248) (xy 411.030295 -307.590884)
			(xy 411.06293 -307.554047) (xy 411.101051 -307.522922) (xy 411.143672 -307.498315) (xy 411.189688 -307.480863)
			(xy 411.237907 -307.471019) (xy 411.287082 -307.469038) (xy 411.335937 -307.47497) (xy 411.383208 -307.488662)
			(xy 411.42767 -307.50976) (xy 411.468173 -307.537716) (xy 411.503666 -307.571808) (xy 411.533231 -307.611152)
			(xy 411.556102 -307.654729) (xy 411.571686 -307.70141) (xy 411.579581 -307.749987) (xy 411.580076 -307.774594)
			(xy 411.919178 -307.774594) (xy 411.923138 -307.72554) (xy 411.934915 -307.677756) (xy 411.954206 -307.63248)
			(xy 411.980509 -307.590884) (xy 412.013144 -307.554047) (xy 412.051265 -307.522922) (xy 412.093886 -307.498315)
			(xy 412.139902 -307.480863) (xy 412.188121 -307.471019) (xy 412.237296 -307.469038) (xy 412.286151 -307.47497)
			(xy 412.333422 -307.488662) (xy 412.377884 -307.50976) (xy 412.418387 -307.537716) (xy 412.45388 -307.571808)
			(xy 412.483445 -307.611152) (xy 412.506316 -307.654729) (xy 412.5219 -307.70141) (xy 412.529795 -307.749987)
			(xy 412.53029 -307.774594) (xy 412.530285 -307.774848) (xy 412.869138 -307.774848) (xy 412.873098 -307.725794)
			(xy 412.884875 -307.67801) (xy 412.904166 -307.632734) (xy 412.930469 -307.591138) (xy 412.963104 -307.554301)
			(xy 413.001225 -307.523176) (xy 413.043846 -307.498569) (xy 413.089862 -307.481117) (xy 413.138081 -307.471273)
			(xy 413.187256 -307.469292) (xy 413.236111 -307.475224) (xy 413.283382 -307.488916) (xy 413.327844 -307.510014)
			(xy 413.368347 -307.53797) (xy 413.40384 -307.572062) (xy 413.433405 -307.611406) (xy 413.456276 -307.654983)
			(xy 413.47186 -307.701664) (xy 413.479755 -307.750241) (xy 413.48025 -307.774848) (xy 413.819098 -307.774848)
			(xy 413.823058 -307.725794) (xy 413.834835 -307.67801) (xy 413.854126 -307.632734) (xy 413.880429 -307.591138)
			(xy 413.913064 -307.554301) (xy 413.951185 -307.523176) (xy 413.993806 -307.498569) (xy 414.039822 -307.481117)
			(xy 414.088041 -307.471273) (xy 414.137216 -307.469292) (xy 414.186071 -307.475224) (xy 414.233342 -307.488916)
			(xy 414.277804 -307.510014) (xy 414.318307 -307.53797) (xy 414.3538 -307.572062) (xy 414.383365 -307.611406)
			(xy 414.406236 -307.654983) (xy 414.42182 -307.701664) (xy 414.429715 -307.750241) (xy 414.43021 -307.774848)
			(xy 414.769058 -307.774848) (xy 414.773018 -307.725794) (xy 414.784795 -307.67801) (xy 414.804086 -307.632734)
			(xy 414.830389 -307.591138) (xy 414.863024 -307.554301) (xy 414.901145 -307.523176) (xy 414.943766 -307.498569)
			(xy 414.989782 -307.481117) (xy 415.038001 -307.471273) (xy 415.087176 -307.469292) (xy 415.136031 -307.475224)
			(xy 415.183302 -307.488916) (xy 415.227764 -307.510014) (xy 415.268267 -307.53797) (xy 415.30376 -307.572062)
			(xy 415.333325 -307.611406) (xy 415.356196 -307.654983) (xy 415.37178 -307.701664) (xy 415.379675 -307.750241)
			(xy 415.38017 -307.774848) (xy 415.719018 -307.774848) (xy 415.722978 -307.725794) (xy 415.734755 -307.67801)
			(xy 415.754046 -307.632734) (xy 415.780349 -307.591138) (xy 415.812984 -307.554301) (xy 415.851105 -307.523176)
			(xy 415.893726 -307.498569) (xy 415.939742 -307.481117) (xy 415.987961 -307.471273) (xy 416.037136 -307.469292)
			(xy 416.085991 -307.475224) (xy 416.133262 -307.488916) (xy 416.177724 -307.510014) (xy 416.218227 -307.53797)
			(xy 416.25372 -307.572062) (xy 416.283285 -307.611406) (xy 416.306156 -307.654983) (xy 416.32174 -307.701664)
			(xy 416.329635 -307.750241) (xy 416.33013 -307.774848) (xy 416.668978 -307.774848) (xy 416.672938 -307.725794)
			(xy 416.684715 -307.67801) (xy 416.704006 -307.632734) (xy 416.730309 -307.591138) (xy 416.762944 -307.554301)
			(xy 416.801065 -307.523176) (xy 416.843686 -307.498569) (xy 416.889702 -307.481117) (xy 416.937921 -307.471273)
			(xy 416.987096 -307.469292) (xy 417.035951 -307.475224) (xy 417.083222 -307.488916) (xy 417.127684 -307.510014)
			(xy 417.168187 -307.53797) (xy 417.20368 -307.572062) (xy 417.233245 -307.611406) (xy 417.256116 -307.654983)
			(xy 417.2717 -307.701664) (xy 417.279595 -307.750241) (xy 417.28009 -307.774848) (xy 417.619192 -307.774848)
			(xy 417.623152 -307.725794) (xy 417.634929 -307.67801) (xy 417.65422 -307.632734) (xy 417.680523 -307.591138)
			(xy 417.713158 -307.554301) (xy 417.751279 -307.523176) (xy 417.7939 -307.498569) (xy 417.839916 -307.481117)
			(xy 417.888135 -307.471273) (xy 417.93731 -307.469292) (xy 417.986165 -307.475224) (xy 418.033436 -307.488916)
			(xy 418.077898 -307.510014) (xy 418.118401 -307.53797) (xy 418.153894 -307.572062) (xy 418.183459 -307.611406)
			(xy 418.20633 -307.654983) (xy 418.221914 -307.701664) (xy 418.229809 -307.750241) (xy 418.230304 -307.774848)
			(xy 418.569152 -307.774848) (xy 418.573112 -307.725794) (xy 418.584889 -307.67801) (xy 418.60418 -307.632734)
			(xy 418.630483 -307.591138) (xy 418.663118 -307.554301) (xy 418.701239 -307.523176) (xy 418.74386 -307.498569)
			(xy 418.789876 -307.481117) (xy 418.838095 -307.471273) (xy 418.88727 -307.469292) (xy 418.936125 -307.475224)
			(xy 418.983396 -307.488916) (xy 419.027858 -307.510014) (xy 419.068361 -307.53797) (xy 419.103854 -307.572062)
			(xy 419.133419 -307.611406) (xy 419.15629 -307.654983) (xy 419.171874 -307.701664) (xy 419.179769 -307.750241)
			(xy 419.180264 -307.774848) (xy 419.519112 -307.774848) (xy 419.523072 -307.725794) (xy 419.534849 -307.67801)
			(xy 419.55414 -307.632734) (xy 419.580443 -307.591138) (xy 419.613078 -307.554301) (xy 419.651199 -307.523176)
			(xy 419.69382 -307.498569) (xy 419.739836 -307.481117) (xy 419.788055 -307.471273) (xy 419.83723 -307.469292)
			(xy 419.886085 -307.475224) (xy 419.933356 -307.488916) (xy 419.977818 -307.510014) (xy 420.018321 -307.53797)
			(xy 420.053814 -307.572062) (xy 420.083379 -307.611406) (xy 420.10625 -307.654983) (xy 420.121834 -307.701664)
			(xy 420.129729 -307.750241) (xy 420.130224 -307.774848) (xy 420.469072 -307.774848) (xy 420.473032 -307.725794)
			(xy 420.484809 -307.67801) (xy 420.5041 -307.632734) (xy 420.530403 -307.591138) (xy 420.563038 -307.554301)
			(xy 420.601159 -307.523176) (xy 420.64378 -307.498569) (xy 420.689796 -307.481117) (xy 420.738015 -307.471273)
			(xy 420.78719 -307.469292) (xy 420.836045 -307.475224) (xy 420.883316 -307.488916) (xy 420.927778 -307.510014)
			(xy 420.968281 -307.53797) (xy 421.003774 -307.572062) (xy 421.033339 -307.611406) (xy 421.05621 -307.654983)
			(xy 421.071794 -307.701664) (xy 421.079689 -307.750241) (xy 421.080184 -307.774848) (xy 421.419032 -307.774848)
			(xy 421.422992 -307.725794) (xy 421.434769 -307.67801) (xy 421.45406 -307.632734) (xy 421.480363 -307.591138)
			(xy 421.512998 -307.554301) (xy 421.551119 -307.523176) (xy 421.59374 -307.498569) (xy 421.639756 -307.481117)
			(xy 421.687975 -307.471273) (xy 421.73715 -307.469292) (xy 421.786005 -307.475224) (xy 421.833276 -307.488916)
			(xy 421.877738 -307.510014) (xy 421.918241 -307.53797) (xy 421.953734 -307.572062) (xy 421.983299 -307.611406)
			(xy 422.00617 -307.654983) (xy 422.021754 -307.701664) (xy 422.029649 -307.750241) (xy 422.030144 -307.774848)
			(xy 422.029649 -307.799455) (xy 422.021754 -307.848032) (xy 422.00617 -307.894713) (xy 421.983299 -307.93829)
			(xy 421.953734 -307.977634) (xy 421.918241 -308.011726) (xy 421.877738 -308.039682) (xy 421.833276 -308.06078)
			(xy 421.786005 -308.074472) (xy 421.73715 -308.080404) (xy 421.687975 -308.078423) (xy 421.639756 -308.068579)
			(xy 421.59374 -308.051127) (xy 421.551119 -308.02652) (xy 421.512998 -307.995395) (xy 421.480363 -307.958558)
			(xy 421.45406 -307.916962) (xy 421.434769 -307.871686) (xy 421.422992 -307.823902) (xy 421.419032 -307.774848)
			(xy 421.080184 -307.774848) (xy 421.079689 -307.799455) (xy 421.071794 -307.848032) (xy 421.05621 -307.894713)
			(xy 421.033339 -307.93829) (xy 421.003774 -307.977634) (xy 420.968281 -308.011726) (xy 420.927778 -308.039682)
			(xy 420.883316 -308.06078) (xy 420.836045 -308.074472) (xy 420.78719 -308.080404) (xy 420.738015 -308.078423)
			(xy 420.689796 -308.068579) (xy 420.64378 -308.051127) (xy 420.601159 -308.02652) (xy 420.563038 -307.995395)
			(xy 420.530403 -307.958558) (xy 420.5041 -307.916962) (xy 420.484809 -307.871686) (xy 420.473032 -307.823902)
			(xy 420.469072 -307.774848) (xy 420.130224 -307.774848) (xy 420.129729 -307.799455) (xy 420.121834 -307.848032)
			(xy 420.10625 -307.894713) (xy 420.083379 -307.93829) (xy 420.053814 -307.977634) (xy 420.018321 -308.011726)
			(xy 419.977818 -308.039682) (xy 419.933356 -308.06078) (xy 419.886085 -308.074472) (xy 419.83723 -308.080404)
			(xy 419.788055 -308.078423) (xy 419.739836 -308.068579) (xy 419.69382 -308.051127) (xy 419.651199 -308.02652)
			(xy 419.613078 -307.995395) (xy 419.580443 -307.958558) (xy 419.55414 -307.916962) (xy 419.534849 -307.871686)
			(xy 419.523072 -307.823902) (xy 419.519112 -307.774848) (xy 419.180264 -307.774848) (xy 419.179769 -307.799455)
			(xy 419.171874 -307.848032) (xy 419.15629 -307.894713) (xy 419.133419 -307.93829) (xy 419.103854 -307.977634)
			(xy 419.068361 -308.011726) (xy 419.027858 -308.039682) (xy 418.983396 -308.06078) (xy 418.936125 -308.074472)
			(xy 418.88727 -308.080404) (xy 418.838095 -308.078423) (xy 418.789876 -308.068579) (xy 418.74386 -308.051127)
			(xy 418.701239 -308.02652) (xy 418.663118 -307.995395) (xy 418.630483 -307.958558) (xy 418.60418 -307.916962)
			(xy 418.584889 -307.871686) (xy 418.573112 -307.823902) (xy 418.569152 -307.774848) (xy 418.230304 -307.774848)
			(xy 418.229809 -307.799455) (xy 418.221914 -307.848032) (xy 418.20633 -307.894713) (xy 418.183459 -307.93829)
			(xy 418.153894 -307.977634) (xy 418.118401 -308.011726) (xy 418.077898 -308.039682) (xy 418.033436 -308.06078)
			(xy 417.986165 -308.074472) (xy 417.93731 -308.080404) (xy 417.888135 -308.078423) (xy 417.839916 -308.068579)
			(xy 417.7939 -308.051127) (xy 417.751279 -308.02652) (xy 417.713158 -307.995395) (xy 417.680523 -307.958558)
			(xy 417.65422 -307.916962) (xy 417.634929 -307.871686) (xy 417.623152 -307.823902) (xy 417.619192 -307.774848)
			(xy 417.28009 -307.774848) (xy 417.279595 -307.799455) (xy 417.2717 -307.848032) (xy 417.256116 -307.894713)
			(xy 417.233245 -307.93829) (xy 417.20368 -307.977634) (xy 417.168187 -308.011726) (xy 417.127684 -308.039682)
			(xy 417.083222 -308.06078) (xy 417.035951 -308.074472) (xy 416.987096 -308.080404) (xy 416.937921 -308.078423)
			(xy 416.889702 -308.068579) (xy 416.843686 -308.051127) (xy 416.801065 -308.02652) (xy 416.762944 -307.995395)
			(xy 416.730309 -307.958558) (xy 416.704006 -307.916962) (xy 416.684715 -307.871686) (xy 416.672938 -307.823902)
			(xy 416.668978 -307.774848) (xy 416.33013 -307.774848) (xy 416.329635 -307.799455) (xy 416.32174 -307.848032)
			(xy 416.306156 -307.894713) (xy 416.283285 -307.93829) (xy 416.25372 -307.977634) (xy 416.218227 -308.011726)
			(xy 416.177724 -308.039682) (xy 416.133262 -308.06078) (xy 416.085991 -308.074472) (xy 416.037136 -308.080404)
			(xy 415.987961 -308.078423) (xy 415.939742 -308.068579) (xy 415.893726 -308.051127) (xy 415.851105 -308.02652)
			(xy 415.812984 -307.995395) (xy 415.780349 -307.958558) (xy 415.754046 -307.916962) (xy 415.734755 -307.871686)
			(xy 415.722978 -307.823902) (xy 415.719018 -307.774848) (xy 415.38017 -307.774848) (xy 415.379675 -307.799455)
			(xy 415.37178 -307.848032) (xy 415.356196 -307.894713) (xy 415.333325 -307.93829) (xy 415.30376 -307.977634)
			(xy 415.268267 -308.011726) (xy 415.227764 -308.039682) (xy 415.183302 -308.06078) (xy 415.136031 -308.074472)
			(xy 415.087176 -308.080404) (xy 415.038001 -308.078423) (xy 414.989782 -308.068579) (xy 414.943766 -308.051127)
			(xy 414.901145 -308.02652) (xy 414.863024 -307.995395) (xy 414.830389 -307.958558) (xy 414.804086 -307.916962)
			(xy 414.784795 -307.871686) (xy 414.773018 -307.823902) (xy 414.769058 -307.774848) (xy 414.43021 -307.774848)
			(xy 414.429715 -307.799455) (xy 414.42182 -307.848032) (xy 414.406236 -307.894713) (xy 414.383365 -307.93829)
			(xy 414.3538 -307.977634) (xy 414.318307 -308.011726) (xy 414.277804 -308.039682) (xy 414.233342 -308.06078)
			(xy 414.186071 -308.074472) (xy 414.137216 -308.080404) (xy 414.088041 -308.078423) (xy 414.039822 -308.068579)
			(xy 413.993806 -308.051127) (xy 413.951185 -308.02652) (xy 413.913064 -307.995395) (xy 413.880429 -307.958558)
			(xy 413.854126 -307.916962) (xy 413.834835 -307.871686) (xy 413.823058 -307.823902) (xy 413.819098 -307.774848)
			(xy 413.48025 -307.774848) (xy 413.479755 -307.799455) (xy 413.47186 -307.848032) (xy 413.456276 -307.894713)
			(xy 413.433405 -307.93829) (xy 413.40384 -307.977634) (xy 413.368347 -308.011726) (xy 413.327844 -308.039682)
			(xy 413.283382 -308.06078) (xy 413.236111 -308.074472) (xy 413.187256 -308.080404) (xy 413.138081 -308.078423)
			(xy 413.089862 -308.068579) (xy 413.043846 -308.051127) (xy 413.001225 -308.02652) (xy 412.963104 -307.995395)
			(xy 412.930469 -307.958558) (xy 412.904166 -307.916962) (xy 412.884875 -307.871686) (xy 412.873098 -307.823902)
			(xy 412.869138 -307.774848) (xy 412.530285 -307.774848) (xy 412.529795 -307.799201) (xy 412.5219 -307.847778)
			(xy 412.506316 -307.894459) (xy 412.483445 -307.938036) (xy 412.45388 -307.97738) (xy 412.418387 -308.011472)
			(xy 412.377884 -308.039428) (xy 412.333422 -308.060526) (xy 412.286151 -308.074218) (xy 412.237296 -308.08015)
			(xy 412.188121 -308.078169) (xy 412.139902 -308.068325) (xy 412.093886 -308.050873) (xy 412.051265 -308.026266)
			(xy 412.013144 -307.995141) (xy 411.980509 -307.958304) (xy 411.954206 -307.916708) (xy 411.934915 -307.871432)
			(xy 411.923138 -307.823648) (xy 411.919178 -307.774594) (xy 411.580076 -307.774594) (xy 411.579581 -307.799201)
			(xy 411.571686 -307.847778) (xy 411.556102 -307.894459) (xy 411.533231 -307.938036) (xy 411.503666 -307.97738)
			(xy 411.468173 -308.011472) (xy 411.42767 -308.039428) (xy 411.383208 -308.060526) (xy 411.335937 -308.074218)
			(xy 411.287082 -308.08015) (xy 411.237907 -308.078169) (xy 411.189688 -308.068325) (xy 411.143672 -308.050873)
			(xy 411.101051 -308.026266) (xy 411.06293 -307.995141) (xy 411.030295 -307.958304) (xy 411.003992 -307.916708)
			(xy 410.984701 -307.871432) (xy 410.972924 -307.823648) (xy 410.968964 -307.774594) (xy 410.630111 -307.774594)
			(xy 410.630116 -307.774848) (xy 410.629621 -307.799455) (xy 410.621726 -307.848032) (xy 410.606142 -307.894713)
			(xy 410.583271 -307.93829) (xy 410.553706 -307.977634) (xy 410.518213 -308.011726) (xy 410.47771 -308.039682)
			(xy 410.433248 -308.06078) (xy 410.385977 -308.074472) (xy 410.337122 -308.080404) (xy 410.287947 -308.078423)
			(xy 410.239728 -308.068579) (xy 410.193712 -308.051127) (xy 410.151091 -308.02652) (xy 410.11297 -307.995395)
			(xy 410.080335 -307.958558) (xy 410.054032 -307.916962) (xy 410.034741 -307.871686) (xy 410.022964 -307.823902)
			(xy 410.019004 -307.774848) (xy 409.680156 -307.774848) (xy 409.679661 -307.799455) (xy 409.671766 -307.848032)
			(xy 409.656182 -307.894713) (xy 409.633311 -307.93829) (xy 409.603746 -307.977634) (xy 409.568253 -308.011726)
			(xy 409.52775 -308.039682) (xy 409.483288 -308.06078) (xy 409.436017 -308.074472) (xy 409.387162 -308.080404)
			(xy 409.337987 -308.078423) (xy 409.289768 -308.068579) (xy 409.243752 -308.051127) (xy 409.201131 -308.02652)
			(xy 409.16301 -307.995395) (xy 409.130375 -307.958558) (xy 409.104072 -307.916962) (xy 409.084781 -307.871686)
			(xy 409.073004 -307.823902) (xy 409.069044 -307.774848) (xy 408.730196 -307.774848) (xy 408.729701 -307.799455)
			(xy 408.721806 -307.848032) (xy 408.706222 -307.894713) (xy 408.683351 -307.93829) (xy 408.653786 -307.977634)
			(xy 408.618293 -308.011726) (xy 408.57779 -308.039682) (xy 408.533328 -308.06078) (xy 408.486057 -308.074472)
			(xy 408.437202 -308.080404) (xy 408.388027 -308.078423) (xy 408.339808 -308.068579) (xy 408.293792 -308.051127)
			(xy 408.251171 -308.02652) (xy 408.21305 -307.995395) (xy 408.180415 -307.958558) (xy 408.154112 -307.916962)
			(xy 408.134821 -307.871686) (xy 408.123044 -307.823902) (xy 408.119084 -307.774848) (xy 406.830276 -307.774848)
			(xy 406.829781 -307.799455) (xy 406.821886 -307.848032) (xy 406.806302 -307.894713) (xy 406.783431 -307.93829)
			(xy 406.753866 -307.977634) (xy 406.718373 -308.011726) (xy 406.67787 -308.039682) (xy 406.633408 -308.06078)
			(xy 406.586137 -308.074472) (xy 406.537282 -308.080404) (xy 406.488107 -308.078423) (xy 406.439888 -308.068579)
			(xy 406.393872 -308.051127) (xy 406.351251 -308.02652) (xy 406.31313 -307.995395) (xy 406.280495 -307.958558)
			(xy 406.254192 -307.916962) (xy 406.234901 -307.871686) (xy 406.223124 -307.823902) (xy 406.219164 -307.774848)
			(xy 405.880316 -307.774848) (xy 405.879821 -307.799455) (xy 405.871926 -307.848032) (xy 405.856342 -307.894713)
			(xy 405.833471 -307.93829) (xy 405.803906 -307.977634) (xy 405.768413 -308.011726) (xy 405.72791 -308.039682)
			(xy 405.683448 -308.06078) (xy 405.636177 -308.074472) (xy 405.587322 -308.080404) (xy 405.538147 -308.078423)
			(xy 405.489928 -308.068579) (xy 405.443912 -308.051127) (xy 405.401291 -308.02652) (xy 405.36317 -307.995395)
			(xy 405.330535 -307.958558) (xy 405.304232 -307.916962) (xy 405.284941 -307.871686) (xy 405.273164 -307.823902)
			(xy 405.269204 -307.774848) (xy 404.930356 -307.774848) (xy 404.929861 -307.799455) (xy 404.921966 -307.848032)
			(xy 404.906382 -307.894713) (xy 404.883511 -307.93829) (xy 404.853946 -307.977634) (xy 404.818453 -308.011726)
			(xy 404.77795 -308.039682) (xy 404.733488 -308.06078) (xy 404.686217 -308.074472) (xy 404.637362 -308.080404)
			(xy 404.588187 -308.078423) (xy 404.539968 -308.068579) (xy 404.493952 -308.051127) (xy 404.451331 -308.02652)
			(xy 404.41321 -307.995395) (xy 404.380575 -307.958558) (xy 404.354272 -307.916962) (xy 404.334981 -307.871686)
			(xy 404.323204 -307.823902) (xy 404.319244 -307.774848) (xy 403.980142 -307.774848) (xy 403.979647 -307.799455)
			(xy 403.971752 -307.848032) (xy 403.956168 -307.894713) (xy 403.933297 -307.93829) (xy 403.903732 -307.977634)
			(xy 403.868239 -308.011726) (xy 403.827736 -308.039682) (xy 403.783274 -308.06078) (xy 403.736003 -308.074472)
			(xy 403.687148 -308.080404) (xy 403.637973 -308.078423) (xy 403.589754 -308.068579) (xy 403.543738 -308.051127)
			(xy 403.501117 -308.02652) (xy 403.462996 -307.995395) (xy 403.430361 -307.958558) (xy 403.404058 -307.916962)
			(xy 403.384767 -307.871686) (xy 403.37299 -307.823902) (xy 403.36903 -307.774848) (xy 403.030182 -307.774848)
			(xy 403.029687 -307.799455) (xy 403.021792 -307.848032) (xy 403.006208 -307.894713) (xy 402.983337 -307.93829)
			(xy 402.953772 -307.977634) (xy 402.918279 -308.011726) (xy 402.877776 -308.039682) (xy 402.833314 -308.06078)
			(xy 402.786043 -308.074472) (xy 402.737188 -308.080404) (xy 402.688013 -308.078423) (xy 402.639794 -308.068579)
			(xy 402.593778 -308.051127) (xy 402.551157 -308.02652) (xy 402.513036 -307.995395) (xy 402.480401 -307.958558)
			(xy 402.454098 -307.916962) (xy 402.434807 -307.871686) (xy 402.42303 -307.823902) (xy 402.41907 -307.774848)
			(xy 402.080222 -307.774848) (xy 402.079727 -307.799455) (xy 402.071832 -307.848032) (xy 402.056248 -307.894713)
			(xy 402.033377 -307.93829) (xy 402.003812 -307.977634) (xy 401.968319 -308.011726) (xy 401.927816 -308.039682)
			(xy 401.883354 -308.06078) (xy 401.836083 -308.074472) (xy 401.787228 -308.080404) (xy 401.738053 -308.078423)
			(xy 401.689834 -308.068579) (xy 401.643818 -308.051127) (xy 401.601197 -308.02652) (xy 401.563076 -307.995395)
			(xy 401.530441 -307.958558) (xy 401.504138 -307.916962) (xy 401.484847 -307.871686) (xy 401.47307 -307.823902)
			(xy 401.46911 -307.774848) (xy 401.130262 -307.774848) (xy 401.129767 -307.799455) (xy 401.121872 -307.848032)
			(xy 401.106288 -307.894713) (xy 401.083417 -307.93829) (xy 401.053852 -307.977634) (xy 401.018359 -308.011726)
			(xy 400.977856 -308.039682) (xy 400.933394 -308.06078) (xy 400.886123 -308.074472) (xy 400.837268 -308.080404)
			(xy 400.788093 -308.078423) (xy 400.739874 -308.068579) (xy 400.693858 -308.051127) (xy 400.651237 -308.02652)
			(xy 400.613116 -307.995395) (xy 400.580481 -307.958558) (xy 400.554178 -307.916962) (xy 400.534887 -307.871686)
			(xy 400.52311 -307.823902) (xy 400.51915 -307.774848) (xy 400.180302 -307.774848) (xy 400.179807 -307.799455)
			(xy 400.171912 -307.848032) (xy 400.156328 -307.894713) (xy 400.133457 -307.93829) (xy 400.103892 -307.977634)
			(xy 400.068399 -308.011726) (xy 400.027896 -308.039682) (xy 399.983434 -308.06078) (xy 399.936163 -308.074472)
			(xy 399.887308 -308.080404) (xy 399.838133 -308.078423) (xy 399.789914 -308.068579) (xy 399.743898 -308.051127)
			(xy 399.701277 -308.02652) (xy 399.663156 -307.995395) (xy 399.630521 -307.958558) (xy 399.604218 -307.916962)
			(xy 399.584927 -307.871686) (xy 399.57315 -307.823902) (xy 399.56919 -307.774848) (xy 399.230342 -307.774848)
			(xy 399.229847 -307.799455) (xy 399.221952 -307.848032) (xy 399.206368 -307.894713) (xy 399.183497 -307.93829)
			(xy 399.153932 -307.977634) (xy 399.118439 -308.011726) (xy 399.077936 -308.039682) (xy 399.033474 -308.06078)
			(xy 398.986203 -308.074472) (xy 398.937348 -308.080404) (xy 398.888173 -308.078423) (xy 398.839954 -308.068579)
			(xy 398.793938 -308.051127) (xy 398.751317 -308.02652) (xy 398.713196 -307.995395) (xy 398.680561 -307.958558)
			(xy 398.654258 -307.916962) (xy 398.634967 -307.871686) (xy 398.62319 -307.823902) (xy 398.61923 -307.774848)
			(xy 398.280128 -307.774848) (xy 398.279633 -307.799455) (xy 398.271738 -307.848032) (xy 398.256154 -307.894713)
			(xy 398.233283 -307.93829) (xy 398.203718 -307.977634) (xy 398.168225 -308.011726) (xy 398.127722 -308.039682)
			(xy 398.08326 -308.06078) (xy 398.035989 -308.074472) (xy 397.987134 -308.080404) (xy 397.937959 -308.078423)
			(xy 397.88974 -308.068579) (xy 397.843724 -308.051127) (xy 397.801103 -308.02652) (xy 397.762982 -307.995395)
			(xy 397.730347 -307.958558) (xy 397.704044 -307.916962) (xy 397.684753 -307.871686) (xy 397.672976 -307.823902)
			(xy 397.669016 -307.774848) (xy 397.330168 -307.774848) (xy 397.329673 -307.799455) (xy 397.321778 -307.848032)
			(xy 397.306194 -307.894713) (xy 397.283323 -307.93829) (xy 397.253758 -307.977634) (xy 397.218265 -308.011726)
			(xy 397.177762 -308.039682) (xy 397.1333 -308.06078) (xy 397.086029 -308.074472) (xy 397.037174 -308.080404)
			(xy 396.987999 -308.078423) (xy 396.93978 -308.068579) (xy 396.893764 -308.051127) (xy 396.851143 -308.02652)
			(xy 396.813022 -307.995395) (xy 396.780387 -307.958558) (xy 396.754084 -307.916962) (xy 396.734793 -307.871686)
			(xy 396.723016 -307.823902) (xy 396.719056 -307.774848) (xy 396.380208 -307.774848) (xy 396.379713 -307.799455)
			(xy 396.371818 -307.848032) (xy 396.356234 -307.894713) (xy 396.333363 -307.93829) (xy 396.303798 -307.977634)
			(xy 396.268305 -308.011726) (xy 396.227802 -308.039682) (xy 396.18334 -308.06078) (xy 396.136069 -308.074472)
			(xy 396.087214 -308.080404) (xy 396.038039 -308.078423) (xy 395.98982 -308.068579) (xy 395.943804 -308.051127)
			(xy 395.901183 -308.02652) (xy 395.863062 -307.995395) (xy 395.830427 -307.958558) (xy 395.804124 -307.916962)
			(xy 395.784833 -307.871686) (xy 395.773056 -307.823902) (xy 395.769096 -307.774848) (xy 395.430248 -307.774848)
			(xy 395.429753 -307.799455) (xy 395.421858 -307.848032) (xy 395.406274 -307.894713) (xy 395.383403 -307.93829)
			(xy 395.353838 -307.977634) (xy 395.318345 -308.011726) (xy 395.277842 -308.039682) (xy 395.23338 -308.06078)
			(xy 395.186109 -308.074472) (xy 395.137254 -308.080404) (xy 395.088079 -308.078423) (xy 395.03986 -308.068579)
			(xy 394.993844 -308.051127) (xy 394.951223 -308.02652) (xy 394.913102 -307.995395) (xy 394.880467 -307.958558)
			(xy 394.854164 -307.916962) (xy 394.834873 -307.871686) (xy 394.823096 -307.823902) (xy 394.819136 -307.774848)
			(xy 389.255 -307.774848) (xy 389.255 -308.241446) (xy 389.255254 -308.249066) (xy 389.255254 -308.249828)
			(xy 389.594102 -308.249828) (xy 389.598062 -308.200774) (xy 389.609839 -308.15299) (xy 389.62913 -308.107714)
			(xy 389.655433 -308.066118) (xy 389.688068 -308.029281) (xy 389.726189 -307.998156) (xy 389.76881 -307.973549)
			(xy 389.814826 -307.956097) (xy 389.863045 -307.946253) (xy 389.91222 -307.944272) (xy 389.961075 -307.950204)
			(xy 390.008346 -307.963896) (xy 390.052808 -307.984994) (xy 390.093311 -308.01295) (xy 390.128804 -308.047042)
			(xy 390.158369 -308.086386) (xy 390.18124 -308.129963) (xy 390.196824 -308.176644) (xy 390.204719 -308.225221)
			(xy 390.205214 -308.249828) (xy 390.544062 -308.249828) (xy 390.548022 -308.200774) (xy 390.559799 -308.15299)
			(xy 390.57909 -308.107714) (xy 390.605393 -308.066118) (xy 390.638028 -308.029281) (xy 390.676149 -307.998156)
			(xy 390.71877 -307.973549) (xy 390.764786 -307.956097) (xy 390.813005 -307.946253) (xy 390.86218 -307.944272)
			(xy 390.911035 -307.950204) (xy 390.958306 -307.963896) (xy 391.002768 -307.984994) (xy 391.043271 -308.01295)
			(xy 391.078764 -308.047042) (xy 391.108329 -308.086386) (xy 391.1312 -308.129963) (xy 391.146784 -308.176644)
			(xy 391.154679 -308.225221) (xy 391.155174 -308.249828) (xy 391.494022 -308.249828) (xy 391.497982 -308.200774)
			(xy 391.509759 -308.15299) (xy 391.52905 -308.107714) (xy 391.555353 -308.066118) (xy 391.587988 -308.029281)
			(xy 391.626109 -307.998156) (xy 391.66873 -307.973549) (xy 391.714746 -307.956097) (xy 391.762965 -307.946253)
			(xy 391.81214 -307.944272) (xy 391.860995 -307.950204) (xy 391.908266 -307.963896) (xy 391.952728 -307.984994)
			(xy 391.993231 -308.01295) (xy 392.028724 -308.047042) (xy 392.058289 -308.086386) (xy 392.08116 -308.129963)
			(xy 392.096744 -308.176644) (xy 392.104639 -308.225221) (xy 392.105134 -308.249828) (xy 392.443982 -308.249828)
			(xy 392.447942 -308.200774) (xy 392.459719 -308.15299) (xy 392.47901 -308.107714) (xy 392.505313 -308.066118)
			(xy 392.537948 -308.029281) (xy 392.576069 -307.998156) (xy 392.61869 -307.973549) (xy 392.664706 -307.956097)
			(xy 392.712925 -307.946253) (xy 392.7621 -307.944272) (xy 392.810955 -307.950204) (xy 392.858226 -307.963896)
			(xy 392.902688 -307.984994) (xy 392.943191 -308.01295) (xy 392.978684 -308.047042) (xy 393.008249 -308.086386)
			(xy 393.03112 -308.129963) (xy 393.046704 -308.176644) (xy 393.054599 -308.225221) (xy 393.055094 -308.249828)
			(xy 393.394196 -308.249828) (xy 393.398156 -308.200774) (xy 393.409933 -308.15299) (xy 393.429224 -308.107714)
			(xy 393.455527 -308.066118) (xy 393.488162 -308.029281) (xy 393.526283 -307.998156) (xy 393.568904 -307.973549)
			(xy 393.61492 -307.956097) (xy 393.663139 -307.946253) (xy 393.712314 -307.944272) (xy 393.761169 -307.950204)
			(xy 393.80844 -307.963896) (xy 393.852902 -307.984994) (xy 393.893405 -308.01295) (xy 393.928898 -308.047042)
			(xy 393.958463 -308.086386) (xy 393.981334 -308.129963) (xy 393.996918 -308.176644) (xy 394.004813 -308.225221)
			(xy 394.005308 -308.249828) (xy 394.004813 -308.274435) (xy 394.004634 -308.275536) (xy 422.823382 -308.275536)
			(xy 422.823382 -308.22412) (xy 422.831425 -308.173338) (xy 422.847313 -308.124439) (xy 422.870656 -308.078627)
			(xy 422.900877 -308.037031) (xy 422.937233 -308.000675) (xy 422.978829 -307.970454) (xy 423.024641 -307.947111)
			(xy 423.07354 -307.931223) (xy 423.124322 -307.92318) (xy 423.175738 -307.92318) (xy 423.22652 -307.931223)
			(xy 423.275419 -307.947111) (xy 423.321231 -307.970454) (xy 423.362827 -308.000675) (xy 423.399183 -308.037031)
			(xy 423.429404 -308.078627) (xy 423.452747 -308.124439) (xy 423.468635 -308.173338) (xy 423.476678 -308.22412)
			(xy 423.477182 -308.249828) (xy 423.476678 -308.275536) (xy 423.773342 -308.275536) (xy 423.773342 -308.22412)
			(xy 423.781385 -308.173338) (xy 423.797273 -308.124439) (xy 423.820616 -308.078627) (xy 423.850837 -308.037031)
			(xy 423.887193 -308.000675) (xy 423.928789 -307.970454) (xy 423.974601 -307.947111) (xy 424.0235 -307.931223)
			(xy 424.074282 -307.92318) (xy 424.125698 -307.92318) (xy 424.17648 -307.931223) (xy 424.225379 -307.947111)
			(xy 424.271191 -307.970454) (xy 424.312787 -308.000675) (xy 424.349143 -308.037031) (xy 424.379364 -308.078627)
			(xy 424.402707 -308.124439) (xy 424.418595 -308.173338) (xy 424.426638 -308.22412) (xy 424.427142 -308.249828)
			(xy 424.426638 -308.275536) (xy 424.418595 -308.326318) (xy 424.402707 -308.375217) (xy 424.379364 -308.421029)
			(xy 424.349143 -308.462625) (xy 424.312787 -308.498981) (xy 424.271191 -308.529202) (xy 424.225379 -308.552545)
			(xy 424.17648 -308.568433) (xy 424.125698 -308.576476) (xy 424.074282 -308.576476) (xy 424.0235 -308.568433)
			(xy 423.974601 -308.552545) (xy 423.928789 -308.529202) (xy 423.887193 -308.498981) (xy 423.850837 -308.462625)
			(xy 423.820616 -308.421029) (xy 423.797273 -308.375217) (xy 423.781385 -308.326318) (xy 423.773342 -308.275536)
			(xy 423.476678 -308.275536) (xy 423.468635 -308.326318) (xy 423.452747 -308.375217) (xy 423.429404 -308.421029)
			(xy 423.399183 -308.462625) (xy 423.362827 -308.498981) (xy 423.321231 -308.529202) (xy 423.275419 -308.552545)
			(xy 423.22652 -308.568433) (xy 423.175738 -308.576476) (xy 423.124322 -308.576476) (xy 423.07354 -308.568433)
			(xy 423.024641 -308.552545) (xy 422.978829 -308.529202) (xy 422.937233 -308.498981) (xy 422.900877 -308.462625)
			(xy 422.870656 -308.421029) (xy 422.847313 -308.375217) (xy 422.831425 -308.326318) (xy 422.823382 -308.275536)
			(xy 394.004634 -308.275536) (xy 393.996918 -308.323012) (xy 393.981334 -308.369693) (xy 393.958463 -308.41327)
			(xy 393.928898 -308.452614) (xy 393.893405 -308.486706) (xy 393.852902 -308.514662) (xy 393.80844 -308.53576)
			(xy 393.761169 -308.549452) (xy 393.712314 -308.555384) (xy 393.663139 -308.553403) (xy 393.61492 -308.543559)
			(xy 393.568904 -308.526107) (xy 393.526283 -308.5015) (xy 393.488162 -308.470375) (xy 393.455527 -308.433538)
			(xy 393.429224 -308.391942) (xy 393.409933 -308.346666) (xy 393.398156 -308.298882) (xy 393.394196 -308.249828)
			(xy 393.055094 -308.249828) (xy 393.054599 -308.274435) (xy 393.046704 -308.323012) (xy 393.03112 -308.369693)
			(xy 393.008249 -308.41327) (xy 392.978684 -308.452614) (xy 392.943191 -308.486706) (xy 392.902688 -308.514662)
			(xy 392.858226 -308.53576) (xy 392.810955 -308.549452) (xy 392.7621 -308.555384) (xy 392.712925 -308.553403)
			(xy 392.664706 -308.543559) (xy 392.61869 -308.526107) (xy 392.576069 -308.5015) (xy 392.537948 -308.470375)
			(xy 392.505313 -308.433538) (xy 392.47901 -308.391942) (xy 392.459719 -308.346666) (xy 392.447942 -308.298882)
			(xy 392.443982 -308.249828) (xy 392.105134 -308.249828) (xy 392.104639 -308.274435) (xy 392.096744 -308.323012)
			(xy 392.08116 -308.369693) (xy 392.058289 -308.41327) (xy 392.028724 -308.452614) (xy 391.993231 -308.486706)
			(xy 391.952728 -308.514662) (xy 391.908266 -308.53576) (xy 391.860995 -308.549452) (xy 391.81214 -308.555384)
			(xy 391.762965 -308.553403) (xy 391.714746 -308.543559) (xy 391.66873 -308.526107) (xy 391.626109 -308.5015)
			(xy 391.587988 -308.470375) (xy 391.555353 -308.433538) (xy 391.52905 -308.391942) (xy 391.509759 -308.346666)
			(xy 391.497982 -308.298882) (xy 391.494022 -308.249828) (xy 391.155174 -308.249828) (xy 391.154679 -308.274435)
			(xy 391.146784 -308.323012) (xy 391.1312 -308.369693) (xy 391.108329 -308.41327) (xy 391.078764 -308.452614)
			(xy 391.043271 -308.486706) (xy 391.002768 -308.514662) (xy 390.958306 -308.53576) (xy 390.911035 -308.549452)
			(xy 390.86218 -308.555384) (xy 390.813005 -308.553403) (xy 390.764786 -308.543559) (xy 390.71877 -308.526107)
			(xy 390.676149 -308.5015) (xy 390.638028 -308.470375) (xy 390.605393 -308.433538) (xy 390.57909 -308.391942)
			(xy 390.559799 -308.346666) (xy 390.548022 -308.298882) (xy 390.544062 -308.249828) (xy 390.205214 -308.249828)
			(xy 390.204719 -308.274435) (xy 390.196824 -308.323012) (xy 390.18124 -308.369693) (xy 390.158369 -308.41327)
			(xy 390.128804 -308.452614) (xy 390.093311 -308.486706) (xy 390.052808 -308.514662) (xy 390.008346 -308.53576)
			(xy 389.961075 -308.549452) (xy 389.91222 -308.555384) (xy 389.863045 -308.553403) (xy 389.814826 -308.543559)
			(xy 389.76881 -308.526107) (xy 389.726189 -308.5015) (xy 389.688068 -308.470375) (xy 389.655433 -308.433538)
			(xy 389.62913 -308.391942) (xy 389.609839 -308.346666) (xy 389.598062 -308.298882) (xy 389.594102 -308.249828)
			(xy 389.255254 -308.249828) (xy 389.255254 -308.25059) (xy 389.255 -308.25821) (xy 389.255 -309.191406)
			(xy 389.255254 -309.199026) (xy 389.255254 -309.199788) (xy 389.594102 -309.199788) (xy 389.598062 -309.150734)
			(xy 389.609839 -309.10295) (xy 389.62913 -309.057674) (xy 389.655433 -309.016078) (xy 389.688068 -308.979241)
			(xy 389.726189 -308.948116) (xy 389.76881 -308.923509) (xy 389.814826 -308.906057) (xy 389.863045 -308.896213)
			(xy 389.91222 -308.894232) (xy 389.961075 -308.900164) (xy 390.008346 -308.913856) (xy 390.052808 -308.934954)
			(xy 390.093311 -308.96291) (xy 390.128804 -308.997002) (xy 390.158369 -309.036346) (xy 390.18124 -309.079923)
			(xy 390.196824 -309.126604) (xy 390.204719 -309.175181) (xy 390.205214 -309.199788) (xy 390.544062 -309.199788)
			(xy 390.548022 -309.150734) (xy 390.559799 -309.10295) (xy 390.57909 -309.057674) (xy 390.605393 -309.016078)
			(xy 390.638028 -308.979241) (xy 390.676149 -308.948116) (xy 390.71877 -308.923509) (xy 390.764786 -308.906057)
			(xy 390.813005 -308.896213) (xy 390.86218 -308.894232) (xy 390.911035 -308.900164) (xy 390.958306 -308.913856)
			(xy 391.002768 -308.934954) (xy 391.043271 -308.96291) (xy 391.078764 -308.997002) (xy 391.108329 -309.036346)
			(xy 391.1312 -309.079923) (xy 391.146784 -309.126604) (xy 391.154679 -309.175181) (xy 391.155174 -309.199788)
			(xy 391.494022 -309.199788) (xy 391.497982 -309.150734) (xy 391.509759 -309.10295) (xy 391.52905 -309.057674)
			(xy 391.555353 -309.016078) (xy 391.587988 -308.979241) (xy 391.626109 -308.948116) (xy 391.66873 -308.923509)
			(xy 391.714746 -308.906057) (xy 391.762965 -308.896213) (xy 391.81214 -308.894232) (xy 391.860995 -308.900164)
			(xy 391.908266 -308.913856) (xy 391.952728 -308.934954) (xy 391.993231 -308.96291) (xy 392.028724 -308.997002)
			(xy 392.058289 -309.036346) (xy 392.08116 -309.079923) (xy 392.096744 -309.126604) (xy 392.104639 -309.175181)
			(xy 392.105134 -309.199788) (xy 392.443982 -309.199788) (xy 392.447942 -309.150734) (xy 392.459719 -309.10295)
			(xy 392.47901 -309.057674) (xy 392.505313 -309.016078) (xy 392.537948 -308.979241) (xy 392.576069 -308.948116)
			(xy 392.61869 -308.923509) (xy 392.664706 -308.906057) (xy 392.712925 -308.896213) (xy 392.7621 -308.894232)
			(xy 392.810955 -308.900164) (xy 392.858226 -308.913856) (xy 392.902688 -308.934954) (xy 392.943191 -308.96291)
			(xy 392.978684 -308.997002) (xy 393.008249 -309.036346) (xy 393.03112 -309.079923) (xy 393.046704 -309.126604)
			(xy 393.054599 -309.175181) (xy 393.055094 -309.199788) (xy 393.394196 -309.199788) (xy 393.398156 -309.150734)
			(xy 393.409933 -309.10295) (xy 393.429224 -309.057674) (xy 393.455527 -309.016078) (xy 393.488162 -308.979241)
			(xy 393.526283 -308.948116) (xy 393.568904 -308.923509) (xy 393.61492 -308.906057) (xy 393.663139 -308.896213)
			(xy 393.712314 -308.894232) (xy 393.761169 -308.900164) (xy 393.80844 -308.913856) (xy 393.852902 -308.934954)
			(xy 393.893405 -308.96291) (xy 393.928898 -308.997002) (xy 393.958463 -309.036346) (xy 393.981334 -309.079923)
			(xy 393.996918 -309.126604) (xy 394.004813 -309.175181) (xy 394.005142 -309.191549) (xy 394.344268 -309.191549)
			(xy 394.349631 -309.142197) (xy 394.362906 -309.094362) (xy 394.383746 -309.049305) (xy 394.4116 -309.008213)
			(xy 394.445735 -308.972169) (xy 394.485252 -308.942122) (xy 394.529109 -308.918864) (xy 394.576151 -308.903007)
			(xy 394.625139 -308.894969) (xy 394.64996 -308.89448) (xy 394.664143 -308.894662) (xy 394.692383 -308.897331)
			(xy 394.706348 -308.899814) (xy 394.720306 -308.902031) (xy 394.748443 -308.89944) (xy 394.774793 -308.88924)
			(xy 394.797341 -308.872212) (xy 394.814361 -308.849657) (xy 394.82455 -308.823302) (xy 394.827129 -308.795165)
			(xy 394.824966 -308.781196) (xy 394.822494 -308.767229) (xy 394.819819 -308.73899) (xy 394.819632 -308.724808)
			(xy 394.820069 -308.699987) (xy 394.828099 -308.650999) (xy 394.843948 -308.603955) (xy 394.867199 -308.560095)
			(xy 394.89724 -308.520574) (xy 394.933278 -308.486434) (xy 394.974365 -308.458573) (xy 395.019417 -308.437727)
			(xy 395.067249 -308.424444) (xy 395.1166 -308.419074) (xy 395.166169 -308.421758) (xy 395.214651 -308.432426)
			(xy 395.260768 -308.450798) (xy 395.303306 -308.476388) (xy 395.341144 -308.508522) (xy 395.373284 -308.546355)
			(xy 395.398881 -308.588889) (xy 395.417259 -308.635003) (xy 395.427935 -308.683484) (xy 395.43018 -308.724808)
			(xy 395.769096 -308.724808) (xy 395.773056 -308.675754) (xy 395.784833 -308.62797) (xy 395.804124 -308.582694)
			(xy 395.830427 -308.541098) (xy 395.863062 -308.504261) (xy 395.901183 -308.473136) (xy 395.943804 -308.448529)
			(xy 395.98982 -308.431077) (xy 396.038039 -308.421233) (xy 396.087214 -308.419252) (xy 396.136069 -308.425184)
			(xy 396.18334 -308.438876) (xy 396.227802 -308.459974) (xy 396.268305 -308.48793) (xy 396.303798 -308.522022)
			(xy 396.333363 -308.561366) (xy 396.356234 -308.604943) (xy 396.371818 -308.651624) (xy 396.379713 -308.700201)
			(xy 396.380208 -308.724808) (xy 396.719056 -308.724808) (xy 396.723016 -308.675754) (xy 396.734793 -308.62797)
			(xy 396.754084 -308.582694) (xy 396.780387 -308.541098) (xy 396.813022 -308.504261) (xy 396.851143 -308.473136)
			(xy 396.893764 -308.448529) (xy 396.93978 -308.431077) (xy 396.987999 -308.421233) (xy 397.037174 -308.419252)
			(xy 397.086029 -308.425184) (xy 397.1333 -308.438876) (xy 397.177762 -308.459974) (xy 397.218265 -308.48793)
			(xy 397.253758 -308.522022) (xy 397.283323 -308.561366) (xy 397.306194 -308.604943) (xy 397.321778 -308.651624)
			(xy 397.329673 -308.700201) (xy 397.330168 -308.724808) (xy 397.669016 -308.724808) (xy 397.672976 -308.675754)
			(xy 397.684753 -308.62797) (xy 397.704044 -308.582694) (xy 397.730347 -308.541098) (xy 397.762982 -308.504261)
			(xy 397.801103 -308.473136) (xy 397.843724 -308.448529) (xy 397.88974 -308.431077) (xy 397.937959 -308.421233)
			(xy 397.987134 -308.419252) (xy 398.035989 -308.425184) (xy 398.08326 -308.438876) (xy 398.127722 -308.459974)
			(xy 398.168225 -308.48793) (xy 398.203718 -308.522022) (xy 398.233283 -308.561366) (xy 398.256154 -308.604943)
			(xy 398.271738 -308.651624) (xy 398.279633 -308.700201) (xy 398.280128 -308.724808) (xy 398.61923 -308.724808)
			(xy 398.62319 -308.675754) (xy 398.634967 -308.62797) (xy 398.654258 -308.582694) (xy 398.680561 -308.541098)
			(xy 398.713196 -308.504261) (xy 398.751317 -308.473136) (xy 398.793938 -308.448529) (xy 398.839954 -308.431077)
			(xy 398.888173 -308.421233) (xy 398.937348 -308.419252) (xy 398.986203 -308.425184) (xy 399.033474 -308.438876)
			(xy 399.077936 -308.459974) (xy 399.118439 -308.48793) (xy 399.153932 -308.522022) (xy 399.183497 -308.561366)
			(xy 399.206368 -308.604943) (xy 399.221952 -308.651624) (xy 399.229847 -308.700201) (xy 399.230342 -308.724808)
			(xy 399.56919 -308.724808) (xy 399.57315 -308.675754) (xy 399.584927 -308.62797) (xy 399.604218 -308.582694)
			(xy 399.630521 -308.541098) (xy 399.663156 -308.504261) (xy 399.701277 -308.473136) (xy 399.743898 -308.448529)
			(xy 399.789914 -308.431077) (xy 399.838133 -308.421233) (xy 399.887308 -308.419252) (xy 399.936163 -308.425184)
			(xy 399.983434 -308.438876) (xy 400.027896 -308.459974) (xy 400.068399 -308.48793) (xy 400.103892 -308.522022)
			(xy 400.133457 -308.561366) (xy 400.156328 -308.604943) (xy 400.171912 -308.651624) (xy 400.179807 -308.700201)
			(xy 400.180302 -308.724808) (xy 400.51915 -308.724808) (xy 400.52311 -308.675754) (xy 400.534887 -308.62797)
			(xy 400.554178 -308.582694) (xy 400.580481 -308.541098) (xy 400.613116 -308.504261) (xy 400.651237 -308.473136)
			(xy 400.693858 -308.448529) (xy 400.739874 -308.431077) (xy 400.788093 -308.421233) (xy 400.837268 -308.419252)
			(xy 400.886123 -308.425184) (xy 400.933394 -308.438876) (xy 400.977856 -308.459974) (xy 401.018359 -308.48793)
			(xy 401.053852 -308.522022) (xy 401.083417 -308.561366) (xy 401.106288 -308.604943) (xy 401.121872 -308.651624)
			(xy 401.129767 -308.700201) (xy 401.130262 -308.724808) (xy 401.46911 -308.724808) (xy 401.47307 -308.675754)
			(xy 401.484847 -308.62797) (xy 401.504138 -308.582694) (xy 401.530441 -308.541098) (xy 401.563076 -308.504261)
			(xy 401.601197 -308.473136) (xy 401.643818 -308.448529) (xy 401.689834 -308.431077) (xy 401.738053 -308.421233)
			(xy 401.787228 -308.419252) (xy 401.836083 -308.425184) (xy 401.883354 -308.438876) (xy 401.927816 -308.459974)
			(xy 401.968319 -308.48793) (xy 402.003812 -308.522022) (xy 402.033377 -308.561366) (xy 402.056248 -308.604943)
			(xy 402.071832 -308.651624) (xy 402.079727 -308.700201) (xy 402.080222 -308.724808) (xy 402.41907 -308.724808)
			(xy 402.42303 -308.675754) (xy 402.434807 -308.62797) (xy 402.454098 -308.582694) (xy 402.480401 -308.541098)
			(xy 402.513036 -308.504261) (xy 402.551157 -308.473136) (xy 402.593778 -308.448529) (xy 402.639794 -308.431077)
			(xy 402.688013 -308.421233) (xy 402.737188 -308.419252) (xy 402.786043 -308.425184) (xy 402.833314 -308.438876)
			(xy 402.877776 -308.459974) (xy 402.918279 -308.48793) (xy 402.953772 -308.522022) (xy 402.983337 -308.561366)
			(xy 403.006208 -308.604943) (xy 403.021792 -308.651624) (xy 403.029687 -308.700201) (xy 403.030182 -308.724808)
			(xy 403.030015 -308.733103) (xy 403.369048 -308.733103) (xy 403.371732 -308.683527) (xy 403.382403 -308.635038)
			(xy 403.400777 -308.588915) (xy 403.426371 -308.546372) (xy 403.458512 -308.50853) (xy 403.496351 -308.476387)
			(xy 403.538892 -308.450789) (xy 403.585013 -308.43241) (xy 403.633501 -308.421736) (xy 403.683077 -308.419047)
			(xy 403.732435 -308.424414) (xy 403.780274 -308.437696) (xy 403.825334 -308.458543) (xy 403.866428 -308.486405)
			(xy 403.902472 -308.520548) (xy 403.932518 -308.560073) (xy 403.955773 -308.603939) (xy 403.971625 -308.650989)
			(xy 403.979657 -308.699984) (xy 403.980142 -308.724808) (xy 403.979966 -308.738991) (xy 403.977293 -308.767231)
			(xy 403.974808 -308.781196) (xy 403.972522 -308.793642) (xy 403.979888 -308.817264) (xy 404.057358 -308.894734)
			(xy 404.08098 -308.9021) (xy 404.093426 -308.899814) (xy 404.107392 -308.897338) (xy 404.135631 -308.894666)
			(xy 404.149814 -308.89448) (xy 404.164061 -308.894646) (xy 404.192429 -308.897316) (xy 404.206456 -308.899814)
			(xy 404.218902 -308.9021) (xy 404.242524 -308.894734) (xy 404.311104 -308.826408) (xy 404.319271 -308.817179)
			(xy 404.326573 -308.793683) (xy 404.325074 -308.78145) (xy 404.325074 -308.780942) (xy 404.322607 -308.767039)
			(xy 404.319938 -308.738927) (xy 404.31974 -308.724808) (xy 404.320169 -308.699987) (xy 404.328199 -308.650999)
			(xy 404.344048 -308.603956) (xy 404.367299 -308.560096) (xy 404.397339 -308.520575) (xy 404.433377 -308.486435)
			(xy 404.474463 -308.458574) (xy 404.519515 -308.437728) (xy 404.567347 -308.424444) (xy 404.616697 -308.419074)
			(xy 404.666266 -308.421758) (xy 404.714748 -308.432426) (xy 404.760865 -308.450796) (xy 404.803403 -308.476385)
			(xy 404.841241 -308.508519) (xy 404.873382 -308.546351) (xy 404.898979 -308.588885) (xy 404.917358 -308.634999)
			(xy 404.928035 -308.683478) (xy 404.93028 -308.724808) (xy 406.219164 -308.724808) (xy 406.223124 -308.675754)
			(xy 406.234901 -308.62797) (xy 406.254192 -308.582694) (xy 406.280495 -308.541098) (xy 406.31313 -308.504261)
			(xy 406.351251 -308.473136) (xy 406.393872 -308.448529) (xy 406.439888 -308.431077) (xy 406.488107 -308.421233)
			(xy 406.537282 -308.419252) (xy 406.586137 -308.425184) (xy 406.633408 -308.438876) (xy 406.67787 -308.459974)
			(xy 406.718373 -308.48793) (xy 406.753866 -308.522022) (xy 406.783431 -308.561366) (xy 406.806302 -308.604943)
			(xy 406.821886 -308.651624) (xy 406.829781 -308.700201) (xy 406.830276 -308.724808) (xy 406.83011 -308.733071)
			(xy 408.119193 -308.733071) (xy 408.121882 -308.683504) (xy 408.132555 -308.635025) (xy 408.15093 -308.588912)
			(xy 408.176523 -308.546379) (xy 408.20866 -308.508546) (xy 408.246495 -308.476411) (xy 408.28903 -308.450821)
			(xy 408.335144 -308.432449) (xy 408.383624 -308.421779) (xy 408.433191 -308.419093) (xy 408.482539 -308.424462)
			(xy 408.530369 -308.437743) (xy 408.57542 -308.458588) (xy 408.616505 -308.486446) (xy 408.652543 -308.520584)
			(xy 408.682582 -308.560103) (xy 408.705833 -308.603961) (xy 408.721681 -308.651002) (xy 408.729711 -308.699988)
			(xy 408.730196 -308.724808) (xy 408.730021 -308.738991) (xy 408.727348 -308.767231) (xy 408.724862 -308.781196)
			(xy 408.722576 -308.793642) (xy 408.729942 -308.817264) (xy 408.807412 -308.894734) (xy 408.831034 -308.9021)
			(xy 408.84348 -308.899814) (xy 408.857445 -308.897331) (xy 408.885685 -308.894663) (xy 408.899868 -308.89448)
			(xy 408.914051 -308.894661) (xy 408.942291 -308.89733) (xy 408.956256 -308.899814) (xy 408.968702 -308.9021)
			(xy 408.992324 -308.894734) (xy 409.069794 -308.817264) (xy 409.07716 -308.793642) (xy 409.074874 -308.781196)
			(xy 409.072401 -308.76723) (xy 409.069727 -308.73899) (xy 409.06954 -308.724808) (xy 409.070062 -308.699553)
			(xy 409.078375 -308.649731) (xy 409.094776 -308.601957) (xy 409.118817 -308.557534) (xy 409.149841 -308.517674)
			(xy 409.187003 -308.483464) (xy 409.229289 -308.455838) (xy 409.275545 -308.435548) (xy 409.32451 -308.423148)
			(xy 409.374848 -308.418977) (xy 409.425186 -308.423148) (xy 409.474151 -308.435548) (xy 409.520407 -308.455838)
			(xy 409.562693 -308.483464) (xy 409.599855 -308.517674) (xy 409.630879 -308.557534) (xy 409.65492 -308.601957)
			(xy 409.671321 -308.649731) (xy 409.679634 -308.699553) (xy 409.680156 -308.724808) (xy 409.679981 -308.738991)
			(xy 409.677308 -308.767231) (xy 409.674822 -308.781196) (xy 409.672536 -308.793642) (xy 409.679902 -308.817264)
			(xy 409.757372 -308.894734) (xy 409.780994 -308.9021) (xy 409.79344 -308.899814) (xy 409.807406 -308.897336)
			(xy 409.835645 -308.894665) (xy 409.849828 -308.89448) (xy 409.864011 -308.894653) (xy 409.892251 -308.897328)
			(xy 409.906216 -308.899814) (xy 409.918662 -308.9021) (xy 409.942284 -308.894734) (xy 410.019754 -308.817264)
			(xy 410.02712 -308.793642) (xy 410.024834 -308.781196) (xy 410.022361 -308.76723) (xy 410.019687 -308.73899)
			(xy 410.0195 -308.724808) (xy 410.019969 -308.699986) (xy 410.027999 -308.650997) (xy 410.043849 -308.603952)
			(xy 410.067101 -308.560092) (xy 410.097143 -308.52057) (xy 410.133183 -308.48643) (xy 410.174271 -308.45857)
			(xy 410.219325 -308.437724) (xy 410.267158 -308.424442) (xy 410.31651 -308.419073) (xy 410.36608 -308.42176)
			(xy 410.414563 -308.43243) (xy 410.460681 -308.450804) (xy 410.503218 -308.476396) (xy 410.541055 -308.508534)
			(xy 410.573194 -308.546369) (xy 410.598789 -308.588905) (xy 410.617165 -308.635022) (xy 410.627838 -308.683504)
			(xy 410.630065 -308.724554) (xy 410.968964 -308.724554) (xy 410.972924 -308.6755) (xy 410.984701 -308.627716)
			(xy 411.003992 -308.58244) (xy 411.030295 -308.540844) (xy 411.06293 -308.504007) (xy 411.101051 -308.472882)
			(xy 411.143672 -308.448275) (xy 411.189688 -308.430823) (xy 411.237907 -308.420979) (xy 411.287082 -308.418998)
			(xy 411.335937 -308.42493) (xy 411.383208 -308.438622) (xy 411.42767 -308.45972) (xy 411.468173 -308.487676)
			(xy 411.503666 -308.521768) (xy 411.533231 -308.561112) (xy 411.556102 -308.604689) (xy 411.571686 -308.65137)
			(xy 411.579581 -308.699947) (xy 411.580076 -308.724554) (xy 411.580071 -308.724808) (xy 411.919178 -308.724808)
			(xy 411.923138 -308.675754) (xy 411.934915 -308.62797) (xy 411.954206 -308.582694) (xy 411.980509 -308.541098)
			(xy 412.013144 -308.504261) (xy 412.051265 -308.473136) (xy 412.093886 -308.448529) (xy 412.139902 -308.431077)
			(xy 412.188121 -308.421233) (xy 412.237296 -308.419252) (xy 412.286151 -308.425184) (xy 412.333422 -308.438876)
			(xy 412.377884 -308.459974) (xy 412.418387 -308.48793) (xy 412.45388 -308.522022) (xy 412.483445 -308.561366)
			(xy 412.506316 -308.604943) (xy 412.5219 -308.651624) (xy 412.529795 -308.700201) (xy 412.53029 -308.724808)
			(xy 412.869138 -308.724808) (xy 412.873098 -308.675754) (xy 412.884875 -308.62797) (xy 412.904166 -308.582694)
			(xy 412.930469 -308.541098) (xy 412.963104 -308.504261) (xy 413.001225 -308.473136) (xy 413.043846 -308.448529)
			(xy 413.089862 -308.431077) (xy 413.138081 -308.421233) (xy 413.187256 -308.419252) (xy 413.236111 -308.425184)
			(xy 413.283382 -308.438876) (xy 413.327844 -308.459974) (xy 413.368347 -308.48793) (xy 413.40384 -308.522022)
			(xy 413.433405 -308.561366) (xy 413.456276 -308.604943) (xy 413.47186 -308.651624) (xy 413.479755 -308.700201)
			(xy 413.48025 -308.724808) (xy 413.819098 -308.724808) (xy 413.823058 -308.675754) (xy 413.834835 -308.62797)
			(xy 413.854126 -308.582694) (xy 413.880429 -308.541098) (xy 413.913064 -308.504261) (xy 413.951185 -308.473136)
			(xy 413.993806 -308.448529) (xy 414.039822 -308.431077) (xy 414.088041 -308.421233) (xy 414.137216 -308.419252)
			(xy 414.186071 -308.425184) (xy 414.233342 -308.438876) (xy 414.277804 -308.459974) (xy 414.318307 -308.48793)
			(xy 414.3538 -308.522022) (xy 414.383365 -308.561366) (xy 414.406236 -308.604943) (xy 414.42182 -308.651624)
			(xy 414.429715 -308.700201) (xy 414.43021 -308.724808) (xy 414.769058 -308.724808) (xy 414.773018 -308.675754)
			(xy 414.784795 -308.62797) (xy 414.804086 -308.582694) (xy 414.830389 -308.541098) (xy 414.863024 -308.504261)
			(xy 414.901145 -308.473136) (xy 414.943766 -308.448529) (xy 414.989782 -308.431077) (xy 415.038001 -308.421233)
			(xy 415.087176 -308.419252) (xy 415.136031 -308.425184) (xy 415.183302 -308.438876) (xy 415.227764 -308.459974)
			(xy 415.268267 -308.48793) (xy 415.30376 -308.522022) (xy 415.333325 -308.561366) (xy 415.356196 -308.604943)
			(xy 415.37178 -308.651624) (xy 415.379675 -308.700201) (xy 415.38017 -308.724808) (xy 415.719018 -308.724808)
			(xy 415.722978 -308.675754) (xy 415.734755 -308.62797) (xy 415.754046 -308.582694) (xy 415.780349 -308.541098)
			(xy 415.812984 -308.504261) (xy 415.851105 -308.473136) (xy 415.893726 -308.448529) (xy 415.939742 -308.431077)
			(xy 415.987961 -308.421233) (xy 416.037136 -308.419252) (xy 416.085991 -308.425184) (xy 416.133262 -308.438876)
			(xy 416.177724 -308.459974) (xy 416.218227 -308.48793) (xy 416.25372 -308.522022) (xy 416.283285 -308.561366)
			(xy 416.306156 -308.604943) (xy 416.32174 -308.651624) (xy 416.329635 -308.700201) (xy 416.33013 -308.724808)
			(xy 416.669232 -308.724808) (xy 416.673192 -308.675754) (xy 416.684969 -308.62797) (xy 416.70426 -308.582694)
			(xy 416.730563 -308.541098) (xy 416.763198 -308.504261) (xy 416.801319 -308.473136) (xy 416.84394 -308.448529)
			(xy 416.889956 -308.431077) (xy 416.938175 -308.421233) (xy 416.98735 -308.419252) (xy 417.036205 -308.425184)
			(xy 417.083476 -308.438876) (xy 417.127938 -308.459974) (xy 417.168441 -308.48793) (xy 417.203934 -308.522022)
			(xy 417.233499 -308.561366) (xy 417.25637 -308.604943) (xy 417.271954 -308.651624) (xy 417.279849 -308.700201)
			(xy 417.280344 -308.724808) (xy 417.619192 -308.724808) (xy 417.623152 -308.675754) (xy 417.634929 -308.62797)
			(xy 417.65422 -308.582694) (xy 417.680523 -308.541098) (xy 417.713158 -308.504261) (xy 417.751279 -308.473136)
			(xy 417.7939 -308.448529) (xy 417.839916 -308.431077) (xy 417.888135 -308.421233) (xy 417.93731 -308.419252)
			(xy 417.986165 -308.425184) (xy 418.033436 -308.438876) (xy 418.077898 -308.459974) (xy 418.118401 -308.48793)
			(xy 418.153894 -308.522022) (xy 418.183459 -308.561366) (xy 418.20633 -308.604943) (xy 418.221914 -308.651624)
			(xy 418.229809 -308.700201) (xy 418.230304 -308.724808) (xy 418.569152 -308.724808) (xy 418.573112 -308.675754)
			(xy 418.584889 -308.62797) (xy 418.60418 -308.582694) (xy 418.630483 -308.541098) (xy 418.663118 -308.504261)
			(xy 418.701239 -308.473136) (xy 418.74386 -308.448529) (xy 418.789876 -308.431077) (xy 418.838095 -308.421233)
			(xy 418.88727 -308.419252) (xy 418.936125 -308.425184) (xy 418.983396 -308.438876) (xy 419.027858 -308.459974)
			(xy 419.068361 -308.48793) (xy 419.103854 -308.522022) (xy 419.133419 -308.561366) (xy 419.15629 -308.604943)
			(xy 419.171874 -308.651624) (xy 419.179769 -308.700201) (xy 419.180264 -308.724808) (xy 419.519112 -308.724808)
			(xy 419.523072 -308.675754) (xy 419.534849 -308.62797) (xy 419.55414 -308.582694) (xy 419.580443 -308.541098)
			(xy 419.613078 -308.504261) (xy 419.651199 -308.473136) (xy 419.69382 -308.448529) (xy 419.739836 -308.431077)
			(xy 419.788055 -308.421233) (xy 419.83723 -308.419252) (xy 419.886085 -308.425184) (xy 419.933356 -308.438876)
			(xy 419.977818 -308.459974) (xy 420.018321 -308.48793) (xy 420.053814 -308.522022) (xy 420.083379 -308.561366)
			(xy 420.10625 -308.604943) (xy 420.121834 -308.651624) (xy 420.129729 -308.700201) (xy 420.130224 -308.724808)
			(xy 420.469072 -308.724808) (xy 420.473032 -308.675754) (xy 420.484809 -308.62797) (xy 420.5041 -308.582694)
			(xy 420.530403 -308.541098) (xy 420.563038 -308.504261) (xy 420.601159 -308.473136) (xy 420.64378 -308.448529)
			(xy 420.689796 -308.431077) (xy 420.738015 -308.421233) (xy 420.78719 -308.419252) (xy 420.836045 -308.425184)
			(xy 420.883316 -308.438876) (xy 420.927778 -308.459974) (xy 420.968281 -308.48793) (xy 421.003774 -308.522022)
			(xy 421.033339 -308.561366) (xy 421.05621 -308.604943) (xy 421.071794 -308.651624) (xy 421.079689 -308.700201)
			(xy 421.080184 -308.724808) (xy 421.419032 -308.724808) (xy 421.422992 -308.675754) (xy 421.434769 -308.62797)
			(xy 421.45406 -308.582694) (xy 421.480363 -308.541098) (xy 421.512998 -308.504261) (xy 421.551119 -308.473136)
			(xy 421.59374 -308.448529) (xy 421.639756 -308.431077) (xy 421.687975 -308.421233) (xy 421.73715 -308.419252)
			(xy 421.786005 -308.425184) (xy 421.833276 -308.438876) (xy 421.877738 -308.459974) (xy 421.918241 -308.48793)
			(xy 421.953734 -308.522022) (xy 421.983299 -308.561366) (xy 422.00617 -308.604943) (xy 422.021754 -308.651624)
			(xy 422.029649 -308.700201) (xy 422.030144 -308.724808) (xy 422.029649 -308.749415) (xy 422.021754 -308.797992)
			(xy 422.00617 -308.844673) (xy 421.983299 -308.88825) (xy 421.953734 -308.927594) (xy 421.918241 -308.961686)
			(xy 421.877738 -308.989642) (xy 421.833276 -309.01074) (xy 421.786005 -309.024432) (xy 421.73715 -309.030364)
			(xy 421.687975 -309.028383) (xy 421.639756 -309.018539) (xy 421.59374 -309.001087) (xy 421.551119 -308.97648)
			(xy 421.512998 -308.945355) (xy 421.480363 -308.908518) (xy 421.45406 -308.866922) (xy 421.434769 -308.821646)
			(xy 421.422992 -308.773862) (xy 421.419032 -308.724808) (xy 421.080184 -308.724808) (xy 421.079689 -308.749415)
			(xy 421.071794 -308.797992) (xy 421.05621 -308.844673) (xy 421.033339 -308.88825) (xy 421.003774 -308.927594)
			(xy 420.968281 -308.961686) (xy 420.927778 -308.989642) (xy 420.883316 -309.01074) (xy 420.836045 -309.024432)
			(xy 420.78719 -309.030364) (xy 420.738015 -309.028383) (xy 420.689796 -309.018539) (xy 420.64378 -309.001087)
			(xy 420.601159 -308.97648) (xy 420.563038 -308.945355) (xy 420.530403 -308.908518) (xy 420.5041 -308.866922)
			(xy 420.484809 -308.821646) (xy 420.473032 -308.773862) (xy 420.469072 -308.724808) (xy 420.130224 -308.724808)
			(xy 420.129729 -308.749415) (xy 420.121834 -308.797992) (xy 420.10625 -308.844673) (xy 420.083379 -308.88825)
			(xy 420.053814 -308.927594) (xy 420.018321 -308.961686) (xy 419.977818 -308.989642) (xy 419.933356 -309.01074)
			(xy 419.886085 -309.024432) (xy 419.83723 -309.030364) (xy 419.788055 -309.028383) (xy 419.739836 -309.018539)
			(xy 419.69382 -309.001087) (xy 419.651199 -308.97648) (xy 419.613078 -308.945355) (xy 419.580443 -308.908518)
			(xy 419.55414 -308.866922) (xy 419.534849 -308.821646) (xy 419.523072 -308.773862) (xy 419.519112 -308.724808)
			(xy 419.180264 -308.724808) (xy 419.179769 -308.749415) (xy 419.171874 -308.797992) (xy 419.15629 -308.844673)
			(xy 419.133419 -308.88825) (xy 419.103854 -308.927594) (xy 419.068361 -308.961686) (xy 419.027858 -308.989642)
			(xy 418.983396 -309.01074) (xy 418.936125 -309.024432) (xy 418.88727 -309.030364) (xy 418.838095 -309.028383)
			(xy 418.789876 -309.018539) (xy 418.74386 -309.001087) (xy 418.701239 -308.97648) (xy 418.663118 -308.945355)
			(xy 418.630483 -308.908518) (xy 418.60418 -308.866922) (xy 418.584889 -308.821646) (xy 418.573112 -308.773862)
			(xy 418.569152 -308.724808) (xy 418.230304 -308.724808) (xy 418.229809 -308.749415) (xy 418.221914 -308.797992)
			(xy 418.20633 -308.844673) (xy 418.183459 -308.88825) (xy 418.153894 -308.927594) (xy 418.118401 -308.961686)
			(xy 418.077898 -308.989642) (xy 418.033436 -309.01074) (xy 417.986165 -309.024432) (xy 417.93731 -309.030364)
			(xy 417.888135 -309.028383) (xy 417.839916 -309.018539) (xy 417.7939 -309.001087) (xy 417.751279 -308.97648)
			(xy 417.713158 -308.945355) (xy 417.680523 -308.908518) (xy 417.65422 -308.866922) (xy 417.634929 -308.821646)
			(xy 417.623152 -308.773862) (xy 417.619192 -308.724808) (xy 417.280344 -308.724808) (xy 417.279849 -308.749415)
			(xy 417.271954 -308.797992) (xy 417.25637 -308.844673) (xy 417.233499 -308.88825) (xy 417.203934 -308.927594)
			(xy 417.168441 -308.961686) (xy 417.127938 -308.989642) (xy 417.083476 -309.01074) (xy 417.036205 -309.024432)
			(xy 416.98735 -309.030364) (xy 416.938175 -309.028383) (xy 416.889956 -309.018539) (xy 416.84394 -309.001087)
			(xy 416.801319 -308.97648) (xy 416.763198 -308.945355) (xy 416.730563 -308.908518) (xy 416.70426 -308.866922)
			(xy 416.684969 -308.821646) (xy 416.673192 -308.773862) (xy 416.669232 -308.724808) (xy 416.33013 -308.724808)
			(xy 416.329635 -308.749415) (xy 416.32174 -308.797992) (xy 416.306156 -308.844673) (xy 416.283285 -308.88825)
			(xy 416.25372 -308.927594) (xy 416.218227 -308.961686) (xy 416.177724 -308.989642) (xy 416.133262 -309.01074)
			(xy 416.085991 -309.024432) (xy 416.037136 -309.030364) (xy 415.987961 -309.028383) (xy 415.939742 -309.018539)
			(xy 415.893726 -309.001087) (xy 415.851105 -308.97648) (xy 415.812984 -308.945355) (xy 415.780349 -308.908518)
			(xy 415.754046 -308.866922) (xy 415.734755 -308.821646) (xy 415.722978 -308.773862) (xy 415.719018 -308.724808)
			(xy 415.38017 -308.724808) (xy 415.379675 -308.749415) (xy 415.37178 -308.797992) (xy 415.356196 -308.844673)
			(xy 415.333325 -308.88825) (xy 415.30376 -308.927594) (xy 415.268267 -308.961686) (xy 415.227764 -308.989642)
			(xy 415.183302 -309.01074) (xy 415.136031 -309.024432) (xy 415.087176 -309.030364) (xy 415.038001 -309.028383)
			(xy 414.989782 -309.018539) (xy 414.943766 -309.001087) (xy 414.901145 -308.97648) (xy 414.863024 -308.945355)
			(xy 414.830389 -308.908518) (xy 414.804086 -308.866922) (xy 414.784795 -308.821646) (xy 414.773018 -308.773862)
			(xy 414.769058 -308.724808) (xy 414.43021 -308.724808) (xy 414.429715 -308.749415) (xy 414.42182 -308.797992)
			(xy 414.406236 -308.844673) (xy 414.383365 -308.88825) (xy 414.3538 -308.927594) (xy 414.318307 -308.961686)
			(xy 414.277804 -308.989642) (xy 414.233342 -309.01074) (xy 414.186071 -309.024432) (xy 414.137216 -309.030364)
			(xy 414.088041 -309.028383) (xy 414.039822 -309.018539) (xy 413.993806 -309.001087) (xy 413.951185 -308.97648)
			(xy 413.913064 -308.945355) (xy 413.880429 -308.908518) (xy 413.854126 -308.866922) (xy 413.834835 -308.821646)
			(xy 413.823058 -308.773862) (xy 413.819098 -308.724808) (xy 413.48025 -308.724808) (xy 413.479755 -308.749415)
			(xy 413.47186 -308.797992) (xy 413.456276 -308.844673) (xy 413.433405 -308.88825) (xy 413.40384 -308.927594)
			(xy 413.368347 -308.961686) (xy 413.327844 -308.989642) (xy 413.283382 -309.01074) (xy 413.236111 -309.024432)
			(xy 413.187256 -309.030364) (xy 413.138081 -309.028383) (xy 413.089862 -309.018539) (xy 413.043846 -309.001087)
			(xy 413.001225 -308.97648) (xy 412.963104 -308.945355) (xy 412.930469 -308.908518) (xy 412.904166 -308.866922)
			(xy 412.884875 -308.821646) (xy 412.873098 -308.773862) (xy 412.869138 -308.724808) (xy 412.53029 -308.724808)
			(xy 412.529795 -308.749415) (xy 412.5219 -308.797992) (xy 412.506316 -308.844673) (xy 412.483445 -308.88825)
			(xy 412.45388 -308.927594) (xy 412.418387 -308.961686) (xy 412.377884 -308.989642) (xy 412.333422 -309.01074)
			(xy 412.286151 -309.024432) (xy 412.237296 -309.030364) (xy 412.188121 -309.028383) (xy 412.139902 -309.018539)
			(xy 412.093886 -309.001087) (xy 412.051265 -308.97648) (xy 412.013144 -308.945355) (xy 411.980509 -308.908518)
			(xy 411.954206 -308.866922) (xy 411.934915 -308.821646) (xy 411.923138 -308.773862) (xy 411.919178 -308.724808)
			(xy 411.580071 -308.724808) (xy 411.579581 -308.749161) (xy 411.571686 -308.797738) (xy 411.556102 -308.844419)
			(xy 411.533231 -308.887996) (xy 411.503666 -308.92734) (xy 411.468173 -308.961432) (xy 411.42767 -308.989388)
			(xy 411.383208 -309.010486) (xy 411.335937 -309.024178) (xy 411.287082 -309.03011) (xy 411.237907 -309.028129)
			(xy 411.189688 -309.018285) (xy 411.143672 -309.000833) (xy 411.101051 -308.976226) (xy 411.06293 -308.945101)
			(xy 411.030295 -308.908264) (xy 411.003992 -308.866668) (xy 410.984701 -308.821392) (xy 410.972924 -308.773608)
			(xy 410.968964 -308.724554) (xy 410.630065 -308.724554) (xy 410.630527 -308.733074) (xy 410.625161 -308.782426)
			(xy 410.611881 -308.83026) (xy 410.591038 -308.875315) (xy 410.56318 -308.916405) (xy 410.529042 -308.952446)
			(xy 410.489522 -308.98249) (xy 410.445662 -309.005744) (xy 410.398618 -309.021597) (xy 410.349629 -309.029629)
			(xy 410.324808 -309.030116) (xy 410.310625 -309.029938) (xy 410.282385 -309.027267) (xy 410.26842 -309.024782)
			(xy 410.255974 -309.022496) (xy 410.232352 -309.029862) (xy 410.154882 -309.107332) (xy 410.147516 -309.130954)
			(xy 410.149802 -309.1434) (xy 410.152275 -309.157367) (xy 410.154949 -309.185606) (xy 410.155136 -309.199788)
			(xy 422.844226 -309.199788) (xy 422.848186 -309.150734) (xy 422.859963 -309.10295) (xy 422.879254 -309.057674)
			(xy 422.905557 -309.016078) (xy 422.938192 -308.979241) (xy 422.976313 -308.948116) (xy 423.018934 -308.923509)
			(xy 423.06495 -308.906057) (xy 423.113169 -308.896213) (xy 423.162344 -308.894232) (xy 423.211199 -308.900164)
			(xy 423.25847 -308.913856) (xy 423.302932 -308.934954) (xy 423.343435 -308.96291) (xy 423.378928 -308.997002)
			(xy 423.408493 -309.036346) (xy 423.431364 -309.079923) (xy 423.446948 -309.126604) (xy 423.454843 -309.175181)
			(xy 423.455338 -309.199788) (xy 423.794186 -309.199788) (xy 423.798146 -309.150734) (xy 423.809923 -309.10295)
			(xy 423.829214 -309.057674) (xy 423.855517 -309.016078) (xy 423.888152 -308.979241) (xy 423.926273 -308.948116)
			(xy 423.968894 -308.923509) (xy 424.01491 -308.906057) (xy 424.063129 -308.896213) (xy 424.112304 -308.894232)
			(xy 424.161159 -308.900164) (xy 424.20843 -308.913856) (xy 424.252892 -308.934954) (xy 424.293395 -308.96291)
			(xy 424.328888 -308.997002) (xy 424.358453 -309.036346) (xy 424.381324 -309.079923) (xy 424.396908 -309.126604)
			(xy 424.404803 -309.175181) (xy 424.405298 -309.199788) (xy 424.404803 -309.224395) (xy 424.396908 -309.272972)
			(xy 424.381324 -309.319653) (xy 424.358453 -309.36323) (xy 424.328888 -309.402574) (xy 424.293395 -309.436666)
			(xy 424.252892 -309.464622) (xy 424.20843 -309.48572) (xy 424.161159 -309.499412) (xy 424.112304 -309.505344)
			(xy 424.063129 -309.503363) (xy 424.01491 -309.493519) (xy 423.968894 -309.476067) (xy 423.926273 -309.45146)
			(xy 423.888152 -309.420335) (xy 423.855517 -309.383498) (xy 423.829214 -309.341902) (xy 423.809923 -309.296626)
			(xy 423.798146 -309.248842) (xy 423.794186 -309.199788) (xy 423.455338 -309.199788) (xy 423.454843 -309.224395)
			(xy 423.446948 -309.272972) (xy 423.431364 -309.319653) (xy 423.408493 -309.36323) (xy 423.378928 -309.402574)
			(xy 423.343435 -309.436666) (xy 423.302932 -309.464622) (xy 423.25847 -309.48572) (xy 423.211199 -309.499412)
			(xy 423.162344 -309.505344) (xy 423.113169 -309.503363) (xy 423.06495 -309.493519) (xy 423.018934 -309.476067)
			(xy 422.976313 -309.45146) (xy 422.938192 -309.420335) (xy 422.905557 -309.383498) (xy 422.879254 -309.341902)
			(xy 422.859963 -309.296626) (xy 422.848186 -309.248842) (xy 422.844226 -309.199788) (xy 410.155136 -309.199788)
			(xy 410.154614 -309.225043) (xy 410.146301 -309.274865) (xy 410.1299 -309.322639) (xy 410.105859 -309.367062)
			(xy 410.074835 -309.406922) (xy 410.037673 -309.441132) (xy 409.995387 -309.468758) (xy 409.949131 -309.489048)
			(xy 409.900166 -309.501448) (xy 409.849828 -309.505619) (xy 409.79949 -309.501448) (xy 409.750525 -309.489048)
			(xy 409.704269 -309.468758) (xy 409.661983 -309.441132) (xy 409.624821 -309.406922) (xy 409.593797 -309.367062)
			(xy 409.569756 -309.322639) (xy 409.553355 -309.274865) (xy 409.545042 -309.225043) (xy 409.54452 -309.199788)
			(xy 409.544695 -309.185605) (xy 409.547368 -309.157365) (xy 409.549854 -309.1434) (xy 409.55214 -309.130954)
			(xy 409.544774 -309.107332) (xy 409.467304 -309.029862) (xy 409.443682 -309.022496) (xy 409.431236 -309.024782)
			(xy 409.417271 -309.027263) (xy 409.389031 -309.029932) (xy 409.374848 -309.030116) (xy 409.360665 -309.029933)
			(xy 409.332425 -309.027265) (xy 409.31846 -309.024782) (xy 409.306014 -309.022496) (xy 409.282392 -309.029862)
			(xy 409.204922 -309.107332) (xy 409.197556 -309.130954) (xy 409.199842 -309.1434) (xy 409.202314 -309.157367)
			(xy 409.204989 -309.185606) (xy 409.205176 -309.199788) (xy 409.204654 -309.225043) (xy 409.196341 -309.274865)
			(xy 409.17994 -309.322639) (xy 409.155899 -309.367062) (xy 409.124875 -309.406922) (xy 409.087713 -309.441132)
			(xy 409.045427 -309.468758) (xy 408.999171 -309.489048) (xy 408.950206 -309.501448) (xy 408.899868 -309.505619)
			(xy 408.84953 -309.501448) (xy 408.800565 -309.489048) (xy 408.754309 -309.468758) (xy 408.712023 -309.441132)
			(xy 408.674861 -309.406922) (xy 408.643837 -309.367062) (xy 408.619796 -309.322639) (xy 408.603395 -309.274865)
			(xy 408.595082 -309.225043) (xy 408.59456 -309.199788) (xy 408.594736 -309.185605) (xy 408.597408 -309.157365)
			(xy 408.599894 -309.1434) (xy 408.60218 -309.130954) (xy 408.594814 -309.107332) (xy 408.517344 -309.029862)
			(xy 408.493722 -309.022496) (xy 408.481276 -309.024782) (xy 408.46731 -309.027258) (xy 408.43907 -309.02993)
			(xy 408.424888 -309.030116) (xy 408.400068 -309.029609) (xy 408.351083 -309.021576) (xy 408.304042 -309.005725)
			(xy 408.260186 -308.982471) (xy 408.220669 -308.952429) (xy 408.186534 -308.91639) (xy 408.158678 -308.875303)
			(xy 408.137836 -308.83025) (xy 408.124558 -308.78242) (xy 408.119193 -308.733071) (xy 406.83011 -308.733071)
			(xy 406.829781 -308.749415) (xy 406.821886 -308.797992) (xy 406.806302 -308.844673) (xy 406.783431 -308.88825)
			(xy 406.753866 -308.927594) (xy 406.718373 -308.961686) (xy 406.67787 -308.989642) (xy 406.633408 -309.01074)
			(xy 406.586137 -309.024432) (xy 406.537282 -309.030364) (xy 406.488107 -309.028383) (xy 406.439888 -309.018539)
			(xy 406.393872 -309.001087) (xy 406.351251 -308.97648) (xy 406.31313 -308.945355) (xy 406.280495 -308.908518)
			(xy 406.254192 -308.866922) (xy 406.234901 -308.821646) (xy 406.223124 -308.773862) (xy 406.219164 -308.724808)
			(xy 404.93028 -308.724808) (xy 404.930728 -308.733047) (xy 404.925366 -308.782398) (xy 404.912092 -308.830232)
			(xy 404.891253 -308.875288) (xy 404.8634 -308.91638) (xy 404.829267 -308.952424) (xy 404.789752 -308.982471)
			(xy 404.745896 -309.00573) (xy 404.698855 -309.021588) (xy 404.649869 -309.029626) (xy 404.625048 -309.030116)
			(xy 404.610801 -309.029949) (xy 404.582434 -309.027276) (xy 404.568406 -309.024782) (xy 404.55596 -309.022496)
			(xy 404.532338 -309.029862) (xy 404.463758 -309.098188) (xy 404.455589 -309.107416) (xy 404.44829 -309.130913)
			(xy 404.449788 -309.143146) (xy 404.449788 -309.143654) (xy 404.452256 -309.157557) (xy 404.454924 -309.185669)
			(xy 404.455122 -309.199788) (xy 404.454943 -309.213971) (xy 404.452273 -309.242211) (xy 404.449788 -309.256176)
			(xy 404.447502 -309.268622) (xy 404.454868 -309.292244) (xy 404.532338 -309.369714) (xy 404.55596 -309.37708)
			(xy 404.568406 -309.374794) (xy 404.582372 -309.372321) (xy 404.610612 -309.369647) (xy 404.624794 -309.36946)
			(xy 404.648783 -309.369968) (xy 404.696172 -309.377472) (xy 404.741803 -309.392297) (xy 404.784554 -309.414077)
			(xy 404.823371 -309.442276) (xy 404.857299 -309.4762) (xy 404.885503 -309.515014) (xy 404.907289 -309.557762)
			(xy 404.922119 -309.603391) (xy 404.929629 -309.650779) (xy 404.930102 -309.674768) (xy 404.929921 -309.688951)
			(xy 404.927252 -309.717191) (xy 404.924768 -309.731156) (xy 404.924768 -309.73141) (xy 404.923328 -309.743641)
			(xy 404.930604 -309.767124) (xy 404.938738 -309.776368) (xy 405.007318 -309.844694) (xy 405.03094 -309.85206)
			(xy 405.043386 -309.849774) (xy 405.057416 -309.847294) (xy 405.085782 -309.844619) (xy 405.100028 -309.84444)
			(xy 405.114211 -309.844612) (xy 405.142451 -309.847287) (xy 405.156416 -309.849774) (xy 405.168862 -309.85206)
			(xy 405.192484 -309.844694) (xy 405.269954 -309.767224) (xy 405.27732 -309.743602) (xy 405.275034 -309.731156)
			(xy 405.272556 -309.71719) (xy 405.269885 -309.688951) (xy 405.2697 -309.674768) (xy 405.270222 -309.649513)
			(xy 405.278535 -309.599691) (xy 405.294936 -309.551917) (xy 405.318977 -309.507494) (xy 405.350001 -309.467634)
			(xy 405.387163 -309.433424) (xy 405.429449 -309.405798) (xy 405.475705 -309.385508) (xy 405.52467 -309.373108)
			(xy 405.575008 -309.368937) (xy 405.625346 -309.373108) (xy 405.674311 -309.385508) (xy 405.720567 -309.405798)
			(xy 405.762853 -309.433424) (xy 405.800015 -309.467634) (xy 405.831039 -309.507494) (xy 405.85508 -309.551917)
			(xy 405.871481 -309.599691) (xy 405.879794 -309.649513) (xy 405.880316 -309.674768) (xy 405.880135 -309.688951)
			(xy 405.877466 -309.717191) (xy 405.874982 -309.731156) (xy 405.872696 -309.743602) (xy 405.880062 -309.767224)
			(xy 405.957532 -309.844694) (xy 405.981154 -309.85206) (xy 405.9936 -309.849774) (xy 406.007566 -309.847301)
			(xy 406.035806 -309.844627) (xy 406.049988 -309.84444) (xy 406.074809 -309.844865) (xy 406.123798 -309.852894)
			(xy 406.170843 -309.868743) (xy 406.214703 -309.891993) (xy 406.254225 -309.922033) (xy 406.288366 -309.958072)
			(xy 406.316228 -309.999158) (xy 406.337075 -310.044211) (xy 406.350359 -310.092043) (xy 406.35573 -310.141394)
			(xy 406.355278 -310.149748) (xy 406.694144 -310.149748) (xy 406.698104 -310.100694) (xy 406.709881 -310.05291)
			(xy 406.729172 -310.007634) (xy 406.755475 -309.966038) (xy 406.78811 -309.929201) (xy 406.826231 -309.898076)
			(xy 406.868852 -309.873469) (xy 406.914868 -309.856017) (xy 406.963087 -309.846173) (xy 407.012262 -309.844192)
			(xy 407.061117 -309.850124) (xy 407.108388 -309.863816) (xy 407.15285 -309.884914) (xy 407.193353 -309.91287)
			(xy 407.228846 -309.946962) (xy 407.258411 -309.986306) (xy 407.281282 -310.029883) (xy 407.296866 -310.076564)
			(xy 407.304761 -310.125141) (xy 407.305256 -310.149748) (xy 407.644104 -310.149748) (xy 407.648064 -310.100694)
			(xy 407.659841 -310.05291) (xy 407.679132 -310.007634) (xy 407.705435 -309.966038) (xy 407.73807 -309.929201)
			(xy 407.776191 -309.898076) (xy 407.818812 -309.873469) (xy 407.864828 -309.856017) (xy 407.913047 -309.846173)
			(xy 407.962222 -309.844192) (xy 408.011077 -309.850124) (xy 408.058348 -309.863816) (xy 408.10281 -309.884914)
			(xy 408.143313 -309.91287) (xy 408.178806 -309.946962) (xy 408.208371 -309.986306) (xy 408.231242 -310.029883)
			(xy 408.246826 -310.076564) (xy 408.254721 -310.125141) (xy 408.255216 -310.149748) (xy 408.594064 -310.149748)
			(xy 408.598024 -310.100694) (xy 408.609801 -310.05291) (xy 408.629092 -310.007634) (xy 408.655395 -309.966038)
			(xy 408.68803 -309.929201) (xy 408.726151 -309.898076) (xy 408.768772 -309.873469) (xy 408.814788 -309.856017)
			(xy 408.863007 -309.846173) (xy 408.912182 -309.844192) (xy 408.961037 -309.850124) (xy 409.008308 -309.863816)
			(xy 409.05277 -309.884914) (xy 409.093273 -309.91287) (xy 409.128766 -309.946962) (xy 409.158331 -309.986306)
			(xy 409.181202 -310.029883) (xy 409.196786 -310.076564) (xy 409.204681 -310.125141) (xy 409.205176 -310.149748)
			(xy 409.544024 -310.149748) (xy 409.547984 -310.100694) (xy 409.559761 -310.05291) (xy 409.579052 -310.007634)
			(xy 409.605355 -309.966038) (xy 409.63799 -309.929201) (xy 409.676111 -309.898076) (xy 409.718732 -309.873469)
			(xy 409.764748 -309.856017) (xy 409.812967 -309.846173) (xy 409.862142 -309.844192) (xy 409.910997 -309.850124)
			(xy 409.958268 -309.863816) (xy 410.00273 -309.884914) (xy 410.043233 -309.91287) (xy 410.078726 -309.946962)
			(xy 410.108291 -309.986306) (xy 410.131162 -310.029883) (xy 410.146746 -310.076564) (xy 410.154641 -310.125141)
			(xy 410.155136 -310.149748) (xy 410.493984 -310.149748) (xy 410.497944 -310.100694) (xy 410.509721 -310.05291)
			(xy 410.529012 -310.007634) (xy 410.555315 -309.966038) (xy 410.58795 -309.929201) (xy 410.626071 -309.898076)
			(xy 410.668692 -309.873469) (xy 410.714708 -309.856017) (xy 410.762927 -309.846173) (xy 410.812102 -309.844192)
			(xy 410.860957 -309.850124) (xy 410.908228 -309.863816) (xy 410.95269 -309.884914) (xy 410.993193 -309.91287)
			(xy 411.028686 -309.946962) (xy 411.058251 -309.986306) (xy 411.081122 -310.029883) (xy 411.096706 -310.076564)
			(xy 411.104601 -310.125141) (xy 411.105096 -310.149748) (xy 411.444198 -310.149748) (xy 411.448158 -310.100694)
			(xy 411.459935 -310.05291) (xy 411.479226 -310.007634) (xy 411.505529 -309.966038) (xy 411.538164 -309.929201)
			(xy 411.576285 -309.898076) (xy 411.618906 -309.873469) (xy 411.664922 -309.856017) (xy 411.713141 -309.846173)
			(xy 411.762316 -309.844192) (xy 411.811171 -309.850124) (xy 411.858442 -309.863816) (xy 411.902904 -309.884914)
			(xy 411.943407 -309.91287) (xy 411.9789 -309.946962) (xy 412.008465 -309.986306) (xy 412.031336 -310.029883)
			(xy 412.04692 -310.076564) (xy 412.054815 -310.125141) (xy 412.05531 -310.149748) (xy 412.394158 -310.149748)
			(xy 412.398118 -310.100694) (xy 412.409895 -310.05291) (xy 412.429186 -310.007634) (xy 412.455489 -309.966038)
			(xy 412.488124 -309.929201) (xy 412.526245 -309.898076) (xy 412.568866 -309.873469) (xy 412.614882 -309.856017)
			(xy 412.663101 -309.846173) (xy 412.712276 -309.844192) (xy 412.761131 -309.850124) (xy 412.808402 -309.863816)
			(xy 412.852864 -309.884914) (xy 412.893367 -309.91287) (xy 412.92886 -309.946962) (xy 412.958425 -309.986306)
			(xy 412.981296 -310.029883) (xy 412.99688 -310.076564) (xy 413.004775 -310.125141) (xy 413.00527 -310.149748)
			(xy 413.344118 -310.149748) (xy 413.348078 -310.100694) (xy 413.359855 -310.05291) (xy 413.379146 -310.007634)
			(xy 413.405449 -309.966038) (xy 413.438084 -309.929201) (xy 413.476205 -309.898076) (xy 413.518826 -309.873469)
			(xy 413.564842 -309.856017) (xy 413.613061 -309.846173) (xy 413.662236 -309.844192) (xy 413.711091 -309.850124)
			(xy 413.758362 -309.863816) (xy 413.802824 -309.884914) (xy 413.843327 -309.91287) (xy 413.87882 -309.946962)
			(xy 413.908385 -309.986306) (xy 413.931256 -310.029883) (xy 413.94684 -310.076564) (xy 413.954735 -310.125141)
			(xy 413.95523 -310.149748) (xy 414.294078 -310.149748) (xy 414.298038 -310.100694) (xy 414.309815 -310.05291)
			(xy 414.329106 -310.007634) (xy 414.355409 -309.966038) (xy 414.388044 -309.929201) (xy 414.426165 -309.898076)
			(xy 414.468786 -309.873469) (xy 414.514802 -309.856017) (xy 414.563021 -309.846173) (xy 414.612196 -309.844192)
			(xy 414.661051 -309.850124) (xy 414.708322 -309.863816) (xy 414.752784 -309.884914) (xy 414.793287 -309.91287)
			(xy 414.82878 -309.946962) (xy 414.858345 -309.986306) (xy 414.881216 -310.029883) (xy 414.8968 -310.076564)
			(xy 414.904695 -310.125141) (xy 414.90519 -310.149748) (xy 415.244038 -310.149748) (xy 415.247998 -310.100694)
			(xy 415.259775 -310.05291) (xy 415.279066 -310.007634) (xy 415.305369 -309.966038) (xy 415.338004 -309.929201)
			(xy 415.376125 -309.898076) (xy 415.418746 -309.873469) (xy 415.464762 -309.856017) (xy 415.512981 -309.846173)
			(xy 415.562156 -309.844192) (xy 415.611011 -309.850124) (xy 415.658282 -309.863816) (xy 415.702744 -309.884914)
			(xy 415.743247 -309.91287) (xy 415.77874 -309.946962) (xy 415.808305 -309.986306) (xy 415.831176 -310.029883)
			(xy 415.84676 -310.076564) (xy 415.854655 -310.125141) (xy 415.85515 -310.149748) (xy 416.193998 -310.149748)
			(xy 416.197958 -310.100694) (xy 416.209735 -310.05291) (xy 416.229026 -310.007634) (xy 416.255329 -309.966038)
			(xy 416.287964 -309.929201) (xy 416.326085 -309.898076) (xy 416.368706 -309.873469) (xy 416.414722 -309.856017)
			(xy 416.462941 -309.846173) (xy 416.512116 -309.844192) (xy 416.560971 -309.850124) (xy 416.608242 -309.863816)
			(xy 416.652704 -309.884914) (xy 416.693207 -309.91287) (xy 416.7287 -309.946962) (xy 416.758265 -309.986306)
			(xy 416.781136 -310.029883) (xy 416.79672 -310.076564) (xy 416.804615 -310.125141) (xy 416.80511 -310.149748)
			(xy 417.144212 -310.149748) (xy 417.148172 -310.100694) (xy 417.159949 -310.05291) (xy 417.17924 -310.007634)
			(xy 417.205543 -309.966038) (xy 417.238178 -309.929201) (xy 417.276299 -309.898076) (xy 417.31892 -309.873469)
			(xy 417.364936 -309.856017) (xy 417.413155 -309.846173) (xy 417.46233 -309.844192) (xy 417.511185 -309.850124)
			(xy 417.558456 -309.863816) (xy 417.602918 -309.884914) (xy 417.643421 -309.91287) (xy 417.678914 -309.946962)
			(xy 417.708479 -309.986306) (xy 417.73135 -310.029883) (xy 417.746934 -310.076564) (xy 417.754829 -310.125141)
			(xy 417.755324 -310.149748) (xy 418.094172 -310.149748) (xy 418.098132 -310.100694) (xy 418.109909 -310.05291)
			(xy 418.1292 -310.007634) (xy 418.155503 -309.966038) (xy 418.188138 -309.929201) (xy 418.226259 -309.898076)
			(xy 418.26888 -309.873469) (xy 418.314896 -309.856017) (xy 418.363115 -309.846173) (xy 418.41229 -309.844192)
			(xy 418.461145 -309.850124) (xy 418.508416 -309.863816) (xy 418.552878 -309.884914) (xy 418.593381 -309.91287)
			(xy 418.628874 -309.946962) (xy 418.658439 -309.986306) (xy 418.68131 -310.029883) (xy 418.696894 -310.076564)
			(xy 418.704789 -310.125141) (xy 418.705284 -310.149748) (xy 419.044132 -310.149748) (xy 419.048092 -310.100694)
			(xy 419.059869 -310.05291) (xy 419.07916 -310.007634) (xy 419.105463 -309.966038) (xy 419.138098 -309.929201)
			(xy 419.176219 -309.898076) (xy 419.21884 -309.873469) (xy 419.264856 -309.856017) (xy 419.313075 -309.846173)
			(xy 419.36225 -309.844192) (xy 419.411105 -309.850124) (xy 419.458376 -309.863816) (xy 419.502838 -309.884914)
			(xy 419.543341 -309.91287) (xy 419.578834 -309.946962) (xy 419.608399 -309.986306) (xy 419.63127 -310.029883)
			(xy 419.646854 -310.076564) (xy 419.654749 -310.125141) (xy 419.655244 -310.149748) (xy 419.994092 -310.149748)
			(xy 419.998052 -310.100694) (xy 420.009829 -310.05291) (xy 420.02912 -310.007634) (xy 420.055423 -309.966038)
			(xy 420.088058 -309.929201) (xy 420.126179 -309.898076) (xy 420.1688 -309.873469) (xy 420.214816 -309.856017)
			(xy 420.263035 -309.846173) (xy 420.31221 -309.844192) (xy 420.361065 -309.850124) (xy 420.408336 -309.863816)
			(xy 420.452798 -309.884914) (xy 420.493301 -309.91287) (xy 420.528794 -309.946962) (xy 420.558359 -309.986306)
			(xy 420.58123 -310.029883) (xy 420.596814 -310.076564) (xy 420.604709 -310.125141) (xy 420.605204 -310.149748)
			(xy 420.944052 -310.149748) (xy 420.948012 -310.100694) (xy 420.959789 -310.05291) (xy 420.97908 -310.007634)
			(xy 421.005383 -309.966038) (xy 421.038018 -309.929201) (xy 421.076139 -309.898076) (xy 421.11876 -309.873469)
			(xy 421.164776 -309.856017) (xy 421.212995 -309.846173) (xy 421.26217 -309.844192) (xy 421.311025 -309.850124)
			(xy 421.358296 -309.863816) (xy 421.402758 -309.884914) (xy 421.443261 -309.91287) (xy 421.478754 -309.946962)
			(xy 421.508319 -309.986306) (xy 421.53119 -310.029883) (xy 421.546774 -310.076564) (xy 421.554669 -310.125141)
			(xy 421.555164 -310.149748) (xy 421.894012 -310.149748) (xy 421.897972 -310.100694) (xy 421.909749 -310.05291)
			(xy 421.92904 -310.007634) (xy 421.955343 -309.966038) (xy 421.987978 -309.929201) (xy 422.026099 -309.898076)
			(xy 422.06872 -309.873469) (xy 422.114736 -309.856017) (xy 422.162955 -309.846173) (xy 422.21213 -309.844192)
			(xy 422.260985 -309.850124) (xy 422.308256 -309.863816) (xy 422.352718 -309.884914) (xy 422.393221 -309.91287)
			(xy 422.428714 -309.946962) (xy 422.458279 -309.986306) (xy 422.48115 -310.029883) (xy 422.496734 -310.076564)
			(xy 422.504629 -310.125141) (xy 422.505124 -310.149748) (xy 422.844226 -310.149748) (xy 422.848186 -310.100694)
			(xy 422.859963 -310.05291) (xy 422.879254 -310.007634) (xy 422.905557 -309.966038) (xy 422.938192 -309.929201)
			(xy 422.976313 -309.898076) (xy 423.018934 -309.873469) (xy 423.06495 -309.856017) (xy 423.113169 -309.846173)
			(xy 423.162344 -309.844192) (xy 423.211199 -309.850124) (xy 423.25847 -309.863816) (xy 423.302932 -309.884914)
			(xy 423.343435 -309.91287) (xy 423.378928 -309.946962) (xy 423.408493 -309.986306) (xy 423.431364 -310.029883)
			(xy 423.446948 -310.076564) (xy 423.454843 -310.125141) (xy 423.455338 -310.149748) (xy 423.794186 -310.149748)
			(xy 423.798146 -310.100694) (xy 423.809923 -310.05291) (xy 423.829214 -310.007634) (xy 423.855517 -309.966038)
			(xy 423.888152 -309.929201) (xy 423.926273 -309.898076) (xy 423.968894 -309.873469) (xy 424.01491 -309.856017)
			(xy 424.063129 -309.846173) (xy 424.112304 -309.844192) (xy 424.161159 -309.850124) (xy 424.20843 -309.863816)
			(xy 424.252892 -309.884914) (xy 424.293395 -309.91287) (xy 424.328888 -309.946962) (xy 424.358453 -309.986306)
			(xy 424.381324 -310.029883) (xy 424.396908 -310.076564) (xy 424.404803 -310.125141) (xy 424.405298 -310.149748)
			(xy 424.404803 -310.174355) (xy 424.396908 -310.222932) (xy 424.381324 -310.269613) (xy 424.358453 -310.31319)
			(xy 424.328888 -310.352534) (xy 424.293395 -310.386626) (xy 424.252892 -310.414582) (xy 424.20843 -310.43568)
			(xy 424.161159 -310.449372) (xy 424.112304 -310.455304) (xy 424.063129 -310.453323) (xy 424.01491 -310.443479)
			(xy 423.968894 -310.426027) (xy 423.926273 -310.40142) (xy 423.888152 -310.370295) (xy 423.855517 -310.333458)
			(xy 423.829214 -310.291862) (xy 423.809923 -310.246586) (xy 423.798146 -310.198802) (xy 423.794186 -310.149748)
			(xy 423.455338 -310.149748) (xy 423.454843 -310.174355) (xy 423.446948 -310.222932) (xy 423.431364 -310.269613)
			(xy 423.408493 -310.31319) (xy 423.378928 -310.352534) (xy 423.343435 -310.386626) (xy 423.302932 -310.414582)
			(xy 423.25847 -310.43568) (xy 423.211199 -310.449372) (xy 423.162344 -310.455304) (xy 423.113169 -310.453323)
			(xy 423.06495 -310.443479) (xy 423.018934 -310.426027) (xy 422.976313 -310.40142) (xy 422.938192 -310.370295)
			(xy 422.905557 -310.333458) (xy 422.879254 -310.291862) (xy 422.859963 -310.246586) (xy 422.848186 -310.198802)
			(xy 422.844226 -310.149748) (xy 422.505124 -310.149748) (xy 422.504629 -310.174355) (xy 422.496734 -310.222932)
			(xy 422.48115 -310.269613) (xy 422.458279 -310.31319) (xy 422.428714 -310.352534) (xy 422.393221 -310.386626)
			(xy 422.352718 -310.414582) (xy 422.308256 -310.43568) (xy 422.260985 -310.449372) (xy 422.21213 -310.455304)
			(xy 422.162955 -310.453323) (xy 422.114736 -310.443479) (xy 422.06872 -310.426027) (xy 422.026099 -310.40142)
			(xy 421.987978 -310.370295) (xy 421.955343 -310.333458) (xy 421.92904 -310.291862) (xy 421.909749 -310.246586)
			(xy 421.897972 -310.198802) (xy 421.894012 -310.149748) (xy 421.555164 -310.149748) (xy 421.554669 -310.174355)
			(xy 421.546774 -310.222932) (xy 421.53119 -310.269613) (xy 421.508319 -310.31319) (xy 421.478754 -310.352534)
			(xy 421.443261 -310.386626) (xy 421.402758 -310.414582) (xy 421.358296 -310.43568) (xy 421.311025 -310.449372)
			(xy 421.26217 -310.455304) (xy 421.212995 -310.453323) (xy 421.164776 -310.443479) (xy 421.11876 -310.426027)
			(xy 421.076139 -310.40142) (xy 421.038018 -310.370295) (xy 421.005383 -310.333458) (xy 420.97908 -310.291862)
			(xy 420.959789 -310.246586) (xy 420.948012 -310.198802) (xy 420.944052 -310.149748) (xy 420.605204 -310.149748)
			(xy 420.604709 -310.174355) (xy 420.596814 -310.222932) (xy 420.58123 -310.269613) (xy 420.558359 -310.31319)
			(xy 420.528794 -310.352534) (xy 420.493301 -310.386626) (xy 420.452798 -310.414582) (xy 420.408336 -310.43568)
			(xy 420.361065 -310.449372) (xy 420.31221 -310.455304) (xy 420.263035 -310.453323) (xy 420.214816 -310.443479)
			(xy 420.1688 -310.426027) (xy 420.126179 -310.40142) (xy 420.088058 -310.370295) (xy 420.055423 -310.333458)
			(xy 420.02912 -310.291862) (xy 420.009829 -310.246586) (xy 419.998052 -310.198802) (xy 419.994092 -310.149748)
			(xy 419.655244 -310.149748) (xy 419.654749 -310.174355) (xy 419.646854 -310.222932) (xy 419.63127 -310.269613)
			(xy 419.608399 -310.31319) (xy 419.578834 -310.352534) (xy 419.543341 -310.386626) (xy 419.502838 -310.414582)
			(xy 419.458376 -310.43568) (xy 419.411105 -310.449372) (xy 419.36225 -310.455304) (xy 419.313075 -310.453323)
			(xy 419.264856 -310.443479) (xy 419.21884 -310.426027) (xy 419.176219 -310.40142) (xy 419.138098 -310.370295)
			(xy 419.105463 -310.333458) (xy 419.07916 -310.291862) (xy 419.059869 -310.246586) (xy 419.048092 -310.198802)
			(xy 419.044132 -310.149748) (xy 418.705284 -310.149748) (xy 418.704789 -310.174355) (xy 418.696894 -310.222932)
			(xy 418.68131 -310.269613) (xy 418.658439 -310.31319) (xy 418.628874 -310.352534) (xy 418.593381 -310.386626)
			(xy 418.552878 -310.414582) (xy 418.508416 -310.43568) (xy 418.461145 -310.449372) (xy 418.41229 -310.455304)
			(xy 418.363115 -310.453323) (xy 418.314896 -310.443479) (xy 418.26888 -310.426027) (xy 418.226259 -310.40142)
			(xy 418.188138 -310.370295) (xy 418.155503 -310.333458) (xy 418.1292 -310.291862) (xy 418.109909 -310.246586)
			(xy 418.098132 -310.198802) (xy 418.094172 -310.149748) (xy 417.755324 -310.149748) (xy 417.754829 -310.174355)
			(xy 417.746934 -310.222932) (xy 417.73135 -310.269613) (xy 417.708479 -310.31319) (xy 417.678914 -310.352534)
			(xy 417.643421 -310.386626) (xy 417.602918 -310.414582) (xy 417.558456 -310.43568) (xy 417.511185 -310.449372)
			(xy 417.46233 -310.455304) (xy 417.413155 -310.453323) (xy 417.364936 -310.443479) (xy 417.31892 -310.426027)
			(xy 417.276299 -310.40142) (xy 417.238178 -310.370295) (xy 417.205543 -310.333458) (xy 417.17924 -310.291862)
			(xy 417.159949 -310.246586) (xy 417.148172 -310.198802) (xy 417.144212 -310.149748) (xy 416.80511 -310.149748)
			(xy 416.804615 -310.174355) (xy 416.79672 -310.222932) (xy 416.781136 -310.269613) (xy 416.758265 -310.31319)
			(xy 416.7287 -310.352534) (xy 416.693207 -310.386626) (xy 416.652704 -310.414582) (xy 416.608242 -310.43568)
			(xy 416.560971 -310.449372) (xy 416.512116 -310.455304) (xy 416.462941 -310.453323) (xy 416.414722 -310.443479)
			(xy 416.368706 -310.426027) (xy 416.326085 -310.40142) (xy 416.287964 -310.370295) (xy 416.255329 -310.333458)
			(xy 416.229026 -310.291862) (xy 416.209735 -310.246586) (xy 416.197958 -310.198802) (xy 416.193998 -310.149748)
			(xy 415.85515 -310.149748) (xy 415.854655 -310.174355) (xy 415.84676 -310.222932) (xy 415.831176 -310.269613)
			(xy 415.808305 -310.31319) (xy 415.77874 -310.352534) (xy 415.743247 -310.386626) (xy 415.702744 -310.414582)
			(xy 415.658282 -310.43568) (xy 415.611011 -310.449372) (xy 415.562156 -310.455304) (xy 415.512981 -310.453323)
			(xy 415.464762 -310.443479) (xy 415.418746 -310.426027) (xy 415.376125 -310.40142) (xy 415.338004 -310.370295)
			(xy 415.305369 -310.333458) (xy 415.279066 -310.291862) (xy 415.259775 -310.246586) (xy 415.247998 -310.198802)
			(xy 415.244038 -310.149748) (xy 414.90519 -310.149748) (xy 414.904695 -310.174355) (xy 414.8968 -310.222932)
			(xy 414.881216 -310.269613) (xy 414.858345 -310.31319) (xy 414.82878 -310.352534) (xy 414.793287 -310.386626)
			(xy 414.752784 -310.414582) (xy 414.708322 -310.43568) (xy 414.661051 -310.449372) (xy 414.612196 -310.455304)
			(xy 414.563021 -310.453323) (xy 414.514802 -310.443479) (xy 414.468786 -310.426027) (xy 414.426165 -310.40142)
			(xy 414.388044 -310.370295) (xy 414.355409 -310.333458) (xy 414.329106 -310.291862) (xy 414.309815 -310.246586)
			(xy 414.298038 -310.198802) (xy 414.294078 -310.149748) (xy 413.95523 -310.149748) (xy 413.954735 -310.174355)
			(xy 413.94684 -310.222932) (xy 413.931256 -310.269613) (xy 413.908385 -310.31319) (xy 413.87882 -310.352534)
			(xy 413.843327 -310.386626) (xy 413.802824 -310.414582) (xy 413.758362 -310.43568) (xy 413.711091 -310.449372)
			(xy 413.662236 -310.455304) (xy 413.613061 -310.453323) (xy 413.564842 -310.443479) (xy 413.518826 -310.426027)
			(xy 413.476205 -310.40142) (xy 413.438084 -310.370295) (xy 413.405449 -310.333458) (xy 413.379146 -310.291862)
			(xy 413.359855 -310.246586) (xy 413.348078 -310.198802) (xy 413.344118 -310.149748) (xy 413.00527 -310.149748)
			(xy 413.004775 -310.174355) (xy 412.99688 -310.222932) (xy 412.981296 -310.269613) (xy 412.958425 -310.31319)
			(xy 412.92886 -310.352534) (xy 412.893367 -310.386626) (xy 412.852864 -310.414582) (xy 412.808402 -310.43568)
			(xy 412.761131 -310.449372) (xy 412.712276 -310.455304) (xy 412.663101 -310.453323) (xy 412.614882 -310.443479)
			(xy 412.568866 -310.426027) (xy 412.526245 -310.40142) (xy 412.488124 -310.370295) (xy 412.455489 -310.333458)
			(xy 412.429186 -310.291862) (xy 412.409895 -310.246586) (xy 412.398118 -310.198802) (xy 412.394158 -310.149748)
			(xy 412.05531 -310.149748) (xy 412.054815 -310.174355) (xy 412.04692 -310.222932) (xy 412.031336 -310.269613)
			(xy 412.008465 -310.31319) (xy 411.9789 -310.352534) (xy 411.943407 -310.386626) (xy 411.902904 -310.414582)
			(xy 411.858442 -310.43568) (xy 411.811171 -310.449372) (xy 411.762316 -310.455304) (xy 411.713141 -310.453323)
			(xy 411.664922 -310.443479) (xy 411.618906 -310.426027) (xy 411.576285 -310.40142) (xy 411.538164 -310.370295)
			(xy 411.505529 -310.333458) (xy 411.479226 -310.291862) (xy 411.459935 -310.246586) (xy 411.448158 -310.198802)
			(xy 411.444198 -310.149748) (xy 411.105096 -310.149748) (xy 411.104601 -310.174355) (xy 411.096706 -310.222932)
			(xy 411.081122 -310.269613) (xy 411.058251 -310.31319) (xy 411.028686 -310.352534) (xy 410.993193 -310.386626)
			(xy 410.95269 -310.414582) (xy 410.908228 -310.43568) (xy 410.860957 -310.449372) (xy 410.812102 -310.455304)
			(xy 410.762927 -310.453323) (xy 410.714708 -310.443479) (xy 410.668692 -310.426027) (xy 410.626071 -310.40142)
			(xy 410.58795 -310.370295) (xy 410.555315 -310.333458) (xy 410.529012 -310.291862) (xy 410.509721 -310.246586)
			(xy 410.497944 -310.198802) (xy 410.493984 -310.149748) (xy 410.155136 -310.149748) (xy 410.154641 -310.174355)
			(xy 410.146746 -310.222932) (xy 410.131162 -310.269613) (xy 410.108291 -310.31319) (xy 410.078726 -310.352534)
			(xy 410.043233 -310.386626) (xy 410.00273 -310.414582) (xy 409.958268 -310.43568) (xy 409.910997 -310.449372)
			(xy 409.862142 -310.455304) (xy 409.812967 -310.453323) (xy 409.764748 -310.443479) (xy 409.718732 -310.426027)
			(xy 409.676111 -310.40142) (xy 409.63799 -310.370295) (xy 409.605355 -310.333458) (xy 409.579052 -310.291862)
			(xy 409.559761 -310.246586) (xy 409.547984 -310.198802) (xy 409.544024 -310.149748) (xy 409.205176 -310.149748)
			(xy 409.204681 -310.174355) (xy 409.196786 -310.222932) (xy 409.181202 -310.269613) (xy 409.158331 -310.31319)
			(xy 409.128766 -310.352534) (xy 409.093273 -310.386626) (xy 409.05277 -310.414582) (xy 409.008308 -310.43568)
			(xy 408.961037 -310.449372) (xy 408.912182 -310.455304) (xy 408.863007 -310.453323) (xy 408.814788 -310.443479)
			(xy 408.768772 -310.426027) (xy 408.726151 -310.40142) (xy 408.68803 -310.370295) (xy 408.655395 -310.333458)
			(xy 408.629092 -310.291862) (xy 408.609801 -310.246586) (xy 408.598024 -310.198802) (xy 408.594064 -310.149748)
			(xy 408.255216 -310.149748) (xy 408.254721 -310.174355) (xy 408.246826 -310.222932) (xy 408.231242 -310.269613)
			(xy 408.208371 -310.31319) (xy 408.178806 -310.352534) (xy 408.143313 -310.386626) (xy 408.10281 -310.414582)
			(xy 408.058348 -310.43568) (xy 408.011077 -310.449372) (xy 407.962222 -310.455304) (xy 407.913047 -310.453323)
			(xy 407.864828 -310.443479) (xy 407.818812 -310.426027) (xy 407.776191 -310.40142) (xy 407.73807 -310.370295)
			(xy 407.705435 -310.333458) (xy 407.679132 -310.291862) (xy 407.659841 -310.246586) (xy 407.648064 -310.198802)
			(xy 407.644104 -310.149748) (xy 407.305256 -310.149748) (xy 407.304761 -310.174355) (xy 407.296866 -310.222932)
			(xy 407.281282 -310.269613) (xy 407.258411 -310.31319) (xy 407.228846 -310.352534) (xy 407.193353 -310.386626)
			(xy 407.15285 -310.414582) (xy 407.108388 -310.43568) (xy 407.061117 -310.449372) (xy 407.012262 -310.455304)
			(xy 406.963087 -310.453323) (xy 406.914868 -310.443479) (xy 406.868852 -310.426027) (xy 406.826231 -310.40142)
			(xy 406.78811 -310.370295) (xy 406.755475 -310.333458) (xy 406.729172 -310.291862) (xy 406.709881 -310.246586)
			(xy 406.698104 -310.198802) (xy 406.694144 -310.149748) (xy 406.355278 -310.149748) (xy 406.353047 -310.190964)
			(xy 406.342379 -310.239447) (xy 406.324009 -310.285565) (xy 406.298419 -310.328104) (xy 406.266285 -310.365942)
			(xy 406.228453 -310.398084) (xy 406.185919 -310.423682) (xy 406.139804 -310.442061) (xy 406.091324 -310.452738)
			(xy 406.041754 -310.455432) (xy 405.992402 -310.45007) (xy 405.944568 -310.436796) (xy 405.899511 -310.415957)
			(xy 405.858418 -310.388104) (xy 405.822374 -310.35397) (xy 405.792326 -310.314454) (xy 405.769066 -310.270598)
			(xy 405.753209 -310.223556) (xy 405.74517 -310.174569) (xy 405.74468 -310.149748) (xy 405.744864 -310.135565)
			(xy 405.747531 -310.107325) (xy 405.750014 -310.09336) (xy 405.7523 -310.080914) (xy 405.744934 -310.057292)
			(xy 405.667464 -309.979822) (xy 405.643842 -309.972456) (xy 405.631396 -309.974742) (xy 405.617429 -309.977215)
			(xy 405.58919 -309.979889) (xy 405.575008 -309.980076) (xy 405.560825 -309.979899) (xy 405.532585 -309.977227)
			(xy 405.51862 -309.974742) (xy 405.506174 -309.972456) (xy 405.482552 -309.979822) (xy 405.405082 -310.057292)
			(xy 405.397716 -310.080914) (xy 405.400002 -310.09336) (xy 405.402483 -310.107325) (xy 405.405152 -310.135565)
			(xy 405.405336 -310.149748) (xy 405.404814 -310.175003) (xy 405.396501 -310.224825) (xy 405.3801 -310.272599)
			(xy 405.356059 -310.317022) (xy 405.325035 -310.356882) (xy 405.287873 -310.391092) (xy 405.245587 -310.418718)
			(xy 405.199331 -310.439008) (xy 405.150366 -310.451408) (xy 405.100028 -310.455579) (xy 405.04969 -310.451408)
			(xy 405.000725 -310.439008) (xy 404.954469 -310.418718) (xy 404.912183 -310.391092) (xy 404.875021 -310.356882)
			(xy 404.843997 -310.317022) (xy 404.819956 -310.272599) (xy 404.803555 -310.224825) (xy 404.795242 -310.175003)
			(xy 404.79472 -310.149748) (xy 404.794903 -310.135565) (xy 404.797571 -310.107325) (xy 404.800054 -310.09336)
			(xy 404.800054 -310.093106) (xy 404.801571 -310.080877) (xy 404.794246 -310.057384) (xy 404.786084 -310.048148)
			(xy 404.717504 -309.979822) (xy 404.693882 -309.972456) (xy 404.681436 -309.974742) (xy 404.667408 -309.977233)
			(xy 404.63904 -309.979901) (xy 404.624794 -309.980076) (xy 404.610611 -309.979901) (xy 404.582371 -309.977228)
			(xy 404.568406 -309.974742) (xy 404.55596 -309.972456) (xy 404.532338 -309.979822) (xy 404.454868 -310.057292)
			(xy 404.447502 -310.080914) (xy 404.449788 -310.09336) (xy 404.452269 -310.107325) (xy 404.454938 -310.135565)
			(xy 404.455122 -310.149748) (xy 404.45457 -310.174564) (xy 404.446533 -310.223542) (xy 404.430678 -310.270574)
			(xy 404.407424 -310.314422) (xy 404.377382 -310.35393) (xy 404.341344 -310.388057) (xy 404.300259 -310.415905)
			(xy 404.255211 -310.43674) (xy 404.207386 -310.450012) (xy 404.158044 -310.455372) (xy 404.108484 -310.452679)
			(xy 404.060013 -310.442004) (xy 404.013907 -310.423628) (xy 403.971382 -310.398035) (xy 403.933557 -310.365899)
			(xy 403.901429 -310.328068) (xy 403.875845 -310.285537) (xy 403.857478 -310.239428) (xy 403.846813 -310.190955)
			(xy 403.84413 -310.141394) (xy 403.8495 -310.092053) (xy 403.862782 -310.04423) (xy 403.883625 -309.999186)
			(xy 403.911481 -309.958108) (xy 403.945616 -309.922077) (xy 403.98513 -309.892043) (xy 404.028983 -309.868797)
			(xy 404.076018 -309.852952) (xy 404.124998 -309.844925) (xy 404.149814 -309.84444) (xy 404.163997 -309.844614)
			(xy 404.192237 -309.847288) (xy 404.206202 -309.849774) (xy 404.218648 -309.85206) (xy 404.24227 -309.844694)
			(xy 404.31974 -309.767224) (xy 404.327106 -309.743602) (xy 404.32482 -309.731156) (xy 404.322342 -309.71719)
			(xy 404.319671 -309.688951) (xy 404.319486 -309.674768) (xy 404.319658 -309.660585) (xy 404.322333 -309.632345)
			(xy 404.32482 -309.61838) (xy 404.327106 -309.605934) (xy 404.31974 -309.582312) (xy 404.24227 -309.504842)
			(xy 404.218648 -309.497476) (xy 404.206202 -309.499762) (xy 404.192235 -309.502234) (xy 404.163996 -309.504909)
			(xy 404.149814 -309.505096) (xy 404.125821 -309.504649) (xy 404.078424 -309.497144) (xy 404.032786 -309.482316)
			(xy 403.990029 -309.460532) (xy 403.951207 -309.432326) (xy 403.917275 -309.398395) (xy 403.889069 -309.359573)
			(xy 403.867284 -309.316816) (xy 403.852457 -309.271177) (xy 403.844951 -309.223781) (xy 403.844506 -309.199788)
			(xy 403.844681 -309.185605) (xy 403.847354 -309.157365) (xy 403.84984 -309.1434) (xy 403.852126 -309.130954)
			(xy 403.84476 -309.107332) (xy 403.76729 -309.029862) (xy 403.743668 -309.022496) (xy 403.731222 -309.024782)
			(xy 403.717257 -309.027265) (xy 403.689017 -309.029933) (xy 403.674834 -309.030116) (xy 403.65001 -309.029659)
			(xy 403.601014 -309.021632) (xy 403.553963 -309.005784) (xy 403.510095 -308.982532) (xy 403.470568 -308.95249)
			(xy 403.436421 -308.916448) (xy 403.408555 -308.875356) (xy 403.387705 -308.830298) (xy 403.374419 -308.78246)
			(xy 403.369048 -308.733103) (xy 403.030015 -308.733103) (xy 403.029687 -308.749415) (xy 403.021792 -308.797992)
			(xy 403.006208 -308.844673) (xy 402.983337 -308.88825) (xy 402.953772 -308.927594) (xy 402.918279 -308.961686)
			(xy 402.877776 -308.989642) (xy 402.833314 -309.01074) (xy 402.786043 -309.024432) (xy 402.737188 -309.030364)
			(xy 402.688013 -309.028383) (xy 402.639794 -309.018539) (xy 402.593778 -309.001087) (xy 402.551157 -308.97648)
			(xy 402.513036 -308.945355) (xy 402.480401 -308.908518) (xy 402.454098 -308.866922) (xy 402.434807 -308.821646)
			(xy 402.42303 -308.773862) (xy 402.41907 -308.724808) (xy 402.080222 -308.724808) (xy 402.079727 -308.749415)
			(xy 402.071832 -308.797992) (xy 402.056248 -308.844673) (xy 402.033377 -308.88825) (xy 402.003812 -308.927594)
			(xy 401.968319 -308.961686) (xy 401.927816 -308.989642) (xy 401.883354 -309.01074) (xy 401.836083 -309.024432)
			(xy 401.787228 -309.030364) (xy 401.738053 -309.028383) (xy 401.689834 -309.018539) (xy 401.643818 -309.001087)
			(xy 401.601197 -308.97648) (xy 401.563076 -308.945355) (xy 401.530441 -308.908518) (xy 401.504138 -308.866922)
			(xy 401.484847 -308.821646) (xy 401.47307 -308.773862) (xy 401.46911 -308.724808) (xy 401.130262 -308.724808)
			(xy 401.129767 -308.749415) (xy 401.121872 -308.797992) (xy 401.106288 -308.844673) (xy 401.083417 -308.88825)
			(xy 401.053852 -308.927594) (xy 401.018359 -308.961686) (xy 400.977856 -308.989642) (xy 400.933394 -309.01074)
			(xy 400.886123 -309.024432) (xy 400.837268 -309.030364) (xy 400.788093 -309.028383) (xy 400.739874 -309.018539)
			(xy 400.693858 -309.001087) (xy 400.651237 -308.97648) (xy 400.613116 -308.945355) (xy 400.580481 -308.908518)
			(xy 400.554178 -308.866922) (xy 400.534887 -308.821646) (xy 400.52311 -308.773862) (xy 400.51915 -308.724808)
			(xy 400.180302 -308.724808) (xy 400.179807 -308.749415) (xy 400.171912 -308.797992) (xy 400.156328 -308.844673)
			(xy 400.133457 -308.88825) (xy 400.103892 -308.927594) (xy 400.068399 -308.961686) (xy 400.027896 -308.989642)
			(xy 399.983434 -309.01074) (xy 399.936163 -309.024432) (xy 399.887308 -309.030364) (xy 399.838133 -309.028383)
			(xy 399.789914 -309.018539) (xy 399.743898 -309.001087) (xy 399.701277 -308.97648) (xy 399.663156 -308.945355)
			(xy 399.630521 -308.908518) (xy 399.604218 -308.866922) (xy 399.584927 -308.821646) (xy 399.57315 -308.773862)
			(xy 399.56919 -308.724808) (xy 399.230342 -308.724808) (xy 399.229847 -308.749415) (xy 399.221952 -308.797992)
			(xy 399.206368 -308.844673) (xy 399.183497 -308.88825) (xy 399.153932 -308.927594) (xy 399.118439 -308.961686)
			(xy 399.077936 -308.989642) (xy 399.033474 -309.01074) (xy 398.986203 -309.024432) (xy 398.937348 -309.030364)
			(xy 398.888173 -309.028383) (xy 398.839954 -309.018539) (xy 398.793938 -309.001087) (xy 398.751317 -308.97648)
			(xy 398.713196 -308.945355) (xy 398.680561 -308.908518) (xy 398.654258 -308.866922) (xy 398.634967 -308.821646)
			(xy 398.62319 -308.773862) (xy 398.61923 -308.724808) (xy 398.280128 -308.724808) (xy 398.279633 -308.749415)
			(xy 398.271738 -308.797992) (xy 398.256154 -308.844673) (xy 398.233283 -308.88825) (xy 398.203718 -308.927594)
			(xy 398.168225 -308.961686) (xy 398.127722 -308.989642) (xy 398.08326 -309.01074) (xy 398.035989 -309.024432)
			(xy 397.987134 -309.030364) (xy 397.937959 -309.028383) (xy 397.88974 -309.018539) (xy 397.843724 -309.001087)
			(xy 397.801103 -308.97648) (xy 397.762982 -308.945355) (xy 397.730347 -308.908518) (xy 397.704044 -308.866922)
			(xy 397.684753 -308.821646) (xy 397.672976 -308.773862) (xy 397.669016 -308.724808) (xy 397.330168 -308.724808)
			(xy 397.329673 -308.749415) (xy 397.321778 -308.797992) (xy 397.306194 -308.844673) (xy 397.283323 -308.88825)
			(xy 397.253758 -308.927594) (xy 397.218265 -308.961686) (xy 397.177762 -308.989642) (xy 397.1333 -309.01074)
			(xy 397.086029 -309.024432) (xy 397.037174 -309.030364) (xy 396.987999 -309.028383) (xy 396.93978 -309.018539)
			(xy 396.893764 -309.001087) (xy 396.851143 -308.97648) (xy 396.813022 -308.945355) (xy 396.780387 -308.908518)
			(xy 396.754084 -308.866922) (xy 396.734793 -308.821646) (xy 396.723016 -308.773862) (xy 396.719056 -308.724808)
			(xy 396.380208 -308.724808) (xy 396.379713 -308.749415) (xy 396.371818 -308.797992) (xy 396.356234 -308.844673)
			(xy 396.333363 -308.88825) (xy 396.303798 -308.927594) (xy 396.268305 -308.961686) (xy 396.227802 -308.989642)
			(xy 396.18334 -309.01074) (xy 396.136069 -309.024432) (xy 396.087214 -309.030364) (xy 396.038039 -309.028383)
			(xy 395.98982 -309.018539) (xy 395.943804 -309.001087) (xy 395.901183 -308.97648) (xy 395.863062 -308.945355)
			(xy 395.830427 -308.908518) (xy 395.804124 -308.866922) (xy 395.784833 -308.821646) (xy 395.773056 -308.773862)
			(xy 395.769096 -308.724808) (xy 395.43018 -308.724808) (xy 395.430628 -308.733052) (xy 395.425265 -308.782404)
			(xy 395.41199 -308.830238) (xy 395.39115 -308.875294) (xy 395.363296 -308.916385) (xy 395.329162 -308.952428)
			(xy 395.289646 -308.982475) (xy 395.245789 -309.005733) (xy 395.198748 -309.021589) (xy 395.149761 -309.029627)
			(xy 395.12494 -309.030116) (xy 395.110757 -309.029934) (xy 395.082517 -309.027265) (xy 395.068552 -309.024782)
			(xy 395.054593 -309.02257) (xy 395.026457 -309.02516) (xy 395.000108 -309.03536) (xy 394.977561 -309.052388)
			(xy 394.960541 -309.074941) (xy 394.950352 -309.101295) (xy 394.947772 -309.129432) (xy 394.949934 -309.1434)
			(xy 394.952406 -309.157367) (xy 394.955081 -309.185606) (xy 394.955268 -309.199788) (xy 394.954835 -309.224609)
			(xy 394.946806 -309.273598) (xy 394.930957 -309.320643) (xy 394.907706 -309.364504) (xy 394.877666 -309.404026)
			(xy 394.841627 -309.438167) (xy 394.80054 -309.466028) (xy 394.755487 -309.486876) (xy 394.707655 -309.50016)
			(xy 394.658303 -309.50553) (xy 394.608733 -309.502846) (xy 394.56025 -309.492178) (xy 394.514132 -309.473807)
			(xy 394.471593 -309.448217) (xy 394.433755 -309.416082) (xy 394.401613 -309.378249) (xy 394.376016 -309.335715)
			(xy 394.357637 -309.289599) (xy 394.346961 -309.241118) (xy 394.344268 -309.191549) (xy 394.005142 -309.191549)
			(xy 394.005308 -309.199788) (xy 394.004813 -309.224395) (xy 393.996918 -309.272972) (xy 393.981334 -309.319653)
			(xy 393.958463 -309.36323) (xy 393.928898 -309.402574) (xy 393.893405 -309.436666) (xy 393.852902 -309.464622)
			(xy 393.80844 -309.48572) (xy 393.761169 -309.499412) (xy 393.712314 -309.505344) (xy 393.663139 -309.503363)
			(xy 393.61492 -309.493519) (xy 393.568904 -309.476067) (xy 393.526283 -309.45146) (xy 393.488162 -309.420335)
			(xy 393.455527 -309.383498) (xy 393.429224 -309.341902) (xy 393.409933 -309.296626) (xy 393.398156 -309.248842)
			(xy 393.394196 -309.199788) (xy 393.055094 -309.199788) (xy 393.054599 -309.224395) (xy 393.046704 -309.272972)
			(xy 393.03112 -309.319653) (xy 393.008249 -309.36323) (xy 392.978684 -309.402574) (xy 392.943191 -309.436666)
			(xy 392.902688 -309.464622) (xy 392.858226 -309.48572) (xy 392.810955 -309.499412) (xy 392.7621 -309.505344)
			(xy 392.712925 -309.503363) (xy 392.664706 -309.493519) (xy 392.61869 -309.476067) (xy 392.576069 -309.45146)
			(xy 392.537948 -309.420335) (xy 392.505313 -309.383498) (xy 392.47901 -309.341902) (xy 392.459719 -309.296626)
			(xy 392.447942 -309.248842) (xy 392.443982 -309.199788) (xy 392.105134 -309.199788) (xy 392.104639 -309.224395)
			(xy 392.096744 -309.272972) (xy 392.08116 -309.319653) (xy 392.058289 -309.36323) (xy 392.028724 -309.402574)
			(xy 391.993231 -309.436666) (xy 391.952728 -309.464622) (xy 391.908266 -309.48572) (xy 391.860995 -309.499412)
			(xy 391.81214 -309.505344) (xy 391.762965 -309.503363) (xy 391.714746 -309.493519) (xy 391.66873 -309.476067)
			(xy 391.626109 -309.45146) (xy 391.587988 -309.420335) (xy 391.555353 -309.383498) (xy 391.52905 -309.341902)
			(xy 391.509759 -309.296626) (xy 391.497982 -309.248842) (xy 391.494022 -309.199788) (xy 391.155174 -309.199788)
			(xy 391.154679 -309.224395) (xy 391.146784 -309.272972) (xy 391.1312 -309.319653) (xy 391.108329 -309.36323)
			(xy 391.078764 -309.402574) (xy 391.043271 -309.436666) (xy 391.002768 -309.464622) (xy 390.958306 -309.48572)
			(xy 390.911035 -309.499412) (xy 390.86218 -309.505344) (xy 390.813005 -309.503363) (xy 390.764786 -309.493519)
			(xy 390.71877 -309.476067) (xy 390.676149 -309.45146) (xy 390.638028 -309.420335) (xy 390.605393 -309.383498)
			(xy 390.57909 -309.341902) (xy 390.559799 -309.296626) (xy 390.548022 -309.248842) (xy 390.544062 -309.199788)
			(xy 390.205214 -309.199788) (xy 390.204719 -309.224395) (xy 390.196824 -309.272972) (xy 390.18124 -309.319653)
			(xy 390.158369 -309.36323) (xy 390.128804 -309.402574) (xy 390.093311 -309.436666) (xy 390.052808 -309.464622)
			(xy 390.008346 -309.48572) (xy 389.961075 -309.499412) (xy 389.91222 -309.505344) (xy 389.863045 -309.503363)
			(xy 389.814826 -309.493519) (xy 389.76881 -309.476067) (xy 389.726189 -309.45146) (xy 389.688068 -309.420335)
			(xy 389.655433 -309.383498) (xy 389.62913 -309.341902) (xy 389.609839 -309.296626) (xy 389.598062 -309.248842)
			(xy 389.594102 -309.199788) (xy 389.255254 -309.199788) (xy 389.255254 -309.20055) (xy 389.255 -309.20817)
			(xy 389.255 -310.141366) (xy 389.255254 -310.148986) (xy 389.255254 -310.149748) (xy 389.594102 -310.149748)
			(xy 389.598062 -310.100694) (xy 389.609839 -310.05291) (xy 389.62913 -310.007634) (xy 389.655433 -309.966038)
			(xy 389.688068 -309.929201) (xy 389.726189 -309.898076) (xy 389.76881 -309.873469) (xy 389.814826 -309.856017)
			(xy 389.863045 -309.846173) (xy 389.91222 -309.844192) (xy 389.961075 -309.850124) (xy 390.008346 -309.863816)
			(xy 390.052808 -309.884914) (xy 390.093311 -309.91287) (xy 390.128804 -309.946962) (xy 390.158369 -309.986306)
			(xy 390.18124 -310.029883) (xy 390.196824 -310.076564) (xy 390.204719 -310.125141) (xy 390.205214 -310.149748)
			(xy 390.544062 -310.149748) (xy 390.548022 -310.100694) (xy 390.559799 -310.05291) (xy 390.57909 -310.007634)
			(xy 390.605393 -309.966038) (xy 390.638028 -309.929201) (xy 390.676149 -309.898076) (xy 390.71877 -309.873469)
			(xy 390.764786 -309.856017) (xy 390.813005 -309.846173) (xy 390.86218 -309.844192) (xy 390.911035 -309.850124)
			(xy 390.958306 -309.863816) (xy 391.002768 -309.884914) (xy 391.043271 -309.91287) (xy 391.078764 -309.946962)
			(xy 391.108329 -309.986306) (xy 391.1312 -310.029883) (xy 391.146784 -310.076564) (xy 391.154679 -310.125141)
			(xy 391.155174 -310.149748) (xy 391.494022 -310.149748) (xy 391.497982 -310.100694) (xy 391.509759 -310.05291)
			(xy 391.52905 -310.007634) (xy 391.555353 -309.966038) (xy 391.587988 -309.929201) (xy 391.626109 -309.898076)
			(xy 391.66873 -309.873469) (xy 391.714746 -309.856017) (xy 391.762965 -309.846173) (xy 391.81214 -309.844192)
			(xy 391.860995 -309.850124) (xy 391.908266 -309.863816) (xy 391.952728 -309.884914) (xy 391.993231 -309.91287)
			(xy 392.028724 -309.946962) (xy 392.058289 -309.986306) (xy 392.08116 -310.029883) (xy 392.096744 -310.076564)
			(xy 392.104639 -310.125141) (xy 392.105134 -310.149748) (xy 392.443982 -310.149748) (xy 392.447942 -310.100694)
			(xy 392.459719 -310.05291) (xy 392.47901 -310.007634) (xy 392.505313 -309.966038) (xy 392.537948 -309.929201)
			(xy 392.576069 -309.898076) (xy 392.61869 -309.873469) (xy 392.664706 -309.856017) (xy 392.712925 -309.846173)
			(xy 392.7621 -309.844192) (xy 392.810955 -309.850124) (xy 392.858226 -309.863816) (xy 392.902688 -309.884914)
			(xy 392.943191 -309.91287) (xy 392.978684 -309.946962) (xy 393.008249 -309.986306) (xy 393.03112 -310.029883)
			(xy 393.046704 -310.076564) (xy 393.054599 -310.125141) (xy 393.055094 -310.149748) (xy 393.394196 -310.149748)
			(xy 393.398156 -310.100694) (xy 393.409933 -310.05291) (xy 393.429224 -310.007634) (xy 393.455527 -309.966038)
			(xy 393.488162 -309.929201) (xy 393.526283 -309.898076) (xy 393.568904 -309.873469) (xy 393.61492 -309.856017)
			(xy 393.663139 -309.846173) (xy 393.712314 -309.844192) (xy 393.761169 -309.850124) (xy 393.80844 -309.863816)
			(xy 393.852902 -309.884914) (xy 393.893405 -309.91287) (xy 393.928898 -309.946962) (xy 393.958463 -309.986306)
			(xy 393.981334 -310.029883) (xy 393.996918 -310.076564) (xy 394.004813 -310.125141) (xy 394.005308 -310.149748)
			(xy 394.344156 -310.149748) (xy 394.348116 -310.100694) (xy 394.359893 -310.05291) (xy 394.379184 -310.007634)
			(xy 394.405487 -309.966038) (xy 394.438122 -309.929201) (xy 394.476243 -309.898076) (xy 394.518864 -309.873469)
			(xy 394.56488 -309.856017) (xy 394.613099 -309.846173) (xy 394.662274 -309.844192) (xy 394.711129 -309.850124)
			(xy 394.7584 -309.863816) (xy 394.802862 -309.884914) (xy 394.843365 -309.91287) (xy 394.878858 -309.946962)
			(xy 394.908423 -309.986306) (xy 394.931294 -310.029883) (xy 394.946878 -310.076564) (xy 394.954773 -310.125141)
			(xy 394.955268 -310.149748) (xy 395.294116 -310.149748) (xy 395.298076 -310.100694) (xy 395.309853 -310.05291)
			(xy 395.329144 -310.007634) (xy 395.355447 -309.966038) (xy 395.388082 -309.929201) (xy 395.426203 -309.898076)
			(xy 395.468824 -309.873469) (xy 395.51484 -309.856017) (xy 395.563059 -309.846173) (xy 395.612234 -309.844192)
			(xy 395.661089 -309.850124) (xy 395.70836 -309.863816) (xy 395.752822 -309.884914) (xy 395.793325 -309.91287)
			(xy 395.828818 -309.946962) (xy 395.858383 -309.986306) (xy 395.881254 -310.029883) (xy 395.896838 -310.076564)
			(xy 395.904733 -310.125141) (xy 395.90506 -310.141417) (xy 396.244229 -310.141417) (xy 396.249595 -310.092077)
			(xy 396.262873 -310.044254) (xy 396.283712 -309.999209) (xy 396.311564 -309.958129) (xy 396.345695 -309.922096)
			(xy 396.385205 -309.892059) (xy 396.429054 -309.868809) (xy 396.476087 -309.85296) (xy 396.525064 -309.844927)
			(xy 396.54988 -309.84444) (xy 396.564063 -309.844619) (xy 396.592303 -309.847289) (xy 396.606268 -309.849774)
			(xy 396.618714 -309.85206) (xy 396.642336 -309.844694) (xy 396.719806 -309.767224) (xy 396.727172 -309.743602)
			(xy 396.724886 -309.731156) (xy 396.722407 -309.71719) (xy 396.719737 -309.688951) (xy 396.719552 -309.674768)
			(xy 396.720074 -309.649513) (xy 396.728387 -309.599691) (xy 396.744788 -309.551917) (xy 396.768829 -309.507494)
			(xy 396.799853 -309.467634) (xy 396.837015 -309.433424) (xy 396.879301 -309.405798) (xy 396.925557 -309.385508)
			(xy 396.974522 -309.373108) (xy 397.02486 -309.368937) (xy 397.075198 -309.373108) (xy 397.124163 -309.385508)
			(xy 397.170419 -309.405798) (xy 397.212705 -309.433424) (xy 397.249867 -309.467634) (xy 397.280891 -309.507494)
			(xy 397.304932 -309.551917) (xy 397.321333 -309.599691) (xy 397.329646 -309.649513) (xy 397.330168 -309.674768)
			(xy 397.329988 -309.688951) (xy 397.327318 -309.717191) (xy 397.324834 -309.731156) (xy 397.322548 -309.743602)
			(xy 397.329914 -309.767224) (xy 397.407384 -309.844694) (xy 397.431006 -309.85206) (xy 397.443452 -309.849774)
			(xy 397.457417 -309.847294) (xy 397.485657 -309.844625) (xy 397.49984 -309.84444) (xy 397.514023 -309.84461)
			(xy 397.542263 -309.847287) (xy 397.556228 -309.849774) (xy 397.568674 -309.85206) (xy 397.592296 -309.844694)
			(xy 397.669766 -309.767224) (xy 397.677132 -309.743602) (xy 397.674846 -309.731156) (xy 397.672368 -309.71719)
			(xy 397.669697 -309.688951) (xy 397.669512 -309.674768) (xy 397.670034 -309.649513) (xy 397.678347 -309.599691)
			(xy 397.694748 -309.551917) (xy 397.718789 -309.507494) (xy 397.749813 -309.467634) (xy 397.786975 -309.433424)
			(xy 397.829261 -309.405798) (xy 397.875517 -309.385508) (xy 397.924482 -309.373108) (xy 397.97482 -309.368937)
			(xy 398.025158 -309.373108) (xy 398.074123 -309.385508) (xy 398.120379 -309.405798) (xy 398.162665 -309.433424)
			(xy 398.199827 -309.467634) (xy 398.230851 -309.507494) (xy 398.254892 -309.551917) (xy 398.271293 -309.599691)
			(xy 398.279606 -309.649513) (xy 398.280128 -309.674768) (xy 398.279947 -309.688951) (xy 398.277278 -309.717191)
			(xy 398.274794 -309.731156) (xy 398.272508 -309.743602) (xy 398.279874 -309.767224) (xy 398.357344 -309.844694)
			(xy 398.380966 -309.85206) (xy 398.393412 -309.849774) (xy 398.407378 -309.8473) (xy 398.435618 -309.844626)
			(xy 398.4498 -309.84444) (xy 398.47462 -309.844878) (xy 398.523606 -309.852908) (xy 398.570648 -309.868758)
			(xy 398.614506 -309.892009) (xy 398.654025 -309.922049) (xy 398.688163 -309.958087) (xy 398.716022 -309.999172)
			(xy 398.736867 -310.044224) (xy 398.750149 -310.092054) (xy 398.755518 -310.141403) (xy 398.755066 -310.149748)
			(xy 399.09421 -310.149748) (xy 399.09817 -310.100694) (xy 399.109947 -310.05291) (xy 399.129238 -310.007634)
			(xy 399.155541 -309.966038) (xy 399.188176 -309.929201) (xy 399.226297 -309.898076) (xy 399.268918 -309.873469)
			(xy 399.314934 -309.856017) (xy 399.363153 -309.846173) (xy 399.412328 -309.844192) (xy 399.461183 -309.850124)
			(xy 399.508454 -309.863816) (xy 399.552916 -309.884914) (xy 399.593419 -309.91287) (xy 399.628912 -309.946962)
			(xy 399.658477 -309.986306) (xy 399.681348 -310.029883) (xy 399.696932 -310.076564) (xy 399.704827 -310.125141)
			(xy 399.705322 -310.149748) (xy 400.04417 -310.149748) (xy 400.04813 -310.100694) (xy 400.059907 -310.05291)
			(xy 400.079198 -310.007634) (xy 400.105501 -309.966038) (xy 400.138136 -309.929201) (xy 400.176257 -309.898076)
			(xy 400.218878 -309.873469) (xy 400.264894 -309.856017) (xy 400.313113 -309.846173) (xy 400.362288 -309.844192)
			(xy 400.411143 -309.850124) (xy 400.458414 -309.863816) (xy 400.502876 -309.884914) (xy 400.543379 -309.91287)
			(xy 400.578872 -309.946962) (xy 400.608437 -309.986306) (xy 400.631308 -310.029883) (xy 400.646892 -310.076564)
			(xy 400.654787 -310.125141) (xy 400.655282 -310.149748) (xy 400.99413 -310.149748) (xy 400.99809 -310.100694)
			(xy 401.009867 -310.05291) (xy 401.029158 -310.007634) (xy 401.055461 -309.966038) (xy 401.088096 -309.929201)
			(xy 401.126217 -309.898076) (xy 401.168838 -309.873469) (xy 401.214854 -309.856017) (xy 401.263073 -309.846173)
			(xy 401.312248 -309.844192) (xy 401.361103 -309.850124) (xy 401.408374 -309.863816) (xy 401.452836 -309.884914)
			(xy 401.493339 -309.91287) (xy 401.528832 -309.946962) (xy 401.558397 -309.986306) (xy 401.581268 -310.029883)
			(xy 401.596852 -310.076564) (xy 401.604747 -310.125141) (xy 401.605242 -310.149748) (xy 401.94409 -310.149748)
			(xy 401.94805 -310.100694) (xy 401.959827 -310.05291) (xy 401.979118 -310.007634) (xy 402.005421 -309.966038)
			(xy 402.038056 -309.929201) (xy 402.076177 -309.898076) (xy 402.118798 -309.873469) (xy 402.164814 -309.856017)
			(xy 402.213033 -309.846173) (xy 402.262208 -309.844192) (xy 402.311063 -309.850124) (xy 402.358334 -309.863816)
			(xy 402.402796 -309.884914) (xy 402.443299 -309.91287) (xy 402.478792 -309.946962) (xy 402.508357 -309.986306)
			(xy 402.531228 -310.029883) (xy 402.546812 -310.076564) (xy 402.554707 -310.125141) (xy 402.555202 -310.149748)
			(xy 402.89405 -310.149748) (xy 402.89801 -310.100694) (xy 402.909787 -310.05291) (xy 402.929078 -310.007634)
			(xy 402.955381 -309.966038) (xy 402.988016 -309.929201) (xy 403.026137 -309.898076) (xy 403.068758 -309.873469)
			(xy 403.114774 -309.856017) (xy 403.162993 -309.846173) (xy 403.212168 -309.844192) (xy 403.261023 -309.850124)
			(xy 403.308294 -309.863816) (xy 403.352756 -309.884914) (xy 403.393259 -309.91287) (xy 403.428752 -309.946962)
			(xy 403.458317 -309.986306) (xy 403.481188 -310.029883) (xy 403.496772 -310.076564) (xy 403.504667 -310.125141)
			(xy 403.505162 -310.149748) (xy 403.504667 -310.174355) (xy 403.496772 -310.222932) (xy 403.481188 -310.269613)
			(xy 403.458317 -310.31319) (xy 403.428752 -310.352534) (xy 403.393259 -310.386626) (xy 403.352756 -310.414582)
			(xy 403.308294 -310.43568) (xy 403.261023 -310.449372) (xy 403.212168 -310.455304) (xy 403.162993 -310.453323)
			(xy 403.114774 -310.443479) (xy 403.068758 -310.426027) (xy 403.026137 -310.40142) (xy 402.988016 -310.370295)
			(xy 402.955381 -310.333458) (xy 402.929078 -310.291862) (xy 402.909787 -310.246586) (xy 402.89801 -310.198802)
			(xy 402.89405 -310.149748) (xy 402.555202 -310.149748) (xy 402.554707 -310.174355) (xy 402.546812 -310.222932)
			(xy 402.531228 -310.269613) (xy 402.508357 -310.31319) (xy 402.478792 -310.352534) (xy 402.443299 -310.386626)
			(xy 402.402796 -310.414582) (xy 402.358334 -310.43568) (xy 402.311063 -310.449372) (xy 402.262208 -310.455304)
			(xy 402.213033 -310.453323) (xy 402.164814 -310.443479) (xy 402.118798 -310.426027) (xy 402.076177 -310.40142)
			(xy 402.038056 -310.370295) (xy 402.005421 -310.333458) (xy 401.979118 -310.291862) (xy 401.959827 -310.246586)
			(xy 401.94805 -310.198802) (xy 401.94409 -310.149748) (xy 401.605242 -310.149748) (xy 401.604747 -310.174355)
			(xy 401.596852 -310.222932) (xy 401.581268 -310.269613) (xy 401.558397 -310.31319) (xy 401.528832 -310.352534)
			(xy 401.493339 -310.386626) (xy 401.452836 -310.414582) (xy 401.408374 -310.43568) (xy 401.361103 -310.449372)
			(xy 401.312248 -310.455304) (xy 401.263073 -310.453323) (xy 401.214854 -310.443479) (xy 401.168838 -310.426027)
			(xy 401.126217 -310.40142) (xy 401.088096 -310.370295) (xy 401.055461 -310.333458) (xy 401.029158 -310.291862)
			(xy 401.009867 -310.246586) (xy 400.99809 -310.198802) (xy 400.99413 -310.149748) (xy 400.655282 -310.149748)
			(xy 400.654787 -310.174355) (xy 400.646892 -310.222932) (xy 400.631308 -310.269613) (xy 400.608437 -310.31319)
			(xy 400.578872 -310.352534) (xy 400.543379 -310.386626) (xy 400.502876 -310.414582) (xy 400.458414 -310.43568)
			(xy 400.411143 -310.449372) (xy 400.362288 -310.455304) (xy 400.313113 -310.453323) (xy 400.264894 -310.443479)
			(xy 400.218878 -310.426027) (xy 400.176257 -310.40142) (xy 400.138136 -310.370295) (xy 400.105501 -310.333458)
			(xy 400.079198 -310.291862) (xy 400.059907 -310.246586) (xy 400.04813 -310.198802) (xy 400.04417 -310.149748)
			(xy 399.705322 -310.149748) (xy 399.704827 -310.174355) (xy 399.696932 -310.222932) (xy 399.681348 -310.269613)
			(xy 399.658477 -310.31319) (xy 399.628912 -310.352534) (xy 399.593419 -310.386626) (xy 399.552916 -310.414582)
			(xy 399.508454 -310.43568) (xy 399.461183 -310.449372) (xy 399.412328 -310.455304) (xy 399.363153 -310.453323)
			(xy 399.314934 -310.443479) (xy 399.268918 -310.426027) (xy 399.226297 -310.40142) (xy 399.188176 -310.370295)
			(xy 399.155541 -310.333458) (xy 399.129238 -310.291862) (xy 399.109947 -310.246586) (xy 399.09817 -310.198802)
			(xy 399.09421 -310.149748) (xy 398.755066 -310.149748) (xy 398.752834 -310.19097) (xy 398.742165 -310.23945)
			(xy 398.723795 -310.285566) (xy 398.698206 -310.328102) (xy 398.666072 -310.365938) (xy 398.628241 -310.398078)
			(xy 398.585709 -310.423673) (xy 398.539596 -310.442051) (xy 398.491118 -310.452727) (xy 398.441551 -310.45542)
			(xy 398.392201 -310.450058) (xy 398.344369 -310.436783) (xy 398.299314 -310.415945) (xy 398.258224 -310.388093)
			(xy 398.222181 -310.35396) (xy 398.192135 -310.314446) (xy 398.168877 -310.270592) (xy 398.15302 -310.223553)
			(xy 398.144982 -310.174568) (xy 398.144492 -310.149748) (xy 398.144675 -310.135565) (xy 398.147343 -310.107325)
			(xy 398.149826 -310.09336) (xy 398.152112 -310.080914) (xy 398.144746 -310.057292) (xy 398.067276 -309.979822)
			(xy 398.043654 -309.972456) (xy 398.031208 -309.974742) (xy 398.017241 -309.977213) (xy 397.989002 -309.979889)
			(xy 397.97482 -309.980076) (xy 397.960637 -309.979897) (xy 397.932397 -309.977227) (xy 397.918432 -309.974742)
			(xy 397.905986 -309.972456) (xy 397.882364 -309.979822) (xy 397.804894 -310.057292) (xy 397.797528 -310.080914)
			(xy 397.799814 -310.09336) (xy 397.802295 -310.107325) (xy 397.804964 -310.135565) (xy 397.805148 -310.149748)
			(xy 397.804626 -310.175003) (xy 397.796313 -310.224825) (xy 397.779912 -310.272599) (xy 397.755871 -310.317022)
			(xy 397.724847 -310.356882) (xy 397.687685 -310.391092) (xy 397.645399 -310.418718) (xy 397.599143 -310.439008)
			(xy 397.550178 -310.451408) (xy 397.49984 -310.455579) (xy 397.449502 -310.451408) (xy 397.400537 -310.439008)
			(xy 397.354281 -310.418718) (xy 397.311995 -310.391092) (xy 397.274833 -310.356882) (xy 397.243809 -310.317022)
			(xy 397.219768 -310.272599) (xy 397.203367 -310.224825) (xy 397.195054 -310.175003) (xy 397.194532 -310.149748)
			(xy 397.194715 -310.135565) (xy 397.197383 -310.107325) (xy 397.199866 -310.09336) (xy 397.202152 -310.080914)
			(xy 397.194786 -310.057292) (xy 397.117316 -309.979822) (xy 397.093694 -309.972456) (xy 397.081248 -309.974742)
			(xy 397.067283 -309.977221) (xy 397.039043 -309.979891) (xy 397.02486 -309.980076) (xy 397.010677 -309.979905)
			(xy 396.982437 -309.977229) (xy 396.968472 -309.974742) (xy 396.956026 -309.972456) (xy 396.932404 -309.979822)
			(xy 396.854934 -310.057292) (xy 396.847568 -310.080914) (xy 396.849854 -310.09336) (xy 396.852334 -310.107325)
			(xy 396.855004 -310.135565) (xy 396.855188 -310.149748) (xy 396.85467 -310.174564) (xy 396.846634 -310.22354)
			(xy 396.83078 -310.270572) (xy 396.807526 -310.314419) (xy 396.777485 -310.353926) (xy 396.741449 -310.388053)
			(xy 396.700366 -310.415901) (xy 396.65532 -310.436737) (xy 396.607496 -310.45001) (xy 396.558155 -310.455372)
			(xy 396.508596 -310.452681) (xy 396.460126 -310.442008) (xy 396.41402 -310.423634) (xy 396.371495 -310.398044)
			(xy 396.333669 -310.365911) (xy 396.30154 -310.328083) (xy 396.275953 -310.285555) (xy 396.257584 -310.239448)
			(xy 396.246916 -310.190976) (xy 396.244229 -310.141417) (xy 395.90506 -310.141417) (xy 395.905228 -310.149748)
			(xy 395.904733 -310.174355) (xy 395.896838 -310.222932) (xy 395.881254 -310.269613) (xy 395.858383 -310.31319)
			(xy 395.828818 -310.352534) (xy 395.793325 -310.386626) (xy 395.752822 -310.414582) (xy 395.70836 -310.43568)
			(xy 395.661089 -310.449372) (xy 395.612234 -310.455304) (xy 395.563059 -310.453323) (xy 395.51484 -310.443479)
			(xy 395.468824 -310.426027) (xy 395.426203 -310.40142) (xy 395.388082 -310.370295) (xy 395.355447 -310.333458)
			(xy 395.329144 -310.291862) (xy 395.309853 -310.246586) (xy 395.298076 -310.198802) (xy 395.294116 -310.149748)
			(xy 394.955268 -310.149748) (xy 394.954773 -310.174355) (xy 394.946878 -310.222932) (xy 394.931294 -310.269613)
			(xy 394.908423 -310.31319) (xy 394.878858 -310.352534) (xy 394.843365 -310.386626) (xy 394.802862 -310.414582)
			(xy 394.7584 -310.43568) (xy 394.711129 -310.449372) (xy 394.662274 -310.455304) (xy 394.613099 -310.453323)
			(xy 394.56488 -310.443479) (xy 394.518864 -310.426027) (xy 394.476243 -310.40142) (xy 394.438122 -310.370295)
			(xy 394.405487 -310.333458) (xy 394.379184 -310.291862) (xy 394.359893 -310.246586) (xy 394.348116 -310.198802)
			(xy 394.344156 -310.149748) (xy 394.005308 -310.149748) (xy 394.004813 -310.174355) (xy 393.996918 -310.222932)
			(xy 393.981334 -310.269613) (xy 393.958463 -310.31319) (xy 393.928898 -310.352534) (xy 393.893405 -310.386626)
			(xy 393.852902 -310.414582) (xy 393.80844 -310.43568) (xy 393.761169 -310.449372) (xy 393.712314 -310.455304)
			(xy 393.663139 -310.453323) (xy 393.61492 -310.443479) (xy 393.568904 -310.426027) (xy 393.526283 -310.40142)
			(xy 393.488162 -310.370295) (xy 393.455527 -310.333458) (xy 393.429224 -310.291862) (xy 393.409933 -310.246586)
			(xy 393.398156 -310.198802) (xy 393.394196 -310.149748) (xy 393.055094 -310.149748) (xy 393.054599 -310.174355)
			(xy 393.046704 -310.222932) (xy 393.03112 -310.269613) (xy 393.008249 -310.31319) (xy 392.978684 -310.352534)
			(xy 392.943191 -310.386626) (xy 392.902688 -310.414582) (xy 392.858226 -310.43568) (xy 392.810955 -310.449372)
			(xy 392.7621 -310.455304) (xy 392.712925 -310.453323) (xy 392.664706 -310.443479) (xy 392.61869 -310.426027)
			(xy 392.576069 -310.40142) (xy 392.537948 -310.370295) (xy 392.505313 -310.333458) (xy 392.47901 -310.291862)
			(xy 392.459719 -310.246586) (xy 392.447942 -310.198802) (xy 392.443982 -310.149748) (xy 392.105134 -310.149748)
			(xy 392.104639 -310.174355) (xy 392.096744 -310.222932) (xy 392.08116 -310.269613) (xy 392.058289 -310.31319)
			(xy 392.028724 -310.352534) (xy 391.993231 -310.386626) (xy 391.952728 -310.414582) (xy 391.908266 -310.43568)
			(xy 391.860995 -310.449372) (xy 391.81214 -310.455304) (xy 391.762965 -310.453323) (xy 391.714746 -310.443479)
			(xy 391.66873 -310.426027) (xy 391.626109 -310.40142) (xy 391.587988 -310.370295) (xy 391.555353 -310.333458)
			(xy 391.52905 -310.291862) (xy 391.509759 -310.246586) (xy 391.497982 -310.198802) (xy 391.494022 -310.149748)
			(xy 391.155174 -310.149748) (xy 391.154679 -310.174355) (xy 391.146784 -310.222932) (xy 391.1312 -310.269613)
			(xy 391.108329 -310.31319) (xy 391.078764 -310.352534) (xy 391.043271 -310.386626) (xy 391.002768 -310.414582)
			(xy 390.958306 -310.43568) (xy 390.911035 -310.449372) (xy 390.86218 -310.455304) (xy 390.813005 -310.453323)
			(xy 390.764786 -310.443479) (xy 390.71877 -310.426027) (xy 390.676149 -310.40142) (xy 390.638028 -310.370295)
			(xy 390.605393 -310.333458) (xy 390.57909 -310.291862) (xy 390.559799 -310.246586) (xy 390.548022 -310.198802)
			(xy 390.544062 -310.149748) (xy 390.205214 -310.149748) (xy 390.204719 -310.174355) (xy 390.196824 -310.222932)
			(xy 390.18124 -310.269613) (xy 390.158369 -310.31319) (xy 390.128804 -310.352534) (xy 390.093311 -310.386626)
			(xy 390.052808 -310.414582) (xy 390.008346 -310.43568) (xy 389.961075 -310.449372) (xy 389.91222 -310.455304)
			(xy 389.863045 -310.453323) (xy 389.814826 -310.443479) (xy 389.76881 -310.426027) (xy 389.726189 -310.40142)
			(xy 389.688068 -310.370295) (xy 389.655433 -310.333458) (xy 389.62913 -310.291862) (xy 389.609839 -310.246586)
			(xy 389.598062 -310.198802) (xy 389.594102 -310.149748) (xy 389.255254 -310.149748) (xy 389.255254 -310.15051)
			(xy 389.255 -310.15813) (xy 389.255 -311.09158) (xy 389.255254 -311.0992) (xy 389.255254 -311.099962)
			(xy 389.594102 -311.099962) (xy 389.598062 -311.050908) (xy 389.609839 -311.003124) (xy 389.62913 -310.957848)
			(xy 389.655433 -310.916252) (xy 389.688068 -310.879415) (xy 389.726189 -310.84829) (xy 389.76881 -310.823683)
			(xy 389.814826 -310.806231) (xy 389.863045 -310.796387) (xy 389.91222 -310.794406) (xy 389.961075 -310.800338)
			(xy 390.008346 -310.81403) (xy 390.052808 -310.835128) (xy 390.093311 -310.863084) (xy 390.128804 -310.897176)
			(xy 390.158369 -310.93652) (xy 390.18124 -310.980097) (xy 390.196824 -311.026778) (xy 390.204719 -311.075355)
			(xy 390.205214 -311.099962) (xy 390.544062 -311.099962) (xy 390.548022 -311.050908) (xy 390.559799 -311.003124)
			(xy 390.57909 -310.957848) (xy 390.605393 -310.916252) (xy 390.638028 -310.879415) (xy 390.676149 -310.84829)
			(xy 390.71877 -310.823683) (xy 390.764786 -310.806231) (xy 390.813005 -310.796387) (xy 390.86218 -310.794406)
			(xy 390.911035 -310.800338) (xy 390.958306 -310.81403) (xy 391.002768 -310.835128) (xy 391.043271 -310.863084)
			(xy 391.078764 -310.897176) (xy 391.108329 -310.93652) (xy 391.1312 -310.980097) (xy 391.146784 -311.026778)
			(xy 391.154679 -311.075355) (xy 391.155174 -311.099962) (xy 391.494022 -311.099962) (xy 391.497982 -311.050908)
			(xy 391.509759 -311.003124) (xy 391.52905 -310.957848) (xy 391.555353 -310.916252) (xy 391.587988 -310.879415)
			(xy 391.626109 -310.84829) (xy 391.66873 -310.823683) (xy 391.714746 -310.806231) (xy 391.762965 -310.796387)
			(xy 391.81214 -310.794406) (xy 391.860995 -310.800338) (xy 391.908266 -310.81403) (xy 391.952728 -310.835128)
			(xy 391.993231 -310.863084) (xy 392.028724 -310.897176) (xy 392.058289 -310.93652) (xy 392.08116 -310.980097)
			(xy 392.096744 -311.026778) (xy 392.104639 -311.075355) (xy 392.105134 -311.099962) (xy 392.443982 -311.099962)
			(xy 392.447942 -311.050908) (xy 392.459719 -311.003124) (xy 392.47901 -310.957848) (xy 392.505313 -310.916252)
			(xy 392.537948 -310.879415) (xy 392.576069 -310.84829) (xy 392.61869 -310.823683) (xy 392.664706 -310.806231)
			(xy 392.712925 -310.796387) (xy 392.7621 -310.794406) (xy 392.810955 -310.800338) (xy 392.858226 -310.81403)
			(xy 392.902688 -310.835128) (xy 392.943191 -310.863084) (xy 392.978684 -310.897176) (xy 393.008249 -310.93652)
			(xy 393.03112 -310.980097) (xy 393.046704 -311.026778) (xy 393.054599 -311.075355) (xy 393.055094 -311.099962)
			(xy 393.394196 -311.099962) (xy 393.398156 -311.050908) (xy 393.409933 -311.003124) (xy 393.429224 -310.957848)
			(xy 393.455527 -310.916252) (xy 393.488162 -310.879415) (xy 393.526283 -310.84829) (xy 393.568904 -310.823683)
			(xy 393.61492 -310.806231) (xy 393.663139 -310.796387) (xy 393.712314 -310.794406) (xy 393.761169 -310.800338)
			(xy 393.80844 -310.81403) (xy 393.852902 -310.835128) (xy 393.893405 -310.863084) (xy 393.928898 -310.897176)
			(xy 393.958463 -310.93652) (xy 393.981334 -310.980097) (xy 393.996918 -311.026778) (xy 394.004813 -311.075355)
			(xy 394.005308 -311.099962) (xy 394.344156 -311.099962) (xy 394.348116 -311.050908) (xy 394.359893 -311.003124)
			(xy 394.379184 -310.957848) (xy 394.405487 -310.916252) (xy 394.438122 -310.879415) (xy 394.476243 -310.84829)
			(xy 394.518864 -310.823683) (xy 394.56488 -310.806231) (xy 394.613099 -310.796387) (xy 394.662274 -310.794406)
			(xy 394.711129 -310.800338) (xy 394.7584 -310.81403) (xy 394.802862 -310.835128) (xy 394.843365 -310.863084)
			(xy 394.878858 -310.897176) (xy 394.908423 -310.93652) (xy 394.931294 -310.980097) (xy 394.946878 -311.026778)
			(xy 394.954773 -311.075355) (xy 394.955268 -311.099962) (xy 395.294116 -311.099962) (xy 395.298076 -311.050908)
			(xy 395.309853 -311.003124) (xy 395.329144 -310.957848) (xy 395.355447 -310.916252) (xy 395.388082 -310.879415)
			(xy 395.426203 -310.84829) (xy 395.468824 -310.823683) (xy 395.51484 -310.806231) (xy 395.563059 -310.796387)
			(xy 395.612234 -310.794406) (xy 395.661089 -310.800338) (xy 395.70836 -310.81403) (xy 395.752822 -310.835128)
			(xy 395.793325 -310.863084) (xy 395.828818 -310.897176) (xy 395.858383 -310.93652) (xy 395.881254 -310.980097)
			(xy 395.896838 -311.026778) (xy 395.904733 -311.075355) (xy 395.905228 -311.099962) (xy 396.244076 -311.099962)
			(xy 396.248036 -311.050908) (xy 396.259813 -311.003124) (xy 396.279104 -310.957848) (xy 396.305407 -310.916252)
			(xy 396.338042 -310.879415) (xy 396.376163 -310.84829) (xy 396.418784 -310.823683) (xy 396.4648 -310.806231)
			(xy 396.513019 -310.796387) (xy 396.562194 -310.794406) (xy 396.611049 -310.800338) (xy 396.65832 -310.81403)
			(xy 396.702782 -310.835128) (xy 396.743285 -310.863084) (xy 396.778778 -310.897176) (xy 396.808343 -310.93652)
			(xy 396.831214 -310.980097) (xy 396.846798 -311.026778) (xy 396.854693 -311.075355) (xy 396.855188 -311.099962)
			(xy 397.194036 -311.099962) (xy 397.197996 -311.050908) (xy 397.209773 -311.003124) (xy 397.229064 -310.957848)
			(xy 397.255367 -310.916252) (xy 397.288002 -310.879415) (xy 397.326123 -310.84829) (xy 397.368744 -310.823683)
			(xy 397.41476 -310.806231) (xy 397.462979 -310.796387) (xy 397.512154 -310.794406) (xy 397.561009 -310.800338)
			(xy 397.60828 -310.81403) (xy 397.652742 -310.835128) (xy 397.693245 -310.863084) (xy 397.728738 -310.897176)
			(xy 397.758303 -310.93652) (xy 397.781174 -310.980097) (xy 397.796758 -311.026778) (xy 397.804653 -311.075355)
			(xy 397.805148 -311.099962) (xy 398.143996 -311.099962) (xy 398.147956 -311.050908) (xy 398.159733 -311.003124)
			(xy 398.179024 -310.957848) (xy 398.205327 -310.916252) (xy 398.237962 -310.879415) (xy 398.276083 -310.84829)
			(xy 398.318704 -310.823683) (xy 398.36472 -310.806231) (xy 398.412939 -310.796387) (xy 398.462114 -310.794406)
			(xy 398.510969 -310.800338) (xy 398.55824 -310.81403) (xy 398.602702 -310.835128) (xy 398.643205 -310.863084)
			(xy 398.678698 -310.897176) (xy 398.708263 -310.93652) (xy 398.731134 -310.980097) (xy 398.746718 -311.026778)
			(xy 398.754613 -311.075355) (xy 398.755108 -311.099962) (xy 398.754613 -311.124569) (xy 398.754434 -311.12567)
			(xy 399.073366 -311.12567) (xy 399.073366 -311.074254) (xy 399.081409 -311.023472) (xy 399.097297 -310.974573)
			(xy 399.12064 -310.928761) (xy 399.150861 -310.887165) (xy 399.187217 -310.850809) (xy 399.228813 -310.820588)
			(xy 399.274625 -310.797245) (xy 399.323524 -310.781357) (xy 399.374306 -310.773314) (xy 399.425722 -310.773314)
			(xy 399.476504 -310.781357) (xy 399.525403 -310.797245) (xy 399.571215 -310.820588) (xy 399.612811 -310.850809)
			(xy 399.649167 -310.887165) (xy 399.679388 -310.928761) (xy 399.702731 -310.974573) (xy 399.718619 -311.023472)
			(xy 399.726662 -311.074254) (xy 399.727166 -311.099962) (xy 400.04417 -311.099962) (xy 400.04813 -311.050908)
			(xy 400.059907 -311.003124) (xy 400.079198 -310.957848) (xy 400.105501 -310.916252) (xy 400.138136 -310.879415)
			(xy 400.176257 -310.84829) (xy 400.218878 -310.823683) (xy 400.264894 -310.806231) (xy 400.313113 -310.796387)
			(xy 400.362288 -310.794406) (xy 400.411143 -310.800338) (xy 400.458414 -310.81403) (xy 400.502876 -310.835128)
			(xy 400.543379 -310.863084) (xy 400.578872 -310.897176) (xy 400.608437 -310.93652) (xy 400.631308 -310.980097)
			(xy 400.646892 -311.026778) (xy 400.654787 -311.075355) (xy 400.655282 -311.099962) (xy 400.654787 -311.124569)
			(xy 400.654608 -311.12567) (xy 400.973286 -311.12567) (xy 400.973286 -311.074254) (xy 400.981329 -311.023472)
			(xy 400.997217 -310.974573) (xy 401.02056 -310.928761) (xy 401.050781 -310.887165) (xy 401.087137 -310.850809)
			(xy 401.128733 -310.820588) (xy 401.174545 -310.797245) (xy 401.223444 -310.781357) (xy 401.274226 -310.773314)
			(xy 401.325642 -310.773314) (xy 401.376424 -310.781357) (xy 401.425323 -310.797245) (xy 401.471135 -310.820588)
			(xy 401.512731 -310.850809) (xy 401.549087 -310.887165) (xy 401.579308 -310.928761) (xy 401.602651 -310.974573)
			(xy 401.618539 -311.023472) (xy 401.626582 -311.074254) (xy 401.627086 -311.099962) (xy 401.94409 -311.099962)
			(xy 401.94805 -311.050908) (xy 401.959827 -311.003124) (xy 401.979118 -310.957848) (xy 402.005421 -310.916252)
			(xy 402.038056 -310.879415) (xy 402.076177 -310.84829) (xy 402.118798 -310.823683) (xy 402.164814 -310.806231)
			(xy 402.213033 -310.796387) (xy 402.262208 -310.794406) (xy 402.311063 -310.800338) (xy 402.358334 -310.81403)
			(xy 402.402796 -310.835128) (xy 402.443299 -310.863084) (xy 402.478792 -310.897176) (xy 402.508357 -310.93652)
			(xy 402.531228 -310.980097) (xy 402.546812 -311.026778) (xy 402.554707 -311.075355) (xy 402.555202 -311.099962)
			(xy 402.554707 -311.124569) (xy 402.554528 -311.12567) (xy 402.873206 -311.12567) (xy 402.873206 -311.074254)
			(xy 402.881249 -311.023472) (xy 402.897137 -310.974573) (xy 402.92048 -310.928761) (xy 402.950701 -310.887165)
			(xy 402.987057 -310.850809) (xy 403.028653 -310.820588) (xy 403.074465 -310.797245) (xy 403.123364 -310.781357)
			(xy 403.174146 -310.773314) (xy 403.225562 -310.773314) (xy 403.276344 -310.781357) (xy 403.325243 -310.797245)
			(xy 403.371055 -310.820588) (xy 403.412651 -310.850809) (xy 403.449007 -310.887165) (xy 403.479228 -310.928761)
			(xy 403.502571 -310.974573) (xy 403.518459 -311.023472) (xy 403.526502 -311.074254) (xy 403.527006 -311.099962)
			(xy 403.84401 -311.099962) (xy 403.84797 -311.050908) (xy 403.859747 -311.003124) (xy 403.879038 -310.957848)
			(xy 403.905341 -310.916252) (xy 403.937976 -310.879415) (xy 403.976097 -310.84829) (xy 404.018718 -310.823683)
			(xy 404.064734 -310.806231) (xy 404.112953 -310.796387) (xy 404.162128 -310.794406) (xy 404.210983 -310.800338)
			(xy 404.258254 -310.81403) (xy 404.302716 -310.835128) (xy 404.343219 -310.863084) (xy 404.378712 -310.897176)
			(xy 404.408277 -310.93652) (xy 404.431148 -310.980097) (xy 404.446732 -311.026778) (xy 404.454627 -311.075355)
			(xy 404.455122 -311.099962) (xy 404.454627 -311.124569) (xy 404.454448 -311.12567) (xy 404.77338 -311.12567)
			(xy 404.77338 -311.074254) (xy 404.781423 -311.023472) (xy 404.797311 -310.974573) (xy 404.820654 -310.928761)
			(xy 404.850875 -310.887165) (xy 404.887231 -310.850809) (xy 404.928827 -310.820588) (xy 404.974639 -310.797245)
			(xy 405.023538 -310.781357) (xy 405.07432 -310.773314) (xy 405.125736 -310.773314) (xy 405.176518 -310.781357)
			(xy 405.225417 -310.797245) (xy 405.271229 -310.820588) (xy 405.312825 -310.850809) (xy 405.349181 -310.887165)
			(xy 405.379402 -310.928761) (xy 405.402745 -310.974573) (xy 405.418633 -311.023472) (xy 405.426676 -311.074254)
			(xy 405.42718 -311.099962) (xy 405.744184 -311.099962) (xy 405.748144 -311.050908) (xy 405.759921 -311.003124)
			(xy 405.779212 -310.957848) (xy 405.805515 -310.916252) (xy 405.83815 -310.879415) (xy 405.876271 -310.84829)
			(xy 405.918892 -310.823683) (xy 405.964908 -310.806231) (xy 406.013127 -310.796387) (xy 406.062302 -310.794406)
			(xy 406.111157 -310.800338) (xy 406.158428 -310.81403) (xy 406.20289 -310.835128) (xy 406.243393 -310.863084)
			(xy 406.278886 -310.897176) (xy 406.308451 -310.93652) (xy 406.331322 -310.980097) (xy 406.346906 -311.026778)
			(xy 406.354801 -311.075355) (xy 406.355296 -311.099962) (xy 406.354801 -311.124569) (xy 406.354622 -311.12567)
			(xy 406.6733 -311.12567) (xy 406.6733 -311.074254) (xy 406.681343 -311.023472) (xy 406.697231 -310.974573)
			(xy 406.720574 -310.928761) (xy 406.750795 -310.887165) (xy 406.787151 -310.850809) (xy 406.828747 -310.820588)
			(xy 406.874559 -310.797245) (xy 406.923458 -310.781357) (xy 406.97424 -310.773314) (xy 407.025656 -310.773314)
			(xy 407.076438 -310.781357) (xy 407.125337 -310.797245) (xy 407.171149 -310.820588) (xy 407.212745 -310.850809)
			(xy 407.249101 -310.887165) (xy 407.279322 -310.928761) (xy 407.302665 -310.974573) (xy 407.318553 -311.023472)
			(xy 407.326596 -311.074254) (xy 407.3271 -311.099962) (xy 407.644104 -311.099962) (xy 407.648064 -311.050908)
			(xy 407.659841 -311.003124) (xy 407.679132 -310.957848) (xy 407.705435 -310.916252) (xy 407.73807 -310.879415)
			(xy 407.776191 -310.84829) (xy 407.818812 -310.823683) (xy 407.864828 -310.806231) (xy 407.913047 -310.796387)
			(xy 407.962222 -310.794406) (xy 408.011077 -310.800338) (xy 408.058348 -310.81403) (xy 408.10281 -310.835128)
			(xy 408.143313 -310.863084) (xy 408.178806 -310.897176) (xy 408.208371 -310.93652) (xy 408.231242 -310.980097)
			(xy 408.246826 -311.026778) (xy 408.254721 -311.075355) (xy 408.255216 -311.099962) (xy 408.254721 -311.124569)
			(xy 408.254542 -311.12567) (xy 408.57322 -311.12567) (xy 408.57322 -311.074254) (xy 408.581263 -311.023472)
			(xy 408.597151 -310.974573) (xy 408.620494 -310.928761) (xy 408.650715 -310.887165) (xy 408.687071 -310.850809)
			(xy 408.728667 -310.820588) (xy 408.774479 -310.797245) (xy 408.823378 -310.781357) (xy 408.87416 -310.773314)
			(xy 408.925576 -310.773314) (xy 408.976358 -310.781357) (xy 409.025257 -310.797245) (xy 409.071069 -310.820588)
			(xy 409.112665 -310.850809) (xy 409.149021 -310.887165) (xy 409.179242 -310.928761) (xy 409.202585 -310.974573)
			(xy 409.218473 -311.023472) (xy 409.226516 -311.074254) (xy 409.22702 -311.099962) (xy 409.544024 -311.099962)
			(xy 409.547984 -311.050908) (xy 409.559761 -311.003124) (xy 409.579052 -310.957848) (xy 409.605355 -310.916252)
			(xy 409.63799 -310.879415) (xy 409.676111 -310.84829) (xy 409.718732 -310.823683) (xy 409.764748 -310.806231)
			(xy 409.812967 -310.796387) (xy 409.862142 -310.794406) (xy 409.910997 -310.800338) (xy 409.958268 -310.81403)
			(xy 410.00273 -310.835128) (xy 410.043233 -310.863084) (xy 410.078726 -310.897176) (xy 410.108291 -310.93652)
			(xy 410.131162 -310.980097) (xy 410.146746 -311.026778) (xy 410.154641 -311.075355) (xy 410.155136 -311.099962)
			(xy 410.154641 -311.124569) (xy 410.154462 -311.12567) (xy 410.47314 -311.12567) (xy 410.47314 -311.074254)
			(xy 410.481183 -311.023472) (xy 410.497071 -310.974573) (xy 410.520414 -310.928761) (xy 410.550635 -310.887165)
			(xy 410.586991 -310.850809) (xy 410.628587 -310.820588) (xy 410.674399 -310.797245) (xy 410.723298 -310.781357)
			(xy 410.77408 -310.773314) (xy 410.825496 -310.773314) (xy 410.876278 -310.781357) (xy 410.925177 -310.797245)
			(xy 410.970989 -310.820588) (xy 411.012585 -310.850809) (xy 411.048941 -310.887165) (xy 411.079162 -310.928761)
			(xy 411.102505 -310.974573) (xy 411.118393 -311.023472) (xy 411.126436 -311.074254) (xy 411.12694 -311.099962)
			(xy 411.444198 -311.099962) (xy 411.448158 -311.050908) (xy 411.459935 -311.003124) (xy 411.479226 -310.957848)
			(xy 411.505529 -310.916252) (xy 411.538164 -310.879415) (xy 411.576285 -310.84829) (xy 411.618906 -310.823683)
			(xy 411.664922 -310.806231) (xy 411.713141 -310.796387) (xy 411.762316 -310.794406) (xy 411.811171 -310.800338)
			(xy 411.858442 -310.81403) (xy 411.902904 -310.835128) (xy 411.943407 -310.863084) (xy 411.9789 -310.897176)
			(xy 412.008465 -310.93652) (xy 412.031336 -310.980097) (xy 412.04692 -311.026778) (xy 412.054815 -311.075355)
			(xy 412.05531 -311.099962) (xy 412.054815 -311.124569) (xy 412.054636 -311.12567) (xy 412.373314 -311.12567)
			(xy 412.373314 -311.074254) (xy 412.381357 -311.023472) (xy 412.397245 -310.974573) (xy 412.420588 -310.928761)
			(xy 412.450809 -310.887165) (xy 412.487165 -310.850809) (xy 412.528761 -310.820588) (xy 412.574573 -310.797245)
			(xy 412.623472 -310.781357) (xy 412.674254 -310.773314) (xy 412.72567 -310.773314) (xy 412.776452 -310.781357)
			(xy 412.825351 -310.797245) (xy 412.871163 -310.820588) (xy 412.912759 -310.850809) (xy 412.949115 -310.887165)
			(xy 412.979336 -310.928761) (xy 413.002679 -310.974573) (xy 413.018567 -311.023472) (xy 413.02661 -311.074254)
			(xy 413.027114 -311.099962) (xy 413.344118 -311.099962) (xy 413.348078 -311.050908) (xy 413.359855 -311.003124)
			(xy 413.379146 -310.957848) (xy 413.405449 -310.916252) (xy 413.438084 -310.879415) (xy 413.476205 -310.84829)
			(xy 413.518826 -310.823683) (xy 413.564842 -310.806231) (xy 413.613061 -310.796387) (xy 413.662236 -310.794406)
			(xy 413.711091 -310.800338) (xy 413.758362 -310.81403) (xy 413.802824 -310.835128) (xy 413.843327 -310.863084)
			(xy 413.87882 -310.897176) (xy 413.908385 -310.93652) (xy 413.931256 -310.980097) (xy 413.94684 -311.026778)
			(xy 413.954735 -311.075355) (xy 413.95523 -311.099962) (xy 414.294078 -311.099962) (xy 414.298038 -311.050908)
			(xy 414.309815 -311.003124) (xy 414.329106 -310.957848) (xy 414.355409 -310.916252) (xy 414.388044 -310.879415)
			(xy 414.426165 -310.84829) (xy 414.468786 -310.823683) (xy 414.514802 -310.806231) (xy 414.563021 -310.796387)
			(xy 414.612196 -310.794406) (xy 414.661051 -310.800338) (xy 414.708322 -310.81403) (xy 414.752784 -310.835128)
			(xy 414.793287 -310.863084) (xy 414.82878 -310.897176) (xy 414.858345 -310.93652) (xy 414.881216 -310.980097)
			(xy 414.8968 -311.026778) (xy 414.904695 -311.075355) (xy 414.90519 -311.099962) (xy 415.244038 -311.099962)
			(xy 415.247998 -311.050908) (xy 415.259775 -311.003124) (xy 415.279066 -310.957848) (xy 415.305369 -310.916252)
			(xy 415.338004 -310.879415) (xy 415.376125 -310.84829) (xy 415.418746 -310.823683) (xy 415.464762 -310.806231)
			(xy 415.512981 -310.796387) (xy 415.562156 -310.794406) (xy 415.611011 -310.800338) (xy 415.658282 -310.81403)
			(xy 415.702744 -310.835128) (xy 415.743247 -310.863084) (xy 415.77874 -310.897176) (xy 415.808305 -310.93652)
			(xy 415.831176 -310.980097) (xy 415.84676 -311.026778) (xy 415.854655 -311.075355) (xy 415.85515 -311.099962)
			(xy 416.193998 -311.099962) (xy 416.197958 -311.050908) (xy 416.209735 -311.003124) (xy 416.229026 -310.957848)
			(xy 416.255329 -310.916252) (xy 416.287964 -310.879415) (xy 416.326085 -310.84829) (xy 416.368706 -310.823683)
			(xy 416.414722 -310.806231) (xy 416.462941 -310.796387) (xy 416.512116 -310.794406) (xy 416.560971 -310.800338)
			(xy 416.608242 -310.81403) (xy 416.652704 -310.835128) (xy 416.693207 -310.863084) (xy 416.7287 -310.897176)
			(xy 416.758265 -310.93652) (xy 416.781136 -310.980097) (xy 416.79672 -311.026778) (xy 416.804615 -311.075355)
			(xy 416.80511 -311.099962) (xy 417.144212 -311.099962) (xy 417.148172 -311.050908) (xy 417.159949 -311.003124)
			(xy 417.17924 -310.957848) (xy 417.205543 -310.916252) (xy 417.238178 -310.879415) (xy 417.276299 -310.84829)
			(xy 417.31892 -310.823683) (xy 417.364936 -310.806231) (xy 417.413155 -310.796387) (xy 417.46233 -310.794406)
			(xy 417.511185 -310.800338) (xy 417.558456 -310.81403) (xy 417.602918 -310.835128) (xy 417.643421 -310.863084)
			(xy 417.678914 -310.897176) (xy 417.708479 -310.93652) (xy 417.73135 -310.980097) (xy 417.746934 -311.026778)
			(xy 417.754829 -311.075355) (xy 417.755324 -311.099962) (xy 418.094172 -311.099962) (xy 418.098132 -311.050908)
			(xy 418.109909 -311.003124) (xy 418.1292 -310.957848) (xy 418.155503 -310.916252) (xy 418.188138 -310.879415)
			(xy 418.226259 -310.84829) (xy 418.26888 -310.823683) (xy 418.314896 -310.806231) (xy 418.363115 -310.796387)
			(xy 418.41229 -310.794406) (xy 418.461145 -310.800338) (xy 418.508416 -310.81403) (xy 418.552878 -310.835128)
			(xy 418.593381 -310.863084) (xy 418.628874 -310.897176) (xy 418.658439 -310.93652) (xy 418.68131 -310.980097)
			(xy 418.696894 -311.026778) (xy 418.704789 -311.075355) (xy 418.705284 -311.099962) (xy 419.044132 -311.099962)
			(xy 419.048092 -311.050908) (xy 419.059869 -311.003124) (xy 419.07916 -310.957848) (xy 419.105463 -310.916252)
			(xy 419.138098 -310.879415) (xy 419.176219 -310.84829) (xy 419.21884 -310.823683) (xy 419.264856 -310.806231)
			(xy 419.313075 -310.796387) (xy 419.36225 -310.794406) (xy 419.411105 -310.800338) (xy 419.458376 -310.81403)
			(xy 419.502838 -310.835128) (xy 419.543341 -310.863084) (xy 419.578834 -310.897176) (xy 419.608399 -310.93652)
			(xy 419.63127 -310.980097) (xy 419.646854 -311.026778) (xy 419.654749 -311.075355) (xy 419.655244 -311.099962)
			(xy 419.994092 -311.099962) (xy 419.998052 -311.050908) (xy 420.009829 -311.003124) (xy 420.02912 -310.957848)
			(xy 420.055423 -310.916252) (xy 420.088058 -310.879415) (xy 420.126179 -310.84829) (xy 420.1688 -310.823683)
			(xy 420.214816 -310.806231) (xy 420.263035 -310.796387) (xy 420.31221 -310.794406) (xy 420.361065 -310.800338)
			(xy 420.408336 -310.81403) (xy 420.452798 -310.835128) (xy 420.493301 -310.863084) (xy 420.528794 -310.897176)
			(xy 420.558359 -310.93652) (xy 420.58123 -310.980097) (xy 420.596814 -311.026778) (xy 420.604709 -311.075355)
			(xy 420.605204 -311.099962) (xy 420.944052 -311.099962) (xy 420.948012 -311.050908) (xy 420.959789 -311.003124)
			(xy 420.97908 -310.957848) (xy 421.005383 -310.916252) (xy 421.038018 -310.879415) (xy 421.076139 -310.84829)
			(xy 421.11876 -310.823683) (xy 421.164776 -310.806231) (xy 421.212995 -310.796387) (xy 421.26217 -310.794406)
			(xy 421.311025 -310.800338) (xy 421.358296 -310.81403) (xy 421.402758 -310.835128) (xy 421.443261 -310.863084)
			(xy 421.478754 -310.897176) (xy 421.508319 -310.93652) (xy 421.53119 -310.980097) (xy 421.546774 -311.026778)
			(xy 421.554669 -311.075355) (xy 421.555164 -311.099962) (xy 421.554669 -311.124569) (xy 421.55449 -311.12567)
			(xy 421.873168 -311.12567) (xy 421.873168 -311.074254) (xy 421.881211 -311.023472) (xy 421.897099 -310.974573)
			(xy 421.920442 -310.928761) (xy 421.950663 -310.887165) (xy 421.987019 -310.850809) (xy 422.028615 -310.820588)
			(xy 422.074427 -310.797245) (xy 422.123326 -310.781357) (xy 422.174108 -310.773314) (xy 422.225524 -310.773314)
			(xy 422.276306 -310.781357) (xy 422.325205 -310.797245) (xy 422.371017 -310.820588) (xy 422.412613 -310.850809)
			(xy 422.448969 -310.887165) (xy 422.47919 -310.928761) (xy 422.502533 -310.974573) (xy 422.518421 -311.023472)
			(xy 422.526464 -311.074254) (xy 422.526968 -311.099962) (xy 422.844226 -311.099962) (xy 422.848186 -311.050908)
			(xy 422.859963 -311.003124) (xy 422.879254 -310.957848) (xy 422.905557 -310.916252) (xy 422.938192 -310.879415)
			(xy 422.976313 -310.84829) (xy 423.018934 -310.823683) (xy 423.06495 -310.806231) (xy 423.113169 -310.796387)
			(xy 423.162344 -310.794406) (xy 423.211199 -310.800338) (xy 423.25847 -310.81403) (xy 423.302932 -310.835128)
			(xy 423.343435 -310.863084) (xy 423.378928 -310.897176) (xy 423.408493 -310.93652) (xy 423.431364 -310.980097)
			(xy 423.446948 -311.026778) (xy 423.454843 -311.075355) (xy 423.455338 -311.099962) (xy 423.454843 -311.124569)
			(xy 423.446948 -311.173146) (xy 423.431364 -311.219827) (xy 423.408493 -311.263404) (xy 423.378928 -311.302748)
			(xy 423.343435 -311.33684) (xy 423.302932 -311.364796) (xy 423.25847 -311.385894) (xy 423.211199 -311.399586)
			(xy 423.162344 -311.405518) (xy 423.113169 -311.403537) (xy 423.06495 -311.393693) (xy 423.018934 -311.376241)
			(xy 422.976313 -311.351634) (xy 422.938192 -311.320509) (xy 422.905557 -311.283672) (xy 422.879254 -311.242076)
			(xy 422.859963 -311.1968) (xy 422.848186 -311.149016) (xy 422.844226 -311.099962) (xy 422.526968 -311.099962)
			(xy 422.526464 -311.12567) (xy 422.518421 -311.176452) (xy 422.502533 -311.225351) (xy 422.47919 -311.271163)
			(xy 422.448969 -311.312759) (xy 422.412613 -311.349115) (xy 422.371017 -311.379336) (xy 422.325205 -311.402679)
			(xy 422.276306 -311.418567) (xy 422.225524 -311.42661) (xy 422.174108 -311.42661) (xy 422.123326 -311.418567)
			(xy 422.074427 -311.402679) (xy 422.028615 -311.379336) (xy 421.987019 -311.349115) (xy 421.950663 -311.312759)
			(xy 421.920442 -311.271163) (xy 421.897099 -311.225351) (xy 421.881211 -311.176452) (xy 421.873168 -311.12567)
			(xy 421.55449 -311.12567) (xy 421.546774 -311.173146) (xy 421.53119 -311.219827) (xy 421.508319 -311.263404)
			(xy 421.478754 -311.302748) (xy 421.443261 -311.33684) (xy 421.402758 -311.364796) (xy 421.358296 -311.385894)
			(xy 421.311025 -311.399586) (xy 421.26217 -311.405518) (xy 421.212995 -311.403537) (xy 421.164776 -311.393693)
			(xy 421.11876 -311.376241) (xy 421.076139 -311.351634) (xy 421.038018 -311.320509) (xy 421.005383 -311.283672)
			(xy 420.97908 -311.242076) (xy 420.959789 -311.1968) (xy 420.948012 -311.149016) (xy 420.944052 -311.099962)
			(xy 420.605204 -311.099962) (xy 420.604709 -311.124569) (xy 420.596814 -311.173146) (xy 420.58123 -311.219827)
			(xy 420.558359 -311.263404) (xy 420.528794 -311.302748) (xy 420.493301 -311.33684) (xy 420.452798 -311.364796)
			(xy 420.408336 -311.385894) (xy 420.361065 -311.399586) (xy 420.31221 -311.405518) (xy 420.263035 -311.403537)
			(xy 420.214816 -311.393693) (xy 420.1688 -311.376241) (xy 420.126179 -311.351634) (xy 420.088058 -311.320509)
			(xy 420.055423 -311.283672) (xy 420.02912 -311.242076) (xy 420.009829 -311.1968) (xy 419.998052 -311.149016)
			(xy 419.994092 -311.099962) (xy 419.655244 -311.099962) (xy 419.654749 -311.124569) (xy 419.646854 -311.173146)
			(xy 419.63127 -311.219827) (xy 419.608399 -311.263404) (xy 419.578834 -311.302748) (xy 419.543341 -311.33684)
			(xy 419.502838 -311.364796) (xy 419.458376 -311.385894) (xy 419.411105 -311.399586) (xy 419.36225 -311.405518)
			(xy 419.313075 -311.403537) (xy 419.264856 -311.393693) (xy 419.21884 -311.376241) (xy 419.176219 -311.351634)
			(xy 419.138098 -311.320509) (xy 419.105463 -311.283672) (xy 419.07916 -311.242076) (xy 419.059869 -311.1968)
			(xy 419.048092 -311.149016) (xy 419.044132 -311.099962) (xy 418.705284 -311.099962) (xy 418.704789 -311.124569)
			(xy 418.696894 -311.173146) (xy 418.68131 -311.219827) (xy 418.658439 -311.263404) (xy 418.628874 -311.302748)
			(xy 418.593381 -311.33684) (xy 418.552878 -311.364796) (xy 418.508416 -311.385894) (xy 418.461145 -311.399586)
			(xy 418.41229 -311.405518) (xy 418.363115 -311.403537) (xy 418.314896 -311.393693) (xy 418.26888 -311.376241)
			(xy 418.226259 -311.351634) (xy 418.188138 -311.320509) (xy 418.155503 -311.283672) (xy 418.1292 -311.242076)
			(xy 418.109909 -311.1968) (xy 418.098132 -311.149016) (xy 418.094172 -311.099962) (xy 417.755324 -311.099962)
			(xy 417.754829 -311.124569) (xy 417.746934 -311.173146) (xy 417.73135 -311.219827) (xy 417.708479 -311.263404)
			(xy 417.678914 -311.302748) (xy 417.643421 -311.33684) (xy 417.602918 -311.364796) (xy 417.558456 -311.385894)
			(xy 417.511185 -311.399586) (xy 417.46233 -311.405518) (xy 417.413155 -311.403537) (xy 417.364936 -311.393693)
			(xy 417.31892 -311.376241) (xy 417.276299 -311.351634) (xy 417.238178 -311.320509) (xy 417.205543 -311.283672)
			(xy 417.17924 -311.242076) (xy 417.159949 -311.1968) (xy 417.148172 -311.149016) (xy 417.144212 -311.099962)
			(xy 416.80511 -311.099962) (xy 416.804615 -311.124569) (xy 416.79672 -311.173146) (xy 416.781136 -311.219827)
			(xy 416.758265 -311.263404) (xy 416.7287 -311.302748) (xy 416.693207 -311.33684) (xy 416.652704 -311.364796)
			(xy 416.608242 -311.385894) (xy 416.560971 -311.399586) (xy 416.512116 -311.405518) (xy 416.462941 -311.403537)
			(xy 416.414722 -311.393693) (xy 416.368706 -311.376241) (xy 416.326085 -311.351634) (xy 416.287964 -311.320509)
			(xy 416.255329 -311.283672) (xy 416.229026 -311.242076) (xy 416.209735 -311.1968) (xy 416.197958 -311.149016)
			(xy 416.193998 -311.099962) (xy 415.85515 -311.099962) (xy 415.854655 -311.124569) (xy 415.84676 -311.173146)
			(xy 415.831176 -311.219827) (xy 415.808305 -311.263404) (xy 415.77874 -311.302748) (xy 415.743247 -311.33684)
			(xy 415.702744 -311.364796) (xy 415.658282 -311.385894) (xy 415.611011 -311.399586) (xy 415.562156 -311.405518)
			(xy 415.512981 -311.403537) (xy 415.464762 -311.393693) (xy 415.418746 -311.376241) (xy 415.376125 -311.351634)
			(xy 415.338004 -311.320509) (xy 415.305369 -311.283672) (xy 415.279066 -311.242076) (xy 415.259775 -311.1968)
			(xy 415.247998 -311.149016) (xy 415.244038 -311.099962) (xy 414.90519 -311.099962) (xy 414.904695 -311.124569)
			(xy 414.8968 -311.173146) (xy 414.881216 -311.219827) (xy 414.858345 -311.263404) (xy 414.82878 -311.302748)
			(xy 414.793287 -311.33684) (xy 414.752784 -311.364796) (xy 414.708322 -311.385894) (xy 414.661051 -311.399586)
			(xy 414.612196 -311.405518) (xy 414.563021 -311.403537) (xy 414.514802 -311.393693) (xy 414.468786 -311.376241)
			(xy 414.426165 -311.351634) (xy 414.388044 -311.320509) (xy 414.355409 -311.283672) (xy 414.329106 -311.242076)
			(xy 414.309815 -311.1968) (xy 414.298038 -311.149016) (xy 414.294078 -311.099962) (xy 413.95523 -311.099962)
			(xy 413.954735 -311.124569) (xy 413.94684 -311.173146) (xy 413.931256 -311.219827) (xy 413.908385 -311.263404)
			(xy 413.87882 -311.302748) (xy 413.843327 -311.33684) (xy 413.802824 -311.364796) (xy 413.758362 -311.385894)
			(xy 413.711091 -311.399586) (xy 413.662236 -311.405518) (xy 413.613061 -311.403537) (xy 413.564842 -311.393693)
			(xy 413.518826 -311.376241) (xy 413.476205 -311.351634) (xy 413.438084 -311.320509) (xy 413.405449 -311.283672)
			(xy 413.379146 -311.242076) (xy 413.359855 -311.1968) (xy 413.348078 -311.149016) (xy 413.344118 -311.099962)
			(xy 413.027114 -311.099962) (xy 413.02661 -311.12567) (xy 413.018567 -311.176452) (xy 413.002679 -311.225351)
			(xy 412.979336 -311.271163) (xy 412.949115 -311.312759) (xy 412.912759 -311.349115) (xy 412.871163 -311.379336)
			(xy 412.825351 -311.402679) (xy 412.776452 -311.418567) (xy 412.72567 -311.42661) (xy 412.674254 -311.42661)
			(xy 412.623472 -311.418567) (xy 412.574573 -311.402679) (xy 412.528761 -311.379336) (xy 412.487165 -311.349115)
			(xy 412.450809 -311.312759) (xy 412.420588 -311.271163) (xy 412.397245 -311.225351) (xy 412.381357 -311.176452)
			(xy 412.373314 -311.12567) (xy 412.054636 -311.12567) (xy 412.04692 -311.173146) (xy 412.031336 -311.219827)
			(xy 412.008465 -311.263404) (xy 411.9789 -311.302748) (xy 411.943407 -311.33684) (xy 411.902904 -311.364796)
			(xy 411.858442 -311.385894) (xy 411.811171 -311.399586) (xy 411.762316 -311.405518) (xy 411.713141 -311.403537)
			(xy 411.664922 -311.393693) (xy 411.618906 -311.376241) (xy 411.576285 -311.351634) (xy 411.538164 -311.320509)
			(xy 411.505529 -311.283672) (xy 411.479226 -311.242076) (xy 411.459935 -311.1968) (xy 411.448158 -311.149016)
			(xy 411.444198 -311.099962) (xy 411.12694 -311.099962) (xy 411.126436 -311.12567) (xy 411.118393 -311.176452)
			(xy 411.102505 -311.225351) (xy 411.079162 -311.271163) (xy 411.048941 -311.312759) (xy 411.012585 -311.349115)
			(xy 410.970989 -311.379336) (xy 410.925177 -311.402679) (xy 410.876278 -311.418567) (xy 410.825496 -311.42661)
			(xy 410.77408 -311.42661) (xy 410.723298 -311.418567) (xy 410.674399 -311.402679) (xy 410.628587 -311.379336)
			(xy 410.586991 -311.349115) (xy 410.550635 -311.312759) (xy 410.520414 -311.271163) (xy 410.497071 -311.225351)
			(xy 410.481183 -311.176452) (xy 410.47314 -311.12567) (xy 410.154462 -311.12567) (xy 410.146746 -311.173146)
			(xy 410.131162 -311.219827) (xy 410.108291 -311.263404) (xy 410.078726 -311.302748) (xy 410.043233 -311.33684)
			(xy 410.00273 -311.364796) (xy 409.958268 -311.385894) (xy 409.910997 -311.399586) (xy 409.862142 -311.405518)
			(xy 409.812967 -311.403537) (xy 409.764748 -311.393693) (xy 409.718732 -311.376241) (xy 409.676111 -311.351634)
			(xy 409.63799 -311.320509) (xy 409.605355 -311.283672) (xy 409.579052 -311.242076) (xy 409.559761 -311.1968)
			(xy 409.547984 -311.149016) (xy 409.544024 -311.099962) (xy 409.22702 -311.099962) (xy 409.226516 -311.12567)
			(xy 409.218473 -311.176452) (xy 409.202585 -311.225351) (xy 409.179242 -311.271163) (xy 409.149021 -311.312759)
			(xy 409.112665 -311.349115) (xy 409.071069 -311.379336) (xy 409.025257 -311.402679) (xy 408.976358 -311.418567)
			(xy 408.925576 -311.42661) (xy 408.87416 -311.42661) (xy 408.823378 -311.418567) (xy 408.774479 -311.402679)
			(xy 408.728667 -311.379336) (xy 408.687071 -311.349115) (xy 408.650715 -311.312759) (xy 408.620494 -311.271163)
			(xy 408.597151 -311.225351) (xy 408.581263 -311.176452) (xy 408.57322 -311.12567) (xy 408.254542 -311.12567)
			(xy 408.246826 -311.173146) (xy 408.231242 -311.219827) (xy 408.208371 -311.263404) (xy 408.178806 -311.302748)
			(xy 408.143313 -311.33684) (xy 408.10281 -311.364796) (xy 408.058348 -311.385894) (xy 408.011077 -311.399586)
			(xy 407.962222 -311.405518) (xy 407.913047 -311.403537) (xy 407.864828 -311.393693) (xy 407.818812 -311.376241)
			(xy 407.776191 -311.351634) (xy 407.73807 -311.320509) (xy 407.705435 -311.283672) (xy 407.679132 -311.242076)
			(xy 407.659841 -311.1968) (xy 407.648064 -311.149016) (xy 407.644104 -311.099962) (xy 407.3271 -311.099962)
			(xy 407.326596 -311.12567) (xy 407.318553 -311.176452) (xy 407.302665 -311.225351) (xy 407.279322 -311.271163)
			(xy 407.249101 -311.312759) (xy 407.212745 -311.349115) (xy 407.171149 -311.379336) (xy 407.125337 -311.402679)
			(xy 407.076438 -311.418567) (xy 407.025656 -311.42661) (xy 406.97424 -311.42661) (xy 406.923458 -311.418567)
			(xy 406.874559 -311.402679) (xy 406.828747 -311.379336) (xy 406.787151 -311.349115) (xy 406.750795 -311.312759)
			(xy 406.720574 -311.271163) (xy 406.697231 -311.225351) (xy 406.681343 -311.176452) (xy 406.6733 -311.12567)
			(xy 406.354622 -311.12567) (xy 406.346906 -311.173146) (xy 406.331322 -311.219827) (xy 406.308451 -311.263404)
			(xy 406.278886 -311.302748) (xy 406.243393 -311.33684) (xy 406.20289 -311.364796) (xy 406.158428 -311.385894)
			(xy 406.111157 -311.399586) (xy 406.062302 -311.405518) (xy 406.013127 -311.403537) (xy 405.964908 -311.393693)
			(xy 405.918892 -311.376241) (xy 405.876271 -311.351634) (xy 405.83815 -311.320509) (xy 405.805515 -311.283672)
			(xy 405.779212 -311.242076) (xy 405.759921 -311.1968) (xy 405.748144 -311.149016) (xy 405.744184 -311.099962)
			(xy 405.42718 -311.099962) (xy 405.426676 -311.12567) (xy 405.418633 -311.176452) (xy 405.402745 -311.225351)
			(xy 405.379402 -311.271163) (xy 405.349181 -311.312759) (xy 405.312825 -311.349115) (xy 405.271229 -311.379336)
			(xy 405.225417 -311.402679) (xy 405.176518 -311.418567) (xy 405.125736 -311.42661) (xy 405.07432 -311.42661)
			(xy 405.023538 -311.418567) (xy 404.974639 -311.402679) (xy 404.928827 -311.379336) (xy 404.887231 -311.349115)
			(xy 404.850875 -311.312759) (xy 404.820654 -311.271163) (xy 404.797311 -311.225351) (xy 404.781423 -311.176452)
			(xy 404.77338 -311.12567) (xy 404.454448 -311.12567) (xy 404.446732 -311.173146) (xy 404.431148 -311.219827)
			(xy 404.408277 -311.263404) (xy 404.378712 -311.302748) (xy 404.343219 -311.33684) (xy 404.302716 -311.364796)
			(xy 404.258254 -311.385894) (xy 404.210983 -311.399586) (xy 404.162128 -311.405518) (xy 404.112953 -311.403537)
			(xy 404.064734 -311.393693) (xy 404.018718 -311.376241) (xy 403.976097 -311.351634) (xy 403.937976 -311.320509)
			(xy 403.905341 -311.283672) (xy 403.879038 -311.242076) (xy 403.859747 -311.1968) (xy 403.84797 -311.149016)
			(xy 403.84401 -311.099962) (xy 403.527006 -311.099962) (xy 403.526502 -311.12567) (xy 403.518459 -311.176452)
			(xy 403.502571 -311.225351) (xy 403.479228 -311.271163) (xy 403.449007 -311.312759) (xy 403.412651 -311.349115)
			(xy 403.371055 -311.379336) (xy 403.325243 -311.402679) (xy 403.276344 -311.418567) (xy 403.225562 -311.42661)
			(xy 403.174146 -311.42661) (xy 403.123364 -311.418567) (xy 403.074465 -311.402679) (xy 403.028653 -311.379336)
			(xy 402.987057 -311.349115) (xy 402.950701 -311.312759) (xy 402.92048 -311.271163) (xy 402.897137 -311.225351)
			(xy 402.881249 -311.176452) (xy 402.873206 -311.12567) (xy 402.554528 -311.12567) (xy 402.546812 -311.173146)
			(xy 402.531228 -311.219827) (xy 402.508357 -311.263404) (xy 402.478792 -311.302748) (xy 402.443299 -311.33684)
			(xy 402.402796 -311.364796) (xy 402.358334 -311.385894) (xy 402.311063 -311.399586) (xy 402.262208 -311.405518)
			(xy 402.213033 -311.403537) (xy 402.164814 -311.393693) (xy 402.118798 -311.376241) (xy 402.076177 -311.351634)
			(xy 402.038056 -311.320509) (xy 402.005421 -311.283672) (xy 401.979118 -311.242076) (xy 401.959827 -311.1968)
			(xy 401.94805 -311.149016) (xy 401.94409 -311.099962) (xy 401.627086 -311.099962) (xy 401.626582 -311.12567)
			(xy 401.618539 -311.176452) (xy 401.602651 -311.225351) (xy 401.579308 -311.271163) (xy 401.549087 -311.312759)
			(xy 401.512731 -311.349115) (xy 401.471135 -311.379336) (xy 401.425323 -311.402679) (xy 401.376424 -311.418567)
			(xy 401.325642 -311.42661) (xy 401.274226 -311.42661) (xy 401.223444 -311.418567) (xy 401.174545 -311.402679)
			(xy 401.128733 -311.379336) (xy 401.087137 -311.349115) (xy 401.050781 -311.312759) (xy 401.02056 -311.271163)
			(xy 400.997217 -311.225351) (xy 400.981329 -311.176452) (xy 400.973286 -311.12567) (xy 400.654608 -311.12567)
			(xy 400.646892 -311.173146) (xy 400.631308 -311.219827) (xy 400.608437 -311.263404) (xy 400.578872 -311.302748)
			(xy 400.543379 -311.33684) (xy 400.502876 -311.364796) (xy 400.458414 -311.385894) (xy 400.411143 -311.399586)
			(xy 400.362288 -311.405518) (xy 400.313113 -311.403537) (xy 400.264894 -311.393693) (xy 400.218878 -311.376241)
			(xy 400.176257 -311.351634) (xy 400.138136 -311.320509) (xy 400.105501 -311.283672) (xy 400.079198 -311.242076)
			(xy 400.059907 -311.1968) (xy 400.04813 -311.149016) (xy 400.04417 -311.099962) (xy 399.727166 -311.099962)
			(xy 399.726662 -311.12567) (xy 399.718619 -311.176452) (xy 399.702731 -311.225351) (xy 399.679388 -311.271163)
			(xy 399.649167 -311.312759) (xy 399.612811 -311.349115) (xy 399.571215 -311.379336) (xy 399.525403 -311.402679)
			(xy 399.476504 -311.418567) (xy 399.425722 -311.42661) (xy 399.374306 -311.42661) (xy 399.323524 -311.418567)
			(xy 399.274625 -311.402679) (xy 399.228813 -311.379336) (xy 399.187217 -311.349115) (xy 399.150861 -311.312759)
			(xy 399.12064 -311.271163) (xy 399.097297 -311.225351) (xy 399.081409 -311.176452) (xy 399.073366 -311.12567)
			(xy 398.754434 -311.12567) (xy 398.746718 -311.173146) (xy 398.731134 -311.219827) (xy 398.708263 -311.263404)
			(xy 398.678698 -311.302748) (xy 398.643205 -311.33684) (xy 398.602702 -311.364796) (xy 398.55824 -311.385894)
			(xy 398.510969 -311.399586) (xy 398.462114 -311.405518) (xy 398.412939 -311.403537) (xy 398.36472 -311.393693)
			(xy 398.318704 -311.376241) (xy 398.276083 -311.351634) (xy 398.237962 -311.320509) (xy 398.205327 -311.283672)
			(xy 398.179024 -311.242076) (xy 398.159733 -311.1968) (xy 398.147956 -311.149016) (xy 398.143996 -311.099962)
			(xy 397.805148 -311.099962) (xy 397.804653 -311.124569) (xy 397.796758 -311.173146) (xy 397.781174 -311.219827)
			(xy 397.758303 -311.263404) (xy 397.728738 -311.302748) (xy 397.693245 -311.33684) (xy 397.652742 -311.364796)
			(xy 397.60828 -311.385894) (xy 397.561009 -311.399586) (xy 397.512154 -311.405518) (xy 397.462979 -311.403537)
			(xy 397.41476 -311.393693) (xy 397.368744 -311.376241) (xy 397.326123 -311.351634) (xy 397.288002 -311.320509)
			(xy 397.255367 -311.283672) (xy 397.229064 -311.242076) (xy 397.209773 -311.1968) (xy 397.197996 -311.149016)
			(xy 397.194036 -311.099962) (xy 396.855188 -311.099962) (xy 396.854693 -311.124569) (xy 396.846798 -311.173146)
			(xy 396.831214 -311.219827) (xy 396.808343 -311.263404) (xy 396.778778 -311.302748) (xy 396.743285 -311.33684)
			(xy 396.702782 -311.364796) (xy 396.65832 -311.385894) (xy 396.611049 -311.399586) (xy 396.562194 -311.405518)
			(xy 396.513019 -311.403537) (xy 396.4648 -311.393693) (xy 396.418784 -311.376241) (xy 396.376163 -311.351634)
			(xy 396.338042 -311.320509) (xy 396.305407 -311.283672) (xy 396.279104 -311.242076) (xy 396.259813 -311.1968)
			(xy 396.248036 -311.149016) (xy 396.244076 -311.099962) (xy 395.905228 -311.099962) (xy 395.904733 -311.124569)
			(xy 395.896838 -311.173146) (xy 395.881254 -311.219827) (xy 395.858383 -311.263404) (xy 395.828818 -311.302748)
			(xy 395.793325 -311.33684) (xy 395.752822 -311.364796) (xy 395.70836 -311.385894) (xy 395.661089 -311.399586)
			(xy 395.612234 -311.405518) (xy 395.563059 -311.403537) (xy 395.51484 -311.393693) (xy 395.468824 -311.376241)
			(xy 395.426203 -311.351634) (xy 395.388082 -311.320509) (xy 395.355447 -311.283672) (xy 395.329144 -311.242076)
			(xy 395.309853 -311.1968) (xy 395.298076 -311.149016) (xy 395.294116 -311.099962) (xy 394.955268 -311.099962)
			(xy 394.954773 -311.124569) (xy 394.946878 -311.173146) (xy 394.931294 -311.219827) (xy 394.908423 -311.263404)
			(xy 394.878858 -311.302748) (xy 394.843365 -311.33684) (xy 394.802862 -311.364796) (xy 394.7584 -311.385894)
			(xy 394.711129 -311.399586) (xy 394.662274 -311.405518) (xy 394.613099 -311.403537) (xy 394.56488 -311.393693)
			(xy 394.518864 -311.376241) (xy 394.476243 -311.351634) (xy 394.438122 -311.320509) (xy 394.405487 -311.283672)
			(xy 394.379184 -311.242076) (xy 394.359893 -311.1968) (xy 394.348116 -311.149016) (xy 394.344156 -311.099962)
			(xy 394.005308 -311.099962) (xy 394.004813 -311.124569) (xy 393.996918 -311.173146) (xy 393.981334 -311.219827)
			(xy 393.958463 -311.263404) (xy 393.928898 -311.302748) (xy 393.893405 -311.33684) (xy 393.852902 -311.364796)
			(xy 393.80844 -311.385894) (xy 393.761169 -311.399586) (xy 393.712314 -311.405518) (xy 393.663139 -311.403537)
			(xy 393.61492 -311.393693) (xy 393.568904 -311.376241) (xy 393.526283 -311.351634) (xy 393.488162 -311.320509)
			(xy 393.455527 -311.283672) (xy 393.429224 -311.242076) (xy 393.409933 -311.1968) (xy 393.398156 -311.149016)
			(xy 393.394196 -311.099962) (xy 393.055094 -311.099962) (xy 393.054599 -311.124569) (xy 393.046704 -311.173146)
			(xy 393.03112 -311.219827) (xy 393.008249 -311.263404) (xy 392.978684 -311.302748) (xy 392.943191 -311.33684)
			(xy 392.902688 -311.364796) (xy 392.858226 -311.385894) (xy 392.810955 -311.399586) (xy 392.7621 -311.405518)
			(xy 392.712925 -311.403537) (xy 392.664706 -311.393693) (xy 392.61869 -311.376241) (xy 392.576069 -311.351634)
			(xy 392.537948 -311.320509) (xy 392.505313 -311.283672) (xy 392.47901 -311.242076) (xy 392.459719 -311.1968)
			(xy 392.447942 -311.149016) (xy 392.443982 -311.099962) (xy 392.105134 -311.099962) (xy 392.104639 -311.124569)
			(xy 392.096744 -311.173146) (xy 392.08116 -311.219827) (xy 392.058289 -311.263404) (xy 392.028724 -311.302748)
			(xy 391.993231 -311.33684) (xy 391.952728 -311.364796) (xy 391.908266 -311.385894) (xy 391.860995 -311.399586)
			(xy 391.81214 -311.405518) (xy 391.762965 -311.403537) (xy 391.714746 -311.393693) (xy 391.66873 -311.376241)
			(xy 391.626109 -311.351634) (xy 391.587988 -311.320509) (xy 391.555353 -311.283672) (xy 391.52905 -311.242076)
			(xy 391.509759 -311.1968) (xy 391.497982 -311.149016) (xy 391.494022 -311.099962) (xy 391.155174 -311.099962)
			(xy 391.154679 -311.124569) (xy 391.146784 -311.173146) (xy 391.1312 -311.219827) (xy 391.108329 -311.263404)
			(xy 391.078764 -311.302748) (xy 391.043271 -311.33684) (xy 391.002768 -311.364796) (xy 390.958306 -311.385894)
			(xy 390.911035 -311.399586) (xy 390.86218 -311.405518) (xy 390.813005 -311.403537) (xy 390.764786 -311.393693)
			(xy 390.71877 -311.376241) (xy 390.676149 -311.351634) (xy 390.638028 -311.320509) (xy 390.605393 -311.283672)
			(xy 390.57909 -311.242076) (xy 390.559799 -311.1968) (xy 390.548022 -311.149016) (xy 390.544062 -311.099962)
			(xy 390.205214 -311.099962) (xy 390.204719 -311.124569) (xy 390.196824 -311.173146) (xy 390.18124 -311.219827)
			(xy 390.158369 -311.263404) (xy 390.128804 -311.302748) (xy 390.093311 -311.33684) (xy 390.052808 -311.364796)
			(xy 390.008346 -311.385894) (xy 389.961075 -311.399586) (xy 389.91222 -311.405518) (xy 389.863045 -311.403537)
			(xy 389.814826 -311.393693) (xy 389.76881 -311.376241) (xy 389.726189 -311.351634) (xy 389.688068 -311.320509)
			(xy 389.655433 -311.283672) (xy 389.62913 -311.242076) (xy 389.609839 -311.1968) (xy 389.598062 -311.149016)
			(xy 389.594102 -311.099962) (xy 389.255254 -311.099962) (xy 389.255254 -311.100724) (xy 389.255 -311.108344)
			(xy 389.255 -311.205118) (xy 389.25546 -311.214995) (xy 389.262903 -311.233294) (xy 389.269478 -311.240678)
			(xy 389.269732 -311.240932) (xy 389.646414 -311.617614) (xy 389.646922 -311.618122) (xy 389.6543 -311.624712)
			(xy 389.672599 -311.632179) (xy 389.682482 -311.6326)
		)
		(stroke
			(width 0)
			(type solid)
		)
		(fill yes)
		(layer "In9.Cu")
		(net "P1V8_VDDA_PEX3")
	)
	(gr_poly
		(pts
			(xy 403.146006 -282.273502) (xy 403.159373 -282.271455) (xy 403.186331 -282.269297) (xy 403.199854 -282.269184)
			(xy 403.213376 -282.269302) (xy 403.240334 -282.271464) (xy 403.253702 -282.273502) (xy 403.257766 -282.274264)
			(xy 406.638252 -282.274264) (xy 406.643078 -282.27401) (xy 406.643332 -282.27401) (xy 406.650058 -282.273051)
			(xy 406.662674 -282.268023) (xy 406.668224 -282.264104) (xy 406.673558 -282.259532) (xy 406.932892 -282.000198)
			(xy 406.937464 -281.995626) (xy 407.362152 -281.570938) (xy 407.369772 -281.562421) (xy 407.377318 -281.540885)
			(xy 407.374785 -281.518205) (xy 407.369264 -281.5082) (xy 407.357072 -281.490674) (xy 407.350468 -281.483562)
			(xy 407.345896 -281.479752) (xy 407.33853 -281.476196) (xy 407.314075 -281.46452) (xy 407.269021 -281.434411)
			(xy 407.229475 -281.397365) (xy 407.196494 -281.354369) (xy 407.170959 -281.306575) (xy 407.153552 -281.255259)
			(xy 407.14474 -281.201792) (xy 407.14422 -281.174698) (xy 407.144438 -281.159814) (xy 407.147234 -281.130177)
			(xy 407.149808 -281.115516) (xy 407.149808 -281.113992) (xy 407.150824 -281.10815) (xy 407.143712 -281.085544)
			(xy 407.079196 -281.01798) (xy 407.070558 -281.009908) (xy 407.04832 -281.001959) (xy 407.036524 -281.00274)
			(xy 407.03627 -281.00274) (xy 407.027226 -281.00379) (xy 407.009052 -281.004936) (xy 406.999948 -281.005026)
			(xy 406.974686 -281.004537) (xy 406.924851 -280.996228) (xy 406.877063 -280.979829) (xy 406.832626 -280.955787)
			(xy 406.792753 -280.924759) (xy 406.758532 -280.88759) (xy 406.730896 -280.845295) (xy 406.710599 -280.799028)
			(xy 406.698195 -280.750051) (xy 406.694022 -280.6997) (xy 406.698195 -280.649349) (xy 406.710599 -280.600372)
			(xy 406.730896 -280.554105) (xy 406.758532 -280.51181) (xy 406.792753 -280.474641) (xy 406.832626 -280.443613)
			(xy 406.877063 -280.419571) (xy 406.924851 -280.403172) (xy 406.974686 -280.394863) (xy 406.999948 -280.39441)
			(xy 407.009052 -280.394508) (xy 407.027225 -280.395652) (xy 407.03627 -280.396696) (xy 407.036524 -280.396696)
			(xy 407.048331 -280.397522) (xy 407.070599 -280.389588) (xy 407.079196 -280.381456) (xy 407.143712 -280.313892)
			(xy 407.150824 -280.291286) (xy 407.149808 -280.284682) (xy 407.147225 -280.26983) (xy 407.144427 -280.239812)
			(xy 407.14422 -280.224738) (xy 407.14422 -280.224484) (xy 407.144385 -280.210056) (xy 407.146933 -280.181313)
			(xy 407.1493 -280.16708) (xy 407.1493 -280.166572) (xy 407.150824 -280.15819) (xy 407.143712 -280.135584)
			(xy 407.071068 -280.05913) (xy 407.048208 -280.051002) (xy 407.036524 -280.052526) (xy 407.027416 -280.053581)
			(xy 407.009116 -280.054726) (xy 406.999948 -280.054812) (xy 406.974687 -280.054323) (xy 406.924854 -280.046015)
			(xy 406.877068 -280.029616) (xy 406.832634 -280.005576) (xy 406.792763 -279.974549) (xy 406.758543 -279.937382)
			(xy 406.730908 -279.895089) (xy 406.710612 -279.848823) (xy 406.698208 -279.799849) (xy 406.694036 -279.7495)
			(xy 406.698208 -279.699151) (xy 406.710612 -279.650177) (xy 406.730908 -279.603911) (xy 406.758543 -279.561618)
			(xy 406.792763 -279.524451) (xy 406.832634 -279.493424) (xy 406.877068 -279.469384) (xy 406.924854 -279.452985)
			(xy 406.974687 -279.444677) (xy 406.999948 -279.444196) (xy 407.017982 -279.444704) (xy 407.031952 -279.445466)
			(xy 407.05659 -279.432512) (xy 407.110946 -279.34412) (xy 407.115461 -279.336092) (xy 407.118976 -279.318028)
			(xy 407.115836 -279.299895) (xy 407.111454 -279.291796) (xy 407.094436 -279.261316) (xy 407.091121 -279.255663)
			(xy 407.082112 -279.246152) (xy 407.076656 -279.24252) (xy 407.037777 -279.217374) (xy 406.964499 -279.160761)
			(xy 406.930352 -279.12949) (xy 406.925806 -279.12552) (xy 406.915281 -279.119618) (xy 406.909524 -279.117806)
			(xy 406.886539 -279.110819) (xy 406.842722 -279.091124) (xy 406.802217 -279.065296) (xy 406.765876 -279.033877)
			(xy 406.734464 -278.99753) (xy 406.708644 -278.957019) (xy 406.688958 -278.913198) (xy 406.68194 -278.890222)
			(xy 406.680151 -278.884455) (xy 406.674246 -278.873926) (xy 406.670256 -278.869394) (xy 406.639377 -278.835672)
			(xy 406.583398 -278.763367) (xy 406.534459 -278.686122) (xy 406.492995 -278.604621) (xy 406.459371 -278.519585)
			(xy 406.433884 -278.431766) (xy 406.416761 -278.341941) (xy 406.408153 -278.250905) (xy 406.40762 -278.205184)
			(xy 406.40762 -278.165814) (xy 406.40723 -278.156254) (xy 406.40022 -278.138469) (xy 406.387144 -278.124522)
			(xy 406.378664 -278.120094) (xy 406.282652 -278.07412) (xy 406.253696 -278.077676) (xy 406.242266 -278.087074)
			(xy 406.221718 -278.103036) (xy 406.176323 -278.128454) (xy 406.127278 -278.145818) (xy 406.076002 -278.154626)
			(xy 406.049988 -278.155146) (xy 406.02473 -278.154623) (xy 405.974904 -278.146307) (xy 405.927126 -278.129903)
			(xy 405.882699 -278.105859) (xy 405.842836 -278.074831) (xy 405.808623 -278.037665) (xy 405.780994 -277.995374)
			(xy 405.760703 -277.949113) (xy 405.748302 -277.900143) (xy 405.744131 -277.8498) (xy 405.748302 -277.799457)
			(xy 405.760703 -277.750487) (xy 405.780994 -277.704226) (xy 405.808623 -277.661935) (xy 405.842836 -277.624769)
			(xy 405.882699 -277.593741) (xy 405.927126 -277.569697) (xy 405.974904 -277.553293) (xy 406.02473 -277.544977)
			(xy 406.049988 -277.54453) (xy 406.076002 -277.545052) (xy 406.127281 -277.553857) (xy 406.176328 -277.571215)
			(xy 406.22173 -277.596625) (xy 406.242266 -277.612602) (xy 406.253696 -277.622) (xy 406.282652 -277.625556)
			(xy 406.378664 -277.579582) (xy 406.387096 -277.575095) (xy 406.400117 -277.561137) (xy 406.407178 -277.543403)
			(xy 406.40762 -277.533862) (xy 406.40762 -275.817584) (xy 406.40722 -275.808096) (xy 406.400322 -275.790417)
			(xy 406.387502 -275.776425) (xy 406.379172 -275.771864) (xy 406.355704 -275.759801) (xy 406.312598 -275.729373)
			(xy 406.274863 -275.692494) (xy 406.243455 -275.650098) (xy 406.219167 -275.603256) (xy 406.202615 -275.553156)
			(xy 406.194219 -275.501065) (xy 406.193752 -275.474684) (xy 406.193752 -274.524724) (xy 406.193794 -274.51537)
			(xy 406.194809 -274.496689) (xy 406.195784 -274.487386) (xy 406.197054 -274.475956) (xy 406.189688 -274.454112)
			(xy 406.117298 -274.381468) (xy 406.095708 -274.373594) (xy 406.084278 -274.374864) (xy 406.050242 -274.376896)
			(xy 406.049734 -274.376896) (xy 406.024039 -274.376372) (xy 405.973286 -274.368296) (xy 405.924419 -274.352385)
			(xy 405.878642 -274.32903) (xy 405.837078 -274.298804) (xy 405.800751 -274.262453) (xy 405.770554 -274.220869)
			(xy 405.74723 -274.175075) (xy 405.731352 -274.126198) (xy 405.72331 -274.07544) (xy 405.722836 -274.049744)
			(xy 405.723311 -274.024032) (xy 405.731349 -273.973239) (xy 405.747235 -273.924329) (xy 405.770576 -273.878507)
			(xy 405.800799 -273.836901) (xy 405.837158 -273.800535) (xy 405.878759 -273.770305) (xy 405.924578 -273.746956)
			(xy 405.973485 -273.731062) (xy 406.024276 -273.723015) (xy 406.049988 -273.722592) (xy 406.076183 -273.72312)
			(xy 406.127898 -273.731508) (xy 406.177608 -273.748053) (xy 406.224034 -273.772331) (xy 406.245314 -273.787616)
			(xy 406.256998 -273.796252) (xy 406.285446 -273.798538) (xy 406.37968 -273.751294) (xy 406.387845 -273.74672)
			(xy 406.400411 -273.732875) (xy 406.407143 -273.715431) (xy 406.40762 -273.706082) (xy 406.40762 -273.443446)
			(xy 406.407145 -273.434105) (xy 406.400363 -273.416692) (xy 406.387821 -273.402838) (xy 406.37968 -273.398234)
			(xy 406.2984 -273.35734) (xy 406.289834 -273.353511) (xy 406.271178 -273.351684) (xy 406.253114 -273.356694)
			(xy 406.245314 -273.361912) (xy 406.224009 -273.377151) (xy 406.17757 -273.401379) (xy 406.127872 -273.41792)
			(xy 406.076176 -273.426352) (xy 406.049988 -273.426936) (xy 406.024282 -273.426431) (xy 405.973504 -273.418387)
			(xy 405.924609 -273.402498) (xy 405.878801 -273.379157) (xy 405.837209 -273.348937) (xy 405.800856 -273.312582)
			(xy 405.770637 -273.270989) (xy 405.747297 -273.22518) (xy 405.73141 -273.176285) (xy 405.723368 -273.125506)
			(xy 405.723368 -273.074094) (xy 405.73141 -273.023315) (xy 405.747297 -272.97442) (xy 405.770637 -272.928611)
			(xy 405.800856 -272.887018) (xy 405.837209 -272.850663) (xy 405.878801 -272.820443) (xy 405.924609 -272.797102)
			(xy 405.973504 -272.781213) (xy 406.024282 -272.773169) (xy 406.049988 -272.772632) (xy 406.076183 -272.77316)
			(xy 406.127898 -272.781549) (xy 406.177606 -272.798096) (xy 406.224031 -272.822376) (xy 406.245314 -272.837656)
			(xy 406.256998 -272.846292) (xy 406.285446 -272.848578) (xy 406.37968 -272.801334) (xy 406.387849 -272.796762)
			(xy 406.400426 -272.782918) (xy 406.407172 -272.765474) (xy 406.40762 -272.756122) (xy 406.40762 -271.851374)
			(xy 406.407498 -271.846685) (xy 406.405707 -271.837479) (xy 406.404064 -271.833086) (xy 406.38784 -271.789821)
			(xy 406.362526 -271.700948) (xy 406.345532 -271.610116) (xy 406.337003 -271.518102) (xy 406.3365 -271.471898)
			(xy 406.3365 -266.156948) (xy 406.336403 -266.152803) (xy 406.334997 -266.144632) (xy 406.333706 -266.140692)
			(xy 377.597924 -181.242716) (xy 377.596654 -181.241192) (xy 377.578604 -181.217082) (xy 377.549536 -181.164337)
			(xy 377.529119 -181.107679) (xy 377.517859 -181.048516) (xy 377.51639 -181.018434) (xy 377.51639 -181.017926)
			(xy 377.516136 -181.008274) (xy 377.516136 -181.006496) (xy 377.516136 -181.00421) (xy 377.516136 -181.001162)
			(xy 376.29084 -177.3809) (xy 376.285674 -177.37722) (xy 376.273975 -177.37233) (xy 376.267726 -177.371248)
			(xy 376.205242 -177.365152) (xy 376.173238 -177.362104) (xy 376.165898 -177.361575) (xy 376.151442 -177.364289)
			(xy 376.14479 -177.367438) (xy 376.13844 -177.370994) (xy 376.12828 -177.380646) (xy 376.124216 -177.387504)
			(xy 376.109519 -177.412112) (xy 376.073905 -177.457021) (xy 376.031979 -177.496104) (xy 375.984684 -177.528481)
			(xy 375.933081 -177.553427) (xy 375.878329 -177.57038) (xy 375.821658 -177.578961) (xy 375.793 -177.579528)
			(xy 375.765747 -177.579042) (xy 375.711797 -177.571285) (xy 375.659499 -177.555929) (xy 375.609919 -177.533287)
			(xy 375.564067 -177.503819) (xy 375.522874 -177.468126) (xy 375.487181 -177.426933) (xy 375.457713 -177.381081)
			(xy 375.435071 -177.331501) (xy 375.419715 -177.279203) (xy 375.411958 -177.225253) (xy 375.411958 -177.170747)
			(xy 375.419715 -177.116797) (xy 375.435071 -177.064499) (xy 375.457713 -177.014919) (xy 375.487181 -176.969067)
			(xy 375.522874 -176.927874) (xy 375.564067 -176.892181) (xy 375.609919 -176.862713) (xy 375.659499 -176.840071)
			(xy 375.711797 -176.824715) (xy 375.765747 -176.816958) (xy 375.793 -176.816512) (xy 375.818356 -176.816951)
			(xy 375.868618 -176.823703) (xy 375.917547 -176.837037) (xy 375.941082 -176.846484) (xy 375.947945 -176.849077)
			(xy 375.962527 -176.850614) (xy 375.969784 -176.849532) (xy 375.976896 -176.848262) (xy 375.989596 -176.841912)
			(xy 376.063256 -176.773586) (xy 376.06813 -176.768728) (xy 376.075335 -176.757011) (xy 376.07748 -176.750472)
			(xy 376.01525 -176.56683) (xy 376.009154 -176.56302) (xy 375.936256 -176.531016) (xy 375.931416 -176.529013)
			(xy 375.921172 -176.526834) (xy 375.915936 -176.526698) (xy 375.905522 -176.526698) (xy 375.902982 -176.527714)
			(xy 375.89587 -176.531016) (xy 375.871521 -176.541283) (xy 375.8207 -176.555756) (xy 375.768367 -176.563066)
			(xy 375.741946 -176.563528) (xy 375.734072 -176.563528) (xy 375.707164 -176.562548) (xy 375.654012 -176.553955)
			(xy 375.602595 -176.537974) (xy 375.553936 -176.514922) (xy 375.509002 -176.485257) (xy 375.468686 -176.449569)
			(xy 375.433787 -176.408567) (xy 375.405001 -176.363065) (xy 375.382898 -176.313968) (xy 375.367918 -176.262251)
			(xy 375.360359 -176.208942) (xy 375.35993 -176.18202) (xy 375.35993 -176.181258) (xy 375.360197 -176.161682)
			(xy 375.364274 -176.122743) (xy 375.368058 -176.103534) (xy 375.368058 -176.103026) (xy 375.368312 -176.102518)
			(xy 375.369363 -176.095959) (xy 375.368466 -176.082711) (xy 375.366534 -176.076356) (xy 375.364502 -176.07026)
			(xy 375.357136 -176.059084) (xy 375.285254 -175.996346) (xy 375.279885 -175.991947) (xy 375.267395 -175.985903)
			(xy 375.260616 -175.984408) (xy 375.254092 -175.983496) (xy 375.240974 -175.984658) (xy 375.234708 -175.986694)
			(xy 375.234454 -175.986694) (xy 375.203352 -175.997126) (xy 375.138728 -176.008366) (xy 375.10593 -176.009046)
			(xy 375.102882 -176.009046) (xy 375.075764 -176.008368) (xy 375.022124 -176.000287) (xy 374.970171 -175.984689)
			(xy 374.920951 -175.961888) (xy 374.875457 -175.932344) (xy 374.834608 -175.896653) (xy 374.799226 -175.855536)
			(xy 374.770027 -175.80982) (xy 374.747598 -175.76043) (xy 374.732392 -175.70836) (xy 374.724716 -175.654661)
			(xy 374.724168 -175.627538) (xy 374.724628 -175.600283) (xy 374.732381 -175.546326) (xy 374.747733 -175.494022)
			(xy 374.770373 -175.444436) (xy 374.79984 -175.398576) (xy 374.835533 -175.357377) (xy 374.876727 -175.321677)
			(xy 374.922582 -175.292203) (xy 374.972164 -175.269555) (xy 375.024466 -175.254194) (xy 375.078421 -175.246433)
			(xy 375.105676 -175.24603) (xy 375.133499 -175.246527) (xy 375.188547 -175.25466) (xy 375.241822 -175.270726)
			(xy 375.26722 -175.282098) (xy 375.267728 -175.282098) (xy 375.267982 -175.282352) (xy 375.273818 -175.284835)
			(xy 375.286282 -175.28715) (xy 375.29262 -175.286924) (xy 375.306082 -175.285908) (xy 375.389648 -175.229774)
			(xy 375.392696 -175.227488) (xy 375.401776 -175.219455) (xy 375.411861 -175.197446) (xy 375.412 -175.185324)
			(xy 375.412 -175.18507) (xy 375.411492 -175.16602) (xy 375.411866 -175.141596) (xy 375.418067 -175.093143)
			(xy 375.430395 -175.045876) (xy 375.44865 -175.000568) (xy 375.46026 -174.979076) (xy 375.46534 -174.969932)
			(xy 375.467372 -174.948596) (xy 375.261632 -174.340012) (xy 375.259854 -174.337218) (xy 375.246567 -174.312575)
			(xy 375.226551 -174.260292) (xy 375.219976 -174.233078) (xy 375.214388 -174.201328) (xy 375.214134 -174.200058)
			(xy 375.07418 -173.786546) (xy 375.066306 -173.775116) (xy 375.061734 -173.771306) (xy 375.041169 -173.753085)
			(xy 375.004968 -173.711755) (xy 374.975064 -173.665664) (xy 374.952073 -173.615763) (xy 374.936469 -173.563082)
			(xy 374.928577 -173.508709) (xy 374.92813 -173.481238) (xy 374.92813 -173.480984) (xy 374.928372 -173.462254)
			(xy 374.932061 -173.424976) (xy 374.935496 -173.406562) (xy 374.936512 -173.401482) (xy 374.937617 -173.394863)
			(xy 374.936708 -173.38148) (xy 374.934734 -173.375066) (xy 374.930924 -173.363382) (xy 374.92432 -173.359318)
			(xy 374.921272 -173.357794) (xy 374.861836 -173.326806) (xy 374.857411 -173.324611) (xy 374.847946 -173.321793)
			(xy 374.84304 -173.321218) (xy 374.833642 -173.320456) (xy 374.824244 -173.32325) (xy 374.79821 -173.330342)
			(xy 374.744796 -173.337984) (xy 374.717818 -173.33849) (xy 374.717056 -173.33849) (xy 374.689807 -173.338001)
			(xy 374.635865 -173.330239) (xy 374.583577 -173.31488) (xy 374.534007 -173.292236) (xy 374.488163 -173.262768)
			(xy 374.44698 -173.227077) (xy 374.411294 -173.185887) (xy 374.381834 -173.140039) (xy 374.359198 -173.090465)
			(xy 374.343848 -173.038174) (xy 374.336095 -172.984231) (xy 374.335548 -172.956982) (xy 374.336068 -172.928619)
			(xy 374.344465 -172.872518) (xy 374.361071 -172.818276) (xy 374.385521 -172.76709) (xy 374.417276 -172.720085)
			(xy 374.455637 -172.678296) (xy 374.49976 -172.642644) (xy 374.548672 -172.613914) (xy 374.574816 -172.602906)
			(xy 374.579896 -172.600874) (xy 374.600216 -172.582078) (xy 374.603791 -172.578598) (xy 374.609671 -172.57054)
			(xy 374.6119 -172.566076) (xy 374.6373 -172.511466) (xy 374.640094 -172.5041) (xy 371.434868 -163.034218)
			(xy 371.422933 -162.997873) (xy 371.403985 -162.923751) (xy 371.397022 -162.886136) (xy 371.397022 -162.88512)
			(xy 370.836952 -160.070292) (xy 370.830101 -160.034234) (xy 370.821073 -159.961389) (xy 370.818918 -159.92475)
			(xy 370.653818 -156.558742) (xy 370.653056 -156.552646) (xy 370.395246 -155.07589) (xy 370.389083 -155.038458)
			(xy 370.381833 -154.962935) (xy 370.380768 -154.925014) (xy 370.368576 -154.28976) (xy 370.366544 -154.179016)
			(xy 370.366084 -154.173287) (xy 370.362883 -154.162251) (xy 370.360194 -154.157172) (xy 370.3574 -154.152092)
			(xy 370.348764 -154.142694) (xy 370.343176 -154.139138) (xy 370.317936 -154.122366) (xy 370.272076 -154.082751)
			(xy 370.232335 -154.037001) (xy 370.199523 -153.986052) (xy 370.174312 -153.930945) (xy 370.157216 -153.872805)
			(xy 370.148586 -153.812822) (xy 370.148104 -153.782522) (xy 370.148104 -153.782268) (xy 370.148578 -153.753943)
			(xy 370.156126 -153.697798) (xy 370.171083 -153.643158) (xy 370.193183 -153.590996) (xy 370.222032 -153.542242)
			(xy 370.257117 -153.497764) (xy 370.297812 -153.458354) (xy 370.320316 -153.441146) (xy 370.325904 -153.437082)
			(xy 370.328698 -153.433526) (xy 370.333778 -153.42616) (xy 370.335556 -153.423112) (xy 370.340636 -153.413714)
			(xy 370.341144 -153.412698) (xy 370.346224 -153.402538) (xy 370.348533 -153.397246) (xy 370.350961 -153.38596)
			(xy 370.35105 -153.380186) (xy 370.35105 -153.379932) (xy 370.317522 -151.630126) (xy 370.256816 -148.477224)
			(xy 370.256816 -148.4757) (xy 370.229892 -147.926552) (xy 370.224812 -147.916646) (xy 370.211377 -147.889405)
			(xy 370.192364 -147.831722) (xy 370.182736 -147.771754) (xy 370.18214 -147.741386) (xy 370.182544 -147.716215)
			(xy 370.189162 -147.666309) (xy 370.202283 -147.617706) (xy 370.211604 -147.59432) (xy 370.213382 -147.589748)
			(xy 370.118386 -145.65249) (xy 370.118067 -145.648118) (xy 370.116151 -145.639563) (xy 370.114576 -145.635472)
			(xy 368.643662 -142.084298) (xy 368.639739 -142.075986) (xy 368.62711 -142.062651) (xy 368.610599 -142.054607)
			(xy 368.601498 -142.05331) (xy 368.49812 -142.043404) (xy 368.472466 -142.055596) (xy 368.464846 -142.067534)
			(xy 368.455667 -142.081169) (xy 368.435317 -142.106984) (xy 368.424206 -142.119096) (xy 368.422682 -142.12062)
			(xy 368.41965 -142.12432) (xy 368.414921 -142.132635) (xy 368.413284 -142.13713) (xy 368.413284 -142.137638)
			(xy 368.412019 -142.141585) (xy 368.410612 -142.149752) (xy 368.41049 -142.153894) (xy 368.41049 -142.222982)
			(xy 368.410589 -142.227127) (xy 368.412 -142.235296) (xy 368.413284 -142.239238) (xy 368.413284 -142.239746)
			(xy 368.414952 -142.244226) (xy 368.419685 -142.252531) (xy 368.422682 -142.256256) (xy 368.424206 -142.25778)
			(xy 368.443473 -142.279107) (xy 368.47603 -142.32647) (xy 368.501114 -142.37818) (xy 368.518157 -142.433068)
			(xy 368.526774 -142.489891) (xy 368.52677 -142.547364) (xy 368.518145 -142.604186) (xy 368.501093 -142.659072)
			(xy 368.476002 -142.710778) (xy 368.443438 -142.758136) (xy 368.424206 -142.779496) (xy 368.422682 -142.78102)
			(xy 368.41965 -142.78472) (xy 368.414921 -142.793035) (xy 368.413284 -142.79753) (xy 368.413284 -142.798038)
			(xy 368.412019 -142.801985) (xy 368.410612 -142.810152) (xy 368.41049 -142.814294) (xy 368.41049 -142.883382)
			(xy 368.410589 -142.887527) (xy 368.412 -142.895696) (xy 368.413284 -142.899638) (xy 368.413284 -142.900146)
			(xy 368.414952 -142.904626) (xy 368.419685 -142.912931) (xy 368.422682 -142.916656) (xy 368.424206 -142.91818)
			(xy 368.443479 -142.939506) (xy 368.47605 -142.986868) (xy 368.501147 -143.038579) (xy 368.518205 -143.09347)
			(xy 368.526836 -143.150298) (xy 368.52733 -143.179038) (xy 368.527254 -143.191776) (xy 368.525604 -143.217198)
			(xy 368.524028 -143.229838) (xy 368.520115 -143.255626) (xy 368.506198 -143.305894) (xy 368.485568 -143.353799)
			(xy 368.458609 -143.398451) (xy 368.425822 -143.439016) (xy 368.387819 -143.474742) (xy 368.366802 -143.490188)
			(xy 368.362992 -143.492982) (xy 368.359453 -143.496204) (xy 368.353566 -143.503748) (xy 368.351308 -143.507968)
			(xy 368.349065 -143.512575) (xy 368.346258 -143.522429) (xy 368.34572 -143.527526) (xy 368.34572 -143.528542)
			(xy 368.345466 -143.53159) (xy 368.345466 -143.596868) (xy 368.346482 -143.605758) (xy 368.348006 -143.612362)
			(xy 368.3508 -143.624046) (xy 368.3508 -143.6243) (xy 368.351054 -143.624808) (xy 368.360452 -143.643096)
			(xy 368.363754 -143.649954) (xy 368.370866 -143.658082) (xy 368.375692 -143.661638) (xy 368.398824 -143.679821)
			(xy 368.439749 -143.722093) (xy 368.473717 -143.770135) (xy 368.499927 -143.822811) (xy 368.51776 -143.878881)
			(xy 368.526796 -143.93702) (xy 368.52733 -143.966438) (xy 368.526842 -143.993688) (xy 368.519081 -144.047633)
			(xy 368.503723 -144.099924) (xy 368.48108 -144.149498) (xy 368.451613 -144.195345) (xy 368.415922 -144.236533)
			(xy 368.374733 -144.272222) (xy 368.328884 -144.301687) (xy 368.279309 -144.324328) (xy 368.227017 -144.339684)
			(xy 368.173072 -144.347443) (xy 368.145822 -144.347946) (xy 368.118086 -144.347443) (xy 368.0632 -144.339401)
			(xy 368.010056 -144.323497) (xy 367.959775 -144.300068) (xy 367.913415 -144.269605) (xy 367.871954 -144.232753)
			(xy 367.836264 -144.190285) (xy 367.807099 -144.143099) (xy 367.785073 -144.092187) (xy 367.770649 -144.038623)
			(xy 367.766854 -144.011142) (xy 367.76533 -143.997426) (xy 367.763542 -143.969258) (xy 367.767292 -143.912942)
			(xy 367.779301 -143.857794) (xy 367.799308 -143.805018) (xy 367.826875 -143.755768) (xy 367.861401 -143.711119)
			(xy 367.902131 -143.672047) (xy 367.924842 -143.655288) (xy 367.927382 -143.653256) (xy 367.934564 -143.646894)
			(xy 367.943967 -143.630186) (xy 367.94567 -143.620744) (xy 367.94567 -143.620236) (xy 367.946178 -143.613886)
			(xy 367.946178 -143.543782) (xy 367.94567 -143.53667) (xy 367.944995 -143.532504) (xy 367.942436 -143.524463)
			(xy 367.94059 -143.520668) (xy 367.936526 -143.51254) (xy 367.929414 -143.499078) (xy 367.925858 -143.493744)
			(xy 367.923826 -143.491204) (xy 367.920524 -143.487394) (xy 367.917984 -143.485108) (xy 367.915698 -143.483584)
			(xy 367.892597 -143.465411) (xy 367.851732 -143.423167) (xy 367.81782 -143.375162) (xy 367.791663 -143.322528)
			(xy 367.773877 -143.266509) (xy 367.764883 -143.208426) (xy 367.764314 -143.179038) (xy 367.764832 -143.150298)
			(xy 367.77345 -143.093468) (xy 367.790496 -143.038573) (xy 367.815585 -142.986858) (xy 367.848149 -142.939491)
			(xy 367.867438 -142.91818) (xy 367.868962 -142.916656) (xy 367.871997 -142.912957) (xy 367.876734 -142.904646)
			(xy 367.87836 -142.900146) (xy 367.87836 -142.899638) (xy 367.879622 -142.895691) (xy 367.881024 -142.887524)
			(xy 367.881154 -142.883382) (xy 367.881154 -142.814294) (xy 367.881061 -142.810148) (xy 367.879663 -142.801975)
			(xy 367.87836 -142.798038) (xy 367.87836 -142.79753) (xy 367.876691 -142.79305) (xy 367.871959 -142.784745)
			(xy 367.868962 -142.78102) (xy 367.867438 -142.779496) (xy 367.848164 -142.758169) (xy 367.815592 -142.710807)
			(xy 367.790494 -142.659093) (xy 367.773438 -142.6042) (xy 367.76481 -142.547369) (xy 367.764806 -142.489887)
			(xy 367.773425 -142.433054) (xy 367.790473 -142.378159) (xy 367.815564 -142.326442) (xy 367.848129 -142.279074)
			(xy 367.867438 -142.25778) (xy 367.868962 -142.256256) (xy 367.871997 -142.252557) (xy 367.876734 -142.244246)
			(xy 367.87836 -142.239746) (xy 367.87836 -142.239238) (xy 367.879622 -142.235291) (xy 367.881024 -142.227124)
			(xy 367.881154 -142.222982) (xy 367.881154 -142.153894) (xy 367.881061 -142.149748) (xy 367.879663 -142.141575)
			(xy 367.87836 -142.137638) (xy 367.87836 -142.13713) (xy 367.876691 -142.13265) (xy 367.871959 -142.124345)
			(xy 367.868962 -142.12062) (xy 367.867438 -142.119096) (xy 367.848164 -142.097769) (xy 367.815592 -142.050407)
			(xy 367.790494 -141.998693) (xy 367.773438 -141.9438) (xy 367.76481 -141.886969) (xy 367.764806 -141.829487)
			(xy 367.773425 -141.772654) (xy 367.790473 -141.717759) (xy 367.815564 -141.666042) (xy 367.848129 -141.618674)
			(xy 367.867438 -141.59738) (xy 367.868962 -141.595856) (xy 367.871997 -141.592157) (xy 367.876734 -141.583846)
			(xy 367.87836 -141.579346) (xy 367.87836 -141.578838) (xy 367.879622 -141.574891) (xy 367.881024 -141.566724)
			(xy 367.881154 -141.562582) (xy 367.881154 -141.493494) (xy 367.881061 -141.489348) (xy 367.879663 -141.481175)
			(xy 367.87836 -141.477238) (xy 367.87836 -141.47673) (xy 367.876691 -141.47225) (xy 367.871959 -141.463945)
			(xy 367.868962 -141.46022) (xy 367.867438 -141.458696) (xy 367.848164 -141.437369) (xy 367.815592 -141.390007)
			(xy 367.790494 -141.338293) (xy 367.773438 -141.2834) (xy 367.76481 -141.226569) (xy 367.764806 -141.169087)
			(xy 367.773425 -141.112254) (xy 367.790473 -141.057359) (xy 367.815564 -141.005642) (xy 367.848129 -140.958274)
			(xy 367.867438 -140.93698) (xy 367.868962 -140.935456) (xy 367.871997 -140.931757) (xy 367.876734 -140.923446)
			(xy 367.87836 -140.918946) (xy 367.87836 -140.918438) (xy 367.879622 -140.914491) (xy 367.881024 -140.906324)
			(xy 367.881154 -140.902182) (xy 367.881154 -140.833094) (xy 367.881061 -140.828948) (xy 367.879663 -140.820775)
			(xy 367.87836 -140.816838) (xy 367.87836 -140.81633) (xy 367.876691 -140.81185) (xy 367.871959 -140.803545)
			(xy 367.868962 -140.79982) (xy 367.867438 -140.798296) (xy 367.848169 -140.776968) (xy 367.815606 -140.729604)
			(xy 367.790515 -140.677893) (xy 367.773464 -140.623003) (xy 367.764838 -140.566177) (xy 367.764314 -140.537438)
			(xy 367.76483 -140.508806) (xy 367.773392 -140.452186) (xy 367.790313 -140.39748) (xy 367.815215 -140.345914)
			(xy 367.847539 -140.298645) (xy 367.866676 -140.277342) (xy 367.867184 -140.276834) (xy 367.874296 -140.26896)
			(xy 367.87963 -140.23975) (xy 367.650776 -139.687554) (xy 367.619534 -139.670536) (xy 367.602008 -139.673838)
			(xy 367.585382 -139.6766) (xy 367.551805 -139.679522) (xy 367.534952 -139.67968) (xy 367.507583 -139.679205)
			(xy 367.453409 -139.671375) (xy 367.400909 -139.655882) (xy 367.351164 -139.633044) (xy 367.305193 -139.603331)
			(xy 367.284254 -139.5857) (xy 367.284 -139.5857) (xy 367.284 -139.585446) (xy 367.276915 -139.579857)
			(xy 367.259997 -139.573609) (xy 367.25098 -139.573254) (xy 367.183924 -139.573254) (xy 367.174905 -139.573608)
			(xy 367.157981 -139.579845) (xy 367.150904 -139.585446) (xy 367.15065 -139.5857) (xy 367.129717 -139.603341)
			(xy 367.083749 -139.633065) (xy 367.034003 -139.655911) (xy 366.981501 -139.671407) (xy 366.927323 -139.679236)
			(xy 366.872581 -139.679236) (xy 366.818403 -139.671407) (xy 366.765901 -139.655911) (xy 366.716155 -139.633065)
			(xy 366.670187 -139.603341) (xy 366.649254 -139.5857) (xy 366.649 -139.5857) (xy 366.649 -139.585446)
			(xy 366.641915 -139.579857) (xy 366.624997 -139.573609) (xy 366.61598 -139.573254) (xy 366.548924 -139.573254)
			(xy 366.539905 -139.573608) (xy 366.522981 -139.579845) (xy 366.515904 -139.585446) (xy 366.51565 -139.5857)
			(xy 366.494717 -139.603341) (xy 366.448749 -139.633065) (xy 366.399003 -139.655911) (xy 366.346501 -139.671407)
			(xy 366.292323 -139.679236) (xy 366.237581 -139.679236) (xy 366.183403 -139.671407) (xy 366.130901 -139.655911)
			(xy 366.081155 -139.633065) (xy 366.035187 -139.603341) (xy 366.014254 -139.5857) (xy 366.014 -139.5857)
			(xy 366.014 -139.585446) (xy 366.006915 -139.579857) (xy 365.989997 -139.573609) (xy 365.98098 -139.573254)
			(xy 365.913924 -139.573254) (xy 365.904905 -139.573608) (xy 365.887981 -139.579845) (xy 365.880904 -139.585446)
			(xy 365.88065 -139.5857) (xy 365.859718 -139.603339) (xy 365.81375 -139.633059) (xy 365.764003 -139.655896)
			(xy 365.7115 -139.671379) (xy 365.657321 -139.679191) (xy 365.629952 -139.67968) (xy 365.602704 -139.67919)
			(xy 365.548763 -139.671428) (xy 365.496475 -139.656069) (xy 365.446906 -139.633424) (xy 365.401064 -139.603956)
			(xy 365.359882 -139.568265) (xy 365.324198 -139.527075) (xy 365.294739 -139.481227) (xy 365.272105 -139.431653)
			(xy 365.256756 -139.379363) (xy 365.249004 -139.32542) (xy 365.248444 -139.298172) (xy 365.248993 -139.268982)
			(xy 365.257873 -139.21128) (xy 365.275438 -139.155605) (xy 365.301276 -139.103254) (xy 365.334786 -139.055448)
			(xy 365.375186 -139.013304) (xy 365.39805 -138.99515) (xy 365.407115 -138.987456) (xy 365.417574 -138.966134)
			(xy 365.418116 -138.954256) (xy 365.417354 -138.872976) (xy 365.416642 -138.861265) (xy 365.406044 -138.840362)
			(xy 365.397034 -138.832844) (xy 365.39678 -138.83259) (xy 365.373188 -138.814485) (xy 365.331388 -138.77219)
			(xy 365.296664 -138.723916) (xy 365.269857 -138.670835) (xy 365.251618 -138.614236) (xy 365.24239 -138.555491)
			(xy 365.24184 -138.525758) (xy 365.242315 -138.498389) (xy 365.250145 -138.444215) (xy 365.265638 -138.391715)
			(xy 365.288476 -138.34197) (xy 365.318189 -138.295999) (xy 365.33582 -138.27506) (xy 365.33582 -138.274806)
			(xy 365.336074 -138.274806) (xy 365.341662 -138.26772) (xy 365.347909 -138.250803) (xy 365.348266 -138.241786)
			(xy 365.348266 -138.17473) (xy 365.347913 -138.165711) (xy 365.34168 -138.148783) (xy 365.336074 -138.14171)
			(xy 365.33582 -138.141456) (xy 365.318183 -138.120523) (xy 365.288464 -138.074556) (xy 365.265625 -138.024812)
			(xy 365.250135 -137.972312) (xy 365.242311 -137.918137) (xy 365.242316 -137.8634) (xy 365.250148 -137.809226)
			(xy 365.265647 -137.756729) (xy 365.288495 -137.706988) (xy 365.318221 -137.661026) (xy 365.33582 -137.64006)
			(xy 365.33582 -137.639806) (xy 365.336074 -137.639806) (xy 365.341662 -137.63272) (xy 365.347909 -137.615803)
			(xy 365.348266 -137.606786) (xy 365.348266 -137.53973) (xy 365.347913 -137.530711) (xy 365.34168 -137.513783)
			(xy 365.336074 -137.50671) (xy 365.33582 -137.506456) (xy 365.318183 -137.485523) (xy 365.288464 -137.439556)
			(xy 365.265625 -137.389812) (xy 365.250135 -137.337312) (xy 365.242311 -137.283137) (xy 365.242316 -137.2284)
			(xy 365.250148 -137.174226) (xy 365.265647 -137.121729) (xy 365.288495 -137.071988) (xy 365.318221 -137.026026)
			(xy 365.33582 -137.00506) (xy 365.33582 -137.004806) (xy 365.336074 -137.004806) (xy 365.341662 -136.99772)
			(xy 365.347909 -136.980803) (xy 365.348266 -136.971786) (xy 365.348266 -136.90473) (xy 365.347913 -136.895711)
			(xy 365.34168 -136.878783) (xy 365.336074 -136.87171) (xy 365.33582 -136.871456) (xy 365.31818 -136.850524)
			(xy 365.288457 -136.804557) (xy 365.265619 -136.75481) (xy 365.250134 -136.702307) (xy 365.242321 -136.648128)
			(xy 365.24184 -136.620758) (xy 365.242326 -136.593507) (xy 365.250082 -136.539559) (xy 365.265437 -136.487264)
			(xy 365.288079 -136.437687) (xy 365.317545 -136.391837) (xy 365.353236 -136.350646) (xy 365.394427 -136.314955)
			(xy 365.440277 -136.285489) (xy 365.489854 -136.262847) (xy 365.542149 -136.247492) (xy 365.596097 -136.239736)
			(xy 365.650599 -136.239736) (xy 365.704547 -136.247492) (xy 365.756842 -136.262847) (xy 365.806419 -136.285489)
			(xy 365.852269 -136.314955) (xy 365.89346 -136.350646) (xy 365.929151 -136.391837) (xy 365.958617 -136.437687)
			(xy 365.981259 -136.487264) (xy 365.996614 -136.539559) (xy 366.00437 -136.593507) (xy 366.004856 -136.620758)
			(xy 366.00438 -136.648126) (xy 365.996548 -136.7023) (xy 365.981053 -136.754798) (xy 365.958214 -136.804542)
			(xy 365.928499 -136.850511) (xy 365.910876 -136.871456) (xy 365.910876 -136.87171) (xy 365.910622 -136.87171)
			(xy 365.905036 -136.878797) (xy 365.898795 -136.895714) (xy 365.89843 -136.90473) (xy 365.89843 -136.971786)
			(xy 365.898786 -136.980804) (xy 365.905023 -136.997729) (xy 365.910622 -137.004806) (xy 365.910876 -137.00506)
			(xy 365.92852 -137.025993) (xy 365.95825 -137.071962) (xy 365.981101 -137.12171) (xy 365.996603 -137.174214)
			(xy 366.004436 -137.228396) (xy 366.004441 -137.283141) (xy 365.996616 -137.337324) (xy 365.981123 -137.389831)
			(xy 365.958281 -137.439583) (xy 365.928558 -137.485557) (xy 365.910876 -137.506456) (xy 365.910876 -137.50671)
			(xy 365.910622 -137.50671) (xy 365.905036 -137.513797) (xy 365.898795 -137.530714) (xy 365.89843 -137.53973)
			(xy 365.89843 -137.606786) (xy 365.898786 -137.615804) (xy 365.905023 -137.632729) (xy 365.910622 -137.639806)
			(xy 365.910876 -137.64006) (xy 365.92852 -137.660993) (xy 365.95825 -137.706962) (xy 365.981101 -137.75671)
			(xy 365.996603 -137.809214) (xy 366.004436 -137.863396) (xy 366.004441 -137.918141) (xy 365.996616 -137.972324)
			(xy 365.981123 -138.024831) (xy 365.958281 -138.074583) (xy 365.928558 -138.120557) (xy 365.910876 -138.141456)
			(xy 365.910876 -138.14171) (xy 365.910622 -138.14171) (xy 365.905036 -138.148797) (xy 365.898795 -138.165714)
			(xy 365.89843 -138.17473) (xy 365.89843 -138.241786) (xy 365.898786 -138.250804) (xy 365.905023 -138.267729)
			(xy 365.910622 -138.274806) (xy 365.910876 -138.27506) (xy 365.928516 -138.295992) (xy 365.958236 -138.341959)
			(xy 365.981073 -138.391707) (xy 365.996556 -138.44421) (xy 366.004367 -138.498388) (xy 366.004856 -138.525758)
			(xy 366.004305 -138.554947) (xy 365.99542 -138.612646) (xy 365.977853 -138.668318) (xy 365.952012 -138.720666)
			(xy 365.9185 -138.768468) (xy 365.8781 -138.810609) (xy 365.85525 -138.82878) (xy 365.84619 -138.836477)
			(xy 365.835743 -138.857798) (xy 365.835184 -138.869674) (xy 365.835946 -138.950954) (xy 365.836664 -138.962662)
			(xy 365.84727 -138.983554) (xy 365.856266 -138.991086) (xy 365.85652 -138.99134) (xy 365.88065 -139.010644)
			(xy 365.880904 -139.010898) (xy 365.887991 -139.016483) (xy 365.904908 -139.022724) (xy 365.913924 -139.02309)
			(xy 365.98098 -139.02309) (xy 365.989998 -139.022734) (xy 366.006917 -139.01649) (xy 366.014 -139.010898)
			(xy 366.014254 -139.010644) (xy 366.035187 -138.993003) (xy 366.081155 -138.963279) (xy 366.130901 -138.940433)
			(xy 366.183403 -138.924937) (xy 366.237581 -138.917108) (xy 366.292323 -138.917108) (xy 366.346501 -138.924937)
			(xy 366.399003 -138.940433) (xy 366.448749 -138.963279) (xy 366.494717 -138.993003) (xy 366.51565 -139.010644)
			(xy 366.515904 -139.010644) (xy 366.515904 -139.010898) (xy 366.522991 -139.016483) (xy 366.539908 -139.022724)
			(xy 366.548924 -139.02309) (xy 366.61598 -139.02309) (xy 366.624998 -139.022734) (xy 366.641917 -139.01649)
			(xy 366.649 -139.010898) (xy 366.649254 -139.010644) (xy 366.670187 -138.993003) (xy 366.716155 -138.963279)
			(xy 366.765901 -138.940433) (xy 366.818403 -138.924937) (xy 366.872581 -138.917108) (xy 366.927323 -138.917108)
			(xy 366.981501 -138.924937) (xy 367.034003 -138.940433) (xy 367.083749 -138.963279) (xy 367.129717 -138.993003)
			(xy 367.15065 -139.010644) (xy 367.150904 -139.010644) (xy 367.150904 -139.010898) (xy 367.157991 -139.016483)
			(xy 367.174908 -139.022724) (xy 367.183924 -139.02309) (xy 367.25098 -139.02309) (xy 367.259998 -139.022734)
			(xy 367.276917 -139.01649) (xy 367.284 -139.010898) (xy 367.284254 -139.010644) (xy 367.303812 -138.994153)
			(xy 367.346532 -138.966007) (xy 367.39263 -138.94382) (xy 367.441278 -138.927991) (xy 367.466372 -138.923014)
			(xy 367.48466 -138.919712) (xy 367.508028 -138.891518) (xy 367.508028 -132.380482) (xy 367.507452 -132.368899)
			(xy 367.497302 -132.348071) (xy 367.479086 -132.333754) (xy 367.467896 -132.330698) (xy 367.441243 -132.324559)
			(xy 367.389912 -132.305676) (xy 367.341805 -132.279654) (xy 367.297908 -132.247027) (xy 367.259122 -132.208465)
			(xy 367.226242 -132.164758) (xy 367.199941 -132.116803) (xy 367.180761 -132.065583) (xy 367.169093 -132.012148)
			(xy 367.165178 -131.957594) (xy 367.169095 -131.903041) (xy 367.180764 -131.849606) (xy 367.199946 -131.798386)
			(xy 367.226248 -131.750432) (xy 367.25913 -131.706726) (xy 367.297917 -131.668165) (xy 367.341815 -131.63554)
			(xy 367.389923 -131.60952) (xy 367.441254 -131.590638) (xy 367.467896 -131.584446) (xy 367.479134 -131.581483)
			(xy 367.497413 -131.567169) (xy 367.50753 -131.546273) (xy 367.508028 -131.534662) (xy 367.508028 -130.714496)
			(xy 367.508606 -130.665563) (xy 367.5182 -130.568168) (xy 367.537303 -130.472184) (xy 367.550954 -130.42519)
			(xy 373.468138 -110.920022) (xy 373.475337 -110.896631) (xy 373.491727 -110.850509) (xy 373.500904 -110.82782)
			(xy 373.638318 -110.496604) (xy 373.641805 -110.487129) (xy 373.641821 -110.466955) (xy 373.638318 -110.457488)
			(xy 373.606822 -110.381796) (xy 373.592598 -110.367572) (xy 373.5832 -110.363762) (xy 373.557435 -110.352526)
			(xy 373.509242 -110.323598) (xy 373.465811 -110.287918) (xy 373.42808 -110.246256) (xy 373.396864 -110.199514)
			(xy 373.372838 -110.148699) (xy 373.356521 -110.094912) (xy 373.348265 -110.039314) (xy 373.347742 -110.01121)
			(xy 373.348246 -109.983474) (xy 373.356289 -109.928589) (xy 373.372194 -109.875446) (xy 373.395624 -109.825165)
			(xy 373.426086 -109.778806) (xy 373.462939 -109.737345) (xy 373.505406 -109.701656) (xy 373.552591 -109.672491)
			(xy 373.603502 -109.650464) (xy 373.657066 -109.636039) (xy 373.684546 -109.632242) (xy 373.698262 -109.630718)
			(xy 373.72925 -109.629448) (xy 373.755348 -109.629891) (xy 373.807053 -109.637036) (xy 373.857302 -109.651159)
			(xy 373.881396 -109.661198) (xy 373.88292 -109.661706) (xy 373.884952 -109.662468) (xy 373.904764 -109.662468)
			(xy 373.980456 -109.631226) (xy 373.989625 -109.626985) (xy 374.003896 -109.612707) (xy 374.008142 -109.60354)
			(xy 375.498868 -106.004868) (xy 375.49963 -106.001312) (xy 375.510986 -105.957705) (xy 375.54053 -105.872569)
			(xy 375.577637 -105.790447) (xy 375.622005 -105.712009) (xy 375.673272 -105.637896) (xy 375.731018 -105.568712)
			(xy 375.76252 -105.536492) (xy 376.269758 -105.029) (xy 376.272806 -105.024174) (xy 376.278394 -105.015284)
			(xy 376.278648 -105.01503) (xy 376.286268 -105.002838) (xy 376.286268 -105.002584) (xy 376.2883 -104.999536)
			(xy 376.289824 -104.996996) (xy 376.29338 -104.991662) (xy 376.293634 -104.991408) (xy 376.297698 -104.985058)
			(xy 376.298714 -104.983534) (xy 376.311668 -104.964992) (xy 376.336279 -104.930882) (xy 376.390455 -104.866532)
			(xy 376.419872 -104.836468) (xy 381.352298 -99.904042) (xy 381.352806 -99.903534) (xy 381.390932 -99.866565)
			(xy 381.473791 -99.80013) (xy 381.51816 -99.770946) (xy 381.53848 -99.758246) (xy 381.539496 -99.757738)
			(xy 381.552958 -99.74961) (xy 381.566928 -99.741482) (xy 381.567182 -99.741482) (xy 381.578358 -99.735386)
			(xy 381.579882 -99.734624) (xy 381.589534 -99.729544) (xy 381.609835 -99.718997) (xy 381.651254 -99.699561)
			(xy 381.672338 -99.690682) (xy 384.074924 -98.695764) (xy 384.111474 -98.681063) (xy 384.186445 -98.656841)
			(xy 384.263107 -98.638663) (xy 384.340972 -98.626644) (xy 384.380232 -98.623374) (xy 384.385312 -98.622612)
			(xy 384.427585 -98.615732) (xy 384.51292 -98.608352) (xy 384.555746 -98.60788) (xy 385.225544 -98.60788)
			(xy 385.228084 -98.605594) (xy 385.252976 -98.580702) (xy 385.257956 -98.575271) (xy 385.264804 -98.562233)
			(xy 385.266438 -98.555048) (xy 385.266438 -98.55454) (xy 385.267454 -98.545142) (xy 385.267454 -97.463102)
			(xy 385.267878 -97.453033) (xy 385.275598 -97.434433) (xy 385.28244 -97.427034) (xy 385.511548 -97.197926)
			(xy 385.514342 -97.194878) (xy 385.51993 -97.187004) (xy 385.520946 -97.184718) (xy 385.524248 -97.173796)
			(xy 385.52628 -97.161858) (xy 385.528044 -97.135377) (xy 385.537974 -97.083242) (xy 385.555027 -97.032983)
			(xy 385.578873 -96.98557) (xy 385.59359 -96.963484) (xy 385.60842 -96.942692) (xy 385.642761 -96.90489)
			(xy 385.681843 -96.872013) (xy 385.724965 -96.844649) (xy 385.771355 -96.823288) (xy 385.820181 -96.808314)
			(xy 385.845304 -96.803718) (xy 385.845812 -96.803718) (xy 385.85267 -96.802448) (xy 385.858512 -96.799908)
			(xy 385.865116 -96.796352) (xy 385.86918 -96.793304) (xy 385.891024 -96.77527) (xy 385.894967 -96.771394)
			(xy 385.901254 -96.762301) (xy 385.90347 -96.757236) (xy 385.919218 -96.712786) (xy 385.919218 -96.712278)
			(xy 385.930394 -96.68002) (xy 385.931664 -96.674686) (xy 385.932426 -96.669098) (xy 385.931918 -96.657922)
			(xy 385.806188 -96.532446) (xy 385.796282 -96.529144) (xy 385.770565 -96.520824) (xy 385.721598 -96.497941)
			(xy 385.676353 -96.468371) (xy 385.635738 -96.432708) (xy 385.600567 -96.391666) (xy 385.571545 -96.346068)
			(xy 385.549253 -96.296828) (xy 385.534139 -96.244934) (xy 385.526506 -96.191425) (xy 385.526026 -96.1644)
			(xy 385.526489 -96.137148) (xy 385.534247 -96.083199) (xy 385.549603 -96.030903) (xy 385.572246 -95.981325)
			(xy 385.601714 -95.935474) (xy 385.637409 -95.894284) (xy 385.678602 -95.858594) (xy 385.724455 -95.82913)
			(xy 385.774035 -95.806491) (xy 385.826332 -95.791139) (xy 385.880282 -95.783387) (xy 385.907534 -95.782892)
			(xy 385.934559 -95.783365) (xy 385.988067 -95.791002) (xy 386.03996 -95.806119) (xy 386.089199 -95.828413)
			(xy 386.134796 -95.857436) (xy 386.175837 -95.892607) (xy 386.211501 -95.933222) (xy 386.241072 -95.978465)
			(xy 386.263957 -96.027431) (xy 386.272278 -96.053148) (xy 386.27558 -96.063054) (xy 387.818122 -97.605596)
			(xy 387.836237 -97.624376) (xy 387.866925 -97.666572) (xy 387.89063 -97.713053) (xy 387.906766 -97.762671)
			(xy 387.914935 -97.814204) (xy 387.915404 -97.840292) (xy 387.915404 -112.019334) (xy 387.914915 -112.045421)
			(xy 387.906745 -112.09695) (xy 387.890611 -112.146566) (xy 387.86691 -112.193046) (xy 387.836228 -112.235243)
			(xy 387.818122 -112.25403) (xy 386.501894 -113.570258) (xy 399.070576 -113.570258) (xy 399.070576 -98.50247)
			(xy 399.071112 -98.476447) (xy 399.079277 -98.425044) (xy 399.095369 -98.375547) (xy 399.118994 -98.329171)
			(xy 399.149573 -98.287053) (xy 399.167604 -98.268282) (xy 399.940526 -97.49536) (xy 399.94738 -97.487971)
			(xy 399.955091 -97.469363) (xy 399.955512 -97.459292) (xy 399.955512 -97.25025) (xy 399.952972 -97.239074)
			(xy 399.950178 -97.23374) (xy 399.94967 -97.232724) (xy 399.935957 -97.205245) (xy 399.916499 -97.147)
			(xy 399.90662 -97.08639) (xy 399.905982 -97.055686) (xy 399.906468 -97.028435) (xy 399.914224 -96.974487)
			(xy 399.929579 -96.922192) (xy 399.952221 -96.872615) (xy 399.981687 -96.826765) (xy 400.017378 -96.785574)
			(xy 400.058569 -96.749883) (xy 400.104419 -96.720417) (xy 400.153996 -96.697775) (xy 400.206291 -96.68242)
			(xy 400.260239 -96.674664) (xy 400.314741 -96.674664) (xy 400.368689 -96.68242) (xy 400.420984 -96.697775)
			(xy 400.470561 -96.720417) (xy 400.516411 -96.749883) (xy 400.557602 -96.785574) (xy 400.593293 -96.826765)
			(xy 400.622759 -96.872615) (xy 400.645401 -96.922192) (xy 400.660756 -96.974487) (xy 400.668512 -97.028435)
			(xy 400.668998 -97.055686) (xy 400.668377 -97.086488) (xy 400.658456 -97.147289) (xy 400.638887 -97.205703)
			(xy 400.625056 -97.233232) (xy 400.624802 -97.23374) (xy 400.622317 -97.239058) (xy 400.61962 -97.250478)
			(xy 400.619468 -97.256346) (xy 400.619468 -97.617788) (xy 400.618997 -97.643876) (xy 400.61083 -97.695409)
			(xy 400.594695 -97.745028) (xy 400.570991 -97.791508) (xy 400.540301 -97.833705) (xy 400.522186 -97.852484)
			(xy 399.74901 -98.625406) (xy 399.742176 -98.632811) (xy 399.734452 -98.651406) (xy 399.734024 -98.661474)
			(xy 399.734024 -100.17633) (xy 401.939252 -100.17633) (xy 401.939252 -99.31273) (xy 401.939742 -99.282762)
			(xy 401.947565 -99.22334) (xy 401.963078 -99.165447) (xy 401.986014 -99.110074) (xy 402.015981 -99.058168)
			(xy 402.052468 -99.010618) (xy 402.094848 -98.968238) (xy 402.142398 -98.931751) (xy 402.194304 -98.901784)
			(xy 402.249677 -98.878848) (xy 402.30757 -98.863335) (xy 402.366992 -98.855512) (xy 402.426928 -98.855512)
			(xy 402.48635 -98.863335) (xy 402.544243 -98.878848) (xy 402.599616 -98.901784) (xy 402.651522 -98.931751)
			(xy 402.699072 -98.968238) (xy 402.741452 -99.010618) (xy 402.777939 -99.058168) (xy 402.807906 -99.110074)
			(xy 402.830842 -99.165447) (xy 402.846355 -99.22334) (xy 402.854178 -99.282762) (xy 402.854668 -99.31273)
			(xy 402.854668 -100.17633) (xy 402.854178 -100.206298) (xy 402.846355 -100.26572) (xy 402.830842 -100.323613)
			(xy 402.807906 -100.378986) (xy 402.777939 -100.430892) (xy 402.741452 -100.478442) (xy 402.699072 -100.520822)
			(xy 402.651522 -100.557309) (xy 402.599616 -100.587276) (xy 402.544243 -100.610212) (xy 402.48635 -100.625725)
			(xy 402.426928 -100.633548) (xy 402.366992 -100.633548) (xy 402.30757 -100.625725) (xy 402.249677 -100.610212)
			(xy 402.194304 -100.587276) (xy 402.142398 -100.557309) (xy 402.094848 -100.520822) (xy 402.052468 -100.478442)
			(xy 402.015981 -100.430892) (xy 401.986014 -100.378986) (xy 401.963078 -100.323613) (xy 401.947565 -100.26572)
			(xy 401.939742 -100.206298) (xy 401.939252 -100.17633) (xy 399.734024 -100.17633) (xy 399.734024 -101.976428)
			(xy 400.085052 -101.976428) (xy 400.085052 -101.112828) (xy 400.085542 -101.08286) (xy 400.093365 -101.023438)
			(xy 400.108878 -100.965545) (xy 400.131814 -100.910172) (xy 400.161781 -100.858266) (xy 400.198268 -100.810716)
			(xy 400.240648 -100.768336) (xy 400.288198 -100.731849) (xy 400.340104 -100.701882) (xy 400.395477 -100.678946)
			(xy 400.45337 -100.663433) (xy 400.512792 -100.65561) (xy 400.572728 -100.65561) (xy 400.63215 -100.663433)
			(xy 400.690043 -100.678946) (xy 400.745416 -100.701882) (xy 400.797322 -100.731849) (xy 400.844872 -100.768336)
			(xy 400.887252 -100.810716) (xy 400.923739 -100.858266) (xy 400.953706 -100.910172) (xy 400.976642 -100.965545)
			(xy 400.992155 -101.023438) (xy 400.999978 -101.08286) (xy 401.000468 -101.112828) (xy 401.000468 -101.976428)
			(xy 400.999978 -102.006396) (xy 400.992155 -102.065818) (xy 400.976642 -102.123711) (xy 400.953706 -102.179084)
			(xy 400.923739 -102.23099) (xy 400.887252 -102.27854) (xy 400.844872 -102.32092) (xy 400.797322 -102.357407)
			(xy 400.745416 -102.387374) (xy 400.690043 -102.41031) (xy 400.63215 -102.425823) (xy 400.572728 -102.433646)
			(xy 400.512792 -102.433646) (xy 400.45337 -102.425823) (xy 400.395477 -102.41031) (xy 400.340104 -102.387374)
			(xy 400.288198 -102.357407) (xy 400.240648 -102.32092) (xy 400.198268 -102.27854) (xy 400.161781 -102.23099)
			(xy 400.131814 -102.179084) (xy 400.108878 -102.123711) (xy 400.093365 -102.065818) (xy 400.085542 -102.006396)
			(xy 400.085052 -101.976428) (xy 399.734024 -101.976428) (xy 399.734024 -103.776272) (xy 401.939252 -103.776272)
			(xy 401.939252 -102.912672) (xy 401.939742 -102.882704) (xy 401.947565 -102.823282) (xy 401.963078 -102.765389)
			(xy 401.986014 -102.710016) (xy 402.015981 -102.65811) (xy 402.052468 -102.61056) (xy 402.094848 -102.56818)
			(xy 402.142398 -102.531693) (xy 402.194304 -102.501726) (xy 402.249677 -102.47879) (xy 402.30757 -102.463277)
			(xy 402.366992 -102.455454) (xy 402.426928 -102.455454) (xy 402.48635 -102.463277) (xy 402.544243 -102.47879)
			(xy 402.599616 -102.501726) (xy 402.651522 -102.531693) (xy 402.699072 -102.56818) (xy 402.741452 -102.61056)
			(xy 402.777939 -102.65811) (xy 402.807906 -102.710016) (xy 402.830842 -102.765389) (xy 402.846355 -102.823282)
			(xy 402.854178 -102.882704) (xy 402.854668 -102.912672) (xy 402.854668 -103.776272) (xy 402.854178 -103.80624)
			(xy 402.846355 -103.865662) (xy 402.830842 -103.923555) (xy 402.807906 -103.978928) (xy 402.777939 -104.030834)
			(xy 402.741452 -104.078384) (xy 402.699072 -104.120764) (xy 402.651522 -104.157251) (xy 402.599616 -104.187218)
			(xy 402.544243 -104.210154) (xy 402.48635 -104.225667) (xy 402.426928 -104.23349) (xy 402.366992 -104.23349)
			(xy 402.30757 -104.225667) (xy 402.249677 -104.210154) (xy 402.194304 -104.187218) (xy 402.142398 -104.157251)
			(xy 402.094848 -104.120764) (xy 402.052468 -104.078384) (xy 402.015981 -104.030834) (xy 401.986014 -103.978928)
			(xy 401.963078 -103.923555) (xy 401.947565 -103.865662) (xy 401.939742 -103.80624) (xy 401.939252 -103.776272)
			(xy 399.734024 -103.776272) (xy 399.734024 -105.57637) (xy 400.085052 -105.57637) (xy 400.085052 -104.71277)
			(xy 400.085542 -104.682802) (xy 400.093365 -104.62338) (xy 400.108878 -104.565487) (xy 400.131814 -104.510114)
			(xy 400.161781 -104.458208) (xy 400.198268 -104.410658) (xy 400.240648 -104.368278) (xy 400.288198 -104.331791)
			(xy 400.340104 -104.301824) (xy 400.395477 -104.278888) (xy 400.45337 -104.263375) (xy 400.512792 -104.255552)
			(xy 400.572728 -104.255552) (xy 400.63215 -104.263375) (xy 400.690043 -104.278888) (xy 400.745416 -104.301824)
			(xy 400.797322 -104.331791) (xy 400.844872 -104.368278) (xy 400.887252 -104.410658) (xy 400.923739 -104.458208)
			(xy 400.953706 -104.510114) (xy 400.976642 -104.565487) (xy 400.992155 -104.62338) (xy 400.999978 -104.682802)
			(xy 401.000468 -104.71277) (xy 401.000468 -105.57637) (xy 400.999978 -105.606338) (xy 400.992155 -105.66576)
			(xy 400.976642 -105.723653) (xy 400.953706 -105.779026) (xy 400.923739 -105.830932) (xy 400.887252 -105.878482)
			(xy 400.844872 -105.920862) (xy 400.797322 -105.957349) (xy 400.745416 -105.987316) (xy 400.690043 -106.010252)
			(xy 400.63215 -106.025765) (xy 400.572728 -106.033588) (xy 400.512792 -106.033588) (xy 400.45337 -106.025765)
			(xy 400.395477 -106.010252) (xy 400.340104 -105.987316) (xy 400.288198 -105.957349) (xy 400.240648 -105.920862)
			(xy 400.198268 -105.878482) (xy 400.161781 -105.830932) (xy 400.131814 -105.779026) (xy 400.108878 -105.723653)
			(xy 400.093365 -105.66576) (xy 400.085542 -105.606338) (xy 400.085052 -105.57637) (xy 399.734024 -105.57637)
			(xy 399.734024 -107.376214) (xy 401.939252 -107.376214) (xy 401.939252 -106.512614) (xy 401.939742 -106.482646)
			(xy 401.947565 -106.423224) (xy 401.963078 -106.365331) (xy 401.986014 -106.309958) (xy 402.015981 -106.258052)
			(xy 402.052468 -106.210502) (xy 402.094848 -106.168122) (xy 402.142398 -106.131635) (xy 402.194304 -106.101668)
			(xy 402.249677 -106.078732) (xy 402.30757 -106.063219) (xy 402.366992 -106.055396) (xy 402.426928 -106.055396)
			(xy 402.48635 -106.063219) (xy 402.544243 -106.078732) (xy 402.599616 -106.101668) (xy 402.651522 -106.131635)
			(xy 402.699072 -106.168122) (xy 402.741452 -106.210502) (xy 402.777939 -106.258052) (xy 402.807906 -106.309958)
			(xy 402.830842 -106.365331) (xy 402.846355 -106.423224) (xy 402.854178 -106.482646) (xy 402.854668 -106.512614)
			(xy 402.854668 -107.376214) (xy 402.854178 -107.406182) (xy 402.846355 -107.465604) (xy 402.830842 -107.523497)
			(xy 402.807906 -107.57887) (xy 402.777939 -107.630776) (xy 402.741452 -107.678326) (xy 402.699072 -107.720706)
			(xy 402.651522 -107.757193) (xy 402.599616 -107.78716) (xy 402.544243 -107.810096) (xy 402.48635 -107.825609)
			(xy 402.426928 -107.833432) (xy 402.366992 -107.833432) (xy 402.30757 -107.825609) (xy 402.249677 -107.810096)
			(xy 402.194304 -107.78716) (xy 402.142398 -107.757193) (xy 402.094848 -107.720706) (xy 402.052468 -107.678326)
			(xy 402.015981 -107.630776) (xy 401.986014 -107.57887) (xy 401.963078 -107.523497) (xy 401.947565 -107.465604)
			(xy 401.939742 -107.406182) (xy 401.939252 -107.376214) (xy 399.734024 -107.376214) (xy 399.734024 -109.176312)
			(xy 400.085052 -109.176312) (xy 400.085052 -108.312712) (xy 400.085542 -108.282744) (xy 400.093365 -108.223322)
			(xy 400.108878 -108.165429) (xy 400.131814 -108.110056) (xy 400.161781 -108.05815) (xy 400.198268 -108.0106)
			(xy 400.240648 -107.96822) (xy 400.288198 -107.931733) (xy 400.340104 -107.901766) (xy 400.395477 -107.87883)
			(xy 400.45337 -107.863317) (xy 400.512792 -107.855494) (xy 400.572728 -107.855494) (xy 400.63215 -107.863317)
			(xy 400.690043 -107.87883) (xy 400.745416 -107.901766) (xy 400.797322 -107.931733) (xy 400.844872 -107.96822)
			(xy 400.887252 -108.0106) (xy 400.923739 -108.05815) (xy 400.953706 -108.110056) (xy 400.976642 -108.165429)
			(xy 400.992155 -108.223322) (xy 400.999978 -108.282744) (xy 401.000468 -108.312712) (xy 401.000468 -109.176312)
			(xy 400.999978 -109.20628) (xy 400.992155 -109.265702) (xy 400.976642 -109.323595) (xy 400.953706 -109.378968)
			(xy 400.923739 -109.430874) (xy 400.887252 -109.478424) (xy 400.844872 -109.520804) (xy 400.797322 -109.557291)
			(xy 400.745416 -109.587258) (xy 400.690043 -109.610194) (xy 400.63215 -109.625707) (xy 400.572728 -109.63353)
			(xy 400.512792 -109.63353) (xy 400.45337 -109.625707) (xy 400.395477 -109.610194) (xy 400.340104 -109.587258)
			(xy 400.288198 -109.557291) (xy 400.240648 -109.520804) (xy 400.198268 -109.478424) (xy 400.161781 -109.430874)
			(xy 400.131814 -109.378968) (xy 400.108878 -109.323595) (xy 400.093365 -109.265702) (xy 400.085542 -109.20628)
			(xy 400.085052 -109.176312) (xy 399.734024 -109.176312) (xy 399.734024 -110.97641) (xy 401.939252 -110.97641)
			(xy 401.939252 -110.11281) (xy 401.939742 -110.082842) (xy 401.947565 -110.02342) (xy 401.963078 -109.965527)
			(xy 401.986014 -109.910154) (xy 402.015981 -109.858248) (xy 402.052468 -109.810698) (xy 402.094848 -109.768318)
			(xy 402.142398 -109.731831) (xy 402.194304 -109.701864) (xy 402.249677 -109.678928) (xy 402.30757 -109.663415)
			(xy 402.366992 -109.655592) (xy 402.426928 -109.655592) (xy 402.48635 -109.663415) (xy 402.544243 -109.678928)
			(xy 402.599616 -109.701864) (xy 402.651522 -109.731831) (xy 402.699072 -109.768318) (xy 402.741452 -109.810698)
			(xy 402.777939 -109.858248) (xy 402.807906 -109.910154) (xy 402.830842 -109.965527) (xy 402.846355 -110.02342)
			(xy 402.854178 -110.082842) (xy 402.854668 -110.11281) (xy 402.854668 -110.97641) (xy 402.854178 -111.006378)
			(xy 402.846355 -111.0658) (xy 402.830842 -111.123693) (xy 402.807906 -111.179066) (xy 402.777939 -111.230972)
			(xy 402.741452 -111.278522) (xy 402.699072 -111.320902) (xy 402.651522 -111.357389) (xy 402.599616 -111.387356)
			(xy 402.544243 -111.410292) (xy 402.48635 -111.425805) (xy 402.426928 -111.433628) (xy 402.366992 -111.433628)
			(xy 402.30757 -111.425805) (xy 402.249677 -111.410292) (xy 402.194304 -111.387356) (xy 402.142398 -111.357389)
			(xy 402.094848 -111.320902) (xy 402.052468 -111.278522) (xy 402.015981 -111.230972) (xy 401.986014 -111.179066)
			(xy 401.963078 -111.123693) (xy 401.947565 -111.0658) (xy 401.939742 -111.006378) (xy 401.939252 -110.97641)
			(xy 399.734024 -110.97641) (xy 399.734024 -112.776508) (xy 400.085052 -112.776508) (xy 400.085052 -111.912908)
			(xy 400.085542 -111.88294) (xy 400.093365 -111.823518) (xy 400.108878 -111.765625) (xy 400.131814 -111.710252)
			(xy 400.161781 -111.658346) (xy 400.198268 -111.610796) (xy 400.240648 -111.568416) (xy 400.288198 -111.531929)
			(xy 400.340104 -111.501962) (xy 400.395477 -111.479026) (xy 400.45337 -111.463513) (xy 400.512792 -111.45569)
			(xy 400.572728 -111.45569) (xy 400.63215 -111.463513) (xy 400.690043 -111.479026) (xy 400.745416 -111.501962)
			(xy 400.797322 -111.531929) (xy 400.844872 -111.568416) (xy 400.887252 -111.610796) (xy 400.923739 -111.658346)
			(xy 400.953706 -111.710252) (xy 400.976642 -111.765625) (xy 400.992155 -111.823518) (xy 400.999978 -111.88294)
			(xy 401.000468 -111.912908) (xy 401.000468 -112.776508) (xy 400.999978 -112.806476) (xy 400.992155 -112.865898)
			(xy 400.976642 -112.923791) (xy 400.953706 -112.979164) (xy 400.923739 -113.03107) (xy 400.887252 -113.07862)
			(xy 400.844872 -113.121) (xy 400.797322 -113.157487) (xy 400.745416 -113.187454) (xy 400.690043 -113.21039)
			(xy 400.63215 -113.225903) (xy 400.572728 -113.233726) (xy 400.512792 -113.233726) (xy 400.45337 -113.225903)
			(xy 400.395477 -113.21039) (xy 400.340104 -113.187454) (xy 400.288198 -113.157487) (xy 400.240648 -113.121)
			(xy 400.198268 -113.07862) (xy 400.161781 -113.03107) (xy 400.131814 -112.979164) (xy 400.108878 -112.923791)
			(xy 400.093365 -112.865898) (xy 400.085542 -112.806476) (xy 400.085052 -112.776508) (xy 399.734024 -112.776508)
			(xy 399.734024 -113.411254) (xy 399.734467 -113.421321) (xy 399.742175 -113.43992) (xy 399.74901 -113.447322)
			(xy 403.50694 -117.204998) (xy 403.524994 -117.223748) (xy 403.55557 -117.265872) (xy 403.579192 -117.312253)
			(xy 403.595282 -117.361754) (xy 403.603443 -117.413161) (xy 403.603968 -117.439186) (xy 403.603968 -117.982238)
			(xy 403.604356 -117.992312) (xy 403.612101 -118.01091) (xy 403.618954 -118.018306) (xy 403.700996 -118.100348)
			(xy 403.707282 -118.106113) (xy 403.722662 -118.113461) (xy 403.739601 -118.11537) (xy 403.747986 -118.11381)
			(xy 403.844252 -118.092728) (xy 403.86381 -118.075456) (xy 403.868128 -118.063264) (xy 403.878677 -118.036125)
			(xy 403.906759 -117.985121) (xy 403.942263 -117.938976) (xy 403.984366 -117.89876) (xy 404.032089 -117.865407)
			(xy 404.084326 -117.839691) (xy 404.139862 -117.822209) (xy 404.19741 -117.813367) (xy 404.226522 -117.81282)
			(xy 404.255676 -117.81337) (xy 404.313304 -117.82224) (xy 404.368914 -117.839768) (xy 404.421212 -117.865549)
			(xy 404.468982 -117.898982) (xy 404.490428 -117.918738) (xy 404.50135 -117.929406) (xy 404.531322 -117.934994)
			(xy 404.631398 -117.892068) (xy 404.640322 -117.887746) (xy 404.654177 -117.873583) (xy 404.661665 -117.855238)
			(xy 404.662132 -117.845332) (xy 404.662132 -116.42471) (xy 404.661719 -116.414639) (xy 404.653992 -116.39604)
			(xy 404.647146 -116.388642) (xy 404.43658 -116.178076) (xy 404.432186 -116.17396) (xy 404.421922 -116.167675)
			(xy 404.41626 -116.16563) (xy 404.415752 -116.16563) (xy 404.390208 -116.157183) (xy 404.341603 -116.134113)
			(xy 404.296721 -116.104444) (xy 404.256453 -116.068763) (xy 404.221597 -116.027779) (xy 404.192845 -115.982304)
			(xy 404.170767 -115.933241) (xy 404.1558 -115.881563) (xy 404.148242 -115.828295) (xy 404.147782 -115.801394)
			(xy 404.148272 -115.774143) (xy 404.156029 -115.720196) (xy 404.171385 -115.667902) (xy 404.194026 -115.618325)
			(xy 404.223492 -115.572475) (xy 404.259183 -115.531286) (xy 404.300372 -115.495594) (xy 404.346222 -115.466128)
			(xy 404.395798 -115.443486) (xy 404.448092 -115.42813) (xy 404.502039 -115.420372) (xy 404.52929 -115.419886)
			(xy 404.556199 -115.420404) (xy 404.60948 -115.427979) (xy 404.661169 -115.442965) (xy 404.710239 -115.465066)
			(xy 404.755717 -115.493843) (xy 404.7967 -115.528724) (xy 404.832375 -115.569018) (xy 404.862034 -115.613925)
			(xy 404.885089 -115.662554) (xy 404.893526 -115.68811) (xy 404.893526 -115.688364) (xy 404.895504 -115.694058)
			(xy 404.901802 -115.704332) (xy 404.905972 -115.708684) (xy 405.228806 -116.031518) (xy 405.246932 -116.050286)
			(xy 405.277612 -116.092489) (xy 405.301309 -116.138973) (xy 405.317439 -116.188593) (xy 405.325603 -116.240126)
			(xy 405.326088 -116.266214) (xy 405.326088 -131.870704) (xy 405.325621 -131.896792) (xy 405.317452 -131.948325)
			(xy 405.301316 -131.997944) (xy 405.277611 -132.044424) (xy 405.246921 -132.08662) (xy 405.228806 -132.1054)
			(xy 404.65375 -132.680202) (xy 404.646924 -132.687613) (xy 404.639194 -132.706204) (xy 404.638764 -132.71627)
			(xy 404.638764 -135.985504) (xy 404.639171 -135.995576) (xy 404.646903 -136.014174) (xy 404.65375 -136.021572)
			(xy 405.54275 -136.910318) (xy 405.547138 -136.91444) (xy 405.557406 -136.920721) (xy 405.56307 -136.922764)
			(xy 405.563578 -136.922764) (xy 405.589127 -136.931198) (xy 405.63773 -136.954271) (xy 405.682611 -136.983943)
			(xy 405.722878 -137.019626) (xy 405.757733 -137.060612) (xy 405.786484 -137.106088) (xy 405.808562 -137.155151)
			(xy 405.823529 -137.20683) (xy 405.831087 -137.260099) (xy 405.831548 -137.287) (xy 405.831022 -137.314249)
			(xy 405.823267 -137.368194) (xy 405.807914 -137.420485) (xy 405.785276 -137.47006) (xy 405.755813 -137.515908)
			(xy 405.720126 -137.557097) (xy 405.67894 -137.592789) (xy 405.633095 -137.622256) (xy 405.583523 -137.6449)
			(xy 405.531233 -137.660258) (xy 405.477289 -137.668019) (xy 405.45004 -137.668508) (xy 405.423129 -137.668056)
			(xy 405.369845 -137.660472) (xy 405.318154 -137.645476) (xy 405.269083 -137.623366) (xy 405.223606 -137.594581)
			(xy 405.182624 -137.559692) (xy 405.14695 -137.519391) (xy 405.117293 -137.474478) (xy 405.09424 -137.425843)
			(xy 405.085804 -137.400284) (xy 405.085804 -137.40003) (xy 405.083822 -137.394338) (xy 405.077527 -137.384063)
			(xy 405.073358 -137.37971) (xy 404.206456 -136.512808) (xy 404.176484 -136.506712) (xy 404.16226 -136.512808)
			(xy 404.153123 -136.517005) (xy 404.138892 -136.531192) (xy 404.131188 -136.549751) (xy 404.130764 -136.559798)
			(xy 404.130764 -138.95705) (xy 404.814532 -138.95705) (xy 404.815018 -138.929799) (xy 404.822774 -138.875851)
			(xy 404.838129 -138.823556) (xy 404.860771 -138.773979) (xy 404.890237 -138.728129) (xy 404.925928 -138.686938)
			(xy 404.967119 -138.651247) (xy 405.012969 -138.621781) (xy 405.062546 -138.599139) (xy 405.114841 -138.583784)
			(xy 405.168789 -138.576028) (xy 405.223291 -138.576028) (xy 405.277239 -138.583784) (xy 405.329534 -138.599139)
			(xy 405.379111 -138.621781) (xy 405.424961 -138.651247) (xy 405.466152 -138.686938) (xy 405.501843 -138.728129)
			(xy 405.531309 -138.773979) (xy 405.553951 -138.823556) (xy 405.569306 -138.875851) (xy 405.577062 -138.929799)
			(xy 405.577548 -138.95705) (xy 405.577051 -138.98483) (xy 405.568978 -139.039801) (xy 405.553008 -139.093017)
			(xy 405.529482 -139.143351) (xy 405.498897 -139.189735) (xy 405.480774 -139.210796) (xy 405.48052 -139.21105)
			(xy 405.474217 -139.218931) (xy 405.467799 -139.238047) (xy 405.468074 -139.248134) (xy 405.473408 -139.321286)
			(xy 405.474577 -139.331363) (xy 405.48375 -139.349439) (xy 405.491188 -139.356338) (xy 405.491442 -139.356592)
			(xy 405.512467 -139.374801) (xy 405.549506 -139.416293) (xy 405.580134 -139.462721) (xy 405.603702 -139.5131)
			(xy 405.619711 -139.566366) (xy 405.627824 -139.621391) (xy 405.628348 -139.6492) (xy 405.627862 -139.676451)
			(xy 405.620106 -139.730399) (xy 405.610811 -139.762055) (xy 428.684853 -139.762055) (xy 428.684853 -139.707545)
			(xy 428.692612 -139.65359) (xy 428.70797 -139.601288) (xy 428.730616 -139.551705) (xy 428.760088 -139.50585)
			(xy 428.795787 -139.464655) (xy 428.836985 -139.428962) (xy 428.882844 -139.399495) (xy 428.93243 -139.376855)
			(xy 428.984733 -139.361502) (xy 429.038689 -139.35375) (xy 429.065944 -139.35329) (xy 429.092169 -139.353742)
			(xy 429.144126 -139.360916) (xy 429.194611 -139.375137) (xy 429.242674 -139.396136) (xy 429.287408 -139.423518)
			(xy 429.327972 -139.456768) (xy 429.346106 -139.475718) (xy 429.353645 -139.483065) (xy 429.372929 -139.491454)
			(xy 429.383444 -139.491974) (xy 429.457612 -139.491974) (xy 429.468137 -139.491514) (xy 429.487429 -139.483098)
			(xy 429.49495 -139.475718) (xy 429.513071 -139.456755) (xy 429.553639 -139.423507) (xy 429.598377 -139.396125)
			(xy 429.646441 -139.375125) (xy 429.696928 -139.360902) (xy 429.748886 -139.353724) (xy 429.775112 -139.35329)
			(xy 429.802363 -139.353781) (xy 429.856309 -139.361538) (xy 429.908602 -139.376895) (xy 429.958177 -139.399536)
			(xy 430.004026 -139.429003) (xy 430.045214 -139.464694) (xy 430.080904 -139.505884) (xy 430.11037 -139.551733)
			(xy 430.13301 -139.60131) (xy 430.148364 -139.653603) (xy 430.15612 -139.707549) (xy 430.15612 -139.71651)
			(xy 431.091846 -139.71651) (xy 431.095917 -139.660888) (xy 431.108043 -139.606451) (xy 431.127966 -139.55436)
			(xy 431.155262 -139.505725) (xy 431.189348 -139.461582) (xy 431.229497 -139.422873) (xy 431.274855 -139.390422)
			(xy 431.324455 -139.364921) (xy 431.377239 -139.346914) (xy 431.432082 -139.336784) (xy 431.487816 -139.334747)
			(xy 431.543253 -139.340847) (xy 431.59721 -139.354953) (xy 431.648539 -139.376765) (xy 431.696145 -139.405819)
			(xy 431.739013 -139.441494) (xy 431.77623 -139.483031) (xy 431.807003 -139.529544) (xy 431.830675 -139.580041)
			(xy 431.846743 -139.633448) (xy 431.854863 -139.688624) (xy 431.855372 -139.71651) (xy 431.854863 -139.744396)
			(xy 431.846743 -139.799572) (xy 431.830675 -139.852979) (xy 431.807003 -139.903476) (xy 431.77623 -139.949989)
			(xy 431.739013 -139.991526) (xy 431.696145 -140.027201) (xy 431.648539 -140.056255) (xy 431.59721 -140.078067)
			(xy 431.543253 -140.092173) (xy 431.487816 -140.098273) (xy 431.432082 -140.096236) (xy 431.377239 -140.086106)
			(xy 431.324455 -140.068099) (xy 431.274855 -140.042598) (xy 431.229497 -140.010147) (xy 431.189348 -139.971438)
			(xy 431.155262 -139.927295) (xy 431.127966 -139.87866) (xy 431.108043 -139.826569) (xy 431.095917 -139.772132)
			(xy 431.091846 -139.71651) (xy 430.15612 -139.71651) (xy 430.15612 -139.762051) (xy 430.148364 -139.815997)
			(xy 430.13301 -139.86829) (xy 430.11037 -139.917867) (xy 430.080904 -139.963716) (xy 430.045214 -140.004906)
			(xy 430.004026 -140.040597) (xy 429.958177 -140.070064) (xy 429.908602 -140.092705) (xy 429.856309 -140.108062)
			(xy 429.802363 -140.115819) (xy 429.775112 -140.116306) (xy 429.748886 -140.115885) (xy 429.696928 -140.108705)
			(xy 429.646442 -140.094478) (xy 429.598379 -140.073473) (xy 429.553646 -140.046085) (xy 429.513083 -140.01283)
			(xy 429.49495 -139.993878) (xy 429.48739 -139.986556) (xy 429.468122 -139.978152) (xy 429.457612 -139.977622)
			(xy 429.383444 -139.977622) (xy 429.372922 -139.978113) (xy 429.35363 -139.986507) (xy 429.346106 -139.993878)
			(xy 429.327957 -140.012813) (xy 429.287395 -140.046064) (xy 429.242663 -140.073449) (xy 429.194604 -140.094454)
			(xy 429.144123 -140.108683) (xy 429.092168 -140.115868) (xy 429.065944 -140.116306) (xy 429.038689 -140.11585)
			(xy 428.984733 -140.108098) (xy 428.93243 -140.092745) (xy 428.882844 -140.070105) (xy 428.836985 -140.040638)
			(xy 428.795787 -140.004945) (xy 428.760088 -139.96375) (xy 428.730616 -139.917895) (xy 428.70797 -139.868312)
			(xy 428.692612 -139.81601) (xy 428.684853 -139.762055) (xy 405.610811 -139.762055) (xy 405.604751 -139.782694)
			(xy 405.582109 -139.832271) (xy 405.552643 -139.878121) (xy 405.516952 -139.919312) (xy 405.475761 -139.955003)
			(xy 405.429911 -139.984469) (xy 405.380334 -140.007111) (xy 405.328039 -140.022466) (xy 405.274091 -140.030222)
			(xy 405.219589 -140.030222) (xy 405.165641 -140.022466) (xy 405.113346 -140.007111) (xy 405.063769 -139.984469)
			(xy 405.017919 -139.955003) (xy 404.976728 -139.919312) (xy 404.941037 -139.878121) (xy 404.911571 -139.832271)
			(xy 404.888929 -139.782694) (xy 404.873574 -139.730399) (xy 404.865818 -139.676451) (xy 404.865332 -139.6492)
			(xy 404.865864 -139.621421) (xy 404.87393 -139.566452) (xy 404.889891 -139.513237) (xy 404.91341 -139.462903)
			(xy 404.943987 -139.416516) (xy 404.962106 -139.395454) (xy 404.96236 -139.3952) (xy 404.968685 -139.387334)
			(xy 404.97509 -139.368207) (xy 404.974806 -139.358116) (xy 404.969472 -139.284964) (xy 404.968333 -139.274881)
			(xy 404.95914 -139.256806) (xy 404.951692 -139.249912) (xy 404.951438 -139.249658) (xy 404.930433 -139.231427)
			(xy 404.893393 -139.189939) (xy 404.862764 -139.143516) (xy 404.839192 -139.093141) (xy 404.823178 -139.039879)
			(xy 404.81506 -138.984858) (xy 404.814532 -138.95705) (xy 404.130764 -138.95705) (xy 404.130764 -141.9352)
			(xy 404.824182 -141.9352) (xy 404.828253 -141.879578) (xy 404.840379 -141.825141) (xy 404.860302 -141.77305)
			(xy 404.887598 -141.724415) (xy 404.921684 -141.680272) (xy 404.961833 -141.641563) (xy 405.007191 -141.609112)
			(xy 405.056791 -141.583611) (xy 405.109575 -141.565604) (xy 405.164418 -141.555474) (xy 405.220152 -141.553437)
			(xy 405.275589 -141.559537) (xy 405.329546 -141.573643) (xy 405.380875 -141.595455) (xy 405.428481 -141.624509)
			(xy 405.471349 -141.660184) (xy 405.508566 -141.701721) (xy 405.539339 -141.748234) (xy 405.563011 -141.798731)
			(xy 405.579079 -141.852138) (xy 405.587199 -141.907314) (xy 405.587708 -141.9352) (xy 405.587199 -141.963086)
			(xy 405.579079 -142.018262) (xy 405.563011 -142.071669) (xy 405.539339 -142.122166) (xy 405.508566 -142.168679)
			(xy 405.471349 -142.210216) (xy 405.428481 -142.245891) (xy 405.380875 -142.274945) (xy 405.329546 -142.296757)
			(xy 405.275589 -142.310863) (xy 405.220152 -142.316963) (xy 405.164418 -142.314926) (xy 405.109575 -142.304796)
			(xy 405.056791 -142.286789) (xy 405.007191 -142.261288) (xy 404.961833 -142.228837) (xy 404.921684 -142.190128)
			(xy 404.887598 -142.145985) (xy 404.860302 -142.09735) (xy 404.840379 -142.045259) (xy 404.828253 -141.990822)
			(xy 404.824182 -141.9352) (xy 404.130764 -141.9352) (xy 404.130764 -142.9512) (xy 404.840438 -142.9512)
			(xy 404.844509 -142.895578) (xy 404.856635 -142.841141) (xy 404.876558 -142.78905) (xy 404.903854 -142.740415)
			(xy 404.93794 -142.696272) (xy 404.978089 -142.657563) (xy 405.023447 -142.625112) (xy 405.073047 -142.599611)
			(xy 405.125831 -142.581604) (xy 405.180674 -142.571474) (xy 405.236408 -142.569437) (xy 405.291845 -142.575537)
			(xy 405.345802 -142.589643) (xy 405.397131 -142.611455) (xy 405.444737 -142.640509) (xy 405.487605 -142.676184)
			(xy 405.524822 -142.717721) (xy 405.555595 -142.764234) (xy 405.579267 -142.814731) (xy 405.595335 -142.868138)
			(xy 405.603455 -142.923314) (xy 405.603964 -142.9512) (xy 405.603455 -142.979086) (xy 405.595335 -143.034262)
			(xy 405.579267 -143.087669) (xy 405.555595 -143.138166) (xy 405.524822 -143.184679) (xy 405.487605 -143.226216)
			(xy 405.444737 -143.261891) (xy 405.397131 -143.290945) (xy 405.345802 -143.312757) (xy 405.291845 -143.326863)
			(xy 405.236408 -143.332963) (xy 405.180674 -143.330926) (xy 405.125831 -143.320796) (xy 405.073047 -143.302789)
			(xy 405.023447 -143.277288) (xy 404.978089 -143.244837) (xy 404.93794 -143.206128) (xy 404.903854 -143.161985)
			(xy 404.876558 -143.11335) (xy 404.856635 -143.061259) (xy 404.844509 -143.006822) (xy 404.840438 -142.9512)
			(xy 404.130764 -142.9512) (xy 404.130764 -143.48714) (xy 414.899348 -143.48714) (xy 414.899348 -142.62354)
			(xy 414.899838 -142.593556) (xy 414.907666 -142.5341) (xy 414.923187 -142.476175) (xy 414.946136 -142.420771)
			(xy 414.97612 -142.368837) (xy 415.012626 -142.321261) (xy 415.055031 -142.278856) (xy 415.102607 -142.24235)
			(xy 415.154541 -142.212366) (xy 415.209945 -142.189417) (xy 415.26787 -142.173896) (xy 415.327326 -142.166068)
			(xy 415.387294 -142.166068) (xy 415.44675 -142.173896) (xy 415.504675 -142.189417) (xy 415.560079 -142.212366)
			(xy 415.612013 -142.24235) (xy 415.659589 -142.278856) (xy 415.701994 -142.321261) (xy 415.7385 -142.368837)
			(xy 415.768484 -142.420771) (xy 415.791433 -142.476175) (xy 415.806954 -142.5341) (xy 415.814782 -142.593556)
			(xy 415.815272 -142.62354) (xy 415.815272 -143.48714) (xy 415.814782 -143.517124) (xy 415.806954 -143.57658)
			(xy 415.791433 -143.634505) (xy 415.768484 -143.689909) (xy 415.7385 -143.741843) (xy 415.701994 -143.789419)
			(xy 415.659589 -143.831824) (xy 415.612013 -143.86833) (xy 415.560079 -143.898314) (xy 415.504675 -143.921263)
			(xy 415.44675 -143.936784) (xy 415.387294 -143.944612) (xy 415.327326 -143.944612) (xy 415.26787 -143.936784)
			(xy 415.209945 -143.921263) (xy 415.154541 -143.898314) (xy 415.102607 -143.86833) (xy 415.055031 -143.831824)
			(xy 415.012626 -143.789419) (xy 414.97612 -143.741843) (xy 414.946136 -143.689909) (xy 414.923187 -143.634505)
			(xy 414.907666 -143.57658) (xy 414.899838 -143.517124) (xy 414.899348 -143.48714) (xy 404.130764 -143.48714)
			(xy 404.130764 -144.272) (xy 404.687022 -144.272) (xy 404.691093 -144.216378) (xy 404.703219 -144.161941)
			(xy 404.723142 -144.10985) (xy 404.750438 -144.061215) (xy 404.784524 -144.017072) (xy 404.824673 -143.978363)
			(xy 404.870031 -143.945912) (xy 404.919631 -143.920411) (xy 404.972415 -143.902404) (xy 405.027258 -143.892274)
			(xy 405.082992 -143.890237) (xy 405.138429 -143.896337) (xy 405.192386 -143.910443) (xy 405.243715 -143.932255)
			(xy 405.291321 -143.961309) (xy 405.334189 -143.996984) (xy 405.371406 -144.038521) (xy 405.402179 -144.085034)
			(xy 405.425851 -144.135531) (xy 405.441919 -144.188938) (xy 405.450039 -144.244114) (xy 405.450548 -144.272)
			(xy 405.450039 -144.299886) (xy 405.441919 -144.355062) (xy 405.425851 -144.408469) (xy 405.402179 -144.458966)
			(xy 405.371406 -144.505479) (xy 405.334189 -144.547016) (xy 405.291321 -144.582691) (xy 405.243715 -144.611745)
			(xy 405.192386 -144.633557) (xy 405.138429 -144.647663) (xy 405.082992 -144.653763) (xy 405.027258 -144.651726)
			(xy 404.972415 -144.641596) (xy 404.919631 -144.623589) (xy 404.870031 -144.598088) (xy 404.824673 -144.565637)
			(xy 404.784524 -144.526928) (xy 404.750438 -144.482785) (xy 404.723142 -144.43415) (xy 404.703219 -144.382059)
			(xy 404.691093 -144.327622) (xy 404.687022 -144.272) (xy 404.130764 -144.272) (xy 404.130764 -145.287238)
			(xy 413.045148 -145.287238) (xy 413.045148 -144.423638) (xy 413.045638 -144.393654) (xy 413.053466 -144.334198)
			(xy 413.068987 -144.276273) (xy 413.091936 -144.220869) (xy 413.12192 -144.168935) (xy 413.158426 -144.121359)
			(xy 413.200831 -144.078954) (xy 413.248407 -144.042448) (xy 413.300341 -144.012464) (xy 413.355745 -143.989515)
			(xy 413.41367 -143.973994) (xy 413.473126 -143.966166) (xy 413.533094 -143.966166) (xy 413.59255 -143.973994)
			(xy 413.650475 -143.989515) (xy 413.705879 -144.012464) (xy 413.757813 -144.042448) (xy 413.805389 -144.078954)
			(xy 413.847794 -144.121359) (xy 413.8843 -144.168935) (xy 413.914284 -144.220869) (xy 413.937233 -144.276273)
			(xy 413.952754 -144.334198) (xy 413.960582 -144.393654) (xy 413.961072 -144.423638) (xy 413.961072 -145.287238)
			(xy 413.960582 -145.317222) (xy 413.952754 -145.376678) (xy 413.937233 -145.434603) (xy 413.914284 -145.490007)
			(xy 413.8843 -145.541941) (xy 413.847794 -145.589517) (xy 413.805389 -145.631922) (xy 413.757813 -145.668428)
			(xy 413.705879 -145.698412) (xy 413.650475 -145.721361) (xy 413.59255 -145.736882) (xy 413.533094 -145.74471)
			(xy 413.473126 -145.74471) (xy 413.41367 -145.736882) (xy 413.355745 -145.721361) (xy 413.300341 -145.698412)
			(xy 413.248407 -145.668428) (xy 413.200831 -145.631922) (xy 413.158426 -145.589517) (xy 413.12192 -145.541941)
			(xy 413.091936 -145.490007) (xy 413.068987 -145.434603) (xy 413.053466 -145.376678) (xy 413.045638 -145.317222)
			(xy 413.045148 -145.287238) (xy 404.130764 -145.287238) (xy 404.130764 -147.087336) (xy 414.899348 -147.087336)
			(xy 414.899348 -146.223736) (xy 414.899838 -146.193752) (xy 414.907666 -146.134296) (xy 414.923187 -146.076371)
			(xy 414.946136 -146.020967) (xy 414.97612 -145.969033) (xy 415.012626 -145.921457) (xy 415.055031 -145.879052)
			(xy 415.102607 -145.842546) (xy 415.154541 -145.812562) (xy 415.209945 -145.789613) (xy 415.26787 -145.774092)
			(xy 415.327326 -145.766264) (xy 415.387294 -145.766264) (xy 415.44675 -145.774092) (xy 415.504675 -145.789613)
			(xy 415.560079 -145.812562) (xy 415.612013 -145.842546) (xy 415.659589 -145.879052) (xy 415.701994 -145.921457)
			(xy 415.7385 -145.969033) (xy 415.768484 -146.020967) (xy 415.791433 -146.076371) (xy 415.806954 -146.134296)
			(xy 415.814782 -146.193752) (xy 415.815272 -146.223736) (xy 415.815272 -147.087336) (xy 415.814782 -147.11732)
			(xy 415.806954 -147.176776) (xy 415.791433 -147.234701) (xy 415.768484 -147.290105) (xy 415.7385 -147.342039)
			(xy 415.701994 -147.389615) (xy 415.659589 -147.43202) (xy 415.612013 -147.468526) (xy 415.560079 -147.49851)
			(xy 415.504675 -147.521459) (xy 415.44675 -147.53698) (xy 415.387294 -147.544808) (xy 415.327326 -147.544808)
			(xy 415.26787 -147.53698) (xy 415.209945 -147.521459) (xy 415.154541 -147.49851) (xy 415.102607 -147.468526)
			(xy 415.055031 -147.43202) (xy 415.012626 -147.389615) (xy 414.97612 -147.342039) (xy 414.946136 -147.290105)
			(xy 414.923187 -147.234701) (xy 414.907666 -147.176776) (xy 414.899838 -147.11732) (xy 414.899348 -147.087336)
			(xy 404.130764 -147.087336) (xy 404.130764 -148.887434) (xy 413.045148 -148.887434) (xy 413.045148 -148.023834)
			(xy 413.045638 -147.99385) (xy 413.053466 -147.934394) (xy 413.068987 -147.876469) (xy 413.091936 -147.821065)
			(xy 413.12192 -147.769131) (xy 413.158426 -147.721555) (xy 413.200831 -147.67915) (xy 413.248407 -147.642644)
			(xy 413.300341 -147.61266) (xy 413.355745 -147.589711) (xy 413.41367 -147.57419) (xy 413.473126 -147.566362)
			(xy 413.533094 -147.566362) (xy 413.59255 -147.57419) (xy 413.650475 -147.589711) (xy 413.705879 -147.61266)
			(xy 413.757813 -147.642644) (xy 413.805389 -147.67915) (xy 413.847794 -147.721555) (xy 413.8843 -147.769131)
			(xy 413.914284 -147.821065) (xy 413.937233 -147.876469) (xy 413.952754 -147.934394) (xy 413.960582 -147.99385)
			(xy 413.961072 -148.023834) (xy 413.961072 -148.887434) (xy 413.960582 -148.917418) (xy 413.952754 -148.976874)
			(xy 413.937233 -149.034799) (xy 413.914284 -149.090203) (xy 413.8843 -149.142137) (xy 413.847794 -149.189713)
			(xy 413.805389 -149.232118) (xy 413.757813 -149.268624) (xy 413.705879 -149.298608) (xy 413.650475 -149.321557)
			(xy 413.59255 -149.337078) (xy 413.533094 -149.344906) (xy 413.473126 -149.344906) (xy 413.41367 -149.337078)
			(xy 413.355745 -149.321557) (xy 413.300341 -149.298608) (xy 413.248407 -149.268624) (xy 413.200831 -149.232118)
			(xy 413.158426 -149.189713) (xy 413.12192 -149.142137) (xy 413.091936 -149.090203) (xy 413.068987 -149.034799)
			(xy 413.053466 -148.976874) (xy 413.045638 -148.917418) (xy 413.045148 -148.887434) (xy 404.130764 -148.887434)
			(xy 404.130764 -150.687278) (xy 414.899348 -150.687278) (xy 414.899348 -149.823678) (xy 414.899838 -149.793694)
			(xy 414.907666 -149.734238) (xy 414.923187 -149.676313) (xy 414.946136 -149.620909) (xy 414.97612 -149.568975)
			(xy 415.012626 -149.521399) (xy 415.055031 -149.478994) (xy 415.102607 -149.442488) (xy 415.154541 -149.412504)
			(xy 415.209945 -149.389555) (xy 415.26787 -149.374034) (xy 415.327326 -149.366206) (xy 415.387294 -149.366206)
			(xy 415.44675 -149.374034) (xy 415.504675 -149.389555) (xy 415.560079 -149.412504) (xy 415.612013 -149.442488)
			(xy 415.659589 -149.478994) (xy 415.701994 -149.521399) (xy 415.7385 -149.568975) (xy 415.768484 -149.620909)
			(xy 415.791433 -149.676313) (xy 415.806954 -149.734238) (xy 415.814782 -149.793694) (xy 415.815272 -149.823678)
			(xy 415.815272 -150.687278) (xy 415.814782 -150.717262) (xy 415.806954 -150.776718) (xy 415.791433 -150.834643)
			(xy 415.768484 -150.890047) (xy 415.7385 -150.941981) (xy 415.701994 -150.989557) (xy 415.659589 -151.031962)
			(xy 415.612013 -151.068468) (xy 415.560079 -151.098452) (xy 415.504675 -151.121401) (xy 415.44675 -151.136922)
			(xy 415.387294 -151.14475) (xy 415.327326 -151.14475) (xy 415.26787 -151.136922) (xy 415.209945 -151.121401)
			(xy 415.154541 -151.098452) (xy 415.102607 -151.068468) (xy 415.055031 -151.031962) (xy 415.012626 -150.989557)
			(xy 414.97612 -150.941981) (xy 414.946136 -150.890047) (xy 414.923187 -150.834643) (xy 414.907666 -150.776718)
			(xy 414.899838 -150.717262) (xy 414.899348 -150.687278) (xy 404.130764 -150.687278) (xy 404.130764 -152.487376)
			(xy 413.045148 -152.487376) (xy 413.045148 -151.623776) (xy 413.045638 -151.593792) (xy 413.053466 -151.534336)
			(xy 413.068987 -151.476411) (xy 413.091936 -151.421007) (xy 413.12192 -151.369073) (xy 413.158426 -151.321497)
			(xy 413.200831 -151.279092) (xy 413.248407 -151.242586) (xy 413.300341 -151.212602) (xy 413.355745 -151.189653)
			(xy 413.41367 -151.174132) (xy 413.473126 -151.166304) (xy 413.533094 -151.166304) (xy 413.59255 -151.174132)
			(xy 413.650475 -151.189653) (xy 413.705879 -151.212602) (xy 413.757813 -151.242586) (xy 413.805389 -151.279092)
			(xy 413.847794 -151.321497) (xy 413.8843 -151.369073) (xy 413.914284 -151.421007) (xy 413.937233 -151.476411)
			(xy 413.952754 -151.534336) (xy 413.960582 -151.593792) (xy 413.961072 -151.623776) (xy 413.961072 -152.487376)
			(xy 413.960582 -152.51736) (xy 413.952754 -152.576816) (xy 413.937233 -152.634741) (xy 413.914284 -152.690145)
			(xy 413.8843 -152.742079) (xy 413.847794 -152.789655) (xy 413.805389 -152.83206) (xy 413.757813 -152.868566)
			(xy 413.705879 -152.89855) (xy 413.650475 -152.921499) (xy 413.59255 -152.93702) (xy 413.533094 -152.944848)
			(xy 413.473126 -152.944848) (xy 413.41367 -152.93702) (xy 413.355745 -152.921499) (xy 413.300341 -152.89855)
			(xy 413.248407 -152.868566) (xy 413.200831 -152.83206) (xy 413.158426 -152.789655) (xy 413.12192 -152.742079)
			(xy 413.091936 -152.690145) (xy 413.068987 -152.634741) (xy 413.053466 -152.576816) (xy 413.045638 -152.51736)
			(xy 413.045148 -152.487376) (xy 404.130764 -152.487376) (xy 404.130764 -154.28722) (xy 414.899348 -154.28722)
			(xy 414.899348 -153.42362) (xy 414.899838 -153.393636) (xy 414.907666 -153.33418) (xy 414.923187 -153.276255)
			(xy 414.946136 -153.220851) (xy 414.97612 -153.168917) (xy 415.012626 -153.121341) (xy 415.055031 -153.078936)
			(xy 415.102607 -153.04243) (xy 415.154541 -153.012446) (xy 415.209945 -152.989497) (xy 415.26787 -152.973976)
			(xy 415.327326 -152.966148) (xy 415.387294 -152.966148) (xy 415.44675 -152.973976) (xy 415.504675 -152.989497)
			(xy 415.560079 -153.012446) (xy 415.612013 -153.04243) (xy 415.659589 -153.078936) (xy 415.701994 -153.121341)
			(xy 415.7385 -153.168917) (xy 415.768484 -153.220851) (xy 415.791433 -153.276255) (xy 415.806954 -153.33418)
			(xy 415.814782 -153.393636) (xy 415.815272 -153.42362) (xy 415.815272 -154.28722) (xy 415.814782 -154.317204)
			(xy 415.806954 -154.37666) (xy 415.791433 -154.434585) (xy 415.768484 -154.489989) (xy 415.7385 -154.541923)
			(xy 415.701994 -154.589499) (xy 415.659589 -154.631904) (xy 415.612013 -154.66841) (xy 415.560079 -154.698394)
			(xy 415.504675 -154.721343) (xy 415.44675 -154.736864) (xy 415.387294 -154.744692) (xy 415.327326 -154.744692)
			(xy 415.26787 -154.736864) (xy 415.209945 -154.721343) (xy 415.154541 -154.698394) (xy 415.102607 -154.66841)
			(xy 415.055031 -154.631904) (xy 415.012626 -154.589499) (xy 414.97612 -154.541923) (xy 414.946136 -154.489989)
			(xy 414.923187 -154.434585) (xy 414.907666 -154.37666) (xy 414.899838 -154.317204) (xy 414.899348 -154.28722)
			(xy 404.130764 -154.28722) (xy 404.130764 -156.087318) (xy 413.045148 -156.087318) (xy 413.045148 -155.223718)
			(xy 413.045638 -155.193734) (xy 413.053466 -155.134278) (xy 413.068987 -155.076353) (xy 413.091936 -155.020949)
			(xy 413.12192 -154.969015) (xy 413.158426 -154.921439) (xy 413.200831 -154.879034) (xy 413.248407 -154.842528)
			(xy 413.300341 -154.812544) (xy 413.355745 -154.789595) (xy 413.41367 -154.774074) (xy 413.473126 -154.766246)
			(xy 413.533094 -154.766246) (xy 413.59255 -154.774074) (xy 413.650475 -154.789595) (xy 413.705879 -154.812544)
			(xy 413.757813 -154.842528) (xy 413.805389 -154.879034) (xy 413.847794 -154.921439) (xy 413.8843 -154.969015)
			(xy 413.914284 -155.020949) (xy 413.937233 -155.076353) (xy 413.952754 -155.134278) (xy 413.960582 -155.193734)
			(xy 413.961072 -155.223718) (xy 413.961072 -156.087318) (xy 413.960582 -156.117302) (xy 413.952754 -156.176758)
			(xy 413.937233 -156.234683) (xy 413.914284 -156.290087) (xy 413.8843 -156.342021) (xy 413.847794 -156.389597)
			(xy 413.805389 -156.432002) (xy 413.757813 -156.468508) (xy 413.705879 -156.498492) (xy 413.650475 -156.521441)
			(xy 413.59255 -156.536962) (xy 413.533094 -156.54479) (xy 413.473126 -156.54479) (xy 413.41367 -156.536962)
			(xy 413.355745 -156.521441) (xy 413.300341 -156.498492) (xy 413.248407 -156.468508) (xy 413.200831 -156.432002)
			(xy 413.158426 -156.389597) (xy 413.12192 -156.342021) (xy 413.091936 -156.290087) (xy 413.068987 -156.234683)
			(xy 413.053466 -156.176758) (xy 413.045638 -156.117302) (xy 413.045148 -156.087318) (xy 404.130764 -156.087318)
			(xy 404.130764 -159.53613) (xy 404.131157 -159.546203) (xy 404.138898 -159.564802) (xy 404.14575 -159.572198)
			(xy 410.902658 -166.328852) (xy 410.907052 -166.332967) (xy 410.917316 -166.339253) (xy 410.922978 -166.341298)
			(xy 410.923486 -166.341298) (xy 410.94872 -166.349651) (xy 410.996772 -166.372373) (xy 411.041206 -166.401544)
			(xy 411.081161 -166.436599) (xy 411.115866 -166.476859) (xy 411.144647 -166.521546) (xy 411.166949 -166.569794)
			(xy 411.182339 -166.620671) (xy 411.186884 -166.64686) (xy 411.18917 -166.661084) (xy 411.207712 -166.682928)
			(xy 411.30728 -166.71544) (xy 411.316308 -166.718065) (xy 411.335074 -166.717096) (xy 411.352223 -166.709411)
			(xy 411.359096 -166.702994) (xy 411.449266 -166.612824) (xy 411.453387 -166.608435) (xy 411.459669 -166.598168)
			(xy 411.461712 -166.592504) (xy 411.461712 -166.591996) (xy 411.467098 -166.575489) (xy 411.480453 -166.543435)
			(xy 411.488382 -166.527988) (xy 411.491099 -166.522465) (xy 411.494055 -166.510519) (xy 411.494224 -166.504366)
			(xy 411.494224 -164.68852) (xy 411.493808 -164.678449) (xy 411.486083 -164.65985) (xy 411.479238 -164.652452)
			(xy 410.331412 -163.50488) (xy 410.313404 -163.486087) (xy 410.28282 -163.443976) (xy 410.259188 -163.397606)
			(xy 410.243088 -163.348113) (xy 410.234915 -163.296714) (xy 410.234384 -163.270692) (xy 410.234384 -161.129218)
			(xy 410.233953 -161.119149) (xy 410.226237 -161.100551) (xy 410.219398 -161.09315) (xy 409.857956 -160.731962)
			(xy 409.83993 -160.713186) (xy 409.80935 -160.671069) (xy 409.785723 -160.624695) (xy 409.769627 -160.575199)
			(xy 409.761457 -160.523797) (xy 409.760928 -160.497774) (xy 409.760928 -157.24632) (xy 409.760732 -157.24017)
			(xy 409.757781 -157.228229) (xy 409.755086 -157.222698) (xy 409.741244 -157.195174) (xy 409.721682 -157.136756)
			(xy 409.711752 -157.075955) (xy 409.711144 -157.045152) (xy 409.71163 -157.017901) (xy 409.719386 -156.963953)
			(xy 409.734741 -156.911658) (xy 409.757383 -156.862081) (xy 409.786849 -156.816231) (xy 409.82254 -156.77504)
			(xy 409.863731 -156.739349) (xy 409.909581 -156.709883) (xy 409.959158 -156.687241) (xy 410.011453 -156.671886)
			(xy 410.065401 -156.66413) (xy 410.119903 -156.66413) (xy 410.173851 -156.671886) (xy 410.226146 -156.687241)
			(xy 410.275723 -156.709883) (xy 410.321573 -156.739349) (xy 410.362764 -156.77504) (xy 410.398455 -156.816231)
			(xy 410.427921 -156.862081) (xy 410.450563 -156.911658) (xy 410.465918 -156.963953) (xy 410.473674 -157.017901)
			(xy 410.47416 -157.045152) (xy 410.726634 -157.045152) (xy 410.730705 -156.98953) (xy 410.742831 -156.935093)
			(xy 410.762754 -156.883002) (xy 410.79005 -156.834367) (xy 410.824136 -156.790224) (xy 410.864285 -156.751515)
			(xy 410.909643 -156.719064) (xy 410.959243 -156.693563) (xy 411.012027 -156.675556) (xy 411.06687 -156.665426)
			(xy 411.122604 -156.663389) (xy 411.178041 -156.669489) (xy 411.231998 -156.683595) (xy 411.283327 -156.705407)
			(xy 411.330933 -156.734461) (xy 411.373801 -156.770136) (xy 411.411018 -156.811673) (xy 411.441791 -156.858186)
			(xy 411.465463 -156.908683) (xy 411.481531 -156.96209) (xy 411.489651 -157.017266) (xy 411.49016 -157.045152)
			(xy 411.489651 -157.073038) (xy 411.481531 -157.128214) (xy 411.465463 -157.181621) (xy 411.441791 -157.232118)
			(xy 411.411018 -157.278631) (xy 411.373801 -157.320168) (xy 411.330933 -157.355843) (xy 411.283327 -157.384897)
			(xy 411.231998 -157.406709) (xy 411.178041 -157.420815) (xy 411.122604 -157.426915) (xy 411.06687 -157.424878)
			(xy 411.012027 -157.414748) (xy 410.959243 -157.396741) (xy 410.909643 -157.37124) (xy 410.864285 -157.338789)
			(xy 410.824136 -157.30008) (xy 410.79005 -157.255937) (xy 410.762754 -157.207302) (xy 410.742831 -157.155211)
			(xy 410.730705 -157.100774) (xy 410.726634 -157.045152) (xy 410.47416 -157.045152) (xy 410.473569 -157.075956)
			(xy 410.463636 -157.136757) (xy 410.444055 -157.19517) (xy 410.430218 -157.222698) (xy 410.427505 -157.228223)
			(xy 410.424547 -157.240167) (xy 410.424376 -157.24632) (xy 410.424376 -158.219648) (xy 429.482248 -158.219648)
			(xy 429.486319 -158.164026) (xy 429.498445 -158.109589) (xy 429.518368 -158.057498) (xy 429.545664 -158.008863)
			(xy 429.57975 -157.96472) (xy 429.619899 -157.926011) (xy 429.665257 -157.89356) (xy 429.714857 -157.868059)
			(xy 429.767641 -157.850052) (xy 429.822484 -157.839922) (xy 429.878218 -157.837885) (xy 429.933655 -157.843985)
			(xy 429.987612 -157.858091) (xy 430.038941 -157.879903) (xy 430.086547 -157.908957) (xy 430.129415 -157.944632)
			(xy 430.166632 -157.986169) (xy 430.197405 -158.032682) (xy 430.221077 -158.083179) (xy 430.237145 -158.136586)
			(xy 430.245265 -158.191762) (xy 430.245774 -158.219648) (xy 430.245265 -158.247534) (xy 430.237145 -158.30271)
			(xy 430.221077 -158.356117) (xy 430.197405 -158.406614) (xy 430.166632 -158.453127) (xy 430.129415 -158.494664)
			(xy 430.086547 -158.530339) (xy 430.038941 -158.559393) (xy 429.987612 -158.581205) (xy 429.933655 -158.595311)
			(xy 429.878218 -158.601411) (xy 429.822484 -158.599374) (xy 429.767641 -158.589244) (xy 429.714857 -158.571237)
			(xy 429.665257 -158.545736) (xy 429.619899 -158.513285) (xy 429.57975 -158.474576) (xy 429.545664 -158.430433)
			(xy 429.518368 -158.381798) (xy 429.498445 -158.329707) (xy 429.486319 -158.27527) (xy 429.482248 -158.219648)
			(xy 410.424376 -158.219648) (xy 410.424376 -160.1851) (xy 418.188915 -160.1851) (xy 418.192871 -160.093241)
			(xy 418.204708 -160.002062) (xy 418.22434 -159.912238) (xy 418.251621 -159.824435) (xy 418.286349 -159.739302)
			(xy 418.328267 -159.657469) (xy 418.377065 -159.579542) (xy 418.43238 -159.506099) (xy 418.493805 -159.437683)
			(xy 418.560884 -159.374801) (xy 418.633119 -159.317918) (xy 418.709978 -159.267455) (xy 418.79089 -159.223786)
			(xy 418.875256 -159.187234) (xy 418.962452 -159.15807) (xy 419.051833 -159.13651) (xy 419.142736 -159.122714)
			(xy 419.234489 -159.116782) (xy 419.326411 -159.118761) (xy 419.417824 -159.128634) (xy 419.508049 -159.146329)
			(xy 419.59642 -159.171714) (xy 419.68228 -159.204602) (xy 419.746243 -159.235648) (xy 429.639982 -159.235648)
			(xy 429.644053 -159.180026) (xy 429.656179 -159.125589) (xy 429.676102 -159.073498) (xy 429.703398 -159.024863)
			(xy 429.737484 -158.98072) (xy 429.777633 -158.942011) (xy 429.822991 -158.90956) (xy 429.872591 -158.884059)
			(xy 429.925375 -158.866052) (xy 429.980218 -158.855922) (xy 430.035952 -158.853885) (xy 430.091389 -158.859985)
			(xy 430.145346 -158.874091) (xy 430.196675 -158.895903) (xy 430.244281 -158.924957) (xy 430.287149 -158.960632)
			(xy 430.324366 -159.002169) (xy 430.355139 -159.048682) (xy 430.378811 -159.099179) (xy 430.394879 -159.152586)
			(xy 430.402999 -159.207762) (xy 430.403508 -159.235648) (xy 430.402999 -159.263534) (xy 430.394879 -159.31871)
			(xy 430.378811 -159.372117) (xy 430.355139 -159.422614) (xy 430.324366 -159.469127) (xy 430.287149 -159.510664)
			(xy 430.244281 -159.546339) (xy 430.196675 -159.575393) (xy 430.145346 -159.597205) (xy 430.091389 -159.611311)
			(xy 430.035952 -159.617411) (xy 429.980218 -159.615374) (xy 429.925375 -159.605244) (xy 429.872591 -159.587237)
			(xy 429.822991 -159.561736) (xy 429.777633 -159.529285) (xy 429.737484 -159.490576) (xy 429.703398 -159.446433)
			(xy 429.676102 -159.397798) (xy 429.656179 -159.345707) (xy 429.644053 -159.29127) (xy 429.639982 -159.235648)
			(xy 419.746243 -159.235648) (xy 419.764996 -159.24475) (xy 419.843954 -159.291859) (xy 419.918571 -159.345582)
			(xy 419.988292 -159.40552) (xy 420.052603 -159.47123) (xy 420.111028 -159.542226) (xy 420.163133 -159.61798)
			(xy 420.208532 -159.697934) (xy 420.246891 -159.781494) (xy 420.277924 -159.868043) (xy 420.301402 -159.956939)
			(xy 420.317152 -160.047524) (xy 420.325056 -160.139128) (xy 420.32555 -160.1851) (xy 420.325056 -160.231072)
			(xy 420.317152 -160.322676) (xy 420.301402 -160.413261) (xy 420.277924 -160.502157) (xy 420.246891 -160.588706)
			(xy 420.208532 -160.672266) (xy 420.163133 -160.75222) (xy 420.111028 -160.827974) (xy 420.052603 -160.89897)
			(xy 419.988292 -160.96468) (xy 419.918571 -161.024618) (xy 419.843954 -161.078341) (xy 419.764996 -161.12545)
			(xy 419.68228 -161.165598) (xy 419.59642 -161.198486) (xy 419.508049 -161.223871) (xy 419.417824 -161.241566)
			(xy 419.326411 -161.251439) (xy 419.234489 -161.253418) (xy 419.142736 -161.247486) (xy 419.051833 -161.23369)
			(xy 418.962452 -161.21213) (xy 418.875256 -161.182966) (xy 418.79089 -161.146414) (xy 418.709978 -161.102745)
			(xy 418.633119 -161.052282) (xy 418.560884 -160.995399) (xy 418.493805 -160.932517) (xy 418.43238 -160.864101)
			(xy 418.377065 -160.790658) (xy 418.328267 -160.712731) (xy 418.286349 -160.630898) (xy 418.251621 -160.545765)
			(xy 418.22434 -160.457962) (xy 418.204708 -160.368138) (xy 418.192871 -160.276959) (xy 418.188915 -160.1851)
			(xy 410.424376 -160.1851) (xy 410.424376 -160.33877) (xy 410.424797 -160.34884) (xy 410.432518 -160.367439)
			(xy 410.439362 -160.374838) (xy 410.800804 -160.736026) (xy 410.818818 -160.754814) (xy 410.8494 -160.796926)
			(xy 410.873031 -160.843298) (xy 410.88913 -160.892791) (xy 410.897302 -160.944192) (xy 410.897832 -160.970214)
			(xy 410.897832 -163.111688) (xy 410.898255 -163.121758) (xy 410.905976 -163.140356) (xy 410.912818 -163.147756)
			(xy 411.151123 -163.386008) (xy 412.932878 -163.386008) (xy 412.936949 -163.330386) (xy 412.949075 -163.275949)
			(xy 412.968998 -163.223858) (xy 412.996294 -163.175223) (xy 413.03038 -163.13108) (xy 413.070529 -163.092371)
			(xy 413.115887 -163.05992) (xy 413.165487 -163.034419) (xy 413.218271 -163.016412) (xy 413.273114 -163.006282)
			(xy 413.328848 -163.004245) (xy 413.384285 -163.010345) (xy 413.438242 -163.024451) (xy 413.489571 -163.046263)
			(xy 413.537177 -163.075317) (xy 413.580045 -163.110992) (xy 413.617262 -163.152529) (xy 413.648035 -163.199042)
			(xy 413.671707 -163.249539) (xy 413.687775 -163.302946) (xy 413.695895 -163.358122) (xy 413.696404 -163.386008)
			(xy 413.695895 -163.413894) (xy 413.687775 -163.46907) (xy 413.671707 -163.522477) (xy 413.648035 -163.572974)
			(xy 413.617262 -163.619487) (xy 413.580045 -163.661024) (xy 413.537177 -163.696699) (xy 413.489571 -163.725753)
			(xy 413.438242 -163.747565) (xy 413.384285 -163.761671) (xy 413.328848 -163.767771) (xy 413.273114 -163.765734)
			(xy 413.218271 -163.755604) (xy 413.165487 -163.737597) (xy 413.115887 -163.712096) (xy 413.070529 -163.679645)
			(xy 413.03038 -163.640936) (xy 412.996294 -163.596793) (xy 412.968998 -163.548158) (xy 412.949075 -163.496067)
			(xy 412.936949 -163.44163) (xy 412.932878 -163.386008) (xy 411.151123 -163.386008) (xy 412.060644 -164.295328)
			(xy 412.078666 -164.314108) (xy 412.109246 -164.356224) (xy 412.132874 -164.402598) (xy 412.148971 -164.452092)
			(xy 412.157142 -164.503493) (xy 412.157672 -164.529516) (xy 412.157672 -166.504366) (xy 412.157873 -166.510515)
			(xy 412.160821 -166.522456) (xy 412.163514 -166.527988) (xy 412.177351 -166.555514) (xy 412.196915 -166.613931)
			(xy 412.206847 -166.674731) (xy 412.207456 -166.705534) (xy 412.207017 -166.732446) (xy 412.199435 -166.785733)
			(xy 412.18444 -166.837425) (xy 412.16233 -166.886498) (xy 412.133544 -166.931977) (xy 412.098652 -166.972959)
			(xy 412.058348 -167.008632) (xy 412.013431 -167.038287) (xy 411.964792 -167.061337) (xy 411.939232 -167.06977)
			(xy 411.938978 -167.06977) (xy 411.933286 -167.071751) (xy 411.92301 -167.078046) (xy 411.918658 -167.082216)
			(xy 409.51531 -169.48531) (xy 409.508474 -169.492714) (xy 409.500752 -169.51131) (xy 409.500324 -169.521378)
			(xy 409.500324 -172.329348) (xy 410.148022 -172.329348) (xy 410.152093 -172.273726) (xy 410.164219 -172.219289)
			(xy 410.184142 -172.167198) (xy 410.211438 -172.118563) (xy 410.245524 -172.07442) (xy 410.285673 -172.035711)
			(xy 410.331031 -172.00326) (xy 410.380631 -171.977759) (xy 410.433415 -171.959752) (xy 410.488258 -171.949622)
			(xy 410.543992 -171.947585) (xy 410.599429 -171.953685) (xy 410.653386 -171.967791) (xy 410.704715 -171.989603)
			(xy 410.752321 -172.018657) (xy 410.795189 -172.054332) (xy 410.832406 -172.095869) (xy 410.863179 -172.142382)
			(xy 410.886851 -172.192879) (xy 410.902919 -172.246286) (xy 410.911039 -172.301462) (xy 410.911548 -172.329348)
			(xy 410.911284 -172.343826) (xy 411.085282 -172.343826) (xy 411.089353 -172.288204) (xy 411.101479 -172.233767)
			(xy 411.121402 -172.181676) (xy 411.148698 -172.133041) (xy 411.182784 -172.088898) (xy 411.222933 -172.050189)
			(xy 411.268291 -172.017738) (xy 411.317891 -171.992237) (xy 411.370675 -171.97423) (xy 411.425518 -171.9641)
			(xy 411.481252 -171.962063) (xy 411.536689 -171.968163) (xy 411.590646 -171.982269) (xy 411.641975 -172.004081)
			(xy 411.689581 -172.033135) (xy 411.732449 -172.06881) (xy 411.769666 -172.110347) (xy 411.800439 -172.15686)
			(xy 411.824111 -172.207357) (xy 411.840179 -172.260764) (xy 411.848299 -172.31594) (xy 411.848808 -172.343826)
			(xy 411.848299 -172.371712) (xy 411.840179 -172.426888) (xy 411.824111 -172.480295) (xy 411.800439 -172.530792)
			(xy 411.769666 -172.577305) (xy 411.732449 -172.618842) (xy 411.689581 -172.654517) (xy 411.641975 -172.683571)
			(xy 411.590646 -172.705383) (xy 411.536689 -172.719489) (xy 411.481252 -172.725589) (xy 411.425518 -172.723552)
			(xy 411.370675 -172.713422) (xy 411.317891 -172.695415) (xy 411.268291 -172.669914) (xy 411.222933 -172.637463)
			(xy 411.182784 -172.598754) (xy 411.148698 -172.554611) (xy 411.121402 -172.505976) (xy 411.101479 -172.453885)
			(xy 411.089353 -172.399448) (xy 411.085282 -172.343826) (xy 410.911284 -172.343826) (xy 410.911039 -172.357234)
			(xy 410.902919 -172.41241) (xy 410.886851 -172.465817) (xy 410.863179 -172.516314) (xy 410.832406 -172.562827)
			(xy 410.795189 -172.604364) (xy 410.752321 -172.640039) (xy 410.704715 -172.669093) (xy 410.653386 -172.690905)
			(xy 410.599429 -172.705011) (xy 410.543992 -172.711111) (xy 410.488258 -172.709074) (xy 410.433415 -172.698944)
			(xy 410.380631 -172.680937) (xy 410.331031 -172.655436) (xy 410.285673 -172.622985) (xy 410.245524 -172.584276)
			(xy 410.211438 -172.540133) (xy 410.184142 -172.491498) (xy 410.164219 -172.439407) (xy 410.152093 -172.38497)
			(xy 410.148022 -172.329348) (xy 409.500324 -172.329348) (xy 409.500324 -173.861222) (xy 409.50094 -173.872361)
			(xy 409.510411 -173.892525) (xy 409.518612 -173.900084) (xy 409.539677 -173.918326) (xy 409.576815 -173.959869)
			(xy 409.607518 -174.00637) (xy 409.631136 -174.05684) (xy 409.647165 -174.110208) (xy 409.655266 -174.165339)
			(xy 409.655772 -174.1932) (xy 409.655345 -174.220454) (xy 409.647587 -174.274409) (xy 409.632229 -174.326709)
			(xy 409.609584 -174.376292) (xy 409.580112 -174.422147) (xy 409.544415 -174.46334) (xy 409.503218 -174.499034)
			(xy 409.45736 -174.528501) (xy 409.407776 -174.551141) (xy 409.355473 -174.566494) (xy 409.301519 -174.574247)
			(xy 409.274264 -174.574708) (xy 409.246843 -174.574197) (xy 409.192567 -174.566345) (xy 409.139973 -174.550808)
			(xy 409.090143 -174.527904) (xy 409.044103 -174.498106) (xy 409.002801 -174.462028) (xy 408.967086 -174.42041)
			(xy 408.937693 -174.374111) (xy 408.915228 -174.324082) (xy 408.907234 -174.297848) (xy 408.905948 -174.29364)
			(xy 408.902119 -174.285718) (xy 408.899614 -174.2821) (xy 408.884867 -174.260808) (xy 408.861438 -174.21462)
			(xy 408.845483 -174.165348) (xy 408.837392 -174.114193) (xy 408.836876 -174.088298) (xy 408.836876 -169.362374)
			(xy 408.837415 -169.336351) (xy 408.845578 -169.284948) (xy 408.86167 -169.235451) (xy 408.885295 -169.189075)
			(xy 408.915873 -169.146957) (xy 408.933904 -169.128186) (xy 410.807408 -167.254682) (xy 410.813722 -167.247743)
			(xy 410.821359 -167.230626) (xy 410.822348 -167.211909) (xy 410.819854 -167.202866) (xy 410.787342 -167.103298)
			(xy 410.765498 -167.084756) (xy 410.751274 -167.08247) (xy 410.725074 -167.077911) (xy 410.674175 -167.062507)
			(xy 410.625909 -167.040183) (xy 410.581211 -167.011373) (xy 410.540947 -166.976633) (xy 410.505899 -166.936638)
			(xy 410.476744 -166.892163) (xy 410.45405 -166.844071) (xy 410.445712 -166.818818) (xy 410.445712 -166.818564)
			(xy 410.443738 -166.812869) (xy 410.437439 -166.802595) (xy 410.433266 -166.798244) (xy 410.343096 -166.708074)
			(xy 410.336151 -166.701767) (xy 410.319037 -166.69413) (xy 410.300323 -166.693137) (xy 410.29128 -166.695628)
			(xy 410.191712 -166.72814) (xy 410.17317 -166.749984) (xy 410.170884 -166.764208) (xy 410.166293 -166.79085)
			(xy 410.150527 -166.842561) (xy 410.127618 -166.891528) (xy 410.098024 -166.936769) (xy 410.062339 -166.97738)
			(xy 410.021277 -167.012544) (xy 409.975662 -167.041559) (xy 409.926407 -167.063843) (xy 409.874499 -167.078949)
			(xy 409.820979 -167.086575) (xy 409.793948 -167.087042) (xy 409.766698 -167.0865) (xy 409.712752 -167.078751)
			(xy 409.660457 -167.063402) (xy 409.61088 -167.040768) (xy 409.565028 -167.011308) (xy 409.523835 -166.975623)
			(xy 409.488141 -166.934438) (xy 409.458671 -166.888593) (xy 409.436026 -166.83902) (xy 409.420667 -166.786729)
			(xy 409.412906 -166.732784) (xy 409.41244 -166.705534) (xy 409.412926 -166.678507) (xy 409.420564 -166.624994)
			(xy 409.435679 -166.573096) (xy 409.457967 -166.52385) (xy 409.486982 -166.478243) (xy 409.522144 -166.437187)
			(xy 409.562748 -166.401505) (xy 409.607981 -166.371911) (xy 409.656939 -166.348997) (xy 409.708641 -166.333222)
			(xy 409.735274 -166.328598) (xy 409.749498 -166.326312) (xy 409.771342 -166.30777) (xy 409.803854 -166.208202)
			(xy 409.806407 -166.199158) (xy 409.805465 -166.180406) (xy 409.797811 -166.163262) (xy 409.791408 -166.156386)
			(xy 403.691598 -160.056576) (xy 403.684196 -160.049739) (xy 403.665598 -160.042018) (xy 403.65553 -160.04159)
			(xy 401.840446 -160.04159) (xy 401.830376 -160.042016) (xy 401.811777 -160.049734) (xy 401.804378 -160.056576)
			(xy 400.991832 -160.869122) (xy 400.968297 -160.892053) (xy 400.916916 -160.933018) (xy 400.861272 -160.967972)
			(xy 400.802063 -160.996476) (xy 400.740036 -161.018171) (xy 400.675969 -161.032785) (xy 400.610668 -161.040133)
			(xy 400.577812 -161.040572) (xy 400.577558 -161.040572) (xy 400.542154 -161.040084) (xy 400.471862 -161.031546)
			(xy 400.403111 -161.014601) (xy 400.336903 -160.989495) (xy 400.274203 -160.956593) (xy 400.215924 -160.916377)
			(xy 400.162915 -160.86943) (xy 400.115951 -160.816439) (xy 400.075713 -160.758174) (xy 400.04279 -160.695485)
			(xy 400.01766 -160.629286) (xy 400.000691 -160.560541) (xy 399.992129 -160.490252) (xy 399.99158 -160.454848)
			(xy 399.992028 -160.421967) (xy 399.999391 -160.356619) (xy 400.01403 -160.292507) (xy 400.03576 -160.230439)
			(xy 400.064308 -160.171196) (xy 400.099314 -160.115526) (xy 400.140337 -160.064128) (xy 400.163284 -160.040574)
			(xy 400.170142 -160.033716) (xy 400.176826 -160.026304) (xy 400.184428 -160.007871) (xy 400.184429 -159.987932)
			(xy 400.176828 -159.969499) (xy 400.170142 -159.962088) (xy 400.16303 -159.954976) (xy 400.153632 -159.950912)
			(xy 400.122048 -159.937185) (xy 400.062036 -159.903399) (xy 400.006401 -159.862808) (xy 399.95591 -159.815971)
			(xy 399.911262 -159.763536) (xy 399.873072 -159.706226) (xy 399.841867 -159.644832) (xy 399.818079 -159.580202)
			(xy 399.802035 -159.513228) (xy 399.793957 -159.444834) (xy 399.79346 -159.4104) (xy 399.794009 -159.375013)
			(xy 399.802538 -159.304754) (xy 399.81947 -159.236036) (xy 399.84456 -159.169858) (xy 399.877442 -159.107186)
			(xy 399.917636 -159.048933) (xy 399.964556 -158.995947) (xy 400.01752 -158.949002) (xy 400.075755 -158.908781)
			(xy 400.138411 -158.875871) (xy 400.204578 -158.850751) (xy 400.273289 -158.833787) (xy 400.343543 -158.825226)
			(xy 400.37893 -158.824676) (xy 400.675094 -158.824676) (xy 400.685164 -158.824254) (xy 400.703762 -158.816532)
			(xy 400.711162 -158.80969) (xy 402.182838 -157.33776) (xy 402.189693 -157.330372) (xy 402.197403 -157.311763)
			(xy 402.197824 -157.301692) (xy 402.197824 -144.995646) (xy 402.197394 -144.985577) (xy 402.189679 -144.966978)
			(xy 402.182838 -144.959578) (xy 400.424904 -143.20139) (xy 400.417498 -143.194558) (xy 400.398903 -143.186834)
			(xy 400.388836 -143.186404) (xy 400.287236 -143.186404) (xy 400.251837 -143.185877) (xy 400.181556 -143.177347)
			(xy 400.112815 -143.160407) (xy 400.046617 -143.135305) (xy 399.983928 -143.102406) (xy 399.925662 -143.06219)
			(xy 399.872668 -143.015243) (xy 399.82572 -142.962251) (xy 399.785503 -142.903986) (xy 399.752602 -142.841298)
			(xy 399.727497 -142.775101) (xy 399.710556 -142.70636) (xy 399.702024 -142.636079) (xy 399.701512 -142.60068)
			(xy 399.701512 -142.600426) (xy 399.702148 -142.562149) (xy 399.712146 -142.486251) (xy 399.731935 -142.412299)
			(xy 399.76118 -142.341552) (xy 399.779744 -142.308072) (xy 399.783924 -142.300208) (xy 399.78701 -142.282676)
			(xy 399.783908 -142.265146) (xy 399.779744 -142.257272) (xy 399.761183 -142.22379) (xy 399.731915 -142.15305)
			(xy 399.712121 -142.079097) (xy 399.702137 -142.003196) (xy 399.701512 -141.964918) (xy 399.702073 -141.929516)
			(xy 399.710603 -141.859227) (xy 399.727541 -141.790478) (xy 399.75264 -141.724272) (xy 399.785535 -141.661572)
			(xy 399.825745 -141.603293) (xy 399.872685 -141.550285) (xy 399.925671 -141.503319) (xy 399.98393 -141.463081)
			(xy 400.046614 -141.430156) (xy 400.112809 -141.405025) (xy 400.181549 -141.388054) (xy 400.251834 -141.37949)
			(xy 400.287236 -141.37894) (xy 400.699478 -141.37894) (xy 400.732359 -141.379383) (xy 400.797707 -141.386748)
			(xy 400.861819 -141.401388) (xy 400.923887 -141.42312) (xy 400.983129 -141.451668) (xy 401.0388 -141.486674)
			(xy 401.090198 -141.527697) (xy 401.113752 -141.550644) (xy 403.391624 -143.828516) (xy 403.421596 -143.834612)
			(xy 403.43582 -143.828516) (xy 403.444943 -143.824293) (xy 403.459176 -143.810118) (xy 403.466887 -143.79157)
			(xy 403.467316 -143.781526) (xy 403.467316 -132.366004) (xy 403.467862 -132.339981) (xy 403.476022 -132.288578)
			(xy 403.492112 -132.239081) (xy 403.515735 -132.192704) (xy 403.546313 -132.150587) (xy 403.564344 -132.131816)
			(xy 404.246842 -131.449572) (xy 404.253693 -131.442181) (xy 404.261405 -131.423575) (xy 404.261828 -131.413504)
			(xy 404.261828 -119.620538) (xy 404.261402 -119.610468) (xy 404.253684 -119.591869) (xy 404.246842 -119.58447)
			(xy 403.037548 -118.37543) (xy 403.019505 -118.356669) (xy 402.988928 -118.314549) (xy 402.965304 -118.26817)
			(xy 402.949212 -118.218671) (xy 402.941047 -118.167266) (xy 402.94052 -118.141242) (xy 402.94052 -117.59819)
			(xy 402.940121 -117.588117) (xy 402.932384 -117.569519) (xy 402.925534 -117.562122) (xy 399.167604 -113.804446)
			(xy 399.149578 -113.785669) (xy 399.118997 -113.743554) (xy 399.095369 -113.697179) (xy 399.079272 -113.647683)
			(xy 399.071104 -113.596281) (xy 399.070576 -113.570258) (xy 386.501894 -113.570258) (xy 385.851146 -114.221006)
			(xy 385.844295 -114.228403) (xy 385.836556 -114.247001) (xy 385.83616 -114.257074) (xy 385.83616 -115.396264)
			(xy 385.838373 -115.399111) (xy 385.843472 -115.404212) (xy 385.84632 -115.406424) (xy 385.922774 -115.455446)
			(xy 385.933785 -115.46109) (xy 385.958456 -115.462398) (xy 385.970018 -115.457986) (xy 385.970272 -115.457986)
			(xy 385.992166 -115.448164) (xy 386.037853 -115.433491) (xy 386.085024 -115.424686) (xy 386.108956 -115.422934)
			(xy 386.120132 -115.422426) (xy 386.129784 -115.417346) (xy 386.134352 -115.414717) (xy 386.142417 -115.407936)
			(xy 386.145786 -115.403884) (xy 386.169408 -115.373912) (xy 386.193284 -115.343686) (xy 386.196492 -115.339466)
			(xy 386.201239 -115.32999) (xy 386.202682 -115.32489) (xy 386.205222 -115.314476) (xy 386.20319 -115.303554)
			(xy 386.20036 -115.286806) (xy 386.197308 -115.252974) (xy 386.197094 -115.23599) (xy 386.197094 -115.235228)
			(xy 386.19758 -115.207977) (xy 386.205336 -115.154029) (xy 386.220691 -115.101734) (xy 386.243333 -115.052157)
			(xy 386.272799 -115.006307) (xy 386.30849 -114.965116) (xy 386.349681 -114.929425) (xy 386.395531 -114.899959)
			(xy 386.445108 -114.877317) (xy 386.497403 -114.861962) (xy 386.551351 -114.854206) (xy 386.605853 -114.854206)
			(xy 386.659801 -114.861962) (xy 386.712096 -114.877317) (xy 386.761673 -114.899959) (xy 386.807523 -114.929425)
			(xy 386.848714 -114.965116) (xy 386.884405 -115.006307) (xy 386.913871 -115.052157) (xy 386.936513 -115.101734)
			(xy 386.951868 -115.154029) (xy 386.959624 -115.207977) (xy 386.96011 -115.235228) (xy 386.959569 -115.264113)
			(xy 386.950844 -115.321221) (xy 386.933614 -115.376362) (xy 386.90827 -115.428276) (xy 386.875393 -115.475779)
			(xy 386.835733 -115.517785) (xy 386.790197 -115.553335) (xy 386.739822 -115.581617) (xy 386.685762 -115.601985)
			(xy 386.629249 -115.613974) (xy 386.600446 -115.616228) (xy 386.58927 -115.616736) (xy 386.579618 -115.621816)
			(xy 386.575049 -115.624443) (xy 386.56698 -115.631221) (xy 386.563616 -115.635278) (xy 386.539994 -115.66525)
			(xy 386.516118 -115.695476) (xy 386.512915 -115.699698) (xy 386.508179 -115.709177) (xy 386.50672 -115.714272)
			(xy 386.50418 -115.724686) (xy 386.506212 -115.735608) (xy 386.509043 -115.752356) (xy 386.512099 -115.786188)
			(xy 386.512308 -115.803172) (xy 386.512308 -115.803934) (xy 386.511845 -115.83092) (xy 386.504244 -115.884354)
			(xy 386.489184 -115.936182) (xy 386.466966 -115.985368) (xy 386.438034 -116.03093) (xy 386.402967 -116.071957)
			(xy 386.362465 -116.10763) (xy 386.317338 -116.137235) (xy 386.293106 -116.14912) (xy 386.282946 -116.153946)
			(xy 386.276088 -116.162074) (xy 386.272568 -116.166419) (xy 386.267315 -116.176287) (xy 386.265674 -116.181632)
			(xy 386.245354 -116.256562) (xy 386.243187 -116.266203) (xy 386.245543 -116.285805) (xy 386.249926 -116.294662)
			(xy 386.252466 -116.298218) (xy 386.267992 -116.322043) (xy 386.292575 -116.37332) (xy 386.30928 -116.427675)
			(xy 386.317739 -116.483908) (xy 386.318252 -116.51234) (xy 386.318252 -116.512594) (xy 386.317767 -116.539847)
			(xy 386.310011 -116.593797) (xy 386.294657 -116.646095) (xy 386.272017 -116.695676) (xy 386.242551 -116.74153)
			(xy 386.20686 -116.782725) (xy 386.165671 -116.818421) (xy 386.11982 -116.847893) (xy 386.070242 -116.870539)
			(xy 386.017946 -116.8859) (xy 385.963997 -116.893663) (xy 385.936744 -116.894102) (xy 385.906283 -116.893501)
			(xy 385.846138 -116.883805) (xy 385.788299 -116.864669) (xy 385.734239 -116.83658) (xy 385.709414 -116.818918)
			(xy 385.703572 -116.8146) (xy 385.690364 -116.809774) (xy 385.683506 -116.809012) (xy 385.676547 -116.808667)
			(xy 385.662886 -116.811379) (xy 385.656582 -116.814346) (xy 385.575048 -116.85524) (xy 385.569879 -116.858032)
			(xy 385.560904 -116.86561) (xy 385.557268 -116.870226) (xy 385.557268 -117.317266) (xy 385.56692 -117.326918)
			(xy 385.630674 -117.376194) (xy 385.635411 -117.379634) (xy 385.646058 -117.3845) (xy 385.651756 -117.385846)
			(xy 385.662678 -117.388132) (xy 385.674362 -117.385084) (xy 385.698197 -117.379295) (xy 385.746864 -117.373181)
			(xy 385.77139 -117.372892) (xy 385.798581 -117.373466) (xy 385.852389 -117.381371) (xy 385.904529 -117.396837)
			(xy 385.953944 -117.419552) (xy 385.999633 -117.449053) (xy 386.040669 -117.484744) (xy 386.076221 -117.525901)
			(xy 386.105568 -117.571689) (xy 386.128115 -117.621181) (xy 386.143405 -117.673373) (xy 386.151129 -117.727207)
			(xy 386.151628 -117.7544) (xy 386.151142 -117.781652) (xy 386.143386 -117.835601) (xy 386.128031 -117.887896)
			(xy 386.10539 -117.937475) (xy 386.075924 -117.983327) (xy 386.040233 -118.024519) (xy 385.999043 -118.060212)
			(xy 385.953193 -118.08968) (xy 385.903615 -118.112324) (xy 385.85132 -118.127682) (xy 385.797372 -118.135441)
			(xy 385.77012 -118.135908) (xy 385.769866 -118.135908) (xy 385.745724 -118.135519) (xy 385.697828 -118.129404)
			(xy 385.674362 -118.123716) (xy 385.662678 -118.120668) (xy 385.651756 -118.122954) (xy 385.646037 -118.12424)
			(xy 385.635381 -118.129113) (xy 385.630674 -118.132606) (xy 385.56692 -118.181882) (xy 385.557268 -118.191534)
			(xy 385.557268 -118.301262) (xy 385.55777 -118.311314) (xy 385.565486 -118.32988) (xy 385.572254 -118.33733)
			(xy 387.321384 -120.086374) (xy 401.939252 -120.086374) (xy 401.939252 -119.222774) (xy 401.939742 -119.192806)
			(xy 401.947565 -119.133384) (xy 401.963078 -119.075491) (xy 401.986014 -119.020118) (xy 402.015981 -118.968212)
			(xy 402.052468 -118.920662) (xy 402.094848 -118.878282) (xy 402.142398 -118.841795) (xy 402.194304 -118.811828)
			(xy 402.249677 -118.788892) (xy 402.30757 -118.773379) (xy 402.366992 -118.765556) (xy 402.426928 -118.765556)
			(xy 402.48635 -118.773379) (xy 402.544243 -118.788892) (xy 402.599616 -118.811828) (xy 402.651522 -118.841795)
			(xy 402.699072 -118.878282) (xy 402.741452 -118.920662) (xy 402.777939 -118.968212) (xy 402.807906 -119.020118)
			(xy 402.830842 -119.075491) (xy 402.846355 -119.133384) (xy 402.854178 -119.192806) (xy 402.854668 -119.222774)
			(xy 402.854668 -120.086374) (xy 402.854178 -120.116342) (xy 402.846355 -120.175764) (xy 402.830842 -120.233657)
			(xy 402.807906 -120.28903) (xy 402.777939 -120.340936) (xy 402.741452 -120.388486) (xy 402.699072 -120.430866)
			(xy 402.651522 -120.467353) (xy 402.599616 -120.49732) (xy 402.544243 -120.520256) (xy 402.48635 -120.535769)
			(xy 402.426928 -120.543592) (xy 402.366992 -120.543592) (xy 402.30757 -120.535769) (xy 402.249677 -120.520256)
			(xy 402.194304 -120.49732) (xy 402.142398 -120.467353) (xy 402.094848 -120.430866) (xy 402.052468 -120.388486)
			(xy 402.015981 -120.340936) (xy 401.986014 -120.28903) (xy 401.963078 -120.233657) (xy 401.947565 -120.175764)
			(xy 401.939742 -120.116342) (xy 401.939252 -120.086374) (xy 387.321384 -120.086374) (xy 389.12157 -121.886472)
			(xy 400.085052 -121.886472) (xy 400.085052 -121.022872) (xy 400.085542 -120.992904) (xy 400.093365 -120.933482)
			(xy 400.108878 -120.875589) (xy 400.131814 -120.820216) (xy 400.161781 -120.76831) (xy 400.198268 -120.72076)
			(xy 400.240648 -120.67838) (xy 400.288198 -120.641893) (xy 400.340104 -120.611926) (xy 400.395477 -120.58899)
			(xy 400.45337 -120.573477) (xy 400.512792 -120.565654) (xy 400.572728 -120.565654) (xy 400.63215 -120.573477)
			(xy 400.690043 -120.58899) (xy 400.745416 -120.611926) (xy 400.797322 -120.641893) (xy 400.844872 -120.67838)
			(xy 400.887252 -120.72076) (xy 400.923739 -120.76831) (xy 400.953706 -120.820216) (xy 400.976642 -120.875589)
			(xy 400.992155 -120.933482) (xy 400.999978 -120.992904) (xy 401.000468 -121.022872) (xy 401.000468 -121.886472)
			(xy 400.999978 -121.91644) (xy 400.992155 -121.975862) (xy 400.976642 -122.033755) (xy 400.953706 -122.089128)
			(xy 400.923739 -122.141034) (xy 400.887252 -122.188584) (xy 400.844872 -122.230964) (xy 400.797322 -122.267451)
			(xy 400.745416 -122.297418) (xy 400.690043 -122.320354) (xy 400.63215 -122.335867) (xy 400.572728 -122.34369)
			(xy 400.512792 -122.34369) (xy 400.45337 -122.335867) (xy 400.395477 -122.320354) (xy 400.340104 -122.297418)
			(xy 400.288198 -122.267451) (xy 400.240648 -122.230964) (xy 400.198268 -122.188584) (xy 400.161781 -122.141034)
			(xy 400.131814 -122.089128) (xy 400.108878 -122.033755) (xy 400.093365 -121.975862) (xy 400.085542 -121.91644)
			(xy 400.085052 -121.886472) (xy 389.12157 -121.886472) (xy 390.752076 -123.516898) (xy 390.770107 -123.535669)
			(xy 390.800686 -123.577786) (xy 390.82431 -123.624163) (xy 390.840401 -123.67366) (xy 390.842411 -123.686316)
			(xy 401.939252 -123.686316) (xy 401.939252 -122.822716) (xy 401.939742 -122.792748) (xy 401.947565 -122.733326)
			(xy 401.963078 -122.675433) (xy 401.986014 -122.62006) (xy 402.015981 -122.568154) (xy 402.052468 -122.520604)
			(xy 402.094848 -122.478224) (xy 402.142398 -122.441737) (xy 402.194304 -122.41177) (xy 402.249677 -122.388834)
			(xy 402.30757 -122.373321) (xy 402.366992 -122.365498) (xy 402.426928 -122.365498) (xy 402.48635 -122.373321)
			(xy 402.544243 -122.388834) (xy 402.599616 -122.41177) (xy 402.651522 -122.441737) (xy 402.699072 -122.478224)
			(xy 402.741452 -122.520604) (xy 402.777939 -122.568154) (xy 402.807906 -122.62006) (xy 402.830842 -122.675433)
			(xy 402.846355 -122.733326) (xy 402.854178 -122.792748) (xy 402.854668 -122.822716) (xy 402.854668 -123.686316)
			(xy 402.854178 -123.716284) (xy 402.846355 -123.775706) (xy 402.830842 -123.833599) (xy 402.807906 -123.888972)
			(xy 402.777939 -123.940878) (xy 402.741452 -123.988428) (xy 402.699072 -124.030808) (xy 402.651522 -124.067295)
			(xy 402.599616 -124.097262) (xy 402.544243 -124.120198) (xy 402.48635 -124.135711) (xy 402.426928 -124.143534)
			(xy 402.366992 -124.143534) (xy 402.30757 -124.135711) (xy 402.249677 -124.120198) (xy 402.194304 -124.097262)
			(xy 402.142398 -124.067295) (xy 402.094848 -124.030808) (xy 402.052468 -123.988428) (xy 402.015981 -123.940878)
			(xy 401.986014 -123.888972) (xy 401.963078 -123.833599) (xy 401.947565 -123.775706) (xy 401.939742 -123.716284)
			(xy 401.939252 -123.686316) (xy 390.842411 -123.686316) (xy 390.848564 -123.725063) (xy 390.849104 -123.751086)
			(xy 390.849104 -125.486414) (xy 400.085052 -125.486414) (xy 400.085052 -124.622814) (xy 400.085542 -124.592846)
			(xy 400.093365 -124.533424) (xy 400.108878 -124.475531) (xy 400.131814 -124.420158) (xy 400.161781 -124.368252)
			(xy 400.198268 -124.320702) (xy 400.240648 -124.278322) (xy 400.288198 -124.241835) (xy 400.340104 -124.211868)
			(xy 400.395477 -124.188932) (xy 400.45337 -124.173419) (xy 400.512792 -124.165596) (xy 400.572728 -124.165596)
			(xy 400.63215 -124.173419) (xy 400.690043 -124.188932) (xy 400.745416 -124.211868) (xy 400.797322 -124.241835)
			(xy 400.844872 -124.278322) (xy 400.887252 -124.320702) (xy 400.923739 -124.368252) (xy 400.953706 -124.420158)
			(xy 400.976642 -124.475531) (xy 400.992155 -124.533424) (xy 400.999978 -124.592846) (xy 401.000468 -124.622814)
			(xy 401.000468 -125.486414) (xy 400.999978 -125.516382) (xy 400.992155 -125.575804) (xy 400.976642 -125.633697)
			(xy 400.953706 -125.68907) (xy 400.923739 -125.740976) (xy 400.887252 -125.788526) (xy 400.844872 -125.830906)
			(xy 400.797322 -125.867393) (xy 400.745416 -125.89736) (xy 400.690043 -125.920296) (xy 400.63215 -125.935809)
			(xy 400.572728 -125.943632) (xy 400.512792 -125.943632) (xy 400.45337 -125.935809) (xy 400.395477 -125.920296)
			(xy 400.340104 -125.89736) (xy 400.288198 -125.867393) (xy 400.240648 -125.830906) (xy 400.198268 -125.788526)
			(xy 400.161781 -125.740976) (xy 400.131814 -125.68907) (xy 400.108878 -125.633697) (xy 400.093365 -125.575804)
			(xy 400.085542 -125.516382) (xy 400.085052 -125.486414) (xy 390.849104 -125.486414) (xy 390.849104 -131.29641)
			(xy 401.939252 -131.29641) (xy 401.939252 -130.43281) (xy 401.939742 -130.402842) (xy 401.947565 -130.34342)
			(xy 401.963078 -130.285527) (xy 401.986014 -130.230154) (xy 402.015981 -130.178248) (xy 402.052468 -130.130698)
			(xy 402.094848 -130.088318) (xy 402.142398 -130.051831) (xy 402.194304 -130.021864) (xy 402.249677 -129.998928)
			(xy 402.30757 -129.983415) (xy 402.366992 -129.975592) (xy 402.426928 -129.975592) (xy 402.48635 -129.983415)
			(xy 402.544243 -129.998928) (xy 402.599616 -130.021864) (xy 402.651522 -130.051831) (xy 402.699072 -130.088318)
			(xy 402.741452 -130.130698) (xy 402.777939 -130.178248) (xy 402.807906 -130.230154) (xy 402.830842 -130.285527)
			(xy 402.846355 -130.34342) (xy 402.854178 -130.402842) (xy 402.854668 -130.43281) (xy 402.854668 -131.29641)
			(xy 402.854178 -131.326378) (xy 402.846355 -131.3858) (xy 402.830842 -131.443693) (xy 402.807906 -131.499066)
			(xy 402.777939 -131.550972) (xy 402.741452 -131.598522) (xy 402.699072 -131.640902) (xy 402.651522 -131.677389)
			(xy 402.599616 -131.707356) (xy 402.544243 -131.730292) (xy 402.48635 -131.745805) (xy 402.426928 -131.753628)
			(xy 402.366992 -131.753628) (xy 402.30757 -131.745805) (xy 402.249677 -131.730292) (xy 402.194304 -131.707356)
			(xy 402.142398 -131.677389) (xy 402.094848 -131.640902) (xy 402.052468 -131.598522) (xy 402.015981 -131.550972)
			(xy 401.986014 -131.499066) (xy 401.963078 -131.443693) (xy 401.947565 -131.3858) (xy 401.939742 -131.326378)
			(xy 401.939252 -131.29641) (xy 390.849104 -131.29641) (xy 390.849104 -133.096508) (xy 400.085052 -133.096508)
			(xy 400.085052 -132.232908) (xy 400.085542 -132.20294) (xy 400.093365 -132.143518) (xy 400.108878 -132.085625)
			(xy 400.131814 -132.030252) (xy 400.161781 -131.978346) (xy 400.198268 -131.930796) (xy 400.240648 -131.888416)
			(xy 400.288198 -131.851929) (xy 400.340104 -131.821962) (xy 400.395477 -131.799026) (xy 400.45337 -131.783513)
			(xy 400.512792 -131.77569) (xy 400.572728 -131.77569) (xy 400.63215 -131.783513) (xy 400.690043 -131.799026)
			(xy 400.745416 -131.821962) (xy 400.797322 -131.851929) (xy 400.844872 -131.888416) (xy 400.887252 -131.930796)
			(xy 400.923739 -131.978346) (xy 400.953706 -132.030252) (xy 400.976642 -132.085625) (xy 400.992155 -132.143518)
			(xy 400.999978 -132.20294) (xy 401.000468 -132.232908) (xy 401.000468 -133.096508) (xy 400.999978 -133.126476)
			(xy 400.992155 -133.185898) (xy 400.976642 -133.243791) (xy 400.953706 -133.299164) (xy 400.923739 -133.35107)
			(xy 400.887252 -133.39862) (xy 400.844872 -133.441) (xy 400.797322 -133.477487) (xy 400.745416 -133.507454)
			(xy 400.690043 -133.53039) (xy 400.63215 -133.545903) (xy 400.572728 -133.553726) (xy 400.512792 -133.553726)
			(xy 400.45337 -133.545903) (xy 400.395477 -133.53039) (xy 400.340104 -133.507454) (xy 400.288198 -133.477487)
			(xy 400.240648 -133.441) (xy 400.198268 -133.39862) (xy 400.161781 -133.35107) (xy 400.131814 -133.299164)
			(xy 400.108878 -133.243791) (xy 400.093365 -133.185898) (xy 400.085542 -133.126476) (xy 400.085052 -133.096508)
			(xy 390.849104 -133.096508) (xy 390.849104 -134.896352) (xy 401.939252 -134.896352) (xy 401.939252 -134.032752)
			(xy 401.939742 -134.002784) (xy 401.947565 -133.943362) (xy 401.963078 -133.885469) (xy 401.986014 -133.830096)
			(xy 402.015981 -133.77819) (xy 402.052468 -133.73064) (xy 402.094848 -133.68826) (xy 402.142398 -133.651773)
			(xy 402.194304 -133.621806) (xy 402.249677 -133.59887) (xy 402.30757 -133.583357) (xy 402.366992 -133.575534)
			(xy 402.426928 -133.575534) (xy 402.48635 -133.583357) (xy 402.544243 -133.59887) (xy 402.599616 -133.621806)
			(xy 402.651522 -133.651773) (xy 402.699072 -133.68826) (xy 402.741452 -133.73064) (xy 402.777939 -133.77819)
			(xy 402.807906 -133.830096) (xy 402.830842 -133.885469) (xy 402.846355 -133.943362) (xy 402.854178 -134.002784)
			(xy 402.854668 -134.032752) (xy 402.854668 -134.896352) (xy 402.854178 -134.92632) (xy 402.846355 -134.985742)
			(xy 402.830842 -135.043635) (xy 402.807906 -135.099008) (xy 402.777939 -135.150914) (xy 402.741452 -135.198464)
			(xy 402.699072 -135.240844) (xy 402.651522 -135.277331) (xy 402.599616 -135.307298) (xy 402.544243 -135.330234)
			(xy 402.48635 -135.345747) (xy 402.426928 -135.35357) (xy 402.366992 -135.35357) (xy 402.30757 -135.345747)
			(xy 402.249677 -135.330234) (xy 402.194304 -135.307298) (xy 402.142398 -135.277331) (xy 402.094848 -135.240844)
			(xy 402.052468 -135.198464) (xy 402.015981 -135.150914) (xy 401.986014 -135.099008) (xy 401.963078 -135.043635)
			(xy 401.947565 -134.985742) (xy 401.939742 -134.92632) (xy 401.939252 -134.896352) (xy 390.849104 -134.896352)
			(xy 390.849104 -136.69645) (xy 400.085052 -136.69645) (xy 400.085052 -135.83285) (xy 400.085542 -135.802882)
			(xy 400.093365 -135.74346) (xy 400.108878 -135.685567) (xy 400.131814 -135.630194) (xy 400.161781 -135.578288)
			(xy 400.198268 -135.530738) (xy 400.240648 -135.488358) (xy 400.288198 -135.451871) (xy 400.340104 -135.421904)
			(xy 400.395477 -135.398968) (xy 400.45337 -135.383455) (xy 400.512792 -135.375632) (xy 400.572728 -135.375632)
			(xy 400.63215 -135.383455) (xy 400.690043 -135.398968) (xy 400.745416 -135.421904) (xy 400.797322 -135.451871)
			(xy 400.844872 -135.488358) (xy 400.887252 -135.530738) (xy 400.923739 -135.578288) (xy 400.953706 -135.630194)
			(xy 400.976642 -135.685567) (xy 400.992155 -135.74346) (xy 400.999978 -135.802882) (xy 401.000468 -135.83285)
			(xy 401.000468 -136.69645) (xy 400.999978 -136.726418) (xy 400.992155 -136.78584) (xy 400.976642 -136.843733)
			(xy 400.953706 -136.899106) (xy 400.923739 -136.951012) (xy 400.887252 -136.998562) (xy 400.844872 -137.040942)
			(xy 400.797322 -137.077429) (xy 400.745416 -137.107396) (xy 400.690043 -137.130332) (xy 400.63215 -137.145845)
			(xy 400.572728 -137.153668) (xy 400.512792 -137.153668) (xy 400.45337 -137.145845) (xy 400.395477 -137.130332)
			(xy 400.340104 -137.107396) (xy 400.288198 -137.077429) (xy 400.240648 -137.040942) (xy 400.198268 -136.998562)
			(xy 400.161781 -136.951012) (xy 400.131814 -136.899106) (xy 400.108878 -136.843733) (xy 400.093365 -136.78584)
			(xy 400.085542 -136.726418) (xy 400.085052 -136.69645) (xy 390.849104 -136.69645) (xy 390.849104 -138.497056)
			(xy 392.27252 -138.497056) (xy 392.27252 -137.633456) (xy 392.27301 -137.603472) (xy 392.280838 -137.544016)
			(xy 392.296359 -137.486091) (xy 392.319308 -137.430687) (xy 392.349292 -137.378753) (xy 392.385798 -137.331177)
			(xy 392.428203 -137.288772) (xy 392.475779 -137.252266) (xy 392.527713 -137.222282) (xy 392.583117 -137.199333)
			(xy 392.641042 -137.183812) (xy 392.700498 -137.175984) (xy 392.760466 -137.175984) (xy 392.819922 -137.183812)
			(xy 392.877847 -137.199333) (xy 392.933251 -137.222282) (xy 392.985185 -137.252266) (xy 393.032761 -137.288772)
			(xy 393.075166 -137.331177) (xy 393.111672 -137.378753) (xy 393.141656 -137.430687) (xy 393.164605 -137.486091)
			(xy 393.180126 -137.544016) (xy 393.187954 -137.603472) (xy 393.188444 -137.633456) (xy 393.188444 -138.497056)
			(xy 393.187954 -138.52704) (xy 393.183073 -138.564112) (xy 394.991334 -138.564112) (xy 394.995405 -138.50849)
			(xy 395.007531 -138.454053) (xy 395.027454 -138.401962) (xy 395.05475 -138.353327) (xy 395.088836 -138.309184)
			(xy 395.128985 -138.270475) (xy 395.174343 -138.238024) (xy 395.223943 -138.212523) (xy 395.276727 -138.194516)
			(xy 395.33157 -138.184386) (xy 395.387304 -138.182349) (xy 395.442741 -138.188449) (xy 395.496698 -138.202555)
			(xy 395.548027 -138.224367) (xy 395.595633 -138.253421) (xy 395.638501 -138.289096) (xy 395.675718 -138.330633)
			(xy 395.706491 -138.377146) (xy 395.730163 -138.427643) (xy 395.746231 -138.48105) (xy 395.754351 -138.536226)
			(xy 395.75486 -138.564112) (xy 395.754351 -138.591998) (xy 395.746231 -138.647174) (xy 395.730163 -138.700581)
			(xy 395.706491 -138.751078) (xy 395.675718 -138.797591) (xy 395.638501 -138.839128) (xy 395.595633 -138.874803)
			(xy 395.548027 -138.903857) (xy 395.496698 -138.925669) (xy 395.442741 -138.939775) (xy 395.387304 -138.945875)
			(xy 395.33157 -138.943838) (xy 395.276727 -138.933708) (xy 395.223943 -138.915701) (xy 395.174343 -138.8902)
			(xy 395.128985 -138.857749) (xy 395.088836 -138.81904) (xy 395.05475 -138.774897) (xy 395.027454 -138.726262)
			(xy 395.007531 -138.674171) (xy 394.995405 -138.619734) (xy 394.991334 -138.564112) (xy 393.183073 -138.564112)
			(xy 393.180126 -138.586496) (xy 393.164605 -138.644421) (xy 393.141656 -138.699825) (xy 393.111672 -138.751759)
			(xy 393.075166 -138.799335) (xy 393.032761 -138.84174) (xy 392.985185 -138.878246) (xy 392.933251 -138.90823)
			(xy 392.877847 -138.931179) (xy 392.819922 -138.9467) (xy 392.760466 -138.954528) (xy 392.700498 -138.954528)
			(xy 392.641042 -138.9467) (xy 392.583117 -138.931179) (xy 392.527713 -138.90823) (xy 392.475779 -138.878246)
			(xy 392.428203 -138.84174) (xy 392.385798 -138.799335) (xy 392.349292 -138.751759) (xy 392.319308 -138.699825)
			(xy 392.296359 -138.644421) (xy 392.280838 -138.586496) (xy 392.27301 -138.52704) (xy 392.27252 -138.497056)
			(xy 390.849104 -138.497056) (xy 390.849104 -140.565378) (xy 391.889742 -140.565378) (xy 391.890185 -140.538007)
			(xy 391.898007 -140.483826) (xy 391.913501 -140.431323) (xy 391.936348 -140.381576) (xy 391.966078 -140.335611)
			(xy 391.983722 -140.31468) (xy 391.983976 -140.314426) (xy 391.989567 -140.307343) (xy 391.995809 -140.290423)
			(xy 391.996168 -140.281406) (xy 391.996168 -140.21435) (xy 391.995794 -140.205335) (xy 391.989559 -140.188417)
			(xy 391.983976 -140.18133) (xy 391.983722 -140.18133) (xy 391.983722 -140.181076) (xy 391.966108 -140.160123)
			(xy 391.936392 -140.114156) (xy 391.913551 -140.064414) (xy 391.898054 -140.011918) (xy 391.890219 -139.957746)
			(xy 391.889742 -139.930378) (xy 391.890135 -139.903122) (xy 391.897896 -139.849166) (xy 391.913257 -139.796864)
			(xy 391.935906 -139.74728) (xy 391.965381 -139.701425) (xy 392.001082 -139.660231) (xy 392.042283 -139.624538)
			(xy 392.088144 -139.595071) (xy 392.137731 -139.572432) (xy 392.190037 -139.55708) (xy 392.243994 -139.549329)
			(xy 392.27125 -139.54887) (xy 392.29862 -139.549348) (xy 392.352799 -139.557161) (xy 392.405303 -139.572646)
			(xy 392.45505 -139.595485) (xy 392.501017 -139.625209) (xy 392.521948 -139.64285) (xy 392.522202 -139.643104)
			(xy 392.529283 -139.648698) (xy 392.546204 -139.65494) (xy 392.555222 -139.655296) (xy 392.622278 -139.655296)
			(xy 392.631294 -139.654929) (xy 392.648211 -139.648689) (xy 392.655298 -139.643104) (xy 392.655298 -139.64285)
			(xy 392.655552 -139.64285) (xy 392.676498 -139.625228) (xy 392.722466 -139.595512) (xy 392.77221 -139.572672)
			(xy 392.824708 -139.557177) (xy 392.878882 -139.549345) (xy 392.90625 -139.54887) (xy 392.933501 -139.549402)
			(xy 392.987448 -139.557151) (xy 393.039743 -139.5725) (xy 393.089322 -139.595135) (xy 393.135174 -139.624596)
			(xy 393.176367 -139.660282) (xy 393.212061 -139.701468) (xy 393.24153 -139.747315) (xy 393.264175 -139.796889)
			(xy 393.279533 -139.849182) (xy 393.287293 -139.903127) (xy 393.287758 -139.930378) (xy 393.287289 -139.957748)
			(xy 393.279474 -140.011928) (xy 393.263986 -140.064431) (xy 393.241144 -140.114178) (xy 393.21142 -140.160145)
			(xy 393.193778 -140.181076) (xy 393.193524 -140.18133) (xy 393.187952 -140.188426) (xy 393.181698 -140.205336)
			(xy 393.181332 -140.21435) (xy 393.181332 -140.281406) (xy 393.181679 -140.290424) (xy 393.187933 -140.307341)
			(xy 393.193524 -140.314426) (xy 393.193778 -140.314426) (xy 393.193778 -140.31468) (xy 393.211418 -140.335612)
			(xy 393.24113 -140.381584) (xy 393.263966 -140.431332) (xy 393.279457 -140.483833) (xy 393.287285 -140.538009)
			(xy 393.287758 -140.565378) (xy 393.287324 -140.592633) (xy 393.279569 -140.646587) (xy 393.264213 -140.698889)
			(xy 393.242363 -140.746734) (xy 400.39493 -140.746734) (xy 400.399001 -140.691112) (xy 400.411127 -140.636675)
			(xy 400.43105 -140.584584) (xy 400.458346 -140.535949) (xy 400.492432 -140.491806) (xy 400.532581 -140.453097)
			(xy 400.577939 -140.420646) (xy 400.627539 -140.395145) (xy 400.680323 -140.377138) (xy 400.735166 -140.367008)
			(xy 400.7909 -140.364971) (xy 400.846337 -140.371071) (xy 400.900294 -140.385177) (xy 400.951623 -140.406989)
			(xy 400.999229 -140.436043) (xy 401.042097 -140.471718) (xy 401.079314 -140.513255) (xy 401.110087 -140.559768)
			(xy 401.133759 -140.610265) (xy 401.149827 -140.663672) (xy 401.157947 -140.718848) (xy 401.158456 -140.746734)
			(xy 401.157947 -140.77462) (xy 401.149827 -140.829796) (xy 401.133759 -140.883203) (xy 401.110087 -140.9337)
			(xy 401.079314 -140.980213) (xy 401.042097 -141.02175) (xy 400.999229 -141.057425) (xy 400.951623 -141.086479)
			(xy 400.900294 -141.108291) (xy 400.846337 -141.122397) (xy 400.7909 -141.128497) (xy 400.735166 -141.12646)
			(xy 400.680323 -141.11633) (xy 400.627539 -141.098323) (xy 400.577939 -141.072822) (xy 400.532581 -141.040371)
			(xy 400.492432 -141.001662) (xy 400.458346 -140.957519) (xy 400.43105 -140.908884) (xy 400.411127 -140.856793)
			(xy 400.399001 -140.802356) (xy 400.39493 -140.746734) (xy 393.242363 -140.746734) (xy 393.241569 -140.748472)
			(xy 393.212099 -140.794328) (xy 393.176402 -140.835522) (xy 393.135205 -140.871216) (xy 393.089347 -140.900683)
			(xy 393.039762 -140.923323) (xy 392.98746 -140.938675) (xy 392.933505 -140.946426) (xy 392.90625 -140.946886)
			(xy 392.878881 -140.946394) (xy 392.824703 -140.938583) (xy 392.7722 -140.9231) (xy 392.722452 -140.900264)
			(xy 392.676484 -140.870545) (xy 392.655552 -140.852906) (xy 392.655298 -140.852652) (xy 392.64822 -140.847053)
			(xy 392.631297 -140.840815) (xy 392.622278 -140.84046) (xy 392.555222 -140.84046) (xy 392.546205 -140.840815)
			(xy 392.529287 -140.847062) (xy 392.522202 -140.852652) (xy 392.522202 -140.852906) (xy 392.521948 -140.852906)
			(xy 392.501009 -140.870537) (xy 392.455038 -140.90025) (xy 392.405292 -140.923087) (xy 392.352793 -140.93858)
			(xy 392.298619 -140.946411) (xy 392.27125 -140.946886) (xy 392.243997 -140.946398) (xy 392.190046 -140.938647)
			(xy 392.137747 -140.923297) (xy 392.088166 -140.900658) (xy 392.042312 -140.871193) (xy 392.001118 -140.835502)
			(xy 391.965423 -140.794311) (xy 391.935955 -140.748459) (xy 391.913313 -140.698879) (xy 391.897959 -140.646581)
			(xy 391.890204 -140.592631) (xy 391.889742 -140.565378) (xy 390.849104 -140.565378) (xy 390.849104 -145.329148)
			(xy 391.465308 -145.329148) (xy 391.465774 -145.302766) (xy 391.473059 -145.250508) (xy 391.487469 -145.19975)
			(xy 391.50873 -145.151459) (xy 391.536436 -145.106555) (xy 391.57006 -145.065893) (xy 391.608963 -145.030247)
			(xy 391.652402 -145.000297) (xy 391.699551 -144.976611) (xy 391.724388 -144.967706) (xy 391.733278 -144.964658)
			(xy 391.747756 -144.95272) (xy 391.790428 -144.87652) (xy 391.792968 -144.857724) (xy 391.790682 -144.84858)
			(xy 391.786023 -144.827167) (xy 391.781055 -144.783625) (xy 391.780776 -144.761712) (xy 391.781289 -144.734462)
			(xy 391.789044 -144.680516) (xy 391.804397 -144.628223) (xy 391.827035 -144.578647) (xy 391.856499 -144.532797)
			(xy 391.892187 -144.491607) (xy 391.933375 -144.455915) (xy 391.979222 -144.426449) (xy 392.028796 -144.403806)
			(xy 392.081089 -144.38845) (xy 392.135034 -144.380691) (xy 392.162284 -144.380204) (xy 392.174255 -144.38032)
			(xy 392.198148 -144.381842) (xy 392.210036 -144.383252) (xy 392.21029 -144.383252) (xy 392.219464 -144.38396)
			(xy 392.237307 -144.379527) (xy 392.245088 -144.374616) (xy 392.301222 -144.3355) (xy 392.308628 -144.329917)
			(xy 392.319176 -144.314679) (xy 392.321796 -144.305782) (xy 392.321796 -144.305528) (xy 392.328784 -144.277975)
			(xy 392.349819 -144.225168) (xy 392.378459 -144.176068) (xy 392.414069 -144.131763) (xy 392.455861 -144.093235)
			(xy 392.502909 -144.061337) (xy 392.55417 -144.036775) (xy 392.60851 -144.020094) (xy 392.664723 -144.011663)
			(xy 392.693144 -144.011142) (xy 392.717815 -144.011556) (xy 392.766741 -144.017956) (xy 392.814436 -144.030605)
			(xy 392.837416 -144.03959) (xy 392.848519 -144.043492) (xy 392.871961 -144.041772) (xy 392.882374 -144.036288)
			(xy 392.952224 -143.994632) (xy 392.961999 -143.988158) (xy 392.974853 -143.968588) (xy 392.976862 -143.95704)
			(xy 392.976862 -143.956532) (xy 392.980573 -143.928978) (xy 392.994833 -143.875245) (xy 393.016745 -143.824151)
			(xy 393.045843 -143.776781) (xy 393.081511 -143.734138) (xy 393.122993 -143.697125) (xy 393.16941 -143.666529)
			(xy 393.219777 -143.642996) (xy 393.273028 -143.627027) (xy 393.328033 -143.618959) (xy 393.35583 -143.618458)
			(xy 393.38308 -143.61895) (xy 393.437026 -143.62671) (xy 393.489319 -143.642067) (xy 393.538894 -143.664709)
			(xy 393.584742 -143.694175) (xy 393.625931 -143.729866) (xy 393.661622 -143.771054) (xy 393.691089 -143.816903)
			(xy 393.713732 -143.866478) (xy 393.72909 -143.91877) (xy 393.73685 -143.972716) (xy 393.737338 -143.999966)
			(xy 393.736862 -144.026547) (xy 393.72948 -144.079193) (xy 393.714855 -144.130303) (xy 393.693271 -144.178885)
			(xy 393.665146 -144.223998) (xy 393.631026 -144.264764) (xy 393.611608 -144.282922) (xy 393.605009 -144.289389)
			(xy 393.59655 -144.305801) (xy 393.595098 -144.314926) (xy 393.587732 -144.381474) (xy 393.586984 -144.39065)
			(xy 393.591429 -144.408501) (xy 393.596368 -144.416272) (xy 393.612484 -144.440397) (xy 393.638018 -144.492491)
			(xy 393.655375 -144.547849) (xy 393.664154 -144.605196) (xy 393.664694 -144.634204) (xy 393.664248 -144.661458)
			(xy 393.65649 -144.71541) (xy 393.641133 -144.767709) (xy 393.618489 -144.81729) (xy 393.58902 -144.863144)
			(xy 393.553324 -144.904337) (xy 393.512129 -144.94003) (xy 393.466274 -144.969498) (xy 393.416692 -144.99214)
			(xy 393.364392 -145.007494) (xy 393.31044 -145.01525) (xy 393.283186 -145.015712) (xy 393.282678 -145.015712)
			(xy 393.272881 -145.015648) (xy 393.253313 -145.014631) (xy 393.243562 -145.01368) (xy 393.243308 -145.01368)
			(xy 393.233918 -145.013063) (xy 393.21578 -145.018034) (xy 393.208002 -145.023332) (xy 393.14501 -145.070068)
			(xy 393.135104 -145.08607) (xy 393.133326 -145.095722) (xy 393.127934 -145.12156) (xy 393.111003 -145.171551)
			(xy 393.087342 -145.218731) (xy 393.057405 -145.2622) (xy 393.021762 -145.301128) (xy 392.981094 -145.334771)
			(xy 392.936177 -145.362489) (xy 392.887869 -145.38375) (xy 392.837091 -145.398151) (xy 392.784812 -145.405415)
			(xy 392.758422 -145.405856) (xy 392.72948 -145.405362) (xy 392.67226 -145.396621) (xy 392.617017 -145.379335)
			(xy 392.56502 -145.353903) (xy 392.517461 -145.320908) (xy 392.475433 -145.281106) (xy 392.4399 -145.235412)
			(xy 392.411678 -145.184875) (xy 392.401044 -145.157952) (xy 392.397063 -145.148552) (xy 392.38303 -145.133749)
			(xy 392.373866 -145.12925) (xy 392.344656 -145.116296) (xy 392.335072 -145.112517) (xy 392.314495 -145.112114)
			(xy 392.304778 -145.115534) (xy 392.284712 -145.123154) (xy 392.275822 -145.126202) (xy 392.261344 -145.13814)
			(xy 392.218672 -145.21434) (xy 392.216132 -145.233136) (xy 392.218418 -145.24228) (xy 392.223087 -145.263691)
			(xy 392.228049 -145.307235) (xy 392.228324 -145.329148) (xy 392.227838 -145.356399) (xy 392.220082 -145.410347)
			(xy 392.204727 -145.462642) (xy 392.182085 -145.512219) (xy 392.152619 -145.558069) (xy 392.116928 -145.59926)
			(xy 392.075737 -145.634951) (xy 392.029887 -145.664417) (xy 391.98031 -145.687059) (xy 391.928015 -145.702414)
			(xy 391.874067 -145.71017) (xy 391.819565 -145.71017) (xy 391.765617 -145.702414) (xy 391.713322 -145.687059)
			(xy 391.663745 -145.664417) (xy 391.617895 -145.634951) (xy 391.576704 -145.59926) (xy 391.541013 -145.558069)
			(xy 391.511547 -145.512219) (xy 391.488905 -145.462642) (xy 391.47355 -145.410347) (xy 391.465794 -145.356399)
			(xy 391.465308 -145.329148) (xy 390.849104 -145.329148) (xy 390.849104 -145.911824) (xy 390.85012 -145.92173)
			(xy 391.012839 -146.739864) (xy 397.210024 -146.739864) (xy 397.214095 -146.684242) (xy 397.226221 -146.629805)
			(xy 397.246144 -146.577714) (xy 397.27344 -146.529079) (xy 397.307526 -146.484936) (xy 397.347675 -146.446227)
			(xy 397.393033 -146.413776) (xy 397.442633 -146.388275) (xy 397.495417 -146.370268) (xy 397.55026 -146.360138)
			(xy 397.605994 -146.358101) (xy 397.661431 -146.364201) (xy 397.715388 -146.378307) (xy 397.766717 -146.400119)
			(xy 397.814323 -146.429173) (xy 397.857191 -146.464848) (xy 397.894408 -146.506385) (xy 397.925181 -146.552898)
			(xy 397.948853 -146.603395) (xy 397.964921 -146.656802) (xy 397.973041 -146.711978) (xy 397.97355 -146.739864)
			(xy 397.973041 -146.76775) (xy 397.964921 -146.822926) (xy 397.948853 -146.876333) (xy 397.925181 -146.92683)
			(xy 397.894408 -146.973343) (xy 397.857191 -147.01488) (xy 397.814323 -147.050555) (xy 397.766717 -147.079609)
			(xy 397.715388 -147.101421) (xy 397.661431 -147.115527) (xy 397.605994 -147.121627) (xy 397.55026 -147.11959)
			(xy 397.495417 -147.10946) (xy 397.442633 -147.091453) (xy 397.393033 -147.065952) (xy 397.347675 -147.033501)
			(xy 397.307526 -146.994792) (xy 397.27344 -146.950649) (xy 397.246144 -146.902014) (xy 397.226221 -146.849923)
			(xy 397.214095 -146.795486) (xy 397.210024 -146.739864) (xy 391.012839 -146.739864) (xy 392.663972 -155.0416)
			(xy 396.463772 -155.0416) (xy 396.467843 -154.985978) (xy 396.479969 -154.931541) (xy 396.499892 -154.87945)
			(xy 396.527188 -154.830815) (xy 396.561274 -154.786672) (xy 396.601423 -154.747963) (xy 396.646781 -154.715512)
			(xy 396.696381 -154.690011) (xy 396.749165 -154.672004) (xy 396.804008 -154.661874) (xy 396.859742 -154.659837)
			(xy 396.915179 -154.665937) (xy 396.969136 -154.680043) (xy 397.020465 -154.701855) (xy 397.068071 -154.730909)
			(xy 397.110939 -154.766584) (xy 397.148156 -154.808121) (xy 397.178929 -154.854634) (xy 397.202601 -154.905131)
			(xy 397.218669 -154.958538) (xy 397.226789 -155.013714) (xy 397.227298 -155.0416) (xy 397.226789 -155.069486)
			(xy 397.218669 -155.124662) (xy 397.202601 -155.178069) (xy 397.178929 -155.228566) (xy 397.148156 -155.275079)
			(xy 397.110939 -155.316616) (xy 397.068071 -155.352291) (xy 397.020465 -155.381345) (xy 396.969136 -155.403157)
			(xy 396.915179 -155.417263) (xy 396.859742 -155.423363) (xy 396.804008 -155.421326) (xy 396.749165 -155.411196)
			(xy 396.696381 -155.393189) (xy 396.646781 -155.367688) (xy 396.601423 -155.335237) (xy 396.561274 -155.296528)
			(xy 396.527188 -155.252385) (xy 396.499892 -155.20375) (xy 396.479969 -155.151659) (xy 396.467843 -155.097222)
			(xy 396.463772 -155.0416) (xy 392.663972 -155.0416) (xy 393.362688 -158.554674) (xy 393.365722 -158.570696)
			(xy 393.36903 -158.603139) (xy 393.369292 -158.619444) (xy 393.369292 -160.1851) (xy 393.824219 -160.1851)
			(xy 393.828174 -160.093263) (xy 393.840009 -160.002106) (xy 393.859636 -159.912303) (xy 393.88691 -159.824521)
			(xy 393.92163 -159.739407) (xy 393.963538 -159.657594) (xy 394.012324 -159.579686) (xy 394.067627 -159.506261)
			(xy 394.129037 -159.437861) (xy 394.196099 -159.374994) (xy 394.268318 -159.318124) (xy 394.345158 -159.267673)
			(xy 394.426051 -159.224014) (xy 394.510397 -159.187471) (xy 394.597573 -159.158314) (xy 394.686932 -159.13676)
			(xy 394.777813 -159.122966) (xy 394.869544 -159.117036) (xy 394.961445 -159.119014) (xy 395.052836 -159.128885)
			(xy 395.14304 -159.146575) (xy 395.231389 -159.171955) (xy 395.317229 -159.204835) (xy 395.399925 -159.244973)
			(xy 395.478865 -159.292072) (xy 395.553463 -159.345782) (xy 395.623169 -159.405706) (xy 395.687464 -159.4714)
			(xy 395.745875 -159.542378) (xy 395.797967 -159.618115) (xy 395.843356 -159.69805) (xy 395.881706 -159.78159)
			(xy 395.912731 -159.868118) (xy 395.936204 -159.956993) (xy 395.95195 -160.047557) (xy 395.959852 -160.139139)
			(xy 395.960346 -160.1851) (xy 395.959852 -160.231061) (xy 395.95195 -160.322643) (xy 395.936204 -160.413207)
			(xy 395.912731 -160.502082) (xy 395.881706 -160.58861) (xy 395.843356 -160.67215) (xy 395.797967 -160.752085)
			(xy 395.745875 -160.827822) (xy 395.687464 -160.8988) (xy 395.623169 -160.964494) (xy 395.553463 -161.024418)
			(xy 395.478865 -161.078128) (xy 395.399925 -161.125227) (xy 395.317229 -161.165365) (xy 395.231389 -161.198245)
			(xy 395.14304 -161.223625) (xy 395.052836 -161.241315) (xy 394.961445 -161.251186) (xy 394.869544 -161.253164)
			(xy 394.777813 -161.247234) (xy 394.686932 -161.23344) (xy 394.597573 -161.211886) (xy 394.510397 -161.182729)
			(xy 394.426051 -161.146186) (xy 394.345158 -161.102527) (xy 394.268318 -161.052076) (xy 394.196099 -160.995206)
			(xy 394.129037 -160.932339) (xy 394.067627 -160.863939) (xy 394.012324 -160.790514) (xy 393.963538 -160.712606)
			(xy 393.92163 -160.630793) (xy 393.88691 -160.545679) (xy 393.859636 -160.457897) (xy 393.840009 -160.368094)
			(xy 393.828174 -160.276937) (xy 393.824219 -160.1851) (xy 393.369292 -160.1851) (xy 393.369292 -160.265618)
			(xy 393.369381 -160.270638) (xy 393.371295 -160.280492) (xy 393.373102 -160.285176) (xy 394.935178 -164.056314)
			(xy 399.637502 -164.056314) (xy 399.641573 -164.000692) (xy 399.653699 -163.946255) (xy 399.673622 -163.894164)
			(xy 399.700918 -163.845529) (xy 399.735004 -163.801386) (xy 399.775153 -163.762677) (xy 399.820511 -163.730226)
			(xy 399.870111 -163.704725) (xy 399.922895 -163.686718) (xy 399.977738 -163.676588) (xy 400.033472 -163.674551)
			(xy 400.088909 -163.680651) (xy 400.142866 -163.694757) (xy 400.194195 -163.716569) (xy 400.241801 -163.745623)
			(xy 400.284669 -163.781298) (xy 400.321886 -163.822835) (xy 400.352659 -163.869348) (xy 400.376331 -163.919845)
			(xy 400.392399 -163.973252) (xy 400.400519 -164.028428) (xy 400.401028 -164.056314) (xy 400.400519 -164.0842)
			(xy 400.392399 -164.139376) (xy 400.376331 -164.192783) (xy 400.352659 -164.24328) (xy 400.321886 -164.289793)
			(xy 400.284669 -164.33133) (xy 400.241801 -164.367005) (xy 400.194195 -164.396059) (xy 400.142866 -164.417871)
			(xy 400.088909 -164.431977) (xy 400.033472 -164.438077) (xy 399.977738 -164.43604) (xy 399.922895 -164.42591)
			(xy 399.870111 -164.407903) (xy 399.820511 -164.382402) (xy 399.775153 -164.349951) (xy 399.735004 -164.311242)
			(xy 399.700918 -164.267099) (xy 399.673622 -164.218464) (xy 399.653699 -164.166373) (xy 399.641573 -164.111936)
			(xy 399.637502 -164.056314) (xy 394.935178 -164.056314) (xy 395.380328 -165.130988) (xy 397.044162 -165.130988)
			(xy 397.048233 -165.075366) (xy 397.060359 -165.020929) (xy 397.080282 -164.968838) (xy 397.107578 -164.920203)
			(xy 397.141664 -164.87606) (xy 397.181813 -164.837351) (xy 397.227171 -164.8049) (xy 397.276771 -164.779399)
			(xy 397.329555 -164.761392) (xy 397.384398 -164.751262) (xy 397.440132 -164.749225) (xy 397.495569 -164.755325)
			(xy 397.549526 -164.769431) (xy 397.600855 -164.791243) (xy 397.648461 -164.820297) (xy 397.691329 -164.855972)
			(xy 397.728546 -164.897509) (xy 397.758325 -164.94252) (xy 398.877534 -164.94252) (xy 398.881605 -164.886898)
			(xy 398.893731 -164.832461) (xy 398.913654 -164.78037) (xy 398.94095 -164.731735) (xy 398.975036 -164.687592)
			(xy 399.015185 -164.648883) (xy 399.060543 -164.616432) (xy 399.110143 -164.590931) (xy 399.162927 -164.572924)
			(xy 399.21777 -164.562794) (xy 399.273504 -164.560757) (xy 399.328941 -164.566857) (xy 399.382898 -164.580963)
			(xy 399.434227 -164.602775) (xy 399.481833 -164.631829) (xy 399.524701 -164.667504) (xy 399.561918 -164.709041)
			(xy 399.592691 -164.755554) (xy 399.616363 -164.806051) (xy 399.632431 -164.859458) (xy 399.640551 -164.914634)
			(xy 399.64106 -164.94252) (xy 399.640551 -164.970406) (xy 399.632431 -165.025582) (xy 399.616363 -165.078989)
			(xy 399.592691 -165.129486) (xy 399.561918 -165.175999) (xy 399.524701 -165.217536) (xy 399.481833 -165.253211)
			(xy 399.434227 -165.282265) (xy 399.382898 -165.304077) (xy 399.328941 -165.318183) (xy 399.273504 -165.324283)
			(xy 399.21777 -165.322246) (xy 399.162927 -165.312116) (xy 399.110143 -165.294109) (xy 399.060543 -165.268608)
			(xy 399.015185 -165.236157) (xy 398.975036 -165.197448) (xy 398.94095 -165.153305) (xy 398.913654 -165.10467)
			(xy 398.893731 -165.052579) (xy 398.881605 -164.998142) (xy 398.877534 -164.94252) (xy 397.758325 -164.94252)
			(xy 397.759319 -164.944022) (xy 397.782991 -164.994519) (xy 397.799059 -165.047926) (xy 397.807179 -165.103102)
			(xy 397.807688 -165.130988) (xy 397.807179 -165.158874) (xy 397.799059 -165.21405) (xy 397.782991 -165.267457)
			(xy 397.759319 -165.317954) (xy 397.728546 -165.364467) (xy 397.691329 -165.406004) (xy 397.648461 -165.441679)
			(xy 397.600855 -165.470733) (xy 397.549526 -165.492545) (xy 397.495569 -165.506651) (xy 397.440132 -165.512751)
			(xy 397.384398 -165.510714) (xy 397.329555 -165.500584) (xy 397.276771 -165.482577) (xy 397.227171 -165.457076)
			(xy 397.181813 -165.424625) (xy 397.141664 -165.385916) (xy 397.107578 -165.341773) (xy 397.080282 -165.293138)
			(xy 397.060359 -165.241047) (xy 397.048233 -165.18661) (xy 397.044162 -165.130988) (xy 395.380328 -165.130988)
			(xy 396.733243 -168.397174) (xy 398.941796 -168.397174) (xy 398.945867 -168.341552) (xy 398.957993 -168.287115)
			(xy 398.977916 -168.235024) (xy 399.005212 -168.186389) (xy 399.039298 -168.142246) (xy 399.079447 -168.103537)
			(xy 399.124805 -168.071086) (xy 399.174405 -168.045585) (xy 399.227189 -168.027578) (xy 399.282032 -168.017448)
			(xy 399.337766 -168.015411) (xy 399.393203 -168.021511) (xy 399.44716 -168.035617) (xy 399.498489 -168.057429)
			(xy 399.546095 -168.086483) (xy 399.588963 -168.122158) (xy 399.62618 -168.163695) (xy 399.656953 -168.210208)
			(xy 399.680625 -168.260705) (xy 399.696693 -168.314112) (xy 399.704813 -168.369288) (xy 399.705322 -168.397174)
			(xy 399.704813 -168.42506) (xy 399.696693 -168.480236) (xy 399.680625 -168.533643) (xy 399.656953 -168.58414)
			(xy 399.62618 -168.630653) (xy 399.588963 -168.67219) (xy 399.546095 -168.707865) (xy 399.498489 -168.736919)
			(xy 399.44716 -168.758731) (xy 399.393203 -168.772837) (xy 399.337766 -168.778937) (xy 399.282032 -168.7769)
			(xy 399.227189 -168.76677) (xy 399.174405 -168.748763) (xy 399.124805 -168.723262) (xy 399.079447 -168.690811)
			(xy 399.039298 -168.652102) (xy 399.005212 -168.607959) (xy 398.977916 -168.559324) (xy 398.957993 -168.507233)
			(xy 398.945867 -168.452796) (xy 398.941796 -168.397174) (xy 396.733243 -168.397174) (xy 396.86865 -168.724072)
			(xy 396.874238 -168.728898) (xy 396.895926 -168.747129) (xy 396.934198 -168.788906) (xy 396.965874 -168.835881)
			(xy 396.990258 -168.887022) (xy 397.006814 -168.941206) (xy 397.015179 -168.997241) (xy 397.015716 -169.02557)
			(xy 397.01523 -169.052821) (xy 397.007474 -169.106769) (xy 396.992119 -169.159064) (xy 396.969477 -169.208641)
			(xy 396.940011 -169.254491) (xy 396.90432 -169.295682) (xy 396.863129 -169.331373) (xy 396.817279 -169.360839)
			(xy 396.767702 -169.383481) (xy 396.715407 -169.398836) (xy 396.661459 -169.406592) (xy 396.606957 -169.406592)
			(xy 396.553009 -169.398836) (xy 396.500714 -169.383481) (xy 396.451137 -169.360839) (xy 396.405287 -169.331373)
			(xy 396.364096 -169.295682) (xy 396.328405 -169.254491) (xy 396.298939 -169.208641) (xy 396.276297 -169.159064)
			(xy 396.260942 -169.106769) (xy 396.253186 -169.052821) (xy 396.2527 -169.02557) (xy 396.254224 -168.990772)
			(xy 396.255494 -168.978326) (xy 392.730736 -160.468818) (xy 392.722738 -160.448608) (xy 392.711458 -160.406634)
			(xy 392.705735 -160.363549) (xy 392.705336 -160.341818) (xy 392.705336 -158.65729) (xy 392.70432 -158.647384)
			(xy 390.192006 -146.01444) (xy 390.189043 -145.998476) (xy 390.185864 -145.96616) (xy 390.185656 -145.949924)
			(xy 390.185656 -123.91009) (xy 390.18523 -123.900022) (xy 390.177508 -123.881424) (xy 390.17067 -123.874022)
			(xy 387.834378 -121.53773) (xy 387.826907 -121.53099) (xy 387.808318 -121.523348) (xy 387.788219 -121.5234)
			(xy 387.778752 -121.526808) (xy 387.75132 -121.538238) (xy 387.74751 -121.543826) (xy 387.74751 -125.71095)
			(xy 387.747078 -125.721016) (xy 387.739352 -125.739609) (xy 387.732524 -125.747018) (xy 386.40639 -127.073152)
			(xy 386.398993 -127.080002) (xy 386.380395 -127.087741) (xy 386.370322 -127.088138) (xy 384.871468 -127.088138)
			(xy 384.858917 -127.088788) (xy 384.836799 -127.100655) (xy 384.829304 -127.110744) (xy 384.588512 -127.470662)
			(xy 384.586734 -127.48133) (xy 384.57915 -127.52201) (xy 384.558108 -127.602049) (xy 384.530509 -127.680069)
			(xy 384.496543 -127.755536) (xy 384.456443 -127.82793) (xy 384.433826 -127.862584) (xy 384.193796 -128.22174)
			(xy 384.171304 -128.254693) (xy 384.121812 -128.317277) (xy 384.067471 -128.375702) (xy 384.00863 -128.429591)
			(xy 383.977388 -128.454404) (xy 383.971149 -128.459607) (xy 383.962098 -128.473086) (xy 383.959608 -128.48082)
			(xy 383.948592 -128.51926) (xy 383.921224 -128.594402) (xy 383.887932 -128.667114) (xy 383.848929 -128.736929)
			(xy 383.82702 -128.77038) (xy 383.586736 -129.12979) (xy 383.561032 -129.167328) (xy 383.503791 -129.23805)
			(xy 383.472436 -129.271014) (xy 383.466058 -129.278065) (xy 383.458622 -129.295548) (xy 383.458107 -129.314539)
			(xy 383.461006 -129.323592) (xy 383.491994 -129.409698) (xy 383.495625 -129.418444) (xy 383.50806 -129.432703)
			(xy 383.524804 -129.441511) (xy 383.534158 -129.442972) (xy 383.579742 -129.448503) (xy 383.669717 -129.466871)
			(xy 383.757622 -129.49343) (xy 383.842715 -129.527955) (xy 383.924275 -129.570156) (xy 384.001611 -129.619673)
			(xy 384.074068 -129.676089) (xy 384.141034 -129.738925) (xy 384.201942 -129.80765) (xy 384.256276 -129.881681)
			(xy 384.28041 -129.920746) (xy 384.283007 -129.924724) (xy 384.2894 -129.931748) (xy 384.29311 -129.934716)
			(xy 384.31573 -129.952904) (xy 384.355725 -129.994964) (xy 384.388888 -130.042596) (xy 384.414456 -130.094702)
			(xy 384.431837 -130.150078) (xy 384.440632 -130.207448) (xy 384.441192 -130.236468) (xy 384.441192 -130.236976)
			(xy 384.440679 -130.266278) (xy 384.431752 -130.324197) (xy 384.423412 -130.352292) (xy 384.422061 -130.356798)
			(xy 384.420907 -130.366135) (xy 384.421126 -130.370834) (xy 384.422014 -130.386694) (xy 384.422903 -130.41845)
			(xy 384.422904 -130.434334) (xy 384.422468 -130.476701) (xy 384.415279 -130.56113) (xy 384.400946 -130.644643)
			(xy 384.379573 -130.726638) (xy 384.351315 -130.806521) (xy 384.334258 -130.845306) (xy 384.330295 -130.855347)
			(xy 384.330308 -130.876914) (xy 384.334258 -130.886962) (xy 384.351299 -130.925751) (xy 384.379531 -131.005641)
			(xy 384.40089 -131.087635) (xy 384.415223 -131.171145) (xy 384.422427 -131.255569) (xy 384.422904 -131.297934)
			(xy 384.422898 -131.313755) (xy 384.422011 -131.345384) (xy 384.421126 -131.36118) (xy 384.420881 -131.365868)
			(xy 384.421901 -131.375199) (xy 384.423158 -131.379722) (xy 384.430357 -131.403647) (xy 384.439153 -131.452829)
			(xy 384.440684 -131.477766) (xy 384.441192 -131.483354) (xy 384.440938 -131.483354) (xy 384.440938 -131.483862)
			(xy 384.441192 -131.484878) (xy 384.441896 -131.494717) (xy 384.449779 -131.512778) (xy 384.463886 -131.526537)
			(xy 384.482139 -131.533966) (xy 384.491992 -131.534408) (xy 385.3434 -131.534408) (xy 385.353121 -131.533924)
			(xy 385.371139 -131.526608) (xy 385.378452 -131.520184) (xy 385.40932 -131.491265) (xy 385.475169 -131.438165)
			(xy 385.545278 -131.390831) (xy 385.619143 -131.349603) (xy 385.696233 -131.314777) (xy 385.775995 -131.286602)
			(xy 385.857856 -131.265282) (xy 385.941228 -131.250968) (xy 386.025512 -131.243765) (xy 386.067808 -131.243324)
			(xy 386.114496 -131.243874) (xy 386.207462 -131.252616) (xy 386.299204 -131.270014) (xy 386.388916 -131.295914)
			(xy 386.475813 -131.330091) (xy 386.559134 -131.372244) (xy 386.638147 -131.422003) (xy 386.712161 -131.478934)
			(xy 386.780527 -131.542537) (xy 386.842645 -131.612254) (xy 386.897971 -131.687475) (xy 386.922518 -131.727194)
			(xy 386.925113 -131.731174) (xy 386.931502 -131.738204) (xy 386.935218 -131.741164) (xy 386.95784 -131.75935)
			(xy 386.997839 -131.801408) (xy 387.031004 -131.84904) (xy 387.056572 -131.901146) (xy 387.073951 -131.956524)
			(xy 387.082741 -132.013895) (xy 387.0833 -132.042916) (xy 387.0833 -132.043424) (xy 387.082783 -132.072725)
			(xy 387.07385 -132.130643) (xy 387.06552 -132.15874) (xy 387.064182 -132.163249) (xy 387.06304 -132.172583)
			(xy 387.063234 -132.177282) (xy 387.064123 -132.193142) (xy 387.065014 -132.224898) (xy 387.065012 -132.240782)
			(xy 387.064578 -132.28315) (xy 387.057393 -132.36758) (xy 387.043064 -132.451095) (xy 387.021695 -132.533091)
			(xy 386.993441 -132.612977) (xy 386.976366 -132.651754) (xy 386.972392 -132.661795) (xy 386.972385 -132.683372)
			(xy 386.976366 -132.69341) (xy 386.993409 -132.732199) (xy 387.021645 -132.812088) (xy 387.043008 -132.894082)
			(xy 387.057345 -132.977592) (xy 387.064553 -133.062016) (xy 387.065012 -133.104382) (xy 387.065008 -133.120266)
			(xy 387.064118 -133.152022) (xy 387.063234 -133.167882) (xy 387.063062 -133.17258) (xy 387.064208 -133.18191)
			(xy 387.06552 -133.186424) (xy 387.073845 -133.214522) (xy 387.082771 -133.272439) (xy 387.0833 -133.30174)
			(xy 387.0833 -133.301994) (xy 387.082759 -133.331034) (xy 387.073968 -133.388444) (xy 387.056587 -133.443861)
			(xy 387.031018 -133.496009) (xy 386.99785 -133.543686) (xy 386.957846 -133.585792) (xy 386.935218 -133.604)
			(xy 386.931551 -133.606956) (xy 386.925279 -133.613982) (xy 386.922772 -133.61797) (xy 386.900345 -133.654435)
			(xy 386.850144 -133.723786) (xy 386.794182 -133.788578) (xy 386.73287 -133.848332) (xy 386.666661 -133.902609)
			(xy 386.596041 -133.95101) (xy 386.521532 -133.993177) (xy 386.443681 -134.028801) (xy 386.363063 -134.057618)
			(xy 386.280271 -134.079417) (xy 386.195914 -134.094036) (xy 386.110615 -134.101369) (xy 386.067808 -134.10184)
			(xy 386.025497 -134.101392) (xy 385.94118 -134.094223) (xy 385.857773 -134.079935) (xy 385.775877 -134.05863)
			(xy 385.69608 -134.030464) (xy 385.618958 -133.995637) (xy 385.545063 -133.9544) (xy 385.474929 -133.907051)
			(xy 385.409058 -133.853929) (xy 385.378198 -133.82498) (xy 385.370832 -133.817868) (xy 385.353052 -133.810756)
			(xy 385.222496 -133.810756) (xy 385.216488 -133.810929) (xy 385.20481 -133.813762) (xy 385.199382 -133.816344)
			(xy 385.159326 -133.836203) (xy 385.076352 -133.869512) (xy 384.990727 -133.895254) (xy 384.90314 -133.913221)
			(xy 384.814296 -133.923268) (xy 384.769614 -133.924802) (xy 384.760216 -133.925056) (xy 384.601466 -133.990842)
			(xy 384.583357 -133.998274) (xy 384.546642 -134.011865) (xy 384.52806 -134.01802) (xy 384.506978 -134.024624)
			(xy 384.467608 -134.035546) (xy 384.45948 -134.037578) (xy 384.452622 -134.041896) (xy 384.449612 -134.043899)
			(xy 384.444135 -134.048621) (xy 384.4417 -134.051294) (xy 384.43535 -134.059168) (xy 384.43281 -134.062216)
			(xy 384.42799 -134.068592) (xy 384.422177 -134.083472) (xy 384.42138 -134.091426) (xy 384.418227 -134.137135)
			(xy 384.404582 -134.227743) (xy 384.382673 -134.316715) (xy 384.352685 -134.403299) (xy 384.334258 -134.445248)
			(xy 384.330283 -134.45529) (xy 384.330274 -134.476867) (xy 384.334258 -134.486904) (xy 384.351302 -134.525693)
			(xy 384.379538 -134.605582) (xy 384.400902 -134.687576) (xy 384.415239 -134.771086) (xy 384.422448 -134.85551)
			(xy 384.422904 -134.897876) (xy 384.422901 -134.91376) (xy 384.42201 -134.945516) (xy 384.421126 -134.961376)
			(xy 384.420954 -134.966074) (xy 384.422098 -134.975404) (xy 384.423412 -134.979918) (xy 384.431301 -135.006422)
			(xy 384.440229 -135.060994) (xy 384.441192 -135.08863) (xy 384.441192 -135.09498) (xy 384.441192 -135.09625)
			(xy 384.441192 -135.10133) (xy 384.440768 -135.118851) (xy 384.43708 -135.153705) (xy 384.433826 -135.170926)
			(xy 384.433064 -135.174228) (xy 384.432355 -135.180812) (xy 384.434024 -135.193943) (xy 384.436366 -135.200136)
			(xy 384.438906 -135.206232) (xy 384.443224 -135.21182) (xy 384.451352 -135.220202) (xy 384.490976 -135.249158)
			(xy 384.491484 -135.249158) (xy 384.5306 -135.277352) (xy 384.532886 -135.278876) (xy 384.560826 -135.262874)
			(xy 384.598227 -135.242285) (xy 384.675902 -135.206829) (xy 384.756322 -135.178142) (xy 384.8389 -135.156435)
			(xy 384.923031 -135.141866) (xy 385.0081 -135.134541) (xy 385.050792 -135.134096) (xy 385.3434 -135.134096)
			(xy 385.353095 -135.133658) (xy 385.371102 -135.126465) (xy 385.378452 -135.120126) (xy 385.40931 -135.091224)
			(xy 385.475138 -135.038158) (xy 385.545224 -134.990858) (xy 385.619064 -134.949664) (xy 385.696127 -134.91487)
			(xy 385.77586 -134.886728) (xy 385.85769 -134.86544) (xy 385.941028 -134.851157) (xy 386.025277 -134.843984)
			(xy 386.067554 -134.84352) (xy 386.067808 -134.84352) (xy 386.114508 -134.844065) (xy 386.207497 -134.852799)
			(xy 386.299263 -134.870189) (xy 386.389001 -134.896082) (xy 386.475925 -134.930253) (xy 386.559273 -134.972402)
			(xy 386.638315 -135.022158) (xy 386.712359 -135.079088) (xy 386.780755 -135.14269) (xy 386.842905 -135.21241)
			(xy 386.898264 -135.287635) (xy 386.922772 -135.32739) (xy 386.925286 -135.331373) (xy 386.931544 -135.338412)
			(xy 386.935218 -135.34136) (xy 386.95784 -135.359546) (xy 386.997839 -135.401604) (xy 387.031005 -135.449235)
			(xy 387.056574 -135.501342) (xy 387.073953 -135.55672) (xy 387.082744 -135.614091) (xy 387.0833 -135.643112)
			(xy 387.0833 -135.643366) (xy 387.082788 -135.672668) (xy 387.073863 -135.730588) (xy 387.06552 -135.758682)
			(xy 387.064177 -135.76319) (xy 387.063023 -135.772525) (xy 387.063234 -135.777224) (xy 387.064123 -135.793084)
			(xy 387.065012 -135.82484) (xy 387.065012 -135.840724) (xy 387.064577 -135.883091) (xy 387.057388 -135.96752)
			(xy 387.043056 -136.051034) (xy 387.021684 -136.133029) (xy 386.993427 -136.212913) (xy 386.976366 -136.251696)
			(xy 386.972401 -136.261737) (xy 386.97241 -136.283306) (xy 386.976366 -136.293352) (xy 386.993408 -136.332141)
			(xy 387.02164 -136.41203) (xy 387.043 -136.494025) (xy 387.057333 -136.577535) (xy 387.064538 -136.661959)
			(xy 387.065012 -136.704324) (xy 387.065009 -136.720208) (xy 387.064121 -136.751964) (xy 387.063234 -136.767824)
			(xy 387.063066 -136.772521) (xy 387.064219 -136.781849) (xy 387.06552 -136.786366) (xy 387.073849 -136.814464)
			(xy 387.082784 -136.872381) (xy 387.0833 -136.901682) (xy 387.0833 -136.90219) (xy 387.08273 -136.931187)
			(xy 387.073898 -136.988507) (xy 387.056496 -137.04383) (xy 387.030926 -137.095884) (xy 386.997774 -137.143471)
			(xy 386.957806 -137.185495) (xy 386.935218 -137.203688) (xy 386.93155 -137.206644) (xy 386.925277 -137.213669)
			(xy 386.922772 -137.217658) (xy 386.90254 -137.250645) (xy 386.85768 -137.313708) (xy 386.808067 -137.373106)
			(xy 386.781294 -137.401046) (xy 386.774706 -137.408425) (xy 386.767246 -137.426724) (xy 386.766816 -137.436606)
			(xy 386.767324 -137.508488) (xy 386.767842 -137.518387) (xy 386.775422 -137.536683) (xy 386.782056 -137.544048)
			(xy 386.839968 -137.60196) (xy 386.874173 -137.636969) (xy 386.936289 -137.712619) (xy 386.99069 -137.793994)
			(xy 387.036851 -137.88031) (xy 387.056122 -137.925302) (xy 387.512052 -139.02563) (xy 387.530314 -139.071238)
			(xy 387.558814 -139.165264) (xy 387.568948 -139.213336) (xy 387.605778 -139.397486) (xy 387.610096 -139.407646)
			(xy 387.613652 -139.412218) (xy 387.639729 -139.448073) (xy 387.686138 -139.523623) (xy 387.725665 -139.60299)
			(xy 387.757999 -139.685549) (xy 387.782885 -139.77065) (xy 387.79196 -139.814046) (xy 387.88594 -140.287756)
			(xy 387.894922 -140.335768) (xy 387.904593 -140.432971) (xy 387.905244 -140.481812) (xy 387.904941 -140.517497)
			(xy 387.899858 -140.588686) (xy 387.895084 -140.624052) (xy 387.894173 -140.632683) (xy 387.897555 -140.649694)
			(xy 387.901688 -140.657326) (xy 387.922993 -140.69407) (xy 387.960001 -140.770527) (xy 387.990381 -140.849852)
			(xy 388.013913 -140.93147) (xy 388.022592 -140.973048) (xy 388.118858 -141.45895) (xy 388.127768 -141.506905)
			(xy 388.137313 -141.60398) (xy 388.137908 -141.652752) (xy 388.137603 -141.688437) (xy 388.132518 -141.759626)
			(xy 388.127748 -141.794992) (xy 388.126827 -141.803625) (xy 388.130195 -141.820645) (xy 388.134352 -141.828266)
			(xy 388.155657 -141.86501) (xy 388.192663 -141.941468) (xy 388.223041 -142.020793) (xy 388.24657 -142.102412)
			(xy 388.255256 -142.143988) (xy 388.298944 -142.364714) (xy 388.316216 -142.38478) (xy 388.328916 -142.389352)
			(xy 388.356333 -142.399687) (xy 388.407872 -142.427558) (xy 388.454543 -142.462982) (xy 388.495248 -142.505125)
			(xy 388.529031 -142.552997) (xy 388.555096 -142.605471) (xy 388.572832 -142.661314) (xy 388.58182 -142.719212)
			(xy 388.582408 -142.748508) (xy 388.582408 -142.748762) (xy 388.581897 -142.777426) (xy 388.573337 -142.834112)
			(xy 388.556401 -142.888882) (xy 388.531471 -142.940507) (xy 388.499108 -142.987826) (xy 388.460036 -143.029779)
			(xy 388.437882 -143.047974) (xy 388.429466 -143.055352) (xy 388.419474 -143.075349) (xy 388.418948 -143.097697)
			(xy 388.422896 -143.108172) (xy 388.444061 -143.15819) (xy 388.47665 -143.261799) (xy 388.48792 -143.314928)
			(xy 388.584186 -143.80083) (xy 388.593097 -143.848785) (xy 388.602643 -143.94586) (xy 388.603236 -143.994632)
			(xy 388.602932 -144.030317) (xy 388.597848 -144.101506) (xy 388.593076 -144.136872) (xy 388.592169 -144.145502)
			(xy 388.595556 -144.16251) (xy 388.59968 -144.170146) (xy 388.620985 -144.20689) (xy 388.657992 -144.283348)
			(xy 388.68837 -144.362673) (xy 388.711901 -144.444291) (xy 388.720584 -144.485868) (xy 388.81685 -144.97177)
			(xy 388.825759 -145.019725) (xy 388.835302 -145.1168) (xy 388.8359 -145.165572) (xy 388.835595 -145.201257)
			(xy 388.830507 -145.272445) (xy 388.82574 -145.307812) (xy 388.824822 -145.316444) (xy 388.828196 -145.333461)
			(xy 388.832344 -145.341086) (xy 388.853647 -145.377831) (xy 388.890648 -145.45429) (xy 388.921022 -145.533616)
			(xy 388.944547 -145.615235) (xy 388.953248 -145.656808) (xy 389.049514 -146.14271) (xy 389.058422 -146.190665)
			(xy 389.067961 -146.28774) (xy 389.068564 -146.336512) (xy 389.068261 -146.372197) (xy 389.063178 -146.443386)
			(xy 389.058404 -146.478752) (xy 389.057493 -146.487383) (xy 389.060876 -146.504393) (xy 389.065008 -146.512026)
			(xy 389.086313 -146.54877) (xy 389.123321 -146.625227) (xy 389.1537 -146.704552) (xy 389.177231 -146.786171)
			(xy 389.185912 -146.827748) (xy 389.282178 -147.31365) (xy 389.291088 -147.361605) (xy 389.300632 -147.45868)
			(xy 389.301228 -147.507452) (xy 389.3009 -147.54032) (xy 389.29645 -147.605905) (xy 389.292338 -147.638516)
			(xy 389.291566 -147.64733) (xy 389.295332 -147.664606) (xy 389.299704 -147.672298) (xy 389.32341 -147.711045)
			(xy 389.364474 -147.792076) (xy 389.397999 -147.876506) (xy 389.423708 -147.963634) (xy 389.433054 -148.008086)
			(xy 389.529574 -148.494242) (xy 389.538524 -148.542319) (xy 389.548068 -148.639652) (xy 389.548624 -148.688552)
			(xy 389.548104 -148.734349) (xy 389.539705 -148.825557) (xy 389.522984 -148.915611) (xy 389.511032 -148.959824)
			(xy 389.50773 -148.971508) (xy 393.626182 -169.710862) (xy 397.16151 -169.710862) (xy 397.165581 -169.65524)
			(xy 397.177707 -169.600803) (xy 397.19763 -169.548712) (xy 397.224926 -169.500077) (xy 397.259012 -169.455934)
			(xy 397.299161 -169.417225) (xy 397.344519 -169.384774) (xy 397.394119 -169.359273) (xy 397.446903 -169.341266)
			(xy 397.501746 -169.331136) (xy 397.55748 -169.329099) (xy 397.612917 -169.335199) (xy 397.666874 -169.349305)
			(xy 397.718203 -169.371117) (xy 397.765809 -169.400171) (xy 397.808677 -169.435846) (xy 397.845894 -169.477383)
			(xy 397.876667 -169.523896) (xy 397.900339 -169.574393) (xy 397.916407 -169.6278) (xy 397.924527 -169.682976)
			(xy 397.925036 -169.710862) (xy 397.924527 -169.738748) (xy 397.916407 -169.793924) (xy 397.900339 -169.847331)
			(xy 397.876667 -169.897828) (xy 397.845894 -169.944341) (xy 397.808677 -169.985878) (xy 397.765809 -170.021553)
			(xy 397.718203 -170.050607) (xy 397.666874 -170.072419) (xy 397.612917 -170.086525) (xy 397.55748 -170.092625)
			(xy 397.501746 -170.090588) (xy 397.446903 -170.080458) (xy 397.394119 -170.062451) (xy 397.344519 -170.03695)
			(xy 397.299161 -170.004499) (xy 397.259012 -169.96579) (xy 397.224926 -169.921647) (xy 397.19763 -169.873012)
			(xy 397.177707 -169.820921) (xy 397.165581 -169.766484) (xy 397.16151 -169.710862) (xy 393.626182 -169.710862)
			(xy 394.083434 -172.013455) (xy 398.255149 -172.013455) (xy 398.255149 -171.958945) (xy 398.262907 -171.90499)
			(xy 398.278266 -171.852689) (xy 398.300911 -171.803105) (xy 398.330383 -171.75725) (xy 398.366081 -171.716055)
			(xy 398.407279 -171.680361) (xy 398.453137 -171.650894) (xy 398.502722 -171.628253) (xy 398.555025 -171.6129)
			(xy 398.608981 -171.605147) (xy 398.636236 -171.604686) (xy 398.667039 -171.605289) (xy 398.72784 -171.615218)
			(xy 398.786254 -171.634794) (xy 398.813782 -171.648628) (xy 398.81429 -171.648882) (xy 398.819601 -171.651382)
			(xy 398.831027 -171.65407) (xy 398.836896 -171.654216) (xy 399.863564 -171.654216) (xy 399.873634 -171.653794)
			(xy 399.892233 -171.646073) (xy 399.899632 -171.63923) (xy 402.019262 -169.5196) (xy 402.026089 -169.51219)
			(xy 402.033818 -169.493598) (xy 402.034248 -169.483532) (xy 402.034248 -164.56279) (xy 402.033842 -164.552718)
			(xy 402.026109 -164.53412) (xy 402.019262 -164.526722) (xy 398.56029 -161.06775) (xy 398.542196 -161.048952)
			(xy 398.511511 -161.006758) (xy 398.487809 -160.960281) (xy 398.471672 -160.910668) (xy 398.463498 -160.85914)
			(xy 398.463008 -160.833054) (xy 398.463008 -147.226782) (xy 398.463467 -147.200694) (xy 398.471638 -147.14916)
			(xy 398.487776 -147.099542) (xy 398.511483 -147.053061) (xy 398.542174 -147.010865) (xy 398.56029 -146.992086)
			(xy 398.849088 -146.703288) (xy 398.853197 -146.698889) (xy 398.859487 -146.688629) (xy 398.861534 -146.682968)
			(xy 398.861534 -146.68246) (xy 398.870017 -146.656929) (xy 398.893083 -146.608325) (xy 398.922749 -146.563445)
			(xy 398.958425 -146.523177) (xy 398.999404 -146.48832) (xy 399.044874 -146.459566) (xy 399.093932 -146.437485)
			(xy 399.145606 -146.422515) (xy 399.198871 -146.414953) (xy 399.22577 -146.41449) (xy 399.253022 -146.414983)
			(xy 399.306972 -146.422736) (xy 399.359269 -146.438088) (xy 399.408849 -146.460727) (xy 399.454702 -146.490192)
			(xy 399.495895 -146.525882) (xy 399.531589 -146.567072) (xy 399.561058 -146.612923) (xy 399.583701 -146.662501)
			(xy 399.599057 -146.714797) (xy 399.606815 -146.768746) (xy 399.607278 -146.795998) (xy 399.606792 -146.822908)
			(xy 399.599215 -146.876192) (xy 399.584226 -146.927883) (xy 399.562122 -146.976955) (xy 399.533342 -147.022433)
			(xy 399.498456 -147.063416) (xy 399.458157 -147.09909) (xy 399.413246 -147.128747) (xy 399.364612 -147.151799)
			(xy 399.339054 -147.160234) (xy 399.3388 -147.160234) (xy 399.333113 -147.162228) (xy 399.322835 -147.168514)
			(xy 399.31848 -147.17268) (xy 399.14195 -147.34921) (xy 399.13512 -147.356618) (xy 399.127393 -147.375211)
			(xy 399.126964 -147.385278) (xy 399.126964 -151.257) (xy 400.877022 -151.257) (xy 400.881093 -151.201378)
			(xy 400.893219 -151.146941) (xy 400.913142 -151.09485) (xy 400.940438 -151.046215) (xy 400.974524 -151.002072)
			(xy 401.014673 -150.963363) (xy 401.060031 -150.930912) (xy 401.109631 -150.905411) (xy 401.162415 -150.887404)
			(xy 401.217258 -150.877274) (xy 401.272992 -150.875237) (xy 401.328429 -150.881337) (xy 401.382386 -150.895443)
			(xy 401.433715 -150.917255) (xy 401.481321 -150.946309) (xy 401.524189 -150.981984) (xy 401.561406 -151.023521)
			(xy 401.592179 -151.070034) (xy 401.615851 -151.120531) (xy 401.631919 -151.173938) (xy 401.640039 -151.229114)
			(xy 401.640548 -151.257) (xy 401.640039 -151.284886) (xy 401.631919 -151.340062) (xy 401.615851 -151.393469)
			(xy 401.592179 -151.443966) (xy 401.561406 -151.490479) (xy 401.524189 -151.532016) (xy 401.481321 -151.567691)
			(xy 401.433715 -151.596745) (xy 401.382386 -151.618557) (xy 401.328429 -151.632663) (xy 401.272992 -151.638763)
			(xy 401.217258 -151.636726) (xy 401.162415 -151.626596) (xy 401.109631 -151.608589) (xy 401.060031 -151.583088)
			(xy 401.014673 -151.550637) (xy 400.974524 -151.511928) (xy 400.940438 -151.467785) (xy 400.913142 -151.41915)
			(xy 400.893219 -151.367059) (xy 400.881093 -151.312622) (xy 400.877022 -151.257) (xy 399.126964 -151.257)
			(xy 399.126964 -153.560018) (xy 400.750022 -153.560018) (xy 400.754093 -153.504396) (xy 400.766219 -153.449959)
			(xy 400.786142 -153.397868) (xy 400.813438 -153.349233) (xy 400.847524 -153.30509) (xy 400.887673 -153.266381)
			(xy 400.933031 -153.23393) (xy 400.982631 -153.208429) (xy 401.035415 -153.190422) (xy 401.090258 -153.180292)
			(xy 401.145992 -153.178255) (xy 401.201429 -153.184355) (xy 401.255386 -153.198461) (xy 401.306715 -153.220273)
			(xy 401.354321 -153.249327) (xy 401.397189 -153.285002) (xy 401.434406 -153.326539) (xy 401.465179 -153.373052)
			(xy 401.488851 -153.423549) (xy 401.504919 -153.476956) (xy 401.513039 -153.532132) (xy 401.513548 -153.560018)
			(xy 401.513039 -153.587904) (xy 401.504919 -153.64308) (xy 401.488851 -153.696487) (xy 401.465179 -153.746984)
			(xy 401.434406 -153.793497) (xy 401.397189 -153.835034) (xy 401.354321 -153.870709) (xy 401.306715 -153.899763)
			(xy 401.255386 -153.921575) (xy 401.201429 -153.935681) (xy 401.145992 -153.941781) (xy 401.090258 -153.939744)
			(xy 401.035415 -153.929614) (xy 400.982631 -153.911607) (xy 400.933031 -153.886106) (xy 400.887673 -153.853655)
			(xy 400.847524 -153.814946) (xy 400.813438 -153.770803) (xy 400.786142 -153.722168) (xy 400.766219 -153.670077)
			(xy 400.754093 -153.61564) (xy 400.750022 -153.560018) (xy 399.126964 -153.560018) (xy 399.126964 -154.159966)
			(xy 399.607022 -154.159966) (xy 399.611093 -154.104344) (xy 399.623219 -154.049907) (xy 399.643142 -153.997816)
			(xy 399.670438 -153.949181) (xy 399.704524 -153.905038) (xy 399.744673 -153.866329) (xy 399.790031 -153.833878)
			(xy 399.839631 -153.808377) (xy 399.892415 -153.79037) (xy 399.947258 -153.78024) (xy 400.002992 -153.778203)
			(xy 400.058429 -153.784303) (xy 400.112386 -153.798409) (xy 400.163715 -153.820221) (xy 400.211321 -153.849275)
			(xy 400.254189 -153.88495) (xy 400.291406 -153.926487) (xy 400.322179 -153.973) (xy 400.345851 -154.023497)
			(xy 400.361919 -154.076904) (xy 400.370039 -154.13208) (xy 400.370548 -154.159966) (xy 400.370039 -154.187852)
			(xy 400.361919 -154.243028) (xy 400.345851 -154.296435) (xy 400.322179 -154.346932) (xy 400.291406 -154.393445)
			(xy 400.254189 -154.434982) (xy 400.211321 -154.470657) (xy 400.163715 -154.499711) (xy 400.112386 -154.521523)
			(xy 400.058429 -154.535629) (xy 400.002992 -154.541729) (xy 399.947258 -154.539692) (xy 399.892415 -154.529562)
			(xy 399.839631 -154.511555) (xy 399.790031 -154.486054) (xy 399.744673 -154.453603) (xy 399.704524 -154.414894)
			(xy 399.670438 -154.370751) (xy 399.643142 -154.322116) (xy 399.623219 -154.270025) (xy 399.611093 -154.215588)
			(xy 399.607022 -154.159966) (xy 399.126964 -154.159966) (xy 399.126964 -154.958288) (xy 401.044154 -154.958288)
			(xy 401.048225 -154.902666) (xy 401.060351 -154.848229) (xy 401.080274 -154.796138) (xy 401.10757 -154.747503)
			(xy 401.141656 -154.70336) (xy 401.181805 -154.664651) (xy 401.227163 -154.6322) (xy 401.276763 -154.606699)
			(xy 401.329547 -154.588692) (xy 401.38439 -154.578562) (xy 401.440124 -154.576525) (xy 401.495561 -154.582625)
			(xy 401.549518 -154.596731) (xy 401.600847 -154.618543) (xy 401.648453 -154.647597) (xy 401.691321 -154.683272)
			(xy 401.728538 -154.724809) (xy 401.759311 -154.771322) (xy 401.782983 -154.821819) (xy 401.799051 -154.875226)
			(xy 401.807171 -154.930402) (xy 401.80768 -154.958288) (xy 401.807171 -154.986174) (xy 401.799051 -155.04135)
			(xy 401.782983 -155.094757) (xy 401.759311 -155.145254) (xy 401.728538 -155.191767) (xy 401.691321 -155.233304)
			(xy 401.648453 -155.268979) (xy 401.600847 -155.298033) (xy 401.549518 -155.319845) (xy 401.495561 -155.333951)
			(xy 401.440124 -155.340051) (xy 401.38439 -155.338014) (xy 401.329547 -155.327884) (xy 401.276763 -155.309877)
			(xy 401.227163 -155.284376) (xy 401.181805 -155.251925) (xy 401.141656 -155.213216) (xy 401.10757 -155.169073)
			(xy 401.080274 -155.120438) (xy 401.060351 -155.068347) (xy 401.048225 -155.01391) (xy 401.044154 -154.958288)
			(xy 399.126964 -154.958288) (xy 399.126964 -155.598368) (xy 399.668236 -155.598368) (xy 399.672307 -155.542746)
			(xy 399.684433 -155.488309) (xy 399.704356 -155.436218) (xy 399.731652 -155.387583) (xy 399.765738 -155.34344)
			(xy 399.805887 -155.304731) (xy 399.851245 -155.27228) (xy 399.900845 -155.246779) (xy 399.953629 -155.228772)
			(xy 400.008472 -155.218642) (xy 400.064206 -155.216605) (xy 400.119643 -155.222705) (xy 400.1736 -155.236811)
			(xy 400.224929 -155.258623) (xy 400.272535 -155.287677) (xy 400.315403 -155.323352) (xy 400.35262 -155.364889)
			(xy 400.383393 -155.411402) (xy 400.407065 -155.461899) (xy 400.423133 -155.515306) (xy 400.431253 -155.570482)
			(xy 400.431762 -155.598368) (xy 400.431253 -155.626254) (xy 400.423133 -155.68143) (xy 400.407065 -155.734837)
			(xy 400.383393 -155.785334) (xy 400.35262 -155.831847) (xy 400.315403 -155.873384) (xy 400.272535 -155.909059)
			(xy 400.224929 -155.938113) (xy 400.1736 -155.959925) (xy 400.119643 -155.974031) (xy 400.064206 -155.980131)
			(xy 400.008472 -155.978094) (xy 399.953629 -155.967964) (xy 399.900845 -155.949957) (xy 399.851245 -155.924456)
			(xy 399.805887 -155.892005) (xy 399.765738 -155.853296) (xy 399.731652 -155.809153) (xy 399.704356 -155.760518)
			(xy 399.684433 -155.708427) (xy 399.672307 -155.65399) (xy 399.668236 -155.598368) (xy 399.126964 -155.598368)
			(xy 399.126964 -156.544518) (xy 401.027898 -156.544518) (xy 401.031969 -156.488896) (xy 401.044095 -156.434459)
			(xy 401.064018 -156.382368) (xy 401.091314 -156.333733) (xy 401.1254 -156.28959) (xy 401.165549 -156.250881)
			(xy 401.210907 -156.21843) (xy 401.260507 -156.192929) (xy 401.313291 -156.174922) (xy 401.368134 -156.164792)
			(xy 401.423868 -156.162755) (xy 401.479305 -156.168855) (xy 401.533262 -156.182961) (xy 401.584591 -156.204773)
			(xy 401.632197 -156.233827) (xy 401.675065 -156.269502) (xy 401.712282 -156.311039) (xy 401.743055 -156.357552)
			(xy 401.766727 -156.408049) (xy 401.782795 -156.461456) (xy 401.790915 -156.516632) (xy 401.791424 -156.544518)
			(xy 401.790915 -156.572404) (xy 401.782795 -156.62758) (xy 401.766727 -156.680987) (xy 401.743055 -156.731484)
			(xy 401.712282 -156.777997) (xy 401.675065 -156.819534) (xy 401.632197 -156.855209) (xy 401.584591 -156.884263)
			(xy 401.533262 -156.906075) (xy 401.479305 -156.920181) (xy 401.423868 -156.926281) (xy 401.368134 -156.924244)
			(xy 401.313291 -156.914114) (xy 401.260507 -156.896107) (xy 401.210907 -156.870606) (xy 401.165549 -156.838155)
			(xy 401.1254 -156.799446) (xy 401.091314 -156.755303) (xy 401.064018 -156.706668) (xy 401.044095 -156.654577)
			(xy 401.031969 -156.60014) (xy 401.027898 -156.544518) (xy 399.126964 -156.544518) (xy 399.126964 -157.0736)
			(xy 399.596862 -157.0736) (xy 399.600933 -157.017978) (xy 399.613059 -156.963541) (xy 399.632982 -156.91145)
			(xy 399.660278 -156.862815) (xy 399.694364 -156.818672) (xy 399.734513 -156.779963) (xy 399.779871 -156.747512)
			(xy 399.829471 -156.722011) (xy 399.882255 -156.704004) (xy 399.937098 -156.693874) (xy 399.992832 -156.691837)
			(xy 400.048269 -156.697937) (xy 400.102226 -156.712043) (xy 400.153555 -156.733855) (xy 400.201161 -156.762909)
			(xy 400.244029 -156.798584) (xy 400.281246 -156.840121) (xy 400.312019 -156.886634) (xy 400.335691 -156.937131)
			(xy 400.351759 -156.990538) (xy 400.359879 -157.045714) (xy 400.360388 -157.0736) (xy 400.359879 -157.101486)
			(xy 400.351759 -157.156662) (xy 400.335691 -157.210069) (xy 400.312019 -157.260566) (xy 400.281246 -157.307079)
			(xy 400.244029 -157.348616) (xy 400.201161 -157.384291) (xy 400.153555 -157.413345) (xy 400.102226 -157.435157)
			(xy 400.048269 -157.449263) (xy 399.992832 -157.455363) (xy 399.937098 -157.453326) (xy 399.882255 -157.443196)
			(xy 399.829471 -157.425189) (xy 399.779871 -157.399688) (xy 399.734513 -157.367237) (xy 399.694364 -157.328528)
			(xy 399.660278 -157.284385) (xy 399.632982 -157.23575) (xy 399.613059 -157.183659) (xy 399.600933 -157.129222)
			(xy 399.596862 -157.0736) (xy 399.126964 -157.0736) (xy 399.126964 -160.674558) (xy 399.127394 -160.684627)
			(xy 399.13511 -160.703226) (xy 399.14195 -160.710626) (xy 402.600922 -164.169598) (xy 402.619041 -164.188372)
			(xy 402.649722 -164.230573) (xy 402.67342 -164.277056) (xy 402.689551 -164.326675) (xy 402.697718 -164.378207)
			(xy 402.698204 -164.404294) (xy 402.698204 -169.642028) (xy 402.697685 -169.668114) (xy 402.689528 -169.719644)
			(xy 402.673404 -169.769262) (xy 402.64971 -169.815744) (xy 402.619032 -169.857942) (xy 402.600922 -169.876724)
			(xy 400.256756 -172.22089) (xy 400.237996 -172.239026) (xy 400.195792 -172.269705) (xy 400.149306 -172.293401)
			(xy 400.099684 -172.309528) (xy 400.048149 -172.317689) (xy 400.02206 -172.318172) (xy 398.8308 -172.318172)
			(xy 398.819624 -172.320712) (xy 398.81429 -172.323506) (xy 398.813274 -172.324014) (xy 398.785802 -172.337744)
			(xy 398.727553 -172.357196) (xy 398.666941 -172.367068) (xy 398.636236 -172.367702) (xy 398.608981 -172.367253)
			(xy 398.555025 -172.3595) (xy 398.502722 -172.344147) (xy 398.453137 -172.321506) (xy 398.407279 -172.292039)
			(xy 398.366081 -172.256345) (xy 398.330383 -172.21515) (xy 398.300911 -172.169295) (xy 398.278266 -172.119711)
			(xy 398.262907 -172.06741) (xy 398.255149 -172.013455) (xy 394.083434 -172.013455) (xy 394.162003 -172.409104)
			(xy 400.429982 -172.409104) (xy 400.434053 -172.353482) (xy 400.446179 -172.299045) (xy 400.466102 -172.246954)
			(xy 400.493398 -172.198319) (xy 400.527484 -172.154176) (xy 400.567633 -172.115467) (xy 400.612991 -172.083016)
			(xy 400.662591 -172.057515) (xy 400.715375 -172.039508) (xy 400.770218 -172.029378) (xy 400.825952 -172.027341)
			(xy 400.881389 -172.033441) (xy 400.935346 -172.047547) (xy 400.986675 -172.069359) (xy 401.034281 -172.098413)
			(xy 401.077149 -172.134088) (xy 401.114366 -172.175625) (xy 401.145139 -172.222138) (xy 401.168811 -172.272635)
			(xy 401.184879 -172.326042) (xy 401.192999 -172.381218) (xy 401.193508 -172.409104) (xy 401.192999 -172.43699)
			(xy 401.184879 -172.492166) (xy 401.168811 -172.545573) (xy 401.145139 -172.59607) (xy 401.114366 -172.642583)
			(xy 401.077149 -172.68412) (xy 401.034281 -172.719795) (xy 400.986675 -172.748849) (xy 400.935346 -172.770661)
			(xy 400.881389 -172.784767) (xy 400.825952 -172.790867) (xy 400.770218 -172.78883) (xy 400.715375 -172.7787)
			(xy 400.662591 -172.760693) (xy 400.612991 -172.735192) (xy 400.567633 -172.702741) (xy 400.527484 -172.664032)
			(xy 400.493398 -172.619889) (xy 400.466102 -172.571254) (xy 400.446179 -172.519163) (xy 400.434053 -172.464726)
			(xy 400.429982 -172.409104) (xy 394.162003 -172.409104) (xy 394.575356 -174.490634) (xy 398.11147 -174.490634)
			(xy 398.115541 -174.435012) (xy 398.127667 -174.380575) (xy 398.14759 -174.328484) (xy 398.174886 -174.279849)
			(xy 398.208972 -174.235706) (xy 398.249121 -174.196997) (xy 398.294479 -174.164546) (xy 398.344079 -174.139045)
			(xy 398.396863 -174.121038) (xy 398.451706 -174.110908) (xy 398.50744 -174.108871) (xy 398.562877 -174.114971)
			(xy 398.616834 -174.129077) (xy 398.668163 -174.150889) (xy 398.715769 -174.179943) (xy 398.758637 -174.215618)
			(xy 398.795854 -174.257155) (xy 398.826627 -174.303668) (xy 398.850299 -174.354165) (xy 398.866367 -174.407572)
			(xy 398.874487 -174.462748) (xy 398.874996 -174.490634) (xy 398.874487 -174.51852) (xy 398.866367 -174.573696)
			(xy 398.850299 -174.627103) (xy 398.826627 -174.6776) (xy 398.795854 -174.724113) (xy 398.758637 -174.76565)
			(xy 398.715769 -174.801325) (xy 398.668163 -174.830379) (xy 398.616834 -174.852191) (xy 398.562877 -174.866297)
			(xy 398.50744 -174.872397) (xy 398.451706 -174.87036) (xy 398.396863 -174.86023) (xy 398.344079 -174.842223)
			(xy 398.294479 -174.816722) (xy 398.249121 -174.784271) (xy 398.208972 -174.745562) (xy 398.174886 -174.701419)
			(xy 398.14759 -174.652784) (xy 398.127667 -174.600693) (xy 398.115541 -174.546256) (xy 398.11147 -174.490634)
			(xy 394.575356 -174.490634) (xy 394.841375 -175.83023) (xy 410.059884 -175.83023) (xy 410.063955 -175.774608)
			(xy 410.076081 -175.720171) (xy 410.096004 -175.66808) (xy 410.1233 -175.619445) (xy 410.157386 -175.575302)
			(xy 410.197535 -175.536593) (xy 410.242893 -175.504142) (xy 410.292493 -175.478641) (xy 410.345277 -175.460634)
			(xy 410.40012 -175.450504) (xy 410.455854 -175.448467) (xy 410.511291 -175.454567) (xy 410.565248 -175.468673)
			(xy 410.616577 -175.490485) (xy 410.664183 -175.519539) (xy 410.707051 -175.555214) (xy 410.744268 -175.596751)
			(xy 410.775041 -175.643264) (xy 410.798713 -175.693761) (xy 410.814781 -175.747168) (xy 410.822901 -175.802344)
			(xy 410.82341 -175.83023) (xy 410.822901 -175.858116) (xy 410.814781 -175.913292) (xy 410.798713 -175.966699)
			(xy 410.775041 -176.017196) (xy 410.744268 -176.063709) (xy 410.707051 -176.105246) (xy 410.664183 -176.140921)
			(xy 410.616577 -176.169975) (xy 410.565248 -176.191787) (xy 410.511291 -176.205893) (xy 410.455854 -176.211993)
			(xy 410.40012 -176.209956) (xy 410.345277 -176.199826) (xy 410.292493 -176.181819) (xy 410.242893 -176.156318)
			(xy 410.197535 -176.123867) (xy 410.157386 -176.085158) (xy 410.1233 -176.041015) (xy 410.096004 -175.99238)
			(xy 410.076081 -175.940289) (xy 410.063955 -175.885852) (xy 410.059884 -175.83023) (xy 394.841375 -175.83023)
			(xy 395.530129 -179.2986) (xy 409.269182 -179.2986) (xy 409.273253 -179.242978) (xy 409.285379 -179.188541)
			(xy 409.305302 -179.13645) (xy 409.332598 -179.087815) (xy 409.366684 -179.043672) (xy 409.406833 -179.004963)
			(xy 409.452191 -178.972512) (xy 409.501791 -178.947011) (xy 409.554575 -178.929004) (xy 409.609418 -178.918874)
			(xy 409.665152 -178.916837) (xy 409.720589 -178.922937) (xy 409.774546 -178.937043) (xy 409.825875 -178.958855)
			(xy 409.873481 -178.987909) (xy 409.916349 -179.023584) (xy 409.953566 -179.065121) (xy 409.984339 -179.111634)
			(xy 410.008011 -179.162131) (xy 410.024079 -179.215538) (xy 410.032199 -179.270714) (xy 410.032708 -179.2986)
			(xy 411.250382 -179.2986) (xy 411.254453 -179.242978) (xy 411.266579 -179.188541) (xy 411.286502 -179.13645)
			(xy 411.313798 -179.087815) (xy 411.347884 -179.043672) (xy 411.388033 -179.004963) (xy 411.433391 -178.972512)
			(xy 411.482991 -178.947011) (xy 411.535775 -178.929004) (xy 411.590618 -178.918874) (xy 411.646352 -178.916837)
			(xy 411.701789 -178.922937) (xy 411.755746 -178.937043) (xy 411.807075 -178.958855) (xy 411.854681 -178.987909)
			(xy 411.897549 -179.023584) (xy 411.934766 -179.065121) (xy 411.965539 -179.111634) (xy 411.989211 -179.162131)
			(xy 412.005279 -179.215538) (xy 412.013399 -179.270714) (xy 412.013908 -179.2986) (xy 412.013399 -179.326486)
			(xy 412.005279 -179.381662) (xy 411.989211 -179.435069) (xy 411.965539 -179.485566) (xy 411.934766 -179.532079)
			(xy 411.897549 -179.573616) (xy 411.854681 -179.609291) (xy 411.807075 -179.638345) (xy 411.755746 -179.660157)
			(xy 411.701789 -179.674263) (xy 411.646352 -179.680363) (xy 411.590618 -179.678326) (xy 411.535775 -179.668196)
			(xy 411.482991 -179.650189) (xy 411.433391 -179.624688) (xy 411.388033 -179.592237) (xy 411.347884 -179.553528)
			(xy 411.313798 -179.509385) (xy 411.286502 -179.46075) (xy 411.266579 -179.408659) (xy 411.254453 -179.354222)
			(xy 411.250382 -179.2986) (xy 410.032708 -179.2986) (xy 410.032199 -179.326486) (xy 410.024079 -179.381662)
			(xy 410.008011 -179.435069) (xy 409.984339 -179.485566) (xy 409.953566 -179.532079) (xy 409.916349 -179.573616)
			(xy 409.873481 -179.609291) (xy 409.825875 -179.638345) (xy 409.774546 -179.660157) (xy 409.720589 -179.674263)
			(xy 409.665152 -179.680363) (xy 409.609418 -179.678326) (xy 409.554575 -179.668196) (xy 409.501791 -179.650189)
			(xy 409.452191 -179.624688) (xy 409.406833 -179.592237) (xy 409.366684 -179.553528) (xy 409.332598 -179.509385)
			(xy 409.305302 -179.46075) (xy 409.285379 -179.408659) (xy 409.273253 -179.354222) (xy 409.269182 -179.2986)
			(xy 395.530129 -179.2986) (xy 395.615473 -179.728368) (xy 399.71675 -179.728368) (xy 399.720821 -179.672746)
			(xy 399.732947 -179.618309) (xy 399.75287 -179.566218) (xy 399.780166 -179.517583) (xy 399.814252 -179.47344)
			(xy 399.854401 -179.434731) (xy 399.899759 -179.40228) (xy 399.949359 -179.376779) (xy 400.002143 -179.358772)
			(xy 400.056986 -179.348642) (xy 400.11272 -179.346605) (xy 400.168157 -179.352705) (xy 400.222114 -179.366811)
			(xy 400.273443 -179.388623) (xy 400.321049 -179.417677) (xy 400.363917 -179.453352) (xy 400.401134 -179.494889)
			(xy 400.431907 -179.541402) (xy 400.455579 -179.591899) (xy 400.471647 -179.645306) (xy 400.479767 -179.700482)
			(xy 400.480276 -179.728368) (xy 400.479767 -179.756254) (xy 400.471647 -179.81143) (xy 400.455579 -179.864837)
			(xy 400.431907 -179.915334) (xy 400.401134 -179.961847) (xy 400.363917 -180.003384) (xy 400.321049 -180.039059)
			(xy 400.273443 -180.068113) (xy 400.222114 -180.089925) (xy 400.168157 -180.104031) (xy 400.11272 -180.110131)
			(xy 400.056986 -180.108094) (xy 400.002143 -180.097964) (xy 399.949359 -180.079957) (xy 399.899759 -180.054456)
			(xy 399.854401 -180.022005) (xy 399.814252 -179.983296) (xy 399.780166 -179.939153) (xy 399.75287 -179.890518)
			(xy 399.732947 -179.838427) (xy 399.720821 -179.78399) (xy 399.71675 -179.728368) (xy 395.615473 -179.728368)
			(xy 395.808405 -180.699918) (xy 413.180782 -180.699918) (xy 413.184853 -180.644296) (xy 413.196979 -180.589859)
			(xy 413.216902 -180.537768) (xy 413.244198 -180.489133) (xy 413.278284 -180.44499) (xy 413.318433 -180.406281)
			(xy 413.363791 -180.37383) (xy 413.413391 -180.348329) (xy 413.466175 -180.330322) (xy 413.521018 -180.320192)
			(xy 413.576752 -180.318155) (xy 413.632189 -180.324255) (xy 413.686146 -180.338361) (xy 413.737475 -180.360173)
			(xy 413.785081 -180.389227) (xy 413.827949 -180.424902) (xy 413.865166 -180.466439) (xy 413.895939 -180.512952)
			(xy 413.919611 -180.563449) (xy 413.935679 -180.616856) (xy 413.943799 -180.672032) (xy 413.944308 -180.699918)
			(xy 413.943799 -180.727804) (xy 413.935679 -180.78298) (xy 413.919611 -180.836387) (xy 413.895939 -180.886884)
			(xy 413.865166 -180.933397) (xy 413.827949 -180.974934) (xy 413.785081 -181.010609) (xy 413.737475 -181.039663)
			(xy 413.686146 -181.061475) (xy 413.632189 -181.075581) (xy 413.576752 -181.081681) (xy 413.521018 -181.079644)
			(xy 413.466175 -181.069514) (xy 413.413391 -181.051507) (xy 413.363791 -181.026006) (xy 413.318433 -180.993555)
			(xy 413.278284 -180.954846) (xy 413.244198 -180.910703) (xy 413.216902 -180.862068) (xy 413.196979 -180.809977)
			(xy 413.184853 -180.75554) (xy 413.180782 -180.699918) (xy 395.808405 -180.699918) (xy 396.363747 -183.496458)
			(xy 408.81884 -183.496458) (xy 408.822911 -183.440836) (xy 408.835037 -183.386399) (xy 408.85496 -183.334308)
			(xy 408.882256 -183.285673) (xy 408.916342 -183.24153) (xy 408.956491 -183.202821) (xy 409.001849 -183.17037)
			(xy 409.051449 -183.144869) (xy 409.104233 -183.126862) (xy 409.159076 -183.116732) (xy 409.21481 -183.114695)
			(xy 409.270247 -183.120795) (xy 409.324204 -183.134901) (xy 409.375533 -183.156713) (xy 409.423139 -183.185767)
			(xy 409.466007 -183.221442) (xy 409.503224 -183.262979) (xy 409.533997 -183.309492) (xy 409.557669 -183.359989)
			(xy 409.573737 -183.413396) (xy 409.581857 -183.468572) (xy 409.582366 -183.496458) (xy 409.581857 -183.524344)
			(xy 409.573737 -183.57952) (xy 409.557669 -183.632927) (xy 409.533997 -183.683424) (xy 409.527794 -183.6928)
			(xy 411.224982 -183.6928) (xy 411.229053 -183.637178) (xy 411.241179 -183.582741) (xy 411.261102 -183.53065)
			(xy 411.288398 -183.482015) (xy 411.322484 -183.437872) (xy 411.362633 -183.399163) (xy 411.407991 -183.366712)
			(xy 411.457591 -183.341211) (xy 411.510375 -183.323204) (xy 411.565218 -183.313074) (xy 411.620952 -183.311037)
			(xy 411.676389 -183.317137) (xy 411.730346 -183.331243) (xy 411.781675 -183.353055) (xy 411.829281 -183.382109)
			(xy 411.872149 -183.417784) (xy 411.909366 -183.459321) (xy 411.940139 -183.505834) (xy 411.963811 -183.556331)
			(xy 411.979879 -183.609738) (xy 411.987999 -183.664914) (xy 411.988508 -183.6928) (xy 411.987999 -183.720686)
			(xy 411.979879 -183.775862) (xy 411.963811 -183.829269) (xy 411.940139 -183.879766) (xy 411.909366 -183.926279)
			(xy 411.872149 -183.967816) (xy 411.829281 -184.003491) (xy 411.781675 -184.032545) (xy 411.730346 -184.054357)
			(xy 411.676389 -184.068463) (xy 411.620952 -184.074563) (xy 411.565218 -184.072526) (xy 411.510375 -184.062396)
			(xy 411.457591 -184.044389) (xy 411.407991 -184.018888) (xy 411.362633 -183.986437) (xy 411.322484 -183.947728)
			(xy 411.288398 -183.903585) (xy 411.261102 -183.85495) (xy 411.241179 -183.802859) (xy 411.229053 -183.748422)
			(xy 411.224982 -183.6928) (xy 409.527794 -183.6928) (xy 409.503224 -183.729937) (xy 409.466007 -183.771474)
			(xy 409.423139 -183.807149) (xy 409.375533 -183.836203) (xy 409.324204 -183.858015) (xy 409.270247 -183.872121)
			(xy 409.21481 -183.878221) (xy 409.159076 -183.876184) (xy 409.104233 -183.866054) (xy 409.051449 -183.848047)
			(xy 409.001849 -183.822546) (xy 408.956491 -183.790095) (xy 408.916342 -183.751386) (xy 408.882256 -183.707243)
			(xy 408.85496 -183.658608) (xy 408.835037 -183.606517) (xy 408.822911 -183.55208) (xy 408.81884 -183.496458)
			(xy 396.363747 -183.496458) (xy 396.650749 -184.941718) (xy 414.979864 -184.941718) (xy 414.983935 -184.886096)
			(xy 414.996061 -184.831659) (xy 415.015984 -184.779568) (xy 415.04328 -184.730933) (xy 415.077366 -184.68679)
			(xy 415.117515 -184.648081) (xy 415.162873 -184.61563) (xy 415.212473 -184.590129) (xy 415.265257 -184.572122)
			(xy 415.3201 -184.561992) (xy 415.375834 -184.559955) (xy 415.431271 -184.566055) (xy 415.485228 -184.580161)
			(xy 415.536557 -184.601973) (xy 415.584163 -184.631027) (xy 415.627031 -184.666702) (xy 415.664248 -184.708239)
			(xy 415.695021 -184.754752) (xy 415.718693 -184.805249) (xy 415.734761 -184.858656) (xy 415.742881 -184.913832)
			(xy 415.74339 -184.941718) (xy 415.742881 -184.969604) (xy 415.734761 -185.02478) (xy 415.718693 -185.078187)
			(xy 415.695021 -185.128684) (xy 415.664248 -185.175197) (xy 415.627031 -185.216734) (xy 415.584163 -185.252409)
			(xy 415.536557 -185.281463) (xy 415.485228 -185.303275) (xy 415.431271 -185.317381) (xy 415.375834 -185.323481)
			(xy 415.3201 -185.321444) (xy 415.265257 -185.311314) (xy 415.212473 -185.293307) (xy 415.162873 -185.267806)
			(xy 415.117515 -185.235355) (xy 415.077366 -185.196646) (xy 415.04328 -185.152503) (xy 415.015984 -185.103868)
			(xy 414.996061 -185.051777) (xy 414.983935 -184.99734) (xy 414.979864 -184.941718) (xy 396.650749 -184.941718)
			(xy 396.662148 -184.999122) (xy 396.663926 -185.005472) (xy 397.317828 -186.937142) (xy 408.89504 -186.937142)
			(xy 408.899111 -186.88152) (xy 408.911237 -186.827083) (xy 408.93116 -186.774992) (xy 408.958456 -186.726357)
			(xy 408.992542 -186.682214) (xy 409.032691 -186.643505) (xy 409.078049 -186.611054) (xy 409.127649 -186.585553)
			(xy 409.180433 -186.567546) (xy 409.235276 -186.557416) (xy 409.29101 -186.555379) (xy 409.346447 -186.561479)
			(xy 409.400404 -186.575585) (xy 409.451733 -186.597397) (xy 409.499339 -186.626451) (xy 409.542207 -186.662126)
			(xy 409.579424 -186.703663) (xy 409.610197 -186.750176) (xy 409.633869 -186.800673) (xy 409.649937 -186.85408)
			(xy 409.658057 -186.909256) (xy 409.658566 -186.937142) (xy 409.658057 -186.965028) (xy 409.649937 -187.020204)
			(xy 409.633869 -187.073611) (xy 409.610197 -187.124108) (xy 409.579424 -187.170621) (xy 409.542207 -187.212158)
			(xy 409.499339 -187.247833) (xy 409.451733 -187.276887) (xy 409.400404 -187.298699) (xy 409.346447 -187.312805)
			(xy 409.29101 -187.318905) (xy 409.235276 -187.316868) (xy 409.180433 -187.306738) (xy 409.127649 -187.288731)
			(xy 409.078049 -187.26323) (xy 409.032691 -187.230779) (xy 408.992542 -187.19207) (xy 408.958456 -187.147927)
			(xy 408.93116 -187.099292) (xy 408.911237 -187.047201) (xy 408.899111 -186.992764) (xy 408.89504 -186.937142)
			(xy 397.317828 -186.937142) (xy 397.517911 -187.5282) (xy 411.123382 -187.5282) (xy 411.127453 -187.472578)
			(xy 411.139579 -187.418141) (xy 411.159502 -187.36605) (xy 411.186798 -187.317415) (xy 411.220884 -187.273272)
			(xy 411.261033 -187.234563) (xy 411.306391 -187.202112) (xy 411.355991 -187.176611) (xy 411.408775 -187.158604)
			(xy 411.463618 -187.148474) (xy 411.519352 -187.146437) (xy 411.574789 -187.152537) (xy 411.628746 -187.166643)
			(xy 411.680075 -187.188455) (xy 411.727681 -187.217509) (xy 411.770549 -187.253184) (xy 411.807766 -187.294721)
			(xy 411.838539 -187.341234) (xy 411.862211 -187.391731) (xy 411.878279 -187.445138) (xy 411.886399 -187.500314)
			(xy 411.886908 -187.5282) (xy 411.886399 -187.556086) (xy 411.878279 -187.611262) (xy 411.862211 -187.664669)
			(xy 411.838539 -187.715166) (xy 411.807766 -187.761679) (xy 411.770549 -187.803216) (xy 411.727681 -187.838891)
			(xy 411.680075 -187.867945) (xy 411.628746 -187.889757) (xy 411.574789 -187.903863) (xy 411.519352 -187.909963)
			(xy 411.463618 -187.907926) (xy 411.408775 -187.897796) (xy 411.355991 -187.879789) (xy 411.306391 -187.854288)
			(xy 411.261033 -187.821837) (xy 411.220884 -187.783128) (xy 411.186798 -187.738985) (xy 411.159502 -187.69035)
			(xy 411.139579 -187.638259) (xy 411.127453 -187.583822) (xy 411.123382 -187.5282) (xy 397.517911 -187.5282)
			(xy 398.052469 -189.107318) (xy 410.255464 -189.107318) (xy 410.259535 -189.051696) (xy 410.271661 -188.997259)
			(xy 410.291584 -188.945168) (xy 410.31888 -188.896533) (xy 410.352966 -188.85239) (xy 410.393115 -188.813681)
			(xy 410.438473 -188.78123) (xy 410.488073 -188.755729) (xy 410.540857 -188.737722) (xy 410.5957 -188.727592)
			(xy 410.651434 -188.725555) (xy 410.706871 -188.731655) (xy 410.760828 -188.745761) (xy 410.812157 -188.767573)
			(xy 410.859763 -188.796627) (xy 410.902631 -188.832302) (xy 410.939848 -188.873839) (xy 410.970621 -188.920352)
			(xy 410.994293 -188.970849) (xy 411.010361 -189.024256) (xy 411.018481 -189.079432) (xy 411.01899 -189.107318)
			(xy 411.018481 -189.135204) (xy 411.010361 -189.19038) (xy 410.994293 -189.243787) (xy 410.970621 -189.294284)
			(xy 410.939848 -189.340797) (xy 410.902631 -189.382334) (xy 410.859763 -189.418009) (xy 410.812157 -189.447063)
			(xy 410.760828 -189.468875) (xy 410.706871 -189.482981) (xy 410.651434 -189.489081) (xy 410.5957 -189.487044)
			(xy 410.540857 -189.476914) (xy 410.488073 -189.458907) (xy 410.438473 -189.433406) (xy 410.393115 -189.400955)
			(xy 410.352966 -189.362246) (xy 410.31888 -189.318103) (xy 410.291584 -189.269468) (xy 410.271661 -189.217377)
			(xy 410.259535 -189.16294) (xy 410.255464 -189.107318) (xy 398.052469 -189.107318) (xy 398.290728 -189.811152)
			(xy 413.217104 -189.811152) (xy 413.221175 -189.75553) (xy 413.233301 -189.701093) (xy 413.253224 -189.649002)
			(xy 413.28052 -189.600367) (xy 413.314606 -189.556224) (xy 413.354755 -189.517515) (xy 413.400113 -189.485064)
			(xy 413.449713 -189.459563) (xy 413.502497 -189.441556) (xy 413.55734 -189.431426) (xy 413.613074 -189.429389)
			(xy 413.668511 -189.435489) (xy 413.722468 -189.449595) (xy 413.773797 -189.471407) (xy 413.821403 -189.500461)
			(xy 413.864271 -189.536136) (xy 413.901488 -189.577673) (xy 413.932261 -189.624186) (xy 413.955933 -189.674683)
			(xy 413.972001 -189.72809) (xy 413.980121 -189.783266) (xy 413.98063 -189.811152) (xy 413.980121 -189.839038)
			(xy 413.972001 -189.894214) (xy 413.955933 -189.947621) (xy 413.932261 -189.998118) (xy 413.901488 -190.044631)
			(xy 413.864271 -190.086168) (xy 413.821403 -190.121843) (xy 413.773797 -190.150897) (xy 413.722468 -190.172709)
			(xy 413.668511 -190.186815) (xy 413.613074 -190.192915) (xy 413.55734 -190.190878) (xy 413.502497 -190.180748)
			(xy 413.449713 -190.162741) (xy 413.400113 -190.13724) (xy 413.354755 -190.104789) (xy 413.314606 -190.06608)
			(xy 413.28052 -190.021937) (xy 413.253224 -189.973302) (xy 413.233301 -189.921211) (xy 413.221175 -189.866774)
			(xy 413.217104 -189.811152) (xy 398.290728 -189.811152) (xy 399.506445 -193.402458) (xy 409.211524 -193.402458)
			(xy 409.215595 -193.346836) (xy 409.227721 -193.292399) (xy 409.247644 -193.240308) (xy 409.27494 -193.191673)
			(xy 409.309026 -193.14753) (xy 409.349175 -193.108821) (xy 409.394533 -193.07637) (xy 409.444133 -193.050869)
			(xy 409.496917 -193.032862) (xy 409.55176 -193.022732) (xy 409.607494 -193.020695) (xy 409.662931 -193.026795)
			(xy 409.716888 -193.040901) (xy 409.768217 -193.062713) (xy 409.815823 -193.091767) (xy 409.858691 -193.127442)
			(xy 409.895908 -193.168979) (xy 409.926681 -193.215492) (xy 409.950353 -193.265989) (xy 409.951139 -193.2686)
			(xy 412.113982 -193.2686) (xy 412.118053 -193.212978) (xy 412.130179 -193.158541) (xy 412.150102 -193.10645)
			(xy 412.177398 -193.057815) (xy 412.211484 -193.013672) (xy 412.251633 -192.974963) (xy 412.296991 -192.942512)
			(xy 412.346591 -192.917011) (xy 412.399375 -192.899004) (xy 412.454218 -192.888874) (xy 412.509952 -192.886837)
			(xy 412.565389 -192.892937) (xy 412.619346 -192.907043) (xy 412.670675 -192.928855) (xy 412.718281 -192.957909)
			(xy 412.761149 -192.993584) (xy 412.798366 -193.035121) (xy 412.829139 -193.081634) (xy 412.852811 -193.132131)
			(xy 412.868879 -193.185538) (xy 412.876999 -193.240714) (xy 412.877508 -193.2686) (xy 412.876999 -193.296486)
			(xy 412.868879 -193.351662) (xy 412.852811 -193.405069) (xy 412.829139 -193.455566) (xy 412.798366 -193.502079)
			(xy 412.761149 -193.543616) (xy 412.718281 -193.579291) (xy 412.670675 -193.608345) (xy 412.619346 -193.630157)
			(xy 412.565389 -193.644263) (xy 412.509952 -193.650363) (xy 412.454218 -193.648326) (xy 412.399375 -193.638196)
			(xy 412.346591 -193.620189) (xy 412.296991 -193.594688) (xy 412.251633 -193.562237) (xy 412.211484 -193.523528)
			(xy 412.177398 -193.479385) (xy 412.150102 -193.43075) (xy 412.130179 -193.378659) (xy 412.118053 -193.324222)
			(xy 412.113982 -193.2686) (xy 409.951139 -193.2686) (xy 409.966421 -193.319396) (xy 409.974541 -193.374572)
			(xy 409.97505 -193.402458) (xy 409.974541 -193.430344) (xy 409.966421 -193.48552) (xy 409.950353 -193.538927)
			(xy 409.926681 -193.589424) (xy 409.895908 -193.635937) (xy 409.858691 -193.677474) (xy 409.815823 -193.713149)
			(xy 409.768217 -193.742203) (xy 409.716888 -193.764015) (xy 409.662931 -193.778121) (xy 409.607494 -193.784221)
			(xy 409.55176 -193.782184) (xy 409.496917 -193.772054) (xy 409.444133 -193.754047) (xy 409.394533 -193.728546)
			(xy 409.349175 -193.696095) (xy 409.309026 -193.657386) (xy 409.27494 -193.613243) (xy 409.247644 -193.564608)
			(xy 409.227721 -193.512517) (xy 409.215595 -193.45808) (xy 409.211524 -193.402458) (xy 399.506445 -193.402458)
			(xy 400.768077 -197.1294) (xy 408.430982 -197.1294) (xy 408.435053 -197.073778) (xy 408.447179 -197.019341)
			(xy 408.467102 -196.96725) (xy 408.494398 -196.918615) (xy 408.528484 -196.874472) (xy 408.568633 -196.835763)
			(xy 408.613991 -196.803312) (xy 408.663591 -196.777811) (xy 408.716375 -196.759804) (xy 408.771218 -196.749674)
			(xy 408.826952 -196.747637) (xy 408.882389 -196.753737) (xy 408.888207 -196.755258) (xy 413.72104 -196.755258)
			(xy 413.725111 -196.699636) (xy 413.737237 -196.645199) (xy 413.75716 -196.593108) (xy 413.784456 -196.544473)
			(xy 413.818542 -196.50033) (xy 413.858691 -196.461621) (xy 413.904049 -196.42917) (xy 413.953649 -196.403669)
			(xy 414.006433 -196.385662) (xy 414.061276 -196.375532) (xy 414.11701 -196.373495) (xy 414.172447 -196.379595)
			(xy 414.226404 -196.393701) (xy 414.277733 -196.415513) (xy 414.325339 -196.444567) (xy 414.368207 -196.480242)
			(xy 414.405424 -196.521779) (xy 414.436197 -196.568292) (xy 414.459869 -196.618789) (xy 414.475937 -196.672196)
			(xy 414.484057 -196.727372) (xy 414.484566 -196.755258) (xy 414.484057 -196.783144) (xy 414.475937 -196.83832)
			(xy 414.459869 -196.891727) (xy 414.436197 -196.942224) (xy 414.405424 -196.988737) (xy 414.368207 -197.030274)
			(xy 414.325339 -197.065949) (xy 414.277733 -197.095003) (xy 414.226404 -197.116815) (xy 414.172447 -197.130921)
			(xy 414.11701 -197.137021) (xy 414.061276 -197.134984) (xy 414.006433 -197.124854) (xy 413.953649 -197.106847)
			(xy 413.904049 -197.081346) (xy 413.858691 -197.048895) (xy 413.818542 -197.010186) (xy 413.784456 -196.966043)
			(xy 413.75716 -196.917408) (xy 413.737237 -196.865317) (xy 413.725111 -196.81088) (xy 413.72104 -196.755258)
			(xy 408.888207 -196.755258) (xy 408.936346 -196.767843) (xy 408.987675 -196.789655) (xy 409.035281 -196.818709)
			(xy 409.078149 -196.854384) (xy 409.115366 -196.895921) (xy 409.146139 -196.942434) (xy 409.169811 -196.992931)
			(xy 409.185879 -197.046338) (xy 409.193999 -197.101514) (xy 409.194508 -197.1294) (xy 409.193999 -197.157286)
			(xy 409.185879 -197.212462) (xy 409.169811 -197.265869) (xy 409.146139 -197.316366) (xy 409.115366 -197.362879)
			(xy 409.078149 -197.404416) (xy 409.035281 -197.440091) (xy 408.987675 -197.469145) (xy 408.936346 -197.490957)
			(xy 408.882389 -197.505063) (xy 408.826952 -197.511163) (xy 408.771218 -197.509126) (xy 408.716375 -197.498996)
			(xy 408.663591 -197.480989) (xy 408.613991 -197.455488) (xy 408.568633 -197.423037) (xy 408.528484 -197.384328)
			(xy 408.494398 -197.340185) (xy 408.467102 -197.29155) (xy 408.447179 -197.239459) (xy 408.435053 -197.185022)
			(xy 408.430982 -197.1294) (xy 400.768077 -197.1294) (xy 401.131528 -198.203058) (xy 408.97124 -198.203058)
			(xy 408.975311 -198.147436) (xy 408.987437 -198.092999) (xy 409.00736 -198.040908) (xy 409.034656 -197.992273)
			(xy 409.068742 -197.94813) (xy 409.108891 -197.909421) (xy 409.154249 -197.87697) (xy 409.203849 -197.851469)
			(xy 409.256633 -197.833462) (xy 409.311476 -197.823332) (xy 409.36721 -197.821295) (xy 409.422647 -197.827395)
			(xy 409.476604 -197.841501) (xy 409.527933 -197.863313) (xy 409.575539 -197.892367) (xy 409.618407 -197.928042)
			(xy 409.655624 -197.969579) (xy 409.686397 -198.016092) (xy 409.710069 -198.066589) (xy 409.726137 -198.119996)
			(xy 409.734257 -198.175172) (xy 409.734766 -198.203058) (xy 409.734257 -198.230944) (xy 409.726137 -198.28612)
			(xy 409.710069 -198.339527) (xy 409.686397 -198.390024) (xy 409.655624 -198.436537) (xy 409.618407 -198.478074)
			(xy 409.575539 -198.513749) (xy 409.527933 -198.542803) (xy 409.476604 -198.564615) (xy 409.422647 -198.578721)
			(xy 409.36721 -198.584821) (xy 409.311476 -198.582784) (xy 409.256633 -198.572654) (xy 409.203849 -198.554647)
			(xy 409.154249 -198.529146) (xy 409.108891 -198.496695) (xy 409.068742 -198.457986) (xy 409.034656 -198.413843)
			(xy 409.00736 -198.365208) (xy 408.987437 -198.313117) (xy 408.975311 -198.25868) (xy 408.97124 -198.203058)
			(xy 401.131528 -198.203058) (xy 401.733411 -199.981058) (xy 413.61944 -199.981058) (xy 413.623511 -199.925436)
			(xy 413.635637 -199.870999) (xy 413.65556 -199.818908) (xy 413.682856 -199.770273) (xy 413.716942 -199.72613)
			(xy 413.757091 -199.687421) (xy 413.802449 -199.65497) (xy 413.852049 -199.629469) (xy 413.904833 -199.611462)
			(xy 413.959676 -199.601332) (xy 414.01541 -199.599295) (xy 414.070847 -199.605395) (xy 414.124804 -199.619501)
			(xy 414.176133 -199.641313) (xy 414.223739 -199.670367) (xy 414.266607 -199.706042) (xy 414.303824 -199.747579)
			(xy 414.334597 -199.794092) (xy 414.358269 -199.844589) (xy 414.374337 -199.897996) (xy 414.382457 -199.953172)
			(xy 414.382966 -199.981058) (xy 414.382457 -200.008944) (xy 414.374337 -200.06412) (xy 414.358269 -200.117527)
			(xy 414.334597 -200.168024) (xy 414.303824 -200.214537) (xy 414.266607 -200.256074) (xy 414.223739 -200.291749)
			(xy 414.176133 -200.320803) (xy 414.124804 -200.342615) (xy 414.070847 -200.356721) (xy 414.01541 -200.362821)
			(xy 413.959676 -200.360784) (xy 413.904833 -200.350654) (xy 413.852049 -200.332647) (xy 413.802449 -200.307146)
			(xy 413.757091 -200.274695) (xy 413.716942 -200.235986) (xy 413.682856 -200.191843) (xy 413.65556 -200.143208)
			(xy 413.635637 -200.091117) (xy 413.623511 -200.03668) (xy 413.61944 -199.981058) (xy 401.733411 -199.981058)
			(xy 402.40408 -201.962258) (xy 409.033724 -201.962258) (xy 409.037795 -201.906636) (xy 409.049921 -201.852199)
			(xy 409.069844 -201.800108) (xy 409.09714 -201.751473) (xy 409.131226 -201.70733) (xy 409.171375 -201.668621)
			(xy 409.216733 -201.63617) (xy 409.266333 -201.610669) (xy 409.319117 -201.592662) (xy 409.37396 -201.582532)
			(xy 409.429694 -201.580495) (xy 409.485131 -201.586595) (xy 409.539088 -201.600701) (xy 409.590417 -201.622513)
			(xy 409.638023 -201.651567) (xy 409.680891 -201.687242) (xy 409.718108 -201.728779) (xy 409.748881 -201.775292)
			(xy 409.772553 -201.825789) (xy 409.788621 -201.879196) (xy 409.796741 -201.934372) (xy 409.79725 -201.962258)
			(xy 409.796741 -201.990144) (xy 409.788621 -202.04532) (xy 409.772553 -202.098727) (xy 409.748881 -202.149224)
			(xy 409.718108 -202.195737) (xy 409.680891 -202.237274) (xy 409.638023 -202.272949) (xy 409.590417 -202.302003)
			(xy 409.539088 -202.323815) (xy 409.485131 -202.337921) (xy 409.429694 -202.344021) (xy 409.37396 -202.341984)
			(xy 409.319117 -202.331854) (xy 409.266333 -202.313847) (xy 409.216733 -202.288346) (xy 409.171375 -202.255895)
			(xy 409.131226 -202.217186) (xy 409.09714 -202.173043) (xy 409.069844 -202.124408) (xy 409.049921 -202.072317)
			(xy 409.037795 -202.01788) (xy 409.033724 -201.962258) (xy 402.40408 -201.962258) (xy 402.945774 -203.562458)
			(xy 413.13684 -203.562458) (xy 413.140911 -203.506836) (xy 413.153037 -203.452399) (xy 413.17296 -203.400308)
			(xy 413.200256 -203.351673) (xy 413.234342 -203.30753) (xy 413.274491 -203.268821) (xy 413.319849 -203.23637)
			(xy 413.369449 -203.210869) (xy 413.422233 -203.192862) (xy 413.477076 -203.182732) (xy 413.53281 -203.180695)
			(xy 413.588247 -203.186795) (xy 413.642204 -203.200901) (xy 413.693533 -203.222713) (xy 413.741139 -203.251767)
			(xy 413.784007 -203.287442) (xy 413.821224 -203.328979) (xy 413.851997 -203.375492) (xy 413.875669 -203.425989)
			(xy 413.891737 -203.479396) (xy 413.899857 -203.534572) (xy 413.900366 -203.562458) (xy 413.899857 -203.590344)
			(xy 413.891737 -203.64552) (xy 413.875669 -203.698927) (xy 413.851997 -203.749424) (xy 413.821224 -203.795937)
			(xy 413.784007 -203.837474) (xy 413.741139 -203.873149) (xy 413.693533 -203.902203) (xy 413.642204 -203.924015)
			(xy 413.588247 -203.938121) (xy 413.53281 -203.944221) (xy 413.477076 -203.942184) (xy 413.422233 -203.932054)
			(xy 413.369449 -203.914047) (xy 413.319849 -203.888546) (xy 413.274491 -203.856095) (xy 413.234342 -203.817386)
			(xy 413.200256 -203.773243) (xy 413.17296 -203.724608) (xy 413.153037 -203.672517) (xy 413.140911 -203.61808)
			(xy 413.13684 -203.562458) (xy 402.945774 -203.562458) (xy 403.147577 -204.158596) (xy 407.590242 -204.158596)
			(xy 407.594313 -204.102974) (xy 407.606439 -204.048537) (xy 407.626362 -203.996446) (xy 407.653658 -203.947811)
			(xy 407.687744 -203.903668) (xy 407.727893 -203.864959) (xy 407.773251 -203.832508) (xy 407.822851 -203.807007)
			(xy 407.875635 -203.789) (xy 407.930478 -203.77887) (xy 407.986212 -203.776833) (xy 408.041649 -203.782933)
			(xy 408.095606 -203.797039) (xy 408.146935 -203.818851) (xy 408.194541 -203.847905) (xy 408.237409 -203.88358)
			(xy 408.274626 -203.925117) (xy 408.305399 -203.97163) (xy 408.329071 -204.022127) (xy 408.345139 -204.075534)
			(xy 408.353259 -204.13071) (xy 408.353768 -204.158596) (xy 408.353259 -204.186482) (xy 408.345139 -204.241658)
			(xy 408.329071 -204.295065) (xy 408.305399 -204.345562) (xy 408.274626 -204.392075) (xy 408.237409 -204.433612)
			(xy 408.194541 -204.469287) (xy 408.146935 -204.498341) (xy 408.095606 -204.520153) (xy 408.041649 -204.534259)
			(xy 407.986212 -204.540359) (xy 407.930478 -204.538322) (xy 407.875635 -204.528192) (xy 407.822851 -204.510185)
			(xy 407.773251 -204.484684) (xy 407.727893 -204.452233) (xy 407.687744 -204.413524) (xy 407.653658 -204.369381)
			(xy 407.626362 -204.320746) (xy 407.606439 -204.268655) (xy 407.594313 -204.214218) (xy 407.590242 -204.158596)
			(xy 403.147577 -204.158596) (xy 404.470945 -208.06791) (xy 407.722068 -208.06791) (xy 407.726139 -208.012288)
			(xy 407.738265 -207.957851) (xy 407.758188 -207.90576) (xy 407.785484 -207.857125) (xy 407.81957 -207.812982)
			(xy 407.859719 -207.774273) (xy 407.905077 -207.741822) (xy 407.954677 -207.716321) (xy 408.007461 -207.698314)
			(xy 408.062304 -207.688184) (xy 408.118038 -207.686147) (xy 408.173475 -207.692247) (xy 408.227432 -207.706353)
			(xy 408.278761 -207.728165) (xy 408.326367 -207.757219) (xy 408.369235 -207.792894) (xy 408.406452 -207.834431)
			(xy 408.437225 -207.880944) (xy 408.460897 -207.931441) (xy 408.476965 -207.984848) (xy 408.485085 -208.040024)
			(xy 408.485594 -208.06791) (xy 408.485085 -208.095796) (xy 408.476965 -208.150972) (xy 408.460897 -208.204379)
			(xy 408.437225 -208.254876) (xy 408.406452 -208.301389) (xy 408.369235 -208.342926) (xy 408.326367 -208.378601)
			(xy 408.278761 -208.407655) (xy 408.227432 -208.429467) (xy 408.173475 -208.443573) (xy 408.118038 -208.449673)
			(xy 408.062304 -208.447636) (xy 408.007461 -208.437506) (xy 407.954677 -208.419499) (xy 407.905077 -208.393998)
			(xy 407.859719 -208.361547) (xy 407.81957 -208.322838) (xy 407.785484 -208.278695) (xy 407.758188 -208.23006)
			(xy 407.738265 -208.177969) (xy 407.726139 -208.123532) (xy 407.722068 -208.06791) (xy 404.470945 -208.06791)
			(xy 405.240667 -210.341718) (xy 409.3497 -210.341718) (xy 409.353771 -210.286096) (xy 409.365897 -210.231659)
			(xy 409.38582 -210.179568) (xy 409.413116 -210.130933) (xy 409.447202 -210.08679) (xy 409.487351 -210.048081)
			(xy 409.532709 -210.01563) (xy 409.582309 -209.990129) (xy 409.635093 -209.972122) (xy 409.689936 -209.961992)
			(xy 409.74567 -209.959955) (xy 409.801107 -209.966055) (xy 409.855064 -209.980161) (xy 409.906393 -210.001973)
			(xy 409.953999 -210.031027) (xy 409.996867 -210.066702) (xy 410.034084 -210.108239) (xy 410.064857 -210.154752)
			(xy 410.088529 -210.205249) (xy 410.104597 -210.258656) (xy 410.112717 -210.313832) (xy 410.113226 -210.341718)
			(xy 410.112717 -210.369604) (xy 410.104597 -210.42478) (xy 410.088529 -210.478187) (xy 410.064857 -210.528684)
			(xy 410.034084 -210.575197) (xy 409.996867 -210.616734) (xy 409.953999 -210.652409) (xy 409.906393 -210.681463)
			(xy 409.855064 -210.703275) (xy 409.801107 -210.717381) (xy 409.74567 -210.723481) (xy 409.689936 -210.721444)
			(xy 409.635093 -210.711314) (xy 409.582309 -210.693307) (xy 409.532709 -210.667806) (xy 409.487351 -210.635355)
			(xy 409.447202 -210.596646) (xy 409.413116 -210.552503) (xy 409.38582 -210.503868) (xy 409.365897 -210.451777)
			(xy 409.353771 -210.39734) (xy 409.3497 -210.341718) (xy 405.240667 -210.341718) (xy 408.958238 -221.323662)
			(xy 417.33419 -221.323662) (xy 417.338261 -221.26804) (xy 417.350387 -221.213603) (xy 417.37031 -221.161512)
			(xy 417.397606 -221.112877) (xy 417.431692 -221.068734) (xy 417.471841 -221.030025) (xy 417.517199 -220.997574)
			(xy 417.566799 -220.972073) (xy 417.619583 -220.954066) (xy 417.674426 -220.943936) (xy 417.73016 -220.941899)
			(xy 417.785597 -220.947999) (xy 417.839554 -220.962105) (xy 417.890883 -220.983917) (xy 417.938489 -221.012971)
			(xy 417.981357 -221.048646) (xy 418.018574 -221.090183) (xy 418.049347 -221.136696) (xy 418.073019 -221.187193)
			(xy 418.089087 -221.2406) (xy 418.097207 -221.295776) (xy 418.097716 -221.323662) (xy 418.097207 -221.351548)
			(xy 418.089087 -221.406724) (xy 418.073019 -221.460131) (xy 418.049347 -221.510628) (xy 418.018574 -221.557141)
			(xy 417.981357 -221.598678) (xy 417.938489 -221.634353) (xy 417.890883 -221.663407) (xy 417.839554 -221.685219)
			(xy 417.785597 -221.699325) (xy 417.73016 -221.705425) (xy 417.674426 -221.703388) (xy 417.619583 -221.693258)
			(xy 417.566799 -221.675251) (xy 417.517199 -221.64975) (xy 417.471841 -221.617299) (xy 417.431692 -221.57859)
			(xy 417.397606 -221.534447) (xy 417.37031 -221.485812) (xy 417.350387 -221.433721) (xy 417.338261 -221.379284)
			(xy 417.33419 -221.323662) (xy 408.958238 -221.323662) (xy 409.82727 -223.89084) (xy 418.05809 -223.89084)
			(xy 418.062161 -223.835218) (xy 418.074287 -223.780781) (xy 418.09421 -223.72869) (xy 418.121506 -223.680055)
			(xy 418.155592 -223.635912) (xy 418.195741 -223.597203) (xy 418.241099 -223.564752) (xy 418.290699 -223.539251)
			(xy 418.343483 -223.521244) (xy 418.398326 -223.511114) (xy 418.45406 -223.509077) (xy 418.509497 -223.515177)
			(xy 418.563454 -223.529283) (xy 418.614783 -223.551095) (xy 418.662389 -223.580149) (xy 418.705257 -223.615824)
			(xy 418.742474 -223.657361) (xy 418.773247 -223.703874) (xy 418.796919 -223.754371) (xy 418.812987 -223.807778)
			(xy 418.821107 -223.862954) (xy 418.821616 -223.89084) (xy 418.821107 -223.918726) (xy 418.812987 -223.973902)
			(xy 418.796919 -224.027309) (xy 418.773247 -224.077806) (xy 418.742474 -224.124319) (xy 418.705257 -224.165856)
			(xy 418.662389 -224.201531) (xy 418.614783 -224.230585) (xy 418.563454 -224.252397) (xy 418.509497 -224.266503)
			(xy 418.45406 -224.272603) (xy 418.398326 -224.270566) (xy 418.343483 -224.260436) (xy 418.290699 -224.242429)
			(xy 418.241099 -224.216928) (xy 418.195741 -224.184477) (xy 418.155592 -224.145768) (xy 418.121506 -224.101625)
			(xy 418.09421 -224.05299) (xy 418.074287 -224.000899) (xy 418.062161 -223.946462) (xy 418.05809 -223.89084)
			(xy 409.82727 -223.89084) (xy 410.283067 -225.237294) (xy 414.952686 -225.237294) (xy 414.956757 -225.181672)
			(xy 414.968883 -225.127235) (xy 414.988806 -225.075144) (xy 415.016102 -225.026509) (xy 415.050188 -224.982366)
			(xy 415.090337 -224.943657) (xy 415.135695 -224.911206) (xy 415.185295 -224.885705) (xy 415.238079 -224.867698)
			(xy 415.292922 -224.857568) (xy 415.348656 -224.855531) (xy 415.404093 -224.861631) (xy 415.45805 -224.875737)
			(xy 415.509379 -224.897549) (xy 415.556985 -224.926603) (xy 415.599853 -224.962278) (xy 415.63707 -225.003815)
			(xy 415.667843 -225.050328) (xy 415.691515 -225.100825) (xy 415.707583 -225.154232) (xy 415.715703 -225.209408)
			(xy 415.716212 -225.237294) (xy 415.715703 -225.26518) (xy 415.707583 -225.320356) (xy 415.691515 -225.373763)
			(xy 415.667843 -225.42426) (xy 415.63707 -225.470773) (xy 415.599853 -225.51231) (xy 415.556985 -225.547985)
			(xy 415.509379 -225.577039) (xy 415.45805 -225.598851) (xy 415.404093 -225.612957) (xy 415.348656 -225.619057)
			(xy 415.292922 -225.61702) (xy 415.238079 -225.60689) (xy 415.185295 -225.588883) (xy 415.135695 -225.563382)
			(xy 415.090337 -225.530931) (xy 415.050188 -225.492222) (xy 415.016102 -225.448079) (xy 414.988806 -225.399444)
			(xy 414.968883 -225.347353) (xy 414.956757 -225.292916) (xy 414.952686 -225.237294) (xy 410.283067 -225.237294)
			(xy 412.217861 -230.952802) (xy 417.376354 -230.952802) (xy 417.380425 -230.89718) (xy 417.392551 -230.842743)
			(xy 417.412474 -230.790652) (xy 417.43977 -230.742017) (xy 417.473856 -230.697874) (xy 417.514005 -230.659165)
			(xy 417.559363 -230.626714) (xy 417.608963 -230.601213) (xy 417.661747 -230.583206) (xy 417.71659 -230.573076)
			(xy 417.772324 -230.571039) (xy 417.827761 -230.577139) (xy 417.881718 -230.591245) (xy 417.933047 -230.613057)
			(xy 417.980653 -230.642111) (xy 418.023521 -230.677786) (xy 418.060738 -230.719323) (xy 418.091511 -230.765836)
			(xy 418.115183 -230.816333) (xy 418.131251 -230.86974) (xy 418.139371 -230.924916) (xy 418.13988 -230.952802)
			(xy 418.139371 -230.980688) (xy 418.131251 -231.035864) (xy 418.115183 -231.089271) (xy 418.091511 -231.139768)
			(xy 418.060738 -231.186281) (xy 418.023521 -231.227818) (xy 417.980653 -231.263493) (xy 417.933047 -231.292547)
			(xy 417.881718 -231.314359) (xy 417.827761 -231.328465) (xy 417.772324 -231.334565) (xy 417.71659 -231.332528)
			(xy 417.661747 -231.322398) (xy 417.608963 -231.304391) (xy 417.559363 -231.27889) (xy 417.514005 -231.246439)
			(xy 417.473856 -231.20773) (xy 417.43977 -231.163587) (xy 417.412474 -231.114952) (xy 417.392551 -231.062861)
			(xy 417.380425 -231.008424) (xy 417.376354 -230.952802) (xy 412.217861 -230.952802) (xy 413.077693 -233.492802)
			(xy 414.907982 -233.492802) (xy 414.912053 -233.43718) (xy 414.924179 -233.382743) (xy 414.944102 -233.330652)
			(xy 414.971398 -233.282017) (xy 415.005484 -233.237874) (xy 415.045633 -233.199165) (xy 415.090991 -233.166714)
			(xy 415.140591 -233.141213) (xy 415.193375 -233.123206) (xy 415.248218 -233.113076) (xy 415.303952 -233.111039)
			(xy 415.359389 -233.117139) (xy 415.413346 -233.131245) (xy 415.464675 -233.153057) (xy 415.512281 -233.182111)
			(xy 415.555149 -233.217786) (xy 415.592366 -233.259323) (xy 415.623139 -233.305836) (xy 415.646811 -233.356333)
			(xy 415.662879 -233.40974) (xy 415.670999 -233.464916) (xy 415.671508 -233.492802) (xy 415.671485 -233.494072)
			(xy 418.149784 -233.494072) (xy 418.153855 -233.43845) (xy 418.165981 -233.384013) (xy 418.185904 -233.331922)
			(xy 418.2132 -233.283287) (xy 418.247286 -233.239144) (xy 418.287435 -233.200435) (xy 418.332793 -233.167984)
			(xy 418.382393 -233.142483) (xy 418.435177 -233.124476) (xy 418.49002 -233.114346) (xy 418.545754 -233.112309)
			(xy 418.601191 -233.118409) (xy 418.655148 -233.132515) (xy 418.706477 -233.154327) (xy 418.754083 -233.183381)
			(xy 418.796951 -233.219056) (xy 418.834168 -233.260593) (xy 418.864941 -233.307106) (xy 418.888613 -233.357603)
			(xy 418.904681 -233.41101) (xy 418.912801 -233.466186) (xy 418.91331 -233.494072) (xy 418.912801 -233.521958)
			(xy 418.904681 -233.577134) (xy 418.888613 -233.630541) (xy 418.864941 -233.681038) (xy 418.834168 -233.727551)
			(xy 418.796951 -233.769088) (xy 418.754083 -233.804763) (xy 418.706477 -233.833817) (xy 418.655148 -233.855629)
			(xy 418.601191 -233.869735) (xy 418.545754 -233.875835) (xy 418.49002 -233.873798) (xy 418.435177 -233.863668)
			(xy 418.382393 -233.845661) (xy 418.332793 -233.82016) (xy 418.287435 -233.787709) (xy 418.247286 -233.749)
			(xy 418.2132 -233.704857) (xy 418.185904 -233.656222) (xy 418.165981 -233.604131) (xy 418.153855 -233.549694)
			(xy 418.149784 -233.494072) (xy 415.671485 -233.494072) (xy 415.670999 -233.520688) (xy 415.662879 -233.575864)
			(xy 415.646811 -233.629271) (xy 415.623139 -233.679768) (xy 415.592366 -233.726281) (xy 415.555149 -233.767818)
			(xy 415.512281 -233.803493) (xy 415.464675 -233.832547) (xy 415.413346 -233.854359) (xy 415.359389 -233.868465)
			(xy 415.303952 -233.874565) (xy 415.248218 -233.872528) (xy 415.193375 -233.862398) (xy 415.140591 -233.844391)
			(xy 415.090991 -233.81889) (xy 415.045633 -233.786439) (xy 415.005484 -233.74773) (xy 414.971398 -233.703587)
			(xy 414.944102 -233.654952) (xy 414.924179 -233.602861) (xy 414.912053 -233.548424) (xy 414.907982 -233.492802)
			(xy 413.077693 -233.492802) (xy 415.043011 -239.29848) (xy 417.276532 -239.29848) (xy 417.280603 -239.242858)
			(xy 417.292729 -239.188421) (xy 417.312652 -239.13633) (xy 417.339948 -239.087695) (xy 417.374034 -239.043552)
			(xy 417.414183 -239.004843) (xy 417.459541 -238.972392) (xy 417.509141 -238.946891) (xy 417.561925 -238.928884)
			(xy 417.616768 -238.918754) (xy 417.672502 -238.916717) (xy 417.727939 -238.922817) (xy 417.781896 -238.936923)
			(xy 417.833225 -238.958735) (xy 417.880831 -238.987789) (xy 417.923699 -239.023464) (xy 417.960916 -239.065001)
			(xy 417.991689 -239.111514) (xy 418.015361 -239.162011) (xy 418.031429 -239.215418) (xy 418.039549 -239.270594)
			(xy 418.040058 -239.29848) (xy 418.039549 -239.326366) (xy 418.031429 -239.381542) (xy 418.015361 -239.434949)
			(xy 417.991689 -239.485446) (xy 417.960916 -239.531959) (xy 417.923699 -239.573496) (xy 417.880831 -239.609171)
			(xy 417.833225 -239.638225) (xy 417.781896 -239.660037) (xy 417.727939 -239.674143) (xy 417.672502 -239.680243)
			(xy 417.616768 -239.678206) (xy 417.561925 -239.668076) (xy 417.509141 -239.650069) (xy 417.459541 -239.624568)
			(xy 417.414183 -239.592117) (xy 417.374034 -239.553408) (xy 417.339948 -239.509265) (xy 417.312652 -239.46063)
			(xy 417.292729 -239.408539) (xy 417.280603 -239.354102) (xy 417.276532 -239.29848) (xy 415.043011 -239.29848)
			(xy 415.338278 -240.170716) (xy 418.30828 -240.170716) (xy 418.312351 -240.115094) (xy 418.324477 -240.060657)
			(xy 418.3444 -240.008566) (xy 418.371696 -239.959931) (xy 418.405782 -239.915788) (xy 418.445931 -239.877079)
			(xy 418.491289 -239.844628) (xy 418.540889 -239.819127) (xy 418.593673 -239.80112) (xy 418.648516 -239.79099)
			(xy 418.70425 -239.788953) (xy 418.759687 -239.795053) (xy 418.813644 -239.809159) (xy 418.864973 -239.830971)
			(xy 418.912579 -239.860025) (xy 418.955447 -239.8957) (xy 418.992664 -239.937237) (xy 419.023437 -239.98375)
			(xy 419.047109 -240.034247) (xy 419.063177 -240.087654) (xy 419.071297 -240.14283) (xy 419.071806 -240.170716)
			(xy 419.071297 -240.198602) (xy 419.063177 -240.253778) (xy 419.047109 -240.307185) (xy 419.023437 -240.357682)
			(xy 418.992664 -240.404195) (xy 418.955447 -240.445732) (xy 418.912579 -240.481407) (xy 418.864973 -240.510461)
			(xy 418.813644 -240.532273) (xy 418.759687 -240.546379) (xy 418.70425 -240.552479) (xy 418.648516 -240.550442)
			(xy 418.593673 -240.540312) (xy 418.540889 -240.522305) (xy 418.491289 -240.496804) (xy 418.445931 -240.464353)
			(xy 418.405782 -240.425644) (xy 418.371696 -240.381501) (xy 418.3444 -240.332866) (xy 418.324477 -240.280775)
			(xy 418.312351 -240.226338) (xy 418.30828 -240.170716) (xy 415.338278 -240.170716) (xy 415.75736 -241.408712)
			(xy 415.760915 -241.41788) (xy 415.77372 -241.432779) (xy 415.782252 -241.437668) (xy 415.845244 -241.469926)
			(xy 415.85408 -241.473949) (xy 415.873397 -241.475761) (xy 415.882836 -241.473482) (xy 415.88309 -241.473482)
			(xy 415.910127 -241.465786) (xy 415.965727 -241.457503) (xy 415.993834 -241.456972) (xy 416.021084 -241.45746)
			(xy 416.075029 -241.46522) (xy 416.127321 -241.480578) (xy 416.176895 -241.503221) (xy 416.222743 -241.532688)
			(xy 416.263931 -241.568379) (xy 416.29962 -241.609568) (xy 416.329086 -241.655417) (xy 416.351727 -241.704992)
			(xy 416.367083 -241.757284) (xy 416.374841 -241.81123) (xy 416.375342 -241.83848) (xy 416.375319 -241.83975)
			(xy 418.075362 -241.83975) (xy 418.079433 -241.784128) (xy 418.091559 -241.729691) (xy 418.111482 -241.6776)
			(xy 418.138778 -241.628965) (xy 418.172864 -241.584822) (xy 418.213013 -241.546113) (xy 418.258371 -241.513662)
			(xy 418.307971 -241.488161) (xy 418.360755 -241.470154) (xy 418.415598 -241.460024) (xy 418.471332 -241.457987)
			(xy 418.526769 -241.464087) (xy 418.580726 -241.478193) (xy 418.632055 -241.500005) (xy 418.679661 -241.529059)
			(xy 418.722529 -241.564734) (xy 418.759746 -241.606271) (xy 418.790519 -241.652784) (xy 418.814191 -241.703281)
			(xy 418.830259 -241.756688) (xy 418.838379 -241.811864) (xy 418.838888 -241.83975) (xy 418.838379 -241.867636)
			(xy 418.830259 -241.922812) (xy 418.814191 -241.976219) (xy 418.790519 -242.026716) (xy 418.759746 -242.073229)
			(xy 418.722529 -242.114766) (xy 418.679661 -242.150441) (xy 418.632055 -242.179495) (xy 418.580726 -242.201307)
			(xy 418.526769 -242.215413) (xy 418.471332 -242.221513) (xy 418.415598 -242.219476) (xy 418.360755 -242.209346)
			(xy 418.307971 -242.191339) (xy 418.258371 -242.165838) (xy 418.213013 -242.133387) (xy 418.172864 -242.094678)
			(xy 418.138778 -242.050535) (xy 418.111482 -242.0019) (xy 418.091559 -241.949809) (xy 418.079433 -241.895372)
			(xy 418.075362 -241.83975) (xy 416.375319 -241.83975) (xy 416.374809 -241.867407) (xy 416.366079 -241.924599)
			(xy 416.348818 -241.979818) (xy 416.32342 -242.031799) (xy 416.290466 -242.079351) (xy 416.250713 -242.121385)
			(xy 416.205071 -242.156936) (xy 416.154586 -242.185192) (xy 416.127692 -242.195858) (xy 416.118294 -242.19916)
			(xy 416.103816 -242.212622) (xy 416.069272 -242.28552) (xy 416.065449 -242.294574) (xy 416.064269 -242.314175)
			(xy 416.066986 -242.32362) (xy 418.29736 -248.912126) (xy 418.334698 -248.930668) (xy 418.350954 -248.925334)
			(xy 418.354764 -248.92381) (xy 418.356288 -248.923302) (xy 418.386592 -248.913477) (xy 418.449406 -248.902886)
			(xy 418.481256 -248.90222) (xy 418.48151 -248.90222) (xy 418.508762 -248.902684) (xy 418.56271 -248.910442)
			(xy 418.615005 -248.9258) (xy 418.664582 -248.948443) (xy 418.710432 -248.977912) (xy 418.751621 -249.013606)
			(xy 418.787311 -249.054798) (xy 418.816775 -249.100651) (xy 418.839414 -249.150231) (xy 418.854766 -249.202527)
			(xy 418.862519 -249.256476) (xy 418.863018 -249.283728) (xy 418.862656 -249.30481) (xy 419.084504 -249.30481)
			(xy 419.088575 -249.249188) (xy 419.100701 -249.194751) (xy 419.120624 -249.14266) (xy 419.14792 -249.094025)
			(xy 419.182006 -249.049882) (xy 419.222155 -249.011173) (xy 419.267513 -248.978722) (xy 419.317113 -248.953221)
			(xy 419.369897 -248.935214) (xy 419.42474 -248.925084) (xy 419.480474 -248.923047) (xy 419.535911 -248.929147)
			(xy 419.589868 -248.943253) (xy 419.641197 -248.965065) (xy 419.688803 -248.994119) (xy 419.731671 -249.029794)
			(xy 419.768888 -249.071331) (xy 419.799661 -249.117844) (xy 419.823333 -249.168341) (xy 419.839401 -249.221748)
			(xy 419.847521 -249.276924) (xy 419.84803 -249.30481) (xy 419.847521 -249.332696) (xy 419.839401 -249.387872)
			(xy 419.823333 -249.441279) (xy 419.799661 -249.491776) (xy 419.768888 -249.538289) (xy 419.731671 -249.579826)
			(xy 419.688803 -249.615501) (xy 419.641197 -249.644555) (xy 419.589868 -249.666367) (xy 419.535911 -249.680473)
			(xy 419.480474 -249.686573) (xy 419.42474 -249.684536) (xy 419.369897 -249.674406) (xy 419.317113 -249.656399)
			(xy 419.267513 -249.630898) (xy 419.222155 -249.598447) (xy 419.182006 -249.559738) (xy 419.14792 -249.515595)
			(xy 419.120624 -249.46696) (xy 419.100701 -249.414869) (xy 419.088575 -249.360432) (xy 419.084504 -249.30481)
			(xy 418.862656 -249.30481) (xy 418.862561 -249.310337) (xy 418.855177 -249.363041) (xy 418.840541 -249.414208)
			(xy 418.818937 -249.462845) (xy 418.790785 -249.508008) (xy 418.756631 -249.548821) (xy 418.717137 -249.584493)
			(xy 418.67307 -249.614331) (xy 418.625284 -249.637757) (xy 418.600128 -249.64644) (xy 418.59962 -249.64644)
			(xy 418.590272 -249.650109) (xy 418.575164 -249.663304) (xy 418.566252 -249.681276) (xy 418.564893 -249.70129)
			(xy 418.567616 -249.710956) (xy 419.389052 -252.137418) (xy 419.392202 -252.145739) (xy 419.403302 -252.159629)
			(xy 419.418503 -252.168854) (xy 419.427152 -252.170946) (xy 419.526974 -252.190758) (xy 419.552374 -252.182122)
			(xy 419.561518 -252.171962) (xy 419.580514 -252.151165) (xy 419.623558 -252.114841) (xy 419.671479 -252.085245)
			(xy 419.697154 -252.073664) (xy 419.7096 -252.06833) (xy 419.725602 -252.047756) (xy 419.74008 -251.94895)
			(xy 419.740989 -251.9403) (xy 419.737618 -251.923248) (xy 419.728757 -251.908294) (xy 419.7223 -251.902468)
			(xy 419.701301 -251.884242) (xy 419.66429 -251.842748) (xy 419.633698 -251.796319) (xy 419.610173 -251.745939)
			(xy 419.594214 -251.692676) (xy 419.586159 -251.637661) (xy 419.585648 -251.60986) (xy 419.586134 -251.582609)
			(xy 419.59389 -251.528661) (xy 419.609245 -251.476366) (xy 419.631887 -251.426789) (xy 419.661353 -251.380939)
			(xy 419.697044 -251.339748) (xy 419.738235 -251.304057) (xy 419.784085 -251.274591) (xy 419.833662 -251.251949)
			(xy 419.885957 -251.236594) (xy 419.939905 -251.228838) (xy 419.994407 -251.228838) (xy 420.048355 -251.236594)
			(xy 420.10065 -251.251949) (xy 420.150227 -251.274591) (xy 420.196077 -251.304057) (xy 420.237268 -251.339748)
			(xy 420.272959 -251.380939) (xy 420.302425 -251.426789) (xy 420.325067 -251.476366) (xy 420.340422 -251.528661)
			(xy 420.348178 -251.582609) (xy 420.348664 -251.60986) (xy 420.348165 -251.637652) (xy 420.340106 -251.692649)
			(xy 420.324152 -251.745895) (xy 420.300642 -251.796262) (xy 420.270072 -251.842685) (xy 420.23309 -251.884182)
			(xy 420.190478 -251.919873) (xy 420.143139 -251.949004) (xy 420.117778 -251.96038) (xy 420.105332 -251.965714)
			(xy 420.08933 -251.986288) (xy 420.074852 -252.085094) (xy 420.07395 -252.093741) (xy 420.077334 -252.110781)
			(xy 420.086205 -252.125719) (xy 420.092632 -252.131576) (xy 420.113632 -252.149802) (xy 420.150646 -252.191295)
			(xy 420.181243 -252.237724) (xy 420.204773 -252.288104) (xy 420.220738 -252.341366) (xy 420.2288 -252.396382)
			(xy 420.229284 -252.424184) (xy 420.228822 -252.451437) (xy 420.221066 -252.505388) (xy 420.205712 -252.557687)
			(xy 420.18307 -252.607267) (xy 420.153602 -252.653121) (xy 420.117908 -252.694313) (xy 420.076714 -252.730007)
			(xy 420.03086 -252.759474) (xy 419.981279 -252.782114) (xy 419.928981 -252.797468) (xy 419.875029 -252.805222)
			(xy 419.847776 -252.805692) (xy 419.82911 -252.805438) (xy 419.79196 -252.801744) (xy 419.773608 -252.798326)
			(xy 419.760146 -252.795786) (xy 419.734746 -252.804422) (xy 419.66769 -252.880876) (xy 419.662066 -252.887776)
			(xy 419.655603 -252.904349) (xy 419.655228 -252.922134) (xy 419.657784 -252.93066) (xy 419.767004 -253.253748)
			(xy 419.770903 -253.263576) (xy 419.785152 -253.279164) (xy 419.804453 -253.287737) (xy 419.81501 -253.288292)
			(xy 421.699436 -253.288292) (xy 421.710161 -253.287875) (xy 421.729768 -253.279192) (xy 421.737282 -253.271528)
			(xy 421.744394 -253.263654) (xy 421.750998 -253.243842) (xy 421.160956 -246.494046) (xy 421.160448 -246.49049)
			(xy 419.428168 -235.615226) (xy 419.425749 -235.604092) (xy 419.412833 -235.585358) (xy 419.403276 -235.579158)
			(xy 419.324536 -235.5342) (xy 419.301676 -235.532422) (xy 419.291008 -235.53674) (xy 419.268838 -235.54503)
			(xy 419.22296 -235.556682) (xy 419.175991 -235.562554) (xy 419.152324 -235.562902) (xy 419.15207 -235.562902)
			(xy 419.124821 -235.562414) (xy 419.070877 -235.554654) (xy 419.018587 -235.539297) (xy 418.969014 -235.516654)
			(xy 418.923168 -235.487188) (xy 418.881982 -235.451497) (xy 418.846294 -235.410308) (xy 418.816831 -235.36446)
			(xy 418.794193 -235.314885) (xy 418.778839 -235.262594) (xy 418.771084 -235.208649) (xy 418.771084 -235.154151)
			(xy 418.778839 -235.100206) (xy 418.794193 -235.047915) (xy 418.816831 -234.99834) (xy 418.846294 -234.952492)
			(xy 418.881982 -234.911303) (xy 418.923168 -234.875612) (xy 418.969014 -234.846146) (xy 419.018587 -234.823503)
			(xy 419.070877 -234.808146) (xy 419.124821 -234.800386) (xy 419.15207 -234.799886) (xy 419.17366 -234.800394)
			(xy 419.18509 -234.801156) (xy 419.206426 -234.79252) (xy 419.267132 -234.72521) (xy 419.274291 -234.716304)
			(xy 419.280738 -234.694415) (xy 419.279578 -234.683046) (xy 418.64534 -230.700326) (xy 418.639606 -230.661721)
			(xy 418.633501 -230.583905) (xy 418.633148 -230.544878) (xy 418.633203 -230.528928) (xy 418.634221 -230.497045)
			(xy 418.63518 -230.481124) (xy 418.944298 -225.702622) (xy 418.94445 -225.690027) (xy 418.934064 -225.667113)
			(xy 418.924486 -225.658934) (xy 418.84727 -225.599752) (xy 418.822124 -225.595688) (xy 418.810186 -225.599752)
			(xy 418.780405 -225.60923) (xy 418.718751 -225.619444) (xy 418.687504 -225.620072) (xy 418.68725 -225.620072)
			(xy 418.660004 -225.619582) (xy 418.606067 -225.611821) (xy 418.553783 -225.596463) (xy 418.504217 -225.573821)
			(xy 418.458377 -225.544356) (xy 418.417196 -225.508668) (xy 418.381514 -225.467483) (xy 418.352055 -225.421639)
			(xy 418.32942 -225.37207) (xy 418.314069 -225.319785) (xy 418.306314 -225.265846) (xy 418.306314 -225.211354)
			(xy 418.314069 -225.157415) (xy 418.32942 -225.10513) (xy 418.352055 -225.055561) (xy 418.381514 -225.009717)
			(xy 418.417197 -224.968532) (xy 418.458377 -224.932844) (xy 418.504217 -224.903379) (xy 418.553783 -224.880737)
			(xy 418.606067 -224.865379) (xy 418.660004 -224.857618) (xy 418.68725 -224.857056) (xy 418.687504 -224.857056)
			(xy 418.716541 -224.857626) (xy 418.773938 -224.866464) (xy 418.82934 -224.883877) (xy 418.855652 -224.896172)
			(xy 418.867082 -224.902014) (xy 418.892482 -224.900998) (xy 418.97681 -224.852484) (xy 418.987349 -224.845567)
			(xy 419.000538 -224.824117) (xy 419.001956 -224.81159) (xy 419.112954 -223.09582) (xy 419.112954 -223.0882)
			(xy 418.886132 -220.497146) (xy 418.884424 -220.475534) (xy 418.882647 -220.432212) (xy 418.882576 -220.410532)
			(xy 418.882576 -220.410024) (xy 418.882635 -220.388344) (xy 418.884414 -220.345022) (xy 418.886132 -220.32341)
			(xy 420.446962 -202.483212) (xy 420.446962 -202.482196) (xy 420.448994 -202.45324) (xy 420.448994 -202.452224)
			(xy 420.450518 -202.425554) (xy 420.450518 -202.4253) (xy 420.784782 -197.256908) (xy 420.804086 -196.959474)
			(xy 420.804086 -196.953886) (xy 420.803832 -196.952108) (xy 420.801292 -196.940932) (xy 420.790878 -196.911468)
			(xy 420.779702 -196.879464) (xy 420.77597 -196.871182) (xy 420.763732 -196.857776) (xy 420.755826 -196.853302)
			(xy 420.755318 -196.853302) (xy 420.753032 -196.852032) (xy 420.751 -196.85127) (xy 420.724445 -196.840446)
			(xy 420.674663 -196.811989) (xy 420.6297 -196.776401) (xy 420.590571 -196.734484) (xy 420.558157 -196.687182)
			(xy 420.533188 -196.635562) (xy 420.516228 -196.580785) (xy 420.507657 -196.524087) (xy 420.50716 -196.495416)
			(xy 420.508938 -196.458078) (xy 420.5097 -196.450458) (xy 420.513242 -196.424445) (xy 420.526544 -196.373659)
			(xy 420.546676 -196.325174) (xy 420.573261 -196.279904) (xy 420.605796 -196.238702) (xy 420.643668 -196.202345)
			(xy 420.66464 -196.186552) (xy 420.685753 -196.171685) (xy 420.731192 -196.147155) (xy 420.779519 -196.128964)
			(xy 420.804594 -196.122798) (xy 420.809674 -196.121528) (xy 420.812976 -196.120766) (xy 420.81831 -196.117718)
			(xy 420.826946 -196.111368) (xy 420.830502 -196.107812) (xy 420.850314 -196.085714) (xy 420.854726 -196.080304)
			(xy 420.860662 -196.067674) (xy 420.861998 -196.060822) (xy 420.875968 -195.847716) (xy 420.884858 -195.709286)
			(xy 420.8843 -195.698668) (xy 420.875486 -195.679337) (xy 420.86784 -195.671948) (xy 420.809166 -195.62445)
			(xy 420.802054 -195.618608) (xy 420.797145 -195.614857) (xy 420.785976 -195.609583) (xy 420.779956 -195.608194)
			(xy 420.771574 -195.606416) (xy 420.759636 -195.608448) (xy 420.756588 -195.60921) (xy 420.756334 -195.60921)
			(xy 420.755572 -195.609464) (xy 420.730488 -195.616001) (xy 420.679128 -195.623012) (xy 420.65321 -195.623434)
			(xy 420.652448 -195.623434) (xy 420.625191 -195.622974) (xy 420.571231 -195.615222) (xy 420.518924 -195.599869)
			(xy 420.469334 -195.577228) (xy 420.423472 -195.547759) (xy 420.382271 -195.512063) (xy 420.346569 -195.470866)
			(xy 420.317095 -195.425008) (xy 420.294447 -195.375421) (xy 420.279088 -195.323116) (xy 420.271329 -195.269157)
			(xy 420.271329 -195.214643) (xy 420.279088 -195.160684) (xy 420.294447 -195.108379) (xy 420.317095 -195.058792)
			(xy 420.346569 -195.012934) (xy 420.382271 -194.971737) (xy 420.423472 -194.936041) (xy 420.469334 -194.906572)
			(xy 420.518924 -194.883931) (xy 420.571231 -194.868578) (xy 420.625191 -194.860826) (xy 420.652448 -194.860418)
			(xy 420.652702 -194.860418) (xy 420.678424 -194.860843) (xy 420.729403 -194.867754) (xy 420.778995 -194.881438)
			(xy 420.802816 -194.891152) (xy 420.807134 -194.89293) (xy 420.811891 -194.894335) (xy 420.82174 -194.895495)
			(xy 420.826692 -194.895216) (xy 420.83863 -194.894454) (xy 420.891462 -194.861942) (xy 420.922958 -194.842638)
			(xy 420.9304 -194.836839) (xy 420.940705 -194.82105) (xy 420.943024 -194.811904) (xy 420.94912 -194.720972)
			(xy 421.002968 -193.88836) (xy 421.004746 -193.864992) (xy 421.004746 -193.863976) (xy 421.14978 -191.622172)
			(xy 421.987726 -178.67757) (xy 421.990488 -178.639723) (xy 422.001101 -178.564578) (xy 422.017456 -178.49047)
			(xy 422.028112 -178.45405) (xy 423.689272 -172.983652) (xy 423.68978 -172.982128) (xy 424.248072 -170.898058)
			(xy 424.259767 -170.856136) (xy 424.289515 -170.774337) (xy 424.326289 -170.695446) (xy 424.34764 -170.65752)
			(xy 431.254154 -158.694374) (xy 431.255424 -158.68396) (xy 431.260315 -158.642794) (xy 431.276065 -158.561398)
			(xy 431.298512 -158.481589) (xy 431.327504 -158.403917) (xy 431.36284 -158.328919) (xy 431.383186 -158.2928)
			(xy 431.63109 -157.86354) (xy 431.651805 -157.828444) (xy 431.698159 -157.761408) (xy 431.749832 -157.698381)
			(xy 431.806479 -157.639784) (xy 431.83683 -157.612588) (xy 431.842908 -157.606875) (xy 431.851338 -157.592492)
			(xy 431.85334 -157.584394) (xy 431.861688 -157.544497) (xy 431.884065 -157.466109) (xy 431.912773 -157.389812)
			(xy 431.947618 -157.316115) (xy 431.96764 -157.28061) (xy 432.063144 -157.11551) (xy 432.067884 -157.106355)
			(xy 432.07038 -157.085909) (xy 432.06797 -157.075886) (xy 432.046888 -157.005274) (xy 432.043515 -156.995435)
			(xy 432.03028 -156.979416) (xy 432.021234 -156.974286) (xy 431.980154 -156.952726) (xy 431.901789 -156.903055)
			(xy 431.828377 -156.846318) (xy 431.760555 -156.783005) (xy 431.698908 -156.713664) (xy 431.643972 -156.638895)
			(xy 431.61966 -156.599382) (xy 431.617063 -156.595404) (xy 431.61067 -156.588379) (xy 431.60696 -156.585412)
			(xy 431.584477 -156.567355) (xy 431.544692 -156.525614) (xy 431.511642 -156.478361) (xy 431.486079 -156.426673)
			(xy 431.468584 -156.371727) (xy 431.459557 -156.314774) (xy 431.458878 -156.285946) (xy 431.458878 -156.282644)
			(xy 431.459454 -156.253473) (xy 431.46839 -156.195817) (xy 431.476658 -156.167836) (xy 431.478003 -156.163328)
			(xy 431.479161 -156.153993) (xy 431.478944 -156.149294) (xy 431.47799 -156.133436) (xy 431.476975 -156.10168)
			(xy 431.476912 -156.085794) (xy 431.477347 -156.043427) (xy 431.484535 -155.958997) (xy 431.498866 -155.875483)
			(xy 431.520237 -155.793488) (xy 431.548493 -155.713603) (xy 431.565558 -155.674822) (xy 431.569537 -155.664782)
			(xy 431.569534 -155.643207) (xy 431.565558 -155.633166) (xy 431.548515 -155.594377) (xy 431.520281 -155.514488)
			(xy 431.498919 -155.432494) (xy 431.484584 -155.348984) (xy 431.477378 -155.26456) (xy 431.476912 -155.222194)
			(xy 431.478944 -155.159202) (xy 431.479114 -155.154504) (xy 431.477965 -155.145175) (xy 431.476658 -155.14066)
			(xy 431.475896 -155.137866) (xy 431.475896 -155.137612) (xy 431.473864 -155.130754) (xy 431.47361 -155.129992)
			(xy 431.471324 -155.121864) (xy 431.471324 -155.12161) (xy 431.4698 -155.115514) (xy 431.466752 -155.102306)
			(xy 431.465736 -155.098242) (xy 431.463344 -155.090869) (xy 431.454817 -155.077932) (xy 431.448972 -155.072842)
			(xy 431.442368 -155.067762) (xy 431.434494 -155.064968) (xy 431.430316 -155.063555) (xy 431.421631 -155.062015)
			(xy 431.417222 -155.06192) (xy 430.991264 -155.06192) (xy 430.943908 -155.061313) (xy 430.849638 -155.052148)
			(xy 430.80305 -155.043632) (xy 430.802542 -155.043632) (xy 430.794668 -155.041854) (xy 430.793906 -155.041854)
			(xy 430.788572 -155.040584) (xy 430.788064 -155.040584) (xy 430.77765 -155.038298) (xy 430.737438 -155.029008)
			(xy 430.658594 -155.004594) (xy 430.62017 -154.98953) (xy 430.616868 -154.98826) (xy 430.611026 -154.98572)
			(xy 430.547018 -154.98572) (xy 430.529238 -154.992832) (xy 430.521872 -154.999944) (xy 430.491 -155.028881)
			(xy 430.425135 -155.082012) (xy 430.355005 -155.129369) (xy 430.281113 -155.170612) (xy 430.203992 -155.205444)
			(xy 430.124196 -155.233615) (xy 430.042299 -155.254922) (xy 429.958892 -155.269211) (xy 429.874573 -155.27638)
			(xy 429.832262 -155.276804) (xy 429.785579 -155.276262) (xy 429.692621 -155.267539) (xy 429.600886 -155.250163)
			(xy 429.511177 -155.224287) (xy 429.424281 -155.190137) (xy 429.340958 -155.148012) (xy 429.261938 -155.098282)
			(xy 429.187914 -155.041381) (xy 429.119533 -154.97781) (xy 429.057396 -154.908123) (xy 429.002046 -154.832933)
			(xy 428.977552 -154.793188) (xy 428.974955 -154.78921) (xy 428.968562 -154.782185) (xy 428.964852 -154.779218)
			(xy 428.942247 -154.761017) (xy 428.902278 -154.71894) (xy 428.869128 -154.671305) (xy 428.843561 -154.619206)
			(xy 428.826164 -154.563841) (xy 428.817336 -154.506483) (xy 428.81677 -154.477466) (xy 428.81677 -154.470354)
			(xy 428.817786 -154.448002) (xy 428.817786 -154.447748) (xy 428.819056 -154.429714) (xy 428.820072 -154.42311)
			(xy 428.822358 -154.411172) (xy 428.822612 -154.409648) (xy 428.824901 -154.397359) (xy 428.830872 -154.373081)
			(xy 428.83455 -154.361134) (xy 428.835902 -154.356628) (xy 428.83706 -154.347291) (xy 428.836836 -154.342592)
			(xy 428.835886 -154.326798) (xy 428.834871 -154.295169) (xy 428.834804 -154.279346) (xy 428.835237 -154.236978)
			(xy 428.84242 -154.152547) (xy 428.856747 -154.069032) (xy 428.878114 -153.987034) (xy 428.906367 -153.907147)
			(xy 428.92345 -153.868374) (xy 428.92744 -153.858334) (xy 428.927458 -153.836749) (xy 428.92345 -153.826718)
			(xy 428.906405 -153.787929) (xy 428.878167 -153.708041) (xy 428.856801 -153.626047) (xy 428.842462 -153.542537)
			(xy 428.835251 -153.458112) (xy 428.834804 -153.415746) (xy 428.834872 -153.39986) (xy 428.835888 -153.368104)
			(xy 428.836836 -153.352246) (xy 428.83701 -153.347548) (xy 428.835869 -153.338216) (xy 428.83455 -153.333704)
			(xy 428.826224 -153.305606) (xy 428.817294 -153.247689) (xy 428.81677 -153.218388) (xy 428.81677 -153.211784)
			(xy 428.817228 -153.193679) (xy 428.821172 -153.157676) (xy 428.824644 -153.139902) (xy 428.825914 -153.134568)
			(xy 428.83201 -153.1112) (xy 428.83201 -153.110692) (xy 428.834804 -153.102056) (xy 428.834804 -153.101548)
			(xy 428.83582 -153.0985) (xy 428.840138 -153.085292) (xy 428.841916 -153.08072) (xy 428.847758 -153.067258)
			(xy 428.848266 -153.065734) (xy 428.849028 -153.06421) (xy 428.851314 -153.059384) (xy 428.851822 -153.058622)
			(xy 428.852076 -153.05786) (xy 428.867316 -153.028396) (xy 428.880083 -153.00688) (xy 428.910361 -152.96705)
			(xy 428.945574 -152.931509) (xy 428.965106 -152.915874) (xy 428.968771 -152.912916) (xy 428.975037 -152.905886)
			(xy 428.977552 -152.901904) (xy 429.002065 -152.862175) (xy 429.057427 -152.787001) (xy 429.119572 -152.717329)
			(xy 429.187956 -152.65377) (xy 429.26198 -152.59688) (xy 429.340997 -152.547156) (xy 429.424315 -152.505034)
			(xy 429.511204 -152.470883) (xy 429.600905 -152.445001) (xy 429.692632 -152.427616) (xy 429.785582 -152.418878)
			(xy 429.832262 -152.418288) (xy 429.874559 -152.418742) (xy 429.958848 -152.425923) (xy 430.042225 -152.44022)
			(xy 430.124092 -152.461529) (xy 430.203859 -152.489698) (xy 430.280952 -152.524523) (xy 430.354817 -152.565756)
			(xy 430.424924 -152.613098) (xy 430.490767 -152.666209) (xy 430.521618 -152.695148) (xy 430.528914 -152.701599)
			(xy 430.546942 -152.708921) (xy 430.55667 -152.709372) (xy 431.42662 -152.709372) (xy 431.429922 -152.705816)
			(xy 431.43043 -152.705308) (xy 431.430684 -152.705054) (xy 431.431192 -152.704546) (xy 431.442876 -152.691338)
			(xy 431.447194 -152.686512) (xy 431.449934 -152.683306) (xy 431.454409 -152.676158) (xy 431.456084 -152.672288)
			(xy 431.459132 -152.664922) (xy 431.459894 -152.656286) (xy 431.460148 -152.651968) (xy 431.460148 -152.650952)
			(xy 431.46218 -152.631902) (xy 431.464547 -152.615329) (xy 431.471796 -152.582643) (xy 431.476658 -152.566624)
			(xy 431.478002 -152.562116) (xy 431.479157 -152.552781) (xy 431.478944 -152.548082) (xy 431.476912 -152.485852)
			(xy 431.477345 -152.443484) (xy 431.484527 -152.359053) (xy 431.498854 -152.275537) (xy 431.520221 -152.19354)
			(xy 431.548473 -152.113653) (xy 431.565558 -152.07488) (xy 431.569527 -152.064841) (xy 431.569509 -152.043273)
			(xy 431.565558 -152.033224) (xy 431.548517 -151.994435) (xy 431.520286 -151.914545) (xy 431.498928 -151.832551)
			(xy 431.484596 -151.749041) (xy 431.477393 -151.664617) (xy 431.476912 -151.622252) (xy 431.478944 -151.559514)
			(xy 431.479116 -151.554816) (xy 431.477969 -151.545486) (xy 431.476658 -151.540972) (xy 431.473573 -151.530942)
			(xy 431.468365 -151.51061) (xy 431.466244 -151.500332) (xy 431.466244 -151.500078) (xy 431.465736 -151.497538)
			(xy 431.465736 -151.49703) (xy 431.465228 -151.495252) (xy 431.46345 -151.48941) (xy 431.460605 -151.482981)
			(xy 431.451974 -151.47189) (xy 431.446432 -151.467566) (xy 431.430684 -151.45639) (xy 431.42281 -151.45385)
			(xy 431.422556 -151.45385) (xy 431.395886 -151.44496) (xy 431.340514 -151.423878) (xy 431.322648 -151.416293)
			(xy 431.28746 -151.399904) (xy 431.270156 -151.391112) (xy 431.264729 -151.388528) (xy 431.25305 -151.385704)
			(xy 431.247042 -151.385524) (xy 430.55667 -151.385524) (xy 430.54695 -151.386011) (xy 430.528933 -151.393328)
			(xy 430.521618 -151.399748) (xy 430.490751 -151.428668) (xy 430.424902 -151.481769) (xy 430.354793 -151.529104)
			(xy 430.280929 -151.570333) (xy 430.203839 -151.605159) (xy 430.124076 -151.633334) (xy 430.042215 -151.654653)
			(xy 429.958843 -151.668965) (xy 429.874558 -151.676167) (xy 429.832262 -151.676608) (xy 429.785579 -151.676066)
			(xy 429.692621 -151.667343) (xy 429.600886 -151.649967) (xy 429.511177 -151.624091) (xy 429.424281 -151.589941)
			(xy 429.340957 -151.547816) (xy 429.261937 -151.498086) (xy 429.187913 -151.441186) (xy 429.119532 -151.377614)
			(xy 429.057395 -151.307928) (xy 429.002045 -151.232737) (xy 428.977552 -151.192992) (xy 428.974956 -151.189014)
			(xy 428.968562 -151.181989) (xy 428.964852 -151.179022) (xy 428.942247 -151.160821) (xy 428.902277 -151.118744)
			(xy 428.869127 -151.071109) (xy 428.84356 -151.019011) (xy 428.826162 -150.963646) (xy 428.817333 -150.906287)
			(xy 428.81677 -150.87727) (xy 428.81677 -150.870158) (xy 428.817786 -150.847806) (xy 428.817786 -150.847552)
			(xy 428.819056 -150.829518) (xy 428.820072 -150.822914) (xy 428.822358 -150.810976) (xy 428.822612 -150.809452)
			(xy 428.824901 -150.797162) (xy 428.830872 -150.772885) (xy 428.83455 -150.760938) (xy 428.835903 -150.756432)
			(xy 428.837061 -150.747095) (xy 428.836836 -150.742396) (xy 428.835886 -150.726602) (xy 428.834871 -150.694973)
			(xy 428.834804 -150.67915) (xy 428.835237 -150.636782) (xy 428.84242 -150.552351) (xy 428.856746 -150.468835)
			(xy 428.878113 -150.386838) (xy 428.906366 -150.306951) (xy 428.92345 -150.268178) (xy 428.927441 -150.258138)
			(xy 428.92746 -150.236552) (xy 428.92345 -150.226522) (xy 428.906409 -150.187733) (xy 428.878179 -150.107843)
			(xy 428.856821 -150.025849) (xy 428.842489 -149.942339) (xy 428.835287 -149.857915) (xy 428.834804 -149.81555)
			(xy 428.834872 -149.799664) (xy 428.835888 -149.767908) (xy 428.836836 -149.75205) (xy 428.837002 -149.747353)
			(xy 428.835844 -149.738027) (xy 428.83455 -149.733508) (xy 428.826224 -149.70541) (xy 428.817293 -149.647493)
			(xy 428.81677 -149.618192) (xy 428.81677 -149.611588) (xy 428.817228 -149.593483) (xy 428.821171 -149.55748)
			(xy 428.824644 -149.539706) (xy 428.825914 -149.534372) (xy 428.83201 -149.511004) (xy 428.83201 -149.510496)
			(xy 428.834804 -149.50186) (xy 428.834804 -149.501352) (xy 428.83582 -149.498304) (xy 428.840138 -149.485096)
			(xy 428.841916 -149.480524) (xy 428.847758 -149.467062) (xy 428.848266 -149.465538) (xy 428.849028 -149.464014)
			(xy 428.851314 -149.459188) (xy 428.851822 -149.458426) (xy 428.852076 -149.457664) (xy 428.867316 -149.4282)
			(xy 428.880083 -149.406684) (xy 428.910361 -149.366854) (xy 428.945573 -149.331312) (xy 428.965106 -149.315678)
			(xy 428.968771 -149.31272) (xy 428.975038 -149.305691) (xy 428.977552 -149.301708) (xy 429.002065 -149.261979)
			(xy 429.057427 -149.186804) (xy 429.119572 -149.117132) (xy 429.187955 -149.053573) (xy 429.261979 -148.996682)
			(xy 429.340996 -148.946959) (xy 429.424314 -148.904837) (xy 429.511204 -148.870685) (xy 429.600905 -148.844804)
			(xy 429.692632 -148.827418) (xy 429.785582 -148.81868) (xy 429.832262 -148.818092) (xy 429.874559 -148.818546)
			(xy 429.958848 -148.825727) (xy 430.042225 -148.840024) (xy 430.124092 -148.861333) (xy 430.203858 -148.889502)
			(xy 430.280951 -148.924328) (xy 430.354817 -148.96556) (xy 430.424923 -149.012902) (xy 430.490766 -149.066014)
			(xy 430.521618 -149.094952) (xy 430.528915 -149.101402) (xy 430.546942 -149.108724) (xy 430.55667 -149.109176)
			(xy 431.426366 -149.109176) (xy 431.430938 -149.104604) (xy 431.44186 -149.092158) (xy 431.447448 -149.085808)
			(xy 431.453544 -149.07133) (xy 431.454052 -149.07006) (xy 431.454052 -149.069552) (xy 431.45964 -149.056598)
			(xy 431.460402 -149.048724) (xy 431.462508 -149.027998) (xy 431.470651 -148.987138) (xy 431.476658 -148.96719)
			(xy 431.478006 -148.962683) (xy 431.479155 -148.953348) (xy 431.478944 -148.948648) (xy 431.476912 -148.88591)
			(xy 431.477346 -148.843542) (xy 431.484533 -148.759113) (xy 431.498862 -148.675598) (xy 431.520232 -148.593602)
			(xy 431.548488 -148.513717) (xy 431.565558 -148.474938) (xy 431.56954 -148.464898) (xy 431.569544 -148.44332)
			(xy 431.565558 -148.433282) (xy 431.548515 -148.394493) (xy 431.520279 -148.314604) (xy 431.498916 -148.23261)
			(xy 431.484579 -148.1491) (xy 431.477372 -148.064676) (xy 431.476912 -148.02231) (xy 431.47742 -147.992846)
			(xy 431.478182 -147.973034) (xy 431.471578 -147.964652) (xy 431.441606 -147.933918) (xy 431.419 -147.910804)
			(xy 431.412598 -147.905465) (xy 431.397303 -147.898865) (xy 431.389028 -147.89785) (xy 431.388012 -147.89785)
			(xy 431.38471 -147.897596) (xy 431.03673 -147.897596) (xy 430.988598 -147.896995) (xy 430.892796 -147.887578)
			(xy 430.845468 -147.8788) (xy 430.833022 -147.87626) (xy 430.793037 -147.867379) (xy 430.714571 -147.843861)
			(xy 430.638315 -147.813942) (xy 430.601374 -147.79625) (xy 430.59096 -147.79117) (xy 430.590452 -147.790662)
			(xy 430.580292 -147.785836) (xy 430.556924 -147.785836) (xy 430.547228 -147.78627) (xy 430.529217 -147.793461)
			(xy 430.521872 -147.799806) (xy 430.491015 -147.828711) (xy 430.425189 -147.881781) (xy 430.355104 -147.929086)
			(xy 430.281265 -147.970285) (xy 430.204202 -148.005083) (xy 430.124469 -148.033229) (xy 430.042638 -148.054521)
			(xy 429.959298 -148.068806) (xy 429.875048 -148.075982) (xy 429.83277 -148.076412) (xy 429.832262 -148.076412)
			(xy 429.78557 -148.075867) (xy 429.692596 -148.067136) (xy 429.600845 -148.049755) (xy 429.511119 -148.023876)
			(xy 429.424205 -147.989725) (xy 429.340862 -147.9476) (xy 429.261821 -147.897872) (xy 429.187773 -147.840975)
			(xy 429.119366 -147.777406) (xy 429.057199 -147.707723) (xy 429.001817 -147.632535) (xy 428.977298 -147.592796)
			(xy 428.974782 -147.588814) (xy 428.96852 -147.58178) (xy 428.964852 -147.578826) (xy 428.942468 -147.560851)
			(xy 428.90284 -147.519315) (xy 428.86988 -147.472313) (xy 428.844332 -147.420905) (xy 428.826772 -147.366249)
			(xy 428.817597 -147.309581) (xy 428.81677 -147.280884) (xy 428.81677 -147.27174) (xy 428.81729 -147.250651)
			(xy 428.822386 -147.208774) (xy 428.82693 -147.188174) (xy 428.83455 -147.160234) (xy 428.835902 -147.155728)
			(xy 428.83706 -147.146391) (xy 428.836836 -147.141692) (xy 428.834804 -147.079208) (xy 428.835239 -147.03684)
			(xy 428.842425 -146.952411) (xy 428.856755 -146.868896) (xy 428.878124 -146.7869) (xy 428.90638 -146.707015)
			(xy 428.92345 -146.668236) (xy 428.927432 -146.658196) (xy 428.927435 -146.636618) (xy 428.92345 -146.62658)
			(xy 428.906407 -146.587791) (xy 428.878172 -146.507902) (xy 428.856809 -146.425908) (xy 428.842472 -146.342398)
			(xy 428.835265 -146.257974) (xy 428.834804 -146.215608) (xy 428.836836 -146.152362) (xy 428.837003 -146.147665)
			(xy 428.835847 -146.138338) (xy 428.83455 -146.13382) (xy 428.829949 -146.118791) (xy 428.822956 -146.088143)
			(xy 428.82058 -146.072606) (xy 428.82058 -146.072098) (xy 428.819818 -146.06651) (xy 428.81804 -146.053302)
			(xy 428.817532 -146.047714) (xy 428.81677 -146.028156) (xy 428.81677 -146.01571) (xy 428.817472 -145.986832)
			(xy 428.826505 -145.92978) (xy 428.84402 -145.874736) (xy 428.869618 -145.822954) (xy 428.902716 -145.775614)
			(xy 428.94256 -145.733793) (xy 428.965106 -145.715736) (xy 428.968769 -145.712776) (xy 428.975031 -145.705744)
			(xy 428.977552 -145.701766) (xy 429.002076 -145.662051) (xy 429.057456 -145.586906) (xy 429.119614 -145.517263)
			(xy 429.188005 -145.453732) (xy 429.262033 -145.396867) (xy 429.341049 -145.347167) (xy 429.424362 -145.305065)
			(xy 429.511244 -145.27093) (xy 429.600935 -145.245062) (xy 429.692651 -145.227684) (xy 429.785589 -145.218951)
			(xy 429.832262 -145.218404) (xy 429.832516 -145.218404) (xy 429.874792 -145.218864) (xy 429.959038 -145.226049)
			(xy 430.042373 -145.24034) (xy 430.1242 -145.261634) (xy 430.20393 -145.28978) (xy 430.28099 -145.324575)
			(xy 430.354829 -145.365768) (xy 430.424915 -145.413064) (xy 430.490746 -145.466125) (xy 430.521618 -145.49501)
			(xy 430.528941 -145.501387) (xy 430.546967 -145.508565) (xy 430.55667 -145.50898) (xy 431.42662 -145.50898)
			(xy 431.431954 -145.503646) (xy 431.442622 -145.4912) (xy 431.449988 -145.479516) (xy 431.45964 -145.455894)
			(xy 431.460402 -145.448274) (xy 431.460402 -145.44802) (xy 431.461164 -145.440654) (xy 431.463419 -145.42181)
			(xy 431.471181 -145.384657) (xy 431.476658 -145.366486) (xy 431.478006 -145.361979) (xy 431.479154 -145.352644)
			(xy 431.478944 -145.347944) (xy 431.476912 -145.285714) (xy 431.477346 -145.243346) (xy 431.484532 -145.158917)
			(xy 431.498862 -145.075402) (xy 431.520231 -144.993406) (xy 431.548486 -144.91352) (xy 431.565558 -144.874742)
			(xy 431.569541 -144.864702) (xy 431.569546 -144.843123) (xy 431.565558 -144.833086) (xy 431.548514 -144.794297)
			(xy 431.520279 -144.714408) (xy 431.498915 -144.632414) (xy 431.484578 -144.548904) (xy 431.47737 -144.46448)
			(xy 431.476912 -144.422114) (xy 431.478944 -144.359376) (xy 431.479112 -144.354679) (xy 431.477959 -144.345351)
			(xy 431.476658 -144.340834) (xy 431.468321 -144.312673) (xy 431.459388 -144.254628) (xy 431.458878 -144.225264)
			(xy 431.458878 -144.222978) (xy 431.459459 -144.194536) (xy 431.467998 -144.138294) (xy 431.475896 -144.110964)
			(xy 431.477516 -144.105137) (xy 431.478293 -144.093072) (xy 431.47742 -144.087088) (xy 431.473102 -144.061942)
			(xy 431.471968 -144.056425) (xy 431.467608 -144.046043) (xy 431.464466 -144.041368) (xy 431.42281 -143.982694)
			(xy 431.413158 -143.973804) (xy 431.318416 -143.973804) (xy 431.313398 -143.973899) (xy 431.303548 -143.975826)
			(xy 431.298858 -143.977614) (xy 430.979834 -144.109948) (xy 430.934466 -144.128058) (xy 430.840969 -144.156375)
			(xy 430.745152 -144.175421) (xy 430.647933 -144.185013) (xy 430.599088 -144.18564) (xy 430.547018 -144.18564)
			(xy 430.529238 -144.192752) (xy 430.521872 -144.199864) (xy 430.490999 -144.228801) (xy 430.425135 -144.28193)
			(xy 430.355004 -144.329286) (xy 430.281112 -144.370529) (xy 430.203991 -144.40536) (xy 430.124195 -144.433531)
			(xy 430.042299 -144.454837) (xy 429.958891 -144.469126) (xy 429.874573 -144.476294) (xy 429.832262 -144.476724)
			(xy 429.785579 -144.476182) (xy 429.692621 -144.467459) (xy 429.600885 -144.450084) (xy 429.511176 -144.424208)
			(xy 429.424279 -144.390058) (xy 429.340955 -144.347934) (xy 429.261935 -144.298204) (xy 429.18791 -144.241304)
			(xy 429.119528 -144.177733) (xy 429.05739 -144.108047) (xy 429.002039 -144.032857) (xy 428.977552 -143.993108)
			(xy 428.974956 -143.989129) (xy 428.968565 -143.982102) (xy 428.964852 -143.979138) (xy 428.942246 -143.960937)
			(xy 428.902274 -143.918861) (xy 428.869123 -143.871227) (xy 428.843553 -143.819128) (xy 428.826152 -143.763763)
			(xy 428.817322 -143.706403) (xy 428.81677 -143.677386) (xy 428.81677 -143.670274) (xy 428.817786 -143.647922)
			(xy 428.817786 -143.647668) (xy 428.819056 -143.629634) (xy 428.820072 -143.62303) (xy 428.822358 -143.611092)
			(xy 428.822612 -143.609568) (xy 428.824903 -143.597279) (xy 428.83088 -143.573004) (xy 428.83455 -143.561054)
			(xy 428.835895 -143.556547) (xy 428.837037 -143.547212) (xy 428.836836 -143.542512) (xy 428.835886 -143.526718)
			(xy 428.83487 -143.495089) (xy 428.834804 -143.479266) (xy 428.83524 -143.436899) (xy 428.84243 -143.35247)
			(xy 428.856763 -143.268957) (xy 428.878136 -143.186963) (xy 428.906394 -143.107079) (xy 428.92345 -143.068294)
			(xy 428.927423 -143.058255) (xy 428.92741 -143.036684) (xy 428.92345 -143.026638) (xy 428.906408 -142.987849)
			(xy 428.878177 -142.907959) (xy 428.856817 -142.825965) (xy 428.842484 -142.742455) (xy 428.835281 -142.658031)
			(xy 428.834804 -142.615666) (xy 428.836836 -142.553182) (xy 428.837005 -142.548485) (xy 428.835852 -142.539157)
			(xy 428.83455 -142.53464) (xy 428.826213 -142.506479) (xy 428.817279 -142.448434) (xy 428.81677 -142.41907)
			(xy 428.81677 -142.411704) (xy 428.817228 -142.393599) (xy 428.821169 -142.357596) (xy 428.824644 -142.339822)
			(xy 428.825914 -142.334488) (xy 428.83201 -142.31112) (xy 428.83201 -142.310612) (xy 428.834804 -142.301976)
			(xy 428.834804 -142.301468) (xy 428.83582 -142.29842) (xy 428.840138 -142.285212) (xy 428.841916 -142.28064)
			(xy 428.847758 -142.267178) (xy 428.848266 -142.265654) (xy 428.849028 -142.26413) (xy 428.851314 -142.259304)
			(xy 428.851822 -142.258542) (xy 428.852076 -142.25778) (xy 428.867316 -142.228316) (xy 428.880087 -142.206803)
			(xy 428.91037 -142.16698) (xy 428.945587 -142.131444) (xy 428.965106 -142.115794) (xy 428.968772 -142.112836)
			(xy 428.975041 -142.105808) (xy 428.977552 -142.101824) (xy 429.002065 -142.062094) (xy 429.057426 -141.986919)
			(xy 429.11957 -141.917246) (xy 429.187953 -141.853685) (xy 429.261978 -141.796794) (xy 429.340994 -141.747069)
			(xy 429.424312 -141.704947) (xy 429.511202 -141.670795) (xy 429.600903 -141.644912) (xy 429.692631 -141.627526)
			(xy 429.785582 -141.618788) (xy 429.832262 -141.618208) (xy 429.874187 -141.618642) (xy 429.957742 -141.625688)
			(xy 430.04041 -141.639725) (xy 430.121607 -141.660654) (xy 430.20076 -141.688326) (xy 430.27731 -141.722547)
			(xy 430.350716 -141.763075) (xy 430.420461 -141.809623) (xy 430.453546 -141.835378) (xy 430.464468 -141.844268)
			(xy 430.491646 -141.848078) (xy 430.672494 -141.773148) (xy 430.717862 -141.755035) (xy 430.811358 -141.726711)
			(xy 430.907175 -141.707659) (xy 431.004394 -141.698059) (xy 431.05324 -141.697456) (xy 431.944272 -141.697456)
			(xy 431.993087 -141.69807) (xy 432.090245 -141.707659) (xy 432.185999 -141.726707) (xy 432.27943 -141.755033)
			(xy 432.324764 -141.773148) (xy 433.20081 -142.136368) (xy 433.204874 -142.137638) (xy 433.641246 -142.278354)
			(xy 433.684426 -142.29334) (xy 433.729892 -142.311628) (xy 433.730908 -142.312136) (xy 433.734972 -142.31366)
			(xy 433.740079 -142.315274) (xy 433.75071 -142.316551) (xy 433.756054 -142.3162) (xy 433.767992 -142.315184)
			(xy 433.840382 -142.26794) (xy 433.84089 -142.267432) (xy 433.850034 -142.261336) (xy 433.860225 -142.253821)
			(xy 433.872226 -142.231562) (xy 433.872894 -142.218918) (xy 433.872894 -139.817094) (xy 433.871624 -139.805918)
			(xy 433.869592 -139.79779) (xy 433.869084 -139.796266) (xy 433.86756 -139.793218) (xy 433.867306 -139.792456)
			(xy 433.861464 -139.77874) (xy 433.861464 -139.778486) (xy 433.859178 -139.773152) (xy 433.690522 -139.370562)
			(xy 433.690268 -139.370054) (xy 433.686966 -139.362434) (xy 433.686966 -139.36218) (xy 433.683156 -139.352782)
			(xy 433.681124 -139.347702) (xy 433.674774 -139.331192) (xy 433.674774 -139.330938) (xy 433.67325 -139.327128)
			(xy 433.67325 -139.326874) (xy 433.667662 -139.311634) (xy 433.667154 -139.310364) (xy 433.667154 -139.31011)
			(xy 433.659788 -139.287504) (xy 433.646741 -139.244646) (xy 433.627534 -139.157135) (xy 433.621434 -139.112752)
			(xy 433.616862 -139.069826) (xy 433.615592 -139.0523) (xy 433.615084 -139.043918) (xy 433.605686 -139.021566)
			(xy 433.60086 -139.015978) (xy 433.588959 -139.001748) (xy 433.566094 -138.972529) (xy 433.55514 -138.957558)
			(xy 433.554124 -138.956034) (xy 433.535328 -138.931142) (xy 433.512806 -138.899683) (xy 433.472178 -138.833833)
			(xy 433.436818 -138.76501) (xy 433.421536 -138.729466) (xy 433.419504 -138.724894) (xy 433.29352 -138.424158)
			(xy 433.250594 -138.321796) (xy 433.250594 -138.321288) (xy 433.244498 -138.307064) (xy 433.244498 -138.30681)
			(xy 433.240434 -138.297158) (xy 433.24018 -138.296396) (xy 433.24018 -138.295888) (xy 433.237386 -138.288268)
			(xy 433.236878 -138.287252) (xy 433.234592 -138.280648) (xy 433.234084 -138.279632) (xy 433.23129 -138.272266)
			(xy 433.23129 -138.271758) (xy 433.229766 -138.267694) (xy 433.229258 -138.266678) (xy 433.226464 -138.25855)
			(xy 433.226464 -138.258042) (xy 433.212895 -138.216785) (xy 433.192187 -138.132431) (xy 433.178959 -138.046586)
			(xy 433.175664 -138.00328) (xy 433.175664 -138.003026) (xy 433.175156 -137.99439) (xy 433.166012 -137.972546)
			(xy 433.164996 -137.97026) (xy 433.163472 -137.967466) (xy 433.158138 -137.959846) (xy 433.154328 -137.954766)
			(xy 433.142737 -137.941654) (xy 433.120379 -137.914724) (xy 433.109624 -137.900918) (xy 433.092352 -137.877804)
			(xy 433.091844 -137.877042) (xy 433.089304 -137.873486) (xy 433.060856 -137.831576) (xy 433.038207 -137.795349)
			(xy 432.998527 -137.719677) (xy 432.981608 -137.680446) (xy 432.810666 -137.272776) (xy 432.802945 -137.254175)
			(xy 432.788845 -137.216443) (xy 432.782472 -137.197338) (xy 432.779424 -137.18794) (xy 432.761644 -137.16635)
			(xy 432.758891 -137.163164) (xy 432.752507 -137.157673) (xy 432.748944 -137.155428) (xy 432.727354 -137.14349)
			(xy 432.723036 -137.141712) (xy 432.704748 -137.14603) (xy 432.66696 -137.15464) (xy 432.590394 -137.166695)
			(xy 432.513124 -137.172782) (xy 432.47437 -137.173208) (xy 432.427687 -137.172667) (xy 432.334728 -137.163944)
			(xy 432.242993 -137.146569) (xy 432.153284 -137.120693) (xy 432.066386 -137.086544) (xy 431.983063 -137.044419)
			(xy 431.904042 -136.994689) (xy 431.830017 -136.937789) (xy 431.761636 -136.874218) (xy 431.699498 -136.804532)
			(xy 431.644147 -136.729341) (xy 431.61966 -136.689592) (xy 431.617064 -136.685614) (xy 431.610671 -136.678588)
			(xy 431.60696 -136.675622) (xy 431.584354 -136.657421) (xy 431.544384 -136.615345) (xy 431.511233 -136.56771)
			(xy 431.485665 -136.515611) (xy 431.468267 -136.460246) (xy 431.459438 -136.402887) (xy 431.458878 -136.37387)
			(xy 431.458878 -136.366758) (xy 431.459894 -136.344406) (xy 431.459894 -136.344152) (xy 431.461164 -136.326118)
			(xy 431.46218 -136.319514) (xy 431.464466 -136.307576) (xy 431.46472 -136.306052) (xy 431.467009 -136.293763)
			(xy 431.47298 -136.269485) (xy 431.476658 -136.257538) (xy 431.478004 -136.25303) (xy 431.479161 -136.243695)
			(xy 431.478944 -136.238996) (xy 431.477994 -136.223202) (xy 431.476979 -136.191573) (xy 431.476912 -136.17575)
			(xy 431.477345 -136.133382) (xy 431.484528 -136.048951) (xy 431.498854 -135.965436) (xy 431.520221 -135.883438)
			(xy 431.548474 -135.803551) (xy 431.565558 -135.764778) (xy 431.569548 -135.754738) (xy 431.569568 -135.733152)
			(xy 431.565558 -135.723122) (xy 431.548523 -135.684357) (xy 431.520297 -135.604518) (xy 431.498935 -135.522575)
			(xy 431.48459 -135.439117) (xy 431.477367 -135.354744) (xy 431.476912 -135.312404) (xy 431.476912 -135.311896)
			(xy 431.47742 -135.28548) (xy 431.47742 -135.284972) (xy 431.477928 -135.26516) (xy 431.472848 -135.25881)
			(xy 431.44821 -135.233156) (xy 431.447956 -135.232902) (xy 431.419254 -135.203692) (xy 431.412802 -135.198133)
			(xy 431.397228 -135.191266) (xy 431.388774 -135.19023) (xy 431.387758 -135.19023) (xy 431.384456 -135.189976)
			(xy 431.121566 -135.189976) (xy 431.090941 -135.189735) (xy 431.029809 -135.185924) (xy 430.999392 -135.182356)
			(xy 430.998884 -135.182356) (xy 430.952348 -135.181805) (xy 430.859682 -135.173107) (xy 430.768229 -135.155816)
			(xy 430.678784 -135.130082) (xy 430.592125 -135.096129) (xy 430.55032 -135.075676) (xy 430.536096 -135.075676)
			(xy 430.505014 -135.106002) (xy 430.438415 -135.161741) (xy 430.367222 -135.211478) (xy 430.291974 -135.254836)
			(xy 430.213241 -135.291487) (xy 430.131619 -135.321153) (xy 430.047726 -135.34361) (xy 429.962199 -135.358686)
			(xy 429.875685 -135.366269) (xy 429.832262 -135.36676) (xy 429.785579 -135.366218) (xy 429.692622 -135.357495)
			(xy 429.600888 -135.340118) (xy 429.51118 -135.314241) (xy 429.424285 -135.28009) (xy 429.340963 -135.237964)
			(xy 429.261945 -135.188233) (xy 429.187922 -135.131331) (xy 429.119544 -135.067758) (xy 429.05741 -134.99807)
			(xy 429.002063 -134.922878) (xy 428.977552 -134.883144) (xy 428.974953 -134.879168) (xy 428.968556 -134.872148)
			(xy 428.964852 -134.869174) (xy 428.942249 -134.850972) (xy 428.902285 -134.808894) (xy 428.869141 -134.761258)
			(xy 428.84358 -134.709159) (xy 428.826189 -134.653795) (xy 428.817367 -134.596437) (xy 428.81677 -134.567422)
			(xy 428.81677 -134.56031) (xy 428.817786 -134.537958) (xy 428.817786 -134.537704) (xy 428.819056 -134.51967)
			(xy 428.820072 -134.513066) (xy 428.822358 -134.501128) (xy 428.822612 -134.499604) (xy 428.824902 -134.487315)
			(xy 428.830876 -134.463039) (xy 428.83455 -134.45109) (xy 428.835898 -134.446583) (xy 428.837047 -134.437248)
			(xy 428.836836 -134.432548) (xy 428.835886 -134.416754) (xy 428.834869 -134.385125) (xy 428.834804 -134.369302)
			(xy 428.835239 -134.326935) (xy 428.842426 -134.242505) (xy 428.856756 -134.158991) (xy 428.878126 -134.076995)
			(xy 428.906382 -133.99711) (xy 428.92345 -133.95833) (xy 428.92743 -133.94829) (xy 428.927431 -133.926713)
			(xy 428.92345 -133.916674) (xy 428.906407 -133.877885) (xy 428.878172 -133.797996) (xy 428.85681 -133.716002)
			(xy 428.842474 -133.632492) (xy 428.835267 -133.548068) (xy 428.834804 -133.505702) (xy 428.836836 -133.442456)
			(xy 428.837002 -133.437759) (xy 428.835845 -133.428432) (xy 428.83455 -133.423914) (xy 428.829949 -133.408884)
			(xy 428.822957 -133.378237) (xy 428.82058 -133.3627) (xy 428.82058 -133.362192) (xy 428.819818 -133.356604)
			(xy 428.81804 -133.343396) (xy 428.817532 -133.337808) (xy 428.81677 -133.31825) (xy 428.81677 -133.305804)
			(xy 428.817472 -133.276926) (xy 428.826506 -133.219874) (xy 428.844022 -133.164831) (xy 428.86962 -133.11305)
			(xy 428.902718 -133.065711) (xy 428.942563 -133.02389) (xy 428.965106 -133.00583) (xy 428.968769 -133.00287)
			(xy 428.97503 -132.995837) (xy 428.977552 -132.99186) (xy 429.002064 -132.952129) (xy 429.057423 -132.876951)
			(xy 429.119567 -132.807276) (xy 429.187949 -132.743713) (xy 429.261973 -132.68682) (xy 429.34099 -132.637093)
			(xy 429.424308 -132.594969) (xy 429.511199 -132.560815) (xy 429.600901 -132.534932) (xy 429.692629 -132.517545)
			(xy 429.785581 -132.508807) (xy 429.832262 -132.508244) (xy 429.874559 -132.508698) (xy 429.958849 -132.515879)
			(xy 430.042226 -132.530175) (xy 430.124093 -132.551484) (xy 430.203861 -132.579651) (xy 430.280955 -132.614476)
			(xy 430.354822 -132.655707) (xy 430.424929 -132.703047) (xy 430.490774 -132.756157) (xy 430.521618 -132.785104)
			(xy 430.528917 -132.791549) (xy 430.546944 -132.798863) (xy 430.55667 -132.799328) (xy 431.42662 -132.799328)
			(xy 431.429922 -132.795772) (xy 431.43043 -132.795264) (xy 431.430684 -132.79501) (xy 431.431192 -132.794502)
			(xy 431.442876 -132.781294) (xy 431.447194 -132.776468) (xy 431.449931 -132.77326) (xy 431.454401 -132.76611)
			(xy 431.456084 -132.762244) (xy 431.459132 -132.754878) (xy 431.459894 -132.746242) (xy 431.460148 -132.741924)
			(xy 431.460148 -132.740908) (xy 431.46218 -132.721858) (xy 431.464549 -132.705286) (xy 431.471801 -132.672601)
			(xy 431.476658 -132.65658) (xy 431.478005 -132.652073) (xy 431.479152 -132.642738) (xy 431.478944 -132.638038)
			(xy 431.476912 -132.575808) (xy 431.477347 -132.53344) (xy 431.484533 -132.449011) (xy 431.498863 -132.365496)
			(xy 431.520233 -132.2835) (xy 431.548489 -132.203615) (xy 431.565558 -132.164836) (xy 431.56954 -132.154796)
			(xy 431.569543 -132.133218) (xy 431.565558 -132.12318) (xy 431.548524 -132.084415) (xy 431.520302 -132.004575)
			(xy 431.498943 -131.922632) (xy 431.484602 -131.839175) (xy 431.477382 -131.754802) (xy 431.476912 -131.712462)
			(xy 431.476912 -131.711954) (xy 431.47742 -131.685284) (xy 431.47742 -131.684776) (xy 431.477928 -131.664964)
			(xy 431.472848 -131.65836) (xy 431.44821 -131.63296) (xy 431.447956 -131.632706) (xy 431.419254 -131.603496)
			(xy 431.412802 -131.597937) (xy 431.397228 -131.591069) (xy 431.388774 -131.590034) (xy 431.387758 -131.590034)
			(xy 431.384456 -131.58978) (xy 431.126392 -131.58978) (xy 431.07962 -131.589223) (xy 430.986498 -131.58036)
			(xy 430.89463 -131.562732) (xy 430.804841 -131.536498) (xy 430.717934 -131.501893) (xy 430.67605 -131.481068)
			(xy 430.670623 -131.478487) (xy 430.658943 -131.475667) (xy 430.652936 -131.47548) (xy 430.547018 -131.47548)
			(xy 430.529238 -131.482592) (xy 430.521872 -131.489704) (xy 430.491 -131.518642) (xy 430.425137 -131.571775)
			(xy 430.355007 -131.619134) (xy 430.281115 -131.660379) (xy 430.203994 -131.695213) (xy 430.124198 -131.723385)
			(xy 430.042301 -131.744692) (xy 429.958893 -131.758982) (xy 429.874574 -131.766151) (xy 429.832262 -131.766564)
			(xy 429.785579 -131.766022) (xy 429.692622 -131.757299) (xy 429.600888 -131.739923) (xy 429.51118 -131.714046)
			(xy 429.424284 -131.679895) (xy 429.340963 -131.637769) (xy 429.261944 -131.588037) (xy 429.187922 -131.531136)
			(xy 429.119543 -131.467563) (xy 429.057409 -131.397875) (xy 429.002061 -131.322683) (xy 428.977552 -131.282948)
			(xy 428.975036 -131.278967) (xy 428.968774 -131.271932) (xy 428.965106 -131.268978) (xy 428.942612 -131.250923)
			(xy 428.902801 -131.209187) (xy 428.869719 -131.161939) (xy 428.844118 -131.110253) (xy 428.826579 -131.055306)
			(xy 428.817502 -130.998347) (xy 428.81677 -130.969512) (xy 428.81677 -130.965956) (xy 428.817345 -130.936784)
			(xy 428.826279 -130.879129) (xy 428.83455 -130.851148) (xy 428.835904 -130.846642) (xy 428.837064 -130.837305)
			(xy 428.836836 -130.832606) (xy 428.835882 -130.816748) (xy 428.834867 -130.784992) (xy 428.834804 -130.769106)
			(xy 428.835239 -130.726738) (xy 428.842425 -130.642309) (xy 428.856755 -130.558794) (xy 428.878125 -130.476798)
			(xy 428.906381 -130.396913) (xy 428.92345 -130.358134) (xy 428.927431 -130.348094) (xy 428.927434 -130.326516)
			(xy 428.92345 -130.316478) (xy 428.906407 -130.277689) (xy 428.878172 -130.1978) (xy 428.856809 -130.115806)
			(xy 428.842473 -130.032296) (xy 428.835266 -129.947872) (xy 428.834804 -129.905506) (xy 428.836836 -129.84226)
			(xy 428.837003 -129.837563) (xy 428.835846 -129.828236) (xy 428.83455 -129.823718) (xy 428.829949 -129.808688)
			(xy 428.822957 -129.778041) (xy 428.82058 -129.762504) (xy 428.82058 -129.761996) (xy 428.819818 -129.756408)
			(xy 428.81804 -129.7432) (xy 428.817532 -129.737612) (xy 428.81677 -129.718054) (xy 428.81677 -129.705608)
			(xy 428.817472 -129.67673) (xy 428.826505 -129.619678) (xy 428.844021 -129.564634) (xy 428.869619 -129.512853)
			(xy 428.902717 -129.465513) (xy 428.942561 -129.423692) (xy 428.965106 -129.405634) (xy 428.968769 -129.402674)
			(xy 428.975031 -129.395642) (xy 428.977552 -129.391664) (xy 429.002064 -129.351933) (xy 429.057423 -129.276755)
			(xy 429.119566 -129.207079) (xy 429.187949 -129.143516) (xy 429.261973 -129.086622) (xy 429.34099 -129.036896)
			(xy 429.424308 -128.994771) (xy 429.511199 -128.960618) (xy 429.600901 -128.934734) (xy 429.692629 -128.917347)
			(xy 429.785581 -128.908609) (xy 429.832262 -128.908048) (xy 429.874559 -128.908502) (xy 429.958849 -128.915683)
			(xy 430.042226 -128.929979) (xy 430.124093 -128.951288) (xy 430.203861 -128.979456) (xy 430.280955 -129.01428)
			(xy 430.354821 -129.055511) (xy 430.424929 -129.102852) (xy 430.490774 -129.155962) (xy 430.521618 -129.184908)
			(xy 430.528917 -129.191352) (xy 430.546944 -129.198666) (xy 430.55667 -129.199132) (xy 432.560222 -129.199132)
			(xy 432.609202 -129.199715) (xy 432.70669 -129.20932) (xy 432.802767 -129.228436) (xy 432.896507 -129.256878)
			(xy 432.941984 -129.275078) (xy 433.787296 -129.625344) (xy 433.796626 -129.628671) (xy 433.816415 -129.628702)
			(xy 433.834747 -129.621247) (xy 433.84216 -129.614676) (xy 433.851568 -129.604947) (xy 433.865327 -129.581654)
			(xy 433.872463 -129.555559) (xy 433.872894 -129.542032) (xy 433.872894 -129.20726) (xy 433.87262 -129.199938)
			(xy 433.868487 -129.185887) (xy 433.864766 -129.179574) (xy 433.864512 -129.17932) (xy 433.838915 -129.13995)
			(xy 433.79439 -129.057262) (xy 433.775612 -129.01422) (xy 433.598066 -128.59258) (xy 433.582971 -128.555674)
			(xy 433.558027 -128.479931) (xy 433.539213 -128.402438) (xy 433.526648 -128.323689) (xy 433.523136 -128.28397)
			(xy 433.522186 -128.275864) (xy 433.515839 -128.260838) (xy 433.51069 -128.254506) (xy 433.484558 -128.224154)
			(xy 433.436697 -128.159928) (xy 433.394152 -128.092063) (xy 433.357198 -128.020999) (xy 433.341272 -127.98425)
			(xy 433.163726 -127.56261) (xy 433.146746 -127.520901) (xy 433.119492 -127.435062) (xy 433.100085 -127.347117)
			(xy 433.093876 -127.302514) (xy 433.091336 -127.292608) (xy 433.077055 -127.249085) (xy 433.055662 -127.160011)
			(xy 433.042597 -127.069341) (xy 433.039774 -127.023622) (xy 433.039266 -127.01397) (xy 433.039022 -127.009605)
			(xy 433.037234 -127.001049) (xy 433.03571 -126.996952) (xy 433.01838 -126.952883) (xy 432.991155 -126.862179)
			(xy 432.981354 -126.81585) (xy 432.81346 -125.971046) (xy 432.813206 -125.970792) (xy 432.7525 -125.932438)
			(xy 432.740308 -125.927104) (xy 432.721766 -125.93193) (xy 432.681288 -125.941858) (xy 432.599103 -125.955745)
			(xy 432.516045 -125.962728) (xy 432.47437 -125.963172) (xy 432.427687 -125.962631) (xy 432.334729 -125.953908)
			(xy 432.242994 -125.936532) (xy 432.153286 -125.910656) (xy 432.06639 -125.876506) (xy 431.983067 -125.83438)
			(xy 431.904048 -125.784649) (xy 431.830024 -125.727748) (xy 431.761645 -125.664176) (xy 431.699509 -125.594488)
			(xy 431.644161 -125.519297) (xy 431.61966 -125.479556) (xy 431.61714 -125.475578) (xy 431.610872 -125.468551)
			(xy 431.607214 -125.465586) (xy 431.583084 -125.445266) (xy 431.564707 -125.427903) (xy 431.532217 -125.389167)
			(xy 431.518314 -125.36805) (xy 431.514758 -125.362462) (xy 431.510694 -125.358652) (xy 431.504852 -125.353826)
			(xy 431.479452 -125.33884) (xy 431.471324 -125.335284) (xy 431.461418 -125.332998) (xy 431.4571 -125.332744)
			(xy 416.530282 -125.332744) (xy 416.520214 -125.332316) (xy 416.50162 -125.324591) (xy 416.494214 -125.317758)
			(xy 411.909768 -120.733312) (xy 411.90799 -120.73128) (xy 411.582362 -120.37187) (xy 411.578791 -120.368468)
			(xy 411.570605 -120.36297) (xy 411.566106 -120.360948) (xy 411.53842 -120.371616) (xy 411.529049 -120.375695)
			(xy 411.514345 -120.389863) (xy 411.506348 -120.408651) (xy 411.505908 -120.41886) (xy 411.505908 -124.967238)
			(xy 413.045148 -124.967238) (xy 413.045148 -124.103638) (xy 413.045638 -124.073654) (xy 413.053466 -124.014198)
			(xy 413.068987 -123.956273) (xy 413.091936 -123.900869) (xy 413.12192 -123.848935) (xy 413.158426 -123.801359)
			(xy 413.200831 -123.758954) (xy 413.248407 -123.722448) (xy 413.300341 -123.692464) (xy 413.355745 -123.669515)
			(xy 413.41367 -123.653994) (xy 413.473126 -123.646166) (xy 413.533094 -123.646166) (xy 413.59255 -123.653994)
			(xy 413.650475 -123.669515) (xy 413.705879 -123.692464) (xy 413.757813 -123.722448) (xy 413.805389 -123.758954)
			(xy 413.847794 -123.801359) (xy 413.8843 -123.848935) (xy 413.914284 -123.900869) (xy 413.937233 -123.956273)
			(xy 413.952754 -124.014198) (xy 413.960582 -124.073654) (xy 413.961072 -124.103638) (xy 413.961072 -124.967238)
			(xy 413.960582 -124.997222) (xy 413.952754 -125.056678) (xy 413.937233 -125.114603) (xy 413.914284 -125.170007)
			(xy 413.8843 -125.221941) (xy 413.847794 -125.269517) (xy 413.805389 -125.311922) (xy 413.757813 -125.348428)
			(xy 413.705879 -125.378412) (xy 413.650475 -125.401361) (xy 413.59255 -125.416882) (xy 413.533094 -125.42471)
			(xy 413.473126 -125.42471) (xy 413.41367 -125.416882) (xy 413.355745 -125.401361) (xy 413.300341 -125.378412)
			(xy 413.248407 -125.348428) (xy 413.200831 -125.311922) (xy 413.158426 -125.269517) (xy 413.12192 -125.221941)
			(xy 413.091936 -125.170007) (xy 413.068987 -125.114603) (xy 413.053466 -125.056678) (xy 413.045638 -124.997222)
			(xy 413.045148 -124.967238) (xy 411.505908 -124.967238) (xy 411.505908 -130.777234) (xy 414.899348 -130.777234)
			(xy 414.899348 -129.913634) (xy 414.899838 -129.88365) (xy 414.907666 -129.824194) (xy 414.923187 -129.766269)
			(xy 414.946136 -129.710865) (xy 414.97612 -129.658931) (xy 415.012626 -129.611355) (xy 415.055031 -129.56895)
			(xy 415.102607 -129.532444) (xy 415.154541 -129.50246) (xy 415.209945 -129.479511) (xy 415.26787 -129.46399)
			(xy 415.327326 -129.456162) (xy 415.387294 -129.456162) (xy 415.44675 -129.46399) (xy 415.504675 -129.479511)
			(xy 415.560079 -129.50246) (xy 415.612013 -129.532444) (xy 415.659589 -129.56895) (xy 415.701994 -129.611355)
			(xy 415.7385 -129.658931) (xy 415.768484 -129.710865) (xy 415.791433 -129.766269) (xy 415.806954 -129.824194)
			(xy 415.814782 -129.88365) (xy 415.815272 -129.913634) (xy 415.815272 -130.777234) (xy 415.814782 -130.807218)
			(xy 415.806954 -130.866674) (xy 415.791433 -130.924599) (xy 415.768484 -130.980003) (xy 415.7385 -131.031937)
			(xy 415.701994 -131.079513) (xy 415.659589 -131.121918) (xy 415.612013 -131.158424) (xy 415.560079 -131.188408)
			(xy 415.504675 -131.211357) (xy 415.44675 -131.226878) (xy 415.387294 -131.234706) (xy 415.327326 -131.234706)
			(xy 415.26787 -131.226878) (xy 415.209945 -131.211357) (xy 415.154541 -131.188408) (xy 415.102607 -131.158424)
			(xy 415.055031 -131.121918) (xy 415.012626 -131.079513) (xy 414.97612 -131.031937) (xy 414.946136 -130.980003)
			(xy 414.923187 -130.924599) (xy 414.907666 -130.866674) (xy 414.899838 -130.807218) (xy 414.899348 -130.777234)
			(xy 411.505908 -130.777234) (xy 411.505908 -132.577332) (xy 413.045148 -132.577332) (xy 413.045148 -131.713732)
			(xy 413.045638 -131.683748) (xy 413.053466 -131.624292) (xy 413.068987 -131.566367) (xy 413.091936 -131.510963)
			(xy 413.12192 -131.459029) (xy 413.158426 -131.411453) (xy 413.200831 -131.369048) (xy 413.248407 -131.332542)
			(xy 413.300341 -131.302558) (xy 413.355745 -131.279609) (xy 413.41367 -131.264088) (xy 413.473126 -131.25626)
			(xy 413.533094 -131.25626) (xy 413.59255 -131.264088) (xy 413.650475 -131.279609) (xy 413.705879 -131.302558)
			(xy 413.757813 -131.332542) (xy 413.805389 -131.369048) (xy 413.847794 -131.411453) (xy 413.8843 -131.459029)
			(xy 413.914284 -131.510963) (xy 413.937233 -131.566367) (xy 413.952754 -131.624292) (xy 413.960582 -131.683748)
			(xy 413.961072 -131.713732) (xy 413.961072 -132.577332) (xy 413.960582 -132.607316) (xy 413.952754 -132.666772)
			(xy 413.937233 -132.724697) (xy 413.914284 -132.780101) (xy 413.8843 -132.832035) (xy 413.847794 -132.879611)
			(xy 413.805389 -132.922016) (xy 413.757813 -132.958522) (xy 413.705879 -132.988506) (xy 413.650475 -133.011455)
			(xy 413.59255 -133.026976) (xy 413.533094 -133.034804) (xy 413.473126 -133.034804) (xy 413.41367 -133.026976)
			(xy 413.355745 -133.011455) (xy 413.300341 -132.988506) (xy 413.248407 -132.958522) (xy 413.200831 -132.922016)
			(xy 413.158426 -132.879611) (xy 413.12192 -132.832035) (xy 413.091936 -132.780101) (xy 413.068987 -132.724697)
			(xy 413.053466 -132.666772) (xy 413.045638 -132.607316) (xy 413.045148 -132.577332) (xy 411.505908 -132.577332)
			(xy 411.505908 -134.377176) (xy 414.899348 -134.377176) (xy 414.899348 -133.513576) (xy 414.899838 -133.483592)
			(xy 414.907666 -133.424136) (xy 414.923187 -133.366211) (xy 414.946136 -133.310807) (xy 414.97612 -133.258873)
			(xy 415.012626 -133.211297) (xy 415.055031 -133.168892) (xy 415.102607 -133.132386) (xy 415.154541 -133.102402)
			(xy 415.209945 -133.079453) (xy 415.26787 -133.063932) (xy 415.327326 -133.056104) (xy 415.387294 -133.056104)
			(xy 415.44675 -133.063932) (xy 415.504675 -133.079453) (xy 415.560079 -133.102402) (xy 415.612013 -133.132386)
			(xy 415.659589 -133.168892) (xy 415.701994 -133.211297) (xy 415.7385 -133.258873) (xy 415.768484 -133.310807)
			(xy 415.791433 -133.366211) (xy 415.806954 -133.424136) (xy 415.814782 -133.483592) (xy 415.815272 -133.513576)
			(xy 415.815272 -134.377176) (xy 415.814782 -134.40716) (xy 415.806954 -134.466616) (xy 415.791433 -134.524541)
			(xy 415.768484 -134.579945) (xy 415.7385 -134.631879) (xy 415.701994 -134.679455) (xy 415.659589 -134.72186)
			(xy 415.612013 -134.758366) (xy 415.560079 -134.78835) (xy 415.504675 -134.811299) (xy 415.44675 -134.82682)
			(xy 415.387294 -134.834648) (xy 415.327326 -134.834648) (xy 415.26787 -134.82682) (xy 415.209945 -134.811299)
			(xy 415.154541 -134.78835) (xy 415.102607 -134.758366) (xy 415.055031 -134.72186) (xy 415.012626 -134.679455)
			(xy 414.97612 -134.631879) (xy 414.946136 -134.579945) (xy 414.923187 -134.524541) (xy 414.907666 -134.466616)
			(xy 414.899838 -134.40716) (xy 414.899348 -134.377176) (xy 411.505908 -134.377176) (xy 411.505908 -136.177274)
			(xy 413.045148 -136.177274) (xy 413.045148 -135.313674) (xy 413.045638 -135.28369) (xy 413.053466 -135.224234)
			(xy 413.068987 -135.166309) (xy 413.091936 -135.110905) (xy 413.12192 -135.058971) (xy 413.158426 -135.011395)
			(xy 413.200831 -134.96899) (xy 413.248407 -134.932484) (xy 413.300341 -134.9025) (xy 413.355745 -134.879551)
			(xy 413.41367 -134.86403) (xy 413.473126 -134.856202) (xy 413.533094 -134.856202) (xy 413.59255 -134.86403)
			(xy 413.650475 -134.879551) (xy 413.705879 -134.9025) (xy 413.757813 -134.932484) (xy 413.805389 -134.96899)
			(xy 413.847794 -135.011395) (xy 413.8843 -135.058971) (xy 413.914284 -135.110905) (xy 413.937233 -135.166309)
			(xy 413.952754 -135.224234) (xy 413.960582 -135.28369) (xy 413.961072 -135.313674) (xy 413.961072 -136.177274)
			(xy 413.960582 -136.207258) (xy 413.952754 -136.266714) (xy 413.937233 -136.324639) (xy 413.914284 -136.380043)
			(xy 413.8843 -136.431977) (xy 413.847794 -136.479553) (xy 413.805389 -136.521958) (xy 413.757813 -136.558464)
			(xy 413.705879 -136.588448) (xy 413.650475 -136.611397) (xy 413.59255 -136.626918) (xy 413.533094 -136.634746)
			(xy 413.473126 -136.634746) (xy 413.41367 -136.626918) (xy 413.355745 -136.611397) (xy 413.300341 -136.588448)
			(xy 413.248407 -136.558464) (xy 413.200831 -136.521958) (xy 413.158426 -136.479553) (xy 413.12192 -136.431977)
			(xy 413.091936 -136.380043) (xy 413.068987 -136.324639) (xy 413.053466 -136.266714) (xy 413.045638 -136.207258)
			(xy 413.045148 -136.177274) (xy 411.505908 -136.177274) (xy 411.505908 -136.98601) (xy 428.857662 -136.98601)
			(xy 428.861733 -136.930388) (xy 428.873859 -136.875951) (xy 428.893782 -136.82386) (xy 428.921078 -136.775225)
			(xy 428.955164 -136.731082) (xy 428.995313 -136.692373) (xy 429.040671 -136.659922) (xy 429.090271 -136.634421)
			(xy 429.143055 -136.616414) (xy 429.197898 -136.606284) (xy 429.253632 -136.604247) (xy 429.309069 -136.610347)
			(xy 429.363026 -136.624453) (xy 429.414355 -136.646265) (xy 429.461961 -136.675319) (xy 429.504829 -136.710994)
			(xy 429.542046 -136.752531) (xy 429.572819 -136.799044) (xy 429.596491 -136.849541) (xy 429.612559 -136.902948)
			(xy 429.620679 -136.958124) (xy 429.621188 -136.98601) (xy 429.620679 -137.013896) (xy 429.612559 -137.069072)
			(xy 429.596491 -137.122479) (xy 429.572819 -137.172976) (xy 429.542046 -137.219489) (xy 429.504829 -137.261026)
			(xy 429.461961 -137.296701) (xy 429.414355 -137.325755) (xy 429.363026 -137.347567) (xy 429.309069 -137.361673)
			(xy 429.253632 -137.367773) (xy 429.197898 -137.365736) (xy 429.143055 -137.355606) (xy 429.090271 -137.337599)
			(xy 429.040671 -137.312098) (xy 428.995313 -137.279647) (xy 428.955164 -137.240938) (xy 428.921078 -137.196795)
			(xy 428.893782 -137.14816) (xy 428.873859 -137.096069) (xy 428.861733 -137.041632) (xy 428.857662 -136.98601)
			(xy 411.505908 -136.98601) (xy 411.505908 -138.31316) (xy 411.50538 -138.339184) (xy 411.497213 -138.390587)
			(xy 411.48112 -138.440085) (xy 411.457495 -138.486464) (xy 411.426919 -138.528584) (xy 411.40888 -138.547348)
			(xy 410.990034 -138.966194) (xy 410.986732 -138.9761) (xy 410.978413 -139.001818) (xy 410.955531 -139.050786)
			(xy 410.925962 -139.096032) (xy 410.890298 -139.136647) (xy 410.849256 -139.171819) (xy 410.803658 -139.200842)
			(xy 410.754418 -139.223133) (xy 410.702523 -139.238246) (xy 410.649013 -139.245879) (xy 410.621988 -139.246356)
			(xy 410.594736 -139.245869) (xy 410.540787 -139.238112) (xy 410.488491 -139.222756) (xy 410.438912 -139.200115)
			(xy 410.39306 -139.170649) (xy 410.351867 -139.134958) (xy 410.316172 -139.093769) (xy 410.286702 -139.047919)
			(xy 410.264056 -138.998343) (xy 410.248696 -138.946048) (xy 410.240933 -138.8921) (xy 410.24048 -138.864848)
			(xy 410.240954 -138.837825) (xy 410.248595 -138.784322) (xy 410.263715 -138.732435) (xy 410.286012 -138.683203)
			(xy 410.315039 -138.637614) (xy 410.350213 -138.596581) (xy 410.39083 -138.560927) (xy 410.436076 -138.531367)
			(xy 410.485043 -138.508494) (xy 410.510736 -138.500104) (xy 410.520642 -138.496802) (xy 410.646626 -138.370818)
			(xy 410.647264 -138.36492) (xy 410.646099 -138.353116) (xy 410.64434 -138.34745) (xy 410.619702 -138.27506)
			(xy 410.617182 -138.268437) (xy 410.609063 -138.256831) (xy 410.6037 -138.2522) (xy 410.573474 -138.227562)
			(xy 410.567378 -138.226546) (xy 410.540494 -138.222149) (xy 410.488249 -138.206732) (xy 410.438725 -138.184046)
			(xy 410.392928 -138.154551) (xy 410.351788 -138.118847) (xy 410.316139 -138.077659) (xy 410.286707 -138.031822)
			(xy 410.264087 -137.982267) (xy 410.248741 -137.930001) (xy 410.240978 -137.876084) (xy 410.24048 -137.848848)
			(xy 410.24094 -137.821593) (xy 410.248691 -137.767636) (xy 410.264043 -137.715331) (xy 410.286682 -137.665744)
			(xy 410.316149 -137.619884) (xy 410.351842 -137.578685) (xy 410.393036 -137.542985) (xy 410.438892 -137.513511)
			(xy 410.488475 -137.490864) (xy 410.540777 -137.475504) (xy 410.594733 -137.467744) (xy 410.621988 -137.46734)
			(xy 410.647771 -137.467733) (xy 410.698873 -137.474619) (xy 410.723842 -137.481056) (xy 410.72435 -137.481056)
			(xy 410.730019 -137.482482) (xy 410.741693 -137.483) (xy 410.747464 -137.482072) (xy 410.758132 -137.48004)
			(xy 410.784802 -137.459974) (xy 410.832554 -137.423652) (xy 410.84246 -137.413746) (xy 410.84246 -119.554498)
			(xy 410.839412 -119.550688) (xy 410.735272 -119.435372) (xy 410.724858 -119.426482) (xy 410.719016 -119.422926)
			(xy 410.712412 -119.420894) (xy 410.688732 -119.413144) (xy 410.644081 -119.39104) (xy 410.603617 -119.361973)
			(xy 410.585666 -119.344694) (xy 410.269436 -119.02821) (xy 410.26409 -119.023283) (xy 410.251325 -119.016334)
			(xy 410.24429 -119.014494) (xy 410.238702 -119.013732) (xy 410.202888 -119.010176) (xy 410.194194 -119.008938)
			(xy 410.178341 -119.001412) (xy 410.1719 -118.995444) (xy 408.633422 -117.456966) (xy 408.632914 -117.456712)
			(xy 408.628974 -117.45309) (xy 408.619876 -117.447456) (xy 408.61488 -117.445536) (xy 408.588718 -117.456458)
			(xy 408.5797 -117.460723) (xy 408.565611 -117.474818) (xy 408.557986 -117.49323) (xy 408.557476 -117.503194)
			(xy 408.557476 -132.225542) (xy 408.556997 -132.258419) (xy 408.549604 -132.323758) (xy 408.534949 -132.387859)
			(xy 408.513216 -132.449919) (xy 408.484677 -132.509158) (xy 408.449691 -132.564833) (xy 408.408698 -132.616246)
			(xy 408.385772 -132.639816) (xy 405.991314 -135.034274) (xy 405.967749 -135.057169) (xy 405.916364 -135.098118)
			(xy 405.86072 -135.13306) (xy 405.801517 -135.161558) (xy 405.739496 -135.183254) (xy 405.675438 -135.197874)
			(xy 405.610147 -135.205235) (xy 405.577294 -135.205724) (xy 405.57704 -135.205724) (xy 405.54164 -135.205213)
			(xy 405.471355 -135.196684) (xy 405.402611 -135.179744) (xy 405.33641 -135.154641) (xy 405.273717 -135.121741)
			(xy 405.215448 -135.081525) (xy 405.162451 -135.034577) (xy 405.1155 -134.981584) (xy 405.075279 -134.923317)
			(xy 405.042375 -134.860627) (xy 405.017268 -134.794428) (xy 405.000324 -134.725685) (xy 404.991789 -134.6554)
			(xy 404.991316 -134.62) (xy 404.991316 -134.619746) (xy 404.991757 -134.586891) (xy 404.999109 -134.521592)
			(xy 405.013727 -134.457528) (xy 405.035425 -134.395503) (xy 405.063931 -134.336297) (xy 405.098887 -134.280656)
			(xy 405.139854 -134.229278) (xy 405.162766 -134.205726) (xy 407.370534 -131.997958) (xy 407.377381 -131.99056)
			(xy 407.385111 -131.971961) (xy 407.38552 -131.96189) (xy 407.38552 -116.308632) (xy 407.38567 -116.291636)
			(xy 407.387705 -116.257706) (xy 407.389584 -116.240814) (xy 407.389584 -116.240306) (xy 407.392124 -116.217954)
			(xy 407.384504 -116.208048) (xy 403.3901 -112.213644) (xy 403.383262 -112.206242) (xy 403.375548 -112.187644)
			(xy 403.375114 -112.177576) (xy 403.375114 -112.15497) (xy 403.374949 -112.14896) (xy 403.37213 -112.137275)
			(xy 403.369526 -112.131856) (xy 403.367686 -112.128382) (xy 403.363092 -112.122004) (xy 403.360382 -112.119156)
			(xy 403.357588 -112.116362) (xy 403.357588 -76.072492) (xy 403.358012 -76.062422) (xy 403.365727 -76.043819)
			(xy 403.372574 -76.036424) (xy 403.442932 -75.966066) (xy 403.44598 -75.962764) (xy 403.446234 -75.96251)
			(xy 403.446996 -75.961748) (xy 404.289006 -75.119738) (xy 404.29053 -75.118468) (xy 404.293324 -75.115674)
			(xy 404.302468 -75.111864) (xy 404.307206 -75.109989) (xy 404.317186 -75.107934) (xy 404.32228 -75.1078)
			(xy 404.491444 -75.1078) (xy 404.495 -75.107546) (xy 404.496778 -75.107546) (xy 404.505369 -75.106603)
			(xy 404.521208 -75.099714) (xy 404.527766 -75.094084) (xy 404.69566 -74.925936) (xy 404.703066 -74.919242)
			(xy 404.721502 -74.911639) (xy 404.731474 -74.911204) (xy 405.025352 -74.911204) (xy 405.03602 -74.910188)
			(xy 405.037798 -74.90968) (xy 405.043132 -74.90841) (xy 405.05295 -74.90568) (xy 405.069451 -74.893754)
			(xy 405.075136 -74.885296) (xy 405.081486 -74.873358) (xy 405.08174 -74.87285) (xy 405.117808 -74.806048)
			(xy 405.119586 -74.802056) (xy 405.12189 -74.793627) (xy 405.12238 -74.789284) (xy 405.107394 -74.767186)
			(xy 405.091028 -74.742344) (xy 405.06513 -74.688791) (xy 405.047523 -74.631969) (xy 405.038604 -74.573155)
			(xy 405.038052 -74.543412) (xy 405.038052 -74.543158) (xy 405.038556 -74.514873) (xy 405.046607 -74.458878)
			(xy 405.062545 -74.404598) (xy 405.086045 -74.35314) (xy 405.11663 -74.305549) (xy 405.153676 -74.262796)
			(xy 405.196429 -74.22575) (xy 405.24402 -74.195165) (xy 405.295478 -74.171665) (xy 405.349758 -74.155727)
			(xy 405.405753 -74.147676) (xy 405.462323 -74.147676) (xy 405.518318 -74.155727) (xy 405.572598 -74.171665)
			(xy 405.624056 -74.195165) (xy 405.637514 -74.203814) (xy 431.474624 -74.203814) (xy 431.478695 -74.148192)
			(xy 431.490821 -74.093755) (xy 431.510744 -74.041664) (xy 431.53804 -73.993029) (xy 431.572126 -73.948886)
			(xy 431.612275 -73.910177) (xy 431.657633 -73.877726) (xy 431.707233 -73.852225) (xy 431.760017 -73.834218)
			(xy 431.81486 -73.824088) (xy 431.870594 -73.822051) (xy 431.926031 -73.828151) (xy 431.979988 -73.842257)
			(xy 432.031317 -73.864069) (xy 432.078923 -73.893123) (xy 432.121791 -73.928798) (xy 432.159008 -73.970335)
			(xy 432.189781 -74.016848) (xy 432.213453 -74.067345) (xy 432.229521 -74.120752) (xy 432.237641 -74.175928)
			(xy 432.23815 -74.203814) (xy 432.237641 -74.2317) (xy 432.229521 -74.286876) (xy 432.213453 -74.340283)
			(xy 432.189781 -74.39078) (xy 432.159008 -74.437293) (xy 432.121791 -74.47883) (xy 432.078923 -74.514505)
			(xy 432.031317 -74.543559) (xy 431.979988 -74.565371) (xy 431.926031 -74.579477) (xy 431.870594 -74.585577)
			(xy 431.81486 -74.58354) (xy 431.760017 -74.57341) (xy 431.707233 -74.555403) (xy 431.657633 -74.529902)
			(xy 431.612275 -74.497451) (xy 431.572126 -74.458742) (xy 431.53804 -74.414599) (xy 431.510744 -74.365964)
			(xy 431.490821 -74.313873) (xy 431.478695 -74.259436) (xy 431.474624 -74.203814) (xy 405.637514 -74.203814)
			(xy 405.671647 -74.22575) (xy 405.7144 -74.262796) (xy 405.751446 -74.305549) (xy 405.782031 -74.35314)
			(xy 405.805531 -74.404598) (xy 405.821469 -74.458878) (xy 405.82952 -74.514873) (xy 405.830024 -74.543158)
			(xy 405.830024 -74.543666) (xy 405.82949 -74.573411) (xy 405.820586 -74.63223) (xy 405.802973 -74.689053)
			(xy 405.777049 -74.742597) (xy 405.760682 -74.76744) (xy 405.745442 -74.789284) (xy 405.745963 -74.793498)
			(xy 405.748258 -74.801674) (xy 405.750014 -74.80554) (xy 405.750268 -74.806302) (xy 405.772112 -74.846688)
			(xy 405.772112 -74.847196) (xy 405.793702 -74.886566) (xy 405.79849 -74.89381) (xy 405.811901 -74.904823)
			(xy 405.828209 -74.910755) (xy 405.836882 -74.911204) (xy 451.883526 -74.911204) (xy 451.892924 -74.910188)
			(xy 451.893432 -74.910188) (xy 451.900588 -74.908477) (xy 451.913604 -74.901634) (xy 451.919086 -74.896726)
			(xy 453.11441 -73.701402) (xy 453.119396 -73.695974) (xy 453.126253 -73.682937) (xy 453.127872 -73.675748)
			(xy 453.127872 -73.67524) (xy 453.128888 -73.665842) (xy 453.128888 -73.039986) (xy 453.128725 -73.033975)
			(xy 453.125908 -73.022289) (xy 453.1233 -73.016872) (xy 453.12146 -73.013398) (xy 453.116866 -73.00702)
			(xy 453.114156 -73.004172) (xy 450.917564 -70.80758) (xy 450.91471 -70.804878) (xy 450.908328 -70.800294)
			(xy 450.904864 -70.798436) (xy 450.899438 -70.79585) (xy 450.887758 -70.793023) (xy 450.88175 -70.792848)
			(xy 357.649526 -70.792848) (xy 357.639463 -70.79241) (xy 357.620883 -70.784671) (xy 357.613458 -70.777862)
			(xy 357.538782 -70.703186) (xy 357.535929 -70.700483) (xy 357.529548 -70.695896) (xy 357.526082 -70.694042)
			(xy 357.520656 -70.691454) (xy 357.508977 -70.688622) (xy 357.502968 -70.688454) (xy 354.908104 -70.688454)
			(xy 354.900374 -70.688723) (xy 354.885633 -70.693382) (xy 354.879148 -70.697598) (xy 354.86975 -70.706996)
			(xy 354.863908 -70.714108) (xy 354.861876 -70.717156) (xy 354.81768 -70.781418) (xy 354.813004 -70.789616)
			(xy 354.809475 -70.808145) (xy 354.810822 -70.817486) (xy 354.811584 -70.821042) (xy 354.813362 -70.826122)
			(xy 354.850789 -70.925767) (xy 354.918534 -71.127581) (xy 354.978056 -71.331972) (xy 355.029258 -71.538604)
			(xy 355.0328 -71.555864) (xy 367.494564 -71.555864) (xy 367.498635 -71.500242) (xy 367.510761 -71.445805)
			(xy 367.530684 -71.393714) (xy 367.55798 -71.345079) (xy 367.592066 -71.300936) (xy 367.632215 -71.262227)
			(xy 367.677573 -71.229776) (xy 367.727173 -71.204275) (xy 367.779957 -71.186268) (xy 367.8348 -71.176138)
			(xy 367.890534 -71.174101) (xy 367.945971 -71.180201) (xy 367.999928 -71.194307) (xy 368.051257 -71.216119)
			(xy 368.098863 -71.245173) (xy 368.141731 -71.280848) (xy 368.178948 -71.322385) (xy 368.209721 -71.368898)
			(xy 368.233393 -71.419395) (xy 368.249461 -71.472802) (xy 368.257581 -71.527978) (xy 368.25809 -71.555864)
			(xy 368.257581 -71.58375) (xy 368.251742 -71.623428) (xy 369.003578 -71.623428) (xy 369.007649 -71.567806)
			(xy 369.019775 -71.513369) (xy 369.039698 -71.461278) (xy 369.066994 -71.412643) (xy 369.10108 -71.3685)
			(xy 369.141229 -71.329791) (xy 369.186587 -71.29734) (xy 369.236187 -71.271839) (xy 369.288971 -71.253832)
			(xy 369.343814 -71.243702) (xy 369.399548 -71.241665) (xy 369.454985 -71.247765) (xy 369.508942 -71.261871)
			(xy 369.560271 -71.283683) (xy 369.607877 -71.312737) (xy 369.650745 -71.348412) (xy 369.687962 -71.389949)
			(xy 369.718735 -71.436462) (xy 369.742407 -71.486959) (xy 369.758475 -71.540366) (xy 369.760756 -71.555864)
			(xy 393.494512 -71.555864) (xy 393.498583 -71.500242) (xy 393.510709 -71.445805) (xy 393.530632 -71.393714)
			(xy 393.557928 -71.345079) (xy 393.592014 -71.300936) (xy 393.632163 -71.262227) (xy 393.677521 -71.229776)
			(xy 393.727121 -71.204275) (xy 393.779905 -71.186268) (xy 393.834748 -71.176138) (xy 393.890482 -71.174101)
			(xy 393.945919 -71.180201) (xy 393.999876 -71.194307) (xy 394.051205 -71.216119) (xy 394.098811 -71.245173)
			(xy 394.141679 -71.280848) (xy 394.178896 -71.322385) (xy 394.209669 -71.368898) (xy 394.233341 -71.419395)
			(xy 394.249409 -71.472802) (xy 394.257529 -71.527978) (xy 394.258038 -71.555864) (xy 394.257529 -71.58375)
			(xy 394.25169 -71.623428) (xy 395.003526 -71.623428) (xy 395.007597 -71.567806) (xy 395.019723 -71.513369)
			(xy 395.039646 -71.461278) (xy 395.066942 -71.412643) (xy 395.101028 -71.3685) (xy 395.141177 -71.329791)
			(xy 395.186535 -71.29734) (xy 395.236135 -71.271839) (xy 395.288919 -71.253832) (xy 395.343762 -71.243702)
			(xy 395.399496 -71.241665) (xy 395.454933 -71.247765) (xy 395.50889 -71.261871) (xy 395.560219 -71.283683)
			(xy 395.607825 -71.312737) (xy 395.650693 -71.348412) (xy 395.68791 -71.389949) (xy 395.718683 -71.436462)
			(xy 395.742355 -71.486959) (xy 395.758423 -71.540366) (xy 395.760704 -71.555864) (xy 419.49446 -71.555864)
			(xy 419.498531 -71.500242) (xy 419.510657 -71.445805) (xy 419.53058 -71.393714) (xy 419.557876 -71.345079)
			(xy 419.591962 -71.300936) (xy 419.632111 -71.262227) (xy 419.677469 -71.229776) (xy 419.727069 -71.204275)
			(xy 419.779853 -71.186268) (xy 419.834696 -71.176138) (xy 419.89043 -71.174101) (xy 419.945867 -71.180201)
			(xy 419.999824 -71.194307) (xy 420.051153 -71.216119) (xy 420.098759 -71.245173) (xy 420.141627 -71.280848)
			(xy 420.178844 -71.322385) (xy 420.209617 -71.368898) (xy 420.233289 -71.419395) (xy 420.249357 -71.472802)
			(xy 420.257477 -71.527978) (xy 420.257986 -71.555864) (xy 420.257477 -71.58375) (xy 420.251638 -71.623428)
			(xy 421.003474 -71.623428) (xy 421.007545 -71.567806) (xy 421.019671 -71.513369) (xy 421.039594 -71.461278)
			(xy 421.06689 -71.412643) (xy 421.100976 -71.3685) (xy 421.141125 -71.329791) (xy 421.186483 -71.29734)
			(xy 421.236083 -71.271839) (xy 421.288867 -71.253832) (xy 421.34371 -71.243702) (xy 421.399444 -71.241665)
			(xy 421.454881 -71.247765) (xy 421.508838 -71.261871) (xy 421.560167 -71.283683) (xy 421.607773 -71.312737)
			(xy 421.650641 -71.348412) (xy 421.687858 -71.389949) (xy 421.718631 -71.436462) (xy 421.742303 -71.486959)
			(xy 421.758371 -71.540366) (xy 421.760652 -71.555864) (xy 445.494408 -71.555864) (xy 445.498479 -71.500242)
			(xy 445.510605 -71.445805) (xy 445.530528 -71.393714) (xy 445.557824 -71.345079) (xy 445.59191 -71.300936)
			(xy 445.632059 -71.262227) (xy 445.677417 -71.229776) (xy 445.727017 -71.204275) (xy 445.779801 -71.186268)
			(xy 445.834644 -71.176138) (xy 445.890378 -71.174101) (xy 445.945815 -71.180201) (xy 445.999772 -71.194307)
			(xy 446.051101 -71.216119) (xy 446.098707 -71.245173) (xy 446.141575 -71.280848) (xy 446.178792 -71.322385)
			(xy 446.209565 -71.368898) (xy 446.233237 -71.419395) (xy 446.249305 -71.472802) (xy 446.257425 -71.527978)
			(xy 446.257934 -71.555864) (xy 446.257425 -71.58375) (xy 446.251586 -71.623428) (xy 447.003422 -71.623428)
			(xy 447.007493 -71.567806) (xy 447.019619 -71.513369) (xy 447.039542 -71.461278) (xy 447.066838 -71.412643)
			(xy 447.100924 -71.3685) (xy 447.141073 -71.329791) (xy 447.186431 -71.29734) (xy 447.236031 -71.271839)
			(xy 447.288815 -71.253832) (xy 447.343658 -71.243702) (xy 447.399392 -71.241665) (xy 447.454829 -71.247765)
			(xy 447.508786 -71.261871) (xy 447.560115 -71.283683) (xy 447.607721 -71.312737) (xy 447.650589 -71.348412)
			(xy 447.687806 -71.389949) (xy 447.718579 -71.436462) (xy 447.742251 -71.486959) (xy 447.758319 -71.540366)
			(xy 447.766439 -71.595542) (xy 447.766948 -71.623428) (xy 447.766439 -71.651314) (xy 447.758319 -71.70649)
			(xy 447.742251 -71.759897) (xy 447.718579 -71.810394) (xy 447.687806 -71.856907) (xy 447.650589 -71.898444)
			(xy 447.607721 -71.934119) (xy 447.560115 -71.963173) (xy 447.508786 -71.984985) (xy 447.454829 -71.999091)
			(xy 447.399392 -72.005191) (xy 447.343658 -72.003154) (xy 447.288815 -71.993024) (xy 447.236031 -71.975017)
			(xy 447.186431 -71.949516) (xy 447.141073 -71.917065) (xy 447.100924 -71.878356) (xy 447.066838 -71.834213)
			(xy 447.039542 -71.785578) (xy 447.019619 -71.733487) (xy 447.007493 -71.67905) (xy 447.003422 -71.623428)
			(xy 446.251586 -71.623428) (xy 446.249305 -71.638926) (xy 446.233237 -71.692333) (xy 446.209565 -71.74283)
			(xy 446.178792 -71.789343) (xy 446.141575 -71.83088) (xy 446.098707 -71.866555) (xy 446.051101 -71.895609)
			(xy 445.999772 -71.917421) (xy 445.945815 -71.931527) (xy 445.890378 -71.937627) (xy 445.834644 -71.93559)
			(xy 445.779801 -71.92546) (xy 445.727017 -71.907453) (xy 445.677417 -71.881952) (xy 445.632059 -71.849501)
			(xy 445.59191 -71.810792) (xy 445.557824 -71.766649) (xy 445.530528 -71.718014) (xy 445.510605 -71.665923)
			(xy 445.498479 -71.611486) (xy 445.494408 -71.555864) (xy 421.760652 -71.555864) (xy 421.766491 -71.595542)
			(xy 421.767 -71.623428) (xy 421.766491 -71.651314) (xy 421.758371 -71.70649) (xy 421.742303 -71.759897)
			(xy 421.718631 -71.810394) (xy 421.687858 -71.856907) (xy 421.650641 -71.898444) (xy 421.607773 -71.934119)
			(xy 421.560167 -71.963173) (xy 421.508838 -71.984985) (xy 421.454881 -71.999091) (xy 421.399444 -72.005191)
			(xy 421.34371 -72.003154) (xy 421.288867 -71.993024) (xy 421.236083 -71.975017) (xy 421.186483 -71.949516)
			(xy 421.141125 -71.917065) (xy 421.100976 -71.878356) (xy 421.06689 -71.834213) (xy 421.039594 -71.785578)
			(xy 421.019671 -71.733487) (xy 421.007545 -71.67905) (xy 421.003474 -71.623428) (xy 420.251638 -71.623428)
			(xy 420.249357 -71.638926) (xy 420.233289 -71.692333) (xy 420.209617 -71.74283) (xy 420.178844 -71.789343)
			(xy 420.141627 -71.83088) (xy 420.098759 -71.866555) (xy 420.051153 -71.895609) (xy 419.999824 -71.917421)
			(xy 419.945867 -71.931527) (xy 419.89043 -71.937627) (xy 419.834696 -71.93559) (xy 419.779853 -71.92546)
			(xy 419.727069 -71.907453) (xy 419.677469 -71.881952) (xy 419.632111 -71.849501) (xy 419.591962 -71.810792)
			(xy 419.557876 -71.766649) (xy 419.53058 -71.718014) (xy 419.510657 -71.665923) (xy 419.498531 -71.611486)
			(xy 419.49446 -71.555864) (xy 395.760704 -71.555864) (xy 395.766543 -71.595542) (xy 395.767052 -71.623428)
			(xy 395.766543 -71.651314) (xy 395.758423 -71.70649) (xy 395.742355 -71.759897) (xy 395.718683 -71.810394)
			(xy 395.68791 -71.856907) (xy 395.650693 -71.898444) (xy 395.607825 -71.934119) (xy 395.560219 -71.963173)
			(xy 395.50889 -71.984985) (xy 395.454933 -71.999091) (xy 395.399496 -72.005191) (xy 395.343762 -72.003154)
			(xy 395.288919 -71.993024) (xy 395.236135 -71.975017) (xy 395.186535 -71.949516) (xy 395.141177 -71.917065)
			(xy 395.101028 -71.878356) (xy 395.066942 -71.834213) (xy 395.039646 -71.785578) (xy 395.019723 -71.733487)
			(xy 395.007597 -71.67905) (xy 395.003526 -71.623428) (xy 394.25169 -71.623428) (xy 394.249409 -71.638926)
			(xy 394.233341 -71.692333) (xy 394.209669 -71.74283) (xy 394.178896 -71.789343) (xy 394.141679 -71.83088)
			(xy 394.098811 -71.866555) (xy 394.051205 -71.895609) (xy 393.999876 -71.917421) (xy 393.945919 -71.931527)
			(xy 393.890482 -71.937627) (xy 393.834748 -71.93559) (xy 393.779905 -71.92546) (xy 393.727121 -71.907453)
			(xy 393.677521 -71.881952) (xy 393.632163 -71.849501) (xy 393.592014 -71.810792) (xy 393.557928 -71.766649)
			(xy 393.530632 -71.718014) (xy 393.510709 -71.665923) (xy 393.498583 -71.611486) (xy 393.494512 -71.555864)
			(xy 369.760756 -71.555864) (xy 369.766595 -71.595542) (xy 369.767104 -71.623428) (xy 369.766595 -71.651314)
			(xy 369.758475 -71.70649) (xy 369.742407 -71.759897) (xy 369.718735 -71.810394) (xy 369.687962 -71.856907)
			(xy 369.650745 -71.898444) (xy 369.607877 -71.934119) (xy 369.560271 -71.963173) (xy 369.508942 -71.984985)
			(xy 369.454985 -71.999091) (xy 369.399548 -72.005191) (xy 369.343814 -72.003154) (xy 369.288971 -71.993024)
			(xy 369.236187 -71.975017) (xy 369.186587 -71.949516) (xy 369.141229 -71.917065) (xy 369.10108 -71.878356)
			(xy 369.066994 -71.834213) (xy 369.039698 -71.785578) (xy 369.019775 -71.733487) (xy 369.007649 -71.67905)
			(xy 369.003578 -71.623428) (xy 368.251742 -71.623428) (xy 368.249461 -71.638926) (xy 368.233393 -71.692333)
			(xy 368.209721 -71.74283) (xy 368.178948 -71.789343) (xy 368.141731 -71.83088) (xy 368.098863 -71.866555)
			(xy 368.051257 -71.895609) (xy 367.999928 -71.917421) (xy 367.945971 -71.931527) (xy 367.890534 -71.937627)
			(xy 367.8348 -71.93559) (xy 367.779957 -71.92546) (xy 367.727173 -71.907453) (xy 367.677573 -71.881952)
			(xy 367.632215 -71.849501) (xy 367.592066 -71.810792) (xy 367.55798 -71.766649) (xy 367.530684 -71.718014)
			(xy 367.510761 -71.665923) (xy 367.498635 -71.611486) (xy 367.494564 -71.555864) (xy 355.0328 -71.555864)
			(xy 355.072055 -71.747139) (xy 355.106377 -71.957236) (xy 355.132168 -72.168549) (xy 355.149386 -72.380733)
			(xy 355.158002 -72.593439) (xy 355.158548 -72.69988) (xy 355.158054 -72.80186) (xy 355.15041 -72.998838)
			(xy 405.177496 -72.998838) (xy 405.181567 -72.943216) (xy 405.193693 -72.888779) (xy 405.213616 -72.836688)
			(xy 405.240912 -72.788053) (xy 405.274998 -72.74391) (xy 405.315147 -72.705201) (xy 405.360505 -72.67275)
			(xy 405.410105 -72.647249) (xy 405.462889 -72.629242) (xy 405.517732 -72.619112) (xy 405.573466 -72.617075)
			(xy 405.628903 -72.623175) (xy 405.68286 -72.637281) (xy 405.734189 -72.659093) (xy 405.781795 -72.688147)
			(xy 405.824663 -72.723822) (xy 405.86188 -72.765359) (xy 405.892653 -72.811872) (xy 405.916325 -72.862369)
			(xy 405.932393 -72.915776) (xy 405.940513 -72.970952) (xy 405.940665 -72.97928) (xy 432.334668 -72.97928)
			(xy 432.338739 -72.923658) (xy 432.350865 -72.869221) (xy 432.370788 -72.81713) (xy 432.398084 -72.768495)
			(xy 432.43217 -72.724352) (xy 432.472319 -72.685643) (xy 432.517677 -72.653192) (xy 432.567277 -72.627691)
			(xy 432.620061 -72.609684) (xy 432.674904 -72.599554) (xy 432.730638 -72.597517) (xy 432.786075 -72.603617)
			(xy 432.840032 -72.617723) (xy 432.891361 -72.639535) (xy 432.938967 -72.668589) (xy 432.981835 -72.704264)
			(xy 433.019052 -72.745801) (xy 433.049825 -72.792314) (xy 433.073497 -72.842811) (xy 433.089565 -72.896218)
			(xy 433.097685 -72.951394) (xy 433.098194 -72.97928) (xy 433.097685 -73.007166) (xy 433.089565 -73.062342)
			(xy 433.073497 -73.115749) (xy 433.049825 -73.166246) (xy 433.019052 -73.212759) (xy 432.981835 -73.254296)
			(xy 432.938967 -73.289971) (xy 432.891361 -73.319025) (xy 432.840032 -73.340837) (xy 432.786075 -73.354943)
			(xy 432.730638 -73.361043) (xy 432.674904 -73.359006) (xy 432.620061 -73.348876) (xy 432.567277 -73.330869)
			(xy 432.517677 -73.305368) (xy 432.472319 -73.272917) (xy 432.43217 -73.234208) (xy 432.398084 -73.190065)
			(xy 432.370788 -73.14143) (xy 432.350865 -73.089339) (xy 432.338739 -73.034902) (xy 432.334668 -72.97928)
			(xy 405.940665 -72.97928) (xy 405.941022 -72.998838) (xy 405.940513 -73.026724) (xy 405.932393 -73.0819)
			(xy 405.916325 -73.135307) (xy 405.892653 -73.185804) (xy 405.86188 -73.232317) (xy 405.824663 -73.273854)
			(xy 405.781795 -73.309529) (xy 405.734189 -73.338583) (xy 405.68286 -73.360395) (xy 405.628903 -73.374501)
			(xy 405.573466 -73.380601) (xy 405.517732 -73.378564) (xy 405.462889 -73.368434) (xy 405.410105 -73.350427)
			(xy 405.360505 -73.324926) (xy 405.315147 -73.292475) (xy 405.274998 -73.253766) (xy 405.240912 -73.209623)
			(xy 405.213616 -73.160988) (xy 405.193693 -73.108897) (xy 405.181567 -73.05446) (xy 405.177496 -72.998838)
			(xy 355.15041 -72.998838) (xy 355.150145 -73.005667) (xy 355.13434 -73.209014) (xy 355.110661 -73.411595)
			(xy 355.079146 -73.613106) (xy 355.03984 -73.813243) (xy 354.992804 -74.011705) (xy 354.938107 -74.208194)
			(xy 354.875833 -74.402415) (xy 354.806074 -74.594075) (xy 354.728936 -74.782886) (xy 354.644535 -74.968564)
			(xy 354.552998 -75.150829) (xy 354.551934 -75.152758) (xy 379.969266 -75.152758) (xy 379.973337 -75.097136)
			(xy 379.985463 -75.042699) (xy 380.005386 -74.990608) (xy 380.032682 -74.941973) (xy 380.066768 -74.89783)
			(xy 380.106917 -74.859121) (xy 380.152275 -74.82667) (xy 380.201875 -74.801169) (xy 380.254659 -74.783162)
			(xy 380.309502 -74.773032) (xy 380.365236 -74.770995) (xy 380.420673 -74.777095) (xy 380.47463 -74.791201)
			(xy 380.525959 -74.813013) (xy 380.573565 -74.842067) (xy 380.616433 -74.877742) (xy 380.65365 -74.919279)
			(xy 380.684423 -74.965792) (xy 380.708095 -75.016289) (xy 380.724088 -75.069446) (xy 381.604518 -75.069446)
			(xy 381.608589 -75.013824) (xy 381.620715 -74.959387) (xy 381.640638 -74.907296) (xy 381.667934 -74.858661)
			(xy 381.70202 -74.814518) (xy 381.742169 -74.775809) (xy 381.787527 -74.743358) (xy 381.837127 -74.717857)
			(xy 381.889911 -74.69985) (xy 381.944754 -74.68972) (xy 382.000488 -74.687683) (xy 382.055925 -74.693783)
			(xy 382.109882 -74.707889) (xy 382.161211 -74.729701) (xy 382.208817 -74.758755) (xy 382.251685 -74.79443)
			(xy 382.288902 -74.835967) (xy 382.319675 -74.88248) (xy 382.343347 -74.932977) (xy 382.359415 -74.986384)
			(xy 382.367535 -75.04156) (xy 382.368044 -75.069446) (xy 382.367535 -75.097332) (xy 382.359415 -75.152508)
			(xy 382.343347 -75.205915) (xy 382.319675 -75.256412) (xy 382.288902 -75.302925) (xy 382.251685 -75.344462)
			(xy 382.208817 -75.380137) (xy 382.161211 -75.409191) (xy 382.109882 -75.431003) (xy 382.055925 -75.445109)
			(xy 382.000488 -75.451209) (xy 381.944754 -75.449172) (xy 381.889911 -75.439042) (xy 381.837127 -75.421035)
			(xy 381.787527 -75.395534) (xy 381.742169 -75.363083) (xy 381.70202 -75.324374) (xy 381.667934 -75.280231)
			(xy 381.640638 -75.231596) (xy 381.620715 -75.179505) (xy 381.608589 -75.125068) (xy 381.604518 -75.069446)
			(xy 380.724088 -75.069446) (xy 380.724163 -75.069696) (xy 380.732283 -75.124872) (xy 380.732792 -75.152758)
			(xy 380.732283 -75.180644) (xy 380.724163 -75.23582) (xy 380.708095 -75.289227) (xy 380.684423 -75.339724)
			(xy 380.65365 -75.386237) (xy 380.616433 -75.427774) (xy 380.573565 -75.463449) (xy 380.525959 -75.492503)
			(xy 380.47463 -75.514315) (xy 380.420673 -75.528421) (xy 380.365236 -75.534521) (xy 380.309502 -75.532484)
			(xy 380.254659 -75.522354) (xy 380.201875 -75.504347) (xy 380.152275 -75.478846) (xy 380.106917 -75.446395)
			(xy 380.066768 -75.407686) (xy 380.032682 -75.363543) (xy 380.005386 -75.314908) (xy 379.985463 -75.262817)
			(xy 379.973337 -75.20838) (xy 379.969266 -75.152758) (xy 354.551934 -75.152758) (xy 354.454463 -75.329408)
			(xy 354.349076 -75.504032) (xy 354.236998 -75.674439) (xy 354.118397 -75.840371) (xy 353.993451 -76.001579)
			(xy 353.862348 -76.157822) (xy 353.725285 -76.308864) (xy 353.582469 -76.454477) (xy 353.434113 -76.594443)
			(xy 353.280442 -76.728551) (xy 353.121687 -76.8566) (xy 352.958086 -76.978396) (xy 352.789885 -77.093758)
			(xy 352.617337 -77.20251) (xy 352.440702 -77.30449) (xy 352.260246 -77.399545) (xy 352.07624 -77.48753)
			(xy 352.025021 -77.509624) (xy 391.980926 -77.509624) (xy 391.984997 -77.454002) (xy 391.997123 -77.399565)
			(xy 392.017046 -77.347474) (xy 392.044342 -77.298839) (xy 392.078428 -77.254696) (xy 392.118577 -77.215987)
			(xy 392.163935 -77.183536) (xy 392.213535 -77.158035) (xy 392.266319 -77.140028) (xy 392.321162 -77.129898)
			(xy 392.376896 -77.127861) (xy 392.432333 -77.133961) (xy 392.48629 -77.148067) (xy 392.537619 -77.169879)
			(xy 392.585225 -77.198933) (xy 392.628093 -77.234608) (xy 392.66531 -77.276145) (xy 392.696083 -77.322658)
			(xy 392.719755 -77.373155) (xy 392.735823 -77.426562) (xy 392.743943 -77.481738) (xy 392.744452 -77.509624)
			(xy 392.744443 -77.510132) (xy 393.554456 -77.510132) (xy 393.558527 -77.45451) (xy 393.570653 -77.400073)
			(xy 393.590576 -77.347982) (xy 393.617872 -77.299347) (xy 393.651958 -77.255204) (xy 393.692107 -77.216495)
			(xy 393.737465 -77.184044) (xy 393.787065 -77.158543) (xy 393.839849 -77.140536) (xy 393.894692 -77.130406)
			(xy 393.950426 -77.128369) (xy 394.005863 -77.134469) (xy 394.05982 -77.148575) (xy 394.111149 -77.170387)
			(xy 394.158755 -77.199441) (xy 394.201623 -77.235116) (xy 394.23884 -77.276653) (xy 394.269613 -77.323166)
			(xy 394.293285 -77.373663) (xy 394.309353 -77.42707) (xy 394.317473 -77.482246) (xy 394.317982 -77.510132)
			(xy 394.317473 -77.538018) (xy 394.309353 -77.593194) (xy 394.293285 -77.646601) (xy 394.269613 -77.697098)
			(xy 394.23884 -77.743611) (xy 394.201623 -77.785148) (xy 394.158755 -77.820823) (xy 394.111149 -77.849877)
			(xy 394.05982 -77.871689) (xy 394.005863 -77.885795) (xy 393.950426 -77.891895) (xy 393.894692 -77.889858)
			(xy 393.839849 -77.879728) (xy 393.787065 -77.861721) (xy 393.737465 -77.83622) (xy 393.692107 -77.803769)
			(xy 393.651958 -77.76506) (xy 393.617872 -77.720917) (xy 393.590576 -77.672282) (xy 393.570653 -77.620191)
			(xy 393.558527 -77.565754) (xy 393.554456 -77.510132) (xy 392.744443 -77.510132) (xy 392.743943 -77.53751)
			(xy 392.735823 -77.592686) (xy 392.719755 -77.646093) (xy 392.696083 -77.69659) (xy 392.66531 -77.743103)
			(xy 392.628093 -77.78464) (xy 392.585225 -77.820315) (xy 392.537619 -77.849369) (xy 392.48629 -77.871181)
			(xy 392.432333 -77.885287) (xy 392.376896 -77.891387) (xy 392.321162 -77.88935) (xy 392.266319 -77.87922)
			(xy 392.213535 -77.861213) (xy 392.163935 -77.835712) (xy 392.118577 -77.803261) (xy 392.078428 -77.764552)
			(xy 392.044342 -77.720409) (xy 392.017046 -77.671774) (xy 391.997123 -77.619683) (xy 391.984997 -77.565246)
			(xy 391.980926 -77.509624) (xy 352.025021 -77.509624) (xy 351.88896 -77.568315) (xy 351.698689 -77.641777)
			(xy 351.505713 -77.707805) (xy 351.310321 -77.766302) (xy 351.112808 -77.817178) (xy 350.913471 -77.860357)
			(xy 350.712609 -77.895774) (xy 350.510525 -77.923377) (xy 350.307523 -77.943122) (xy 350.103908 -77.954981)
			(xy 349.899986 -77.958937) (xy 349.696064 -77.954981) (xy 349.492449 -77.943122) (xy 349.289447 -77.923377)
			(xy 349.087363 -77.895774) (xy 348.886501 -77.860357) (xy 348.687164 -77.817178) (xy 348.489651 -77.766302)
			(xy 348.294259 -77.707805) (xy 348.101283 -77.641777) (xy 347.911012 -77.568315) (xy 347.723732 -77.48753)
			(xy 347.539726 -77.399545) (xy 347.35927 -77.30449) (xy 347.182635 -77.20251) (xy 347.010087 -77.093758)
			(xy 346.841886 -76.978396) (xy 346.678285 -76.8566) (xy 346.51953 -76.728551) (xy 346.365859 -76.594443)
			(xy 346.217503 -76.454477) (xy 346.074687 -76.308864) (xy 345.937624 -76.157822) (xy 345.806521 -76.001579)
			(xy 345.681575 -75.840371) (xy 345.562974 -75.674439) (xy 345.450896 -75.504032) (xy 345.345509 -75.329408)
			(xy 345.246974 -75.150829) (xy 345.155437 -74.968564) (xy 345.071036 -74.782886) (xy 344.993898 -74.594075)
			(xy 344.924139 -74.402415) (xy 344.861865 -74.208194) (xy 344.807168 -74.011705) (xy 344.760132 -73.813243)
			(xy 344.720826 -73.613106) (xy 344.689311 -73.411595) (xy 344.665632 -73.209014) (xy 344.649827 -73.005667)
			(xy 344.641918 -72.80186) (xy 344.641424 -72.69988) (xy 344.641909 -72.598712) (xy 344.649693 -72.396527)
			(xy 344.665248 -72.19479) (xy 344.688551 -71.993801) (xy 344.719568 -71.793857) (xy 344.758253 -71.595254)
			(xy 344.804549 -71.398286) (xy 344.858386 -71.203244) (xy 344.919687 -71.010418) (xy 344.988358 -70.820093)
			(xy 345.0643 -70.632549) (xy 345.1474 -70.448066) (xy 345.237534 -70.266916) (xy 345.33457 -70.089366)
			(xy 345.438363 -69.915681) (xy 345.54876 -69.746116) (xy 345.665598 -69.580924) (xy 345.788704 -69.420348)
			(xy 345.917895 -69.264626) (xy 346.05298 -69.113988) (xy 346.19376 -68.968659) (xy 346.340025 -68.828851)
			(xy 346.49156 -68.694774) (xy 346.64814 -68.566624) (xy 346.809534 -68.444592) (xy 346.975502 -68.328859)
			(xy 347.145799 -68.219595) (xy 347.320172 -68.116962) (xy 347.498365 -68.021113) (xy 347.680112 -67.932188)
			(xy 347.865146 -67.850321) (xy 348.053191 -67.775631) (xy 348.243971 -67.70823) (xy 348.437201 -67.648217)
			(xy 348.632597 -67.595681) (xy 348.82987 -67.5507) (xy 348.929198 -67.531488) (xy 348.937834 -67.529964)
			(xy 348.947994 -67.524122) (xy 348.9579 -67.515486) (xy 348.969584 -67.501516) (xy 348.970092 -67.501008)
			(xy 348.978474 -67.490594) (xy 348.978982 -67.490086) (xy 348.982538 -67.484244) (xy 348.984215 -67.481046)
			(xy 348.986765 -67.474291) (xy 348.987618 -67.470782) (xy 348.988634 -67.46113) (xy 348.988634 -41.2496)
			(xy 348.988527 -41.245984) (xy 348.987386 -41.238841) (xy 348.986348 -41.235376) (xy 348.977458 -41.209468)
			(xy 348.972378 -41.202864) (xy 348.956042 -41.180609) (xy 348.929272 -41.132328) (xy 348.90974 -41.080692)
			(xy 348.897855 -41.026781) (xy 348.893863 -40.971719) (xy 348.897849 -40.916657) (xy 348.909729 -40.862745)
			(xy 348.929256 -40.811107) (xy 348.956021 -40.762823) (xy 348.972378 -40.740584) (xy 348.977458 -40.73398)
			(xy 348.986348 -40.708072) (xy 348.988634 -40.693848) (xy 348.988634 -40.342566) (xy 348.98838 -40.33774)
			(xy 348.986368 -40.32523) (xy 348.972101 -40.304329) (xy 348.961202 -40.297862) (xy 348.958916 -40.296846)
			(xy 348.956884 -40.29583) (xy 348.95536 -40.295322) (xy 348.88678 -40.263572) (xy 348.87408 -40.25773)
			(xy 348.866102 -40.255425) (xy 348.849509 -40.255556) (xy 348.841568 -40.257984) (xy 348.830646 -40.261794)
			(xy 348.826749 -40.263289) (xy 348.819469 -40.267368) (xy 348.816168 -40.269922) (xy 348.79579 -40.285654)
			(xy 348.751611 -40.312086) (xy 348.704285 -40.332351) (xy 348.654668 -40.346082) (xy 348.603657 -40.353032)
			(xy 348.577916 -40.353488) (xy 348.550664 -40.353026) (xy 348.496714 -40.345271) (xy 348.444417 -40.329917)
			(xy 348.394837 -40.307277) (xy 348.348985 -40.277811) (xy 348.307792 -40.242119) (xy 348.272099 -40.200928)
			(xy 348.242631 -40.155077) (xy 348.219988 -40.105498) (xy 348.204632 -40.053202) (xy 348.196875 -39.999252)
			(xy 348.196875 -39.944748) (xy 348.204632 -39.890798) (xy 348.219988 -39.838502) (xy 348.242631 -39.788923)
			(xy 348.272099 -39.743072) (xy 348.307792 -39.701881) (xy 348.348985 -39.666189) (xy 348.394837 -39.636723)
			(xy 348.444417 -39.614083) (xy 348.496714 -39.598729) (xy 348.550664 -39.590974) (xy 348.577916 -39.590472)
			(xy 348.591378 -39.590472) (xy 348.621941 -39.592144) (xy 348.681986 -39.603999) (xy 348.739378 -39.625266)
			(xy 348.79265 -39.655401) (xy 348.81693 -39.674038) (xy 348.821248 -39.67734) (xy 348.831154 -39.68242)
			(xy 348.843854 -39.686738) (xy 348.85137 -39.688687) (xy 348.866888 -39.688431) (xy 348.874334 -39.68623)
			(xy 348.886526 -39.680388) (xy 348.887034 -39.680388) (xy 348.955614 -39.648638) (xy 348.961202 -39.646098)
			(xy 348.963996 -39.644574) (xy 348.973723 -39.638091) (xy 348.986443 -39.618509) (xy 348.98838 -39.606982)
			(xy 348.988634 -39.602664) (xy 348.988634 -38.432232) (xy 348.988152 -38.422218) (xy 348.980499 -38.403709)
			(xy 348.966346 -38.389538) (xy 348.947848 -38.381861) (xy 348.937834 -38.381432) (xy 347.585538 -38.381432)
			(xy 347.581982 -38.381686) (xy 347.580458 -38.381686) (xy 347.570851 -38.382835) (xy 347.55348 -38.391318)
			(xy 347.546676 -38.398196) (xy 347.54185 -38.40353) (xy 347.532198 -38.421564) (xy 347.490542 -38.499796)
			(xy 347.491304 -38.51402) (xy 347.492066 -38.527482) (xy 347.499432 -38.538912) (xy 347.499686 -38.53942)
			(xy 347.51481 -38.563007) (xy 347.538722 -38.61368) (xy 347.554958 -38.667307) (xy 347.563168 -38.722733)
			(xy 347.563694 -38.750748) (xy 347.563204 -38.777997) (xy 347.555442 -38.831938) (xy 347.540083 -38.884226)
			(xy 347.517439 -38.933797) (xy 347.487971 -38.97964) (xy 347.452279 -39.020823) (xy 347.41109 -39.056508)
			(xy 347.365242 -39.085969) (xy 347.315668 -39.108605) (xy 347.263378 -39.123956) (xy 347.209435 -39.131709)
			(xy 347.182186 -39.132256) (xy 347.154741 -39.131781) (xy 347.100415 -39.123925) (xy 347.047771 -39.108378)
			(xy 346.997894 -39.085459) (xy 346.951809 -39.055639) (xy 346.910465 -39.019533) (xy 346.874712 -38.977883)
			(xy 346.859606 -38.954964) (xy 346.85605 -38.949376) (xy 346.85224 -38.945566) (xy 346.843858 -38.939216)
			(xy 346.82303 -38.926008) (xy 346.817815 -38.923058) (xy 346.806389 -38.91946) (xy 346.800424 -38.918896)
			(xy 346.729304 -38.914324) (xy 346.717138 -38.914221) (xy 346.694857 -38.923902) (xy 346.686632 -38.932866)
			(xy 346.680028 -38.941502) (xy 346.661786 -38.963357) (xy 346.619935 -39.001945) (xy 346.572826 -39.033902)
			(xy 346.5215 -39.058523) (xy 346.467091 -39.075262) (xy 346.410802 -39.083751) (xy 346.38234 -39.08425)
			(xy 346.382086 -39.08425) (xy 346.354834 -39.083763) (xy 346.300886 -39.076005) (xy 346.24859 -39.060649)
			(xy 346.199012 -39.038008) (xy 346.153161 -39.008542) (xy 346.111969 -38.972851) (xy 346.076275 -38.931662)
			(xy 346.046805 -38.885812) (xy 346.02416 -38.836236) (xy 346.008801 -38.783942) (xy 346.001039 -38.729994)
			(xy 346.000578 -38.702742) (xy 346.001137 -38.672656) (xy 346.010582 -38.613231) (xy 346.029259 -38.556032)
			(xy 346.042488 -38.529006) (xy 346.044012 -38.525958) (xy 346.046122 -38.52069) (xy 346.048177 -38.509533)
			(xy 346.048076 -38.50386) (xy 346.047568 -38.490906) (xy 345.995244 -38.405562) (xy 345.994228 -38.404038)
			(xy 345.991434 -38.40099) (xy 345.990418 -38.39972) (xy 345.986862 -38.395402) (xy 345.979592 -38.389061)
			(xy 345.961701 -38.381891) (xy 345.952064 -38.381432) (xy 343.5858 -38.381432) (xy 343.575833 -38.381907)
			(xy 343.557394 -38.389481) (xy 343.549986 -38.396164) (xy 343.265252 -38.680898) (xy 343.263728 -38.682168)
			(xy 343.262966 -38.68293) (xy 343.23907 -38.705969) (xy 343.186338 -38.746286) (xy 343.128806 -38.779395)
			(xy 343.067452 -38.804729) (xy 343.003322 -38.821859) (xy 342.937507 -38.830492) (xy 342.904318 -38.831012)
			(xy 341.288878 -38.831012) (xy 341.2556 -38.830467) (xy 341.189615 -38.821779) (xy 341.125327 -38.804556)
			(xy 341.063836 -38.779091) (xy 341.006194 -38.74582) (xy 340.953386 -38.705311) (xy 340.929468 -38.682168)
			(xy 340.08187 -37.834824) (xy 340.0595 -37.811808) (xy 340.020142 -37.761106) (xy 340.003384 -37.733732)
			(xy 340.003384 -37.733478) (xy 340.00186 -37.730938) (xy 339.98535 -37.699696) (xy 339.984334 -37.697664)
			(xy 339.98281 -37.69487) (xy 339.982302 -37.694362) (xy 339.97373 -37.675845) (xy 339.959236 -37.637698)
			(xy 339.953346 -37.618162) (xy 339.953346 -37.617908) (xy 339.95233 -37.614098) (xy 339.949028 -37.602922)
			(xy 339.949028 -37.602668) (xy 339.947504 -37.596572) (xy 339.940392 -37.563552) (xy 339.940392 -37.563044)
			(xy 339.93963 -37.55898) (xy 339.938614 -37.551868) (xy 339.938614 -37.55136) (xy 339.936074 -37.531548)
			(xy 339.936074 -37.530532) (xy 339.935312 -37.525198) (xy 339.935312 -37.524182) (xy 339.933534 -37.500052)
			(xy 339.93328 -37.499036) (xy 339.933026 -37.494718) (xy 339.933026 -37.494464) (xy 339.932312 -37.46327)
			(xy 339.937582 -37.401096) (xy 339.950421 -37.340034) (xy 339.970633 -37.281002) (xy 339.997917 -37.224886)
			(xy 340.031861 -37.17253) (xy 340.071956 -37.12472) (xy 340.117599 -37.082175) (xy 340.168105 -37.045535)
			(xy 340.222715 -37.015349) (xy 340.280607 -36.992071) (xy 340.340912 -36.976051) (xy 340.402725 -36.96753)
			(xy 340.433914 -36.966652) (xy 340.443058 -36.966652) (xy 340.474844 -36.967255) (xy 340.537893 -36.975412)
			(xy 340.568788 -36.982908) (xy 340.60482 -36.99295) (xy 340.673682 -37.022152) (xy 340.705948 -37.041074)
			(xy 340.706456 -37.041328) (xy 340.707218 -37.041836) (xy 340.713314 -37.045646) (xy 340.714584 -37.046408)
			(xy 340.715092 -37.046662) (xy 340.72495 -37.053068) (xy 340.744135 -37.066662) (xy 340.753446 -37.07384)
			(xy 340.768178 -37.085778) (xy 340.800944 -37.11575) (xy 341.111078 -37.425884) (xy 341.48522 -37.80028)
			(xy 341.49061 -37.805173) (xy 341.503517 -37.811896) (xy 341.51062 -37.813488) (xy 341.511128 -37.813488)
			(xy 341.520526 -37.814504) (xy 342.150192 -37.814504) (xy 342.155427 -37.81435) (xy 342.16567 -37.81218)
			(xy 342.170512 -37.810186) (xy 342.17991 -37.806122) (xy 342.186768 -37.798756) (xy 342.188038 -37.797486)
			(xy 342.23833 -37.741352) (xy 342.238584 -37.741098) (xy 342.242011 -37.736976) (xy 342.247249 -37.727624)
			(xy 342.248998 -37.722556) (xy 342.252046 -37.712396) (xy 342.25103 -37.701982) (xy 342.248998 -37.667946)
			(xy 342.248998 -37.660834) (xy 342.249626 -37.632833) (xy 342.258079 -37.577468) (xy 342.274529 -37.523932)
			(xy 342.298624 -37.473373) (xy 342.329847 -37.426877) (xy 342.348312 -37.405818) (xy 342.349328 -37.404802)
			(xy 342.354154 -37.399214) (xy 342.359488 -37.373306) (xy 342.402414 -37.35578) (xy 342.41359 -37.348414)
			(xy 342.414606 -37.347906) (xy 342.438565 -37.332089) (xy 342.490225 -37.30705) (xy 342.545048 -37.290018)
			(xy 342.601802 -37.281375) (xy 342.630506 -37.28085) (xy 342.643244 -37.280928) (xy 342.668665 -37.282582)
			(xy 342.681306 -37.284152) (xy 342.68156 -37.284152) (xy 342.68664 -37.284914) (xy 342.687656 -37.284914)
			(xy 342.698832 -37.286946) (xy 342.69934 -37.286946) (xy 342.71077 -37.289232) (xy 342.736841 -37.295302)
			(xy 342.787087 -37.313759) (xy 342.834265 -37.339049) (xy 342.87745 -37.370677) (xy 342.915797 -37.408025)
			(xy 342.932512 -37.428932) (xy 342.936068 -37.433504) (xy 342.941554 -37.438692) (xy 342.954866 -37.445807)
			(xy 342.96223 -37.447474) (xy 342.98001 -37.450522) (xy 342.983566 -37.45103) (xy 342.989916 -37.451538)
			(xy 343.054686 -37.451538) (xy 343.059641 -37.451421) (xy 343.069364 -37.449506) (xy 343.07399 -37.447728)
			(xy 343.081356 -37.443918) (xy 343.083134 -37.442648) (xy 343.098374 -37.433504) (xy 343.120462 -37.420972)
			(xy 343.16665 -37.399853) (xy 343.190576 -37.39134) (xy 343.191338 -37.391086) (xy 343.193624 -37.390324)
			(xy 343.194132 -37.39007) (xy 343.22199 -37.381262) (xy 343.279192 -37.369357) (xy 343.337383 -37.364101)
			(xy 343.366598 -37.364416) (xy 348.937834 -37.364416) (xy 348.947838 -37.363923) (xy 348.966321 -37.356257)
			(xy 348.980468 -37.342106) (xy 348.988126 -37.323621) (xy 348.988634 -37.313616) (xy 348.988634 -5.04317)
			(xy 348.988469 -5.03716) (xy 348.985651 -5.025474) (xy 348.983046 -5.020056) (xy 348.981203 -5.016584)
			(xy 348.976604 -5.010211) (xy 348.973902 -5.007356) (xy 346.736162 -2.769616) (xy 346.733309 -2.766913)
			(xy 346.726928 -2.762325) (xy 346.723462 -2.760472) (xy 346.718035 -2.75789) (xy 346.706355 -2.755066)
			(xy 346.700348 -2.754884) (xy 340.097872 -2.754884) (xy 340.091862 -2.755049) (xy 340.080177 -2.757867)
			(xy 340.074758 -2.760472) (xy 340.071284 -2.762312) (xy 340.064906 -2.766906) (xy 340.062058 -2.769616)
			(xy 337.980782 -4.850892) (xy 337.978078 -4.853744) (xy 337.973488 -4.860124) (xy 337.971638 -4.863592)
			(xy 337.969058 -4.869019) (xy 337.966244 -4.880699) (xy 337.96605 -4.886706) (xy 337.96605 -5.747258)
			(xy 339.126066 -5.747258) (xy 339.130137 -5.691636) (xy 339.142263 -5.637199) (xy 339.162186 -5.585108)
			(xy 339.189482 -5.536473) (xy 339.223568 -5.49233) (xy 339.263717 -5.453621) (xy 339.309075 -5.42117)
			(xy 339.358675 -5.395669) (xy 339.411459 -5.377662) (xy 339.466302 -5.367532) (xy 339.522036 -5.365495)
			(xy 339.577473 -5.371595) (xy 339.63143 -5.385701) (xy 339.682759 -5.407513) (xy 339.730365 -5.436567)
			(xy 339.773233 -5.472242) (xy 339.81045 -5.513779) (xy 339.841223 -5.560292) (xy 339.864895 -5.610789)
			(xy 339.880963 -5.664196) (xy 339.889083 -5.719372) (xy 339.889592 -5.747258) (xy 339.889083 -5.775144)
			(xy 339.880963 -5.83032) (xy 339.864895 -5.883727) (xy 339.841223 -5.934224) (xy 339.81045 -5.980737)
			(xy 339.773233 -6.022274) (xy 339.730365 -6.057949) (xy 339.682759 -6.087003) (xy 339.63143 -6.108815)
			(xy 339.577473 -6.122921) (xy 339.522036 -6.129021) (xy 339.466302 -6.126984) (xy 339.411459 -6.116854)
			(xy 339.358675 -6.098847) (xy 339.309075 -6.073346) (xy 339.263717 -6.040895) (xy 339.223568 -6.002186)
			(xy 339.189482 -5.958043) (xy 339.162186 -5.909408) (xy 339.142263 -5.857317) (xy 339.130137 -5.80288)
			(xy 339.126066 -5.747258) (xy 337.96605 -5.747258) (xy 337.96605 -6.739636) (xy 339.101936 -6.739636)
			(xy 339.106007 -6.684014) (xy 339.118133 -6.629577) (xy 339.138056 -6.577486) (xy 339.165352 -6.528851)
			(xy 339.199438 -6.484708) (xy 339.239587 -6.445999) (xy 339.284945 -6.413548) (xy 339.334545 -6.388047)
			(xy 339.387329 -6.37004) (xy 339.442172 -6.35991) (xy 339.497906 -6.357873) (xy 339.553343 -6.363973)
			(xy 339.6073 -6.378079) (xy 339.658629 -6.399891) (xy 339.706235 -6.428945) (xy 339.749103 -6.46462)
			(xy 339.78632 -6.506157) (xy 339.817093 -6.55267) (xy 339.840765 -6.603167) (xy 339.856833 -6.656574)
			(xy 339.864953 -6.71175) (xy 339.865462 -6.739636) (xy 339.864953 -6.767522) (xy 339.856833 -6.822698)
			(xy 339.840765 -6.876105) (xy 339.817093 -6.926602) (xy 339.78632 -6.973115) (xy 339.749103 -7.014652)
			(xy 339.706235 -7.050327) (xy 339.658629 -7.079381) (xy 339.6073 -7.101193) (xy 339.553343 -7.115299)
			(xy 339.497906 -7.121399) (xy 339.442172 -7.119362) (xy 339.387329 -7.109232) (xy 339.334545 -7.091225)
			(xy 339.284945 -7.065724) (xy 339.239587 -7.033273) (xy 339.199438 -6.994564) (xy 339.165352 -6.950421)
			(xy 339.138056 -6.901786) (xy 339.118133 -6.849695) (xy 339.106007 -6.795258) (xy 339.101936 -6.739636)
			(xy 337.96605 -6.739636) (xy 337.96605 -7.742682) (xy 339.120224 -7.742682) (xy 339.124295 -7.68706)
			(xy 339.136421 -7.632623) (xy 339.156344 -7.580532) (xy 339.18364 -7.531897) (xy 339.217726 -7.487754)
			(xy 339.257875 -7.449045) (xy 339.303233 -7.416594) (xy 339.352833 -7.391093) (xy 339.405617 -7.373086)
			(xy 339.46046 -7.362956) (xy 339.516194 -7.360919) (xy 339.571631 -7.367019) (xy 339.625588 -7.381125)
			(xy 339.676917 -7.402937) (xy 339.724523 -7.431991) (xy 339.767391 -7.467666) (xy 339.804608 -7.509203)
			(xy 339.835381 -7.555716) (xy 339.859053 -7.606213) (xy 339.875121 -7.65962) (xy 339.883241 -7.714796)
			(xy 339.88375 -7.742682) (xy 339.883241 -7.770568) (xy 339.875121 -7.825744) (xy 339.859053 -7.879151)
			(xy 339.835381 -7.929648) (xy 339.804608 -7.976161) (xy 339.767391 -8.017698) (xy 339.724523 -8.053373)
			(xy 339.676917 -8.082427) (xy 339.625588 -8.104239) (xy 339.571631 -8.118345) (xy 339.516194 -8.124445)
			(xy 339.46046 -8.122408) (xy 339.405617 -8.112278) (xy 339.352833 -8.094271) (xy 339.303233 -8.06877)
			(xy 339.257875 -8.036319) (xy 339.217726 -7.99761) (xy 339.18364 -7.953467) (xy 339.156344 -7.904832)
			(xy 339.136421 -7.852741) (xy 339.124295 -7.798304) (xy 339.120224 -7.742682) (xy 337.96605 -7.742682)
			(xy 337.96605 -8.00354) (xy 337.966901 -8.012757) (xy 337.974316 -8.029699) (xy 337.980528 -8.03656)
			(xy 338.000848 -8.055864) (xy 338.036916 -8.090154) (xy 338.044039 -8.095832) (xy 338.061089 -8.102209)
			(xy 338.07019 -8.1026) (xy 338.074 -8.1026) (xy 338.092542 -8.102092) (xy 338.119791 -8.102581) (xy 338.173734 -8.110342)
			(xy 338.226024 -8.125701) (xy 338.275596 -8.148344) (xy 338.321441 -8.177812) (xy 338.362626 -8.213503)
			(xy 338.398313 -8.254692) (xy 338.427776 -8.300541) (xy 338.450414 -8.350115) (xy 338.465767 -8.402407)
			(xy 338.473522 -8.456351) (xy 338.473522 -8.510849) (xy 338.465767 -8.564793) (xy 338.450414 -8.617085)
			(xy 338.427776 -8.666659) (xy 338.398313 -8.712508) (xy 338.362626 -8.753697) (xy 338.321441 -8.789388)
			(xy 338.275596 -8.818856) (xy 338.226024 -8.841499) (xy 338.173734 -8.856858) (xy 338.119791 -8.864619)
			(xy 338.092542 -8.865108) (xy 338.073238 -8.8646) (xy 338.062824 -8.864092) (xy 338.04987 -8.869172)
			(xy 338.046665 -8.870631) (xy 338.040671 -8.874325) (xy 338.037932 -8.876538) (xy 337.982052 -8.92937)
			(xy 337.975956 -8.936228) (xy 337.97173 -8.942395) (xy 337.966703 -8.956466) (xy 337.96605 -8.963914)
			(xy 337.96605 -35.876738) (xy 341.01735 -35.876738) (xy 341.021421 -35.821116) (xy 341.033547 -35.766679)
			(xy 341.05347 -35.714588) (xy 341.080766 -35.665953) (xy 341.114852 -35.62181) (xy 341.155001 -35.583101)
			(xy 341.200359 -35.55065) (xy 341.249959 -35.525149) (xy 341.302743 -35.507142) (xy 341.357586 -35.497012)
			(xy 341.41332 -35.494975) (xy 341.468757 -35.501075) (xy 341.522714 -35.515181) (xy 341.574043 -35.536993)
			(xy 341.621649 -35.566047) (xy 341.664517 -35.601722) (xy 341.701734 -35.643259) (xy 341.732507 -35.689772)
			(xy 341.756179 -35.740269) (xy 341.772247 -35.793676) (xy 341.780367 -35.848852) (xy 341.780876 -35.876738)
			(xy 345.08897 -35.876738) (xy 345.093041 -35.821116) (xy 345.105167 -35.766679) (xy 345.12509 -35.714588)
			(xy 345.152386 -35.665953) (xy 345.186472 -35.62181) (xy 345.226621 -35.583101) (xy 345.271979 -35.55065)
			(xy 345.321579 -35.525149) (xy 345.374363 -35.507142) (xy 345.429206 -35.497012) (xy 345.48494 -35.494975)
			(xy 345.540377 -35.501075) (xy 345.594334 -35.515181) (xy 345.645663 -35.536993) (xy 345.693269 -35.566047)
			(xy 345.736137 -35.601722) (xy 345.773354 -35.643259) (xy 345.804127 -35.689772) (xy 345.827799 -35.740269)
			(xy 345.843867 -35.793676) (xy 345.851987 -35.848852) (xy 345.852496 -35.876738) (xy 345.851987 -35.904624)
			(xy 345.843867 -35.9598) (xy 345.827799 -36.013207) (xy 345.804127 -36.063704) (xy 345.773354 -36.110217)
			(xy 345.736137 -36.151754) (xy 345.693269 -36.187429) (xy 345.645663 -36.216483) (xy 345.594334 -36.238295)
			(xy 345.540377 -36.252401) (xy 345.48494 -36.258501) (xy 345.429206 -36.256464) (xy 345.374363 -36.246334)
			(xy 345.321579 -36.228327) (xy 345.271979 -36.202826) (xy 345.226621 -36.170375) (xy 345.186472 -36.131666)
			(xy 345.152386 -36.087523) (xy 345.12509 -36.038888) (xy 345.105167 -35.986797) (xy 345.093041 -35.93236)
			(xy 345.08897 -35.876738) (xy 341.780876 -35.876738) (xy 341.780367 -35.904624) (xy 341.772247 -35.9598)
			(xy 341.756179 -36.013207) (xy 341.732507 -36.063704) (xy 341.701734 -36.110217) (xy 341.664517 -36.151754)
			(xy 341.621649 -36.187429) (xy 341.574043 -36.216483) (xy 341.522714 -36.238295) (xy 341.468757 -36.252401)
			(xy 341.41332 -36.258501) (xy 341.357586 -36.256464) (xy 341.302743 -36.246334) (xy 341.249959 -36.228327)
			(xy 341.200359 -36.202826) (xy 341.155001 -36.170375) (xy 341.114852 -36.131666) (xy 341.080766 -36.087523)
			(xy 341.05347 -36.038888) (xy 341.033547 -35.986797) (xy 341.021421 -35.93236) (xy 341.01735 -35.876738)
			(xy 337.96605 -35.876738) (xy 337.96605 -36.50996) (xy 342.913968 -36.50996) (xy 342.918039 -36.454338)
			(xy 342.930165 -36.399901) (xy 342.950088 -36.34781) (xy 342.977384 -36.299175) (xy 343.01147 -36.255032)
			(xy 343.051619 -36.216323) (xy 343.096977 -36.183872) (xy 343.146577 -36.158371) (xy 343.199361 -36.140364)
			(xy 343.254204 -36.130234) (xy 343.309938 -36.128197) (xy 343.365375 -36.134297) (xy 343.419332 -36.148403)
			(xy 343.470661 -36.170215) (xy 343.518267 -36.199269) (xy 343.561135 -36.234944) (xy 343.598352 -36.276481)
			(xy 343.629125 -36.322994) (xy 343.652797 -36.373491) (xy 343.668865 -36.426898) (xy 343.67279 -36.453572)
			(xy 346.228668 -36.453572) (xy 346.232739 -36.39795) (xy 346.244865 -36.343513) (xy 346.264788 -36.291422)
			(xy 346.292084 -36.242787) (xy 346.32617 -36.198644) (xy 346.366319 -36.159935) (xy 346.411677 -36.127484)
			(xy 346.461277 -36.101983) (xy 346.514061 -36.083976) (xy 346.568904 -36.073846) (xy 346.624638 -36.071809)
			(xy 346.680075 -36.077909) (xy 346.734032 -36.092015) (xy 346.785361 -36.113827) (xy 346.832967 -36.142881)
			(xy 346.875835 -36.178556) (xy 346.913052 -36.220093) (xy 346.943825 -36.266606) (xy 346.967497 -36.317103)
			(xy 346.983565 -36.37051) (xy 346.991685 -36.425686) (xy 346.992194 -36.453572) (xy 346.991685 -36.481458)
			(xy 346.983565 -36.536634) (xy 346.967497 -36.590041) (xy 346.943825 -36.640538) (xy 346.913052 -36.687051)
			(xy 346.875835 -36.728588) (xy 346.832967 -36.764263) (xy 346.785361 -36.793317) (xy 346.734032 -36.815129)
			(xy 346.680075 -36.829235) (xy 346.624638 -36.835335) (xy 346.568904 -36.833298) (xy 346.514061 -36.823168)
			(xy 346.461277 -36.805161) (xy 346.411677 -36.77966) (xy 346.366319 -36.747209) (xy 346.32617 -36.7085)
			(xy 346.292084 -36.664357) (xy 346.264788 -36.615722) (xy 346.244865 -36.563631) (xy 346.232739 -36.509194)
			(xy 346.228668 -36.453572) (xy 343.67279 -36.453572) (xy 343.676985 -36.482074) (xy 343.677494 -36.50996)
			(xy 343.676985 -36.537846) (xy 343.668865 -36.593022) (xy 343.652797 -36.646429) (xy 343.629125 -36.696926)
			(xy 343.598352 -36.743439) (xy 343.561135 -36.784976) (xy 343.518267 -36.820651) (xy 343.470661 -36.849705)
			(xy 343.419332 -36.871517) (xy 343.365375 -36.885623) (xy 343.309938 -36.891723) (xy 343.254204 -36.889686)
			(xy 343.199361 -36.879556) (xy 343.146577 -36.861549) (xy 343.096977 -36.836048) (xy 343.051619 -36.803597)
			(xy 343.01147 -36.764888) (xy 342.977384 -36.720745) (xy 342.950088 -36.67211) (xy 342.930165 -36.620019)
			(xy 342.918039 -36.565582) (xy 342.913968 -36.50996) (xy 337.96605 -36.50996) (xy 337.96605 -56.97474)
			(xy 337.965618 -56.984806) (xy 337.957888 -57.003395) (xy 337.951064 -57.010808) (xy 337.651598 -57.310274)
			(xy 337.644763 -57.317677) (xy 337.637056 -57.336275) (xy 337.636612 -57.346342) (xy 337.636612 -67.366388)
			(xy 342.116408 -67.366388) (xy 342.120479 -67.310766) (xy 342.132605 -67.256329) (xy 342.152528 -67.204238)
			(xy 342.179824 -67.155603) (xy 342.21391 -67.11146) (xy 342.254059 -67.072751) (xy 342.299417 -67.0403)
			(xy 342.349017 -67.014799) (xy 342.401801 -66.996792) (xy 342.456644 -66.986662) (xy 342.512378 -66.984625)
			(xy 342.567815 -66.990725) (xy 342.621772 -67.004831) (xy 342.673101 -67.026643) (xy 342.720707 -67.055697)
			(xy 342.763575 -67.091372) (xy 342.800792 -67.132909) (xy 342.831565 -67.179422) (xy 342.855237 -67.229919)
			(xy 342.871305 -67.283326) (xy 342.879425 -67.338502) (xy 342.879934 -67.366388) (xy 342.879425 -67.394274)
			(xy 342.871305 -67.44945) (xy 342.855237 -67.502857) (xy 342.831565 -67.553354) (xy 342.800792 -67.599867)
			(xy 342.763575 -67.641404) (xy 342.720707 -67.677079) (xy 342.673101 -67.706133) (xy 342.621772 -67.727945)
			(xy 342.567815 -67.742051) (xy 342.512378 -67.748151) (xy 342.456644 -67.746114) (xy 342.401801 -67.735984)
			(xy 342.349017 -67.717977) (xy 342.299417 -67.692476) (xy 342.254059 -67.660025) (xy 342.21391 -67.621316)
			(xy 342.179824 -67.577173) (xy 342.152528 -67.528538) (xy 342.132605 -67.476447) (xy 342.120479 -67.42201)
			(xy 342.116408 -67.366388) (xy 337.636612 -67.366388) (xy 337.636612 -69.880734) (xy 337.636157 -69.912134)
			(xy 337.629062 -69.974532) (xy 337.615021 -70.035743) (xy 337.59421 -70.094995) (xy 337.566893 -70.151543)
			(xy 337.533412 -70.204674) (xy 337.494189 -70.253719) (xy 337.472274 -70.276212) (xy 337.375754 -70.372732)
			(xy 337.368986 -70.380161) (xy 337.361412 -70.398757) (xy 337.361022 -70.4088) (xy 337.361022 -76.386944)
			(xy 337.361454 -76.39701) (xy 337.369182 -76.415601) (xy 337.376008 -76.423012) (xy 338.459064 -77.506068)
			(xy 338.466464 -77.512908) (xy 338.485063 -77.520624) (xy 338.495132 -77.521054) (xy 340.741 -77.521054)
			(xy 340.751018 -77.520634) (xy 340.769527 -77.512962) (xy 340.783688 -77.498788) (xy 340.791343 -77.480272)
			(xy 340.7918 -77.470254) (xy 340.7918 -71.232522) (xy 340.788457 -71.228217) (xy 340.780254 -71.221041)
			(xy 340.775544 -71.218298) (xy 340.726776 -71.195438) (xy 340.726268 -71.195438) (xy 340.68893 -71.178166)
			(xy 340.677246 -71.174356) (xy 340.673096 -71.173611) (xy 340.664668 -71.173348) (xy 340.660482 -71.173848)
			(xy 340.65337 -71.174864) (xy 340.640416 -71.180706) (xy 340.634574 -71.185532) (xy 340.63432 -71.185786)
			(xy 340.61349 -71.202962) (xy 340.567907 -71.23189) (xy 340.518702 -71.254107) (xy 340.466859 -71.26917)
			(xy 340.41341 -71.276778) (xy 340.386416 -71.277226) (xy 340.359161 -71.276764) (xy 340.305206 -71.269009)
			(xy 340.252904 -71.253653) (xy 340.203319 -71.231011) (xy 340.157462 -71.201542) (xy 340.116265 -71.165846)
			(xy 340.080568 -71.124651) (xy 340.051097 -71.078795) (xy 340.028452 -71.029211) (xy 340.013095 -70.97691)
			(xy 340.005337 -70.922955) (xy 340.005337 -70.868445) (xy 340.013095 -70.81449) (xy 340.028452 -70.762189)
			(xy 340.051097 -70.712605) (xy 340.080568 -70.666749) (xy 340.116265 -70.625554) (xy 340.157462 -70.589858)
			(xy 340.203319 -70.560389) (xy 340.252904 -70.537747) (xy 340.305206 -70.522391) (xy 340.359161 -70.514636)
			(xy 340.386416 -70.51421) (xy 340.38667 -70.51421) (xy 340.415146 -70.514737) (xy 340.471464 -70.523206)
			(xy 340.525896 -70.539959) (xy 340.57723 -70.564625) (xy 340.624322 -70.596653) (xy 340.666125 -70.635332)
			(xy 340.684358 -70.657212) (xy 340.684358 -70.657466) (xy 340.686898 -70.660514) (xy 340.694993 -70.668282)
			(xy 340.71581 -70.676577) (xy 340.72703 -70.676516) (xy 340.786974 -70.669404) (xy 340.787482 -70.669404)
			(xy 340.802976 -70.667372) (xy 340.808947 -70.666484) (xy 340.820246 -70.662248) (xy 340.825328 -70.65899)
			(xy 340.830916 -70.654926) (xy 340.839044 -70.649084) (xy 340.844632 -70.636892) (xy 340.858947 -70.606602)
			(xy 340.89351 -70.549206) (xy 340.934393 -70.496125) (xy 340.981062 -70.448053) (xy 341.032908 -70.405617)
			(xy 341.089256 -70.36937) (xy 341.149369 -70.339785) (xy 341.212464 -70.317248) (xy 341.277718 -70.302054)
			(xy 341.344278 -70.294399) (xy 341.377778 -70.293992) (xy 341.413183 -70.294525) (xy 341.483476 -70.303055)
			(xy 341.552229 -70.319993) (xy 341.61844 -70.345093) (xy 341.681145 -70.377989) (xy 341.739428 -70.418201)
			(xy 341.792441 -70.465143) (xy 341.83941 -70.518131) (xy 341.879653 -70.576393) (xy 341.912581 -70.63908)
			(xy 341.937716 -70.705278) (xy 341.95469 -70.774023) (xy 341.963257 -70.844312) (xy 341.963756 -70.879716)
			(xy 341.963756 -79.844646) (xy 341.968328 -79.84998) (xy 342.941148 -80.8228) (xy 377.396754 -80.8228)
			(xy 377.400825 -80.767178) (xy 377.412951 -80.712741) (xy 377.432874 -80.66065) (xy 377.46017 -80.612015)
			(xy 377.494256 -80.567872) (xy 377.534405 -80.529163) (xy 377.579763 -80.496712) (xy 377.629363 -80.471211)
			(xy 377.682147 -80.453204) (xy 377.73699 -80.443074) (xy 377.792724 -80.441037) (xy 377.848161 -80.447137)
			(xy 377.902118 -80.461243) (xy 377.953447 -80.483055) (xy 378.001053 -80.512109) (xy 378.043921 -80.547784)
			(xy 378.081138 -80.589321) (xy 378.111911 -80.635834) (xy 378.116208 -80.645) (xy 380.871982 -80.645)
			(xy 380.876053 -80.589378) (xy 380.888179 -80.534941) (xy 380.908102 -80.48285) (xy 380.935398 -80.434215)
			(xy 380.969484 -80.390072) (xy 381.009633 -80.351363) (xy 381.054991 -80.318912) (xy 381.104591 -80.293411)
			(xy 381.157375 -80.275404) (xy 381.212218 -80.265274) (xy 381.267952 -80.263237) (xy 381.323389 -80.269337)
			(xy 381.377346 -80.283443) (xy 381.428675 -80.305255) (xy 381.476281 -80.334309) (xy 381.502588 -80.356202)
			(xy 392.196064 -80.356202) (xy 392.200135 -80.30058) (xy 392.212261 -80.246143) (xy 392.232184 -80.194052)
			(xy 392.25948 -80.145417) (xy 392.293566 -80.101274) (xy 392.333715 -80.062565) (xy 392.379073 -80.030114)
			(xy 392.428673 -80.004613) (xy 392.481457 -79.986606) (xy 392.5363 -79.976476) (xy 392.592034 -79.974439)
			(xy 392.647471 -79.980539) (xy 392.701428 -79.994645) (xy 392.752757 -80.016457) (xy 392.800363 -80.045511)
			(xy 392.843231 -80.081186) (xy 392.880448 -80.122723) (xy 392.911221 -80.169236) (xy 392.934893 -80.219733)
			(xy 392.950961 -80.27314) (xy 392.959081 -80.328316) (xy 392.95959 -80.356202) (xy 394.436344 -80.356202)
			(xy 394.440415 -80.30058) (xy 394.452541 -80.246143) (xy 394.472464 -80.194052) (xy 394.49976 -80.145417)
			(xy 394.533846 -80.101274) (xy 394.573995 -80.062565) (xy 394.619353 -80.030114) (xy 394.668953 -80.004613)
			(xy 394.721737 -79.986606) (xy 394.77658 -79.976476) (xy 394.832314 -79.974439) (xy 394.887751 -79.980539)
			(xy 394.941708 -79.994645) (xy 394.993037 -80.016457) (xy 395.040643 -80.045511) (xy 395.083511 -80.081186)
			(xy 395.120728 -80.122723) (xy 395.151501 -80.169236) (xy 395.175173 -80.219733) (xy 395.191241 -80.27314)
			(xy 395.199361 -80.328316) (xy 395.19987 -80.356202) (xy 396.84274 -80.356202) (xy 396.846811 -80.30058)
			(xy 396.858937 -80.246143) (xy 396.87886 -80.194052) (xy 396.906156 -80.145417) (xy 396.940242 -80.101274)
			(xy 396.980391 -80.062565) (xy 397.025749 -80.030114) (xy 397.075349 -80.004613) (xy 397.128133 -79.986606)
			(xy 397.182976 -79.976476) (xy 397.23871 -79.974439) (xy 397.294147 -79.980539) (xy 397.348104 -79.994645)
			(xy 397.399433 -80.016457) (xy 397.447039 -80.045511) (xy 397.489907 -80.081186) (xy 397.527124 -80.122723)
			(xy 397.557897 -80.169236) (xy 397.581569 -80.219733) (xy 397.597637 -80.27314) (xy 397.605757 -80.328316)
			(xy 397.606266 -80.356202) (xy 397.605757 -80.384088) (xy 397.597637 -80.439264) (xy 397.581569 -80.492671)
			(xy 397.557897 -80.543168) (xy 397.527124 -80.589681) (xy 397.489907 -80.631218) (xy 397.447039 -80.666893)
			(xy 397.399433 -80.695947) (xy 397.348104 -80.717759) (xy 397.294147 -80.731865) (xy 397.23871 -80.737965)
			(xy 397.182976 -80.735928) (xy 397.128133 -80.725798) (xy 397.075349 -80.707791) (xy 397.025749 -80.68229)
			(xy 396.980391 -80.649839) (xy 396.940242 -80.61113) (xy 396.906156 -80.566987) (xy 396.87886 -80.518352)
			(xy 396.858937 -80.466261) (xy 396.846811 -80.411824) (xy 396.84274 -80.356202) (xy 395.19987 -80.356202)
			(xy 395.199361 -80.384088) (xy 395.191241 -80.439264) (xy 395.175173 -80.492671) (xy 395.151501 -80.543168)
			(xy 395.120728 -80.589681) (xy 395.083511 -80.631218) (xy 395.040643 -80.666893) (xy 394.993037 -80.695947)
			(xy 394.941708 -80.717759) (xy 394.887751 -80.731865) (xy 394.832314 -80.737965) (xy 394.77658 -80.735928)
			(xy 394.721737 -80.725798) (xy 394.668953 -80.707791) (xy 394.619353 -80.68229) (xy 394.573995 -80.649839)
			(xy 394.533846 -80.61113) (xy 394.49976 -80.566987) (xy 394.472464 -80.518352) (xy 394.452541 -80.466261)
			(xy 394.440415 -80.411824) (xy 394.436344 -80.356202) (xy 392.95959 -80.356202) (xy 392.959081 -80.384088)
			(xy 392.950961 -80.439264) (xy 392.934893 -80.492671) (xy 392.911221 -80.543168) (xy 392.880448 -80.589681)
			(xy 392.843231 -80.631218) (xy 392.800363 -80.666893) (xy 392.752757 -80.695947) (xy 392.701428 -80.717759)
			(xy 392.647471 -80.731865) (xy 392.592034 -80.737965) (xy 392.5363 -80.735928) (xy 392.481457 -80.725798)
			(xy 392.428673 -80.707791) (xy 392.379073 -80.68229) (xy 392.333715 -80.649839) (xy 392.293566 -80.61113)
			(xy 392.25948 -80.566987) (xy 392.232184 -80.518352) (xy 392.212261 -80.466261) (xy 392.200135 -80.411824)
			(xy 392.196064 -80.356202) (xy 381.502588 -80.356202) (xy 381.519149 -80.369984) (xy 381.556366 -80.411521)
			(xy 381.587139 -80.458034) (xy 381.610811 -80.508531) (xy 381.626879 -80.561938) (xy 381.634999 -80.617114)
			(xy 381.635508 -80.645) (xy 381.634999 -80.672886) (xy 381.626879 -80.728062) (xy 381.610811 -80.781469)
			(xy 381.587139 -80.831966) (xy 381.556366 -80.878479) (xy 381.519149 -80.920016) (xy 381.476281 -80.955691)
			(xy 381.428675 -80.984745) (xy 381.377346 -81.006557) (xy 381.323389 -81.020663) (xy 381.267952 -81.026763)
			(xy 381.212218 -81.024726) (xy 381.157375 -81.014596) (xy 381.104591 -80.996589) (xy 381.054991 -80.971088)
			(xy 381.009633 -80.938637) (xy 380.969484 -80.899928) (xy 380.935398 -80.855785) (xy 380.908102 -80.80715)
			(xy 380.888179 -80.755059) (xy 380.876053 -80.700622) (xy 380.871982 -80.645) (xy 378.116208 -80.645)
			(xy 378.135583 -80.686331) (xy 378.151651 -80.739738) (xy 378.159771 -80.794914) (xy 378.16028 -80.8228)
			(xy 378.159771 -80.850686) (xy 378.151651 -80.905862) (xy 378.135583 -80.959269) (xy 378.111911 -81.009766)
			(xy 378.081138 -81.056279) (xy 378.043921 -81.097816) (xy 378.001053 -81.133491) (xy 377.953447 -81.162545)
			(xy 377.902118 -81.184357) (xy 377.848161 -81.198463) (xy 377.792724 -81.204563) (xy 377.73699 -81.202526)
			(xy 377.682147 -81.192396) (xy 377.629363 -81.174389) (xy 377.579763 -81.148888) (xy 377.534405 -81.116437)
			(xy 377.494256 -81.077728) (xy 377.46017 -81.033585) (xy 377.432874 -80.98495) (xy 377.412951 -80.932859)
			(xy 377.400825 -80.878422) (xy 377.396754 -80.8228) (xy 342.941148 -80.8228) (xy 343.619582 -81.501234)
			(xy 351.221292 -81.501234) (xy 351.225363 -81.445612) (xy 351.237489 -81.391175) (xy 351.257412 -81.339084)
			(xy 351.284708 -81.290449) (xy 351.318794 -81.246306) (xy 351.358943 -81.207597) (xy 351.404301 -81.175146)
			(xy 351.453901 -81.149645) (xy 351.506685 -81.131638) (xy 351.561528 -81.121508) (xy 351.617262 -81.119471)
			(xy 351.672699 -81.125571) (xy 351.726656 -81.139677) (xy 351.777985 -81.161489) (xy 351.825591 -81.190543)
			(xy 351.868459 -81.226218) (xy 351.905676 -81.267755) (xy 351.936449 -81.314268) (xy 351.960121 -81.364765)
			(xy 351.975044 -81.414366) (xy 354.132386 -81.414366) (xy 354.136457 -81.358744) (xy 354.148583 -81.304307)
			(xy 354.168506 -81.252216) (xy 354.195802 -81.203581) (xy 354.229888 -81.159438) (xy 354.270037 -81.120729)
			(xy 354.315395 -81.088278) (xy 354.364995 -81.062777) (xy 354.417779 -81.04477) (xy 354.472622 -81.03464)
			(xy 354.528356 -81.032603) (xy 354.583793 -81.038703) (xy 354.63775 -81.052809) (xy 354.689079 -81.074621)
			(xy 354.736685 -81.103675) (xy 354.779553 -81.13935) (xy 354.81677 -81.180887) (xy 354.847543 -81.2274)
			(xy 354.871215 -81.277897) (xy 354.887283 -81.331304) (xy 354.895403 -81.38648) (xy 354.895912 -81.414366)
			(xy 354.895403 -81.442252) (xy 354.887283 -81.497428) (xy 354.886902 -81.498694) (xy 364.632238 -81.498694)
			(xy 364.636309 -81.443072) (xy 364.648435 -81.388635) (xy 364.668358 -81.336544) (xy 364.695654 -81.287909)
			(xy 364.72974 -81.243766) (xy 364.769889 -81.205057) (xy 364.815247 -81.172606) (xy 364.864847 -81.147105)
			(xy 364.917631 -81.129098) (xy 364.972474 -81.118968) (xy 365.028208 -81.116931) (xy 365.083645 -81.123031)
			(xy 365.137602 -81.137137) (xy 365.188931 -81.158949) (xy 365.236537 -81.188003) (xy 365.279405 -81.223678)
			(xy 365.316622 -81.265215) (xy 365.347395 -81.311728) (xy 365.371067 -81.362225) (xy 365.387135 -81.415632)
			(xy 365.395255 -81.470808) (xy 365.395764 -81.498694) (xy 367.679222 -81.498694) (xy 367.683293 -81.443072)
			(xy 367.695419 -81.388635) (xy 367.715342 -81.336544) (xy 367.742638 -81.287909) (xy 367.776724 -81.243766)
			(xy 367.816873 -81.205057) (xy 367.862231 -81.172606) (xy 367.911831 -81.147105) (xy 367.964615 -81.129098)
			(xy 368.019458 -81.118968) (xy 368.075192 -81.116931) (xy 368.130629 -81.123031) (xy 368.184586 -81.137137)
			(xy 368.235915 -81.158949) (xy 368.283521 -81.188003) (xy 368.326389 -81.223678) (xy 368.363606 -81.265215)
			(xy 368.394379 -81.311728) (xy 368.418051 -81.362225) (xy 368.434119 -81.415632) (xy 368.442239 -81.470808)
			(xy 368.442748 -81.498694) (xy 370.219222 -81.498694) (xy 370.223293 -81.443072) (xy 370.235419 -81.388635)
			(xy 370.255342 -81.336544) (xy 370.282638 -81.287909) (xy 370.316724 -81.243766) (xy 370.356873 -81.205057)
			(xy 370.402231 -81.172606) (xy 370.451831 -81.147105) (xy 370.504615 -81.129098) (xy 370.559458 -81.118968)
			(xy 370.615192 -81.116931) (xy 370.670629 -81.123031) (xy 370.724586 -81.137137) (xy 370.775915 -81.158949)
			(xy 370.823521 -81.188003) (xy 370.866389 -81.223678) (xy 370.903606 -81.265215) (xy 370.934379 -81.311728)
			(xy 370.958051 -81.362225) (xy 370.974119 -81.415632) (xy 370.982239 -81.470808) (xy 370.982748 -81.498694)
			(xy 370.982239 -81.52658) (xy 370.981147 -81.534) (xy 380.998982 -81.534) (xy 381.003053 -81.478378)
			(xy 381.015179 -81.423941) (xy 381.035102 -81.37185) (xy 381.062398 -81.323215) (xy 381.096484 -81.279072)
			(xy 381.136633 -81.240363) (xy 381.181991 -81.207912) (xy 381.231591 -81.182411) (xy 381.284375 -81.164404)
			(xy 381.339218 -81.154274) (xy 381.394952 -81.152237) (xy 381.450389 -81.158337) (xy 381.504346 -81.172443)
			(xy 381.555675 -81.194255) (xy 381.603281 -81.223309) (xy 381.646149 -81.258984) (xy 381.683366 -81.300521)
			(xy 381.714139 -81.347034) (xy 381.737811 -81.397531) (xy 381.753879 -81.450938) (xy 381.760982 -81.499202)
			(xy 390.559542 -81.499202) (xy 390.563613 -81.44358) (xy 390.575739 -81.389143) (xy 390.595662 -81.337052)
			(xy 390.622958 -81.288417) (xy 390.657044 -81.244274) (xy 390.697193 -81.205565) (xy 390.742551 -81.173114)
			(xy 390.792151 -81.147613) (xy 390.844935 -81.129606) (xy 390.899778 -81.119476) (xy 390.955512 -81.117439)
			(xy 391.010949 -81.123539) (xy 391.064906 -81.137645) (xy 391.116235 -81.159457) (xy 391.163841 -81.188511)
			(xy 391.206709 -81.224186) (xy 391.243926 -81.265723) (xy 391.274699 -81.312236) (xy 391.298371 -81.362733)
			(xy 391.314439 -81.41614) (xy 391.322559 -81.471316) (xy 391.323068 -81.499202) (xy 391.322559 -81.527088)
			(xy 391.314439 -81.582264) (xy 391.298371 -81.635671) (xy 391.274699 -81.686168) (xy 391.243926 -81.732681)
			(xy 391.206709 -81.774218) (xy 391.163841 -81.809893) (xy 391.116235 -81.838947) (xy 391.064906 -81.860759)
			(xy 391.010949 -81.874865) (xy 390.955512 -81.880965) (xy 390.899778 -81.878928) (xy 390.844935 -81.868798)
			(xy 390.792151 -81.850791) (xy 390.742551 -81.82529) (xy 390.697193 -81.792839) (xy 390.657044 -81.75413)
			(xy 390.622958 -81.709987) (xy 390.595662 -81.661352) (xy 390.575739 -81.609261) (xy 390.563613 -81.554824)
			(xy 390.559542 -81.499202) (xy 381.760982 -81.499202) (xy 381.761999 -81.506114) (xy 381.762508 -81.534)
			(xy 381.761999 -81.561886) (xy 381.753879 -81.617062) (xy 381.737811 -81.670469) (xy 381.714139 -81.720966)
			(xy 381.683366 -81.767479) (xy 381.646149 -81.809016) (xy 381.603281 -81.844691) (xy 381.555675 -81.873745)
			(xy 381.504346 -81.895557) (xy 381.450389 -81.909663) (xy 381.394952 -81.915763) (xy 381.339218 -81.913726)
			(xy 381.284375 -81.903596) (xy 381.231591 -81.885589) (xy 381.181991 -81.860088) (xy 381.136633 -81.827637)
			(xy 381.096484 -81.788928) (xy 381.062398 -81.744785) (xy 381.035102 -81.69615) (xy 381.015179 -81.644059)
			(xy 381.003053 -81.589622) (xy 380.998982 -81.534) (xy 370.981147 -81.534) (xy 370.974119 -81.581756)
			(xy 370.958051 -81.635163) (xy 370.934379 -81.68566) (xy 370.903606 -81.732173) (xy 370.866389 -81.77371)
			(xy 370.823521 -81.809385) (xy 370.775915 -81.838439) (xy 370.724586 -81.860251) (xy 370.670629 -81.874357)
			(xy 370.615192 -81.880457) (xy 370.559458 -81.87842) (xy 370.504615 -81.86829) (xy 370.451831 -81.850283)
			(xy 370.402231 -81.824782) (xy 370.356873 -81.792331) (xy 370.316724 -81.753622) (xy 370.282638 -81.709479)
			(xy 370.255342 -81.660844) (xy 370.235419 -81.608753) (xy 370.223293 -81.554316) (xy 370.219222 -81.498694)
			(xy 368.442748 -81.498694) (xy 368.442239 -81.52658) (xy 368.434119 -81.581756) (xy 368.418051 -81.635163)
			(xy 368.394379 -81.68566) (xy 368.363606 -81.732173) (xy 368.326389 -81.77371) (xy 368.283521 -81.809385)
			(xy 368.235915 -81.838439) (xy 368.184586 -81.860251) (xy 368.130629 -81.874357) (xy 368.075192 -81.880457)
			(xy 368.019458 -81.87842) (xy 367.964615 -81.86829) (xy 367.911831 -81.850283) (xy 367.862231 -81.824782)
			(xy 367.816873 -81.792331) (xy 367.776724 -81.753622) (xy 367.742638 -81.709479) (xy 367.715342 -81.660844)
			(xy 367.695419 -81.608753) (xy 367.683293 -81.554316) (xy 367.679222 -81.498694) (xy 365.395764 -81.498694)
			(xy 365.395255 -81.52658) (xy 365.387135 -81.581756) (xy 365.371067 -81.635163) (xy 365.347395 -81.68566)
			(xy 365.316622 -81.732173) (xy 365.279405 -81.77371) (xy 365.236537 -81.809385) (xy 365.188931 -81.838439)
			(xy 365.137602 -81.860251) (xy 365.083645 -81.874357) (xy 365.028208 -81.880457) (xy 364.972474 -81.87842)
			(xy 364.917631 -81.86829) (xy 364.864847 -81.850283) (xy 364.815247 -81.824782) (xy 364.769889 -81.792331)
			(xy 364.72974 -81.753622) (xy 364.695654 -81.709479) (xy 364.668358 -81.660844) (xy 364.648435 -81.608753)
			(xy 364.636309 -81.554316) (xy 364.632238 -81.498694) (xy 354.886902 -81.498694) (xy 354.871215 -81.550835)
			(xy 354.847543 -81.601332) (xy 354.81677 -81.647845) (xy 354.779553 -81.689382) (xy 354.736685 -81.725057)
			(xy 354.689079 -81.754111) (xy 354.63775 -81.775923) (xy 354.583793 -81.790029) (xy 354.528356 -81.796129)
			(xy 354.472622 -81.794092) (xy 354.417779 -81.783962) (xy 354.364995 -81.765955) (xy 354.315395 -81.740454)
			(xy 354.270037 -81.708003) (xy 354.229888 -81.669294) (xy 354.195802 -81.625151) (xy 354.168506 -81.576516)
			(xy 354.148583 -81.524425) (xy 354.136457 -81.469988) (xy 354.132386 -81.414366) (xy 351.975044 -81.414366)
			(xy 351.976189 -81.418172) (xy 351.984309 -81.473348) (xy 351.984818 -81.501234) (xy 351.984309 -81.52912)
			(xy 351.976189 -81.584296) (xy 351.960121 -81.637703) (xy 351.936449 -81.6882) (xy 351.905676 -81.734713)
			(xy 351.868459 -81.77625) (xy 351.825591 -81.811925) (xy 351.777985 -81.840979) (xy 351.726656 -81.862791)
			(xy 351.672699 -81.876897) (xy 351.617262 -81.882997) (xy 351.561528 -81.88096) (xy 351.506685 -81.87083)
			(xy 351.453901 -81.852823) (xy 351.404301 -81.827322) (xy 351.358943 -81.794871) (xy 351.318794 -81.756162)
			(xy 351.284708 -81.712019) (xy 351.257412 -81.663384) (xy 351.237489 -81.611293) (xy 351.225363 -81.556856)
			(xy 351.221292 -81.501234) (xy 343.619582 -81.501234) (xy 344.00871 -81.890362) (xy 355.959916 -81.890362)
			(xy 355.963987 -81.83474) (xy 355.976113 -81.780303) (xy 355.996036 -81.728212) (xy 356.023332 -81.679577)
			(xy 356.057418 -81.635434) (xy 356.097567 -81.596725) (xy 356.142925 -81.564274) (xy 356.192525 -81.538773)
			(xy 356.245309 -81.520766) (xy 356.300152 -81.510636) (xy 356.355886 -81.508599) (xy 356.411323 -81.514699)
			(xy 356.46528 -81.528805) (xy 356.516609 -81.550617) (xy 356.564215 -81.579671) (xy 356.607083 -81.615346)
			(xy 356.6443 -81.656883) (xy 356.675073 -81.703396) (xy 356.698745 -81.753893) (xy 356.714813 -81.8073)
			(xy 356.722933 -81.862476) (xy 356.723442 -81.890362) (xy 356.722933 -81.918248) (xy 356.715935 -81.9658)
			(xy 374.915428 -81.9658) (xy 374.919499 -81.910178) (xy 374.931625 -81.855741) (xy 374.951548 -81.80365)
			(xy 374.978844 -81.755015) (xy 375.01293 -81.710872) (xy 375.053079 -81.672163) (xy 375.098437 -81.639712)
			(xy 375.148037 -81.614211) (xy 375.200821 -81.596204) (xy 375.255664 -81.586074) (xy 375.311398 -81.584037)
			(xy 375.366835 -81.590137) (xy 375.420792 -81.604243) (xy 375.472121 -81.626055) (xy 375.519727 -81.655109)
			(xy 375.562595 -81.690784) (xy 375.599812 -81.732321) (xy 375.630585 -81.778834) (xy 375.654257 -81.829331)
			(xy 375.670325 -81.882738) (xy 375.678445 -81.937914) (xy 375.678954 -81.9658) (xy 377.153422 -81.9658)
			(xy 377.157493 -81.910178) (xy 377.169619 -81.855741) (xy 377.189542 -81.80365) (xy 377.216838 -81.755015)
			(xy 377.250924 -81.710872) (xy 377.291073 -81.672163) (xy 377.336431 -81.639712) (xy 377.386031 -81.614211)
			(xy 377.438815 -81.596204) (xy 377.493658 -81.586074) (xy 377.549392 -81.584037) (xy 377.604829 -81.590137)
			(xy 377.658786 -81.604243) (xy 377.710115 -81.626055) (xy 377.757721 -81.655109) (xy 377.800589 -81.690784)
			(xy 377.837806 -81.732321) (xy 377.868579 -81.778834) (xy 377.892251 -81.829331) (xy 377.908319 -81.882738)
			(xy 377.916439 -81.937914) (xy 377.916948 -81.9658) (xy 379.501652 -81.9658) (xy 379.505723 -81.910178)
			(xy 379.517849 -81.855741) (xy 379.537772 -81.80365) (xy 379.565068 -81.755015) (xy 379.599154 -81.710872)
			(xy 379.639303 -81.672163) (xy 379.684661 -81.639712) (xy 379.734261 -81.614211) (xy 379.787045 -81.596204)
			(xy 379.841888 -81.586074) (xy 379.897622 -81.584037) (xy 379.953059 -81.590137) (xy 380.007016 -81.604243)
			(xy 380.058345 -81.626055) (xy 380.105951 -81.655109) (xy 380.148819 -81.690784) (xy 380.186036 -81.732321)
			(xy 380.216809 -81.778834) (xy 380.240481 -81.829331) (xy 380.256549 -81.882738) (xy 380.264669 -81.937914)
			(xy 380.265178 -81.9658) (xy 380.264669 -81.993686) (xy 380.256549 -82.048862) (xy 380.240481 -82.102269)
			(xy 380.216809 -82.152766) (xy 380.186036 -82.199279) (xy 380.148819 -82.240816) (xy 380.105951 -82.276491)
			(xy 380.058345 -82.305545) (xy 380.007016 -82.327357) (xy 379.953059 -82.341463) (xy 379.897622 -82.347563)
			(xy 379.841888 -82.345526) (xy 379.787045 -82.335396) (xy 379.734261 -82.317389) (xy 379.684661 -82.291888)
			(xy 379.639303 -82.259437) (xy 379.599154 -82.220728) (xy 379.565068 -82.176585) (xy 379.537772 -82.12795)
			(xy 379.517849 -82.075859) (xy 379.505723 -82.021422) (xy 379.501652 -81.9658) (xy 377.916948 -81.9658)
			(xy 377.916439 -81.993686) (xy 377.908319 -82.048862) (xy 377.892251 -82.102269) (xy 377.868579 -82.152766)
			(xy 377.837806 -82.199279) (xy 377.800589 -82.240816) (xy 377.757721 -82.276491) (xy 377.710115 -82.305545)
			(xy 377.658786 -82.327357) (xy 377.604829 -82.341463) (xy 377.549392 -82.347563) (xy 377.493658 -82.345526)
			(xy 377.438815 -82.335396) (xy 377.386031 -82.317389) (xy 377.336431 -82.291888) (xy 377.291073 -82.259437)
			(xy 377.250924 -82.220728) (xy 377.216838 -82.176585) (xy 377.189542 -82.12795) (xy 377.169619 -82.075859)
			(xy 377.157493 -82.021422) (xy 377.153422 -81.9658) (xy 375.678954 -81.9658) (xy 375.678445 -81.993686)
			(xy 375.670325 -82.048862) (xy 375.654257 -82.102269) (xy 375.630585 -82.152766) (xy 375.599812 -82.199279)
			(xy 375.562595 -82.240816) (xy 375.519727 -82.276491) (xy 375.472121 -82.305545) (xy 375.420792 -82.327357)
			(xy 375.366835 -82.341463) (xy 375.311398 -82.347563) (xy 375.255664 -82.345526) (xy 375.200821 -82.335396)
			(xy 375.148037 -82.317389) (xy 375.098437 -82.291888) (xy 375.053079 -82.259437) (xy 375.01293 -82.220728)
			(xy 374.978844 -82.176585) (xy 374.951548 -82.12795) (xy 374.931625 -82.075859) (xy 374.919499 -82.021422)
			(xy 374.915428 -81.9658) (xy 356.715935 -81.9658) (xy 356.714813 -81.973424) (xy 356.698745 -82.026831)
			(xy 356.675073 -82.077328) (xy 356.6443 -82.123841) (xy 356.607083 -82.165378) (xy 356.564215 -82.201053)
			(xy 356.516609 -82.230107) (xy 356.46528 -82.251919) (xy 356.411323 -82.266025) (xy 356.355886 -82.272125)
			(xy 356.300152 -82.270088) (xy 356.245309 -82.259958) (xy 356.192525 -82.241951) (xy 356.142925 -82.21645)
			(xy 356.097567 -82.183999) (xy 356.057418 -82.14529) (xy 356.023332 -82.101147) (xy 355.996036 -82.052512)
			(xy 355.976113 -82.000421) (xy 355.963987 -81.945984) (xy 355.959916 -81.890362) (xy 344.00871 -81.890362)
			(xy 344.762582 -82.644234) (xy 351.221292 -82.644234) (xy 351.225363 -82.588612) (xy 351.237489 -82.534175)
			(xy 351.257412 -82.482084) (xy 351.284708 -82.433449) (xy 351.318794 -82.389306) (xy 351.358943 -82.350597)
			(xy 351.404301 -82.318146) (xy 351.453901 -82.292645) (xy 351.506685 -82.274638) (xy 351.561528 -82.264508)
			(xy 351.617262 -82.262471) (xy 351.672699 -82.268571) (xy 351.726656 -82.282677) (xy 351.777985 -82.304489)
			(xy 351.825591 -82.333543) (xy 351.868459 -82.369218) (xy 351.905676 -82.410755) (xy 351.936449 -82.457268)
			(xy 351.960121 -82.507765) (xy 351.976189 -82.561172) (xy 351.984309 -82.616348) (xy 351.984818 -82.644234)
			(xy 351.984309 -82.67212) (xy 351.982507 -82.684366) (xy 354.092254 -82.684366) (xy 354.096325 -82.628744)
			(xy 354.108451 -82.574307) (xy 354.128374 -82.522216) (xy 354.15567 -82.473581) (xy 354.189756 -82.429438)
			(xy 354.229905 -82.390729) (xy 354.275263 -82.358278) (xy 354.324863 -82.332777) (xy 354.377647 -82.31477)
			(xy 354.43249 -82.30464) (xy 354.488224 -82.302603) (xy 354.543661 -82.308703) (xy 354.597618 -82.322809)
			(xy 354.648947 -82.344621) (xy 354.696553 -82.373675) (xy 354.739421 -82.40935) (xy 354.776638 -82.450887)
			(xy 354.807411 -82.4974) (xy 354.831083 -82.547897) (xy 354.847151 -82.601304) (xy 354.853095 -82.641694)
			(xy 363.896146 -82.641694) (xy 363.900217 -82.586072) (xy 363.912343 -82.531635) (xy 363.932266 -82.479544)
			(xy 363.959562 -82.430909) (xy 363.993648 -82.386766) (xy 364.033797 -82.348057) (xy 364.079155 -82.315606)
			(xy 364.128755 -82.290105) (xy 364.181539 -82.272098) (xy 364.236382 -82.261968) (xy 364.292116 -82.259931)
			(xy 364.347553 -82.266031) (xy 364.40151 -82.280137) (xy 364.452839 -82.301949) (xy 364.500445 -82.331003)
			(xy 364.543313 -82.366678) (xy 364.58053 -82.408215) (xy 364.611303 -82.454728) (xy 364.634975 -82.505225)
			(xy 364.651043 -82.558632) (xy 364.659163 -82.613808) (xy 364.659672 -82.641694) (xy 364.659163 -82.66958)
			(xy 364.651043 -82.724756) (xy 364.634975 -82.778163) (xy 364.611303 -82.82866) (xy 364.58053 -82.875173)
			(xy 364.543313 -82.91671) (xy 364.542013 -82.917792) (xy 367.650774 -82.917792) (xy 367.654845 -82.86217)
			(xy 367.666971 -82.807733) (xy 367.686894 -82.755642) (xy 367.71419 -82.707007) (xy 367.748276 -82.662864)
			(xy 367.788425 -82.624155) (xy 367.833783 -82.591704) (xy 367.883383 -82.566203) (xy 367.936167 -82.548196)
			(xy 367.99101 -82.538066) (xy 368.046744 -82.536029) (xy 368.102181 -82.542129) (xy 368.156138 -82.556235)
			(xy 368.207467 -82.578047) (xy 368.255073 -82.607101) (xy 368.296641 -82.641694) (xy 370.219222 -82.641694)
			(xy 370.223293 -82.586072) (xy 370.235419 -82.531635) (xy 370.255342 -82.479544) (xy 370.282638 -82.430909)
			(xy 370.316724 -82.386766) (xy 370.356873 -82.348057) (xy 370.402231 -82.315606) (xy 370.451831 -82.290105)
			(xy 370.504615 -82.272098) (xy 370.559458 -82.261968) (xy 370.615192 -82.259931) (xy 370.670629 -82.266031)
			(xy 370.724586 -82.280137) (xy 370.775915 -82.301949) (xy 370.823521 -82.331003) (xy 370.866389 -82.366678)
			(xy 370.903606 -82.408215) (xy 370.934379 -82.454728) (xy 370.958051 -82.505225) (xy 370.974119 -82.558632)
			(xy 370.982239 -82.613808) (xy 370.982748 -82.641694) (xy 370.982739 -82.642202) (xy 392.209526 -82.642202)
			(xy 392.213597 -82.58658) (xy 392.225723 -82.532143) (xy 392.245646 -82.480052) (xy 392.272942 -82.431417)
			(xy 392.307028 -82.387274) (xy 392.347177 -82.348565) (xy 392.392535 -82.316114) (xy 392.442135 -82.290613)
			(xy 392.494919 -82.272606) (xy 392.549762 -82.262476) (xy 392.605496 -82.260439) (xy 392.660933 -82.266539)
			(xy 392.71489 -82.280645) (xy 392.766219 -82.302457) (xy 392.813825 -82.331511) (xy 392.856693 -82.367186)
			(xy 392.89391 -82.408723) (xy 392.924683 -82.455236) (xy 392.948355 -82.505733) (xy 392.964423 -82.55914)
			(xy 392.972543 -82.614316) (xy 392.973052 -82.642202) (xy 396.84274 -82.642202) (xy 396.846811 -82.58658)
			(xy 396.858937 -82.532143) (xy 396.87886 -82.480052) (xy 396.906156 -82.431417) (xy 396.940242 -82.387274)
			(xy 396.980391 -82.348565) (xy 397.025749 -82.316114) (xy 397.075349 -82.290613) (xy 397.128133 -82.272606)
			(xy 397.182976 -82.262476) (xy 397.23871 -82.260439) (xy 397.294147 -82.266539) (xy 397.348104 -82.280645)
			(xy 397.399433 -82.302457) (xy 397.447039 -82.331511) (xy 397.489907 -82.367186) (xy 397.527124 -82.408723)
			(xy 397.557897 -82.455236) (xy 397.581569 -82.505733) (xy 397.597637 -82.55914) (xy 397.605757 -82.614316)
			(xy 397.606266 -82.642202) (xy 397.605757 -82.670088) (xy 397.597637 -82.725264) (xy 397.581569 -82.778671)
			(xy 397.557897 -82.829168) (xy 397.527124 -82.875681) (xy 397.489907 -82.917218) (xy 397.447039 -82.952893)
			(xy 397.399433 -82.981947) (xy 397.348104 -83.003759) (xy 397.294147 -83.017865) (xy 397.23871 -83.023965)
			(xy 397.182976 -83.021928) (xy 397.128133 -83.011798) (xy 397.075349 -82.993791) (xy 397.025749 -82.96829)
			(xy 396.980391 -82.935839) (xy 396.940242 -82.89713) (xy 396.906156 -82.852987) (xy 396.87886 -82.804352)
			(xy 396.858937 -82.752261) (xy 396.846811 -82.697824) (xy 396.84274 -82.642202) (xy 392.973052 -82.642202)
			(xy 392.972543 -82.670088) (xy 392.964423 -82.725264) (xy 392.948355 -82.778671) (xy 392.924683 -82.829168)
			(xy 392.89391 -82.875681) (xy 392.856693 -82.917218) (xy 392.813825 -82.952893) (xy 392.766219 -82.981947)
			(xy 392.71489 -83.003759) (xy 392.660933 -83.017865) (xy 392.605496 -83.023965) (xy 392.549762 -83.021928)
			(xy 392.494919 -83.011798) (xy 392.442135 -82.993791) (xy 392.392535 -82.96829) (xy 392.347177 -82.935839)
			(xy 392.307028 -82.89713) (xy 392.272942 -82.852987) (xy 392.245646 -82.804352) (xy 392.225723 -82.752261)
			(xy 392.213597 -82.697824) (xy 392.209526 -82.642202) (xy 370.982739 -82.642202) (xy 370.982239 -82.66958)
			(xy 370.974119 -82.724756) (xy 370.958051 -82.778163) (xy 370.934379 -82.82866) (xy 370.903606 -82.875173)
			(xy 370.866389 -82.91671) (xy 370.823521 -82.952385) (xy 370.775915 -82.981439) (xy 370.724586 -83.003251)
			(xy 370.670629 -83.017357) (xy 370.615192 -83.023457) (xy 370.559458 -83.02142) (xy 370.504615 -83.01129)
			(xy 370.451831 -82.993283) (xy 370.402231 -82.967782) (xy 370.356873 -82.935331) (xy 370.316724 -82.896622)
			(xy 370.282638 -82.852479) (xy 370.255342 -82.803844) (xy 370.235419 -82.751753) (xy 370.223293 -82.697316)
			(xy 370.219222 -82.641694) (xy 368.296641 -82.641694) (xy 368.297941 -82.642776) (xy 368.335158 -82.684313)
			(xy 368.365931 -82.730826) (xy 368.389603 -82.781323) (xy 368.405671 -82.83473) (xy 368.413791 -82.889906)
			(xy 368.4143 -82.917792) (xy 368.413791 -82.945678) (xy 368.405671 -83.000854) (xy 368.389603 -83.054261)
			(xy 368.365931 -83.104758) (xy 368.363257 -83.1088) (xy 374.915428 -83.1088) (xy 374.919499 -83.053178)
			(xy 374.931625 -82.998741) (xy 374.951548 -82.94665) (xy 374.978844 -82.898015) (xy 375.01293 -82.853872)
			(xy 375.053079 -82.815163) (xy 375.098437 -82.782712) (xy 375.148037 -82.757211) (xy 375.200821 -82.739204)
			(xy 375.255664 -82.729074) (xy 375.311398 -82.727037) (xy 375.366835 -82.733137) (xy 375.420792 -82.747243)
			(xy 375.472121 -82.769055) (xy 375.519727 -82.798109) (xy 375.562595 -82.833784) (xy 375.599812 -82.875321)
			(xy 375.630585 -82.921834) (xy 375.654257 -82.972331) (xy 375.670325 -83.025738) (xy 375.678445 -83.080914)
			(xy 375.678954 -83.1088) (xy 377.280422 -83.1088) (xy 377.284493 -83.053178) (xy 377.296619 -82.998741)
			(xy 377.316542 -82.94665) (xy 377.343838 -82.898015) (xy 377.377924 -82.853872) (xy 377.418073 -82.815163)
			(xy 377.463431 -82.782712) (xy 377.513031 -82.757211) (xy 377.565815 -82.739204) (xy 377.620658 -82.729074)
			(xy 377.676392 -82.727037) (xy 377.731829 -82.733137) (xy 377.785786 -82.747243) (xy 377.837115 -82.769055)
			(xy 377.884721 -82.798109) (xy 377.927589 -82.833784) (xy 377.964806 -82.875321) (xy 377.995579 -82.921834)
			(xy 378.019251 -82.972331) (xy 378.035319 -83.025738) (xy 378.043439 -83.080914) (xy 378.043948 -83.1088)
			(xy 378.043439 -83.136686) (xy 378.042422 -83.143598) (xy 394.215618 -83.143598) (xy 394.219689 -83.087976)
			(xy 394.231815 -83.033539) (xy 394.251738 -82.981448) (xy 394.279034 -82.932813) (xy 394.31312 -82.88867)
			(xy 394.353269 -82.849961) (xy 394.398627 -82.81751) (xy 394.448227 -82.792009) (xy 394.501011 -82.774002)
			(xy 394.555854 -82.763872) (xy 394.611588 -82.761835) (xy 394.667025 -82.767935) (xy 394.720982 -82.782041)
			(xy 394.772311 -82.803853) (xy 394.819917 -82.832907) (xy 394.862785 -82.868582) (xy 394.900002 -82.910119)
			(xy 394.930775 -82.956632) (xy 394.954447 -83.007129) (xy 394.970515 -83.060536) (xy 394.978635 -83.115712)
			(xy 394.979144 -83.143598) (xy 394.978635 -83.171484) (xy 394.970515 -83.22666) (xy 394.954447 -83.280067)
			(xy 394.930775 -83.330564) (xy 394.900002 -83.377077) (xy 394.862785 -83.418614) (xy 394.819917 -83.454289)
			(xy 394.772311 -83.483343) (xy 394.720982 -83.505155) (xy 394.667025 -83.519261) (xy 394.611588 -83.525361)
			(xy 394.555854 -83.523324) (xy 394.501011 -83.513194) (xy 394.448227 -83.495187) (xy 394.398627 -83.469686)
			(xy 394.353269 -83.437235) (xy 394.31312 -83.398526) (xy 394.279034 -83.354383) (xy 394.251738 -83.305748)
			(xy 394.231815 -83.253657) (xy 394.219689 -83.19922) (xy 394.215618 -83.143598) (xy 378.042422 -83.143598)
			(xy 378.035319 -83.191862) (xy 378.019251 -83.245269) (xy 377.995579 -83.295766) (xy 377.964806 -83.342279)
			(xy 377.927589 -83.383816) (xy 377.884721 -83.419491) (xy 377.837115 -83.448545) (xy 377.785786 -83.470357)
			(xy 377.731829 -83.484463) (xy 377.676392 -83.490563) (xy 377.620658 -83.488526) (xy 377.565815 -83.478396)
			(xy 377.513031 -83.460389) (xy 377.463431 -83.434888) (xy 377.418073 -83.402437) (xy 377.377924 -83.363728)
			(xy 377.343838 -83.319585) (xy 377.316542 -83.27095) (xy 377.296619 -83.218859) (xy 377.284493 -83.164422)
			(xy 377.280422 -83.1088) (xy 375.678954 -83.1088) (xy 375.678445 -83.136686) (xy 375.670325 -83.191862)
			(xy 375.654257 -83.245269) (xy 375.630585 -83.295766) (xy 375.599812 -83.342279) (xy 375.562595 -83.383816)
			(xy 375.519727 -83.419491) (xy 375.472121 -83.448545) (xy 375.420792 -83.470357) (xy 375.366835 -83.484463)
			(xy 375.311398 -83.490563) (xy 375.255664 -83.488526) (xy 375.200821 -83.478396) (xy 375.148037 -83.460389)
			(xy 375.098437 -83.434888) (xy 375.053079 -83.402437) (xy 375.01293 -83.363728) (xy 374.978844 -83.319585)
			(xy 374.951548 -83.27095) (xy 374.931625 -83.218859) (xy 374.919499 -83.164422) (xy 374.915428 -83.1088)
			(xy 368.363257 -83.1088) (xy 368.335158 -83.151271) (xy 368.297941 -83.192808) (xy 368.255073 -83.228483)
			(xy 368.207467 -83.257537) (xy 368.156138 -83.279349) (xy 368.102181 -83.293455) (xy 368.046744 -83.299555)
			(xy 367.99101 -83.297518) (xy 367.936167 -83.287388) (xy 367.883383 -83.269381) (xy 367.833783 -83.24388)
			(xy 367.788425 -83.211429) (xy 367.748276 -83.17272) (xy 367.71419 -83.128577) (xy 367.686894 -83.079942)
			(xy 367.666971 -83.027851) (xy 367.654845 -82.973414) (xy 367.650774 -82.917792) (xy 364.542013 -82.917792)
			(xy 364.500445 -82.952385) (xy 364.452839 -82.981439) (xy 364.40151 -83.003251) (xy 364.347553 -83.017357)
			(xy 364.292116 -83.023457) (xy 364.236382 -83.02142) (xy 364.181539 -83.01129) (xy 364.128755 -82.993283)
			(xy 364.079155 -82.967782) (xy 364.033797 -82.935331) (xy 363.993648 -82.896622) (xy 363.959562 -82.852479)
			(xy 363.932266 -82.803844) (xy 363.912343 -82.751753) (xy 363.900217 -82.697316) (xy 363.896146 -82.641694)
			(xy 354.853095 -82.641694) (xy 354.855271 -82.65648) (xy 354.85578 -82.684366) (xy 354.855271 -82.712252)
			(xy 354.847151 -82.767428) (xy 354.831083 -82.820835) (xy 354.807411 -82.871332) (xy 354.776638 -82.917845)
			(xy 354.739421 -82.959382) (xy 354.696553 -82.995057) (xy 354.648947 -83.024111) (xy 354.597618 -83.045923)
			(xy 354.543661 -83.060029) (xy 354.488224 -83.066129) (xy 354.43249 -83.064092) (xy 354.377647 -83.053962)
			(xy 354.324863 -83.035955) (xy 354.275263 -83.010454) (xy 354.229905 -82.978003) (xy 354.189756 -82.939294)
			(xy 354.15567 -82.895151) (xy 354.128374 -82.846516) (xy 354.108451 -82.794425) (xy 354.096325 -82.739988)
			(xy 354.092254 -82.684366) (xy 351.982507 -82.684366) (xy 351.976189 -82.727296) (xy 351.960121 -82.780703)
			(xy 351.936449 -82.8312) (xy 351.905676 -82.877713) (xy 351.868459 -82.91925) (xy 351.825591 -82.954925)
			(xy 351.777985 -82.983979) (xy 351.726656 -83.005791) (xy 351.672699 -83.019897) (xy 351.617262 -83.025997)
			(xy 351.561528 -83.02396) (xy 351.506685 -83.01383) (xy 351.453901 -82.995823) (xy 351.404301 -82.970322)
			(xy 351.358943 -82.937871) (xy 351.318794 -82.899162) (xy 351.284708 -82.855019) (xy 351.257412 -82.806384)
			(xy 351.237489 -82.754293) (xy 351.225363 -82.699856) (xy 351.221292 -82.644234) (xy 344.762582 -82.644234)
			(xy 345.328494 -83.210146) (xy 345.335334 -83.217547) (xy 345.343053 -83.236145) (xy 345.34348 -83.246214)
			(xy 345.34348 -84.144612) (xy 345.879928 -84.144612) (xy 345.879928 -83.281012) (xy 345.880418 -83.251028)
			(xy 345.888246 -83.191572) (xy 345.903767 -83.133647) (xy 345.926716 -83.078243) (xy 345.9567 -83.026309)
			(xy 345.993206 -82.978733) (xy 346.035611 -82.936328) (xy 346.083187 -82.899822) (xy 346.135121 -82.869838)
			(xy 346.190525 -82.846889) (xy 346.24845 -82.831368) (xy 346.307906 -82.82354) (xy 346.367874 -82.82354)
			(xy 346.42733 -82.831368) (xy 346.485255 -82.846889) (xy 346.540659 -82.869838) (xy 346.592593 -82.899822)
			(xy 346.640169 -82.936328) (xy 346.682574 -82.978733) (xy 346.71908 -83.026309) (xy 346.749064 -83.078243)
			(xy 346.772013 -83.133647) (xy 346.787534 -83.191572) (xy 346.795362 -83.251028) (xy 346.795852 -83.281012)
			(xy 346.795852 -83.787234) (xy 351.221292 -83.787234) (xy 351.225363 -83.731612) (xy 351.237489 -83.677175)
			(xy 351.257412 -83.625084) (xy 351.284708 -83.576449) (xy 351.318794 -83.532306) (xy 351.358943 -83.493597)
			(xy 351.404301 -83.461146) (xy 351.453901 -83.435645) (xy 351.506685 -83.417638) (xy 351.561528 -83.407508)
			(xy 351.617262 -83.405471) (xy 351.672699 -83.411571) (xy 351.726656 -83.425677) (xy 351.777985 -83.447489)
			(xy 351.825591 -83.476543) (xy 351.868459 -83.512218) (xy 351.905676 -83.553755) (xy 351.936449 -83.600268)
			(xy 351.960121 -83.650765) (xy 351.976189 -83.704172) (xy 351.984309 -83.759348) (xy 351.984818 -83.787234)
			(xy 351.984309 -83.81512) (xy 351.976189 -83.870296) (xy 351.960121 -83.923703) (xy 351.945747 -83.954366)
			(xy 354.132386 -83.954366) (xy 354.136457 -83.898744) (xy 354.148583 -83.844307) (xy 354.168506 -83.792216)
			(xy 354.195802 -83.743581) (xy 354.229888 -83.699438) (xy 354.270037 -83.660729) (xy 354.315395 -83.628278)
			(xy 354.364995 -83.602777) (xy 354.417779 -83.58477) (xy 354.472622 -83.57464) (xy 354.528356 -83.572603)
			(xy 354.583793 -83.578703) (xy 354.63775 -83.592809) (xy 354.689079 -83.614621) (xy 354.736685 -83.643675)
			(xy 354.779553 -83.67935) (xy 354.81677 -83.720887) (xy 354.847543 -83.7674) (xy 354.85565 -83.784694)
			(xy 365.080548 -83.784694) (xy 365.084619 -83.729072) (xy 365.096745 -83.674635) (xy 365.116668 -83.622544)
			(xy 365.143964 -83.573909) (xy 365.17805 -83.529766) (xy 365.218199 -83.491057) (xy 365.263557 -83.458606)
			(xy 365.313157 -83.433105) (xy 365.365941 -83.415098) (xy 365.420784 -83.404968) (xy 365.476518 -83.402931)
			(xy 365.531955 -83.409031) (xy 365.585912 -83.423137) (xy 365.637241 -83.444949) (xy 365.684847 -83.474003)
			(xy 365.727715 -83.509678) (xy 365.764932 -83.551215) (xy 365.795705 -83.597728) (xy 365.819377 -83.648225)
			(xy 365.835445 -83.701632) (xy 365.843565 -83.756808) (xy 365.844074 -83.784694) (xy 365.843565 -83.81258)
			(xy 365.835445 -83.867756) (xy 365.819377 -83.921163) (xy 365.795705 -83.97166) (xy 365.764932 -84.018173)
			(xy 365.727715 -84.05971) (xy 365.684847 -84.095385) (xy 365.637241 -84.124439) (xy 365.585912 -84.146251)
			(xy 365.531955 -84.160357) (xy 365.476518 -84.166457) (xy 365.420784 -84.16442) (xy 365.365941 -84.15429)
			(xy 365.313157 -84.136283) (xy 365.263557 -84.110782) (xy 365.218199 -84.078331) (xy 365.17805 -84.039622)
			(xy 365.143964 -83.995479) (xy 365.116668 -83.946844) (xy 365.096745 -83.894753) (xy 365.084619 -83.840316)
			(xy 365.080548 -83.784694) (xy 354.85565 -83.784694) (xy 354.871215 -83.817897) (xy 354.887283 -83.871304)
			(xy 354.895403 -83.92648) (xy 354.895912 -83.954366) (xy 354.895403 -83.982252) (xy 354.887283 -84.037428)
			(xy 354.871215 -84.090835) (xy 354.847543 -84.141332) (xy 354.81677 -84.187845) (xy 354.779553 -84.229382)
			(xy 354.736685 -84.265057) (xy 354.689079 -84.294111) (xy 354.63775 -84.315923) (xy 354.583793 -84.330029)
			(xy 354.528356 -84.336129) (xy 354.472622 -84.334092) (xy 354.417779 -84.323962) (xy 354.364995 -84.305955)
			(xy 354.315395 -84.280454) (xy 354.270037 -84.248003) (xy 354.229888 -84.209294) (xy 354.195802 -84.165151)
			(xy 354.168506 -84.116516) (xy 354.148583 -84.064425) (xy 354.136457 -84.009988) (xy 354.132386 -83.954366)
			(xy 351.945747 -83.954366) (xy 351.936449 -83.9742) (xy 351.905676 -84.020713) (xy 351.868459 -84.06225)
			(xy 351.825591 -84.097925) (xy 351.777985 -84.126979) (xy 351.726656 -84.148791) (xy 351.672699 -84.162897)
			(xy 351.617262 -84.168997) (xy 351.561528 -84.16696) (xy 351.506685 -84.15683) (xy 351.453901 -84.138823)
			(xy 351.404301 -84.113322) (xy 351.358943 -84.080871) (xy 351.318794 -84.042162) (xy 351.284708 -83.998019)
			(xy 351.257412 -83.949384) (xy 351.237489 -83.897293) (xy 351.225363 -83.842856) (xy 351.221292 -83.787234)
			(xy 346.795852 -83.787234) (xy 346.795852 -84.144612) (xy 346.795362 -84.174596) (xy 346.787534 -84.234052)
			(xy 346.772013 -84.291977) (xy 346.749064 -84.347381) (xy 346.71908 -84.399315) (xy 346.682574 -84.446891)
			(xy 346.640169 -84.489296) (xy 346.592593 -84.525802) (xy 346.540659 -84.555786) (xy 346.485255 -84.578735)
			(xy 346.42733 -84.594256) (xy 346.367874 -84.602084) (xy 346.307906 -84.602084) (xy 346.24845 -84.594256)
			(xy 346.190525 -84.578735) (xy 346.135121 -84.555786) (xy 346.083187 -84.525802) (xy 346.035611 -84.489296)
			(xy 345.993206 -84.446891) (xy 345.9567 -84.399315) (xy 345.926716 -84.347381) (xy 345.903767 -84.291977)
			(xy 345.888246 -84.234052) (xy 345.880418 -84.174596) (xy 345.879928 -84.144612) (xy 345.34348 -84.144612)
			(xy 345.34348 -84.283042) (xy 345.344242 -84.287614) (xy 345.34862 -84.313427) (xy 345.353323 -84.365575)
			(xy 345.35364 -84.391754) (xy 345.35364 -86.144608) (xy 346.641928 -86.144608) (xy 346.641928 -85.281008)
			(xy 346.642418 -85.251024) (xy 346.650246 -85.191568) (xy 346.665767 -85.133643) (xy 346.688716 -85.078239)
			(xy 346.7187 -85.026305) (xy 346.755206 -84.978729) (xy 346.797611 -84.936324) (xy 346.845187 -84.899818)
			(xy 346.897121 -84.869834) (xy 346.952525 -84.846885) (xy 347.01045 -84.831364) (xy 347.069906 -84.823536)
			(xy 347.129874 -84.823536) (xy 347.18933 -84.831364) (xy 347.247255 -84.846885) (xy 347.302659 -84.869834)
			(xy 347.354593 -84.899818) (xy 347.394232 -84.930234) (xy 351.221292 -84.930234) (xy 351.225363 -84.874612)
			(xy 351.237489 -84.820175) (xy 351.257412 -84.768084) (xy 351.284708 -84.719449) (xy 351.318794 -84.675306)
			(xy 351.358943 -84.636597) (xy 351.404301 -84.604146) (xy 351.453901 -84.578645) (xy 351.506685 -84.560638)
			(xy 351.561528 -84.550508) (xy 351.617262 -84.548471) (xy 351.672699 -84.554571) (xy 351.726656 -84.568677)
			(xy 351.777985 -84.590489) (xy 351.825591 -84.619543) (xy 351.868459 -84.655218) (xy 351.905676 -84.696755)
			(xy 351.936449 -84.743268) (xy 351.960121 -84.793765) (xy 351.976189 -84.847172) (xy 351.984309 -84.902348)
			(xy 351.984818 -84.930234) (xy 351.984309 -84.95812) (xy 351.976189 -85.013296) (xy 351.960121 -85.066703)
			(xy 351.936449 -85.1172) (xy 351.905676 -85.163713) (xy 351.868459 -85.20525) (xy 351.845489 -85.224366)
			(xy 354.134926 -85.224366) (xy 354.138997 -85.168744) (xy 354.151123 -85.114307) (xy 354.171046 -85.062216)
			(xy 354.198342 -85.013581) (xy 354.232428 -84.969438) (xy 354.272577 -84.930729) (xy 354.317935 -84.898278)
			(xy 354.367535 -84.872777) (xy 354.420319 -84.85477) (xy 354.475162 -84.84464) (xy 354.530896 -84.842603)
			(xy 354.586333 -84.848703) (xy 354.64029 -84.862809) (xy 354.645342 -84.864956) (xy 363.863634 -84.864956)
			(xy 363.867705 -84.809334) (xy 363.879831 -84.754897) (xy 363.899754 -84.702806) (xy 363.92705 -84.654171)
			(xy 363.961136 -84.610028) (xy 364.001285 -84.571319) (xy 364.046643 -84.538868) (xy 364.096243 -84.513367)
			(xy 364.149027 -84.49536) (xy 364.20387 -84.48523) (xy 364.259604 -84.483193) (xy 364.315041 -84.489293)
			(xy 364.368998 -84.503399) (xy 364.420327 -84.525211) (xy 364.467933 -84.554265) (xy 364.473791 -84.55914)
			(xy 367.596928 -84.55914) (xy 367.59742 -84.530678) (xy 367.605878 -84.474387) (xy 367.622614 -84.419979)
			(xy 367.647253 -84.368664) (xy 367.67925 -84.321584) (xy 367.717891 -84.279786) (xy 367.762318 -84.244198)
			(xy 367.786666 -84.229448) (xy 367.798256 -84.22222) (xy 367.817381 -84.202733) (xy 367.830658 -84.178874)
			(xy 367.837138 -84.152349) (xy 367.836356 -84.125056) (xy 367.828369 -84.098945) (xy 367.813747 -84.075885)
			(xy 367.803938 -84.06638) (xy 367.784723 -84.048244) (xy 367.751006 -84.007563) (xy 367.723225 -83.962618)
			(xy 367.70191 -83.914271) (xy 367.68747 -83.863445) (xy 367.68018 -83.811113) (xy 367.679732 -83.784694)
			(xy 367.680218 -83.757443) (xy 367.687974 -83.703495) (xy 367.703329 -83.6512) (xy 367.725971 -83.601623)
			(xy 367.755437 -83.555773) (xy 367.791128 -83.514582) (xy 367.832319 -83.478891) (xy 367.878169 -83.449425)
			(xy 367.927746 -83.426783) (xy 367.980041 -83.411428) (xy 368.033989 -83.403672) (xy 368.088491 -83.403672)
			(xy 368.142439 -83.411428) (xy 368.194734 -83.426783) (xy 368.244311 -83.449425) (xy 368.290161 -83.478891)
			(xy 368.331352 -83.514582) (xy 368.367043 -83.555773) (xy 368.396509 -83.601623) (xy 368.419151 -83.6512)
			(xy 368.434506 -83.703495) (xy 368.442262 -83.757443) (xy 368.442748 -83.784694) (xy 370.219222 -83.784694)
			(xy 370.223293 -83.729072) (xy 370.235419 -83.674635) (xy 370.255342 -83.622544) (xy 370.282638 -83.573909)
			(xy 370.316724 -83.529766) (xy 370.356873 -83.491057) (xy 370.402231 -83.458606) (xy 370.451831 -83.433105)
			(xy 370.504615 -83.415098) (xy 370.559458 -83.404968) (xy 370.615192 -83.402931) (xy 370.670629 -83.409031)
			(xy 370.724586 -83.423137) (xy 370.775915 -83.444949) (xy 370.823521 -83.474003) (xy 370.866389 -83.509678)
			(xy 370.903606 -83.551215) (xy 370.934379 -83.597728) (xy 370.958051 -83.648225) (xy 370.974119 -83.701632)
			(xy 370.982239 -83.756808) (xy 370.982748 -83.784694) (xy 370.982239 -83.81258) (xy 370.974119 -83.867756)
			(xy 370.958051 -83.921163) (xy 370.934379 -83.97166) (xy 370.903606 -84.018173) (xy 370.866389 -84.05971)
			(xy 370.823521 -84.095385) (xy 370.775915 -84.124439) (xy 370.724586 -84.146251) (xy 370.670629 -84.160357)
			(xy 370.615192 -84.166457) (xy 370.559458 -84.16442) (xy 370.504615 -84.15429) (xy 370.451831 -84.136283)
			(xy 370.402231 -84.110782) (xy 370.356873 -84.078331) (xy 370.316724 -84.039622) (xy 370.282638 -83.995479)
			(xy 370.255342 -83.946844) (xy 370.235419 -83.894753) (xy 370.223293 -83.840316) (xy 370.219222 -83.784694)
			(xy 368.442748 -83.784694) (xy 368.442216 -83.813155) (xy 368.433766 -83.869445) (xy 368.417039 -83.923852)
			(xy 368.392406 -83.975167) (xy 368.360416 -84.022248) (xy 368.321779 -84.064048) (xy 368.277356 -84.099636)
			(xy 368.25301 -84.114386) (xy 368.24139 -84.121569) (xy 368.222267 -84.141067) (xy 368.208993 -84.164935)
			(xy 368.202519 -84.191468) (xy 368.203306 -84.218768) (xy 368.211299 -84.244883) (xy 368.215685 -84.2518)
			(xy 374.915428 -84.2518) (xy 374.919499 -84.196178) (xy 374.931625 -84.141741) (xy 374.951548 -84.08965)
			(xy 374.978844 -84.041015) (xy 375.01293 -83.996872) (xy 375.053079 -83.958163) (xy 375.098437 -83.925712)
			(xy 375.148037 -83.900211) (xy 375.200821 -83.882204) (xy 375.255664 -83.872074) (xy 375.311398 -83.870037)
			(xy 375.366835 -83.876137) (xy 375.420792 -83.890243) (xy 375.472121 -83.912055) (xy 375.519727 -83.941109)
			(xy 375.562595 -83.976784) (xy 375.599812 -84.018321) (xy 375.630585 -84.064834) (xy 375.654257 -84.115331)
			(xy 375.662608 -84.143088) (xy 377.35459 -84.143088) (xy 377.358661 -84.087466) (xy 377.370787 -84.033029)
			(xy 377.39071 -83.980938) (xy 377.418006 -83.932303) (xy 377.452092 -83.88816) (xy 377.492241 -83.849451)
			(xy 377.537599 -83.817) (xy 377.587199 -83.791499) (xy 377.639983 -83.773492) (xy 377.694826 -83.763362)
			(xy 377.75056 -83.761325) (xy 377.805997 -83.767425) (xy 377.859954 -83.781531) (xy 377.911283 -83.803343)
			(xy 377.948565 -83.826096) (xy 380.785368 -83.826096) (xy 380.789439 -83.770474) (xy 380.801565 -83.716037)
			(xy 380.821488 -83.663946) (xy 380.848784 -83.615311) (xy 380.88287 -83.571168) (xy 380.923019 -83.532459)
			(xy 380.968377 -83.500008) (xy 381.017977 -83.474507) (xy 381.070761 -83.4565) (xy 381.125604 -83.44637)
			(xy 381.181338 -83.444333) (xy 381.236775 -83.450433) (xy 381.290732 -83.464539) (xy 381.342061 -83.486351)
			(xy 381.389667 -83.515405) (xy 381.432535 -83.55108) (xy 381.469752 -83.592617) (xy 381.500525 -83.63913)
			(xy 381.524197 -83.689627) (xy 381.540265 -83.743034) (xy 381.546471 -83.785202) (xy 391.48842 -83.785202)
			(xy 391.492491 -83.72958) (xy 391.504617 -83.675143) (xy 391.52454 -83.623052) (xy 391.551836 -83.574417)
			(xy 391.585922 -83.530274) (xy 391.626071 -83.491565) (xy 391.671429 -83.459114) (xy 391.721029 -83.433613)
			(xy 391.773813 -83.415606) (xy 391.828656 -83.405476) (xy 391.88439 -83.403439) (xy 391.939827 -83.409539)
			(xy 391.993784 -83.423645) (xy 392.045113 -83.445457) (xy 392.092719 -83.474511) (xy 392.135587 -83.510186)
			(xy 392.172804 -83.551723) (xy 392.203577 -83.598236) (xy 392.227249 -83.648733) (xy 392.243317 -83.70214)
			(xy 392.251437 -83.757316) (xy 392.251946 -83.785202) (xy 396.84274 -83.785202) (xy 396.846811 -83.72958)
			(xy 396.858937 -83.675143) (xy 396.87886 -83.623052) (xy 396.906156 -83.574417) (xy 396.940242 -83.530274)
			(xy 396.980391 -83.491565) (xy 397.025749 -83.459114) (xy 397.075349 -83.433613) (xy 397.128133 -83.415606)
			(xy 397.182976 -83.405476) (xy 397.23871 -83.403439) (xy 397.294147 -83.409539) (xy 397.348104 -83.423645)
			(xy 397.399433 -83.445457) (xy 397.447039 -83.474511) (xy 397.489907 -83.510186) (xy 397.527124 -83.551723)
			(xy 397.557897 -83.598236) (xy 397.581569 -83.648733) (xy 397.597637 -83.70214) (xy 397.605757 -83.757316)
			(xy 397.606266 -83.785202) (xy 397.605757 -83.813088) (xy 397.597637 -83.868264) (xy 397.581569 -83.921671)
			(xy 397.557897 -83.972168) (xy 397.527124 -84.018681) (xy 397.489907 -84.060218) (xy 397.447039 -84.095893)
			(xy 397.399433 -84.124947) (xy 397.348104 -84.146759) (xy 397.294147 -84.160865) (xy 397.23871 -84.166965)
			(xy 397.182976 -84.164928) (xy 397.128133 -84.154798) (xy 397.075349 -84.136791) (xy 397.025749 -84.11129)
			(xy 396.980391 -84.078839) (xy 396.940242 -84.04013) (xy 396.906156 -83.995987) (xy 396.87886 -83.947352)
			(xy 396.858937 -83.895261) (xy 396.846811 -83.840824) (xy 396.84274 -83.785202) (xy 392.251946 -83.785202)
			(xy 392.251437 -83.813088) (xy 392.243317 -83.868264) (xy 392.227249 -83.921671) (xy 392.203577 -83.972168)
			(xy 392.172804 -84.018681) (xy 392.135587 -84.060218) (xy 392.092719 -84.095893) (xy 392.045113 -84.124947)
			(xy 391.993784 -84.146759) (xy 391.939827 -84.160865) (xy 391.88439 -84.166965) (xy 391.828656 -84.164928)
			(xy 391.773813 -84.154798) (xy 391.721029 -84.136791) (xy 391.671429 -84.11129) (xy 391.626071 -84.078839)
			(xy 391.585922 -84.04013) (xy 391.551836 -83.995987) (xy 391.52454 -83.947352) (xy 391.504617 -83.895261)
			(xy 391.492491 -83.840824) (xy 391.48842 -83.785202) (xy 381.546471 -83.785202) (xy 381.548385 -83.79821)
			(xy 381.548894 -83.826096) (xy 381.548385 -83.853982) (xy 381.540265 -83.909158) (xy 381.524197 -83.962565)
			(xy 381.500525 -84.013062) (xy 381.469752 -84.059575) (xy 381.432535 -84.101112) (xy 381.389667 -84.136787)
			(xy 381.342061 -84.165841) (xy 381.290732 -84.187653) (xy 381.236775 -84.201759) (xy 381.181338 -84.207859)
			(xy 381.125604 -84.205822) (xy 381.070761 -84.195692) (xy 381.017977 -84.177685) (xy 380.968377 -84.152184)
			(xy 380.923019 -84.119733) (xy 380.88287 -84.081024) (xy 380.848784 -84.036881) (xy 380.821488 -83.988246)
			(xy 380.801565 -83.936155) (xy 380.789439 -83.881718) (xy 380.785368 -83.826096) (xy 377.948565 -83.826096)
			(xy 377.958889 -83.832397) (xy 378.001757 -83.868072) (xy 378.038974 -83.909609) (xy 378.069747 -83.956122)
			(xy 378.093419 -84.006619) (xy 378.109487 -84.060026) (xy 378.117607 -84.115202) (xy 378.118116 -84.143088)
			(xy 378.117607 -84.170974) (xy 378.109487 -84.22615) (xy 378.093419 -84.279557) (xy 378.069747 -84.330054)
			(xy 378.038974 -84.376567) (xy 378.001757 -84.418104) (xy 377.958889 -84.453779) (xy 377.942738 -84.463636)
			(xy 379.522988 -84.463636) (xy 379.527059 -84.408014) (xy 379.539185 -84.353577) (xy 379.559108 -84.301486)
			(xy 379.586404 -84.252851) (xy 379.62049 -84.208708) (xy 379.660639 -84.169999) (xy 379.705997 -84.137548)
			(xy 379.755597 -84.112047) (xy 379.808381 -84.09404) (xy 379.863224 -84.08391) (xy 379.918958 -84.081873)
			(xy 379.974395 -84.087973) (xy 380.028352 -84.102079) (xy 380.079681 -84.123891) (xy 380.127287 -84.152945)
			(xy 380.170155 -84.18862) (xy 380.207372 -84.230157) (xy 380.238145 -84.27667) (xy 380.238155 -84.276692)
			(xy 394.311122 -84.276692) (xy 394.315193 -84.22107) (xy 394.327319 -84.166633) (xy 394.347242 -84.114542)
			(xy 394.374538 -84.065907) (xy 394.408624 -84.021764) (xy 394.448773 -83.983055) (xy 394.494131 -83.950604)
			(xy 394.543731 -83.925103) (xy 394.596515 -83.907096) (xy 394.651358 -83.896966) (xy 394.707092 -83.894929)
			(xy 394.762529 -83.901029) (xy 394.816486 -83.915135) (xy 394.867815 -83.936947) (xy 394.915421 -83.966001)
			(xy 394.958289 -84.001676) (xy 394.995506 -84.043213) (xy 395.026279 -84.089726) (xy 395.049951 -84.140223)
			(xy 395.066019 -84.19363) (xy 395.074139 -84.248806) (xy 395.074648 -84.276692) (xy 395.074139 -84.304578)
			(xy 395.066019 -84.359754) (xy 395.049951 -84.413161) (xy 395.026279 -84.463658) (xy 394.995506 -84.510171)
			(xy 394.958289 -84.551708) (xy 394.915421 -84.587383) (xy 394.867815 -84.616437) (xy 394.816486 -84.638249)
			(xy 394.762529 -84.652355) (xy 394.707092 -84.658455) (xy 394.651358 -84.656418) (xy 394.596515 -84.646288)
			(xy 394.543731 -84.628281) (xy 394.494131 -84.60278) (xy 394.448773 -84.570329) (xy 394.408624 -84.53162)
			(xy 394.374538 -84.487477) (xy 394.347242 -84.438842) (xy 394.327319 -84.386751) (xy 394.315193 -84.332314)
			(xy 394.311122 -84.276692) (xy 380.238155 -84.276692) (xy 380.261817 -84.327167) (xy 380.277885 -84.380574)
			(xy 380.286005 -84.43575) (xy 380.286514 -84.463636) (xy 380.286005 -84.491522) (xy 380.277885 -84.546698)
			(xy 380.261817 -84.600105) (xy 380.238145 -84.650602) (xy 380.207372 -84.697115) (xy 380.170155 -84.738652)
			(xy 380.127287 -84.774327) (xy 380.079681 -84.803381) (xy 380.028352 -84.825193) (xy 379.974395 -84.839299)
			(xy 379.918958 -84.845399) (xy 379.863224 -84.843362) (xy 379.808381 -84.833232) (xy 379.755597 -84.815225)
			(xy 379.705997 -84.789724) (xy 379.660639 -84.757273) (xy 379.62049 -84.718564) (xy 379.586404 -84.674421)
			(xy 379.559108 -84.625786) (xy 379.539185 -84.573695) (xy 379.527059 -84.519258) (xy 379.522988 -84.463636)
			(xy 377.942738 -84.463636) (xy 377.911283 -84.482833) (xy 377.859954 -84.504645) (xy 377.805997 -84.518751)
			(xy 377.75056 -84.524851) (xy 377.694826 -84.522814) (xy 377.639983 -84.512684) (xy 377.587199 -84.494677)
			(xy 377.537599 -84.469176) (xy 377.492241 -84.436725) (xy 377.452092 -84.398016) (xy 377.418006 -84.353873)
			(xy 377.39071 -84.305238) (xy 377.370787 -84.253147) (xy 377.358661 -84.19871) (xy 377.35459 -84.143088)
			(xy 375.662608 -84.143088) (xy 375.670325 -84.168738) (xy 375.678445 -84.223914) (xy 375.678954 -84.2518)
			(xy 375.678445 -84.279686) (xy 375.670325 -84.334862) (xy 375.654257 -84.388269) (xy 375.630585 -84.438766)
			(xy 375.599812 -84.485279) (xy 375.562595 -84.526816) (xy 375.519727 -84.562491) (xy 375.472121 -84.591545)
			(xy 375.420792 -84.613357) (xy 375.366835 -84.627463) (xy 375.311398 -84.633563) (xy 375.255664 -84.631526)
			(xy 375.200821 -84.621396) (xy 375.148037 -84.603389) (xy 375.098437 -84.577888) (xy 375.053079 -84.545437)
			(xy 375.01293 -84.506728) (xy 374.978844 -84.462585) (xy 374.951548 -84.41395) (xy 374.931625 -84.361859)
			(xy 374.919499 -84.307422) (xy 374.915428 -84.2518) (xy 368.215685 -84.2518) (xy 368.225925 -84.267947)
			(xy 368.235738 -84.277454) (xy 368.254965 -84.295578) (xy 368.288682 -84.336262) (xy 368.316462 -84.381208)
			(xy 368.337775 -84.429558) (xy 368.352213 -84.480386) (xy 368.359498 -84.53272) (xy 368.359944 -84.55914)
			(xy 368.359458 -84.586391) (xy 368.351702 -84.640339) (xy 368.336347 -84.692634) (xy 368.313705 -84.742211)
			(xy 368.284239 -84.788061) (xy 368.248548 -84.829252) (xy 368.207357 -84.864943) (xy 368.161507 -84.894409)
			(xy 368.11193 -84.917051) (xy 368.075683 -84.927694) (xy 370.219222 -84.927694) (xy 370.223293 -84.872072)
			(xy 370.235419 -84.817635) (xy 370.255342 -84.765544) (xy 370.282638 -84.716909) (xy 370.316724 -84.672766)
			(xy 370.356873 -84.634057) (xy 370.402231 -84.601606) (xy 370.451831 -84.576105) (xy 370.504615 -84.558098)
			(xy 370.559458 -84.547968) (xy 370.615192 -84.545931) (xy 370.670629 -84.552031) (xy 370.724586 -84.566137)
			(xy 370.775915 -84.587949) (xy 370.823521 -84.617003) (xy 370.866389 -84.652678) (xy 370.903606 -84.694215)
			(xy 370.934379 -84.740728) (xy 370.958051 -84.791225) (xy 370.974119 -84.844632) (xy 370.982239 -84.899808)
			(xy 370.982748 -84.927694) (xy 370.982739 -84.928202) (xy 392.262866 -84.928202) (xy 392.266937 -84.87258)
			(xy 392.279063 -84.818143) (xy 392.298986 -84.766052) (xy 392.326282 -84.717417) (xy 392.360368 -84.673274)
			(xy 392.400517 -84.634565) (xy 392.445875 -84.602114) (xy 392.495475 -84.576613) (xy 392.548259 -84.558606)
			(xy 392.603102 -84.548476) (xy 392.658836 -84.546439) (xy 392.714273 -84.552539) (xy 392.76823 -84.566645)
			(xy 392.819559 -84.588457) (xy 392.867165 -84.617511) (xy 392.910033 -84.653186) (xy 392.94725 -84.694723)
			(xy 392.978023 -84.741236) (xy 393.001695 -84.791733) (xy 393.017763 -84.84514) (xy 393.025883 -84.900316)
			(xy 393.026392 -84.928202) (xy 396.84274 -84.928202) (xy 396.846811 -84.87258) (xy 396.858937 -84.818143)
			(xy 396.87886 -84.766052) (xy 396.906156 -84.717417) (xy 396.940242 -84.673274) (xy 396.980391 -84.634565)
			(xy 397.025749 -84.602114) (xy 397.075349 -84.576613) (xy 397.128133 -84.558606) (xy 397.182976 -84.548476)
			(xy 397.23871 -84.546439) (xy 397.294147 -84.552539) (xy 397.348104 -84.566645) (xy 397.399433 -84.588457)
			(xy 397.447039 -84.617511) (xy 397.489907 -84.653186) (xy 397.527124 -84.694723) (xy 397.544804 -84.721446)
			(xy 399.610832 -84.721446) (xy 399.614903 -84.665824) (xy 399.627029 -84.611387) (xy 399.646952 -84.559296)
			(xy 399.674248 -84.510661) (xy 399.708334 -84.466518) (xy 399.748483 -84.427809) (xy 399.793841 -84.395358)
			(xy 399.843441 -84.369857) (xy 399.896225 -84.35185) (xy 399.951068 -84.34172) (xy 400.006802 -84.339683)
			(xy 400.062239 -84.345783) (xy 400.116196 -84.359889) (xy 400.167525 -84.381701) (xy 400.215131 -84.410755)
			(xy 400.257999 -84.44643) (xy 400.295216 -84.487967) (xy 400.325989 -84.53448) (xy 400.349661 -84.584977)
			(xy 400.365729 -84.638384) (xy 400.373849 -84.69356) (xy 400.374358 -84.721446) (xy 400.373849 -84.749332)
			(xy 400.365729 -84.804508) (xy 400.349661 -84.857915) (xy 400.325989 -84.908412) (xy 400.295216 -84.954925)
			(xy 400.257999 -84.996462) (xy 400.215131 -85.032137) (xy 400.167525 -85.061191) (xy 400.116196 -85.083003)
			(xy 400.062239 -85.097109) (xy 400.006802 -85.103209) (xy 399.951068 -85.101172) (xy 399.896225 -85.091042)
			(xy 399.843441 -85.073035) (xy 399.793841 -85.047534) (xy 399.748483 -85.015083) (xy 399.708334 -84.976374)
			(xy 399.674248 -84.932231) (xy 399.646952 -84.883596) (xy 399.627029 -84.831505) (xy 399.614903 -84.777068)
			(xy 399.610832 -84.721446) (xy 397.544804 -84.721446) (xy 397.557897 -84.741236) (xy 397.581569 -84.791733)
			(xy 397.597637 -84.84514) (xy 397.605757 -84.900316) (xy 397.606266 -84.928202) (xy 397.605757 -84.956088)
			(xy 397.597637 -85.011264) (xy 397.581569 -85.064671) (xy 397.557897 -85.115168) (xy 397.527124 -85.161681)
			(xy 397.489907 -85.203218) (xy 397.447039 -85.238893) (xy 397.399433 -85.267947) (xy 397.348104 -85.289759)
			(xy 397.294147 -85.303865) (xy 397.23871 -85.309965) (xy 397.182976 -85.307928) (xy 397.128133 -85.297798)
			(xy 397.075349 -85.279791) (xy 397.025749 -85.25429) (xy 396.980391 -85.221839) (xy 396.940242 -85.18313)
			(xy 396.906156 -85.138987) (xy 396.87886 -85.090352) (xy 396.858937 -85.038261) (xy 396.846811 -84.983824)
			(xy 396.84274 -84.928202) (xy 393.026392 -84.928202) (xy 393.025883 -84.956088) (xy 393.017763 -85.011264)
			(xy 393.001695 -85.064671) (xy 392.978023 -85.115168) (xy 392.94725 -85.161681) (xy 392.910033 -85.203218)
			(xy 392.867165 -85.238893) (xy 392.819559 -85.267947) (xy 392.76823 -85.289759) (xy 392.714273 -85.303865)
			(xy 392.658836 -85.309965) (xy 392.603102 -85.307928) (xy 392.548259 -85.297798) (xy 392.495475 -85.279791)
			(xy 392.445875 -85.25429) (xy 392.400517 -85.221839) (xy 392.360368 -85.18313) (xy 392.326282 -85.138987)
			(xy 392.298986 -85.090352) (xy 392.279063 -85.038261) (xy 392.266937 -84.983824) (xy 392.262866 -84.928202)
			(xy 370.982739 -84.928202) (xy 370.982239 -84.95558) (xy 370.974119 -85.010756) (xy 370.958051 -85.064163)
			(xy 370.934379 -85.11466) (xy 370.903606 -85.161173) (xy 370.866389 -85.20271) (xy 370.823521 -85.238385)
			(xy 370.775915 -85.267439) (xy 370.724586 -85.289251) (xy 370.670629 -85.303357) (xy 370.615192 -85.309457)
			(xy 370.559458 -85.30742) (xy 370.504615 -85.29729) (xy 370.451831 -85.279283) (xy 370.402231 -85.253782)
			(xy 370.356873 -85.221331) (xy 370.316724 -85.182622) (xy 370.282638 -85.138479) (xy 370.255342 -85.089844)
			(xy 370.235419 -85.037753) (xy 370.223293 -84.983316) (xy 370.219222 -84.927694) (xy 368.075683 -84.927694)
			(xy 368.059635 -84.932406) (xy 368.005687 -84.940162) (xy 367.951185 -84.940162) (xy 367.897237 -84.932406)
			(xy 367.844942 -84.917051) (xy 367.795365 -84.894409) (xy 367.749515 -84.864943) (xy 367.708324 -84.829252)
			(xy 367.672633 -84.788061) (xy 367.643167 -84.742211) (xy 367.620525 -84.692634) (xy 367.60517 -84.640339)
			(xy 367.597414 -84.586391) (xy 367.596928 -84.55914) (xy 364.473791 -84.55914) (xy 364.510801 -84.58994)
			(xy 364.548018 -84.631477) (xy 364.578791 -84.67799) (xy 364.602463 -84.728487) (xy 364.618531 -84.781894)
			(xy 364.626651 -84.83707) (xy 364.62716 -84.864956) (xy 364.626651 -84.892842) (xy 364.618531 -84.948018)
			(xy 364.602463 -85.001425) (xy 364.578791 -85.051922) (xy 364.548018 -85.098435) (xy 364.510801 -85.139972)
			(xy 364.467933 -85.175647) (xy 364.420327 -85.204701) (xy 364.368998 -85.226513) (xy 364.315041 -85.240619)
			(xy 364.259604 -85.246719) (xy 364.20387 -85.244682) (xy 364.149027 -85.234552) (xy 364.096243 -85.216545)
			(xy 364.046643 -85.191044) (xy 364.001285 -85.158593) (xy 363.961136 -85.119884) (xy 363.92705 -85.075741)
			(xy 363.899754 -85.027106) (xy 363.879831 -84.975015) (xy 363.867705 -84.920578) (xy 363.863634 -84.864956)
			(xy 354.645342 -84.864956) (xy 354.691619 -84.884621) (xy 354.739225 -84.913675) (xy 354.782093 -84.94935)
			(xy 354.81931 -84.990887) (xy 354.850083 -85.0374) (xy 354.873755 -85.087897) (xy 354.889823 -85.141304)
			(xy 354.897943 -85.19648) (xy 354.898452 -85.224366) (xy 354.897943 -85.252252) (xy 354.889823 -85.307428)
			(xy 354.873755 -85.360835) (xy 354.850083 -85.411332) (xy 354.81931 -85.457845) (xy 354.782093 -85.499382)
			(xy 354.763396 -85.514942) (xy 365.30483 -85.514942) (xy 365.308901 -85.45932) (xy 365.321027 -85.404883)
			(xy 365.34095 -85.352792) (xy 365.368246 -85.304157) (xy 365.402332 -85.260014) (xy 365.442481 -85.221305)
			(xy 365.487839 -85.188854) (xy 365.537439 -85.163353) (xy 365.590223 -85.145346) (xy 365.645066 -85.135216)
			(xy 365.7008 -85.133179) (xy 365.756237 -85.139279) (xy 365.810194 -85.153385) (xy 365.861523 -85.175197)
			(xy 365.909129 -85.204251) (xy 365.951997 -85.239926) (xy 365.989214 -85.281463) (xy 366.019987 -85.327976)
			(xy 366.043659 -85.378473) (xy 366.059727 -85.43188) (xy 366.067764 -85.486494) (xy 381.045718 -85.486494)
			(xy 381.049789 -85.430872) (xy 381.061915 -85.376435) (xy 381.081838 -85.324344) (xy 381.109134 -85.275709)
			(xy 381.14322 -85.231566) (xy 381.183369 -85.192857) (xy 381.228727 -85.160406) (xy 381.278327 -85.134905)
			(xy 381.331111 -85.116898) (xy 381.385954 -85.106768) (xy 381.441688 -85.104731) (xy 381.497125 -85.110831)
			(xy 381.551082 -85.124937) (xy 381.602411 -85.146749) (xy 381.650017 -85.175803) (xy 381.692885 -85.211478)
			(xy 381.730102 -85.253015) (xy 381.760875 -85.299528) (xy 381.784547 -85.350025) (xy 381.800615 -85.403432)
			(xy 381.808735 -85.458608) (xy 381.809244 -85.486494) (xy 381.809059 -85.496654) (xy 394.23162 -85.496654)
			(xy 394.235691 -85.441032) (xy 394.247817 -85.386595) (xy 394.26774 -85.334504) (xy 394.295036 -85.285869)
			(xy 394.329122 -85.241726) (xy 394.369271 -85.203017) (xy 394.414629 -85.170566) (xy 394.464229 -85.145065)
			(xy 394.517013 -85.127058) (xy 394.571856 -85.116928) (xy 394.62759 -85.114891) (xy 394.683027 -85.120991)
			(xy 394.736984 -85.135097) (xy 394.788313 -85.156909) (xy 394.835919 -85.185963) (xy 394.878787 -85.221638)
			(xy 394.916004 -85.263175) (xy 394.946777 -85.309688) (xy 394.970449 -85.360185) (xy 394.986517 -85.413592)
			(xy 394.994637 -85.468768) (xy 394.995146 -85.496654) (xy 394.994637 -85.52454) (xy 394.986517 -85.579716)
			(xy 394.970449 -85.633123) (xy 394.946777 -85.68362) (xy 394.916004 -85.730133) (xy 394.878787 -85.77167)
			(xy 394.835919 -85.807345) (xy 394.788313 -85.836399) (xy 394.736984 -85.858211) (xy 394.683027 -85.872317)
			(xy 394.62759 -85.878417) (xy 394.571856 -85.87638) (xy 394.517013 -85.86625) (xy 394.464229 -85.848243)
			(xy 394.414629 -85.822742) (xy 394.369271 -85.790291) (xy 394.329122 -85.751582) (xy 394.295036 -85.707439)
			(xy 394.26774 -85.658804) (xy 394.247817 -85.606713) (xy 394.235691 -85.552276) (xy 394.23162 -85.496654)
			(xy 381.809059 -85.496654) (xy 381.808735 -85.51438) (xy 381.800615 -85.569556) (xy 381.784547 -85.622963)
			(xy 381.760875 -85.67346) (xy 381.730102 -85.719973) (xy 381.692885 -85.76151) (xy 381.650017 -85.797185)
			(xy 381.602411 -85.826239) (xy 381.551082 -85.848051) (xy 381.497125 -85.862157) (xy 381.441688 -85.868257)
			(xy 381.385954 -85.86622) (xy 381.331111 -85.85609) (xy 381.278327 -85.838083) (xy 381.228727 -85.812582)
			(xy 381.183369 -85.780131) (xy 381.14322 -85.741422) (xy 381.109134 -85.697279) (xy 381.081838 -85.648644)
			(xy 381.061915 -85.596553) (xy 381.049789 -85.542116) (xy 381.045718 -85.486494) (xy 366.067764 -85.486494)
			(xy 366.067847 -85.487056) (xy 366.068356 -85.514942) (xy 366.067847 -85.542828) (xy 366.059727 -85.598004)
			(xy 366.043659 -85.651411) (xy 366.019987 -85.701908) (xy 365.989214 -85.748421) (xy 365.951997 -85.789958)
			(xy 365.909129 -85.825633) (xy 365.861523 -85.854687) (xy 365.810194 -85.876499) (xy 365.756237 -85.890605)
			(xy 365.7008 -85.896705) (xy 365.645066 -85.894668) (xy 365.590223 -85.884538) (xy 365.537439 -85.866531)
			(xy 365.487839 -85.84103) (xy 365.442481 -85.808579) (xy 365.402332 -85.76987) (xy 365.368246 -85.725727)
			(xy 365.34095 -85.677092) (xy 365.321027 -85.625001) (xy 365.308901 -85.570564) (xy 365.30483 -85.514942)
			(xy 354.763396 -85.514942) (xy 354.739225 -85.535057) (xy 354.691619 -85.564111) (xy 354.64029 -85.585923)
			(xy 354.586333 -85.600029) (xy 354.530896 -85.606129) (xy 354.475162 -85.604092) (xy 354.420319 -85.593962)
			(xy 354.367535 -85.575955) (xy 354.317935 -85.550454) (xy 354.272577 -85.518003) (xy 354.232428 -85.479294)
			(xy 354.198342 -85.435151) (xy 354.171046 -85.386516) (xy 354.151123 -85.334425) (xy 354.138997 -85.279988)
			(xy 354.134926 -85.224366) (xy 351.845489 -85.224366) (xy 351.825591 -85.240925) (xy 351.777985 -85.269979)
			(xy 351.726656 -85.291791) (xy 351.672699 -85.305897) (xy 351.617262 -85.311997) (xy 351.561528 -85.30996)
			(xy 351.506685 -85.29983) (xy 351.453901 -85.281823) (xy 351.404301 -85.256322) (xy 351.358943 -85.223871)
			(xy 351.318794 -85.185162) (xy 351.284708 -85.141019) (xy 351.257412 -85.092384) (xy 351.237489 -85.040293)
			(xy 351.225363 -84.985856) (xy 351.221292 -84.930234) (xy 347.394232 -84.930234) (xy 347.402169 -84.936324)
			(xy 347.444574 -84.978729) (xy 347.48108 -85.026305) (xy 347.511064 -85.078239) (xy 347.534013 -85.133643)
			(xy 347.549534 -85.191568) (xy 347.557362 -85.251024) (xy 347.557852 -85.281008) (xy 347.557852 -85.803232)
			(xy 351.039936 -85.803232) (xy 351.044007 -85.74761) (xy 351.056133 -85.693173) (xy 351.076056 -85.641082)
			(xy 351.103352 -85.592447) (xy 351.137438 -85.548304) (xy 351.177587 -85.509595) (xy 351.222945 -85.477144)
			(xy 351.272545 -85.451643) (xy 351.325329 -85.433636) (xy 351.380172 -85.423506) (xy 351.435906 -85.421469)
			(xy 351.491343 -85.427569) (xy 351.5453 -85.441675) (xy 351.596629 -85.463487) (xy 351.644235 -85.492541)
			(xy 351.687103 -85.528216) (xy 351.72432 -85.569753) (xy 351.755093 -85.616266) (xy 351.778765 -85.666763)
			(xy 351.794833 -85.72017) (xy 351.802953 -85.775346) (xy 351.803462 -85.803232) (xy 351.802953 -85.831118)
			(xy 351.794833 -85.886294) (xy 351.778765 -85.939701) (xy 351.755093 -85.990198) (xy 351.72432 -86.036711)
			(xy 351.687103 -86.078248) (xy 351.644235 -86.113923) (xy 351.596629 -86.142977) (xy 351.5453 -86.164789)
			(xy 351.491343 -86.178895) (xy 351.435906 -86.184995) (xy 351.380172 -86.182958) (xy 351.325329 -86.172828)
			(xy 351.272545 -86.154821) (xy 351.222945 -86.12932) (xy 351.177587 -86.096869) (xy 351.137438 -86.05816)
			(xy 351.103352 -86.014017) (xy 351.076056 -85.965382) (xy 351.056133 -85.913291) (xy 351.044007 -85.858854)
			(xy 351.039936 -85.803232) (xy 347.557852 -85.803232) (xy 347.557852 -86.144608) (xy 347.557362 -86.174592)
			(xy 347.549534 -86.234048) (xy 347.534013 -86.291973) (xy 347.511064 -86.347377) (xy 347.48108 -86.399311)
			(xy 347.444574 -86.446887) (xy 347.402169 -86.489292) (xy 347.395556 -86.494366) (xy 354.132386 -86.494366)
			(xy 354.136457 -86.438744) (xy 354.148583 -86.384307) (xy 354.168506 -86.332216) (xy 354.195802 -86.283581)
			(xy 354.229888 -86.239438) (xy 354.270037 -86.200729) (xy 354.315395 -86.168278) (xy 354.364995 -86.142777)
			(xy 354.417779 -86.12477) (xy 354.472622 -86.11464) (xy 354.528356 -86.112603) (xy 354.583793 -86.118703)
			(xy 354.63775 -86.132809) (xy 354.689079 -86.154621) (xy 354.705967 -86.164928) (xy 363.895638 -86.164928)
			(xy 363.899709 -86.109306) (xy 363.911835 -86.054869) (xy 363.931758 -86.002778) (xy 363.959054 -85.954143)
			(xy 363.99314 -85.91) (xy 364.033289 -85.871291) (xy 364.078647 -85.83884) (xy 364.128247 -85.813339)
			(xy 364.181031 -85.795332) (xy 364.235874 -85.785202) (xy 364.291608 -85.783165) (xy 364.347045 -85.789265)
			(xy 364.401002 -85.803371) (xy 364.452331 -85.825183) (xy 364.499937 -85.854237) (xy 364.542805 -85.889912)
			(xy 364.580022 -85.931449) (xy 364.610795 -85.977962) (xy 364.634467 -86.028459) (xy 364.647174 -86.070694)
			(xy 370.219222 -86.070694) (xy 370.223293 -86.015072) (xy 370.235419 -85.960635) (xy 370.255342 -85.908544)
			(xy 370.282638 -85.859909) (xy 370.316724 -85.815766) (xy 370.356873 -85.777057) (xy 370.402231 -85.744606)
			(xy 370.451831 -85.719105) (xy 370.504615 -85.701098) (xy 370.559458 -85.690968) (xy 370.615192 -85.688931)
			(xy 370.670629 -85.695031) (xy 370.724586 -85.709137) (xy 370.775915 -85.730949) (xy 370.823521 -85.760003)
			(xy 370.866389 -85.795678) (xy 370.903606 -85.837215) (xy 370.934379 -85.883728) (xy 370.956298 -85.930486)
			(xy 400.536662 -85.930486) (xy 400.540733 -85.874864) (xy 400.552859 -85.820427) (xy 400.572782 -85.768336)
			(xy 400.600078 -85.719701) (xy 400.634164 -85.675558) (xy 400.674313 -85.636849) (xy 400.719671 -85.604398)
			(xy 400.769271 -85.578897) (xy 400.822055 -85.56089) (xy 400.876898 -85.55076) (xy 400.932632 -85.548723)
			(xy 400.988069 -85.554823) (xy 401.042026 -85.568929) (xy 401.093355 -85.590741) (xy 401.140961 -85.619795)
			(xy 401.183829 -85.65547) (xy 401.221046 -85.697007) (xy 401.251819 -85.74352) (xy 401.275491 -85.794017)
			(xy 401.291559 -85.847424) (xy 401.299679 -85.9026) (xy 401.300188 -85.930486) (xy 401.299679 -85.958372)
			(xy 401.291559 -86.013548) (xy 401.275491 -86.066955) (xy 401.251819 -86.117452) (xy 401.221046 -86.163965)
			(xy 401.183829 -86.205502) (xy 401.140961 -86.241177) (xy 401.093355 -86.270231) (xy 401.042026 -86.292043)
			(xy 400.988069 -86.306149) (xy 400.932632 -86.312249) (xy 400.876898 -86.310212) (xy 400.822055 -86.300082)
			(xy 400.769271 -86.282075) (xy 400.719671 -86.256574) (xy 400.674313 -86.224123) (xy 400.634164 -86.185414)
			(xy 400.600078 -86.141271) (xy 400.572782 -86.092636) (xy 400.552859 -86.040545) (xy 400.540733 -85.986108)
			(xy 400.536662 -85.930486) (xy 370.956298 -85.930486) (xy 370.958051 -85.934225) (xy 370.974119 -85.987632)
			(xy 370.982239 -86.042808) (xy 370.982748 -86.070694) (xy 370.982239 -86.09858) (xy 370.974119 -86.153756)
			(xy 370.958051 -86.207163) (xy 370.934379 -86.25766) (xy 370.903606 -86.304173) (xy 370.866389 -86.34571)
			(xy 370.823521 -86.381385) (xy 370.775915 -86.410439) (xy 370.724586 -86.432251) (xy 370.670629 -86.446357)
			(xy 370.615192 -86.452457) (xy 370.559458 -86.45042) (xy 370.504615 -86.44029) (xy 370.451831 -86.422283)
			(xy 370.402231 -86.396782) (xy 370.356873 -86.364331) (xy 370.316724 -86.325622) (xy 370.282638 -86.281479)
			(xy 370.255342 -86.232844) (xy 370.235419 -86.180753) (xy 370.223293 -86.126316) (xy 370.219222 -86.070694)
			(xy 364.647174 -86.070694) (xy 364.650535 -86.081866) (xy 364.658655 -86.137042) (xy 364.659164 -86.164928)
			(xy 364.658655 -86.192814) (xy 364.650535 -86.24799) (xy 364.634467 -86.301397) (xy 364.610795 -86.351894)
			(xy 364.580022 -86.398407) (xy 364.542805 -86.439944) (xy 364.499937 -86.475619) (xy 364.452331 -86.504673)
			(xy 364.449091 -86.50605) (xy 367.536982 -86.50605) (xy 367.541053 -86.450428) (xy 367.553179 -86.395991)
			(xy 367.573102 -86.3439) (xy 367.600398 -86.295265) (xy 367.634484 -86.251122) (xy 367.674633 -86.212413)
			(xy 367.719991 -86.179962) (xy 367.769591 -86.154461) (xy 367.822375 -86.136454) (xy 367.877218 -86.126324)
			(xy 367.932952 -86.124287) (xy 367.988389 -86.130387) (xy 368.042346 -86.144493) (xy 368.093675 -86.166305)
			(xy 368.141281 -86.195359) (xy 368.184149 -86.231034) (xy 368.221366 -86.272571) (xy 368.252139 -86.319084)
			(xy 368.275811 -86.369581) (xy 368.291879 -86.422988) (xy 368.299999 -86.478164) (xy 368.300508 -86.50605)
			(xy 368.299999 -86.533936) (xy 368.29943 -86.5378) (xy 374.915428 -86.5378) (xy 374.919499 -86.482178)
			(xy 374.931625 -86.427741) (xy 374.951548 -86.37565) (xy 374.978844 -86.327015) (xy 375.01293 -86.282872)
			(xy 375.053079 -86.244163) (xy 375.098437 -86.211712) (xy 375.148037 -86.186211) (xy 375.200821 -86.168204)
			(xy 375.255664 -86.158074) (xy 375.311398 -86.156037) (xy 375.366835 -86.162137) (xy 375.420792 -86.176243)
			(xy 375.472121 -86.198055) (xy 375.519727 -86.227109) (xy 375.562595 -86.262784) (xy 375.599812 -86.304321)
			(xy 375.630585 -86.350834) (xy 375.654257 -86.401331) (xy 375.666811 -86.443058) (xy 377.293884 -86.443058)
			(xy 377.297955 -86.387436) (xy 377.310081 -86.332999) (xy 377.330004 -86.280908) (xy 377.3573 -86.232273)
			(xy 377.391386 -86.18813) (xy 377.431535 -86.149421) (xy 377.476893 -86.11697) (xy 377.526493 -86.091469)
			(xy 377.579277 -86.073462) (xy 377.63412 -86.063332) (xy 377.689854 -86.061295) (xy 377.745291 -86.067395)
			(xy 377.799248 -86.081501) (xy 377.850577 -86.103313) (xy 377.898183 -86.132367) (xy 377.941051 -86.168042)
			(xy 377.978268 -86.209579) (xy 378.009041 -86.256092) (xy 378.032713 -86.306589) (xy 378.048781 -86.359996)
			(xy 378.056901 -86.415172) (xy 378.05741 -86.443058) (xy 378.056901 -86.470944) (xy 378.048781 -86.52612)
			(xy 378.045267 -86.5378) (xy 379.480316 -86.5378) (xy 379.484387 -86.482178) (xy 379.496513 -86.427741)
			(xy 379.516436 -86.37565) (xy 379.543732 -86.327015) (xy 379.577818 -86.282872) (xy 379.617967 -86.244163)
			(xy 379.663325 -86.211712) (xy 379.712925 -86.186211) (xy 379.765709 -86.168204) (xy 379.820552 -86.158074)
			(xy 379.876286 -86.156037) (xy 379.931723 -86.162137) (xy 379.98568 -86.176243) (xy 380.037009 -86.198055)
			(xy 380.084615 -86.227109) (xy 380.127483 -86.262784) (xy 380.1647 -86.304321) (xy 380.195473 -86.350834)
			(xy 380.219145 -86.401331) (xy 380.235213 -86.454738) (xy 380.243333 -86.509914) (xy 380.243842 -86.5378)
			(xy 380.243333 -86.565686) (xy 380.235213 -86.620862) (xy 380.219145 -86.674269) (xy 380.195473 -86.724766)
			(xy 380.1647 -86.771279) (xy 380.127483 -86.812816) (xy 380.126183 -86.813898) (xy 400.57908 -86.813898)
			(xy 400.583151 -86.758276) (xy 400.595277 -86.703839) (xy 400.6152 -86.651748) (xy 400.642496 -86.603113)
			(xy 400.676582 -86.55897) (xy 400.716731 -86.520261) (xy 400.762089 -86.48781) (xy 400.811689 -86.462309)
			(xy 400.864473 -86.444302) (xy 400.919316 -86.434172) (xy 400.97505 -86.432135) (xy 401.030487 -86.438235)
			(xy 401.084444 -86.452341) (xy 401.135773 -86.474153) (xy 401.183379 -86.503207) (xy 401.226247 -86.538882)
			(xy 401.263464 -86.580419) (xy 401.294237 -86.626932) (xy 401.317909 -86.677429) (xy 401.333977 -86.730836)
			(xy 401.342097 -86.786012) (xy 401.342606 -86.813898) (xy 401.342097 -86.841784) (xy 401.333977 -86.89696)
			(xy 401.317909 -86.950367) (xy 401.294237 -87.000864) (xy 401.263464 -87.047377) (xy 401.226247 -87.088914)
			(xy 401.183379 -87.124589) (xy 401.135773 -87.153643) (xy 401.084444 -87.175455) (xy 401.030487 -87.189561)
			(xy 400.97505 -87.195661) (xy 400.919316 -87.193624) (xy 400.864473 -87.183494) (xy 400.811689 -87.165487)
			(xy 400.762089 -87.139986) (xy 400.716731 -87.107535) (xy 400.676582 -87.068826) (xy 400.642496 -87.024683)
			(xy 400.6152 -86.976048) (xy 400.595277 -86.923957) (xy 400.583151 -86.86952) (xy 400.57908 -86.813898)
			(xy 380.126183 -86.813898) (xy 380.084615 -86.848491) (xy 380.037009 -86.877545) (xy 379.98568 -86.899357)
			(xy 379.931723 -86.913463) (xy 379.876286 -86.919563) (xy 379.820552 -86.917526) (xy 379.765709 -86.907396)
			(xy 379.712925 -86.889389) (xy 379.663325 -86.863888) (xy 379.617967 -86.831437) (xy 379.577818 -86.792728)
			(xy 379.543732 -86.748585) (xy 379.516436 -86.69995) (xy 379.496513 -86.647859) (xy 379.484387 -86.593422)
			(xy 379.480316 -86.5378) (xy 378.045267 -86.5378) (xy 378.032713 -86.579527) (xy 378.009041 -86.630024)
			(xy 377.978268 -86.676537) (xy 377.941051 -86.718074) (xy 377.898183 -86.753749) (xy 377.850577 -86.782803)
			(xy 377.799248 -86.804615) (xy 377.745291 -86.818721) (xy 377.689854 -86.824821) (xy 377.63412 -86.822784)
			(xy 377.579277 -86.812654) (xy 377.526493 -86.794647) (xy 377.476893 -86.769146) (xy 377.431535 -86.736695)
			(xy 377.391386 -86.697986) (xy 377.3573 -86.653843) (xy 377.330004 -86.605208) (xy 377.310081 -86.553117)
			(xy 377.297955 -86.49868) (xy 377.293884 -86.443058) (xy 375.666811 -86.443058) (xy 375.670325 -86.454738)
			(xy 375.678445 -86.509914) (xy 375.678954 -86.5378) (xy 375.678445 -86.565686) (xy 375.670325 -86.620862)
			(xy 375.654257 -86.674269) (xy 375.630585 -86.724766) (xy 375.599812 -86.771279) (xy 375.562595 -86.812816)
			(xy 375.519727 -86.848491) (xy 375.472121 -86.877545) (xy 375.420792 -86.899357) (xy 375.366835 -86.913463)
			(xy 375.311398 -86.919563) (xy 375.255664 -86.917526) (xy 375.200821 -86.907396) (xy 375.148037 -86.889389)
			(xy 375.098437 -86.863888) (xy 375.053079 -86.831437) (xy 375.01293 -86.792728) (xy 374.978844 -86.748585)
			(xy 374.951548 -86.69995) (xy 374.931625 -86.647859) (xy 374.919499 -86.593422) (xy 374.915428 -86.5378)
			(xy 368.29943 -86.5378) (xy 368.291879 -86.589112) (xy 368.275811 -86.642519) (xy 368.252139 -86.693016)
			(xy 368.221366 -86.739529) (xy 368.184149 -86.781066) (xy 368.141281 -86.816741) (xy 368.093675 -86.845795)
			(xy 368.042346 -86.867607) (xy 367.988389 -86.881713) (xy 367.932952 -86.887813) (xy 367.877218 -86.885776)
			(xy 367.822375 -86.875646) (xy 367.769591 -86.857639) (xy 367.719991 -86.832138) (xy 367.674633 -86.799687)
			(xy 367.634484 -86.760978) (xy 367.600398 -86.716835) (xy 367.573102 -86.6682) (xy 367.553179 -86.616109)
			(xy 367.541053 -86.561672) (xy 367.536982 -86.50605) (xy 364.449091 -86.50605) (xy 364.401002 -86.526485)
			(xy 364.347045 -86.540591) (xy 364.291608 -86.546691) (xy 364.235874 -86.544654) (xy 364.181031 -86.534524)
			(xy 364.128247 -86.516517) (xy 364.078647 -86.491016) (xy 364.033289 -86.458565) (xy 363.99314 -86.419856)
			(xy 363.959054 -86.375713) (xy 363.931758 -86.327078) (xy 363.911835 -86.274987) (xy 363.899709 -86.22055)
			(xy 363.895638 -86.164928) (xy 354.705967 -86.164928) (xy 354.736685 -86.183675) (xy 354.779553 -86.21935)
			(xy 354.81677 -86.260887) (xy 354.847543 -86.3074) (xy 354.871215 -86.357897) (xy 354.887283 -86.411304)
			(xy 354.895403 -86.46648) (xy 354.895912 -86.494366) (xy 354.895403 -86.522252) (xy 354.887283 -86.577428)
			(xy 354.871215 -86.630835) (xy 354.847543 -86.681332) (xy 354.81677 -86.727845) (xy 354.779553 -86.769382)
			(xy 354.736685 -86.805057) (xy 354.689079 -86.834111) (xy 354.63775 -86.855923) (xy 354.583793 -86.870029)
			(xy 354.528356 -86.876129) (xy 354.472622 -86.874092) (xy 354.417779 -86.863962) (xy 354.364995 -86.845955)
			(xy 354.315395 -86.820454) (xy 354.270037 -86.788003) (xy 354.229888 -86.749294) (xy 354.195802 -86.705151)
			(xy 354.168506 -86.656516) (xy 354.148583 -86.604425) (xy 354.136457 -86.549988) (xy 354.132386 -86.494366)
			(xy 347.395556 -86.494366) (xy 347.354593 -86.525798) (xy 347.302659 -86.555782) (xy 347.247255 -86.578731)
			(xy 347.18933 -86.594252) (xy 347.129874 -86.60208) (xy 347.069906 -86.60208) (xy 347.01045 -86.594252)
			(xy 346.952525 -86.578731) (xy 346.897121 -86.555782) (xy 346.845187 -86.525798) (xy 346.797611 -86.489292)
			(xy 346.755206 -86.446887) (xy 346.7187 -86.399311) (xy 346.688716 -86.347377) (xy 346.665767 -86.291973)
			(xy 346.650246 -86.234048) (xy 346.642418 -86.174592) (xy 346.641928 -86.144608) (xy 345.35364 -86.144608)
			(xy 345.35364 -88.144604) (xy 345.879928 -88.144604) (xy 345.879928 -87.281004) (xy 345.880418 -87.25102)
			(xy 345.888246 -87.191564) (xy 345.903767 -87.133639) (xy 345.926716 -87.078235) (xy 345.9567 -87.026301)
			(xy 345.993206 -86.978725) (xy 346.035611 -86.93632) (xy 346.083187 -86.899814) (xy 346.135121 -86.86983)
			(xy 346.190525 -86.846881) (xy 346.24845 -86.83136) (xy 346.307906 -86.823532) (xy 346.367874 -86.823532)
			(xy 346.42733 -86.83136) (xy 346.485255 -86.846881) (xy 346.540659 -86.86983) (xy 346.592593 -86.899814)
			(xy 346.640169 -86.93632) (xy 346.682574 -86.978725) (xy 346.71908 -87.026301) (xy 346.740016 -87.062564)
			(xy 351.061018 -87.062564) (xy 351.065089 -87.006942) (xy 351.077215 -86.952505) (xy 351.097138 -86.900414)
			(xy 351.124434 -86.851779) (xy 351.15852 -86.807636) (xy 351.198669 -86.768927) (xy 351.244027 -86.736476)
			(xy 351.293627 -86.710975) (xy 351.346411 -86.692968) (xy 351.401254 -86.682838) (xy 351.456988 -86.680801)
			(xy 351.512425 -86.686901) (xy 351.566382 -86.701007) (xy 351.617711 -86.722819) (xy 351.665317 -86.751873)
			(xy 351.708185 -86.787548) (xy 351.745402 -86.829085) (xy 351.776175 -86.875598) (xy 351.799847 -86.926095)
			(xy 351.815915 -86.979502) (xy 351.824035 -87.034678) (xy 351.824544 -87.062564) (xy 351.824035 -87.09045)
			(xy 351.815915 -87.145626) (xy 351.799847 -87.199033) (xy 351.792974 -87.213694) (xy 370.219222 -87.213694)
			(xy 370.223293 -87.158072) (xy 370.235419 -87.103635) (xy 370.255342 -87.051544) (xy 370.282638 -87.002909)
			(xy 370.316724 -86.958766) (xy 370.356873 -86.920057) (xy 370.402231 -86.887606) (xy 370.451831 -86.862105)
			(xy 370.504615 -86.844098) (xy 370.559458 -86.833968) (xy 370.615192 -86.831931) (xy 370.670629 -86.838031)
			(xy 370.724586 -86.852137) (xy 370.775915 -86.873949) (xy 370.823521 -86.903003) (xy 370.866389 -86.938678)
			(xy 370.903606 -86.980215) (xy 370.934379 -87.026728) (xy 370.958051 -87.077225) (xy 370.974119 -87.130632)
			(xy 370.982239 -87.185808) (xy 370.982748 -87.213694) (xy 370.982239 -87.24158) (xy 370.974119 -87.296756)
			(xy 370.958051 -87.350163) (xy 370.934379 -87.40066) (xy 370.903606 -87.447173) (xy 370.866389 -87.48871)
			(xy 370.823521 -87.524385) (xy 370.775915 -87.553439) (xy 370.724586 -87.575251) (xy 370.670629 -87.589357)
			(xy 370.615192 -87.595457) (xy 370.559458 -87.59342) (xy 370.504615 -87.58329) (xy 370.451831 -87.565283)
			(xy 370.402231 -87.539782) (xy 370.356873 -87.507331) (xy 370.316724 -87.468622) (xy 370.282638 -87.424479)
			(xy 370.255342 -87.375844) (xy 370.235419 -87.323753) (xy 370.223293 -87.269316) (xy 370.219222 -87.213694)
			(xy 351.792974 -87.213694) (xy 351.776175 -87.24953) (xy 351.745402 -87.296043) (xy 351.708185 -87.33758)
			(xy 351.665317 -87.373255) (xy 351.617711 -87.402309) (xy 351.566382 -87.424121) (xy 351.512425 -87.438227)
			(xy 351.456988 -87.444327) (xy 351.401254 -87.44229) (xy 351.346411 -87.43216) (xy 351.293627 -87.414153)
			(xy 351.244027 -87.388652) (xy 351.198669 -87.356201) (xy 351.15852 -87.317492) (xy 351.124434 -87.273349)
			(xy 351.097138 -87.224714) (xy 351.077215 -87.172623) (xy 351.065089 -87.118186) (xy 351.061018 -87.062564)
			(xy 346.740016 -87.062564) (xy 346.749064 -87.078235) (xy 346.772013 -87.133639) (xy 346.787534 -87.191564)
			(xy 346.795362 -87.25102) (xy 346.795852 -87.281004) (xy 346.795852 -87.764366) (xy 354.132386 -87.764366)
			(xy 354.136457 -87.708744) (xy 354.148583 -87.654307) (xy 354.168506 -87.602216) (xy 354.195802 -87.553581)
			(xy 354.229888 -87.509438) (xy 354.270037 -87.470729) (xy 354.315395 -87.438278) (xy 354.364995 -87.412777)
			(xy 354.417779 -87.39477) (xy 354.472622 -87.38464) (xy 354.528356 -87.382603) (xy 354.583793 -87.388703)
			(xy 354.63775 -87.402809) (xy 354.689079 -87.424621) (xy 354.736685 -87.453675) (xy 354.779553 -87.48935)
			(xy 354.81677 -87.530887) (xy 354.847543 -87.5774) (xy 354.871215 -87.627897) (xy 354.887283 -87.681304)
			(xy 354.891844 -87.712296) (xy 367.61877 -87.712296) (xy 367.622841 -87.656674) (xy 367.634967 -87.602237)
			(xy 367.65489 -87.550146) (xy 367.682186 -87.501511) (xy 367.716272 -87.457368) (xy 367.756421 -87.418659)
			(xy 367.801779 -87.386208) (xy 367.851379 -87.360707) (xy 367.904163 -87.3427) (xy 367.959006 -87.33257)
			(xy 368.01474 -87.330533) (xy 368.070177 -87.336633) (xy 368.124134 -87.350739) (xy 368.175463 -87.372551)
			(xy 368.223069 -87.401605) (xy 368.265937 -87.43728) (xy 368.303154 -87.478817) (xy 368.333927 -87.52533)
			(xy 368.357599 -87.575827) (xy 368.373667 -87.629234) (xy 368.381256 -87.6808) (xy 374.915428 -87.6808)
			(xy 374.919499 -87.625178) (xy 374.931625 -87.570741) (xy 374.951548 -87.51865) (xy 374.978844 -87.470015)
			(xy 375.01293 -87.425872) (xy 375.053079 -87.387163) (xy 375.098437 -87.354712) (xy 375.148037 -87.329211)
			(xy 375.200821 -87.311204) (xy 375.255664 -87.301074) (xy 375.311398 -87.299037) (xy 375.366835 -87.305137)
			(xy 375.420792 -87.319243) (xy 375.472121 -87.341055) (xy 375.519727 -87.370109) (xy 375.562595 -87.405784)
			(xy 375.599812 -87.447321) (xy 375.630585 -87.493834) (xy 375.654257 -87.544331) (xy 375.670325 -87.597738)
			(xy 375.678445 -87.652914) (xy 375.678954 -87.6808) (xy 377.153422 -87.6808) (xy 377.157493 -87.625178)
			(xy 377.169619 -87.570741) (xy 377.189542 -87.51865) (xy 377.216838 -87.470015) (xy 377.250924 -87.425872)
			(xy 377.291073 -87.387163) (xy 377.336431 -87.354712) (xy 377.386031 -87.329211) (xy 377.438815 -87.311204)
			(xy 377.493658 -87.301074) (xy 377.549392 -87.299037) (xy 377.604829 -87.305137) (xy 377.658786 -87.319243)
			(xy 377.710115 -87.341055) (xy 377.757721 -87.370109) (xy 377.800589 -87.405784) (xy 377.837806 -87.447321)
			(xy 377.868579 -87.493834) (xy 377.889784 -87.539068) (xy 380.716026 -87.539068) (xy 380.720097 -87.483446)
			(xy 380.732223 -87.429009) (xy 380.752146 -87.376918) (xy 380.779442 -87.328283) (xy 380.813528 -87.28414)
			(xy 380.853677 -87.245431) (xy 380.899035 -87.21298) (xy 380.948635 -87.187479) (xy 381.001419 -87.169472)
			(xy 381.056262 -87.159342) (xy 381.111996 -87.157305) (xy 381.167433 -87.163405) (xy 381.22139 -87.177511)
			(xy 381.272719 -87.199323) (xy 381.297099 -87.214202) (xy 392.035536 -87.214202) (xy 392.039607 -87.15858)
			(xy 392.051733 -87.104143) (xy 392.071656 -87.052052) (xy 392.098952 -87.003417) (xy 392.133038 -86.959274)
			(xy 392.173187 -86.920565) (xy 392.218545 -86.888114) (xy 392.268145 -86.862613) (xy 392.320929 -86.844606)
			(xy 392.375772 -86.834476) (xy 392.431506 -86.832439) (xy 392.486943 -86.838539) (xy 392.5409 -86.852645)
			(xy 392.592229 -86.874457) (xy 392.639835 -86.903511) (xy 392.682703 -86.939186) (xy 392.71992 -86.980723)
			(xy 392.750693 -87.027236) (xy 392.774365 -87.077733) (xy 392.790433 -87.13114) (xy 392.798553 -87.186316)
			(xy 392.799062 -87.214202) (xy 396.84274 -87.214202) (xy 396.846811 -87.15858) (xy 396.858937 -87.104143)
			(xy 396.87886 -87.052052) (xy 396.906156 -87.003417) (xy 396.940242 -86.959274) (xy 396.980391 -86.920565)
			(xy 397.025749 -86.888114) (xy 397.075349 -86.862613) (xy 397.128133 -86.844606) (xy 397.182976 -86.834476)
			(xy 397.23871 -86.832439) (xy 397.294147 -86.838539) (xy 397.348104 -86.852645) (xy 397.399433 -86.874457)
			(xy 397.447039 -86.903511) (xy 397.489907 -86.939186) (xy 397.527124 -86.980723) (xy 397.557897 -87.027236)
			(xy 397.581569 -87.077733) (xy 397.597637 -87.13114) (xy 397.605757 -87.186316) (xy 397.606266 -87.214202)
			(xy 397.605757 -87.242088) (xy 397.597637 -87.297264) (xy 397.581569 -87.350671) (xy 397.557897 -87.401168)
			(xy 397.534488 -87.436551) (xy 398.811752 -87.436551) (xy 398.811752 -87.382049) (xy 398.819507 -87.328102)
			(xy 398.834861 -87.275808) (xy 398.8575 -87.226231) (xy 398.886964 -87.180379) (xy 398.922652 -87.139188)
			(xy 398.963839 -87.103494) (xy 399.009687 -87.074024) (xy 399.059261 -87.051379) (xy 399.111553 -87.036018)
			(xy 399.165499 -87.028255) (xy 399.19275 -87.027766) (xy 399.219314 -87.028244) (xy 399.271928 -87.035605)
			(xy 399.323014 -87.050191) (xy 399.371583 -87.07172) (xy 399.416698 -87.099777) (xy 399.457486 -87.133819)
			(xy 399.493159 -87.173188) (xy 399.508472 -87.194898) (xy 399.516806 -87.206378) (xy 399.53855 -87.224582)
			(xy 399.564463 -87.2361) (xy 399.592546 -87.24004) (xy 399.620629 -87.2361) (xy 399.646542 -87.224582)
			(xy 399.668286 -87.206378) (xy 399.67662 -87.194898) (xy 399.69188 -87.173054) (xy 399.727531 -87.133451)
			(xy 399.768349 -87.099197) (xy 399.813537 -87.070959) (xy 399.862216 -87.049286) (xy 399.913439 -87.034601)
			(xy 399.966207 -87.02719) (xy 399.99285 -87.02675) (xy 400.020102 -87.027294) (xy 400.074053 -87.035044)
			(xy 400.126351 -87.050394) (xy 400.175932 -87.073031) (xy 400.221786 -87.102495) (xy 400.26298 -87.138184)
			(xy 400.298675 -87.179374) (xy 400.328145 -87.225224) (xy 400.350788 -87.274802) (xy 400.366145 -87.327098)
			(xy 400.373903 -87.381048) (xy 400.373903 -87.435552) (xy 400.366145 -87.489502) (xy 400.350788 -87.541798)
			(xy 400.328145 -87.591376) (xy 400.298675 -87.637226) (xy 400.26298 -87.678416) (xy 400.221786 -87.714105)
			(xy 400.175932 -87.743569) (xy 400.126351 -87.766206) (xy 400.074053 -87.781556) (xy 400.020102 -87.789306)
			(xy 399.99285 -87.789766) (xy 399.966287 -87.789274) (xy 399.913673 -87.781914) (xy 399.862589 -87.767329)
			(xy 399.81402 -87.745802) (xy 399.768905 -87.717748) (xy 399.728117 -87.683709) (xy 399.692442 -87.644343)
			(xy 399.677128 -87.622634) (xy 399.668794 -87.611154) (xy 399.64705 -87.59295) (xy 399.621137 -87.581432)
			(xy 399.593054 -87.577492) (xy 399.564971 -87.581432) (xy 399.539058 -87.59295) (xy 399.517314 -87.611154)
			(xy 399.50898 -87.622634) (xy 399.49373 -87.644485) (xy 399.458076 -87.684086) (xy 399.417256 -87.718339)
			(xy 399.372066 -87.746576) (xy 399.323386 -87.768247) (xy 399.272162 -87.782931) (xy 399.219393 -87.790342)
			(xy 399.19275 -87.790782) (xy 399.165499 -87.790345) (xy 399.111553 -87.782582) (xy 399.059261 -87.767221)
			(xy 399.009687 -87.744576) (xy 398.963839 -87.715106) (xy 398.922652 -87.679412) (xy 398.886964 -87.638221)
			(xy 398.8575 -87.592369) (xy 398.834861 -87.542792) (xy 398.819507 -87.490498) (xy 398.811752 -87.436551)
			(xy 397.534488 -87.436551) (xy 397.527124 -87.447681) (xy 397.489907 -87.489218) (xy 397.447039 -87.524893)
			(xy 397.399433 -87.553947) (xy 397.348104 -87.575759) (xy 397.294147 -87.589865) (xy 397.23871 -87.595965)
			(xy 397.182976 -87.593928) (xy 397.128133 -87.583798) (xy 397.075349 -87.565791) (xy 397.025749 -87.54029)
			(xy 396.980391 -87.507839) (xy 396.940242 -87.46913) (xy 396.906156 -87.424987) (xy 396.87886 -87.376352)
			(xy 396.858937 -87.324261) (xy 396.846811 -87.269824) (xy 396.84274 -87.214202) (xy 392.799062 -87.214202)
			(xy 392.798553 -87.242088) (xy 392.790433 -87.297264) (xy 392.774365 -87.350671) (xy 392.750693 -87.401168)
			(xy 392.71992 -87.447681) (xy 392.682703 -87.489218) (xy 392.639835 -87.524893) (xy 392.592229 -87.553947)
			(xy 392.5409 -87.575759) (xy 392.486943 -87.589865) (xy 392.431506 -87.595965) (xy 392.375772 -87.593928)
			(xy 392.320929 -87.583798) (xy 392.268145 -87.565791) (xy 392.218545 -87.54029) (xy 392.173187 -87.507839)
			(xy 392.133038 -87.46913) (xy 392.098952 -87.424987) (xy 392.071656 -87.376352) (xy 392.051733 -87.324261)
			(xy 392.039607 -87.269824) (xy 392.035536 -87.214202) (xy 381.297099 -87.214202) (xy 381.320325 -87.228377)
			(xy 381.363193 -87.264052) (xy 381.40041 -87.305589) (xy 381.431183 -87.352102) (xy 381.454855 -87.402599)
			(xy 381.470923 -87.456006) (xy 381.479043 -87.511182) (xy 381.479552 -87.539068) (xy 381.479043 -87.566954)
			(xy 381.474736 -87.596218) (xy 394.29893 -87.596218) (xy 394.303001 -87.540596) (xy 394.315127 -87.486159)
			(xy 394.33505 -87.434068) (xy 394.362346 -87.385433) (xy 394.396432 -87.34129) (xy 394.436581 -87.302581)
			(xy 394.481939 -87.27013) (xy 394.531539 -87.244629) (xy 394.584323 -87.226622) (xy 394.639166 -87.216492)
			(xy 394.6949 -87.214455) (xy 394.750337 -87.220555) (xy 394.804294 -87.234661) (xy 394.855623 -87.256473)
			(xy 394.903229 -87.285527) (xy 394.946097 -87.321202) (xy 394.983314 -87.362739) (xy 395.014087 -87.409252)
			(xy 395.037759 -87.459749) (xy 395.053827 -87.513156) (xy 395.061947 -87.568332) (xy 395.062456 -87.596218)
			(xy 395.061947 -87.624104) (xy 395.053827 -87.67928) (xy 395.037759 -87.732687) (xy 395.014087 -87.783184)
			(xy 394.983314 -87.829697) (xy 394.946097 -87.871234) (xy 394.903229 -87.906909) (xy 394.855623 -87.935963)
			(xy 394.804294 -87.957775) (xy 394.750337 -87.971881) (xy 394.6949 -87.977981) (xy 394.639166 -87.975944)
			(xy 394.584323 -87.965814) (xy 394.531539 -87.947807) (xy 394.481939 -87.922306) (xy 394.436581 -87.889855)
			(xy 394.396432 -87.851146) (xy 394.362346 -87.807003) (xy 394.33505 -87.758368) (xy 394.315127 -87.706277)
			(xy 394.303001 -87.65184) (xy 394.29893 -87.596218) (xy 381.474736 -87.596218) (xy 381.470923 -87.62213)
			(xy 381.454855 -87.675537) (xy 381.431183 -87.726034) (xy 381.40041 -87.772547) (xy 381.363193 -87.814084)
			(xy 381.320325 -87.849759) (xy 381.272719 -87.878813) (xy 381.22139 -87.900625) (xy 381.167433 -87.914731)
			(xy 381.111996 -87.920831) (xy 381.056262 -87.918794) (xy 381.001419 -87.908664) (xy 380.948635 -87.890657)
			(xy 380.899035 -87.865156) (xy 380.853677 -87.832705) (xy 380.813528 -87.793996) (xy 380.779442 -87.749853)
			(xy 380.752146 -87.701218) (xy 380.732223 -87.649127) (xy 380.720097 -87.59469) (xy 380.716026 -87.539068)
			(xy 377.889784 -87.539068) (xy 377.892251 -87.544331) (xy 377.908319 -87.597738) (xy 377.916439 -87.652914)
			(xy 377.916948 -87.6808) (xy 377.916439 -87.708686) (xy 377.908319 -87.763862) (xy 377.892251 -87.817269)
			(xy 377.868579 -87.867766) (xy 377.837806 -87.914279) (xy 377.800589 -87.955816) (xy 377.757721 -87.991491)
			(xy 377.710115 -88.020545) (xy 377.658786 -88.042357) (xy 377.604829 -88.056463) (xy 377.549392 -88.062563)
			(xy 377.493658 -88.060526) (xy 377.438815 -88.050396) (xy 377.386031 -88.032389) (xy 377.336431 -88.006888)
			(xy 377.291073 -87.974437) (xy 377.250924 -87.935728) (xy 377.216838 -87.891585) (xy 377.189542 -87.84295)
			(xy 377.169619 -87.790859) (xy 377.157493 -87.736422) (xy 377.153422 -87.6808) (xy 375.678954 -87.6808)
			(xy 375.678445 -87.708686) (xy 375.670325 -87.763862) (xy 375.654257 -87.817269) (xy 375.630585 -87.867766)
			(xy 375.599812 -87.914279) (xy 375.562595 -87.955816) (xy 375.519727 -87.991491) (xy 375.472121 -88.020545)
			(xy 375.420792 -88.042357) (xy 375.366835 -88.056463) (xy 375.311398 -88.062563) (xy 375.255664 -88.060526)
			(xy 375.200821 -88.050396) (xy 375.148037 -88.032389) (xy 375.098437 -88.006888) (xy 375.053079 -87.974437)
			(xy 375.01293 -87.935728) (xy 374.978844 -87.891585) (xy 374.951548 -87.84295) (xy 374.931625 -87.790859)
			(xy 374.919499 -87.736422) (xy 374.915428 -87.6808) (xy 368.381256 -87.6808) (xy 368.381787 -87.68441)
			(xy 368.382296 -87.712296) (xy 368.381787 -87.740182) (xy 368.373667 -87.795358) (xy 368.357599 -87.848765)
			(xy 368.333927 -87.899262) (xy 368.303154 -87.945775) (xy 368.265937 -87.987312) (xy 368.223069 -88.022987)
			(xy 368.175463 -88.052041) (xy 368.124134 -88.073853) (xy 368.070177 -88.087959) (xy 368.01474 -88.094059)
			(xy 367.959006 -88.092022) (xy 367.904163 -88.081892) (xy 367.851379 -88.063885) (xy 367.801779 -88.038384)
			(xy 367.756421 -88.005933) (xy 367.716272 -87.967224) (xy 367.682186 -87.923081) (xy 367.65489 -87.874446)
			(xy 367.634967 -87.822355) (xy 367.622841 -87.767918) (xy 367.61877 -87.712296) (xy 354.891844 -87.712296)
			(xy 354.895403 -87.73648) (xy 354.895912 -87.764366) (xy 354.895403 -87.792252) (xy 354.887283 -87.847428)
			(xy 354.871215 -87.900835) (xy 354.847543 -87.951332) (xy 354.81677 -87.997845) (xy 354.779553 -88.039382)
			(xy 354.736685 -88.075057) (xy 354.689079 -88.104111) (xy 354.63775 -88.125923) (xy 354.583793 -88.140029)
			(xy 354.528356 -88.146129) (xy 354.472622 -88.144092) (xy 354.417779 -88.133962) (xy 354.364995 -88.115955)
			(xy 354.315395 -88.090454) (xy 354.270037 -88.058003) (xy 354.229888 -88.019294) (xy 354.195802 -87.975151)
			(xy 354.168506 -87.926516) (xy 354.148583 -87.874425) (xy 354.136457 -87.819988) (xy 354.132386 -87.764366)
			(xy 346.795852 -87.764366) (xy 346.795852 -88.144604) (xy 346.795362 -88.174588) (xy 346.787534 -88.234044)
			(xy 346.772013 -88.291969) (xy 346.749064 -88.347373) (xy 346.71908 -88.399307) (xy 346.682574 -88.446883)
			(xy 346.640169 -88.489288) (xy 346.592593 -88.525794) (xy 346.540659 -88.555778) (xy 346.485255 -88.578727)
			(xy 346.42733 -88.594248) (xy 346.367874 -88.602076) (xy 346.307906 -88.602076) (xy 346.24845 -88.594248)
			(xy 346.190525 -88.578727) (xy 346.135121 -88.555778) (xy 346.083187 -88.525794) (xy 346.035611 -88.489288)
			(xy 345.993206 -88.446883) (xy 345.9567 -88.399307) (xy 345.926716 -88.347373) (xy 345.903767 -88.291969)
			(xy 345.888246 -88.234044) (xy 345.880418 -88.174588) (xy 345.879928 -88.144604) (xy 345.35364 -88.144604)
			(xy 345.35364 -88.756998) (xy 351.028762 -88.756998) (xy 351.029248 -88.729747) (xy 351.037004 -88.675799)
			(xy 351.052359 -88.623504) (xy 351.075001 -88.573927) (xy 351.104467 -88.528077) (xy 351.140158 -88.486886)
			(xy 351.181349 -88.451195) (xy 351.227199 -88.421729) (xy 351.276776 -88.399087) (xy 351.329071 -88.383732)
			(xy 351.383019 -88.375976) (xy 351.437521 -88.375976) (xy 351.491469 -88.383732) (xy 351.543764 -88.399087)
			(xy 351.593341 -88.421729) (xy 351.639191 -88.451195) (xy 351.680382 -88.486886) (xy 351.716073 -88.528077)
			(xy 351.745539 -88.573927) (xy 351.768181 -88.623504) (xy 351.783536 -88.675799) (xy 351.791292 -88.729747)
			(xy 351.791778 -88.756998) (xy 351.791327 -88.782508) (xy 351.784543 -88.833076) (xy 351.771081 -88.882289)
			(xy 351.751182 -88.929269) (xy 351.725202 -88.97318) (xy 351.709736 -88.993472) (xy 351.701773 -89.004257)
			(xy 351.691233 -89.028898) (xy 351.690457 -89.034366) (xy 354.132386 -89.034366) (xy 354.136457 -88.978744)
			(xy 354.148583 -88.924307) (xy 354.168506 -88.872216) (xy 354.195802 -88.823581) (xy 354.229888 -88.779438)
			(xy 354.270037 -88.740729) (xy 354.315395 -88.708278) (xy 354.364995 -88.682777) (xy 354.417779 -88.66477)
			(xy 354.472622 -88.65464) (xy 354.528356 -88.652603) (xy 354.583793 -88.658703) (xy 354.63775 -88.672809)
			(xy 354.689079 -88.694621) (xy 354.736685 -88.723675) (xy 354.779553 -88.75935) (xy 354.81677 -88.800887)
			(xy 354.847543 -88.8474) (xy 354.871215 -88.897897) (xy 354.887283 -88.951304) (xy 354.895403 -89.00648)
			(xy 354.895912 -89.034366) (xy 354.895403 -89.062252) (xy 354.887283 -89.117428) (xy 354.871215 -89.170835)
			(xy 354.847543 -89.221332) (xy 354.81677 -89.267845) (xy 354.779553 -89.309382) (xy 354.736685 -89.345057)
			(xy 354.689079 -89.374111) (xy 354.63775 -89.395923) (xy 354.583793 -89.410029) (xy 354.528356 -89.416129)
			(xy 354.472622 -89.414092) (xy 354.417779 -89.403962) (xy 354.364995 -89.385955) (xy 354.315395 -89.360454)
			(xy 354.270037 -89.328003) (xy 354.229888 -89.289294) (xy 354.195802 -89.245151) (xy 354.168506 -89.196516)
			(xy 354.148583 -89.144425) (xy 354.136457 -89.089988) (xy 354.132386 -89.034366) (xy 351.690457 -89.034366)
			(xy 351.687465 -89.055432) (xy 351.690729 -89.082033) (xy 351.7008 -89.106869) (xy 351.716985 -89.12823)
			(xy 351.73817 -89.144646) (xy 351.750376 -89.15019) (xy 351.776044 -89.161469) (xy 351.824052 -89.190426)
			(xy 351.867306 -89.226095) (xy 351.904876 -89.267709) (xy 351.935953 -89.314373) (xy 351.959868 -89.365081)
			(xy 351.976106 -89.418742) (xy 351.984319 -89.474202) (xy 351.984818 -89.502234) (xy 351.984332 -89.529485)
			(xy 351.976576 -89.583433) (xy 351.961221 -89.635728) (xy 351.938579 -89.685305) (xy 351.909113 -89.731155)
			(xy 351.873422 -89.772346) (xy 351.832231 -89.808037) (xy 351.786381 -89.837503) (xy 351.736804 -89.860145)
			(xy 351.684509 -89.8755) (xy 351.630561 -89.883256) (xy 351.576059 -89.883256) (xy 351.522111 -89.8755)
			(xy 351.469816 -89.860145) (xy 351.420239 -89.837503) (xy 351.374389 -89.808037) (xy 351.333198 -89.772346)
			(xy 351.297507 -89.731155) (xy 351.268041 -89.685305) (xy 351.245399 -89.635728) (xy 351.230044 -89.583433)
			(xy 351.222288 -89.529485) (xy 351.221802 -89.502234) (xy 351.22222 -89.476722) (xy 351.229013 -89.426154)
			(xy 351.242482 -89.37694) (xy 351.262388 -89.329961) (xy 351.288375 -89.286051) (xy 351.303844 -89.26576)
			(xy 351.311777 -89.254953) (xy 351.322323 -89.230319) (xy 351.326097 -89.203789) (xy 351.322838 -89.177192)
			(xy 351.312772 -89.152358) (xy 351.29659 -89.130998) (xy 351.275409 -89.114585) (xy 351.263204 -89.109042)
			(xy 351.237528 -89.097778) (xy 351.189516 -89.068824) (xy 351.146258 -89.033155) (xy 351.108686 -88.991539)
			(xy 351.077609 -88.944873) (xy 351.053696 -88.894161) (xy 351.037462 -88.840495) (xy 351.029257 -88.785032)
			(xy 351.028762 -88.756998) (xy 345.35364 -88.756998) (xy 345.35364 -90.1446) (xy 346.641928 -90.1446)
			(xy 346.641928 -89.281) (xy 346.642418 -89.251016) (xy 346.650246 -89.19156) (xy 346.665767 -89.133635)
			(xy 346.688716 -89.078231) (xy 346.7187 -89.026297) (xy 346.755206 -88.978721) (xy 346.797611 -88.936316)
			(xy 346.845187 -88.89981) (xy 346.897121 -88.869826) (xy 346.952525 -88.846877) (xy 347.01045 -88.831356)
			(xy 347.069906 -88.823528) (xy 347.129874 -88.823528) (xy 347.18933 -88.831356) (xy 347.247255 -88.846877)
			(xy 347.302659 -88.869826) (xy 347.354593 -88.89981) (xy 347.402169 -88.936316) (xy 347.444574 -88.978721)
			(xy 347.48108 -89.026297) (xy 347.511064 -89.078231) (xy 347.534013 -89.133635) (xy 347.549534 -89.19156)
			(xy 347.557362 -89.251016) (xy 347.557852 -89.281) (xy 347.557852 -90.1446) (xy 347.557362 -90.174584)
			(xy 347.549534 -90.23404) (xy 347.534013 -90.291965) (xy 347.511064 -90.347369) (xy 347.48108 -90.399303)
			(xy 347.444574 -90.446879) (xy 347.402169 -90.489284) (xy 347.354593 -90.52579) (xy 347.302659 -90.555774)
			(xy 347.247255 -90.578723) (xy 347.18933 -90.594244) (xy 347.129874 -90.602072) (xy 347.069906 -90.602072)
			(xy 347.01045 -90.594244) (xy 346.952525 -90.578723) (xy 346.897121 -90.555774) (xy 346.845187 -90.52579)
			(xy 346.797611 -90.489284) (xy 346.755206 -90.446879) (xy 346.7187 -90.399303) (xy 346.688716 -90.347369)
			(xy 346.665767 -90.291965) (xy 346.650246 -90.23404) (xy 346.642418 -90.174584) (xy 346.641928 -90.1446)
			(xy 345.35364 -90.1446) (xy 345.35364 -90.645234) (xy 348.886524 -90.645234) (xy 348.890595 -90.589612)
			(xy 348.902721 -90.535175) (xy 348.922644 -90.483084) (xy 348.94994 -90.434449) (xy 348.984026 -90.390306)
			(xy 349.024175 -90.351597) (xy 349.069533 -90.319146) (xy 349.119133 -90.293645) (xy 349.171917 -90.275638)
			(xy 349.22676 -90.265508) (xy 349.282494 -90.263471) (xy 349.337931 -90.269571) (xy 349.391888 -90.283677)
			(xy 349.440574 -90.304366) (xy 354.132386 -90.304366) (xy 354.136457 -90.248744) (xy 354.148583 -90.194307)
			(xy 354.168506 -90.142216) (xy 354.195802 -90.093581) (xy 354.229888 -90.049438) (xy 354.270037 -90.010729)
			(xy 354.315395 -89.978278) (xy 354.364995 -89.952777) (xy 354.417779 -89.93477) (xy 354.472622 -89.92464)
			(xy 354.528356 -89.922603) (xy 354.583793 -89.928703) (xy 354.63775 -89.942809) (xy 354.689079 -89.964621)
			(xy 354.736685 -89.993675) (xy 354.779553 -90.02935) (xy 354.81677 -90.070887) (xy 354.847543 -90.1174)
			(xy 354.871215 -90.167897) (xy 354.887283 -90.221304) (xy 354.895403 -90.27648) (xy 354.895912 -90.304366)
			(xy 354.895403 -90.332252) (xy 354.887283 -90.387428) (xy 354.871215 -90.440835) (xy 354.847543 -90.491332)
			(xy 354.81677 -90.537845) (xy 354.779553 -90.579382) (xy 354.736685 -90.615057) (xy 354.689079 -90.644111)
			(xy 354.63775 -90.665923) (xy 354.583793 -90.680029) (xy 354.528356 -90.686129) (xy 354.472622 -90.684092)
			(xy 354.417779 -90.673962) (xy 354.364995 -90.655955) (xy 354.315395 -90.630454) (xy 354.270037 -90.598003)
			(xy 354.229888 -90.559294) (xy 354.195802 -90.515151) (xy 354.168506 -90.466516) (xy 354.148583 -90.414425)
			(xy 354.136457 -90.359988) (xy 354.132386 -90.304366) (xy 349.440574 -90.304366) (xy 349.443217 -90.305489)
			(xy 349.490823 -90.334543) (xy 349.533691 -90.370218) (xy 349.570908 -90.411755) (xy 349.601681 -90.458268)
			(xy 349.625353 -90.508765) (xy 349.641421 -90.562172) (xy 349.649541 -90.617348) (xy 349.65005 -90.645234)
			(xy 349.649541 -90.67312) (xy 349.641421 -90.728296) (xy 349.625353 -90.781703) (xy 349.601681 -90.8322)
			(xy 349.570908 -90.878713) (xy 349.533691 -90.92025) (xy 349.490823 -90.955925) (xy 349.443217 -90.984979)
			(xy 349.391888 -91.006791) (xy 349.337931 -91.020897) (xy 349.282494 -91.026997) (xy 349.22676 -91.02496)
			(xy 349.171917 -91.01483) (xy 349.119133 -90.996823) (xy 349.069533 -90.971322) (xy 349.024175 -90.938871)
			(xy 348.984026 -90.900162) (xy 348.94994 -90.856019) (xy 348.922644 -90.807384) (xy 348.902721 -90.755293)
			(xy 348.890595 -90.700856) (xy 348.886524 -90.645234) (xy 345.35364 -90.645234) (xy 345.35364 -91.781376)
			(xy 345.354078 -91.791439) (xy 345.356375 -91.796955) (xy 348.165847 -91.796955) (xy 348.165847 -91.742445)
			(xy 348.173605 -91.688491) (xy 348.188963 -91.63619) (xy 348.211608 -91.586607) (xy 348.241079 -91.540751)
			(xy 348.276777 -91.499557) (xy 348.317974 -91.463863) (xy 348.363831 -91.434395) (xy 348.413416 -91.411753)
			(xy 348.465718 -91.396399) (xy 348.519673 -91.388645) (xy 348.546928 -91.388184) (xy 348.574574 -91.388676)
			(xy 348.629285 -91.396678) (xy 348.682268 -91.412496) (xy 348.732411 -91.435799) (xy 348.778664 -91.466098)
			(xy 348.820057 -91.502757) (xy 348.838266 -91.523566) (xy 348.845593 -91.531385) (xy 348.864916 -91.540599)
			(xy 348.875604 -91.541346) (xy 348.962726 -91.543886) (xy 348.982792 -91.53525) (xy 348.990158 -91.527376)
			(xy 349.008249 -91.508679) (xy 349.048654 -91.475902) (xy 349.093138 -91.44892) (xy 349.140876 -91.428235)
			(xy 349.190983 -91.41423) (xy 349.242528 -91.407165) (xy 349.268542 -91.406726) (xy 349.295794 -91.407147)
			(xy 349.349742 -91.414909) (xy 349.402036 -91.430269) (xy 349.451612 -91.452914) (xy 349.497462 -91.482385)
			(xy 349.538651 -91.518079) (xy 349.574341 -91.559272) (xy 349.584041 -91.574366) (xy 354.132386 -91.574366)
			(xy 354.136457 -91.518744) (xy 354.148583 -91.464307) (xy 354.168506 -91.412216) (xy 354.195802 -91.363581)
			(xy 354.229888 -91.319438) (xy 354.270037 -91.280729) (xy 354.315395 -91.248278) (xy 354.364995 -91.222777)
			(xy 354.417779 -91.20477) (xy 354.472622 -91.19464) (xy 354.528356 -91.192603) (xy 354.583793 -91.198703)
			(xy 354.63775 -91.212809) (xy 354.689079 -91.234621) (xy 354.736685 -91.263675) (xy 354.779553 -91.29935)
			(xy 354.81677 -91.340887) (xy 354.847543 -91.3874) (xy 354.871215 -91.437897) (xy 354.887283 -91.491304)
			(xy 354.895403 -91.54648) (xy 354.895912 -91.574366) (xy 354.895403 -91.602252) (xy 354.887283 -91.657428)
			(xy 354.871215 -91.710835) (xy 354.847543 -91.761332) (xy 354.81677 -91.807845) (xy 354.779553 -91.849382)
			(xy 354.736685 -91.885057) (xy 354.689079 -91.914111) (xy 354.63775 -91.935923) (xy 354.583793 -91.950029)
			(xy 354.528356 -91.956129) (xy 354.472622 -91.954092) (xy 354.417779 -91.943962) (xy 354.364995 -91.925955)
			(xy 354.315395 -91.900454) (xy 354.270037 -91.868003) (xy 354.229888 -91.829294) (xy 354.195802 -91.785151)
			(xy 354.168506 -91.736516) (xy 354.148583 -91.684425) (xy 354.136457 -91.629988) (xy 354.132386 -91.574366)
			(xy 349.584041 -91.574366) (xy 349.603806 -91.605124) (xy 349.626446 -91.654703) (xy 349.6418 -91.706999)
			(xy 349.649556 -91.760948) (xy 349.649556 -91.815452) (xy 349.6418 -91.869401) (xy 349.626446 -91.921697)
			(xy 349.603806 -91.971276) (xy 349.58465 -92.001086) (xy 356.409242 -92.001086) (xy 356.413313 -91.945464)
			(xy 356.425439 -91.891027) (xy 356.445362 -91.838936) (xy 356.472658 -91.790301) (xy 356.506744 -91.746158)
			(xy 356.546893 -91.707449) (xy 356.592251 -91.674998) (xy 356.641851 -91.649497) (xy 356.694635 -91.63149)
			(xy 356.749478 -91.62136) (xy 356.805212 -91.619323) (xy 356.860649 -91.625423) (xy 356.914606 -91.639529)
			(xy 356.965935 -91.661341) (xy 357.013541 -91.690395) (xy 357.056409 -91.72607) (xy 357.093626 -91.767607)
			(xy 357.124399 -91.81412) (xy 357.148071 -91.864617) (xy 357.164139 -91.918024) (xy 357.172259 -91.9732)
			(xy 357.172768 -92.001086) (xy 357.172259 -92.028972) (xy 357.164139 -92.084148) (xy 357.148071 -92.137555)
			(xy 357.124399 -92.188052) (xy 357.093626 -92.234565) (xy 357.056409 -92.276102) (xy 357.013541 -92.311777)
			(xy 356.965935 -92.340831) (xy 356.914606 -92.362643) (xy 356.860649 -92.376749) (xy 356.805212 -92.382849)
			(xy 356.749478 -92.380812) (xy 356.694635 -92.370682) (xy 356.641851 -92.352675) (xy 356.592251 -92.327174)
			(xy 356.546893 -92.294723) (xy 356.506744 -92.256014) (xy 356.472658 -92.211871) (xy 356.445362 -92.163236)
			(xy 356.425439 -92.111145) (xy 356.413313 -92.056708) (xy 356.409242 -92.001086) (xy 349.58465 -92.001086)
			(xy 349.574341 -92.017128) (xy 349.538651 -92.058321) (xy 349.497462 -92.094015) (xy 349.451612 -92.123486)
			(xy 349.402036 -92.146131) (xy 349.349742 -92.161491) (xy 349.295794 -92.169253) (xy 349.268542 -92.169742)
			(xy 349.240896 -92.169228) (xy 349.186185 -92.161234) (xy 349.133202 -92.145422) (xy 349.083058 -92.122123)
			(xy 349.036805 -92.091827) (xy 348.995412 -92.055169) (xy 348.977204 -92.03436) (xy 348.969885 -92.026532)
			(xy 348.950556 -92.017322) (xy 348.939866 -92.01658) (xy 348.852744 -92.01404) (xy 348.832678 -92.022676)
			(xy 348.825312 -92.03055) (xy 348.807192 -92.049218) (xy 348.766793 -92.081997) (xy 348.722315 -92.108981)
			(xy 348.674582 -92.129672) (xy 348.624481 -92.143683) (xy 348.57294 -92.150757) (xy 348.546928 -92.1512)
			(xy 348.519673 -92.150755) (xy 348.465718 -92.143001) (xy 348.413416 -92.127647) (xy 348.363831 -92.105005)
			(xy 348.317974 -92.075537) (xy 348.276777 -92.039843) (xy 348.241079 -91.998649) (xy 348.211608 -91.952793)
			(xy 348.188963 -91.90321) (xy 348.173605 -91.850909) (xy 348.165847 -91.796955) (xy 345.356375 -91.796955)
			(xy 345.361817 -91.81002) (xy 345.368626 -91.817444) (xy 349.814896 -96.263714) (xy 349.82229 -96.27057)
			(xy 349.840889 -96.27832) (xy 349.850964 -96.2787) (xy 351.079308 -96.2787) (xy 351.093852 -96.281647)
			(xy 351.123467 -96.279959) (xy 351.151354 -96.269851) (xy 351.17517 -96.25217) (xy 351.184464 -96.2406)
			(xy 351.189104 -96.233916) (xy 351.194288 -96.218503) (xy 351.194624 -96.210374) (xy 351.194624 -93.33738)
			(xy 351.194448 -93.331229) (xy 351.191482 -93.319289) (xy 351.188782 -93.313758) (xy 351.174939 -93.286188)
			(xy 351.155355 -93.227689) (xy 351.145429 -93.166803) (xy 351.14484 -93.135958) (xy 351.145348 -93.120718)
			(xy 351.146929 -93.092908) (xy 351.15715 -93.038155) (xy 351.175223 -92.985469) (xy 351.200765 -92.935971)
			(xy 351.233233 -92.890713) (xy 351.271937 -92.850657) (xy 351.316054 -92.816654) (xy 351.364645 -92.789428)
			(xy 351.41668 -92.769556) (xy 351.471051 -92.757461) (xy 351.526602 -92.753401) (xy 351.582153 -92.757461)
			(xy 351.636524 -92.769556) (xy 351.688559 -92.789428) (xy 351.73715 -92.816654) (xy 351.781267 -92.850657)
			(xy 351.819971 -92.890713) (xy 351.852439 -92.935971) (xy 351.877981 -92.985469) (xy 351.896054 -93.038155)
			(xy 351.906275 -93.092908) (xy 351.907856 -93.120718) (xy 351.908364 -93.135958) (xy 351.908204 -93.14434)
			(xy 352.13112 -93.14434) (xy 352.135191 -93.088718) (xy 352.147317 -93.034281) (xy 352.16724 -92.98219)
			(xy 352.194536 -92.933555) (xy 352.228622 -92.889412) (xy 352.268771 -92.850703) (xy 352.314129 -92.818252)
			(xy 352.363729 -92.792751) (xy 352.416513 -92.774744) (xy 352.471356 -92.764614) (xy 352.52709 -92.762577)
			(xy 352.582527 -92.768677) (xy 352.636484 -92.782783) (xy 352.687813 -92.804595) (xy 352.735419 -92.833649)
			(xy 352.748297 -92.844366) (xy 353.159566 -92.844366) (xy 353.163637 -92.788744) (xy 353.175763 -92.734307)
			(xy 353.195686 -92.682216) (xy 353.222982 -92.633581) (xy 353.257068 -92.589438) (xy 353.297217 -92.550729)
			(xy 353.342575 -92.518278) (xy 353.392175 -92.492777) (xy 353.444959 -92.47477) (xy 353.499802 -92.46464)
			(xy 353.555536 -92.462603) (xy 353.610973 -92.468703) (xy 353.66493 -92.482809) (xy 353.716259 -92.504621)
			(xy 353.763865 -92.533675) (xy 353.806733 -92.56935) (xy 353.84395 -92.610887) (xy 353.874723 -92.6574)
			(xy 353.898395 -92.707897) (xy 353.914463 -92.761304) (xy 353.922583 -92.81648) (xy 353.923092 -92.844366)
			(xy 353.922583 -92.872252) (xy 353.914463 -92.927428) (xy 353.898395 -92.980835) (xy 353.874723 -93.031332)
			(xy 353.84395 -93.077845) (xy 353.806733 -93.119382) (xy 353.763865 -93.155057) (xy 353.716259 -93.184111)
			(xy 353.66493 -93.205923) (xy 353.610973 -93.220029) (xy 353.555536 -93.226129) (xy 353.499802 -93.224092)
			(xy 353.444959 -93.213962) (xy 353.392175 -93.195955) (xy 353.342575 -93.170454) (xy 353.297217 -93.138003)
			(xy 353.257068 -93.099294) (xy 353.222982 -93.055151) (xy 353.195686 -93.006516) (xy 353.175763 -92.954425)
			(xy 353.163637 -92.899988) (xy 353.159566 -92.844366) (xy 352.748297 -92.844366) (xy 352.778287 -92.869324)
			(xy 352.815504 -92.910861) (xy 352.846277 -92.957374) (xy 352.869949 -93.007871) (xy 352.886017 -93.061278)
			(xy 352.894137 -93.116454) (xy 352.894646 -93.14434) (xy 352.894137 -93.172226) (xy 352.886017 -93.227402)
			(xy 352.876237 -93.25991) (xy 355.188518 -93.25991) (xy 355.192589 -93.204288) (xy 355.204715 -93.149851)
			(xy 355.224638 -93.09776) (xy 355.251934 -93.049125) (xy 355.28602 -93.004982) (xy 355.326169 -92.966273)
			(xy 355.371527 -92.933822) (xy 355.421127 -92.908321) (xy 355.473911 -92.890314) (xy 355.528754 -92.880184)
			(xy 355.584488 -92.878147) (xy 355.639925 -92.884247) (xy 355.693882 -92.898353) (xy 355.745211 -92.920165)
			(xy 355.792817 -92.949219) (xy 355.835685 -92.984894) (xy 355.872902 -93.026431) (xy 355.903675 -93.072944)
			(xy 355.927347 -93.123441) (xy 355.943415 -93.176848) (xy 355.951535 -93.232024) (xy 355.952044 -93.25991)
			(xy 355.951535 -93.287796) (xy 355.943415 -93.342972) (xy 355.927347 -93.396379) (xy 355.903675 -93.446876)
			(xy 355.872902 -93.493389) (xy 355.835685 -93.534926) (xy 355.792817 -93.570601) (xy 355.745211 -93.599655)
			(xy 355.693882 -93.621467) (xy 355.639925 -93.635573) (xy 355.584488 -93.641673) (xy 355.528754 -93.639636)
			(xy 355.473911 -93.629506) (xy 355.421127 -93.611499) (xy 355.371527 -93.585998) (xy 355.326169 -93.553547)
			(xy 355.28602 -93.514838) (xy 355.251934 -93.470695) (xy 355.224638 -93.42206) (xy 355.204715 -93.369969)
			(xy 355.192589 -93.315532) (xy 355.188518 -93.25991) (xy 352.876237 -93.25991) (xy 352.869949 -93.280809)
			(xy 352.846277 -93.331306) (xy 352.815504 -93.377819) (xy 352.778287 -93.419356) (xy 352.735419 -93.455031)
			(xy 352.687813 -93.484085) (xy 352.636484 -93.505897) (xy 352.582527 -93.520003) (xy 352.52709 -93.526103)
			(xy 352.471356 -93.524066) (xy 352.416513 -93.513936) (xy 352.363729 -93.495929) (xy 352.314129 -93.470428)
			(xy 352.268771 -93.437977) (xy 352.228622 -93.399268) (xy 352.194536 -93.355125) (xy 352.16724 -93.30649)
			(xy 352.147317 -93.254399) (xy 352.135191 -93.199962) (xy 352.13112 -93.14434) (xy 351.908204 -93.14434)
			(xy 351.907775 -93.166803) (xy 351.897857 -93.227692) (xy 351.878273 -93.286191) (xy 351.864422 -93.313758)
			(xy 351.861723 -93.319288) (xy 351.858761 -93.331229) (xy 351.85858 -93.33738) (xy 351.85858 -96.826578)
			(xy 357.466898 -96.826578) (xy 357.470969 -96.770956) (xy 357.483095 -96.716519) (xy 357.503018 -96.664428)
			(xy 357.530314 -96.615793) (xy 357.5644 -96.57165) (xy 357.604549 -96.532941) (xy 357.649907 -96.50049)
			(xy 357.699507 -96.474989) (xy 357.752291 -96.456982) (xy 357.807134 -96.446852) (xy 357.862868 -96.444815)
			(xy 357.918305 -96.450915) (xy 357.972262 -96.465021) (xy 358.023591 -96.486833) (xy 358.071197 -96.515887)
			(xy 358.114065 -96.551562) (xy 358.151282 -96.593099) (xy 358.182055 -96.639612) (xy 358.205727 -96.690109)
			(xy 358.221795 -96.743516) (xy 358.229915 -96.798692) (xy 358.230424 -96.826578) (xy 358.229915 -96.854464)
			(xy 358.226917 -96.874838) (xy 359.401362 -96.874838) (xy 359.405433 -96.819216) (xy 359.417559 -96.764779)
			(xy 359.437482 -96.712688) (xy 359.464778 -96.664053) (xy 359.498864 -96.61991) (xy 359.539013 -96.581201)
			(xy 359.584371 -96.54875) (xy 359.633971 -96.523249) (xy 359.686755 -96.505242) (xy 359.741598 -96.495112)
			(xy 359.797332 -96.493075) (xy 359.852769 -96.499175) (xy 359.906726 -96.513281) (xy 359.958055 -96.535093)
			(xy 360.005661 -96.564147) (xy 360.048529 -96.599822) (xy 360.085746 -96.641359) (xy 360.116519 -96.687872)
			(xy 360.140191 -96.738369) (xy 360.156259 -96.791776) (xy 360.164379 -96.846952) (xy 360.164888 -96.874838)
			(xy 360.164379 -96.902724) (xy 360.156259 -96.9579) (xy 360.140191 -97.011307) (xy 360.116519 -97.061804)
			(xy 360.085746 -97.108317) (xy 360.048529 -97.149854) (xy 360.005661 -97.185529) (xy 359.958055 -97.214583)
			(xy 359.906726 -97.236395) (xy 359.852769 -97.250501) (xy 359.797332 -97.256601) (xy 359.741598 -97.254564)
			(xy 359.686755 -97.244434) (xy 359.633971 -97.226427) (xy 359.584371 -97.200926) (xy 359.539013 -97.168475)
			(xy 359.498864 -97.129766) (xy 359.464778 -97.085623) (xy 359.437482 -97.036988) (xy 359.417559 -96.984897)
			(xy 359.405433 -96.93046) (xy 359.401362 -96.874838) (xy 358.226917 -96.874838) (xy 358.221795 -96.90964)
			(xy 358.205727 -96.963047) (xy 358.182055 -97.013544) (xy 358.151282 -97.060057) (xy 358.114065 -97.101594)
			(xy 358.071197 -97.137269) (xy 358.023591 -97.166323) (xy 357.972262 -97.188135) (xy 357.918305 -97.202241)
			(xy 357.862868 -97.208341) (xy 357.807134 -97.206304) (xy 357.752291 -97.196174) (xy 357.699507 -97.178167)
			(xy 357.649907 -97.152666) (xy 357.604549 -97.120215) (xy 357.5644 -97.081506) (xy 357.530314 -97.037363)
			(xy 357.503018 -96.988728) (xy 357.483095 -96.936637) (xy 357.470969 -96.8822) (xy 357.466898 -96.826578)
			(xy 351.85858 -96.826578) (xy 351.85858 -98.273362) (xy 359.51363 -98.273362) (xy 359.517701 -98.21774)
			(xy 359.529827 -98.163303) (xy 359.54975 -98.111212) (xy 359.577046 -98.062577) (xy 359.611132 -98.018434)
			(xy 359.651281 -97.979725) (xy 359.696639 -97.947274) (xy 359.746239 -97.921773) (xy 359.799023 -97.903766)
			(xy 359.853866 -97.893636) (xy 359.9096 -97.891599) (xy 359.965037 -97.897699) (xy 360.018994 -97.911805)
			(xy 360.070323 -97.933617) (xy 360.117929 -97.962671) (xy 360.160797 -97.998346) (xy 360.198014 -98.039883)
			(xy 360.228787 -98.086396) (xy 360.252459 -98.136893) (xy 360.268527 -98.1903) (xy 360.276647 -98.245476)
			(xy 360.277156 -98.273362) (xy 360.276647 -98.301248) (xy 360.268527 -98.356424) (xy 360.252459 -98.409831)
			(xy 360.228787 -98.460328) (xy 360.198014 -98.506841) (xy 360.160797 -98.548378) (xy 360.117929 -98.584053)
			(xy 360.070323 -98.613107) (xy 360.018994 -98.634919) (xy 359.965037 -98.649025) (xy 359.9096 -98.655125)
			(xy 359.853866 -98.653088) (xy 359.799023 -98.642958) (xy 359.746239 -98.624951) (xy 359.696639 -98.59945)
			(xy 359.651281 -98.566999) (xy 359.611132 -98.52829) (xy 359.577046 -98.484147) (xy 359.54975 -98.435512)
			(xy 359.529827 -98.383421) (xy 359.517701 -98.328984) (xy 359.51363 -98.273362) (xy 351.85858 -98.273362)
			(xy 351.85858 -99.152248) (xy 355.277702 -99.152248) (xy 355.277702 -99.097752) (xy 355.285457 -99.04381)
			(xy 355.30081 -98.99152) (xy 355.323448 -98.941948) (xy 355.35291 -98.896102) (xy 355.388597 -98.854915)
			(xy 355.429781 -98.819226) (xy 355.475625 -98.789761) (xy 355.525196 -98.767119) (xy 355.577484 -98.751763)
			(xy 355.631426 -98.744004) (xy 355.658674 -98.743516) (xy 355.688256 -98.744117) (xy 355.746712 -98.753246)
			(xy 355.803058 -98.771289) (xy 355.855944 -98.797813) (xy 355.904101 -98.832184) (xy 355.925628 -98.852482)
			(xy 355.932994 -98.859594) (xy 355.952044 -98.867214) (xy 356.046024 -98.86442) (xy 356.06482 -98.855784)
			(xy 356.071678 -98.848164) (xy 356.089826 -98.828878) (xy 356.130555 -98.795029) (xy 356.175571 -98.767135)
			(xy 356.224011 -98.745731) (xy 356.274944 -98.731228) (xy 356.327393 -98.723904) (xy 356.353872 -98.72345)
			(xy 356.381123 -98.723995) (xy 356.435071 -98.731748) (xy 356.487367 -98.7471) (xy 356.536945 -98.769739)
			(xy 356.582796 -98.799203) (xy 356.623988 -98.834892) (xy 356.659681 -98.876081) (xy 356.689148 -98.921931)
			(xy 356.71179 -98.971507) (xy 356.727146 -99.023801) (xy 356.734903 -99.077749) (xy 356.734903 -99.132251)
			(xy 356.727146 -99.186199) (xy 356.71179 -99.238493) (xy 356.689148 -99.288069) (xy 356.659681 -99.333919)
			(xy 356.623988 -99.375108) (xy 356.582796 -99.410797) (xy 356.536945 -99.440261) (xy 356.487367 -99.4629)
			(xy 356.435071 -99.478252) (xy 356.381123 -99.486005) (xy 356.353872 -99.486466) (xy 356.324288 -99.485904)
			(xy 356.26583 -99.476766) (xy 356.209483 -99.458714) (xy 356.156599 -99.432181) (xy 356.108443 -99.397802)
			(xy 356.086918 -99.3775) (xy 356.079552 -99.370388) (xy 356.060502 -99.362768) (xy 355.966522 -99.365562)
			(xy 355.947726 -99.374198) (xy 355.940868 -99.381818) (xy 355.922694 -99.401079) (xy 355.881971 -99.43493)
			(xy 355.83696 -99.462828) (xy 355.788526 -99.484237) (xy 355.737597 -99.498745) (xy 355.685151 -99.506075)
			(xy 355.658674 -99.506532) (xy 355.631426 -99.505996) (xy 355.577484 -99.498237) (xy 355.525196 -99.482881)
			(xy 355.475625 -99.460239) (xy 355.429781 -99.430774) (xy 355.388597 -99.395085) (xy 355.35291 -99.353898)
			(xy 355.323448 -99.308052) (xy 355.30081 -99.25848) (xy 355.285457 -99.20619) (xy 355.277702 -99.152248)
			(xy 351.85858 -99.152248) (xy 351.85858 -100.975946) (xy 352.819522 -100.975946) (xy 352.819522 -100.921454)
			(xy 352.827277 -100.867516) (xy 352.842628 -100.81523) (xy 352.865264 -100.765661) (xy 352.894723 -100.719818)
			(xy 352.930406 -100.678633) (xy 352.971587 -100.642946) (xy 353.017428 -100.613482) (xy 353.066994 -100.590841)
			(xy 353.119278 -100.575485) (xy 353.173216 -100.567725) (xy 353.200462 -100.567236) (xy 353.228365 -100.567766)
			(xy 353.283576 -100.575903) (xy 353.337012 -100.591994) (xy 353.387536 -100.615696) (xy 353.434069 -100.646503)
			(xy 353.475619 -100.683759) (xy 353.493832 -100.704904) (xy 353.494086 -100.705158) (xy 353.502 -100.713719)
			(xy 353.52332 -100.723098) (xy 353.53498 -100.723192) (xy 353.62769 -100.719382) (xy 353.648518 -100.707952)
			(xy 353.655376 -100.6983) (xy 353.670737 -100.677075) (xy 353.706324 -100.638624) (xy 353.746841 -100.605407)
			(xy 353.791522 -100.578048) (xy 353.839529 -100.557064) (xy 353.889956 -100.542848) (xy 353.941854 -100.53567)
			(xy 353.96805 -100.535232) (xy 353.997917 -100.535824) (xy 354.056921 -100.54514) (xy 354.113752 -100.563538)
			(xy 354.167022 -100.590567) (xy 354.215429 -100.625567) (xy 354.25779 -100.667683) (xy 354.275898 -100.691442)
			(xy 354.282756 -100.70084) (xy 354.302822 -100.711508) (xy 354.393246 -100.715826) (xy 354.404525 -100.71583)
			(xy 354.425355 -100.707245) (xy 354.433378 -100.699316) (xy 354.433632 -100.699062) (xy 354.451835 -100.679437)
			(xy 354.492736 -100.644911) (xy 354.53806 -100.616438) (xy 354.586918 -100.594576) (xy 354.63835 -100.579755)
			(xy 354.691349 -100.572265) (xy 354.718112 -100.571808) (xy 354.747239 -100.572336) (xy 354.804813 -100.581206)
			(xy 354.86037 -100.598723) (xy 354.912619 -100.62448) (xy 354.960347 -100.657879) (xy 355.002445 -100.698144)
			(xy 355.020626 -100.720906) (xy 355.028349 -100.729903) (xy 355.049672 -100.740219) (xy 355.06152 -100.740718)
			(xy 355.154992 -100.739702) (xy 355.176074 -100.72878) (xy 355.183186 -100.718874) (xy 355.201274 -100.695097)
			(xy 355.243635 -100.652975) (xy 355.292044 -100.617971) (xy 355.345318 -100.590942) (xy 355.402155 -100.572549)
			(xy 355.461165 -100.563241) (xy 355.491034 -100.562664) (xy 355.518282 -100.563209) (xy 355.572222 -100.570968)
			(xy 355.624508 -100.586325) (xy 355.674078 -100.608967) (xy 355.71992 -100.638432) (xy 355.761103 -100.674121)
			(xy 355.796789 -100.715307) (xy 355.82625 -100.761152) (xy 355.848887 -100.810723) (xy 355.864239 -100.863012)
			(xy 355.871994 -100.916952) (xy 355.871994 -100.971448) (xy 355.864239 -101.025388) (xy 355.848887 -101.077677)
			(xy 355.837591 -101.102414) (xy 357.314498 -101.102414) (xy 357.318569 -101.046792) (xy 357.330695 -100.992355)
			(xy 357.350618 -100.940264) (xy 357.377914 -100.891629) (xy 357.412 -100.847486) (xy 357.452149 -100.808777)
			(xy 357.497507 -100.776326) (xy 357.547107 -100.750825) (xy 357.599891 -100.732818) (xy 357.654734 -100.722688)
			(xy 357.710468 -100.720651) (xy 357.765905 -100.726751) (xy 357.819862 -100.740857) (xy 357.871191 -100.762669)
			(xy 357.918797 -100.791723) (xy 357.961665 -100.827398) (xy 357.998882 -100.868935) (xy 358.029655 -100.915448)
			(xy 358.053327 -100.965945) (xy 358.069395 -101.019352) (xy 358.077515 -101.074528) (xy 358.078024 -101.102414)
			(xy 358.077954 -101.106224) (xy 358.867708 -101.106224) (xy 358.871779 -101.050602) (xy 358.883905 -100.996165)
			(xy 358.903828 -100.944074) (xy 358.931124 -100.895439) (xy 358.96521 -100.851296) (xy 359.005359 -100.812587)
			(xy 359.050717 -100.780136) (xy 359.100317 -100.754635) (xy 359.153101 -100.736628) (xy 359.207944 -100.726498)
			(xy 359.263678 -100.724461) (xy 359.319115 -100.730561) (xy 359.373072 -100.744667) (xy 359.424401 -100.766479)
			(xy 359.472007 -100.795533) (xy 359.514875 -100.831208) (xy 359.552092 -100.872745) (xy 359.582865 -100.919258)
			(xy 359.606537 -100.969755) (xy 359.622605 -101.023162) (xy 359.630725 -101.078338) (xy 359.631234 -101.106224)
			(xy 359.630725 -101.13411) (xy 359.622605 -101.189286) (xy 359.606537 -101.242693) (xy 359.582865 -101.29319)
			(xy 359.552092 -101.339703) (xy 359.514875 -101.38124) (xy 359.472007 -101.416915) (xy 359.424401 -101.445969)
			(xy 359.373072 -101.467781) (xy 359.319115 -101.481887) (xy 359.263678 -101.487987) (xy 359.207944 -101.48595)
			(xy 359.153101 -101.47582) (xy 359.100317 -101.457813) (xy 359.050717 -101.432312) (xy 359.005359 -101.399861)
			(xy 358.96521 -101.361152) (xy 358.931124 -101.317009) (xy 358.903828 -101.268374) (xy 358.883905 -101.216283)
			(xy 358.871779 -101.161846) (xy 358.867708 -101.106224) (xy 358.077954 -101.106224) (xy 358.077515 -101.1303)
			(xy 358.069395 -101.185476) (xy 358.053327 -101.238883) (xy 358.029655 -101.28938) (xy 357.998882 -101.335893)
			(xy 357.961665 -101.37743) (xy 357.918797 -101.413105) (xy 357.871191 -101.442159) (xy 357.819862 -101.463971)
			(xy 357.765905 -101.478077) (xy 357.710468 -101.484177) (xy 357.654734 -101.48214) (xy 357.599891 -101.47201)
			(xy 357.547107 -101.454003) (xy 357.497507 -101.428502) (xy 357.452149 -101.396051) (xy 357.412 -101.357342)
			(xy 357.377914 -101.313199) (xy 357.350618 -101.264564) (xy 357.330695 -101.212473) (xy 357.318569 -101.158036)
			(xy 357.314498 -101.102414) (xy 355.837591 -101.102414) (xy 355.82625 -101.127248) (xy 355.796789 -101.173093)
			(xy 355.761103 -101.214279) (xy 355.71992 -101.249968) (xy 355.674078 -101.279433) (xy 355.624508 -101.302075)
			(xy 355.572222 -101.317432) (xy 355.518282 -101.325191) (xy 355.491034 -101.32568) (xy 355.461908 -101.325124)
			(xy 355.404336 -101.31626) (xy 355.348779 -101.298749) (xy 355.296529 -101.272997) (xy 355.2488 -101.239603)
			(xy 355.206701 -101.199343) (xy 355.18852 -101.176582) (xy 355.180779 -101.167604) (xy 355.159469 -101.157279)
			(xy 355.147626 -101.15677) (xy 355.054154 -101.157786) (xy 355.033072 -101.168708) (xy 355.02596 -101.178614)
			(xy 355.009286 -101.200574) (xy 354.970658 -101.239916) (xy 354.926767 -101.273287) (xy 354.87853 -101.299993)
			(xy 354.826951 -101.319475) (xy 354.773104 -101.33133) (xy 354.718112 -101.335309) (xy 354.66312 -101.33133)
			(xy 354.609273 -101.319475) (xy 354.557694 -101.299993) (xy 354.509457 -101.273287) (xy 354.465566 -101.239916)
			(xy 354.426938 -101.200574) (xy 354.410264 -101.178614) (xy 354.403406 -101.169216) (xy 354.38334 -101.158548)
			(xy 354.292916 -101.15423) (xy 354.281641 -101.154275) (xy 354.260813 -101.162827) (xy 354.252784 -101.17074)
			(xy 354.25253 -101.170994) (xy 354.234358 -101.190648) (xy 354.193448 -101.22517) (xy 354.148118 -101.253637)
			(xy 354.099254 -101.275493) (xy 354.047817 -101.290309) (xy 353.994814 -101.297794) (xy 353.96805 -101.298248)
			(xy 353.940144 -101.297785) (xy 353.88493 -101.289635) (xy 353.831492 -101.273531) (xy 353.780969 -101.249817)
			(xy 353.734438 -101.218997) (xy 353.692891 -101.18173) (xy 353.67468 -101.16058) (xy 353.674426 -101.160326)
			(xy 353.666495 -101.151784) (xy 353.645188 -101.142391) (xy 353.633532 -101.142292) (xy 353.540822 -101.146102)
			(xy 353.519994 -101.157532) (xy 353.513136 -101.167184) (xy 353.497763 -101.188399) (xy 353.462178 -101.226851)
			(xy 353.421664 -101.26007) (xy 353.376984 -101.28743) (xy 353.32898 -101.308416) (xy 353.278554 -101.322633)
			(xy 353.226658 -101.329814) (xy 353.200462 -101.330252) (xy 353.173216 -101.329675) (xy 353.119278 -101.321915)
			(xy 353.066994 -101.306559) (xy 353.017428 -101.283918) (xy 352.971587 -101.254454) (xy 352.930406 -101.218767)
			(xy 352.894723 -101.177582) (xy 352.865264 -101.131739) (xy 352.842628 -101.08217) (xy 352.827277 -101.029884)
			(xy 352.819522 -100.975946) (xy 351.85858 -100.975946) (xy 351.85858 -103.529638) (xy 351.859009 -103.539706)
			(xy 351.866731 -103.558302) (xy 351.873566 -103.565706) (xy 352.42246 -104.1146) (xy 353.090224 -104.1146)
			(xy 353.094295 -104.058978) (xy 353.106421 -104.004541) (xy 353.126344 -103.95245) (xy 353.15364 -103.903815)
			(xy 353.187726 -103.859672) (xy 353.227875 -103.820963) (xy 353.273233 -103.788512) (xy 353.322833 -103.763011)
			(xy 353.375617 -103.745004) (xy 353.43046 -103.734874) (xy 353.486194 -103.732837) (xy 353.541631 -103.738937)
			(xy 353.595588 -103.753043) (xy 353.646917 -103.774855) (xy 353.694523 -103.803909) (xy 353.737391 -103.839584)
			(xy 353.774608 -103.881121) (xy 353.805381 -103.927634) (xy 353.829053 -103.978131) (xy 353.845121 -104.031538)
			(xy 353.853241 -104.086714) (xy 353.85375 -104.1146) (xy 353.853241 -104.142486) (xy 353.845121 -104.197662)
			(xy 353.829053 -104.251069) (xy 353.805381 -104.301566) (xy 353.774608 -104.348079) (xy 353.737391 -104.389616)
			(xy 353.722051 -104.402382) (xy 357.210358 -104.402382) (xy 357.214429 -104.34676) (xy 357.226555 -104.292323)
			(xy 357.246478 -104.240232) (xy 357.273774 -104.191597) (xy 357.30786 -104.147454) (xy 357.348009 -104.108745)
			(xy 357.393367 -104.076294) (xy 357.442967 -104.050793) (xy 357.495751 -104.032786) (xy 357.550594 -104.022656)
			(xy 357.606328 -104.020619) (xy 357.661765 -104.026719) (xy 357.715722 -104.040825) (xy 357.767051 -104.062637)
			(xy 357.814657 -104.091691) (xy 357.857525 -104.127366) (xy 357.894742 -104.168903) (xy 357.925515 -104.215416)
			(xy 357.949187 -104.265913) (xy 357.965255 -104.31932) (xy 357.973375 -104.374496) (xy 357.973884 -104.402382)
			(xy 357.973375 -104.430268) (xy 357.965255 -104.485444) (xy 357.949187 -104.538851) (xy 357.925515 -104.589348)
			(xy 357.894742 -104.635861) (xy 357.857525 -104.677398) (xy 357.814657 -104.713073) (xy 357.767051 -104.742127)
			(xy 357.715722 -104.763939) (xy 357.661765 -104.778045) (xy 357.606328 -104.784145) (xy 357.550594 -104.782108)
			(xy 357.495751 -104.771978) (xy 357.442967 -104.753971) (xy 357.393367 -104.72847) (xy 357.348009 -104.696019)
			(xy 357.30786 -104.65731) (xy 357.273774 -104.613167) (xy 357.246478 -104.564532) (xy 357.226555 -104.512441)
			(xy 357.214429 -104.458004) (xy 357.210358 -104.402382) (xy 353.722051 -104.402382) (xy 353.694523 -104.425291)
			(xy 353.646917 -104.454345) (xy 353.595588 -104.476157) (xy 353.541631 -104.490263) (xy 353.486194 -104.496363)
			(xy 353.43046 -104.494326) (xy 353.375617 -104.484196) (xy 353.322833 -104.466189) (xy 353.273233 -104.440688)
			(xy 353.227875 -104.408237) (xy 353.187726 -104.369528) (xy 353.15364 -104.325385) (xy 353.126344 -104.27675)
			(xy 353.106421 -104.224659) (xy 353.094295 -104.170222) (xy 353.090224 -104.1146) (xy 352.42246 -104.1146)
			(xy 354.389436 -106.081576) (xy 359.182922 -106.081576) (xy 359.186993 -106.025954) (xy 359.199119 -105.971517)
			(xy 359.219042 -105.919426) (xy 359.246338 -105.870791) (xy 359.280424 -105.826648) (xy 359.320573 -105.787939)
			(xy 359.365931 -105.755488) (xy 359.415531 -105.729987) (xy 359.468315 -105.71198) (xy 359.523158 -105.70185)
			(xy 359.578892 -105.699813) (xy 359.634329 -105.705913) (xy 359.688286 -105.720019) (xy 359.739615 -105.741831)
			(xy 359.787221 -105.770885) (xy 359.830089 -105.80656) (xy 359.867306 -105.848097) (xy 359.898079 -105.89461)
			(xy 359.921751 -105.945107) (xy 359.937819 -105.998514) (xy 359.945939 -106.05369) (xy 359.946448 -106.081576)
			(xy 359.945939 -106.109462) (xy 359.937819 -106.164638) (xy 359.921751 -106.218045) (xy 359.898079 -106.268542)
			(xy 359.867306 -106.315055) (xy 359.830089 -106.356592) (xy 359.787221 -106.392267) (xy 359.739615 -106.421321)
			(xy 359.688286 -106.443133) (xy 359.634329 -106.457239) (xy 359.578892 -106.463339) (xy 359.523158 -106.461302)
			(xy 359.468315 -106.451172) (xy 359.415531 -106.433165) (xy 359.365931 -106.407664) (xy 359.320573 -106.375213)
			(xy 359.280424 -106.336504) (xy 359.246338 -106.292361) (xy 359.219042 -106.243726) (xy 359.199119 -106.191635)
			(xy 359.186993 -106.137198) (xy 359.182922 -106.081576) (xy 354.389436 -106.081576) (xy 354.640896 -106.333036)
			(xy 354.65893 -106.351806) (xy 354.689514 -106.393922) (xy 354.713146 -106.440298) (xy 354.729245 -106.489795)
			(xy 354.737417 -106.5412) (xy 354.737924 -106.567224) (xy 354.737924 -107.004612) (xy 359.199178 -107.004612)
			(xy 359.203249 -106.94899) (xy 359.215375 -106.894553) (xy 359.235298 -106.842462) (xy 359.262594 -106.793827)
			(xy 359.29668 -106.749684) (xy 359.336829 -106.710975) (xy 359.382187 -106.678524) (xy 359.431787 -106.653023)
			(xy 359.484571 -106.635016) (xy 359.539414 -106.624886) (xy 359.595148 -106.622849) (xy 359.650585 -106.628949)
			(xy 359.704542 -106.643055) (xy 359.755871 -106.664867) (xy 359.803477 -106.693921) (xy 359.846345 -106.729596)
			(xy 359.883562 -106.771133) (xy 359.914335 -106.817646) (xy 359.938007 -106.868143) (xy 359.954075 -106.92155)
			(xy 359.962195 -106.976726) (xy 359.962704 -107.004612) (xy 359.962195 -107.032498) (xy 359.954075 -107.087674)
			(xy 359.938007 -107.141081) (xy 359.914335 -107.191578) (xy 359.883562 -107.238091) (xy 359.846345 -107.279628)
			(xy 359.803477 -107.315303) (xy 359.755871 -107.344357) (xy 359.704542 -107.366169) (xy 359.650585 -107.380275)
			(xy 359.595148 -107.386375) (xy 359.539414 -107.384338) (xy 359.484571 -107.374208) (xy 359.431787 -107.356201)
			(xy 359.382187 -107.3307) (xy 359.336829 -107.298249) (xy 359.29668 -107.25954) (xy 359.262594 -107.215397)
			(xy 359.235298 -107.166762) (xy 359.215375 -107.114671) (xy 359.203249 -107.060234) (xy 359.199178 -107.004612)
			(xy 354.737924 -107.004612) (xy 354.737924 -109.728508) (xy 354.737392 -109.75453) (xy 354.729217 -109.805928)
			(xy 354.713115 -109.855419) (xy 354.689482 -109.901788) (xy 354.658898 -109.943897) (xy 354.640896 -109.962696)
			(xy 352.8822 -111.721392) (xy 352.875352 -111.72879) (xy 352.867615 -111.747388) (xy 352.867214 -111.75746)
			(xy 352.867214 -114.479578) (xy 352.867652 -114.489642) (xy 352.875388 -114.508224) (xy 352.8822 -114.515646)
			(xy 353.195636 -114.829082) (xy 353.203036 -114.835925) (xy 353.221634 -114.843649) (xy 353.231704 -114.844068)
			(xy 353.814634 -114.844068) (xy 353.824701 -114.843638) (xy 353.843293 -114.835911) (xy 353.850702 -114.829082)
			(xy 361.086908 -107.592876) (xy 361.087416 -107.585764) (xy 361.087416 -104.015032) (xy 361.087162 -104.010206)
			(xy 361.086212 -104.00297) (xy 361.080809 -103.98942) (xy 361.076494 -103.983536) (xy 361.070398 -103.976932)
			(xy 361.01401 -103.92664) (xy 361.010006 -103.923245) (xy 361.000919 -103.917993) (xy 360.995976 -103.916226)
			(xy 360.985816 -103.912924) (xy 360.975148 -103.91394) (xy 360.965207 -103.914906) (xy 360.945258 -103.915923)
			(xy 360.93527 -103.915972) (xy 360.908023 -103.915484) (xy 360.854083 -103.907725) (xy 360.801797 -103.892368)
			(xy 360.752229 -103.869728) (xy 360.706386 -103.840263) (xy 360.665204 -103.804575) (xy 360.629519 -103.76339)
			(xy 360.600058 -103.717545) (xy 360.577421 -103.667975) (xy 360.562069 -103.615687) (xy 360.554314 -103.561747)
			(xy 360.554314 -103.507253) (xy 360.562069 -103.453313) (xy 360.577421 -103.401025) (xy 360.600058 -103.351455)
			(xy 360.629519 -103.30561) (xy 360.665204 -103.264425) (xy 360.706386 -103.228737) (xy 360.752229 -103.199272)
			(xy 360.801797 -103.176632) (xy 360.854083 -103.161275) (xy 360.908023 -103.153516) (xy 360.93527 -103.152956)
			(xy 360.945258 -103.153009) (xy 360.965207 -103.154028) (xy 360.975148 -103.154988) (xy 360.985816 -103.156004)
			(xy 360.995976 -103.152702) (xy 361.000932 -103.150962) (xy 361.01003 -103.145715) (xy 361.01401 -103.142288)
			(xy 361.070398 -103.091996) (xy 361.076494 -103.085392) (xy 361.080835 -103.07952) (xy 361.086263 -103.065969)
			(xy 361.087162 -103.058722) (xy 361.087416 -103.053896) (xy 361.087416 -91.769438) (xy 361.086908 -91.762326)
			(xy 357.995474 -88.670892) (xy 357.985568 -88.66759) (xy 357.959853 -88.659269) (xy 357.910892 -88.636383)
			(xy 357.865653 -88.606811) (xy 357.825045 -88.571146) (xy 357.78988 -88.530104) (xy 357.760865 -88.484506)
			(xy 357.738581 -88.435267) (xy 357.723475 -88.383375) (xy 357.715849 -88.329869) (xy 357.715312 -88.302846)
			(xy 357.715772 -88.275592) (xy 357.723524 -88.221637) (xy 357.738876 -88.169334) (xy 357.761516 -88.11975)
			(xy 357.790983 -88.073892) (xy 357.826677 -88.032696) (xy 357.867872 -87.996999) (xy 357.913727 -87.967529)
			(xy 357.96331 -87.944885) (xy 358.015611 -87.92953) (xy 358.069566 -87.921774) (xy 358.09682 -87.921338)
			(xy 358.123845 -87.92181) (xy 358.177352 -87.929446) (xy 358.229245 -87.944563) (xy 358.278483 -87.966857)
			(xy 358.324079 -87.995881) (xy 358.365118 -88.031053) (xy 358.400779 -88.071669) (xy 358.430347 -88.116915)
			(xy 358.453228 -88.165882) (xy 358.454482 -88.16975) (xy 364.03102 -88.16975) (xy 364.035091 -88.114128)
			(xy 364.047217 -88.059691) (xy 364.06714 -88.0076) (xy 364.094436 -87.958965) (xy 364.128522 -87.914822)
			(xy 364.168671 -87.876113) (xy 364.214029 -87.843662) (xy 364.263629 -87.818161) (xy 364.316413 -87.800154)
			(xy 364.371256 -87.790024) (xy 364.42699 -87.787987) (xy 364.482427 -87.794087) (xy 364.536384 -87.808193)
			(xy 364.587713 -87.830005) (xy 364.635319 -87.859059) (xy 364.678187 -87.894734) (xy 364.715404 -87.936271)
			(xy 364.746177 -87.982784) (xy 364.769849 -88.033281) (xy 364.785917 -88.086688) (xy 364.787226 -88.095582)
			(xy 365.484662 -88.095582) (xy 365.488733 -88.03996) (xy 365.500859 -87.985523) (xy 365.520782 -87.933432)
			(xy 365.548078 -87.884797) (xy 365.582164 -87.840654) (xy 365.622313 -87.801945) (xy 365.667671 -87.769494)
			(xy 365.717271 -87.743993) (xy 365.770055 -87.725986) (xy 365.824898 -87.715856) (xy 365.880632 -87.713819)
			(xy 365.936069 -87.719919) (xy 365.990026 -87.734025) (xy 366.041355 -87.755837) (xy 366.088961 -87.784891)
			(xy 366.131829 -87.820566) (xy 366.169046 -87.862103) (xy 366.199819 -87.908616) (xy 366.223491 -87.959113)
			(xy 366.239559 -88.01252) (xy 366.247679 -88.067696) (xy 366.248188 -88.095582) (xy 366.247679 -88.123468)
			(xy 366.239559 -88.178644) (xy 366.223491 -88.232051) (xy 366.199819 -88.282548) (xy 366.169046 -88.329061)
			(xy 366.144287 -88.356694) (xy 370.219222 -88.356694) (xy 370.223293 -88.301072) (xy 370.235419 -88.246635)
			(xy 370.255342 -88.194544) (xy 370.282638 -88.145909) (xy 370.316724 -88.101766) (xy 370.356873 -88.063057)
			(xy 370.402231 -88.030606) (xy 370.451831 -88.005105) (xy 370.504615 -87.987098) (xy 370.559458 -87.976968)
			(xy 370.615192 -87.974931) (xy 370.670629 -87.981031) (xy 370.724586 -87.995137) (xy 370.775915 -88.016949)
			(xy 370.823521 -88.046003) (xy 370.866389 -88.081678) (xy 370.903606 -88.123215) (xy 370.934379 -88.169728)
			(xy 370.958051 -88.220225) (xy 370.965561 -88.245188) (xy 384.894834 -88.245188) (xy 384.898905 -88.189566)
			(xy 384.911031 -88.135129) (xy 384.930954 -88.083038) (xy 384.95825 -88.034403) (xy 384.992336 -87.99026)
			(xy 385.032485 -87.951551) (xy 385.077843 -87.9191) (xy 385.127443 -87.893599) (xy 385.180227 -87.875592)
			(xy 385.23507 -87.865462) (xy 385.290804 -87.863425) (xy 385.346241 -87.869525) (xy 385.400198 -87.883631)
			(xy 385.451527 -87.905443) (xy 385.499133 -87.934497) (xy 385.542001 -87.970172) (xy 385.579218 -88.011709)
			(xy 385.609991 -88.058222) (xy 385.633663 -88.108719) (xy 385.649731 -88.162126) (xy 385.656759 -88.209882)
			(xy 393.616432 -88.209882) (xy 393.620503 -88.15426) (xy 393.632629 -88.099823) (xy 393.652552 -88.047732)
			(xy 393.679848 -87.999097) (xy 393.713934 -87.954954) (xy 393.754083 -87.916245) (xy 393.799441 -87.883794)
			(xy 393.849041 -87.858293) (xy 393.901825 -87.840286) (xy 393.956668 -87.830156) (xy 394.012402 -87.828119)
			(xy 394.067839 -87.834219) (xy 394.121796 -87.848325) (xy 394.173125 -87.870137) (xy 394.220731 -87.899191)
			(xy 394.263599 -87.934866) (xy 394.300816 -87.976403) (xy 394.331589 -88.022916) (xy 394.355261 -88.073413)
			(xy 394.371329 -88.12682) (xy 394.379449 -88.181996) (xy 394.379958 -88.209882) (xy 394.379449 -88.237768)
			(xy 394.371329 -88.292944) (xy 394.355261 -88.346351) (xy 394.331589 -88.396848) (xy 394.300816 -88.443361)
			(xy 394.263599 -88.484898) (xy 394.220731 -88.520573) (xy 394.173125 -88.549627) (xy 394.121796 -88.571439)
			(xy 394.067839 -88.585545) (xy 394.012402 -88.591645) (xy 393.956668 -88.589608) (xy 393.901825 -88.579478)
			(xy 393.849041 -88.561471) (xy 393.799441 -88.53597) (xy 393.754083 -88.503519) (xy 393.713934 -88.46481)
			(xy 393.679848 -88.420667) (xy 393.652552 -88.372032) (xy 393.632629 -88.319941) (xy 393.620503 -88.265504)
			(xy 393.616432 -88.209882) (xy 385.656759 -88.209882) (xy 385.657851 -88.217302) (xy 385.65836 -88.245188)
			(xy 385.657851 -88.273074) (xy 385.649731 -88.32825) (xy 385.633663 -88.381657) (xy 385.609991 -88.432154)
			(xy 385.579218 -88.478667) (xy 385.542001 -88.520204) (xy 385.499133 -88.555879) (xy 385.451527 -88.584933)
			(xy 385.400198 -88.606745) (xy 385.346241 -88.620851) (xy 385.290804 -88.626951) (xy 385.23507 -88.624914)
			(xy 385.180227 -88.614784) (xy 385.127443 -88.596777) (xy 385.077843 -88.571276) (xy 385.032485 -88.538825)
			(xy 384.992336 -88.500116) (xy 384.95825 -88.455973) (xy 384.930954 -88.407338) (xy 384.911031 -88.355247)
			(xy 384.898905 -88.30081) (xy 384.894834 -88.245188) (xy 370.965561 -88.245188) (xy 370.974119 -88.273632)
			(xy 370.982239 -88.328808) (xy 370.982748 -88.356694) (xy 370.982239 -88.38458) (xy 370.974119 -88.439756)
			(xy 370.958051 -88.493163) (xy 370.934379 -88.54366) (xy 370.903606 -88.590173) (xy 370.866389 -88.63171)
			(xy 370.823521 -88.667385) (xy 370.775915 -88.696439) (xy 370.724586 -88.718251) (xy 370.670629 -88.732357)
			(xy 370.615192 -88.738457) (xy 370.559458 -88.73642) (xy 370.504615 -88.72629) (xy 370.451831 -88.708283)
			(xy 370.402231 -88.682782) (xy 370.356873 -88.650331) (xy 370.316724 -88.611622) (xy 370.282638 -88.567479)
			(xy 370.255342 -88.518844) (xy 370.235419 -88.466753) (xy 370.223293 -88.412316) (xy 370.219222 -88.356694)
			(xy 366.144287 -88.356694) (xy 366.131829 -88.370598) (xy 366.088961 -88.406273) (xy 366.041355 -88.435327)
			(xy 365.990026 -88.457139) (xy 365.936069 -88.471245) (xy 365.880632 -88.477345) (xy 365.824898 -88.475308)
			(xy 365.770055 -88.465178) (xy 365.717271 -88.447171) (xy 365.667671 -88.42167) (xy 365.622313 -88.389219)
			(xy 365.582164 -88.35051) (xy 365.548078 -88.306367) (xy 365.520782 -88.257732) (xy 365.500859 -88.205641)
			(xy 365.488733 -88.151204) (xy 365.484662 -88.095582) (xy 364.787226 -88.095582) (xy 364.794037 -88.141864)
			(xy 364.794546 -88.16975) (xy 364.794037 -88.197636) (xy 364.785917 -88.252812) (xy 364.769849 -88.306219)
			(xy 364.746177 -88.356716) (xy 364.715404 -88.403229) (xy 364.678187 -88.444766) (xy 364.635319 -88.480441)
			(xy 364.587713 -88.509495) (xy 364.536384 -88.531307) (xy 364.482427 -88.545413) (xy 364.42699 -88.551513)
			(xy 364.371256 -88.549476) (xy 364.316413 -88.539346) (xy 364.263629 -88.521339) (xy 364.214029 -88.495838)
			(xy 364.168671 -88.463387) (xy 364.128522 -88.424678) (xy 364.094436 -88.380535) (xy 364.06714 -88.3319)
			(xy 364.047217 -88.279809) (xy 364.035091 -88.225372) (xy 364.03102 -88.16975) (xy 358.454482 -88.16975)
			(xy 358.461564 -88.191594) (xy 358.464866 -88.2015) (xy 359.261664 -88.998298) (xy 365.306608 -88.998298)
			(xy 365.310679 -88.942676) (xy 365.322805 -88.888239) (xy 365.342728 -88.836148) (xy 365.370024 -88.787513)
			(xy 365.40411 -88.74337) (xy 365.444259 -88.704661) (xy 365.489617 -88.67221) (xy 365.539217 -88.646709)
			(xy 365.592001 -88.628702) (xy 365.646844 -88.618572) (xy 365.702578 -88.616535) (xy 365.758015 -88.622635)
			(xy 365.811972 -88.636741) (xy 365.863301 -88.658553) (xy 365.910907 -88.687607) (xy 365.953775 -88.723282)
			(xy 365.984895 -88.758014) (xy 367.55578 -88.758014) (xy 367.556266 -88.730763) (xy 367.564022 -88.676815)
			(xy 367.579377 -88.62452) (xy 367.602019 -88.574943) (xy 367.631485 -88.529093) (xy 367.667176 -88.487902)
			(xy 367.708367 -88.452211) (xy 367.754217 -88.422745) (xy 367.803794 -88.400103) (xy 367.856089 -88.384748)
			(xy 367.910037 -88.376992) (xy 367.964539 -88.376992) (xy 368.018487 -88.384748) (xy 368.070782 -88.400103)
			(xy 368.120359 -88.422745) (xy 368.166209 -88.452211) (xy 368.2074 -88.487902) (xy 368.243091 -88.529093)
			(xy 368.272557 -88.574943) (xy 368.295199 -88.62452) (xy 368.310554 -88.676815) (xy 368.31831 -88.730763)
			(xy 368.318796 -88.758014) (xy 368.318796 -88.758268) (xy 368.318301 -88.785979) (xy 368.312775 -88.8238)
			(xy 374.915428 -88.8238) (xy 374.919499 -88.768178) (xy 374.931625 -88.713741) (xy 374.951548 -88.66165)
			(xy 374.978844 -88.613015) (xy 375.01293 -88.568872) (xy 375.053079 -88.530163) (xy 375.098437 -88.497712)
			(xy 375.148037 -88.472211) (xy 375.200821 -88.454204) (xy 375.255664 -88.444074) (xy 375.311398 -88.442037)
			(xy 375.366835 -88.448137) (xy 375.420792 -88.462243) (xy 375.472121 -88.484055) (xy 375.519727 -88.513109)
			(xy 375.562595 -88.548784) (xy 375.599812 -88.590321) (xy 375.630585 -88.636834) (xy 375.654257 -88.687331)
			(xy 375.670325 -88.740738) (xy 375.678445 -88.795914) (xy 375.678954 -88.8238) (xy 377.153422 -88.8238)
			(xy 377.157493 -88.768178) (xy 377.169619 -88.713741) (xy 377.189542 -88.66165) (xy 377.216838 -88.613015)
			(xy 377.250924 -88.568872) (xy 377.291073 -88.530163) (xy 377.336431 -88.497712) (xy 377.386031 -88.472211)
			(xy 377.438815 -88.454204) (xy 377.493658 -88.444074) (xy 377.549392 -88.442037) (xy 377.604829 -88.448137)
			(xy 377.658786 -88.462243) (xy 377.710115 -88.484055) (xy 377.757721 -88.513109) (xy 377.800589 -88.548784)
			(xy 377.837806 -88.590321) (xy 377.868579 -88.636834) (xy 377.892251 -88.687331) (xy 377.908319 -88.740738)
			(xy 377.916439 -88.795914) (xy 377.91686 -88.818974) (xy 379.480316 -88.818974) (xy 379.484387 -88.763352)
			(xy 379.496513 -88.708915) (xy 379.516436 -88.656824) (xy 379.543732 -88.608189) (xy 379.577818 -88.564046)
			(xy 379.617967 -88.525337) (xy 379.663325 -88.492886) (xy 379.712925 -88.467385) (xy 379.765709 -88.449378)
			(xy 379.820552 -88.439248) (xy 379.876286 -88.437211) (xy 379.931723 -88.443311) (xy 379.98568 -88.457417)
			(xy 380.037009 -88.479229) (xy 380.084615 -88.508283) (xy 380.127483 -88.543958) (xy 380.1647 -88.585495)
			(xy 380.195473 -88.632008) (xy 380.219145 -88.682505) (xy 380.235213 -88.735912) (xy 380.243333 -88.791088)
			(xy 380.243842 -88.818974) (xy 380.243333 -88.84686) (xy 380.235213 -88.902036) (xy 380.219145 -88.955443)
			(xy 380.195473 -89.00594) (xy 380.1647 -89.052453) (xy 380.127483 -89.09399) (xy 380.084615 -89.129665)
			(xy 380.037009 -89.158719) (xy 379.98568 -89.180531) (xy 379.931723 -89.194637) (xy 379.876286 -89.200737)
			(xy 379.820552 -89.1987) (xy 379.765709 -89.18857) (xy 379.712925 -89.170563) (xy 379.663325 -89.145062)
			(xy 379.617967 -89.112611) (xy 379.577818 -89.073902) (xy 379.543732 -89.029759) (xy 379.516436 -88.981124)
			(xy 379.496513 -88.929033) (xy 379.484387 -88.874596) (xy 379.480316 -88.818974) (xy 377.91686 -88.818974)
			(xy 377.916948 -88.8238) (xy 377.916439 -88.851686) (xy 377.908319 -88.906862) (xy 377.892251 -88.960269)
			(xy 377.868579 -89.010766) (xy 377.837806 -89.057279) (xy 377.800589 -89.098816) (xy 377.757721 -89.134491)
			(xy 377.710115 -89.163545) (xy 377.658786 -89.185357) (xy 377.604829 -89.199463) (xy 377.549392 -89.205563)
			(xy 377.493658 -89.203526) (xy 377.438815 -89.193396) (xy 377.386031 -89.175389) (xy 377.336431 -89.149888)
			(xy 377.291073 -89.117437) (xy 377.250924 -89.078728) (xy 377.216838 -89.034585) (xy 377.189542 -88.98595)
			(xy 377.169619 -88.933859) (xy 377.157493 -88.879422) (xy 377.153422 -88.8238) (xy 375.678954 -88.8238)
			(xy 375.678445 -88.851686) (xy 375.670325 -88.906862) (xy 375.654257 -88.960269) (xy 375.630585 -89.010766)
			(xy 375.599812 -89.057279) (xy 375.562595 -89.098816) (xy 375.519727 -89.134491) (xy 375.472121 -89.163545)
			(xy 375.420792 -89.185357) (xy 375.366835 -89.199463) (xy 375.311398 -89.205563) (xy 375.255664 -89.203526)
			(xy 375.200821 -89.193396) (xy 375.148037 -89.175389) (xy 375.098437 -89.149888) (xy 375.053079 -89.117437)
			(xy 375.01293 -89.078728) (xy 374.978844 -89.034585) (xy 374.951548 -88.98595) (xy 374.931625 -88.933859)
			(xy 374.919499 -88.879422) (xy 374.915428 -88.8238) (xy 368.312775 -88.8238) (xy 368.310288 -88.840817)
			(xy 368.294412 -88.893916) (xy 368.271008 -88.944153) (xy 368.240571 -88.990467) (xy 368.22253 -89.011506)
			(xy 368.214656 -89.020142) (xy 368.208306 -89.041986) (xy 368.223292 -89.131394) (xy 368.225638 -89.142656)
			(xy 368.238891 -89.161436) (xy 368.248692 -89.167462) (xy 368.273516 -89.182113) (xy 368.318894 -89.217652)
			(xy 368.358408 -89.259615) (xy 368.391156 -89.307046) (xy 368.416393 -89.358866) (xy 368.433545 -89.413893)
			(xy 368.44222 -89.470875) (xy 368.442748 -89.499694) (xy 370.219222 -89.499694) (xy 370.223293 -89.444072)
			(xy 370.235419 -89.389635) (xy 370.255342 -89.337544) (xy 370.282638 -89.288909) (xy 370.316724 -89.244766)
			(xy 370.356873 -89.206057) (xy 370.402231 -89.173606) (xy 370.451831 -89.148105) (xy 370.504615 -89.130098)
			(xy 370.559458 -89.119968) (xy 370.615192 -89.117931) (xy 370.670629 -89.124031) (xy 370.724586 -89.138137)
			(xy 370.775915 -89.159949) (xy 370.823521 -89.189003) (xy 370.866389 -89.224678) (xy 370.903606 -89.266215)
			(xy 370.934379 -89.312728) (xy 370.958051 -89.363225) (xy 370.974119 -89.416632) (xy 370.982239 -89.471808)
			(xy 370.982748 -89.499694) (xy 370.982739 -89.500202) (xy 392.158218 -89.500202) (xy 392.162289 -89.44458)
			(xy 392.174415 -89.390143) (xy 392.194338 -89.338052) (xy 392.221634 -89.289417) (xy 392.25572 -89.245274)
			(xy 392.295869 -89.206565) (xy 392.341227 -89.174114) (xy 392.390827 -89.148613) (xy 392.443611 -89.130606)
			(xy 392.498454 -89.120476) (xy 392.554188 -89.118439) (xy 392.609625 -89.124539) (xy 392.663582 -89.138645)
			(xy 392.714911 -89.160457) (xy 392.762517 -89.189511) (xy 392.805385 -89.225186) (xy 392.842602 -89.266723)
			(xy 392.873375 -89.313236) (xy 392.897047 -89.363733) (xy 392.913115 -89.41714) (xy 392.921235 -89.472316)
			(xy 392.921744 -89.500202) (xy 396.84274 -89.500202) (xy 396.846811 -89.44458) (xy 396.858937 -89.390143)
			(xy 396.87886 -89.338052) (xy 396.906156 -89.289417) (xy 396.940242 -89.245274) (xy 396.980391 -89.206565)
			(xy 397.025749 -89.174114) (xy 397.075349 -89.148613) (xy 397.128133 -89.130606) (xy 397.182976 -89.120476)
			(xy 397.23871 -89.118439) (xy 397.294147 -89.124539) (xy 397.348104 -89.138645) (xy 397.399433 -89.160457)
			(xy 397.447039 -89.189511) (xy 397.489907 -89.225186) (xy 397.527124 -89.266723) (xy 397.557897 -89.313236)
			(xy 397.581569 -89.363733) (xy 397.597637 -89.41714) (xy 397.605757 -89.472316) (xy 397.606266 -89.500202)
			(xy 397.605757 -89.528088) (xy 397.597637 -89.583264) (xy 397.581569 -89.636671) (xy 397.557897 -89.687168)
			(xy 397.527124 -89.733681) (xy 397.489907 -89.775218) (xy 397.447039 -89.810893) (xy 397.399433 -89.839947)
			(xy 397.348104 -89.861759) (xy 397.294147 -89.875865) (xy 397.23871 -89.881965) (xy 397.182976 -89.879928)
			(xy 397.128133 -89.869798) (xy 397.075349 -89.851791) (xy 397.025749 -89.82629) (xy 396.980391 -89.793839)
			(xy 396.940242 -89.75513) (xy 396.906156 -89.710987) (xy 396.87886 -89.662352) (xy 396.858937 -89.610261)
			(xy 396.846811 -89.555824) (xy 396.84274 -89.500202) (xy 392.921744 -89.500202) (xy 392.921235 -89.528088)
			(xy 392.913115 -89.583264) (xy 392.897047 -89.636671) (xy 392.873375 -89.687168) (xy 392.842602 -89.733681)
			(xy 392.805385 -89.775218) (xy 392.762517 -89.810893) (xy 392.714911 -89.839947) (xy 392.663582 -89.861759)
			(xy 392.609625 -89.875865) (xy 392.554188 -89.881965) (xy 392.498454 -89.879928) (xy 392.443611 -89.869798)
			(xy 392.390827 -89.851791) (xy 392.341227 -89.82629) (xy 392.295869 -89.793839) (xy 392.25572 -89.75513)
			(xy 392.221634 -89.710987) (xy 392.194338 -89.662352) (xy 392.174415 -89.610261) (xy 392.162289 -89.555824)
			(xy 392.158218 -89.500202) (xy 370.982739 -89.500202) (xy 370.982239 -89.52758) (xy 370.974119 -89.582756)
			(xy 370.958051 -89.636163) (xy 370.934379 -89.68666) (xy 370.903606 -89.733173) (xy 370.866389 -89.77471)
			(xy 370.823521 -89.810385) (xy 370.775915 -89.839439) (xy 370.724586 -89.861251) (xy 370.670629 -89.875357)
			(xy 370.615192 -89.881457) (xy 370.559458 -89.87942) (xy 370.504615 -89.86929) (xy 370.451831 -89.851283)
			(xy 370.402231 -89.825782) (xy 370.356873 -89.793331) (xy 370.316724 -89.754622) (xy 370.282638 -89.710479)
			(xy 370.255342 -89.661844) (xy 370.235419 -89.609753) (xy 370.223293 -89.555316) (xy 370.219222 -89.499694)
			(xy 368.442748 -89.499694) (xy 368.442262 -89.526945) (xy 368.434506 -89.580893) (xy 368.419151 -89.633188)
			(xy 368.396509 -89.682765) (xy 368.367043 -89.728615) (xy 368.331352 -89.769806) (xy 368.290161 -89.805497)
			(xy 368.244311 -89.834963) (xy 368.194734 -89.857605) (xy 368.142439 -89.87296) (xy 368.088491 -89.880716)
			(xy 368.033989 -89.880716) (xy 367.980041 -89.87296) (xy 367.927746 -89.857605) (xy 367.878169 -89.834963)
			(xy 367.832319 -89.805497) (xy 367.791128 -89.769806) (xy 367.755437 -89.728615) (xy 367.725971 -89.682765)
			(xy 367.703329 -89.633188) (xy 367.687974 -89.580893) (xy 367.680218 -89.526945) (xy 367.679732 -89.499694)
			(xy 367.679732 -89.49944) (xy 367.680225 -89.471729) (xy 367.688237 -89.41689) (xy 367.704113 -89.363792)
			(xy 367.727518 -89.313555) (xy 367.757956 -89.26724) (xy 367.775998 -89.246202) (xy 367.783872 -89.237566)
			(xy 367.790222 -89.215722) (xy 367.775236 -89.126314) (xy 367.772874 -89.115057) (xy 367.759632 -89.096276)
			(xy 367.749836 -89.090246) (xy 367.724978 -89.075649) (xy 367.679598 -89.040103) (xy 367.640085 -88.998132)
			(xy 367.60734 -88.950691) (xy 367.582108 -88.898862) (xy 367.564965 -88.843826) (xy 367.556302 -88.786836)
			(xy 367.55578 -88.758014) (xy 365.984895 -88.758014) (xy 365.990992 -88.764819) (xy 366.021765 -88.811332)
			(xy 366.045437 -88.861829) (xy 366.061505 -88.915236) (xy 366.069625 -88.970412) (xy 366.070134 -88.998298)
			(xy 366.069625 -89.026184) (xy 366.061505 -89.08136) (xy 366.045437 -89.134767) (xy 366.021765 -89.185264)
			(xy 365.990992 -89.231777) (xy 365.953775 -89.273314) (xy 365.910907 -89.308989) (xy 365.863301 -89.338043)
			(xy 365.811972 -89.359855) (xy 365.758015 -89.373961) (xy 365.702578 -89.380061) (xy 365.646844 -89.378024)
			(xy 365.592001 -89.367894) (xy 365.539217 -89.349887) (xy 365.489617 -89.324386) (xy 365.444259 -89.291935)
			(xy 365.40411 -89.253226) (xy 365.370024 -89.209083) (xy 365.342728 -89.160448) (xy 365.322805 -89.108357)
			(xy 365.310679 -89.05392) (xy 365.306608 -88.998298) (xy 359.261664 -88.998298) (xy 359.76306 -89.499694)
			(xy 364.315754 -89.499694) (xy 364.319825 -89.444072) (xy 364.331951 -89.389635) (xy 364.351874 -89.337544)
			(xy 364.37917 -89.288909) (xy 364.413256 -89.244766) (xy 364.453405 -89.206057) (xy 364.498763 -89.173606)
			(xy 364.548363 -89.148105) (xy 364.601147 -89.130098) (xy 364.65599 -89.119968) (xy 364.711724 -89.117931)
			(xy 364.767161 -89.124031) (xy 364.821118 -89.138137) (xy 364.872447 -89.159949) (xy 364.920053 -89.189003)
			(xy 364.962921 -89.224678) (xy 365.000138 -89.266215) (xy 365.030911 -89.312728) (xy 365.054583 -89.363225)
			(xy 365.070651 -89.416632) (xy 365.078771 -89.471808) (xy 365.07928 -89.499694) (xy 365.078771 -89.52758)
			(xy 365.070651 -89.582756) (xy 365.054583 -89.636163) (xy 365.030911 -89.68666) (xy 365.000138 -89.733173)
			(xy 364.962921 -89.77471) (xy 364.920053 -89.810385) (xy 364.872447 -89.839439) (xy 364.821118 -89.861251)
			(xy 364.767161 -89.875357) (xy 364.711724 -89.881457) (xy 364.65599 -89.87942) (xy 364.601147 -89.86929)
			(xy 364.548363 -89.851283) (xy 364.498763 -89.825782) (xy 364.453405 -89.793331) (xy 364.413256 -89.754622)
			(xy 364.37917 -89.710479) (xy 364.351874 -89.661844) (xy 364.331951 -89.609753) (xy 364.319825 -89.555316)
			(xy 364.315754 -89.499694) (xy 359.76306 -89.499694) (xy 360.410252 -90.146886) (xy 365.677702 -90.146886)
			(xy 365.681773 -90.091264) (xy 365.693899 -90.036827) (xy 365.713822 -89.984736) (xy 365.741118 -89.936101)
			(xy 365.775204 -89.891958) (xy 365.815353 -89.853249) (xy 365.860711 -89.820798) (xy 365.910311 -89.795297)
			(xy 365.963095 -89.77729) (xy 366.017938 -89.76716) (xy 366.073672 -89.765123) (xy 366.129109 -89.771223)
			(xy 366.183066 -89.785329) (xy 366.234395 -89.807141) (xy 366.282001 -89.836195) (xy 366.324869 -89.87187)
			(xy 366.362086 -89.913407) (xy 366.392859 -89.95992) (xy 366.396084 -89.9668) (xy 374.915428 -89.9668)
			(xy 374.919499 -89.911178) (xy 374.931625 -89.856741) (xy 374.951548 -89.80465) (xy 374.978844 -89.756015)
			(xy 375.01293 -89.711872) (xy 375.053079 -89.673163) (xy 375.098437 -89.640712) (xy 375.148037 -89.615211)
			(xy 375.200821 -89.597204) (xy 375.255664 -89.587074) (xy 375.311398 -89.585037) (xy 375.366835 -89.591137)
			(xy 375.420792 -89.605243) (xy 375.472121 -89.627055) (xy 375.519727 -89.656109) (xy 375.562595 -89.691784)
			(xy 375.599812 -89.733321) (xy 375.630585 -89.779834) (xy 375.654257 -89.830331) (xy 375.670325 -89.883738)
			(xy 375.67511 -89.916254) (xy 380.577088 -89.916254) (xy 380.581159 -89.860632) (xy 380.593285 -89.806195)
			(xy 380.613208 -89.754104) (xy 380.640504 -89.705469) (xy 380.67459 -89.661326) (xy 380.714739 -89.622617)
			(xy 380.760097 -89.590166) (xy 380.809697 -89.564665) (xy 380.862481 -89.546658) (xy 380.917324 -89.536528)
			(xy 380.973058 -89.534491) (xy 381.028495 -89.540591) (xy 381.082452 -89.554697) (xy 381.133781 -89.576509)
			(xy 381.181387 -89.605563) (xy 381.224255 -89.641238) (xy 381.261472 -89.682775) (xy 381.292245 -89.729288)
			(xy 381.315917 -89.779785) (xy 381.331985 -89.833192) (xy 381.340105 -89.888368) (xy 381.340614 -89.916254)
			(xy 381.340105 -89.94414) (xy 381.331985 -89.999316) (xy 381.315917 -90.052723) (xy 381.308449 -90.068654)
			(xy 384.658868 -90.068654) (xy 384.662939 -90.013032) (xy 384.675065 -89.958595) (xy 384.694988 -89.906504)
			(xy 384.722284 -89.857869) (xy 384.75637 -89.813726) (xy 384.796519 -89.775017) (xy 384.841877 -89.742566)
			(xy 384.891477 -89.717065) (xy 384.944261 -89.699058) (xy 384.999104 -89.688928) (xy 385.054838 -89.686891)
			(xy 385.110275 -89.692991) (xy 385.164232 -89.707097) (xy 385.215561 -89.728909) (xy 385.263167 -89.757963)
			(xy 385.306035 -89.793638) (xy 385.343252 -89.835175) (xy 385.374025 -89.881688) (xy 385.397697 -89.932185)
			(xy 385.413765 -89.985592) (xy 385.421885 -90.040768) (xy 385.422171 -90.056462) (xy 390.303764 -90.056462)
			(xy 390.307835 -90.00084) (xy 390.319961 -89.946403) (xy 390.339884 -89.894312) (xy 390.36718 -89.845677)
			(xy 390.401266 -89.801534) (xy 390.441415 -89.762825) (xy 390.486773 -89.730374) (xy 390.536373 -89.704873)
			(xy 390.589157 -89.686866) (xy 390.644 -89.676736) (xy 390.699734 -89.674699) (xy 390.755171 -89.680799)
			(xy 390.809128 -89.694905) (xy 390.860457 -89.716717) (xy 390.908063 -89.745771) (xy 390.950931 -89.781446)
			(xy 390.988148 -89.822983) (xy 391.018921 -89.869496) (xy 391.042593 -89.919993) (xy 391.058661 -89.9734)
			(xy 391.066781 -90.028576) (xy 391.06729 -90.056462) (xy 391.066781 -90.084348) (xy 391.058661 -90.139524)
			(xy 391.042593 -90.192931) (xy 391.018921 -90.243428) (xy 390.988148 -90.289941) (xy 390.950931 -90.331478)
			(xy 390.908063 -90.367153) (xy 390.860457 -90.396207) (xy 390.809128 -90.418019) (xy 390.755171 -90.432125)
			(xy 390.699734 -90.438225) (xy 390.644 -90.436188) (xy 390.589157 -90.426058) (xy 390.536373 -90.408051)
			(xy 390.486773 -90.38255) (xy 390.441415 -90.350099) (xy 390.401266 -90.31139) (xy 390.36718 -90.267247)
			(xy 390.339884 -90.218612) (xy 390.319961 -90.166521) (xy 390.307835 -90.112084) (xy 390.303764 -90.056462)
			(xy 385.422171 -90.056462) (xy 385.422394 -90.068654) (xy 385.421885 -90.09654) (xy 385.413765 -90.151716)
			(xy 385.397697 -90.205123) (xy 385.374025 -90.25562) (xy 385.343252 -90.302133) (xy 385.306035 -90.34367)
			(xy 385.263167 -90.379345) (xy 385.215561 -90.408399) (xy 385.164232 -90.430211) (xy 385.110275 -90.444317)
			(xy 385.054838 -90.450417) (xy 384.999104 -90.44838) (xy 384.944261 -90.43825) (xy 384.891477 -90.420243)
			(xy 384.841877 -90.394742) (xy 384.796519 -90.362291) (xy 384.75637 -90.323582) (xy 384.722284 -90.279439)
			(xy 384.694988 -90.230804) (xy 384.675065 -90.178713) (xy 384.662939 -90.124276) (xy 384.658868 -90.068654)
			(xy 381.308449 -90.068654) (xy 381.292245 -90.10322) (xy 381.261472 -90.149733) (xy 381.224255 -90.19127)
			(xy 381.181387 -90.226945) (xy 381.133781 -90.255999) (xy 381.082452 -90.277811) (xy 381.028495 -90.291917)
			(xy 380.973058 -90.298017) (xy 380.917324 -90.29598) (xy 380.862481 -90.28585) (xy 380.809697 -90.267843)
			(xy 380.760097 -90.242342) (xy 380.714739 -90.209891) (xy 380.67459 -90.171182) (xy 380.640504 -90.127039)
			(xy 380.613208 -90.078404) (xy 380.593285 -90.026313) (xy 380.581159 -89.971876) (xy 380.577088 -89.916254)
			(xy 375.67511 -89.916254) (xy 375.678445 -89.938914) (xy 375.678954 -89.9668) (xy 375.678445 -89.994686)
			(xy 375.670325 -90.049862) (xy 375.654257 -90.103269) (xy 375.630585 -90.153766) (xy 375.599812 -90.200279)
			(xy 375.562595 -90.241816) (xy 375.519727 -90.277491) (xy 375.472121 -90.306545) (xy 375.420792 -90.328357)
			(xy 375.366835 -90.342463) (xy 375.311398 -90.348563) (xy 375.255664 -90.346526) (xy 375.200821 -90.336396)
			(xy 375.148037 -90.318389) (xy 375.098437 -90.292888) (xy 375.053079 -90.260437) (xy 375.01293 -90.221728)
			(xy 374.978844 -90.177585) (xy 374.951548 -90.12895) (xy 374.931625 -90.076859) (xy 374.919499 -90.022422)
			(xy 374.915428 -89.9668) (xy 366.396084 -89.9668) (xy 366.416531 -90.010417) (xy 366.432599 -90.063824)
			(xy 366.440719 -90.119) (xy 366.441228 -90.146886) (xy 366.440719 -90.174772) (xy 366.432599 -90.229948)
			(xy 366.416531 -90.283355) (xy 366.392859 -90.333852) (xy 366.362086 -90.380365) (xy 366.324869 -90.421902)
			(xy 366.282001 -90.457577) (xy 366.234395 -90.486631) (xy 366.183066 -90.508443) (xy 366.129109 -90.522549)
			(xy 366.073672 -90.528649) (xy 366.017938 -90.526612) (xy 365.963095 -90.516482) (xy 365.910311 -90.498475)
			(xy 365.860711 -90.472974) (xy 365.815353 -90.440523) (xy 365.775204 -90.401814) (xy 365.741118 -90.357671)
			(xy 365.713822 -90.309036) (xy 365.693899 -90.256945) (xy 365.681773 -90.202508) (xy 365.677702 -90.146886)
			(xy 360.410252 -90.146886) (xy 360.90606 -90.642694) (xy 367.679222 -90.642694) (xy 367.683293 -90.587072)
			(xy 367.695419 -90.532635) (xy 367.715342 -90.480544) (xy 367.742638 -90.431909) (xy 367.776724 -90.387766)
			(xy 367.816873 -90.349057) (xy 367.862231 -90.316606) (xy 367.911831 -90.291105) (xy 367.964615 -90.273098)
			(xy 368.019458 -90.262968) (xy 368.075192 -90.260931) (xy 368.130629 -90.267031) (xy 368.184586 -90.281137)
			(xy 368.235915 -90.302949) (xy 368.283521 -90.332003) (xy 368.326389 -90.367678) (xy 368.363606 -90.409215)
			(xy 368.394379 -90.455728) (xy 368.418051 -90.506225) (xy 368.434119 -90.559632) (xy 368.442239 -90.614808)
			(xy 368.442748 -90.642694) (xy 368.442239 -90.67058) (xy 368.434119 -90.725756) (xy 368.418051 -90.779163)
			(xy 368.394379 -90.82966) (xy 368.363606 -90.876173) (xy 368.326389 -90.91771) (xy 368.283521 -90.953385)
			(xy 368.235915 -90.982439) (xy 368.184586 -91.004251) (xy 368.130629 -91.018357) (xy 368.075192 -91.024457)
			(xy 368.019458 -91.02242) (xy 367.964615 -91.01229) (xy 367.911831 -90.994283) (xy 367.862231 -90.968782)
			(xy 367.816873 -90.936331) (xy 367.776724 -90.897622) (xy 367.742638 -90.853479) (xy 367.715342 -90.804844)
			(xy 367.695419 -90.752753) (xy 367.683293 -90.698316) (xy 367.679222 -90.642694) (xy 360.90606 -90.642694)
			(xy 361.373166 -91.1098) (xy 374.915428 -91.1098) (xy 374.919499 -91.054178) (xy 374.931625 -90.999741)
			(xy 374.951548 -90.94765) (xy 374.978844 -90.899015) (xy 375.01293 -90.854872) (xy 375.053079 -90.816163)
			(xy 375.098437 -90.783712) (xy 375.148037 -90.758211) (xy 375.200821 -90.740204) (xy 375.255664 -90.730074)
			(xy 375.311398 -90.728037) (xy 375.366835 -90.734137) (xy 375.420792 -90.748243) (xy 375.472121 -90.770055)
			(xy 375.519727 -90.799109) (xy 375.562595 -90.834784) (xy 375.599812 -90.876321) (xy 375.630585 -90.922834)
			(xy 375.654257 -90.973331) (xy 375.670325 -91.026738) (xy 375.678445 -91.081914) (xy 375.678954 -91.1098)
			(xy 379.582932 -91.1098) (xy 379.587003 -91.054178) (xy 379.599129 -90.999741) (xy 379.619052 -90.94765)
			(xy 379.646348 -90.899015) (xy 379.680434 -90.854872) (xy 379.720583 -90.816163) (xy 379.765941 -90.783712)
			(xy 379.815541 -90.758211) (xy 379.868325 -90.740204) (xy 379.923168 -90.730074) (xy 379.978902 -90.728037)
			(xy 380.034339 -90.734137) (xy 380.088296 -90.748243) (xy 380.139625 -90.770055) (xy 380.187231 -90.799109)
			(xy 380.230099 -90.834784) (xy 380.267316 -90.876321) (xy 380.298089 -90.922834) (xy 380.321761 -90.973331)
			(xy 380.337829 -91.026738) (xy 380.345949 -91.081914) (xy 380.346458 -91.1098) (xy 380.345949 -91.137686)
			(xy 380.337829 -91.192862) (xy 380.321761 -91.246269) (xy 380.298089 -91.296766) (xy 380.267316 -91.343279)
			(xy 380.230099 -91.384816) (xy 380.187231 -91.420491) (xy 380.139625 -91.449545) (xy 380.088296 -91.471357)
			(xy 380.034339 -91.485463) (xy 379.978902 -91.491563) (xy 379.923168 -91.489526) (xy 379.868325 -91.479396)
			(xy 379.815541 -91.461389) (xy 379.765941 -91.435888) (xy 379.720583 -91.403437) (xy 379.680434 -91.364728)
			(xy 379.646348 -91.320585) (xy 379.619052 -91.27195) (xy 379.599129 -91.219859) (xy 379.587003 -91.165422)
			(xy 379.582932 -91.1098) (xy 375.678954 -91.1098) (xy 375.678445 -91.137686) (xy 375.670325 -91.192862)
			(xy 375.654257 -91.246269) (xy 375.630585 -91.296766) (xy 375.599812 -91.343279) (xy 375.562595 -91.384816)
			(xy 375.519727 -91.420491) (xy 375.472121 -91.449545) (xy 375.420792 -91.471357) (xy 375.366835 -91.485463)
			(xy 375.311398 -91.491563) (xy 375.255664 -91.489526) (xy 375.200821 -91.479396) (xy 375.148037 -91.461389)
			(xy 375.098437 -91.435888) (xy 375.053079 -91.403437) (xy 375.01293 -91.364728) (xy 374.978844 -91.320585)
			(xy 374.951548 -91.27195) (xy 374.931625 -91.219859) (xy 374.919499 -91.165422) (xy 374.915428 -91.1098)
			(xy 361.373166 -91.1098) (xy 361.727496 -91.46413) (xy 361.745524 -91.482902) (xy 361.776097 -91.525021)
			(xy 361.799715 -91.571398) (xy 361.815801 -91.620894) (xy 361.823958 -91.672296) (xy 361.824524 -91.698318)
			(xy 361.824524 -92.096336) (xy 364.008414 -92.096336) (xy 364.012485 -92.040714) (xy 364.024611 -91.986277)
			(xy 364.044534 -91.934186) (xy 364.07183 -91.885551) (xy 364.105916 -91.841408) (xy 364.146065 -91.802699)
			(xy 364.191423 -91.770248) (xy 364.241023 -91.744747) (xy 364.293807 -91.72674) (xy 364.34865 -91.71661)
			(xy 364.404384 -91.714573) (xy 364.459821 -91.720673) (xy 364.513778 -91.734779) (xy 364.565107 -91.756591)
			(xy 364.612713 -91.785645) (xy 364.655581 -91.82132) (xy 364.692798 -91.862857) (xy 364.723571 -91.90937)
			(xy 364.747243 -91.959867) (xy 364.763311 -92.013274) (xy 364.771431 -92.06845) (xy 364.77194 -92.096336)
			(xy 364.771431 -92.124222) (xy 364.763311 -92.179398) (xy 364.747243 -92.232805) (xy 364.723571 -92.283302)
			(xy 364.692798 -92.329815) (xy 364.655581 -92.371352) (xy 364.612713 -92.407027) (xy 364.565107 -92.436081)
			(xy 364.513778 -92.457893) (xy 364.459821 -92.471999) (xy 364.404384 -92.478099) (xy 364.34865 -92.476062)
			(xy 364.293807 -92.465932) (xy 364.241023 -92.447925) (xy 364.191423 -92.422424) (xy 364.146065 -92.389973)
			(xy 364.105916 -92.351264) (xy 364.07183 -92.307121) (xy 364.044534 -92.258486) (xy 364.024611 -92.206395)
			(xy 364.012485 -92.151958) (xy 364.008414 -92.096336) (xy 361.824524 -92.096336) (xy 361.824524 -94.40037)
			(xy 365.065054 -94.40037) (xy 365.069125 -94.344748) (xy 365.081251 -94.290311) (xy 365.101174 -94.23822)
			(xy 365.12847 -94.189585) (xy 365.162556 -94.145442) (xy 365.202705 -94.106733) (xy 365.248063 -94.074282)
			(xy 365.297663 -94.048781) (xy 365.350447 -94.030774) (xy 365.40529 -94.020644) (xy 365.461024 -94.018607)
			(xy 365.516461 -94.024707) (xy 365.570418 -94.038813) (xy 365.621747 -94.060625) (xy 365.669353 -94.089679)
			(xy 365.712221 -94.125354) (xy 365.749438 -94.166891) (xy 365.780211 -94.213404) (xy 365.803883 -94.263901)
			(xy 365.819951 -94.317308) (xy 365.826456 -94.361508) (xy 366.046764 -94.361508) (xy 366.050835 -94.305886)
			(xy 366.062961 -94.251449) (xy 366.082884 -94.199358) (xy 366.11018 -94.150723) (xy 366.144266 -94.10658)
			(xy 366.184415 -94.067871) (xy 366.229773 -94.03542) (xy 366.279373 -94.009919) (xy 366.332157 -93.991912)
			(xy 366.387 -93.981782) (xy 366.442734 -93.979745) (xy 366.498171 -93.985845) (xy 366.552128 -93.999951)
			(xy 366.603457 -94.021763) (xy 366.651063 -94.050817) (xy 366.693931 -94.086492) (xy 366.731148 -94.128029)
			(xy 366.761921 -94.174542) (xy 366.785593 -94.225039) (xy 366.801661 -94.278446) (xy 366.809781 -94.333622)
			(xy 366.81029 -94.361508) (xy 366.809781 -94.389394) (xy 366.801661 -94.44457) (xy 366.785593 -94.497977)
			(xy 366.761921 -94.548474) (xy 366.731148 -94.594987) (xy 366.693931 -94.636524) (xy 366.651063 -94.672199)
			(xy 366.603457 -94.701253) (xy 366.552128 -94.723065) (xy 366.498171 -94.737171) (xy 366.442734 -94.743271)
			(xy 366.387 -94.741234) (xy 366.332157 -94.731104) (xy 366.279373 -94.713097) (xy 366.229773 -94.687596)
			(xy 366.184415 -94.655145) (xy 366.144266 -94.616436) (xy 366.11018 -94.572293) (xy 366.082884 -94.523658)
			(xy 366.062961 -94.471567) (xy 366.050835 -94.41713) (xy 366.046764 -94.361508) (xy 365.826456 -94.361508)
			(xy 365.828071 -94.372484) (xy 365.82858 -94.40037) (xy 365.828071 -94.428256) (xy 365.819951 -94.483432)
			(xy 365.803883 -94.536839) (xy 365.780211 -94.587336) (xy 365.749438 -94.633849) (xy 365.712221 -94.675386)
			(xy 365.669353 -94.711061) (xy 365.621747 -94.740115) (xy 365.570418 -94.761927) (xy 365.516461 -94.776033)
			(xy 365.461024 -94.782133) (xy 365.40529 -94.780096) (xy 365.350447 -94.769966) (xy 365.297663 -94.751959)
			(xy 365.248063 -94.726458) (xy 365.202705 -94.694007) (xy 365.162556 -94.655298) (xy 365.12847 -94.611155)
			(xy 365.101174 -94.56252) (xy 365.081251 -94.510429) (xy 365.069125 -94.455992) (xy 365.065054 -94.40037)
			(xy 361.824524 -94.40037) (xy 361.824524 -97.217738) (xy 365.510824 -97.217738) (xy 365.514895 -97.162116)
			(xy 365.527021 -97.107679) (xy 365.546944 -97.055588) (xy 365.57424 -97.006953) (xy 365.608326 -96.96281)
			(xy 365.648475 -96.924101) (xy 365.693833 -96.89165) (xy 365.743433 -96.866149) (xy 365.796217 -96.848142)
			(xy 365.85106 -96.838012) (xy 365.906794 -96.835975) (xy 365.962231 -96.842075) (xy 366.016188 -96.856181)
			(xy 366.067517 -96.877993) (xy 366.115123 -96.907047) (xy 366.157991 -96.942722) (xy 366.195208 -96.984259)
			(xy 366.225981 -97.030772) (xy 366.249653 -97.081269) (xy 366.265721 -97.134676) (xy 366.273841 -97.189852)
			(xy 366.27435 -97.217738) (xy 366.273841 -97.245624) (xy 366.265721 -97.3008) (xy 366.249653 -97.354207)
			(xy 366.225981 -97.404704) (xy 366.195208 -97.451217) (xy 366.157991 -97.492754) (xy 366.115123 -97.528429)
			(xy 366.067517 -97.557483) (xy 366.016188 -97.579295) (xy 365.962231 -97.593401) (xy 365.906794 -97.599501)
			(xy 365.85106 -97.597464) (xy 365.796217 -97.587334) (xy 365.743433 -97.569327) (xy 365.693833 -97.543826)
			(xy 365.648475 -97.511375) (xy 365.608326 -97.472666) (xy 365.57424 -97.428523) (xy 365.546944 -97.379888)
			(xy 365.527021 -97.327797) (xy 365.514895 -97.27336) (xy 365.510824 -97.217738) (xy 361.824524 -97.217738)
			(xy 361.824524 -107.354116) (xy 361.824952 -107.364159) (xy 361.832664 -107.382705) (xy 361.846901 -107.396874)
			(xy 361.85602 -107.401106) (xy 361.870244 -107.407202) (xy 361.900216 -107.401106) (xy 366.913414 -102.388162)
			(xy 366.920264 -102.380766) (xy 366.927998 -102.362166) (xy 366.9284 -102.352094) (xy 366.9284 -93.160342)
			(xy 366.924336 -93.152214) (xy 366.910031 -93.124367) (xy 366.889706 -93.065158) (xy 366.879319 -93.003426)
			(xy 366.878616 -92.972128) (xy 366.878616 -92.971112) (xy 366.878616 -92.968826) (xy 366.879141 -92.944766)
			(xy 366.885516 -92.897065) (xy 366.897853 -92.850547) (xy 366.906556 -92.82811) (xy 366.906556 -92.827856)
			(xy 366.910436 -92.816521) (xy 366.908439 -92.792679) (xy 366.902746 -92.782136) (xy 366.88395 -92.754196)
			(xy 366.854486 -92.710508) (xy 366.852029 -92.707047) (xy 366.846153 -92.700922) (xy 366.842802 -92.698316)
			(xy 366.721136 -92.698316) (xy 366.713008 -92.70238) (xy 366.685083 -92.716718) (xy 366.625706 -92.73707)
			(xy 366.563797 -92.747428) (xy 366.532414 -92.7481) (xy 366.505161 -92.747638) (xy 366.45121 -92.739882)
			(xy 366.398911 -92.724528) (xy 366.34933 -92.701887) (xy 366.303477 -92.67242) (xy 366.262283 -92.636727)
			(xy 366.226589 -92.595535) (xy 366.19712 -92.549682) (xy 366.174477 -92.500102) (xy 366.159121 -92.447804)
			(xy 366.151363 -92.393853) (xy 366.151363 -92.339347) (xy 366.159121 -92.285396) (xy 366.174477 -92.233098)
			(xy 366.19712 -92.183518) (xy 366.226589 -92.137665) (xy 366.262283 -92.096473) (xy 366.303477 -92.06078)
			(xy 366.34933 -92.031313) (xy 366.398911 -92.008672) (xy 366.45121 -91.993318) (xy 366.505161 -91.985562)
			(xy 366.532414 -91.985084) (xy 366.563797 -91.985763) (xy 366.625704 -91.996121) (xy 366.685081 -92.016472)
			(xy 366.713008 -92.030804) (xy 366.721136 -92.034868) (xy 367.403634 -92.034868) (xy 367.414364 -92.034616)
			(xy 367.434125 -92.026284) (xy 367.448769 -92.010617) (xy 367.455752 -91.990341) (xy 367.453859 -91.968979)
			(xy 367.44342 -91.950247) (xy 367.43513 -91.943428) (xy 367.412072 -91.925279) (xy 367.371282 -91.883098)
			(xy 367.337428 -91.835172) (xy 367.311305 -91.782631) (xy 367.293531 -91.72671) (xy 367.284523 -91.668728)
			(xy 367.284 -91.63939) (xy 367.284486 -91.61214) (xy 367.292244 -91.558194) (xy 367.3076 -91.505901)
			(xy 367.330241 -91.456326) (xy 367.359708 -91.410477) (xy 367.395399 -91.369289) (xy 367.436589 -91.333599)
			(xy 367.482438 -91.304135) (xy 367.532014 -91.281495) (xy 367.584307 -91.266141) (xy 367.638254 -91.258385)
			(xy 367.692754 -91.258386) (xy 367.7467 -91.266143) (xy 367.798993 -91.281498) (xy 367.848569 -91.304139)
			(xy 367.894418 -91.333604) (xy 367.935607 -91.369295) (xy 367.971297 -91.410484) (xy 368.000762 -91.456333)
			(xy 368.023403 -91.505908) (xy 368.038758 -91.558202) (xy 368.046514 -91.612148) (xy 368.046514 -91.666648)
			(xy 368.038758 -91.720595) (xy 368.023404 -91.772888) (xy 368.000764 -91.822464) (xy 367.971299 -91.868313)
			(xy 367.935609 -91.909502) (xy 367.894421 -91.945193) (xy 367.848572 -91.974659) (xy 367.798997 -91.997301)
			(xy 367.746704 -92.012656) (xy 367.692758 -92.020414) (xy 367.665508 -92.020898) (xy 367.643664 -92.02039)
			(xy 367.64087 -92.02039) (xy 367.630866 -92.020883) (xy 367.612382 -92.028548) (xy 367.598237 -92.042699)
			(xy 367.590579 -92.061185) (xy 367.59007 -92.07119) (xy 367.603786 -92.1004) (xy 367.60619 -92.105068)
			(xy 367.612589 -92.113391) (xy 367.616486 -92.11691) (xy 367.632488 -92.131896) (xy 368.077496 -92.576904)
			(xy 368.095526 -92.595676) (xy 368.126102 -92.637794) (xy 368.149724 -92.68417) (xy 368.165813 -92.733667)
			(xy 368.173974 -92.785069) (xy 368.174524 -92.811092) (xy 368.174524 -93.603064) (xy 375.71629 -93.603064)
			(xy 375.720361 -93.547442) (xy 375.732487 -93.493005) (xy 375.75241 -93.440914) (xy 375.779706 -93.392279)
			(xy 375.813792 -93.348136) (xy 375.853941 -93.309427) (xy 375.899299 -93.276976) (xy 375.948899 -93.251475)
			(xy 376.001683 -93.233468) (xy 376.056526 -93.223338) (xy 376.11226 -93.221301) (xy 376.167697 -93.227401)
			(xy 376.221654 -93.241507) (xy 376.272983 -93.263319) (xy 376.320589 -93.292373) (xy 376.363457 -93.328048)
			(xy 376.400674 -93.369585) (xy 376.431447 -93.416098) (xy 376.455119 -93.466595) (xy 376.471187 -93.520002)
			(xy 376.479307 -93.575178) (xy 376.479816 -93.603064) (xy 376.479538 -93.618304) (xy 377.288042 -93.618304)
			(xy 377.292113 -93.562682) (xy 377.304239 -93.508245) (xy 377.324162 -93.456154) (xy 377.351458 -93.407519)
			(xy 377.385544 -93.363376) (xy 377.425693 -93.324667) (xy 377.471051 -93.292216) (xy 377.520651 -93.266715)
			(xy 377.573435 -93.248708) (xy 377.628278 -93.238578) (xy 377.684012 -93.236541) (xy 377.739449 -93.242641)
			(xy 377.793406 -93.256747) (xy 377.844735 -93.278559) (xy 377.892341 -93.307613) (xy 377.935209 -93.343288)
			(xy 377.972426 -93.384825) (xy 378.003199 -93.431338) (xy 378.026871 -93.481835) (xy 378.042939 -93.535242)
			(xy 378.051059 -93.590418) (xy 378.051568 -93.618304) (xy 378.051059 -93.64619) (xy 378.042939 -93.701366)
			(xy 378.026871 -93.754773) (xy 378.003199 -93.80527) (xy 377.972426 -93.851783) (xy 377.935209 -93.89332)
			(xy 377.892341 -93.928995) (xy 377.844735 -93.958049) (xy 377.793406 -93.979861) (xy 377.739449 -93.993967)
			(xy 377.684012 -94.000067) (xy 377.628278 -93.99803) (xy 377.573435 -93.9879) (xy 377.520651 -93.969893)
			(xy 377.471051 -93.944392) (xy 377.425693 -93.911941) (xy 377.385544 -93.873232) (xy 377.351458 -93.829089)
			(xy 377.324162 -93.780454) (xy 377.304239 -93.728363) (xy 377.292113 -93.673926) (xy 377.288042 -93.618304)
			(xy 376.479538 -93.618304) (xy 376.479307 -93.63095) (xy 376.471187 -93.686126) (xy 376.455119 -93.739533)
			(xy 376.431447 -93.79003) (xy 376.400674 -93.836543) (xy 376.363457 -93.87808) (xy 376.320589 -93.913755)
			(xy 376.272983 -93.942809) (xy 376.221654 -93.964621) (xy 376.167697 -93.978727) (xy 376.11226 -93.984827)
			(xy 376.056526 -93.98279) (xy 376.001683 -93.97266) (xy 375.948899 -93.954653) (xy 375.899299 -93.929152)
			(xy 375.853941 -93.896701) (xy 375.813792 -93.857992) (xy 375.779706 -93.813849) (xy 375.75241 -93.765214)
			(xy 375.732487 -93.713123) (xy 375.720361 -93.658686) (xy 375.71629 -93.603064) (xy 368.174524 -93.603064)
			(xy 368.174524 -94.665546) (xy 379.166626 -94.665546) (xy 379.170697 -94.609924) (xy 379.182823 -94.555487)
			(xy 379.202746 -94.503396) (xy 379.230042 -94.454761) (xy 379.264128 -94.410618) (xy 379.304277 -94.371909)
			(xy 379.349635 -94.339458) (xy 379.399235 -94.313957) (xy 379.452019 -94.29595) (xy 379.506862 -94.28582)
			(xy 379.562596 -94.283783) (xy 379.618033 -94.289883) (xy 379.67199 -94.303989) (xy 379.723319 -94.325801)
			(xy 379.770925 -94.354855) (xy 379.813793 -94.39053) (xy 379.85101 -94.432067) (xy 379.881783 -94.47858)
			(xy 379.905455 -94.529077) (xy 379.921523 -94.582484) (xy 379.929643 -94.63766) (xy 379.930152 -94.665546)
			(xy 379.929643 -94.693432) (xy 379.921523 -94.748608) (xy 379.905455 -94.802015) (xy 379.881783 -94.852512)
			(xy 379.85101 -94.899025) (xy 379.813793 -94.940562) (xy 379.770925 -94.976237) (xy 379.723319 -95.005291)
			(xy 379.67199 -95.027103) (xy 379.618033 -95.041209) (xy 379.562596 -95.047309) (xy 379.506862 -95.045272)
			(xy 379.452019 -95.035142) (xy 379.399235 -95.017135) (xy 379.349635 -94.991634) (xy 379.304277 -94.959183)
			(xy 379.264128 -94.920474) (xy 379.230042 -94.876331) (xy 379.202746 -94.827696) (xy 379.182823 -94.775605)
			(xy 379.170697 -94.721168) (xy 379.166626 -94.665546) (xy 368.174524 -94.665546) (xy 368.174524 -95.214948)
			(xy 395.574279 -95.214948) (xy 395.578234 -95.123111) (xy 395.590069 -95.031954) (xy 395.609696 -94.942151)
			(xy 395.63697 -94.854369) (xy 395.67169 -94.769255) (xy 395.713598 -94.687442) (xy 395.762384 -94.609534)
			(xy 395.817687 -94.536109) (xy 395.879097 -94.467709) (xy 395.946159 -94.404842) (xy 396.018378 -94.347972)
			(xy 396.095218 -94.297521) (xy 396.176111 -94.253862) (xy 396.260457 -94.217319) (xy 396.347633 -94.188162)
			(xy 396.436992 -94.166608) (xy 396.527873 -94.152814) (xy 396.619604 -94.146884) (xy 396.711505 -94.148862)
			(xy 396.802896 -94.158733) (xy 396.8931 -94.176423) (xy 396.981449 -94.201803) (xy 397.067289 -94.234683)
			(xy 397.149985 -94.274821) (xy 397.228925 -94.32192) (xy 397.303523 -94.37563) (xy 397.373229 -94.435554)
			(xy 397.437524 -94.501248) (xy 397.495935 -94.572226) (xy 397.548027 -94.647963) (xy 397.593416 -94.727898)
			(xy 397.631766 -94.811438) (xy 397.662791 -94.897966) (xy 397.686264 -94.986841) (xy 397.70201 -95.077405)
			(xy 397.709912 -95.168987) (xy 397.710406 -95.214948) (xy 397.709912 -95.260909) (xy 397.70201 -95.352491)
			(xy 397.686264 -95.443055) (xy 397.662791 -95.53193) (xy 397.631766 -95.618458) (xy 397.593416 -95.701998)
			(xy 397.548027 -95.781933) (xy 397.495935 -95.85767) (xy 397.437524 -95.928648) (xy 397.373229 -95.994342)
			(xy 397.303523 -96.054266) (xy 397.228925 -96.107976) (xy 397.149985 -96.155075) (xy 397.067289 -96.195213)
			(xy 396.981449 -96.228093) (xy 396.8931 -96.253473) (xy 396.802896 -96.271163) (xy 396.711505 -96.281034)
			(xy 396.619604 -96.283012) (xy 396.527873 -96.277082) (xy 396.436992 -96.263288) (xy 396.347633 -96.241734)
			(xy 396.260457 -96.212577) (xy 396.176111 -96.176034) (xy 396.095218 -96.132375) (xy 396.018378 -96.081924)
			(xy 395.946159 -96.025054) (xy 395.879097 -95.962187) (xy 395.817687 -95.893787) (xy 395.762384 -95.820362)
			(xy 395.713598 -95.742454) (xy 395.67169 -95.660641) (xy 395.63697 -95.575527) (xy 395.609696 -95.487745)
			(xy 395.590069 -95.397942) (xy 395.578234 -95.306785) (xy 395.574279 -95.214948) (xy 368.174524 -95.214948)
			(xy 368.174524 -99.520357) (xy 370.426625 -99.520357) (xy 370.426625 -99.465843) (xy 370.434384 -99.411884)
			(xy 370.449743 -99.359579) (xy 370.47239 -99.309992) (xy 370.501865 -99.264133) (xy 370.537566 -99.222936)
			(xy 370.578767 -99.18724) (xy 370.624629 -99.15777) (xy 370.674218 -99.135128) (xy 370.726525 -99.119775)
			(xy 370.780485 -99.112022) (xy 370.807742 -99.111562) (xy 370.834964 -99.112001) (xy 370.888857 -99.119729)
			(xy 370.941105 -99.135037) (xy 370.990648 -99.157614) (xy 371.036479 -99.187003) (xy 371.077669 -99.222605)
			(xy 371.113382 -99.2637) (xy 371.128544 -99.286314) (xy 371.137173 -99.298701) (xy 371.16016 -99.318238)
			(xy 371.187857 -99.330197) (xy 371.21784 -99.333532) (xy 371.247488 -99.327951) (xy 371.274206 -99.313941)
			(xy 371.295659 -99.292729) (xy 371.303296 -99.27971) (xy 371.317739 -99.254195) (xy 371.353158 -99.207477)
			(xy 371.39531 -99.16673) (xy 371.443202 -99.132915) (xy 371.495705 -99.106828) (xy 371.551582 -99.089084)
			(xy 371.609517 -99.0801) (xy 371.63883 -99.079558) (xy 371.666077 -99.080114) (xy 371.720017 -99.087874)
			(xy 371.772303 -99.10323) (xy 371.821872 -99.125871) (xy 371.867715 -99.155335) (xy 371.908898 -99.191023)
			(xy 371.944583 -99.232209) (xy 371.974044 -99.278054) (xy 371.996681 -99.327625) (xy 372.012033 -99.379912)
			(xy 372.019788 -99.433853) (xy 372.019788 -99.488347) (xy 372.012033 -99.542288) (xy 371.996681 -99.594575)
			(xy 371.974044 -99.644146) (xy 371.944583 -99.689991) (xy 371.908898 -99.731177) (xy 371.867715 -99.766865)
			(xy 371.821872 -99.796329) (xy 371.772303 -99.81897) (xy 371.720017 -99.834326) (xy 371.666077 -99.842086)
			(xy 371.63883 -99.842574) (xy 371.61161 -99.842064) (xy 371.557721 -99.834346) (xy 371.505476 -99.819049)
			(xy 371.455934 -99.796483) (xy 371.410102 -99.767107) (xy 371.368909 -99.731515) (xy 371.333192 -99.690431)
			(xy 371.318028 -99.667822) (xy 371.30944 -99.655403) (xy 371.286446 -99.635857) (xy 371.258739 -99.623894)
			(xy 371.228744 -99.620561) (xy 371.199087 -99.62615) (xy 371.172363 -99.640172) (xy 371.150911 -99.661399)
			(xy 371.143276 -99.674426) (xy 371.128868 -99.699962) (xy 371.093441 -99.746678) (xy 371.051282 -99.787422)
			(xy 371.003385 -99.821235) (xy 370.950877 -99.847318) (xy 370.894995 -99.865058) (xy 370.837057 -99.874038)
			(xy 370.807742 -99.874578) (xy 370.780485 -99.874178) (xy 370.726525 -99.866425) (xy 370.674218 -99.851072)
			(xy 370.624629 -99.82843) (xy 370.578767 -99.79896) (xy 370.537566 -99.763264) (xy 370.501865 -99.722067)
			(xy 370.47239 -99.676208) (xy 370.449743 -99.626621) (xy 370.434384 -99.574316) (xy 370.426625 -99.520357)
			(xy 368.174524 -99.520357) (xy 368.174524 -102.489508) (xy 368.173992 -102.51553) (xy 368.165817 -102.566928)
			(xy 368.149715 -102.616419) (xy 368.126082 -102.662788) (xy 368.095498 -102.704897) (xy 368.077496 -102.723696)
			(xy 367.61851 -103.182674) (xy 370.004338 -103.182674) (xy 370.008409 -103.127052) (xy 370.020535 -103.072615)
			(xy 370.040458 -103.020524) (xy 370.067754 -102.971889) (xy 370.10184 -102.927746) (xy 370.141989 -102.889037)
			(xy 370.187347 -102.856586) (xy 370.236947 -102.831085) (xy 370.289731 -102.813078) (xy 370.344574 -102.802948)
			(xy 370.400308 -102.800911) (xy 370.455745 -102.807011) (xy 370.509702 -102.821117) (xy 370.561031 -102.842929)
			(xy 370.608637 -102.871983) (xy 370.651505 -102.907658) (xy 370.688722 -102.949195) (xy 370.719495 -102.995708)
			(xy 370.743167 -103.046205) (xy 370.759235 -103.099612) (xy 370.767355 -103.154788) (xy 370.767864 -103.182674)
			(xy 370.767355 -103.21056) (xy 370.759235 -103.265736) (xy 370.743167 -103.319143) (xy 370.719495 -103.36964)
			(xy 370.688722 -103.416153) (xy 370.651505 -103.45769) (xy 370.608637 -103.493365) (xy 370.561031 -103.522419)
			(xy 370.509702 -103.544231) (xy 370.455745 -103.558337) (xy 370.400308 -103.564437) (xy 370.344574 -103.5624)
			(xy 370.289731 -103.55227) (xy 370.236947 -103.534263) (xy 370.187347 -103.508762) (xy 370.141989 -103.476311)
			(xy 370.10184 -103.437602) (xy 370.067754 -103.393459) (xy 370.040458 -103.344824) (xy 370.020535 -103.292733)
			(xy 370.008409 -103.238296) (xy 370.004338 -103.182674) (xy 367.61851 -103.182674) (xy 366.950478 -103.850694)
			(xy 372.568468 -103.850694) (xy 372.572539 -103.795072) (xy 372.584665 -103.740635) (xy 372.604588 -103.688544)
			(xy 372.631884 -103.639909) (xy 372.66597 -103.595766) (xy 372.706119 -103.557057) (xy 372.751477 -103.524606)
			(xy 372.801077 -103.499105) (xy 372.853861 -103.481098) (xy 372.908704 -103.470968) (xy 372.964438 -103.468931)
			(xy 373.019875 -103.475031) (xy 373.073832 -103.489137) (xy 373.125161 -103.510949) (xy 373.172767 -103.540003)
			(xy 373.215635 -103.575678) (xy 373.252852 -103.617215) (xy 373.283625 -103.663728) (xy 373.307297 -103.714225)
			(xy 373.323365 -103.767632) (xy 373.331485 -103.822808) (xy 373.331994 -103.850694) (xy 373.331485 -103.87858)
			(xy 373.323365 -103.933756) (xy 373.307297 -103.987163) (xy 373.283625 -104.03766) (xy 373.252852 -104.084173)
			(xy 373.215635 -104.12571) (xy 373.172767 -104.161385) (xy 373.125161 -104.190439) (xy 373.073832 -104.212251)
			(xy 373.019875 -104.226357) (xy 372.964438 -104.232457) (xy 372.908704 -104.23042) (xy 372.853861 -104.22029)
			(xy 372.801077 -104.202283) (xy 372.751477 -104.176782) (xy 372.706119 -104.144331) (xy 372.66597 -104.105622)
			(xy 372.631884 -104.061479) (xy 372.604588 -104.012844) (xy 372.584665 -103.960753) (xy 372.572539 -103.906316)
			(xy 372.568468 -103.850694) (xy 366.950478 -103.850694) (xy 366.030728 -104.770428) (xy 374.327926 -104.770428)
			(xy 374.331997 -104.714806) (xy 374.344123 -104.660369) (xy 374.364046 -104.608278) (xy 374.391342 -104.559643)
			(xy 374.425428 -104.5155) (xy 374.465577 -104.476791) (xy 374.510935 -104.44434) (xy 374.560535 -104.418839)
			(xy 374.613319 -104.400832) (xy 374.668162 -104.390702) (xy 374.723896 -104.388665) (xy 374.779333 -104.394765)
			(xy 374.83329 -104.408871) (xy 374.884619 -104.430683) (xy 374.932225 -104.459737) (xy 374.975093 -104.495412)
			(xy 375.01231 -104.536949) (xy 375.043083 -104.583462) (xy 375.066755 -104.633959) (xy 375.082823 -104.687366)
			(xy 375.090943 -104.742542) (xy 375.091452 -104.770428) (xy 375.090943 -104.798314) (xy 375.082823 -104.85349)
			(xy 375.066755 -104.906897) (xy 375.043083 -104.957394) (xy 375.01231 -105.003907) (xy 374.975093 -105.045444)
			(xy 374.932225 -105.081119) (xy 374.884619 -105.110173) (xy 374.83329 -105.131985) (xy 374.779333 -105.146091)
			(xy 374.723896 -105.152191) (xy 374.668162 -105.150154) (xy 374.613319 -105.140024) (xy 374.560535 -105.122017)
			(xy 374.510935 -105.096516) (xy 374.465577 -105.064065) (xy 374.425428 -105.025356) (xy 374.391342 -104.981213)
			(xy 374.364046 -104.932578) (xy 374.344123 -104.880487) (xy 374.331997 -104.82605) (xy 374.327926 -104.770428)
			(xy 366.030728 -104.770428) (xy 364.935206 -105.86593) (xy 372.880634 -105.86593) (xy 372.884705 -105.810308)
			(xy 372.896831 -105.755871) (xy 372.916754 -105.70378) (xy 372.94405 -105.655145) (xy 372.978136 -105.611002)
			(xy 373.018285 -105.572293) (xy 373.063643 -105.539842) (xy 373.113243 -105.514341) (xy 373.166027 -105.496334)
			(xy 373.22087 -105.486204) (xy 373.276604 -105.484167) (xy 373.332041 -105.490267) (xy 373.385998 -105.504373)
			(xy 373.437327 -105.526185) (xy 373.484933 -105.555239) (xy 373.527801 -105.590914) (xy 373.565018 -105.632451)
			(xy 373.595791 -105.678964) (xy 373.619463 -105.729461) (xy 373.635531 -105.782868) (xy 373.643651 -105.838044)
			(xy 373.64416 -105.86593) (xy 373.643651 -105.893816) (xy 373.635531 -105.948992) (xy 373.619463 -106.002399)
			(xy 373.595791 -106.052896) (xy 373.565018 -106.099409) (xy 373.527801 -106.140946) (xy 373.484933 -106.176621)
			(xy 373.437327 -106.205675) (xy 373.385998 -106.227487) (xy 373.332041 -106.241593) (xy 373.276604 -106.247693)
			(xy 373.22087 -106.245656) (xy 373.166027 -106.235526) (xy 373.113243 -106.217519) (xy 373.063643 -106.192018)
			(xy 373.018285 -106.159567) (xy 372.978136 -106.120858) (xy 372.94405 -106.076715) (xy 372.916754 -106.02808)
			(xy 372.896831 -105.975989) (xy 372.884705 -105.921552) (xy 372.880634 -105.86593) (xy 364.935206 -105.86593)
			(xy 363.188671 -107.612434) (xy 372.040656 -107.612434) (xy 372.044727 -107.556812) (xy 372.056853 -107.502375)
			(xy 372.076776 -107.450284) (xy 372.104072 -107.401649) (xy 372.138158 -107.357506) (xy 372.178307 -107.318797)
			(xy 372.223665 -107.286346) (xy 372.273265 -107.260845) (xy 372.326049 -107.242838) (xy 372.380892 -107.232708)
			(xy 372.436626 -107.230671) (xy 372.492063 -107.236771) (xy 372.54602 -107.250877) (xy 372.597349 -107.272689)
			(xy 372.644955 -107.301743) (xy 372.687823 -107.337418) (xy 372.72504 -107.378955) (xy 372.755813 -107.425468)
			(xy 372.779485 -107.475965) (xy 372.795553 -107.529372) (xy 372.803673 -107.584548) (xy 372.804182 -107.612434)
			(xy 372.803673 -107.64032) (xy 372.795553 -107.695496) (xy 372.779485 -107.748903) (xy 372.755813 -107.7994)
			(xy 372.72504 -107.845913) (xy 372.687823 -107.88745) (xy 372.644955 -107.923125) (xy 372.597349 -107.952179)
			(xy 372.54602 -107.973991) (xy 372.492063 -107.988097) (xy 372.436626 -107.994197) (xy 372.380892 -107.99216)
			(xy 372.326049 -107.98203) (xy 372.273265 -107.964023) (xy 372.223665 -107.938522) (xy 372.178307 -107.906071)
			(xy 372.138158 -107.867362) (xy 372.104072 -107.823219) (xy 372.076776 -107.774584) (xy 372.056853 -107.722493)
			(xy 372.044727 -107.668056) (xy 372.040656 -107.612434) (xy 363.188671 -107.612434) (xy 361.941255 -108.859828)
			(xy 372.147844 -108.859828) (xy 372.151915 -108.804206) (xy 372.164041 -108.749769) (xy 372.183964 -108.697678)
			(xy 372.21126 -108.649043) (xy 372.245346 -108.6049) (xy 372.285495 -108.566191) (xy 372.330853 -108.53374)
			(xy 372.380453 -108.508239) (xy 372.433237 -108.490232) (xy 372.48808 -108.480102) (xy 372.543814 -108.478065)
			(xy 372.599251 -108.484165) (xy 372.653208 -108.498271) (xy 372.704537 -108.520083) (xy 372.752143 -108.549137)
			(xy 372.795011 -108.584812) (xy 372.832228 -108.626349) (xy 372.863001 -108.672862) (xy 372.886673 -108.723359)
			(xy 372.902741 -108.776766) (xy 372.910861 -108.831942) (xy 372.91137 -108.859828) (xy 372.910861 -108.887714)
			(xy 372.902741 -108.94289) (xy 372.886673 -108.996297) (xy 372.863001 -109.046794) (xy 372.832228 -109.093307)
			(xy 372.795011 -109.134844) (xy 372.752143 -109.170519) (xy 372.704537 -109.199573) (xy 372.653208 -109.221385)
			(xy 372.599251 -109.235491) (xy 372.543814 -109.241591) (xy 372.48808 -109.239554) (xy 372.433237 -109.229424)
			(xy 372.380453 -109.211417) (xy 372.330853 -109.185916) (xy 372.285495 -109.153465) (xy 372.245346 -109.114756)
			(xy 372.21126 -109.070613) (xy 372.183964 -109.021978) (xy 372.164041 -108.969887) (xy 372.151915 -108.91545)
			(xy 372.147844 -108.859828) (xy 361.941255 -108.859828) (xy 361.489381 -109.311694) (xy 364.215678 -109.311694)
			(xy 364.219749 -109.256072) (xy 364.231875 -109.201635) (xy 364.251798 -109.149544) (xy 364.279094 -109.100909)
			(xy 364.31318 -109.056766) (xy 364.353329 -109.018057) (xy 364.398687 -108.985606) (xy 364.448287 -108.960105)
			(xy 364.501071 -108.942098) (xy 364.555914 -108.931968) (xy 364.611648 -108.929931) (xy 364.667085 -108.936031)
			(xy 364.721042 -108.950137) (xy 364.772371 -108.971949) (xy 364.819977 -109.001003) (xy 364.862845 -109.036678)
			(xy 364.900062 -109.078215) (xy 364.930835 -109.124728) (xy 364.954507 -109.175225) (xy 364.970575 -109.228632)
			(xy 364.978695 -109.283808) (xy 364.979204 -109.311694) (xy 364.978695 -109.33958) (xy 364.970575 -109.394756)
			(xy 364.954507 -109.448163) (xy 364.930835 -109.49866) (xy 364.900062 -109.545173) (xy 364.862845 -109.58671)
			(xy 364.819977 -109.622385) (xy 364.772371 -109.651439) (xy 364.721042 -109.673251) (xy 364.667085 -109.687357)
			(xy 364.611648 -109.693457) (xy 364.555914 -109.69142) (xy 364.501071 -109.68129) (xy 364.448287 -109.663283)
			(xy 364.398687 -109.637782) (xy 364.353329 -109.605331) (xy 364.31318 -109.566622) (xy 364.279094 -109.522479)
			(xy 364.251798 -109.473844) (xy 364.231875 -109.421753) (xy 364.219749 -109.367316) (xy 364.215678 -109.311694)
			(xy 361.489381 -109.311694) (xy 360.790107 -110.010956) (xy 371.610126 -110.010956) (xy 371.614197 -109.955334)
			(xy 371.626323 -109.900897) (xy 371.646246 -109.848806) (xy 371.673542 -109.800171) (xy 371.707628 -109.756028)
			(xy 371.747777 -109.717319) (xy 371.793135 -109.684868) (xy 371.842735 -109.659367) (xy 371.895519 -109.64136)
			(xy 371.950362 -109.63123) (xy 372.006096 -109.629193) (xy 372.061533 -109.635293) (xy 372.11549 -109.649399)
			(xy 372.166819 -109.671211) (xy 372.214425 -109.700265) (xy 372.257293 -109.73594) (xy 372.29451 -109.777477)
			(xy 372.325283 -109.82399) (xy 372.348955 -109.874487) (xy 372.365023 -109.927894) (xy 372.373143 -109.98307)
			(xy 372.373652 -110.010956) (xy 372.373143 -110.038842) (xy 372.365023 -110.094018) (xy 372.348955 -110.147425)
			(xy 372.325283 -110.197922) (xy 372.29451 -110.244435) (xy 372.257293 -110.285972) (xy 372.214425 -110.321647)
			(xy 372.166819 -110.350701) (xy 372.11549 -110.372513) (xy 372.061533 -110.386619) (xy 372.006096 -110.392719)
			(xy 371.950362 -110.390682) (xy 371.895519 -110.380552) (xy 371.842735 -110.362545) (xy 371.793135 -110.337044)
			(xy 371.747777 -110.304593) (xy 371.707628 -110.265884) (xy 371.673542 -110.221741) (xy 371.646246 -110.173106)
			(xy 371.626323 -110.121015) (xy 371.614197 -110.066578) (xy 371.610126 -110.010956) (xy 360.790107 -110.010956)
			(xy 359.061606 -111.739426) (xy 359.765344 -111.739426) (xy 359.769415 -111.683804) (xy 359.781541 -111.629367)
			(xy 359.801464 -111.577276) (xy 359.82876 -111.528641) (xy 359.862846 -111.484498) (xy 359.902995 -111.445789)
			(xy 359.948353 -111.413338) (xy 359.997953 -111.387837) (xy 360.050737 -111.36983) (xy 360.10558 -111.3597)
			(xy 360.161314 -111.357663) (xy 360.216751 -111.363763) (xy 360.270708 -111.377869) (xy 360.322037 -111.399681)
			(xy 360.369643 -111.428735) (xy 360.412511 -111.46441) (xy 360.449728 -111.505947) (xy 360.480501 -111.55246)
			(xy 360.504173 -111.602957) (xy 360.520241 -111.656364) (xy 360.528361 -111.71154) (xy 360.52887 -111.739426)
			(xy 360.528361 -111.767312) (xy 360.520241 -111.822488) (xy 360.504173 -111.875895) (xy 360.480501 -111.926392)
			(xy 360.449728 -111.972905) (xy 360.412511 -112.014442) (xy 360.369643 -112.050117) (xy 360.322037 -112.079171)
			(xy 360.270708 -112.100983) (xy 360.216751 -112.115089) (xy 360.161314 -112.121189) (xy 360.10558 -112.119152)
			(xy 360.050737 -112.109022) (xy 359.997953 -112.091015) (xy 359.948353 -112.065514) (xy 359.902995 -112.033063)
			(xy 359.862846 -111.994354) (xy 359.82876 -111.950211) (xy 359.801464 -111.901576) (xy 359.781541 -111.849485)
			(xy 359.769415 -111.795048) (xy 359.765344 -111.739426) (xy 359.061606 -111.739426) (xy 358.260984 -112.540034)
			(xy 362.1057 -112.540034) (xy 362.109771 -112.484412) (xy 362.121897 -112.429975) (xy 362.14182 -112.377884)
			(xy 362.169116 -112.329249) (xy 362.203202 -112.285106) (xy 362.243351 -112.246397) (xy 362.288709 -112.213946)
			(xy 362.338309 -112.188445) (xy 362.391093 -112.170438) (xy 362.445936 -112.160308) (xy 362.50167 -112.158271)
			(xy 362.557107 -112.164371) (xy 362.611064 -112.178477) (xy 362.662393 -112.200289) (xy 362.709999 -112.229343)
			(xy 362.752867 -112.265018) (xy 362.790084 -112.306555) (xy 362.820857 -112.353068) (xy 362.844529 -112.403565)
			(xy 362.849823 -112.421162) (xy 364.10722 -112.421162) (xy 364.111291 -112.36554) (xy 364.123417 -112.311103)
			(xy 364.14334 -112.259012) (xy 364.170636 -112.210377) (xy 364.204722 -112.166234) (xy 364.244871 -112.127525)
			(xy 364.290229 -112.095074) (xy 364.339829 -112.069573) (xy 364.392613 -112.051566) (xy 364.447456 -112.041436)
			(xy 364.50319 -112.039399) (xy 364.558627 -112.045499) (xy 364.612584 -112.059605) (xy 364.663913 -112.081417)
			(xy 364.711519 -112.110471) (xy 364.754387 -112.146146) (xy 364.791604 -112.187683) (xy 364.822377 -112.234196)
			(xy 364.846049 -112.284693) (xy 364.862117 -112.3381) (xy 364.870237 -112.393276) (xy 364.870746 -112.421162)
			(xy 364.870237 -112.449048) (xy 364.862117 -112.504224) (xy 364.846049 -112.557631) (xy 364.822377 -112.608128)
			(xy 364.791604 -112.654641) (xy 364.754387 -112.696178) (xy 364.711519 -112.731853) (xy 364.663913 -112.760907)
			(xy 364.612584 -112.782719) (xy 364.558627 -112.796825) (xy 364.50319 -112.802925) (xy 364.447456 -112.800888)
			(xy 364.392613 -112.790758) (xy 364.339829 -112.772751) (xy 364.290229 -112.74725) (xy 364.244871 -112.714799)
			(xy 364.204722 -112.67609) (xy 364.170636 -112.631947) (xy 364.14334 -112.583312) (xy 364.123417 -112.531221)
			(xy 364.111291 -112.476784) (xy 364.10722 -112.421162) (xy 362.849823 -112.421162) (xy 362.860597 -112.456972)
			(xy 362.868717 -112.512148) (xy 362.869226 -112.540034) (xy 362.868717 -112.56792) (xy 362.860597 -112.623096)
			(xy 362.844529 -112.676503) (xy 362.820857 -112.727) (xy 362.790084 -112.773513) (xy 362.752867 -112.81505)
			(xy 362.709999 -112.850725) (xy 362.662393 -112.879779) (xy 362.611064 -112.901591) (xy 362.557107 -112.915697)
			(xy 362.50167 -112.921797) (xy 362.445936 -112.91976) (xy 362.391093 -112.90963) (xy 362.338309 -112.891623)
			(xy 362.288709 -112.866122) (xy 362.243351 -112.833671) (xy 362.203202 -112.794962) (xy 362.169116 -112.750819)
			(xy 362.14182 -112.702184) (xy 362.121897 -112.650093) (xy 362.109771 -112.595656) (xy 362.1057 -112.540034)
			(xy 358.260984 -112.540034) (xy 356.902568 -113.898426) (xy 359.753406 -113.898426) (xy 359.757477 -113.842804)
			(xy 359.769603 -113.788367) (xy 359.789526 -113.736276) (xy 359.816822 -113.687641) (xy 359.850908 -113.643498)
			(xy 359.891057 -113.604789) (xy 359.936415 -113.572338) (xy 359.986015 -113.546837) (xy 360.038799 -113.52883)
			(xy 360.093642 -113.5187) (xy 360.149376 -113.516663) (xy 360.204813 -113.522763) (xy 360.25877 -113.536869)
			(xy 360.310099 -113.558681) (xy 360.357705 -113.587735) (xy 360.400573 -113.62341) (xy 360.43779 -113.664947)
			(xy 360.468563 -113.71146) (xy 360.492235 -113.761957) (xy 360.508303 -113.815364) (xy 360.516423 -113.87054)
			(xy 360.516932 -113.898426) (xy 360.516423 -113.926312) (xy 360.508303 -113.981488) (xy 360.492235 -114.034895)
			(xy 360.468563 -114.085392) (xy 360.43779 -114.131905) (xy 360.400573 -114.173442) (xy 360.357705 -114.209117)
			(xy 360.310099 -114.238171) (xy 360.25877 -114.259983) (xy 360.204813 -114.274089) (xy 360.149376 -114.280189)
			(xy 360.093642 -114.278152) (xy 360.038799 -114.268022) (xy 359.986015 -114.250015) (xy 359.936415 -114.224514)
			(xy 359.891057 -114.192063) (xy 359.850908 -114.153354) (xy 359.816822 -114.109211) (xy 359.789526 -114.060576)
			(xy 359.769603 -114.008485) (xy 359.757477 -113.954048) (xy 359.753406 -113.898426) (xy 356.902568 -113.898426)
			(xy 353.817429 -116.98351) (xy 356.001572 -116.98351) (xy 356.005643 -116.927888) (xy 356.017769 -116.873451)
			(xy 356.037692 -116.82136) (xy 356.064988 -116.772725) (xy 356.099074 -116.728582) (xy 356.139223 -116.689873)
			(xy 356.184581 -116.657422) (xy 356.234181 -116.631921) (xy 356.286965 -116.613914) (xy 356.341808 -116.603784)
			(xy 356.397542 -116.601747) (xy 356.452979 -116.607847) (xy 356.506936 -116.621953) (xy 356.558265 -116.643765)
			(xy 356.604703 -116.672106) (xy 361.16895 -116.672106) (xy 361.169407 -116.644735) (xy 361.177225 -116.590555)
			(xy 361.192716 -116.538052) (xy 361.21556 -116.488305) (xy 361.245287 -116.442339) (xy 361.26293 -116.421408)
			(xy 361.263184 -116.421154) (xy 361.268752 -116.414055) (xy 361.27501 -116.397148) (xy 361.275376 -116.388134)
			(xy 361.275376 -116.321078) (xy 361.275035 -116.312059) (xy 361.268777 -116.295142) (xy 361.263184 -116.288058)
			(xy 361.26293 -116.288058) (xy 361.26293 -116.287804) (xy 361.245295 -116.266867) (xy 361.21557 -116.2209)
			(xy 361.192724 -116.171154) (xy 361.177227 -116.118653) (xy 361.169398 -116.064475) (xy 361.169397 -116.009734)
			(xy 361.177225 -115.955556) (xy 361.192721 -115.903054) (xy 361.215565 -115.853308) (xy 361.24529 -115.807341)
			(xy 361.26293 -115.786408) (xy 361.263184 -115.786154) (xy 361.268752 -115.779055) (xy 361.27501 -115.762148)
			(xy 361.275376 -115.753134) (xy 361.275376 -115.686078) (xy 361.275035 -115.677059) (xy 361.268777 -115.660142)
			(xy 361.263184 -115.653058) (xy 361.26293 -115.653058) (xy 361.26293 -115.652804) (xy 361.245284 -115.631877)
			(xy 361.215572 -115.585904) (xy 361.192737 -115.536155) (xy 361.177248 -115.483653) (xy 361.169422 -115.429476)
			(xy 361.16895 -115.402106) (xy 361.169483 -115.374857) (xy 361.177238 -115.320913) (xy 361.19259 -115.268622)
			(xy 361.215227 -115.219047) (xy 361.244689 -115.173199) (xy 361.280376 -115.13201) (xy 361.32156 -115.096318)
			(xy 361.367405 -115.06685) (xy 361.416977 -115.044207) (xy 361.469266 -115.028848) (xy 361.523209 -115.021087)
			(xy 361.550458 -115.020598) (xy 361.577827 -115.021089) (xy 361.632005 -115.028901) (xy 361.684508 -115.044384)
			(xy 361.734255 -115.06722) (xy 361.780223 -115.096939) (xy 361.801156 -115.114578) (xy 361.80141 -115.114832)
			(xy 361.808487 -115.120432) (xy 361.825411 -115.12667) (xy 361.83443 -115.127024) (xy 361.901486 -115.127024)
			(xy 361.910502 -115.126655) (xy 361.927418 -115.120415) (xy 361.934506 -115.114832) (xy 361.934506 -115.114578)
			(xy 361.93476 -115.114578) (xy 361.955694 -115.096941) (xy 362.001666 -115.067229) (xy 362.051413 -115.044393)
			(xy 362.103914 -115.028902) (xy 362.158089 -115.021073) (xy 362.185458 -115.020598) (xy 362.21271 -115.021094)
			(xy 362.26666 -115.028846) (xy 362.318958 -115.044197) (xy 362.368538 -115.066835) (xy 362.414392 -115.096299)
			(xy 362.455585 -115.131989) (xy 362.491279 -115.173179) (xy 362.520748 -115.21903) (xy 362.543391 -115.268608)
			(xy 362.558747 -115.320905) (xy 362.566503 -115.374854) (xy 362.566966 -115.402106) (xy 362.566512 -115.429477)
			(xy 362.558692 -115.483657) (xy 362.543201 -115.53616) (xy 362.520356 -115.585907) (xy 362.490629 -115.631873)
			(xy 362.472986 -115.652804) (xy 362.472732 -115.653058) (xy 362.467149 -115.660147) (xy 362.460902 -115.677062)
			(xy 362.46054 -115.686078) (xy 362.46054 -115.753134) (xy 362.460872 -115.762154) (xy 362.467136 -115.779071)
			(xy 362.472732 -115.786154) (xy 362.472986 -115.786154) (xy 362.472986 -115.786408) (xy 362.490632 -115.807336)
			(xy 362.520356 -115.853305) (xy 362.5432 -115.903052) (xy 362.558695 -115.955555) (xy 362.566523 -116.009734)
			(xy 362.566522 -116.064475) (xy 362.558693 -116.118654) (xy 362.543197 -116.171156) (xy 362.520351 -116.220903)
			(xy 362.490627 -116.266871) (xy 362.472986 -116.287804) (xy 362.472732 -116.288058) (xy 362.467149 -116.295147)
			(xy 362.460902 -116.312062) (xy 362.46054 -116.321078) (xy 362.46054 -116.388134) (xy 362.460872 -116.397154)
			(xy 362.467136 -116.414071) (xy 362.472732 -116.421154) (xy 362.472986 -116.421154) (xy 362.472986 -116.421408)
			(xy 362.49064 -116.442328) (xy 362.52035 -116.488304) (xy 362.543183 -116.538054) (xy 362.558671 -116.590558)
			(xy 362.566495 -116.644736) (xy 362.566966 -116.672106) (xy 362.566828 -116.680234) (xy 363.451138 -116.680234)
			(xy 363.455209 -116.624612) (xy 363.467335 -116.570175) (xy 363.487258 -116.518084) (xy 363.514554 -116.469449)
			(xy 363.54864 -116.425306) (xy 363.588789 -116.386597) (xy 363.634147 -116.354146) (xy 363.683747 -116.328645)
			(xy 363.736531 -116.310638) (xy 363.791374 -116.300508) (xy 363.847108 -116.298471) (xy 363.902545 -116.304571)
			(xy 363.956502 -116.318677) (xy 364.007831 -116.340489) (xy 364.055437 -116.369543) (xy 364.098305 -116.405218)
			(xy 364.135522 -116.446755) (xy 364.166295 -116.493268) (xy 364.189967 -116.543765) (xy 364.206035 -116.597172)
			(xy 364.214155 -116.652348) (xy 364.214664 -116.680234) (xy 364.214155 -116.70812) (xy 364.206035 -116.763296)
			(xy 364.189967 -116.816703) (xy 364.166295 -116.8672) (xy 364.135522 -116.913713) (xy 364.098305 -116.95525)
			(xy 364.055437 -116.990925) (xy 364.007831 -117.019979) (xy 363.956502 -117.041791) (xy 363.902545 -117.055897)
			(xy 363.847108 -117.061997) (xy 363.791374 -117.05996) (xy 363.736531 -117.04983) (xy 363.683747 -117.031823)
			(xy 363.634147 -117.006322) (xy 363.588789 -116.973871) (xy 363.54864 -116.935162) (xy 363.514554 -116.891019)
			(xy 363.487258 -116.842384) (xy 363.467335 -116.790293) (xy 363.455209 -116.735856) (xy 363.451138 -116.680234)
			(xy 362.566828 -116.680234) (xy 362.566514 -116.698663) (xy 362.559145 -116.751262) (xy 362.54455 -116.802331)
			(xy 362.5342 -116.826792) (xy 362.529851 -116.83816) (xy 362.531199 -116.862434) (xy 362.53674 -116.873274)
			(xy 362.578142 -116.944394) (xy 362.584859 -116.954477) (xy 362.605279 -116.967461) (xy 362.617258 -116.969286)
			(xy 362.64524 -116.972462) (xy 362.699904 -116.985999) (xy 362.751984 -117.007426) (xy 362.800347 -117.036278)
			(xy 362.843942 -117.071927) (xy 362.881822 -117.113598) (xy 362.913164 -117.160386) (xy 362.937286 -117.211274)
			(xy 362.953663 -117.265155) (xy 362.959105 -117.301772) (xy 364.598202 -117.301772) (xy 364.602273 -117.24615)
			(xy 364.614399 -117.191713) (xy 364.634322 -117.139622) (xy 364.661618 -117.090987) (xy 364.695704 -117.046844)
			(xy 364.735853 -117.008135) (xy 364.781211 -116.975684) (xy 364.830811 -116.950183) (xy 364.883595 -116.932176)
			(xy 364.938438 -116.922046) (xy 364.994172 -116.920009) (xy 365.049609 -116.926109) (xy 365.103566 -116.940215)
			(xy 365.154895 -116.962027) (xy 365.202501 -116.991081) (xy 365.245369 -117.026756) (xy 365.282586 -117.068293)
			(xy 365.313359 -117.114806) (xy 365.337031 -117.165303) (xy 365.353099 -117.21871) (xy 365.359118 -117.259608)
			(xy 365.477552 -117.259608) (xy 365.47801 -117.232237) (xy 365.485828 -117.178057) (xy 365.501318 -117.125554)
			(xy 365.524162 -117.075807) (xy 365.553889 -117.029841) (xy 365.571532 -117.00891) (xy 365.571786 -117.008656)
			(xy 365.577354 -117.001556) (xy 365.583612 -116.98465) (xy 365.583978 -116.975636) (xy 365.583978 -116.90858)
			(xy 365.583635 -116.899562) (xy 365.577378 -116.882644) (xy 365.571786 -116.87556) (xy 365.571532 -116.87556)
			(xy 365.571532 -116.875306) (xy 365.553899 -116.854367) (xy 365.524173 -116.8084) (xy 365.501327 -116.758655)
			(xy 365.48583 -116.706154) (xy 365.478001 -116.651976) (xy 365.478 -116.597236) (xy 365.485828 -116.543058)
			(xy 365.501323 -116.490556) (xy 365.524168 -116.44081) (xy 365.553892 -116.394843) (xy 365.571532 -116.37391)
			(xy 365.571786 -116.373656) (xy 365.577354 -116.366556) (xy 365.583612 -116.34965) (xy 365.583978 -116.340636)
			(xy 365.583978 -116.27358) (xy 365.583635 -116.264562) (xy 365.577378 -116.247644) (xy 365.571786 -116.24056)
			(xy 365.571532 -116.24056) (xy 365.571532 -116.240306) (xy 365.553887 -116.219378) (xy 365.524175 -116.173405)
			(xy 365.50134 -116.123656) (xy 365.48585 -116.071154) (xy 365.478024 -116.016978) (xy 365.477552 -115.989608)
			(xy 365.478085 -115.962359) (xy 365.485839 -115.908415) (xy 365.501192 -115.856123) (xy 365.523829 -115.806549)
			(xy 365.553291 -115.7607) (xy 365.588977 -115.719511) (xy 365.630162 -115.683819) (xy 365.676007 -115.654352)
			(xy 365.725578 -115.631708) (xy 365.777868 -115.61635) (xy 365.831811 -115.608589) (xy 365.85906 -115.6081)
			(xy 365.886429 -115.60859) (xy 365.940607 -115.616402) (xy 365.99311 -115.631885) (xy 366.042858 -115.654722)
			(xy 366.088825 -115.684441) (xy 366.109758 -115.70208) (xy 366.110012 -115.702334) (xy 366.117088 -115.707936)
			(xy 366.134013 -115.714172) (xy 366.143032 -115.714526) (xy 366.210088 -115.714526) (xy 366.219104 -115.714158)
			(xy 366.23602 -115.707917) (xy 366.243108 -115.702334) (xy 366.243108 -115.70208) (xy 366.243362 -115.70208)
			(xy 366.264295 -115.684442) (xy 366.310268 -115.654731) (xy 366.360015 -115.631895) (xy 366.412516 -115.616404)
			(xy 366.466691 -115.608575) (xy 366.49406 -115.6081) (xy 366.521312 -115.608593) (xy 366.575263 -115.616344)
			(xy 366.62756 -115.631696) (xy 366.677141 -115.654334) (xy 366.722995 -115.683799) (xy 366.764188 -115.719489)
			(xy 366.799882 -115.76068) (xy 366.829351 -115.806531) (xy 366.851993 -115.85611) (xy 366.867349 -115.908406)
			(xy 366.875105 -115.962356) (xy 366.875568 -115.989608) (xy 366.875114 -116.016979) (xy 366.867295 -116.071159)
			(xy 366.851803 -116.123662) (xy 366.828959 -116.173409) (xy 366.799231 -116.219375) (xy 366.781588 -116.240306)
			(xy 366.781334 -116.24056) (xy 366.77575 -116.247648) (xy 366.769504 -116.264564) (xy 366.769142 -116.27358)
			(xy 366.769142 -116.340636) (xy 366.769473 -116.349656) (xy 366.775737 -116.366573) (xy 366.781334 -116.373656)
			(xy 366.781588 -116.373656) (xy 366.781588 -116.37391) (xy 366.799236 -116.394837) (xy 366.828959 -116.440806)
			(xy 366.851803 -116.490553) (xy 366.867298 -116.543056) (xy 366.875126 -116.597235) (xy 366.875125 -116.651977)
			(xy 366.867296 -116.706156) (xy 366.851799 -116.758658) (xy 366.828953 -116.808405) (xy 366.799229 -116.854373)
			(xy 366.781588 -116.875306) (xy 366.781334 -116.87556) (xy 366.77575 -116.882648) (xy 366.769504 -116.899564)
			(xy 366.769142 -116.90858) (xy 366.769142 -116.975636) (xy 366.769473 -116.984656) (xy 366.775737 -117.001573)
			(xy 366.781334 -117.008656) (xy 366.781588 -117.008656) (xy 366.781588 -117.00891) (xy 366.799243 -117.029829)
			(xy 366.828953 -117.075805) (xy 366.851786 -117.125556) (xy 366.867273 -117.17806) (xy 366.875097 -117.232238)
			(xy 366.875568 -117.259608) (xy 366.875152 -117.286863) (xy 366.867393 -117.340818) (xy 366.852034 -117.393119)
			(xy 366.829387 -117.442702) (xy 366.799915 -117.488557) (xy 366.764216 -117.52975) (xy 366.723018 -117.565444)
			(xy 366.677159 -117.594911) (xy 366.627574 -117.617551) (xy 366.575271 -117.632903) (xy 366.521315 -117.640655)
			(xy 366.49406 -117.641116) (xy 366.46669 -117.640635) (xy 366.412511 -117.632824) (xy 366.360007 -117.61734)
			(xy 366.31026 -117.594501) (xy 366.264293 -117.564777) (xy 366.243362 -117.547136) (xy 366.243108 -117.546882)
			(xy 366.236025 -117.541291) (xy 366.219105 -117.535047) (xy 366.210088 -117.53469) (xy 366.143032 -117.53469)
			(xy 366.134017 -117.535064) (xy 366.1171 -117.5413) (xy 366.110012 -117.546882) (xy 366.110012 -117.547136)
			(xy 366.109758 -117.547136) (xy 366.08882 -117.564767) (xy 366.042848 -117.594479) (xy 365.993102 -117.617316)
			(xy 365.940603 -117.632809) (xy 365.886429 -117.64064) (xy 365.85906 -117.641116) (xy 365.831808 -117.640659)
			(xy 365.77786 -117.632898) (xy 365.725565 -117.617538) (xy 365.675988 -117.594893) (xy 365.630138 -117.565423)
			(xy 365.588949 -117.529729) (xy 365.553258 -117.488536) (xy 365.523792 -117.442684) (xy 365.501151 -117.393105)
			(xy 365.485796 -117.340809) (xy 365.478038 -117.28686) (xy 365.477552 -117.259608) (xy 365.359118 -117.259608)
			(xy 365.361219 -117.273886) (xy 365.361728 -117.301772) (xy 365.361219 -117.329658) (xy 365.353099 -117.384834)
			(xy 365.337031 -117.438241) (xy 365.313359 -117.488738) (xy 365.282586 -117.535251) (xy 365.245369 -117.576788)
			(xy 365.202501 -117.612463) (xy 365.154895 -117.641517) (xy 365.103566 -117.663329) (xy 365.049609 -117.677435)
			(xy 364.994172 -117.683535) (xy 364.938438 -117.681498) (xy 364.883595 -117.671368) (xy 364.830811 -117.653361)
			(xy 364.781211 -117.62786) (xy 364.735853 -117.595409) (xy 364.695704 -117.5567) (xy 364.661618 -117.512557)
			(xy 364.634322 -117.463922) (xy 364.614399 -117.411831) (xy 364.602273 -117.357394) (xy 364.598202 -117.301772)
			(xy 362.959105 -117.301772) (xy 362.961941 -117.320858) (xy 362.962444 -117.349016) (xy 362.961958 -117.376267)
			(xy 362.954202 -117.430215) (xy 362.938847 -117.48251) (xy 362.916205 -117.532087) (xy 362.886739 -117.577937)
			(xy 362.851048 -117.619128) (xy 362.809857 -117.654819) (xy 362.764007 -117.684285) (xy 362.71443 -117.706927)
			(xy 362.662135 -117.722282) (xy 362.608187 -117.730038) (xy 362.553685 -117.730038) (xy 362.499737 -117.722282)
			(xy 362.447442 -117.706927) (xy 362.397865 -117.684285) (xy 362.352015 -117.654819) (xy 362.310824 -117.619128)
			(xy 362.275133 -117.577937) (xy 362.245667 -117.532087) (xy 362.223025 -117.48251) (xy 362.20767 -117.430215)
			(xy 362.199914 -117.376267) (xy 362.199428 -117.349016) (xy 362.199888 -117.32246) (xy 362.207254 -117.26986)
			(xy 362.221846 -117.218791) (xy 362.232194 -117.19433) (xy 362.236529 -117.182958) (xy 362.235191 -117.158688)
			(xy 362.229654 -117.147848) (xy 362.188252 -117.076728) (xy 362.181509 -117.066666) (xy 362.161107 -117.053675)
			(xy 362.149136 -117.051836) (xy 362.119662 -117.048454) (xy 362.062193 -117.033737) (xy 362.007697 -117.010298)
			(xy 361.957487 -116.978703) (xy 361.93476 -116.959634) (xy 361.934506 -116.95938) (xy 361.927424 -116.953788)
			(xy 361.910504 -116.947545) (xy 361.901486 -116.947188) (xy 361.83443 -116.947188) (xy 361.825415 -116.947562)
			(xy 361.808498 -116.953798) (xy 361.80141 -116.95938) (xy 361.80141 -116.959634) (xy 361.801156 -116.959634)
			(xy 361.780218 -116.977266) (xy 361.734246 -117.006977) (xy 361.6845 -117.029814) (xy 361.632001 -117.045307)
			(xy 361.577827 -117.053138) (xy 361.550458 -117.053614) (xy 361.523206 -117.053161) (xy 361.469257 -117.045399)
			(xy 361.416962 -117.030039) (xy 361.367385 -117.007393) (xy 361.321536 -116.977923) (xy 361.280346 -116.942229)
			(xy 361.244655 -116.901036) (xy 361.215189 -116.855183) (xy 361.192548 -116.805604) (xy 361.177193 -116.753307)
			(xy 361.169436 -116.699358) (xy 361.16895 -116.672106) (xy 356.604703 -116.672106) (xy 356.605871 -116.672819)
			(xy 356.648739 -116.708494) (xy 356.685956 -116.750031) (xy 356.716729 -116.796544) (xy 356.740401 -116.847041)
			(xy 356.756469 -116.900448) (xy 356.764589 -116.955624) (xy 356.765098 -116.98351) (xy 356.764589 -117.011396)
			(xy 356.756469 -117.066572) (xy 356.740401 -117.119979) (xy 356.716729 -117.170476) (xy 356.685956 -117.216989)
			(xy 356.648739 -117.258526) (xy 356.605871 -117.294201) (xy 356.558265 -117.323255) (xy 356.54845 -117.327426)
			(xy 357.987344 -117.327426) (xy 357.991415 -117.271804) (xy 358.003541 -117.217367) (xy 358.023464 -117.165276)
			(xy 358.05076 -117.116641) (xy 358.084846 -117.072498) (xy 358.124995 -117.033789) (xy 358.170353 -117.001338)
			(xy 358.219953 -116.975837) (xy 358.272737 -116.95783) (xy 358.32758 -116.9477) (xy 358.383314 -116.945663)
			(xy 358.438751 -116.951763) (xy 358.492708 -116.965869) (xy 358.544037 -116.987681) (xy 358.591643 -117.016735)
			(xy 358.634511 -117.05241) (xy 358.671728 -117.093947) (xy 358.702501 -117.14046) (xy 358.726173 -117.190957)
			(xy 358.729022 -117.200426) (xy 360.019344 -117.200426) (xy 360.023415 -117.144804) (xy 360.035541 -117.090367)
			(xy 360.055464 -117.038276) (xy 360.08276 -116.989641) (xy 360.116846 -116.945498) (xy 360.156995 -116.906789)
			(xy 360.202353 -116.874338) (xy 360.251953 -116.848837) (xy 360.304737 -116.83083) (xy 360.35958 -116.8207)
			(xy 360.415314 -116.818663) (xy 360.470751 -116.824763) (xy 360.524708 -116.838869) (xy 360.576037 -116.860681)
			(xy 360.623643 -116.889735) (xy 360.666511 -116.92541) (xy 360.703728 -116.966947) (xy 360.734501 -117.01346)
			(xy 360.758173 -117.063957) (xy 360.774241 -117.117364) (xy 360.782361 -117.17254) (xy 360.78287 -117.200426)
			(xy 360.782361 -117.228312) (xy 360.774241 -117.283488) (xy 360.758173 -117.336895) (xy 360.734501 -117.387392)
			(xy 360.703728 -117.433905) (xy 360.666511 -117.475442) (xy 360.623643 -117.511117) (xy 360.576037 -117.540171)
			(xy 360.524708 -117.561983) (xy 360.470751 -117.576089) (xy 360.415314 -117.582189) (xy 360.35958 -117.580152)
			(xy 360.304737 -117.570022) (xy 360.251953 -117.552015) (xy 360.202353 -117.526514) (xy 360.156995 -117.494063)
			(xy 360.116846 -117.455354) (xy 360.08276 -117.411211) (xy 360.055464 -117.362576) (xy 360.035541 -117.310485)
			(xy 360.023415 -117.256048) (xy 360.019344 -117.200426) (xy 358.729022 -117.200426) (xy 358.742241 -117.244364)
			(xy 358.750361 -117.29954) (xy 358.75087 -117.327426) (xy 358.750361 -117.355312) (xy 358.742241 -117.410488)
			(xy 358.726173 -117.463895) (xy 358.702501 -117.514392) (xy 358.671728 -117.560905) (xy 358.634511 -117.602442)
			(xy 358.591643 -117.638117) (xy 358.544037 -117.667171) (xy 358.492708 -117.688983) (xy 358.438751 -117.703089)
			(xy 358.383314 -117.709189) (xy 358.32758 -117.707152) (xy 358.272737 -117.697022) (xy 358.219953 -117.679015)
			(xy 358.170353 -117.653514) (xy 358.124995 -117.621063) (xy 358.084846 -117.582354) (xy 358.05076 -117.538211)
			(xy 358.023464 -117.489576) (xy 358.003541 -117.437485) (xy 357.991415 -117.383048) (xy 357.987344 -117.327426)
			(xy 356.54845 -117.327426) (xy 356.506936 -117.345067) (xy 356.452979 -117.359173) (xy 356.397542 -117.365273)
			(xy 356.341808 -117.363236) (xy 356.286965 -117.353106) (xy 356.234181 -117.335099) (xy 356.184581 -117.309598)
			(xy 356.139223 -117.277147) (xy 356.099074 -117.238438) (xy 356.064988 -117.194295) (xy 356.037692 -117.14566)
			(xy 356.017769 -117.093569) (xy 356.005643 -117.039132) (xy 356.001572 -116.98351) (xy 353.817429 -116.98351)
			(xy 353.76231 -117.038628) (xy 353.755467 -117.046028) (xy 353.747741 -117.064626) (xy 353.747324 -117.074696)
			(xy 353.747324 -119.486426) (xy 357.987344 -119.486426) (xy 357.991415 -119.430804) (xy 358.003541 -119.376367)
			(xy 358.023464 -119.324276) (xy 358.05076 -119.275641) (xy 358.084846 -119.231498) (xy 358.124995 -119.192789)
			(xy 358.170353 -119.160338) (xy 358.219953 -119.134837) (xy 358.272737 -119.11683) (xy 358.32758 -119.1067)
			(xy 358.383314 -119.104663) (xy 358.438751 -119.110763) (xy 358.492708 -119.124869) (xy 358.544037 -119.146681)
			(xy 358.591643 -119.175735) (xy 358.634511 -119.21141) (xy 358.671728 -119.252947) (xy 358.702501 -119.29946)
			(xy 358.726173 -119.349957) (xy 358.727952 -119.35587) (xy 359.003344 -119.35587) (xy 359.007415 -119.300248)
			(xy 359.019541 -119.245811) (xy 359.039464 -119.19372) (xy 359.06676 -119.145085) (xy 359.100846 -119.100942)
			(xy 359.140995 -119.062233) (xy 359.186353 -119.029782) (xy 359.235953 -119.004281) (xy 359.288737 -118.986274)
			(xy 359.34358 -118.976144) (xy 359.399314 -118.974107) (xy 359.454751 -118.980207) (xy 359.508708 -118.994313)
			(xy 359.560037 -119.016125) (xy 359.607643 -119.045179) (xy 359.650511 -119.080854) (xy 359.687728 -119.122391)
			(xy 359.718501 -119.168904) (xy 359.742173 -119.219401) (xy 359.758241 -119.272808) (xy 359.766361 -119.327984)
			(xy 359.76687 -119.35587) (xy 360.019344 -119.35587) (xy 360.023415 -119.300248) (xy 360.035541 -119.245811)
			(xy 360.055464 -119.19372) (xy 360.08276 -119.145085) (xy 360.116846 -119.100942) (xy 360.156995 -119.062233)
			(xy 360.202353 -119.029782) (xy 360.251953 -119.004281) (xy 360.304737 -118.986274) (xy 360.35958 -118.976144)
			(xy 360.415314 -118.974107) (xy 360.470751 -118.980207) (xy 360.524708 -118.994313) (xy 360.576037 -119.016125)
			(xy 360.623643 -119.045179) (xy 360.666511 -119.080854) (xy 360.703728 -119.122391) (xy 360.734501 -119.168904)
			(xy 360.758173 -119.219401) (xy 360.774241 -119.272808) (xy 360.782361 -119.327984) (xy 360.78287 -119.35587)
			(xy 360.782361 -119.383756) (xy 360.781232 -119.39143) (xy 363.214918 -119.39143) (xy 363.218989 -119.335808)
			(xy 363.231115 -119.281371) (xy 363.251038 -119.22928) (xy 363.278334 -119.180645) (xy 363.31242 -119.136502)
			(xy 363.352569 -119.097793) (xy 363.397927 -119.065342) (xy 363.447527 -119.039841) (xy 363.500311 -119.021834)
			(xy 363.555154 -119.011704) (xy 363.610888 -119.009667) (xy 363.666325 -119.015767) (xy 363.720282 -119.029873)
			(xy 363.771611 -119.051685) (xy 363.819217 -119.080739) (xy 363.862085 -119.116414) (xy 363.899302 -119.157951)
			(xy 363.930075 -119.204464) (xy 363.953747 -119.254961) (xy 363.969815 -119.308368) (xy 363.977935 -119.363544)
			(xy 363.978444 -119.39143) (xy 363.977935 -119.419316) (xy 363.969815 -119.474492) (xy 363.953747 -119.527899)
			(xy 363.930075 -119.578396) (xy 363.899302 -119.624909) (xy 363.862085 -119.666446) (xy 363.819217 -119.702121)
			(xy 363.771611 -119.731175) (xy 363.720282 -119.752987) (xy 363.666325 -119.767093) (xy 363.610888 -119.773193)
			(xy 363.555154 -119.771156) (xy 363.500311 -119.761026) (xy 363.447527 -119.743019) (xy 363.397927 -119.717518)
			(xy 363.352569 -119.685067) (xy 363.31242 -119.646358) (xy 363.278334 -119.602215) (xy 363.251038 -119.55358)
			(xy 363.231115 -119.501489) (xy 363.218989 -119.447052) (xy 363.214918 -119.39143) (xy 360.781232 -119.39143)
			(xy 360.774241 -119.438932) (xy 360.758173 -119.492339) (xy 360.734501 -119.542836) (xy 360.703728 -119.589349)
			(xy 360.666511 -119.630886) (xy 360.623643 -119.666561) (xy 360.576037 -119.695615) (xy 360.524708 -119.717427)
			(xy 360.470751 -119.731533) (xy 360.415314 -119.737633) (xy 360.35958 -119.735596) (xy 360.304737 -119.725466)
			(xy 360.251953 -119.707459) (xy 360.202353 -119.681958) (xy 360.156995 -119.649507) (xy 360.116846 -119.610798)
			(xy 360.08276 -119.566655) (xy 360.055464 -119.51802) (xy 360.035541 -119.465929) (xy 360.023415 -119.411492)
			(xy 360.019344 -119.35587) (xy 359.76687 -119.35587) (xy 359.766361 -119.383756) (xy 359.758241 -119.438932)
			(xy 359.742173 -119.492339) (xy 359.718501 -119.542836) (xy 359.687728 -119.589349) (xy 359.650511 -119.630886)
			(xy 359.607643 -119.666561) (xy 359.560037 -119.695615) (xy 359.508708 -119.717427) (xy 359.454751 -119.731533)
			(xy 359.399314 -119.737633) (xy 359.34358 -119.735596) (xy 359.288737 -119.725466) (xy 359.235953 -119.707459)
			(xy 359.186353 -119.681958) (xy 359.140995 -119.649507) (xy 359.100846 -119.610798) (xy 359.06676 -119.566655)
			(xy 359.039464 -119.51802) (xy 359.019541 -119.465929) (xy 359.007415 -119.411492) (xy 359.003344 -119.35587)
			(xy 358.727952 -119.35587) (xy 358.742241 -119.403364) (xy 358.750361 -119.45854) (xy 358.75087 -119.486426)
			(xy 358.750361 -119.514312) (xy 358.742241 -119.569488) (xy 358.726173 -119.622895) (xy 358.702501 -119.673392)
			(xy 358.671728 -119.719905) (xy 358.634511 -119.761442) (xy 358.591643 -119.797117) (xy 358.544037 -119.826171)
			(xy 358.492708 -119.847983) (xy 358.438751 -119.862089) (xy 358.383314 -119.868189) (xy 358.32758 -119.866152)
			(xy 358.272737 -119.856022) (xy 358.219953 -119.838015) (xy 358.170353 -119.812514) (xy 358.124995 -119.780063)
			(xy 358.084846 -119.741354) (xy 358.05076 -119.697211) (xy 358.023464 -119.648576) (xy 358.003541 -119.596485)
			(xy 357.991415 -119.542048) (xy 357.987344 -119.486426) (xy 353.747324 -119.486426) (xy 353.747324 -121.57075)
			(xy 361.920028 -121.57075) (xy 361.920517 -121.54338) (xy 361.928328 -121.489202) (xy 361.943811 -121.436699)
			(xy 361.966648 -121.386952) (xy 361.996369 -121.340984) (xy 362.014008 -121.320052) (xy 362.014262 -121.319798)
			(xy 362.019863 -121.312722) (xy 362.026099 -121.295797) (xy 362.026454 -121.286778) (xy 362.026454 -121.219722)
			(xy 362.026096 -121.210705) (xy 362.01985 -121.193788) (xy 362.014262 -121.186702) (xy 362.014008 -121.186702)
			(xy 362.014008 -121.186448) (xy 361.996379 -121.165508) (xy 361.966666 -121.119537) (xy 361.943827 -121.069792)
			(xy 361.928334 -121.017293) (xy 361.920503 -120.963119) (xy 361.920028 -120.93575) (xy 361.920514 -120.908499)
			(xy 361.92827 -120.854551) (xy 361.943625 -120.802256) (xy 361.966267 -120.752679) (xy 361.995733 -120.706829)
			(xy 362.031424 -120.665638) (xy 362.072615 -120.629947) (xy 362.118465 -120.600481) (xy 362.168042 -120.577839)
			(xy 362.220337 -120.562484) (xy 362.274285 -120.554728) (xy 362.328787 -120.554728) (xy 362.382735 -120.562484)
			(xy 362.43503 -120.577839) (xy 362.484607 -120.600481) (xy 362.530457 -120.629947) (xy 362.571648 -120.665638)
			(xy 362.607339 -120.706829) (xy 362.636805 -120.752679) (xy 362.659447 -120.802256) (xy 362.674802 -120.854551)
			(xy 362.682558 -120.908499) (xy 362.683044 -120.93575) (xy 362.682562 -120.96312) (xy 362.67475 -121.017299)
			(xy 362.659266 -121.069802) (xy 362.636427 -121.119549) (xy 362.606705 -121.165516) (xy 362.589064 -121.186448)
			(xy 362.58881 -121.186702) (xy 362.583218 -121.193785) (xy 362.576974 -121.210704) (xy 362.576618 -121.219722)
			(xy 362.576618 -121.286778) (xy 362.576982 -121.295794) (xy 362.583224 -121.312711) (xy 362.58881 -121.319798)
			(xy 362.589064 -121.319798) (xy 362.589064 -121.320052) (xy 362.606688 -121.340996) (xy 362.636404 -121.386965)
			(xy 362.659243 -121.436709) (xy 362.674737 -121.489208) (xy 362.682569 -121.543382) (xy 362.683044 -121.57075)
			(xy 362.682558 -121.598001) (xy 362.674802 -121.651949) (xy 362.659447 -121.704244) (xy 362.636805 -121.753821)
			(xy 362.607339 -121.799671) (xy 362.571648 -121.840862) (xy 362.530457 -121.876553) (xy 362.484607 -121.906019)
			(xy 362.43503 -121.928661) (xy 362.382735 -121.944016) (xy 362.328787 -121.951772) (xy 362.274285 -121.951772)
			(xy 362.220337 -121.944016) (xy 362.168042 -121.928661) (xy 362.118465 -121.906019) (xy 362.072615 -121.876553)
			(xy 362.031424 -121.840862) (xy 361.995733 -121.799671) (xy 361.966267 -121.753821) (xy 361.943625 -121.704244)
			(xy 361.92827 -121.651949) (xy 361.920514 -121.598001) (xy 361.920028 -121.57075) (xy 353.747324 -121.57075)
			(xy 353.747324 -122.292618) (xy 358.080308 -122.292618) (xy 358.084379 -122.236996) (xy 358.096505 -122.182559)
			(xy 358.116428 -122.130468) (xy 358.143724 -122.081833) (xy 358.17781 -122.03769) (xy 358.217959 -121.998981)
			(xy 358.263317 -121.96653) (xy 358.312917 -121.941029) (xy 358.365701 -121.923022) (xy 358.420544 -121.912892)
			(xy 358.476278 -121.910855) (xy 358.531715 -121.916955) (xy 358.585672 -121.931061) (xy 358.637001 -121.952873)
			(xy 358.684607 -121.981927) (xy 358.727475 -122.017602) (xy 358.764692 -122.059139) (xy 358.795465 -122.105652)
			(xy 358.819137 -122.156149) (xy 358.835205 -122.209556) (xy 358.843325 -122.264732) (xy 358.843834 -122.292618)
			(xy 358.843325 -122.320504) (xy 358.835205 -122.37568) (xy 358.819137 -122.429087) (xy 358.8 -122.46991)
			(xy 359.237024 -122.46991) (xy 359.241095 -122.414288) (xy 359.253221 -122.359851) (xy 359.273144 -122.30776)
			(xy 359.30044 -122.259125) (xy 359.334526 -122.214982) (xy 359.374675 -122.176273) (xy 359.420033 -122.143822)
			(xy 359.469633 -122.118321) (xy 359.522417 -122.100314) (xy 359.57726 -122.090184) (xy 359.632994 -122.088147)
			(xy 359.688431 -122.094247) (xy 359.742388 -122.108353) (xy 359.793717 -122.130165) (xy 359.841323 -122.159219)
			(xy 359.884191 -122.194894) (xy 359.921408 -122.236431) (xy 359.952181 -122.282944) (xy 359.975853 -122.333441)
			(xy 359.991921 -122.386848) (xy 360.000041 -122.442024) (xy 360.00055 -122.46991) (xy 360.000041 -122.497796)
			(xy 359.991921 -122.552972) (xy 359.975853 -122.606379) (xy 359.952181 -122.656876) (xy 359.921408 -122.703389)
			(xy 359.884191 -122.744926) (xy 359.841323 -122.780601) (xy 359.793717 -122.809655) (xy 359.742388 -122.831467)
			(xy 359.688431 -122.845573) (xy 359.632994 -122.851673) (xy 359.57726 -122.849636) (xy 359.522417 -122.839506)
			(xy 359.469633 -122.821499) (xy 359.420033 -122.795998) (xy 359.374675 -122.763547) (xy 359.334526 -122.724838)
			(xy 359.30044 -122.680695) (xy 359.273144 -122.63206) (xy 359.253221 -122.579969) (xy 359.241095 -122.525532)
			(xy 359.237024 -122.46991) (xy 358.8 -122.46991) (xy 358.795465 -122.479584) (xy 358.764692 -122.526097)
			(xy 358.727475 -122.567634) (xy 358.684607 -122.603309) (xy 358.637001 -122.632363) (xy 358.585672 -122.654175)
			(xy 358.531715 -122.668281) (xy 358.476278 -122.674381) (xy 358.420544 -122.672344) (xy 358.365701 -122.662214)
			(xy 358.312917 -122.644207) (xy 358.263317 -122.618706) (xy 358.217959 -122.586255) (xy 358.17781 -122.547546)
			(xy 358.143724 -122.503403) (xy 358.116428 -122.454768) (xy 358.096505 -122.402677) (xy 358.084379 -122.34824)
			(xy 358.080308 -122.292618) (xy 353.747324 -122.292618) (xy 353.747324 -123.213876) (xy 353.746795 -123.239899)
			(xy 353.745229 -123.24975) (xy 360.21009 -123.24975) (xy 360.21009 -123.19525) (xy 360.217847 -123.141304)
			(xy 360.233201 -123.089011) (xy 360.255842 -123.039435) (xy 360.285307 -122.993586) (xy 360.320997 -122.952397)
			(xy 360.362186 -122.916707) (xy 360.408035 -122.887242) (xy 360.457611 -122.864601) (xy 360.509904 -122.849247)
			(xy 360.56385 -122.84149) (xy 360.5911 -122.841004) (xy 360.61813 -122.841499) (xy 360.671647 -122.849137)
			(xy 360.723549 -122.86426) (xy 360.772793 -122.886564) (xy 360.818392 -122.915602) (xy 360.85943 -122.950792)
			(xy 360.877612 -122.970798) (xy 360.877866 -122.971052) (xy 360.885307 -122.978703) (xy 360.904793 -122.987368)
			(xy 360.915458 -122.987816) (xy 361.003088 -122.988324) (xy 361.022646 -122.979688) (xy 361.030012 -122.971306)
			(xy 361.048173 -122.951583) (xy 361.089074 -122.916919) (xy 361.134429 -122.88833) (xy 361.183345 -122.866382)
			(xy 361.234854 -122.851506) (xy 361.287939 -122.843997) (xy 361.314746 -122.843544) (xy 361.342116 -122.844031)
			(xy 361.396294 -122.851842) (xy 361.448798 -122.867326) (xy 361.498545 -122.890163) (xy 361.544512 -122.919884)
			(xy 361.565444 -122.937524) (xy 361.565698 -122.937778) (xy 361.572774 -122.943379) (xy 361.589699 -122.949615)
			(xy 361.598718 -122.94997) (xy 361.665774 -122.94997) (xy 361.67479 -122.949607) (xy 361.691708 -122.943364)
			(xy 361.698794 -122.937778) (xy 361.698794 -122.937524) (xy 361.699048 -122.937524) (xy 361.719981 -122.919883)
			(xy 361.765949 -122.890159) (xy 361.815695 -122.867313) (xy 361.868197 -122.851817) (xy 361.922375 -122.843988)
			(xy 361.977117 -122.843988) (xy 362.031295 -122.851817) (xy 362.083797 -122.867313) (xy 362.133543 -122.890159)
			(xy 362.179511 -122.919883) (xy 362.200444 -122.937524) (xy 362.200698 -122.937778) (xy 362.207774 -122.943379)
			(xy 362.224699 -122.949615) (xy 362.233718 -122.94997) (xy 362.300774 -122.94997) (xy 362.30979 -122.949607)
			(xy 362.326708 -122.943364) (xy 362.333794 -122.937778) (xy 362.334302 -122.937524) (xy 362.347036 -122.92658)
			(xy 362.374128 -122.906738) (xy 362.388404 -122.8979) (xy 362.397294 -122.892566) (xy 362.409486 -122.875548)
			(xy 362.429806 -122.78233) (xy 362.425488 -122.761756) (xy 362.419646 -122.75312) (xy 362.403646 -122.729056)
			(xy 362.378305 -122.677124) (xy 362.36108 -122.621966) (xy 362.352364 -122.564842) (xy 362.351828 -122.53595)
			(xy 362.352314 -122.508699) (xy 362.36007 -122.454751) (xy 362.375425 -122.402456) (xy 362.398067 -122.352879)
			(xy 362.427533 -122.307029) (xy 362.463224 -122.265838) (xy 362.504415 -122.230147) (xy 362.550265 -122.200681)
			(xy 362.599842 -122.178039) (xy 362.652137 -122.162684) (xy 362.706085 -122.154928) (xy 362.760587 -122.154928)
			(xy 362.814535 -122.162684) (xy 362.86683 -122.178039) (xy 362.916407 -122.200681) (xy 362.962257 -122.230147)
			(xy 363.003448 -122.265838) (xy 363.039139 -122.307029) (xy 363.068605 -122.352879) (xy 363.091247 -122.402456)
			(xy 363.106602 -122.454751) (xy 363.114358 -122.508699) (xy 363.114844 -122.53595) (xy 363.114297 -122.56404)
			(xy 363.106078 -122.619614) (xy 363.089795 -122.673381) (xy 363.065801 -122.724178) (xy 363.034614 -122.770905)
			(xy 362.99691 -122.812552) (xy 362.953505 -122.848217) (xy 362.929678 -122.863102) (xy 362.920788 -122.868436)
			(xy 362.908596 -122.885454) (xy 362.888276 -122.978672) (xy 362.892594 -122.999246) (xy 362.898436 -123.007882)
			(xy 362.914435 -123.031947) (xy 362.939777 -123.083878) (xy 362.957002 -123.139036) (xy 362.965719 -123.19616)
			(xy 362.966254 -123.225052) (xy 362.9657 -123.252302) (xy 362.957951 -123.306247) (xy 362.942603 -123.35854)
			(xy 362.91997 -123.408117) (xy 362.890511 -123.453968) (xy 362.854827 -123.49516) (xy 362.813644 -123.530855)
			(xy 362.7678 -123.560325) (xy 362.718228 -123.58297) (xy 362.665939 -123.598331) (xy 362.611995 -123.606093)
			(xy 362.584746 -123.60656) (xy 362.557376 -123.606077) (xy 362.503198 -123.598265) (xy 362.450694 -123.58278)
			(xy 362.400947 -123.559942) (xy 362.35498 -123.53022) (xy 362.334048 -123.51258) (xy 362.333794 -123.512326)
			(xy 362.32672 -123.506722) (xy 362.309793 -123.500488) (xy 362.300774 -123.500134) (xy 362.233718 -123.500134)
			(xy 362.224701 -123.500492) (xy 362.207784 -123.506738) (xy 362.200698 -123.512326) (xy 362.200444 -123.51258)
			(xy 362.179511 -123.530221) (xy 362.133543 -123.559945) (xy 362.083797 -123.582791) (xy 362.031295 -123.598287)
			(xy 361.977117 -123.606116) (xy 361.922375 -123.606116) (xy 361.868197 -123.598287) (xy 361.815695 -123.582791)
			(xy 361.765949 -123.559945) (xy 361.719981 -123.530221) (xy 361.699048 -123.51258) (xy 361.698794 -123.512326)
			(xy 361.69172 -123.506722) (xy 361.674793 -123.500488) (xy 361.665774 -123.500134) (xy 361.598718 -123.500134)
			(xy 361.589701 -123.500492) (xy 361.572784 -123.506738) (xy 361.565698 -123.512326) (xy 361.565698 -123.51258)
			(xy 361.565444 -123.51258) (xy 361.544504 -123.530209) (xy 361.498533 -123.559923) (xy 361.448788 -123.582761)
			(xy 361.396289 -123.598255) (xy 361.342115 -123.606085) (xy 361.314746 -123.60656) (xy 361.287716 -123.60608)
			(xy 361.234199 -123.598436) (xy 361.182298 -123.583308) (xy 361.133054 -123.561001) (xy 361.087456 -123.531962)
			(xy 361.046417 -123.496772) (xy 361.028234 -123.476766) (xy 361.02798 -123.476512) (xy 361.020512 -123.468892)
			(xy 361.001047 -123.460207) (xy 360.990388 -123.459748) (xy 360.902758 -123.45924) (xy 360.8832 -123.467876)
			(xy 360.875834 -123.476258) (xy 360.857663 -123.495971) (xy 360.816763 -123.530634) (xy 360.771409 -123.559222)
			(xy 360.722496 -123.581172) (xy 360.67099 -123.596051) (xy 360.617906 -123.603564) (xy 360.5911 -123.60402)
			(xy 360.56385 -123.60351) (xy 360.509904 -123.595753) (xy 360.457611 -123.580399) (xy 360.408035 -123.557758)
			(xy 360.362186 -123.528293) (xy 360.320997 -123.492603) (xy 360.285307 -123.451414) (xy 360.255842 -123.405565)
			(xy 360.233201 -123.355989) (xy 360.217847 -123.303696) (xy 360.21009 -123.24975) (xy 353.745229 -123.24975)
			(xy 353.738624 -123.291299) (xy 353.722526 -123.340793) (xy 353.698895 -123.387166) (xy 353.668313 -123.429279)
			(xy 353.650296 -123.448064) (xy 353.61245 -123.48591) (xy 353.6056 -123.493307) (xy 353.597861 -123.511905)
			(xy 353.597464 -123.521978) (xy 353.597464 -123.61926) (xy 353.597029 -123.629325) (xy 353.589295 -123.64791)
			(xy 353.582478 -123.655328) (xy 352.77171 -124.46635) (xy 352.76487 -124.473751) (xy 352.757152 -124.492349)
			(xy 352.756724 -124.502418) (xy 352.756724 -124.963428) (xy 356.973122 -124.963428) (xy 356.977193 -124.907806)
			(xy 356.989319 -124.853369) (xy 357.009242 -124.801278) (xy 357.036538 -124.752643) (xy 357.070624 -124.7085)
			(xy 357.110773 -124.669791) (xy 357.156131 -124.63734) (xy 357.205731 -124.611839) (xy 357.258515 -124.593832)
			(xy 357.313358 -124.583702) (xy 357.369092 -124.581665) (xy 357.424529 -124.587765) (xy 357.478486 -124.601871)
			(xy 357.529815 -124.623683) (xy 357.577421 -124.652737) (xy 357.620289 -124.688412) (xy 357.657506 -124.729949)
			(xy 357.688279 -124.776462) (xy 357.711951 -124.826959) (xy 357.728019 -124.880366) (xy 357.736139 -124.935542)
			(xy 357.736648 -124.963428) (xy 357.736139 -124.991314) (xy 357.729552 -125.036072) (xy 359.186224 -125.036072)
			(xy 359.190295 -124.98045) (xy 359.202421 -124.926013) (xy 359.222344 -124.873922) (xy 359.24964 -124.825287)
			(xy 359.283726 -124.781144) (xy 359.323875 -124.742435) (xy 359.369233 -124.709984) (xy 359.418833 -124.684483)
			(xy 359.471617 -124.666476) (xy 359.52646 -124.656346) (xy 359.582194 -124.654309) (xy 359.637631 -124.660409)
			(xy 359.691588 -124.674515) (xy 359.742917 -124.696327) (xy 359.790523 -124.725381) (xy 359.833391 -124.761056)
			(xy 359.870608 -124.802593) (xy 359.901381 -124.849106) (xy 359.925053 -124.899603) (xy 359.941121 -124.95301)
			(xy 359.949241 -125.008186) (xy 359.94975 -125.036072) (xy 359.949241 -125.063958) (xy 359.941121 -125.119134)
			(xy 359.925053 -125.172541) (xy 359.901381 -125.223038) (xy 359.870608 -125.269551) (xy 359.833391 -125.311088)
			(xy 359.790523 -125.346763) (xy 359.742917 -125.375817) (xy 359.691588 -125.397629) (xy 359.669682 -125.403356)
			(xy 363.844332 -125.403356) (xy 363.844823 -125.375987) (xy 363.852634 -125.321808) (xy 363.868116 -125.269305)
			(xy 363.890953 -125.219558) (xy 363.920673 -125.17359) (xy 363.938312 -125.152658) (xy 363.938566 -125.152404)
			(xy 363.944165 -125.145326) (xy 363.950402 -125.128402) (xy 363.950758 -125.119384) (xy 363.950758 -125.052328)
			(xy 363.950397 -125.043311) (xy 363.944153 -125.026394) (xy 363.938566 -125.019308) (xy 363.938312 -125.019308)
			(xy 363.938312 -125.019054) (xy 363.920687 -124.998111) (xy 363.890972 -124.952141) (xy 363.868134 -124.902397)
			(xy 363.852639 -124.849898) (xy 363.844808 -124.795724) (xy 363.844332 -124.768356) (xy 363.844818 -124.741105)
			(xy 363.852574 -124.687157) (xy 363.867929 -124.634862) (xy 363.890571 -124.585285) (xy 363.920037 -124.539435)
			(xy 363.955728 -124.498244) (xy 363.996919 -124.462553) (xy 364.042769 -124.433087) (xy 364.092346 -124.410445)
			(xy 364.144641 -124.39509) (xy 364.198589 -124.387334) (xy 364.253091 -124.387334) (xy 364.307039 -124.39509)
			(xy 364.359334 -124.410445) (xy 364.408911 -124.433087) (xy 364.454761 -124.462553) (xy 364.495952 -124.498244)
			(xy 364.531643 -124.539435) (xy 364.561109 -124.585285) (xy 364.583751 -124.634862) (xy 364.599106 -124.687157)
			(xy 364.606862 -124.741105) (xy 364.607348 -124.768356) (xy 364.606869 -124.795726) (xy 364.599056 -124.849905)
			(xy 364.583571 -124.902408) (xy 364.560732 -124.952156) (xy 364.531009 -124.998122) (xy 364.513368 -125.019054)
			(xy 364.513114 -125.019308) (xy 364.507519 -125.026389) (xy 364.501277 -125.04331) (xy 364.500922 -125.052328)
			(xy 364.500922 -125.119384) (xy 364.501282 -125.128401) (xy 364.507527 -125.145318) (xy 364.513114 -125.152404)
			(xy 364.513368 -125.152404) (xy 364.513368 -125.152658) (xy 364.530996 -125.173599) (xy 364.560711 -125.219569)
			(xy 364.583549 -125.269314) (xy 364.599043 -125.321813) (xy 364.606873 -125.375987) (xy 364.607348 -125.403356)
			(xy 364.606862 -125.430607) (xy 364.599106 -125.484555) (xy 364.583751 -125.53685) (xy 364.561109 -125.586427)
			(xy 364.531643 -125.632277) (xy 364.495952 -125.673468) (xy 364.454761 -125.709159) (xy 364.408911 -125.738625)
			(xy 364.359334 -125.761267) (xy 364.307039 -125.776622) (xy 364.253091 -125.784378) (xy 364.198589 -125.784378)
			(xy 364.144641 -125.776622) (xy 364.092346 -125.761267) (xy 364.042769 -125.738625) (xy 363.996919 -125.709159)
			(xy 363.955728 -125.673468) (xy 363.920037 -125.632277) (xy 363.890571 -125.586427) (xy 363.867929 -125.53685)
			(xy 363.852574 -125.484555) (xy 363.844818 -125.430607) (xy 363.844332 -125.403356) (xy 359.669682 -125.403356)
			(xy 359.637631 -125.411735) (xy 359.582194 -125.417835) (xy 359.52646 -125.415798) (xy 359.471617 -125.405668)
			(xy 359.418833 -125.387661) (xy 359.369233 -125.36216) (xy 359.323875 -125.329709) (xy 359.283726 -125.291)
			(xy 359.24964 -125.246857) (xy 359.222344 -125.198222) (xy 359.202421 -125.146131) (xy 359.190295 -125.091694)
			(xy 359.186224 -125.036072) (xy 357.729552 -125.036072) (xy 357.728019 -125.04649) (xy 357.711951 -125.099897)
			(xy 357.688279 -125.150394) (xy 357.657506 -125.196907) (xy 357.620289 -125.238444) (xy 357.577421 -125.274119)
			(xy 357.529815 -125.303173) (xy 357.478486 -125.324985) (xy 357.424529 -125.339091) (xy 357.369092 -125.345191)
			(xy 357.313358 -125.343154) (xy 357.258515 -125.333024) (xy 357.205731 -125.315017) (xy 357.156131 -125.289516)
			(xy 357.110773 -125.257065) (xy 357.070624 -125.218356) (xy 357.036538 -125.174213) (xy 357.009242 -125.125578)
			(xy 356.989319 -125.073487) (xy 356.977193 -125.01905) (xy 356.973122 -124.963428) (xy 352.756724 -124.963428)
			(xy 352.756724 -125.979428) (xy 356.973122 -125.979428) (xy 356.977193 -125.923806) (xy 356.989319 -125.869369)
			(xy 357.009242 -125.817278) (xy 357.036538 -125.768643) (xy 357.070624 -125.7245) (xy 357.110773 -125.685791)
			(xy 357.156131 -125.65334) (xy 357.205731 -125.627839) (xy 357.258515 -125.609832) (xy 357.313358 -125.599702)
			(xy 357.369092 -125.597665) (xy 357.424529 -125.603765) (xy 357.478486 -125.617871) (xy 357.529815 -125.639683)
			(xy 357.577421 -125.668737) (xy 357.620289 -125.704412) (xy 357.657506 -125.745949) (xy 357.688279 -125.792462)
			(xy 357.711951 -125.842959) (xy 357.727562 -125.894846) (xy 359.386884 -125.894846) (xy 359.390955 -125.839224)
			(xy 359.403081 -125.784787) (xy 359.423004 -125.732696) (xy 359.4503 -125.684061) (xy 359.484386 -125.639918)
			(xy 359.524535 -125.601209) (xy 359.569893 -125.568758) (xy 359.619493 -125.543257) (xy 359.672277 -125.52525)
			(xy 359.72712 -125.51512) (xy 359.782854 -125.513083) (xy 359.838291 -125.519183) (xy 359.892248 -125.533289)
			(xy 359.943577 -125.555101) (xy 359.991183 -125.584155) (xy 360.034051 -125.61983) (xy 360.071268 -125.661367)
			(xy 360.102041 -125.70788) (xy 360.125713 -125.758377) (xy 360.141781 -125.811784) (xy 360.147949 -125.853698)
			(xy 364.784894 -125.853698) (xy 364.78536 -125.826328) (xy 364.793178 -125.772149) (xy 364.808667 -125.719646)
			(xy 364.831509 -125.669899) (xy 364.861233 -125.623932) (xy 364.878874 -125.603) (xy 364.879128 -125.602746)
			(xy 364.884705 -125.595653) (xy 364.890956 -125.578741) (xy 364.89132 -125.569726) (xy 364.89132 -125.50267)
			(xy 364.890973 -125.493652) (xy 364.884718 -125.476735) (xy 364.879128 -125.46965) (xy 364.878874 -125.46965)
			(xy 364.878874 -125.469396) (xy 364.861216 -125.44848) (xy 364.831507 -125.402502) (xy 364.808676 -125.352751)
			(xy 364.793189 -125.300247) (xy 364.785366 -125.246068) (xy 364.784894 -125.218698) (xy 364.78538 -125.191447)
			(xy 364.793136 -125.137499) (xy 364.808491 -125.085204) (xy 364.831133 -125.035627) (xy 364.860599 -124.989777)
			(xy 364.89629 -124.948586) (xy 364.937481 -124.912895) (xy 364.983331 -124.883429) (xy 365.032908 -124.860787)
			(xy 365.085203 -124.845432) (xy 365.139151 -124.837676) (xy 365.193653 -124.837676) (xy 365.247601 -124.845432)
			(xy 365.299896 -124.860787) (xy 365.349473 -124.883429) (xy 365.395323 -124.912895) (xy 365.436514 -124.948586)
			(xy 365.472205 -124.989777) (xy 365.501671 -125.035627) (xy 365.524313 -125.085204) (xy 365.539668 -125.137499)
			(xy 365.547424 -125.191447) (xy 365.54791 -125.218698) (xy 365.54744 -125.246068) (xy 365.539623 -125.300247)
			(xy 365.524135 -125.35275) (xy 365.501294 -125.402497) (xy 365.471571 -125.448464) (xy 365.45393 -125.469396)
			(xy 365.453676 -125.46965) (xy 365.448102 -125.476745) (xy 365.441848 -125.493655) (xy 365.441484 -125.50267)
			(xy 365.441484 -125.569726) (xy 365.441832 -125.578744) (xy 365.448086 -125.59566) (xy 365.453676 -125.602746)
			(xy 365.45393 -125.602746) (xy 365.45393 -125.603) (xy 365.471587 -125.623917) (xy 365.501295 -125.669895)
			(xy 365.524127 -125.719646) (xy 365.539614 -125.77215) (xy 365.547438 -125.826328) (xy 365.54791 -125.853698)
			(xy 365.547424 -125.880949) (xy 365.539668 -125.934897) (xy 365.524313 -125.987192) (xy 365.501671 -126.036769)
			(xy 365.472205 -126.082619) (xy 365.436514 -126.12381) (xy 365.395323 -126.159501) (xy 365.349473 -126.188967)
			(xy 365.299896 -126.211609) (xy 365.247601 -126.226964) (xy 365.193653 -126.23472) (xy 365.139151 -126.23472)
			(xy 365.085203 -126.226964) (xy 365.032908 -126.211609) (xy 364.983331 -126.188967) (xy 364.937481 -126.159501)
			(xy 364.89629 -126.12381) (xy 364.860599 -126.082619) (xy 364.831133 -126.036769) (xy 364.808491 -125.987192)
			(xy 364.793136 -125.934897) (xy 364.78538 -125.880949) (xy 364.784894 -125.853698) (xy 360.147949 -125.853698)
			(xy 360.149901 -125.86696) (xy 360.15041 -125.894846) (xy 360.149901 -125.922732) (xy 360.141781 -125.977908)
			(xy 360.125713 -126.031315) (xy 360.102041 -126.081812) (xy 360.071268 -126.128325) (xy 360.034051 -126.169862)
			(xy 359.991183 -126.205537) (xy 359.943577 -126.234591) (xy 359.892248 -126.256403) (xy 359.838291 -126.270509)
			(xy 359.782854 -126.276609) (xy 359.72712 -126.274572) (xy 359.672277 -126.264442) (xy 359.619493 -126.246435)
			(xy 359.569893 -126.220934) (xy 359.524535 -126.188483) (xy 359.484386 -126.149774) (xy 359.4503 -126.105631)
			(xy 359.423004 -126.056996) (xy 359.403081 -126.004905) (xy 359.390955 -125.950468) (xy 359.386884 -125.894846)
			(xy 357.727562 -125.894846) (xy 357.728019 -125.896366) (xy 357.736139 -125.951542) (xy 357.736648 -125.979428)
			(xy 357.736139 -126.007314) (xy 357.728019 -126.06249) (xy 357.711951 -126.115897) (xy 357.688279 -126.166394)
			(xy 357.657506 -126.212907) (xy 357.620289 -126.254444) (xy 357.577421 -126.290119) (xy 357.529815 -126.319173)
			(xy 357.478486 -126.340985) (xy 357.424529 -126.355091) (xy 357.369092 -126.361191) (xy 357.313358 -126.359154)
			(xy 357.258515 -126.349024) (xy 357.205731 -126.331017) (xy 357.156131 -126.305516) (xy 357.110773 -126.273065)
			(xy 357.070624 -126.234356) (xy 357.036538 -126.190213) (xy 357.009242 -126.141578) (xy 356.989319 -126.089487)
			(xy 356.977193 -126.03505) (xy 356.973122 -125.979428) (xy 352.756724 -125.979428) (xy 352.756724 -126.530354)
			(xy 365.993426 -126.530354) (xy 365.993968 -126.50269) (xy 366.001961 -126.447942) (xy 366.017771 -126.39492)
			(xy 366.041069 -126.344736) (xy 366.071366 -126.298439) (xy 366.108028 -126.257001) (xy 366.150286 -126.221287)
			(xy 366.173512 -126.20625) (xy 366.183163 -126.199581) (xy 366.195622 -126.179744) (xy 366.197388 -126.16815)
			(xy 366.205262 -126.08814) (xy 366.205858 -126.076503) (xy 366.197802 -126.054668) (xy 366.189768 -126.04623)
			(xy 366.189514 -126.045976) (xy 366.170942 -126.027886) (xy 366.138362 -125.987557) (xy 366.111547 -125.943184)
			(xy 366.090993 -125.895587) (xy 366.077078 -125.845645) (xy 366.070059 -125.794277) (xy 366.069626 -125.768354)
			(xy 366.070035 -125.7411) (xy 366.077799 -125.687148) (xy 366.093161 -125.63485) (xy 366.11581 -125.58527)
			(xy 366.145285 -125.539418) (xy 366.180984 -125.498228) (xy 366.222182 -125.462537) (xy 366.26804 -125.433072)
			(xy 366.317625 -125.410433) (xy 366.369926 -125.395082) (xy 366.42388 -125.387329) (xy 366.451134 -125.386846)
			(xy 366.478505 -125.387281) (xy 366.532686 -125.395105) (xy 366.58519 -125.4106) (xy 366.634937 -125.433449)
			(xy 366.680902 -125.463181) (xy 366.701832 -125.480826) (xy 366.702086 -125.48108) (xy 366.709166 -125.486676)
			(xy 366.726088 -125.492915) (xy 366.735106 -125.493272) (xy 366.802162 -125.493272) (xy 366.811178 -125.492903)
			(xy 366.828095 -125.486664) (xy 366.835182 -125.48108) (xy 366.835182 -125.480826) (xy 366.835436 -125.480826)
			(xy 366.856385 -125.463207) (xy 366.902353 -125.433492) (xy 366.952096 -125.410651) (xy 367.004593 -125.395156)
			(xy 367.058766 -125.387322) (xy 367.086134 -125.386846) (xy 367.113384 -125.387346) (xy 367.167329 -125.395106)
			(xy 367.21962 -125.410463) (xy 367.269195 -125.433105) (xy 367.315043 -125.46257) (xy 367.356231 -125.49826)
			(xy 367.391922 -125.539448) (xy 367.421389 -125.585295) (xy 367.444033 -125.634868) (xy 367.459391 -125.687159)
			(xy 367.467153 -125.741104) (xy 367.467642 -125.768354) (xy 367.467113 -125.797271) (xy 367.458389 -125.854442)
			(xy 367.441135 -125.909642) (xy 367.415745 -125.961604) (xy 367.382803 -126.009138) (xy 367.343062 -126.051155)
			(xy 367.320576 -126.069344) (xy 367.311755 -126.076938) (xy 367.30158 -126.097849) (xy 367.301018 -126.109476)
			(xy 367.301018 -126.189232) (xy 367.301547 -126.200865) (xy 367.311742 -126.221775) (xy 367.320576 -126.229364)
			(xy 367.343037 -126.247581) (xy 367.382775 -126.289595) (xy 367.415717 -126.337124) (xy 367.44111 -126.38908)
			(xy 367.45837 -126.444274) (xy 367.467104 -126.501439) (xy 367.467642 -126.530354) (xy 367.467102 -126.557604)
			(xy 367.459352 -126.611551) (xy 367.447251 -126.652782) (xy 367.738914 -126.652782) (xy 367.739366 -126.625411)
			(xy 367.747187 -126.571231) (xy 367.762679 -126.518728) (xy 367.785524 -126.468981) (xy 367.815251 -126.423015)
			(xy 367.832894 -126.402084) (xy 367.833148 -126.40183) (xy 367.838734 -126.394743) (xy 367.84498 -126.377826)
			(xy 367.84534 -126.36881) (xy 367.84534 -126.301754) (xy 367.84497 -126.292738) (xy 367.838733 -126.27582)
			(xy 367.833148 -126.268734) (xy 367.832894 -126.268734) (xy 367.832894 -126.26848) (xy 367.815237 -126.247561)
			(xy 367.785515 -126.20159) (xy 367.762673 -126.151841) (xy 367.74718 -126.099337) (xy 367.739354 -126.045158)
			(xy 367.739355 -125.990415) (xy 367.747186 -125.936236) (xy 367.762683 -125.883733) (xy 367.785529 -125.833986)
			(xy 367.815253 -125.788017) (xy 367.832894 -125.767084) (xy 367.833148 -125.76683) (xy 367.838734 -125.759743)
			(xy 367.84498 -125.742826) (xy 367.84534 -125.73381) (xy 367.84534 -125.666754) (xy 367.84497 -125.657738)
			(xy 367.838733 -125.64082) (xy 367.833148 -125.633734) (xy 367.832894 -125.633734) (xy 367.832894 -125.63348)
			(xy 367.815237 -125.612561) (xy 367.785515 -125.56659) (xy 367.762673 -125.516841) (xy 367.74718 -125.464337)
			(xy 367.739354 -125.410158) (xy 367.739355 -125.355415) (xy 367.747186 -125.301236) (xy 367.762683 -125.248733)
			(xy 367.785529 -125.198986) (xy 367.815253 -125.153017) (xy 367.832894 -125.132084) (xy 367.833148 -125.13183)
			(xy 367.838734 -125.124743) (xy 367.84498 -125.107826) (xy 367.84534 -125.09881) (xy 367.84534 -125.031754)
			(xy 367.84497 -125.022738) (xy 367.838733 -125.00582) (xy 367.833148 -124.998734) (xy 367.832894 -124.998734)
			(xy 367.832894 -124.99848) (xy 367.815278 -124.977529) (xy 367.785563 -124.931562) (xy 367.762723 -124.881819)
			(xy 367.747226 -124.829322) (xy 367.739392 -124.77515) (xy 367.738914 -124.747782) (xy 367.7394 -124.720531)
			(xy 367.747156 -124.666583) (xy 367.762511 -124.614288) (xy 367.785153 -124.564711) (xy 367.814619 -124.518861)
			(xy 367.85031 -124.47767) (xy 367.891501 -124.441979) (xy 367.937351 -124.412513) (xy 367.986928 -124.389871)
			(xy 368.039223 -124.374516) (xy 368.093171 -124.36676) (xy 368.147673 -124.36676) (xy 368.201621 -124.374516)
			(xy 368.253916 -124.389871) (xy 368.303493 -124.412513) (xy 368.349343 -124.441979) (xy 368.390534 -124.47767)
			(xy 368.426225 -124.518861) (xy 368.455691 -124.564711) (xy 368.478333 -124.614288) (xy 368.493688 -124.666583)
			(xy 368.501444 -124.720531) (xy 368.50193 -124.747782) (xy 368.50147 -124.775153) (xy 368.493654 -124.829333)
			(xy 368.478164 -124.881837) (xy 368.45532 -124.931583) (xy 368.425593 -124.977549) (xy 368.40795 -124.99848)
			(xy 368.407696 -124.998734) (xy 368.40213 -125.005835) (xy 368.395871 -125.022741) (xy 368.395504 -125.031754)
			(xy 368.395504 -125.09881) (xy 368.395855 -125.107827) (xy 368.402107 -125.124744) (xy 368.407696 -125.13183)
			(xy 368.40795 -125.13183) (xy 368.40795 -125.132084) (xy 368.425574 -125.153031) (xy 368.455301 -125.198995)
			(xy 368.478149 -125.248739) (xy 368.493648 -125.301239) (xy 368.501479 -125.355416) (xy 368.50148 -125.410156)
			(xy 368.493654 -125.464334) (xy 368.478159 -125.516835) (xy 368.455314 -125.566581) (xy 368.42559 -125.612548)
			(xy 368.40795 -125.63348) (xy 368.407696 -125.633734) (xy 368.40213 -125.640835) (xy 368.395871 -125.657741)
			(xy 368.395504 -125.666754) (xy 368.395504 -125.73381) (xy 368.395855 -125.742827) (xy 368.402107 -125.759744)
			(xy 368.407696 -125.76683) (xy 368.40795 -125.76683) (xy 368.40795 -125.767084) (xy 368.425574 -125.788031)
			(xy 368.455301 -125.833995) (xy 368.478149 -125.883739) (xy 368.493648 -125.936239) (xy 368.501479 -125.990416)
			(xy 368.50148 -126.045156) (xy 368.493654 -126.099334) (xy 368.478159 -126.151835) (xy 368.455314 -126.201581)
			(xy 368.42559 -126.247548) (xy 368.40795 -126.26848) (xy 368.407696 -126.268734) (xy 368.40213 -126.275835)
			(xy 368.395871 -126.292741) (xy 368.395504 -126.301754) (xy 368.395504 -126.36881) (xy 368.395855 -126.377827)
			(xy 368.402107 -126.394744) (xy 368.407696 -126.40183) (xy 368.40795 -126.40183) (xy 368.40795 -126.402084)
			(xy 368.425587 -126.423018) (xy 368.455301 -126.468989) (xy 368.478138 -126.518736) (xy 368.493629 -126.571237)
			(xy 368.501457 -126.625413) (xy 368.50193 -126.652782) (xy 368.501444 -126.680033) (xy 368.493688 -126.733981)
			(xy 368.478333 -126.786276) (xy 368.455691 -126.835853) (xy 368.426225 -126.881703) (xy 368.390534 -126.922894)
			(xy 368.349343 -126.958585) (xy 368.303493 -126.988051) (xy 368.253916 -127.010693) (xy 368.201621 -127.026048)
			(xy 368.147673 -127.033804) (xy 368.093171 -127.033804) (xy 368.039223 -127.026048) (xy 367.986928 -127.010693)
			(xy 367.937351 -126.988051) (xy 367.891501 -126.958585) (xy 367.85031 -126.922894) (xy 367.814619 -126.881703)
			(xy 367.785153 -126.835853) (xy 367.762511 -126.786276) (xy 367.747156 -126.733981) (xy 367.7394 -126.680033)
			(xy 367.738914 -126.652782) (xy 367.447251 -126.652782) (xy 367.444004 -126.663845) (xy 367.421369 -126.713423)
			(xy 367.391909 -126.759274) (xy 367.356223 -126.800467) (xy 367.315038 -126.836161) (xy 367.269193 -126.865631)
			(xy 367.21962 -126.888276) (xy 367.167329 -126.903635) (xy 367.113384 -126.911396) (xy 367.086134 -126.911862)
			(xy 367.059818 -126.911451) (xy 367.007687 -126.904206) (xy 366.957042 -126.889877) (xy 366.908843 -126.868734)
			(xy 366.864001 -126.841177) (xy 366.823365 -126.807728) (xy 366.80521 -126.788672) (xy 366.797677 -126.781283)
			(xy 366.778406 -126.772749) (xy 366.767872 -126.772162) (xy 366.693196 -126.772162) (xy 366.682646 -126.772687)
			(xy 366.663352 -126.781226) (xy 366.655858 -126.788672) (xy 366.63771 -126.807736) (xy 366.59708 -126.841193)
			(xy 366.552238 -126.868752) (xy 366.504035 -126.889889) (xy 366.453386 -126.904204) (xy 366.401251 -126.911426)
			(xy 366.374934 -126.911862) (xy 366.34768 -126.911413) (xy 366.293726 -126.903659) (xy 366.241425 -126.888305)
			(xy 366.191842 -126.865663) (xy 366.145987 -126.836195) (xy 366.104792 -126.800499) (xy 366.069098 -126.759304)
			(xy 366.039631 -126.713447) (xy 366.01699 -126.663864) (xy 366.001638 -126.611562) (xy 365.993886 -126.557608)
			(xy 365.993426 -126.530354) (xy 352.756724 -126.530354) (xy 352.756724 -127.051308) (xy 359.044238 -127.051308)
			(xy 359.048309 -126.995686) (xy 359.060435 -126.941249) (xy 359.080358 -126.889158) (xy 359.107654 -126.840523)
			(xy 359.14174 -126.79638) (xy 359.181889 -126.757671) (xy 359.227247 -126.72522) (xy 359.276847 -126.699719)
			(xy 359.329631 -126.681712) (xy 359.384474 -126.671582) (xy 359.440208 -126.669545) (xy 359.495645 -126.675645)
			(xy 359.549602 -126.689751) (xy 359.600931 -126.711563) (xy 359.648537 -126.740617) (xy 359.691405 -126.776292)
			(xy 359.728622 -126.817829) (xy 359.759395 -126.864342) (xy 359.783067 -126.914839) (xy 359.799135 -126.968246)
			(xy 359.807255 -127.023422) (xy 359.807764 -127.051308) (xy 359.807255 -127.079194) (xy 359.799135 -127.13437)
			(xy 359.783067 -127.187777) (xy 359.759395 -127.238274) (xy 359.728622 -127.284787) (xy 359.691405 -127.326324)
			(xy 359.648537 -127.361999) (xy 359.600931 -127.391053) (xy 359.549602 -127.412865) (xy 359.495645 -127.426971)
			(xy 359.440208 -127.433071) (xy 359.384474 -127.431034) (xy 359.329631 -127.420904) (xy 359.276847 -127.402897)
			(xy 359.227247 -127.377396) (xy 359.181889 -127.344945) (xy 359.14174 -127.306236) (xy 359.107654 -127.262093)
			(xy 359.080358 -127.213458) (xy 359.060435 -127.161367) (xy 359.048309 -127.10693) (xy 359.044238 -127.051308)
			(xy 352.756724 -127.051308) (xy 352.756724 -128.252747) (xy 358.028528 -128.252747) (xy 358.028528 -128.198253)
			(xy 358.036283 -128.144313) (xy 358.051636 -128.092025) (xy 358.074274 -128.042455) (xy 358.103736 -127.996611)
			(xy 358.139422 -127.955426) (xy 358.180606 -127.919739) (xy 358.22645 -127.890277) (xy 358.27602 -127.867638)
			(xy 358.328307 -127.852285) (xy 358.382247 -127.844529) (xy 358.409494 -127.844042) (xy 358.436865 -127.844501)
			(xy 358.491044 -127.852319) (xy 358.543548 -127.867809) (xy 358.593295 -127.890653) (xy 358.639261 -127.92038)
			(xy 358.660192 -127.938022) (xy 358.660446 -127.938276) (xy 358.667537 -127.943855) (xy 358.684451 -127.950104)
			(xy 358.693466 -127.950468) (xy 358.760522 -127.950468) (xy 358.769541 -127.950129) (xy 358.786458 -127.94387)
			(xy 358.793542 -127.938276) (xy 358.793542 -127.938022) (xy 358.793796 -127.938022) (xy 358.814729 -127.920381)
			(xy 358.860697 -127.890657) (xy 358.910443 -127.867811) (xy 358.962945 -127.852315) (xy 359.017123 -127.844486)
			(xy 359.071865 -127.844486) (xy 359.126043 -127.852315) (xy 359.178545 -127.867811) (xy 359.228291 -127.890657)
			(xy 359.274259 -127.920381) (xy 359.295192 -127.938022) (xy 359.295446 -127.938276) (xy 359.302537 -127.943855)
			(xy 359.319451 -127.950104) (xy 359.328466 -127.950468) (xy 359.395522 -127.950468) (xy 359.404541 -127.950129)
			(xy 359.421458 -127.94387) (xy 359.428542 -127.938276) (xy 359.428542 -127.938022) (xy 359.428796 -127.938022)
			(xy 359.449722 -127.920375) (xy 359.495696 -127.890663) (xy 359.545445 -127.867829) (xy 359.597947 -127.85234)
			(xy 359.652124 -127.844514) (xy 359.679494 -127.844042) (xy 359.706751 -127.844405) (xy 359.760709 -127.852162)
			(xy 359.813015 -127.867519) (xy 359.862602 -127.890165) (xy 359.908462 -127.919636) (xy 359.949661 -127.955335)
			(xy 359.98536 -127.996533) (xy 360.014833 -128.042392) (xy 360.037478 -128.091979) (xy 360.052837 -128.144285)
			(xy 360.060595 -128.198243) (xy 360.060595 -128.252757) (xy 360.052837 -128.306715) (xy 360.037478 -128.359021)
			(xy 360.014833 -128.408608) (xy 359.98536 -128.454467) (xy 359.949661 -128.495665) (xy 359.908462 -128.531364)
			(xy 359.862602 -128.560835) (xy 359.813015 -128.583481) (xy 359.760709 -128.598838) (xy 359.706751 -128.606595)
			(xy 359.679494 -128.607058) (xy 359.652123 -128.606606) (xy 359.597943 -128.598786) (xy 359.545439 -128.583294)
			(xy 359.495693 -128.560449) (xy 359.449727 -128.530721) (xy 359.428796 -128.513078) (xy 359.428542 -128.512824)
			(xy 359.421454 -128.50724) (xy 359.404538 -128.500994) (xy 359.395522 -128.500632) (xy 359.328466 -128.500632)
			(xy 359.319447 -128.500966) (xy 359.302529 -128.507229) (xy 359.295446 -128.512824) (xy 359.295192 -128.513078)
			(xy 359.274259 -128.530719) (xy 359.228291 -128.560443) (xy 359.178545 -128.583289) (xy 359.126043 -128.598785)
			(xy 359.071865 -128.606614) (xy 359.017123 -128.606614) (xy 358.962945 -128.598785) (xy 358.910443 -128.583289)
			(xy 358.860697 -128.560443) (xy 358.814729 -128.530719) (xy 358.793796 -128.513078) (xy 358.793542 -128.512824)
			(xy 358.786454 -128.50724) (xy 358.769538 -128.500994) (xy 358.760522 -128.500632) (xy 358.693466 -128.500632)
			(xy 358.684447 -128.500966) (xy 358.667529 -128.507229) (xy 358.660446 -128.512824) (xy 358.660446 -128.513078)
			(xy 358.660192 -128.513078) (xy 358.639271 -128.530731) (xy 358.593295 -128.560441) (xy 358.543545 -128.583275)
			(xy 358.491042 -128.598763) (xy 358.436864 -128.606587) (xy 358.409494 -128.607058) (xy 358.382247 -128.606471)
			(xy 358.328307 -128.598715) (xy 358.27602 -128.583362) (xy 358.22645 -128.560723) (xy 358.180606 -128.531261)
			(xy 358.139422 -128.495574) (xy 358.103736 -128.454389) (xy 358.074274 -128.408545) (xy 358.051636 -128.358975)
			(xy 358.036283 -128.306687) (xy 358.028528 -128.252747) (xy 352.756724 -128.252747) (xy 352.756724 -128.995424)
			(xy 353.680268 -128.995424) (xy 353.680754 -128.968173) (xy 353.68851 -128.914225) (xy 353.703865 -128.86193)
			(xy 353.726507 -128.812353) (xy 353.755973 -128.766503) (xy 353.791664 -128.725312) (xy 353.832855 -128.689621)
			(xy 353.878705 -128.660155) (xy 353.928282 -128.637513) (xy 353.980577 -128.622158) (xy 354.034525 -128.614402)
			(xy 354.089027 -128.614402) (xy 354.142975 -128.622158) (xy 354.19527 -128.637513) (xy 354.244847 -128.660155)
			(xy 354.290697 -128.689621) (xy 354.331888 -128.725312) (xy 354.367579 -128.766503) (xy 354.397045 -128.812353)
			(xy 354.419687 -128.86193) (xy 354.435042 -128.914225) (xy 354.442798 -128.968173) (xy 354.443284 -128.995424)
			(xy 354.442716 -129.02523) (xy 354.433422 -129.084112) (xy 354.415081 -129.140832) (xy 354.388139 -129.194007)
			(xy 354.353252 -129.242344) (xy 354.311269 -129.284664) (xy 354.287582 -129.302764) (xy 354.276455 -129.31143)
			(xy 354.25915 -129.333688) (xy 354.248595 -129.359833) (xy 354.245596 -129.387867) (xy 354.250383 -129.415652)
			(xy 354.262589 -129.441068) (xy 354.281284 -129.462173) (xy 354.292916 -129.47015) (xy 354.315638 -129.485287)
			(xy 354.356946 -129.520983) (xy 354.392746 -129.562203) (xy 354.422305 -129.608104) (xy 354.44502 -129.657749)
			(xy 354.460429 -129.710125) (xy 354.468215 -129.764162) (xy 354.468684 -129.79146) (xy 354.468198 -129.818711)
			(xy 354.460442 -129.872659) (xy 354.445087 -129.924954) (xy 354.422445 -129.974531) (xy 354.392979 -130.020381)
			(xy 354.357288 -130.061572) (xy 354.316097 -130.097263) (xy 354.270247 -130.126729) (xy 354.22067 -130.149371)
			(xy 354.168375 -130.164726) (xy 354.114427 -130.172482) (xy 354.059925 -130.172482) (xy 354.005977 -130.164726)
			(xy 353.953682 -130.149371) (xy 353.904105 -130.126729) (xy 353.858255 -130.097263) (xy 353.817064 -130.061572)
			(xy 353.781373 -130.020381) (xy 353.751907 -129.974531) (xy 353.729265 -129.924954) (xy 353.71391 -129.872659)
			(xy 353.706154 -129.818711) (xy 353.705668 -129.79146) (xy 353.706203 -129.761653) (xy 353.715501 -129.702768)
			(xy 353.733847 -129.646047) (xy 353.760795 -129.592871) (xy 353.795689 -129.544535) (xy 353.837679 -129.502218)
			(xy 353.86137 -129.48412) (xy 353.872506 -129.475469) (xy 353.889803 -129.453204) (xy 353.900351 -129.427058)
			(xy 353.903345 -129.399023) (xy 353.898558 -129.371239) (xy 353.886355 -129.345823) (xy 353.867666 -129.324714)
			(xy 353.856036 -129.316734) (xy 353.833296 -129.301624) (xy 353.79199 -129.265921) (xy 353.756194 -129.224696)
			(xy 353.726638 -129.17879) (xy 353.703925 -129.129141) (xy 353.688519 -129.076762) (xy 353.680736 -129.022723)
			(xy 353.680268 -128.995424) (xy 352.756724 -128.995424) (xy 352.756724 -131.447157) (xy 358.013409 -131.447157)
			(xy 358.013409 -131.392643) (xy 358.021167 -131.338685) (xy 358.036525 -131.28638) (xy 358.059171 -131.236794)
			(xy 358.088644 -131.190935) (xy 358.124342 -131.149737) (xy 358.165541 -131.114039) (xy 358.211401 -131.084567)
			(xy 358.260988 -131.061923) (xy 358.313293 -131.046565) (xy 358.367251 -131.038808) (xy 358.394508 -131.038346)
			(xy 358.421879 -131.038796) (xy 358.476059 -131.046616) (xy 358.528563 -131.062108) (xy 358.57831 -131.084954)
			(xy 358.624275 -131.114683) (xy 358.645206 -131.132326) (xy 358.64546 -131.13258) (xy 358.652547 -131.138165)
			(xy 358.669464 -131.144411) (xy 358.67848 -131.144772) (xy 358.745536 -131.144772) (xy 358.754555 -131.144438)
			(xy 358.771472 -131.138175) (xy 358.778556 -131.13258) (xy 358.778556 -131.132326) (xy 358.77881 -131.132326)
			(xy 358.799743 -131.114685) (xy 358.845711 -131.084961) (xy 358.895457 -131.062115) (xy 358.947959 -131.046619)
			(xy 359.002137 -131.03879) (xy 359.056879 -131.03879) (xy 359.111057 -131.046619) (xy 359.163559 -131.062115)
			(xy 359.213305 -131.084961) (xy 359.259273 -131.114685) (xy 359.280206 -131.132326) (xy 359.28046 -131.13258)
			(xy 359.287547 -131.138165) (xy 359.304464 -131.144411) (xy 359.31348 -131.144772) (xy 359.380536 -131.144772)
			(xy 359.389555 -131.144438) (xy 359.406472 -131.138175) (xy 359.413556 -131.13258) (xy 359.413556 -131.132326)
			(xy 359.41381 -131.132326) (xy 359.434731 -131.114673) (xy 359.480706 -131.084962) (xy 359.530457 -131.062129)
			(xy 359.58296 -131.046641) (xy 359.637138 -131.038817) (xy 359.664508 -131.038346) (xy 359.691756 -131.038925)
			(xy 359.745696 -131.046681) (xy 359.797983 -131.062035) (xy 359.847553 -131.084674) (xy 359.893397 -131.114137)
			(xy 359.934582 -131.149824) (xy 359.970268 -131.191009) (xy 359.99973 -131.236854) (xy 360.022368 -131.286424)
			(xy 360.037721 -131.338712) (xy 360.045476 -131.392652) (xy 360.045476 -131.447148) (xy 360.037721 -131.501088)
			(xy 360.022368 -131.553376) (xy 359.99973 -131.602946) (xy 359.970268 -131.648791) (xy 359.934582 -131.689976)
			(xy 359.893397 -131.725663) (xy 359.847553 -131.755126) (xy 359.797983 -131.777765) (xy 359.745696 -131.793119)
			(xy 359.691756 -131.800875) (xy 359.664508 -131.801362) (xy 359.637137 -131.800901) (xy 359.582958 -131.793083)
			(xy 359.530454 -131.777593) (xy 359.480708 -131.75475) (xy 359.434741 -131.725024) (xy 359.41381 -131.707382)
			(xy 359.413556 -131.707128) (xy 359.406464 -131.70155) (xy 359.389551 -131.6953) (xy 359.380536 -131.694936)
			(xy 359.31348 -131.694936) (xy 359.304461 -131.695276) (xy 359.287544 -131.701534) (xy 359.28046 -131.707128)
			(xy 359.280206 -131.707382) (xy 359.259273 -131.725023) (xy 359.213305 -131.754747) (xy 359.163559 -131.777593)
			(xy 359.111057 -131.793089) (xy 359.056879 -131.800918) (xy 359.002137 -131.800918) (xy 358.947959 -131.793089)
			(xy 358.895457 -131.777593) (xy 358.845711 -131.754747) (xy 358.799743 -131.725023) (xy 358.77881 -131.707382)
			(xy 358.778556 -131.707128) (xy 358.771464 -131.70155) (xy 358.754551 -131.6953) (xy 358.745536 -131.694936)
			(xy 358.67848 -131.694936) (xy 358.669461 -131.695276) (xy 358.652544 -131.701534) (xy 358.64546 -131.707128)
			(xy 358.64546 -131.707382) (xy 358.645206 -131.707382) (xy 358.62428 -131.725029) (xy 358.578306 -131.75474)
			(xy 358.528557 -131.777575) (xy 358.476055 -131.793064) (xy 358.421878 -131.80089) (xy 358.394508 -131.801362)
			(xy 358.367251 -131.800992) (xy 358.313293 -131.793235) (xy 358.260988 -131.777877) (xy 358.211401 -131.755233)
			(xy 358.165541 -131.725761) (xy 358.124342 -131.690063) (xy 358.088644 -131.648865) (xy 358.059171 -131.603006)
			(xy 358.036525 -131.55342) (xy 358.021167 -131.501115) (xy 358.013409 -131.447157) (xy 352.756724 -131.447157)
			(xy 352.756724 -133.443726) (xy 359.422954 -133.443726) (xy 359.423421 -133.417412) (xy 359.430654 -133.365283)
			(xy 359.444972 -133.314639) (xy 359.466104 -133.26644) (xy 359.493651 -133.221596) (xy 359.527091 -133.180958)
			(xy 359.546144 -133.162802) (xy 359.553538 -133.155274) (xy 359.562069 -133.135999) (xy 359.562654 -133.125464)
			(xy 359.562654 -133.050788) (xy 359.562158 -133.040234) (xy 359.553601 -133.020938) (xy 359.546144 -133.01345)
			(xy 359.527061 -132.995323) (xy 359.493608 -132.954686) (xy 359.466054 -132.909839) (xy 359.444921 -132.861633)
			(xy 359.430609 -132.810981) (xy 359.42339 -132.758844) (xy 359.422954 -132.732526) (xy 359.42344 -132.705275)
			(xy 359.431196 -132.651327) (xy 359.446551 -132.599032) (xy 359.469193 -132.549455) (xy 359.498659 -132.503605)
			(xy 359.53435 -132.462414) (xy 359.575541 -132.426723) (xy 359.621391 -132.397257) (xy 359.670968 -132.374615)
			(xy 359.723263 -132.35926) (xy 359.777211 -132.351504) (xy 359.831713 -132.351504) (xy 359.885661 -132.35926)
			(xy 359.937956 -132.374615) (xy 359.987533 -132.397257) (xy 360.033383 -132.426723) (xy 360.074574 -132.462414)
			(xy 360.110265 -132.503605) (xy 360.139731 -132.549455) (xy 360.162373 -132.599032) (xy 360.177728 -132.651327)
			(xy 360.185484 -132.705275) (xy 360.18597 -132.732526) (xy 360.185529 -132.758841) (xy 360.17829 -132.810971)
			(xy 360.163967 -132.861615) (xy 360.142829 -132.909814) (xy 360.115278 -132.954657) (xy 360.081834 -132.995295)
			(xy 360.06278 -133.01345) (xy 360.055351 -133.020948) (xy 360.046843 -133.040246) (xy 360.04627 -133.050788)
			(xy 360.04627 -133.125464) (xy 360.046814 -133.136012) (xy 360.05534 -133.155307) (xy 360.06278 -133.162802)
			(xy 360.081826 -133.180968) (xy 360.115285 -133.221595) (xy 360.142845 -133.266433) (xy 360.163986 -133.314632)
			(xy 360.178305 -133.365278) (xy 360.185531 -133.41741) (xy 360.18597 -133.443726) (xy 360.185484 -133.470977)
			(xy 360.177728 -133.524925) (xy 360.162373 -133.57722) (xy 360.139731 -133.626797) (xy 360.110265 -133.672647)
			(xy 360.074574 -133.713838) (xy 360.033383 -133.749529) (xy 359.987533 -133.778995) (xy 359.937956 -133.801637)
			(xy 359.885661 -133.816992) (xy 359.831713 -133.824748) (xy 359.777211 -133.824748) (xy 359.723263 -133.816992)
			(xy 359.670968 -133.801637) (xy 359.621391 -133.778995) (xy 359.575541 -133.749529) (xy 359.53435 -133.713838)
			(xy 359.498659 -133.672647) (xy 359.469193 -133.626797) (xy 359.446551 -133.57722) (xy 359.431196 -133.524925)
			(xy 359.42344 -133.470977) (xy 359.422954 -133.443726) (xy 352.756724 -133.443726) (xy 352.756724 -134.042404)
			(xy 354.476048 -134.042404) (xy 354.480119 -133.986782) (xy 354.492245 -133.932345) (xy 354.512168 -133.880254)
			(xy 354.539464 -133.831619) (xy 354.57355 -133.787476) (xy 354.613699 -133.748767) (xy 354.659057 -133.716316)
			(xy 354.708657 -133.690815) (xy 354.761441 -133.672808) (xy 354.816284 -133.662678) (xy 354.872018 -133.660641)
			(xy 354.927455 -133.666741) (xy 354.981412 -133.680847) (xy 355.032741 -133.702659) (xy 355.080347 -133.731713)
			(xy 355.123215 -133.767388) (xy 355.160432 -133.808925) (xy 355.191205 -133.855438) (xy 355.214877 -133.905935)
			(xy 355.230945 -133.959342) (xy 355.239065 -134.014518) (xy 355.239574 -134.042404) (xy 355.239065 -134.07029)
			(xy 355.230945 -134.125466) (xy 355.214877 -134.178873) (xy 355.191205 -134.22937) (xy 355.160432 -134.275883)
			(xy 355.123215 -134.31742) (xy 355.080347 -134.353095) (xy 355.032741 -134.382149) (xy 354.981412 -134.403961)
			(xy 354.927455 -134.418067) (xy 354.872018 -134.424167) (xy 354.816284 -134.42213) (xy 354.761441 -134.412)
			(xy 354.708657 -134.393993) (xy 354.659057 -134.368492) (xy 354.613699 -134.336041) (xy 354.57355 -134.297332)
			(xy 354.539464 -134.253189) (xy 354.512168 -134.204554) (xy 354.492245 -134.152463) (xy 354.480119 -134.098026)
			(xy 354.476048 -134.042404) (xy 352.756724 -134.042404) (xy 352.756724 -135.142051) (xy 357.66197 -135.142051)
			(xy 357.66197 -135.087549) (xy 357.669726 -135.033603) (xy 357.68508 -134.981309) (xy 357.707719 -134.931733)
			(xy 357.737184 -134.885883) (xy 357.772873 -134.844693) (xy 357.814061 -134.809) (xy 357.859908 -134.779533)
			(xy 357.909483 -134.756889) (xy 357.961776 -134.741532) (xy 358.015721 -134.733772) (xy 358.042972 -134.733284)
			(xy 358.07189 -134.73379) (xy 358.129063 -134.742517) (xy 358.184263 -134.759776) (xy 358.236226 -134.785169)
			(xy 358.283759 -134.818117) (xy 358.325774 -134.857862) (xy 358.343962 -134.88035) (xy 358.351755 -134.889337)
			(xy 358.37322 -134.899526) (xy 358.38511 -134.899908) (xy 358.478582 -134.897876) (xy 358.499918 -134.8867)
			(xy 358.506776 -134.876794) (xy 358.522175 -134.855885) (xy 358.557753 -134.818058) (xy 358.598132 -134.785406)
			(xy 358.642566 -134.758531) (xy 358.690235 -134.737931) (xy 358.740256 -134.723985) (xy 358.791707 -134.716952)
			(xy 358.817672 -134.71652) (xy 358.845042 -134.716998) (xy 358.899221 -134.724812) (xy 358.951724 -134.740298)
			(xy 359.001471 -134.763137) (xy 359.047438 -134.79286) (xy 359.06837 -134.8105) (xy 359.068624 -134.810754)
			(xy 359.075695 -134.816363) (xy 359.092624 -134.822595) (xy 359.101644 -134.822946) (xy 359.1687 -134.822946)
			(xy 359.177718 -134.822601) (xy 359.194636 -134.816346) (xy 359.20172 -134.810754) (xy 359.20172 -134.8105)
			(xy 359.201974 -134.8105) (xy 359.222907 -134.792859) (xy 359.268875 -134.763135) (xy 359.318621 -134.740289)
			(xy 359.371123 -134.724793) (xy 359.425301 -134.716964) (xy 359.480043 -134.716964) (xy 359.534221 -134.724793)
			(xy 359.586723 -134.740289) (xy 359.636469 -134.763135) (xy 359.682437 -134.792859) (xy 359.70337 -134.8105)
			(xy 359.703624 -134.810754) (xy 359.710695 -134.816363) (xy 359.727624 -134.822595) (xy 359.736644 -134.822946)
			(xy 359.8037 -134.822946) (xy 359.812718 -134.822601) (xy 359.829636 -134.816346) (xy 359.83672 -134.810754)
			(xy 359.837228 -134.8105) (xy 359.849966 -134.79956) (xy 359.877055 -134.779716) (xy 359.89133 -134.770876)
			(xy 359.90022 -134.765542) (xy 359.912412 -134.748524) (xy 359.932732 -134.655306) (xy 359.928414 -134.634732)
			(xy 359.922572 -134.626096) (xy 359.906565 -134.602037) (xy 359.881225 -134.550103) (xy 359.864001 -134.494944)
			(xy 359.855288 -134.437819) (xy 359.854754 -134.408926) (xy 359.85524 -134.381675) (xy 359.862996 -134.327727)
			(xy 359.878351 -134.275432) (xy 359.900993 -134.225855) (xy 359.930459 -134.180005) (xy 359.96615 -134.138814)
			(xy 360.007341 -134.103123) (xy 360.053191 -134.073657) (xy 360.102768 -134.051015) (xy 360.155063 -134.03566)
			(xy 360.209011 -134.027904) (xy 360.263513 -134.027904) (xy 360.317461 -134.03566) (xy 360.369756 -134.051015)
			(xy 360.419333 -134.073657) (xy 360.465183 -134.103123) (xy 360.506374 -134.138814) (xy 360.542065 -134.180005)
			(xy 360.571531 -134.225855) (xy 360.594173 -134.275432) (xy 360.609528 -134.327727) (xy 360.617284 -134.381675)
			(xy 360.61777 -134.408926) (xy 360.617319 -134.437019) (xy 360.609086 -134.492599) (xy 360.592789 -134.546371)
			(xy 360.56878 -134.597169) (xy 360.537578 -134.643895) (xy 360.499859 -134.685539) (xy 360.456438 -134.721198)
			(xy 360.432604 -134.736078) (xy 360.423714 -134.741412) (xy 360.411522 -134.75843) (xy 360.391202 -134.851648)
			(xy 360.39552 -134.872222) (xy 360.401362 -134.880858) (xy 360.417342 -134.904935) (xy 360.44269 -134.956861)
			(xy 360.459922 -135.012015) (xy 360.468643 -135.069137) (xy 360.46918 -135.098028) (xy 360.468748 -135.125281)
			(xy 360.460987 -135.179232) (xy 360.445627 -135.23153) (xy 360.422981 -135.281109) (xy 360.393509 -135.326961)
			(xy 360.357812 -135.368151) (xy 360.316616 -135.403842) (xy 360.27076 -135.433307) (xy 360.221177 -135.455947)
			(xy 360.168878 -135.471299) (xy 360.114925 -135.479052) (xy 360.087672 -135.479536) (xy 360.0603 -135.479102)
			(xy 360.006119 -135.471279) (xy 359.953615 -135.455783) (xy 359.903869 -135.432934) (xy 359.857904 -135.403201)
			(xy 359.836974 -135.385556) (xy 359.83672 -135.385302) (xy 359.829632 -135.379718) (xy 359.812716 -135.37347)
			(xy 359.8037 -135.37311) (xy 359.736644 -135.37311) (xy 359.727629 -135.373486) (xy 359.710712 -135.37972)
			(xy 359.703624 -135.385302) (xy 359.703624 -135.385556) (xy 359.70337 -135.385556) (xy 359.682437 -135.403197)
			(xy 359.636469 -135.432921) (xy 359.586723 -135.455767) (xy 359.534221 -135.471263) (xy 359.480043 -135.479092)
			(xy 359.425301 -135.479092) (xy 359.371123 -135.471263) (xy 359.318621 -135.455767) (xy 359.268875 -135.432921)
			(xy 359.222907 -135.403197) (xy 359.201974 -135.385556) (xy 359.20172 -135.385302) (xy 359.194632 -135.379718)
			(xy 359.177716 -135.37347) (xy 359.1687 -135.37311) (xy 359.101644 -135.37311) (xy 359.092629 -135.373486)
			(xy 359.075712 -135.37972) (xy 359.068624 -135.385302) (xy 359.068624 -135.385556) (xy 359.06837 -135.385556)
			(xy 359.047417 -135.403169) (xy 359.00145 -135.432886) (xy 358.951708 -135.455728) (xy 358.899212 -135.471225)
			(xy 358.84504 -135.479059) (xy 358.817672 -135.479536) (xy 358.788756 -135.47899) (xy 358.731585 -135.47027)
			(xy 358.676386 -135.453019) (xy 358.624423 -135.427633) (xy 358.576889 -135.394693) (xy 358.534872 -135.354954)
			(xy 358.516682 -135.33247) (xy 358.508866 -135.323507) (xy 358.487419 -135.313305) (xy 358.475534 -135.312912)
			(xy 358.382062 -135.314944) (xy 358.360726 -135.32612) (xy 358.353868 -135.336026) (xy 358.338447 -135.356919)
			(xy 358.302873 -135.394745) (xy 358.262497 -135.427398) (xy 358.218066 -135.454275) (xy 358.170402 -135.474878)
			(xy 358.120383 -135.488827) (xy 358.068936 -135.495865) (xy 358.042972 -135.4963) (xy 358.015721 -135.495828)
			(xy 357.961776 -135.488068) (xy 357.909483 -135.472711) (xy 357.859908 -135.450067) (xy 357.814061 -135.4206)
			(xy 357.772873 -135.384907) (xy 357.737184 -135.343717) (xy 357.707719 -135.297867) (xy 357.68508 -135.248291)
			(xy 357.669726 -135.195997) (xy 357.66197 -135.142051) (xy 352.756724 -135.142051) (xy 352.756724 -135.689594)
			(xy 355.583234 -135.689594) (xy 355.587305 -135.633972) (xy 355.599431 -135.579535) (xy 355.619354 -135.527444)
			(xy 355.64665 -135.478809) (xy 355.680736 -135.434666) (xy 355.720885 -135.395957) (xy 355.766243 -135.363506)
			(xy 355.815843 -135.338005) (xy 355.868627 -135.319998) (xy 355.92347 -135.309868) (xy 355.979204 -135.307831)
			(xy 356.034641 -135.313931) (xy 356.088598 -135.328037) (xy 356.139927 -135.349849) (xy 356.187533 -135.378903)
			(xy 356.230401 -135.414578) (xy 356.267618 -135.456115) (xy 356.298391 -135.502628) (xy 356.322063 -135.553125)
			(xy 356.338131 -135.606532) (xy 356.346251 -135.661708) (xy 356.34676 -135.689594) (xy 356.346251 -135.71748)
			(xy 356.338131 -135.772656) (xy 356.322063 -135.826063) (xy 356.302926 -135.866886) (xy 356.73995 -135.866886)
			(xy 356.744021 -135.811264) (xy 356.756147 -135.756827) (xy 356.77607 -135.704736) (xy 356.803366 -135.656101)
			(xy 356.837452 -135.611958) (xy 356.877601 -135.573249) (xy 356.922959 -135.540798) (xy 356.972559 -135.515297)
			(xy 357.025343 -135.49729) (xy 357.080186 -135.48716) (xy 357.13592 -135.485123) (xy 357.191357 -135.491223)
			(xy 357.245314 -135.505329) (xy 357.296643 -135.527141) (xy 357.344249 -135.556195) (xy 357.387117 -135.59187)
			(xy 357.424334 -135.633407) (xy 357.455107 -135.67992) (xy 357.478779 -135.730417) (xy 357.494847 -135.783824)
			(xy 357.502967 -135.839) (xy 357.503476 -135.866886) (xy 357.502967 -135.894772) (xy 357.494847 -135.949948)
			(xy 357.478779 -136.003355) (xy 357.455107 -136.053852) (xy 357.424334 -136.100365) (xy 357.387117 -136.141902)
			(xy 357.344249 -136.177577) (xy 357.296643 -136.206631) (xy 357.245314 -136.228443) (xy 357.191357 -136.242549)
			(xy 357.13592 -136.248649) (xy 357.080186 -136.246612) (xy 357.025343 -136.236482) (xy 356.972559 -136.218475)
			(xy 356.922959 -136.192974) (xy 356.877601 -136.160523) (xy 356.837452 -136.121814) (xy 356.803366 -136.077671)
			(xy 356.77607 -136.029036) (xy 356.756147 -135.976945) (xy 356.744021 -135.922508) (xy 356.73995 -135.866886)
			(xy 356.302926 -135.866886) (xy 356.298391 -135.87656) (xy 356.267618 -135.923073) (xy 356.230401 -135.96461)
			(xy 356.187533 -136.000285) (xy 356.139927 -136.029339) (xy 356.088598 -136.051151) (xy 356.034641 -136.065257)
			(xy 355.979204 -136.071357) (xy 355.92347 -136.06932) (xy 355.868627 -136.05919) (xy 355.815843 -136.041183)
			(xy 355.766243 -136.015682) (xy 355.720885 -135.983231) (xy 355.680736 -135.944522) (xy 355.64665 -135.900379)
			(xy 355.619354 -135.851744) (xy 355.599431 -135.799653) (xy 355.587305 -135.745216) (xy 355.583234 -135.689594)
			(xy 352.756724 -135.689594) (xy 352.756724 -137.44829) (xy 356.645208 -137.44829) (xy 356.649279 -137.392668)
			(xy 356.661405 -137.338231) (xy 356.681328 -137.28614) (xy 356.708624 -137.237505) (xy 356.74271 -137.193362)
			(xy 356.782859 -137.154653) (xy 356.828217 -137.122202) (xy 356.877817 -137.096701) (xy 356.930601 -137.078694)
			(xy 356.985444 -137.068564) (xy 357.041178 -137.066527) (xy 357.096615 -137.072627) (xy 357.150572 -137.086733)
			(xy 357.201901 -137.108545) (xy 357.249507 -137.137599) (xy 357.292375 -137.173274) (xy 357.329592 -137.214811)
			(xy 357.360365 -137.261324) (xy 357.3674 -137.276332) (xy 361.347258 -137.276332) (xy 361.347662 -137.250016)
			(xy 361.354907 -137.197884) (xy 361.369237 -137.147239) (xy 361.390382 -137.09904) (xy 361.41794 -137.054198)
			(xy 361.451391 -137.013562) (xy 361.470448 -136.995408) (xy 361.47784 -136.987878) (xy 361.486372 -136.968605)
			(xy 361.486958 -136.95807) (xy 361.486958 -136.883394) (xy 361.486458 -136.872841) (xy 361.477904 -136.853545)
			(xy 361.470448 -136.846056) (xy 361.451368 -136.827925) (xy 361.417915 -136.787289) (xy 361.390361 -136.742443)
			(xy 361.369227 -136.694238) (xy 361.354914 -136.643586) (xy 361.347694 -136.591449) (xy 361.347258 -136.565132)
			(xy 361.347744 -136.537881) (xy 361.3555 -136.483933) (xy 361.370855 -136.431638) (xy 361.393497 -136.382061)
			(xy 361.422963 -136.336211) (xy 361.458654 -136.29502) (xy 361.499845 -136.259329) (xy 361.545695 -136.229863)
			(xy 361.595272 -136.207221) (xy 361.647567 -136.191866) (xy 361.701515 -136.18411) (xy 361.756017 -136.18411)
			(xy 361.809965 -136.191866) (xy 361.86226 -136.207221) (xy 361.911837 -136.229863) (xy 361.957687 -136.259329)
			(xy 361.998878 -136.29502) (xy 362.034569 -136.336211) (xy 362.064035 -136.382061) (xy 362.086677 -136.431638)
			(xy 362.102032 -136.483933) (xy 362.109788 -136.537881) (xy 362.110274 -136.565132) (xy 362.109836 -136.591447)
			(xy 362.102596 -136.643577) (xy 362.088272 -136.694221) (xy 362.067134 -136.74242) (xy 362.039582 -136.787263)
			(xy 362.006138 -136.827901) (xy 361.987084 -136.846056) (xy 361.979697 -136.85359) (xy 361.971165 -136.872861)
			(xy 361.970574 -136.883394) (xy 361.970574 -136.95807) (xy 361.971114 -136.968618) (xy 361.979642 -136.987913)
			(xy 361.987084 -136.995408) (xy 362.006133 -137.01357) (xy 362.039592 -137.054198) (xy 362.067152 -137.099037)
			(xy 362.088292 -137.147236) (xy 362.10261 -137.197883) (xy 362.109835 -137.250016) (xy 362.110274 -137.276332)
			(xy 362.109788 -137.303583) (xy 362.102032 -137.357531) (xy 362.086677 -137.409826) (xy 362.064035 -137.459403)
			(xy 362.034569 -137.505253) (xy 361.998878 -137.546444) (xy 361.957687 -137.582135) (xy 361.911837 -137.611601)
			(xy 361.86226 -137.634243) (xy 361.809965 -137.649598) (xy 361.756017 -137.657354) (xy 361.701515 -137.657354)
			(xy 361.647567 -137.649598) (xy 361.595272 -137.634243) (xy 361.545695 -137.611601) (xy 361.499845 -137.582135)
			(xy 361.458654 -137.546444) (xy 361.422963 -137.505253) (xy 361.393497 -137.459403) (xy 361.370855 -137.409826)
			(xy 361.3555 -137.357531) (xy 361.347744 -137.303583) (xy 361.347258 -137.276332) (xy 357.3674 -137.276332)
			(xy 357.384037 -137.311821) (xy 357.400105 -137.365228) (xy 357.408225 -137.420404) (xy 357.408734 -137.44829)
			(xy 357.408225 -137.476176) (xy 357.400105 -137.531352) (xy 357.384037 -137.584759) (xy 357.360365 -137.635256)
			(xy 357.329592 -137.681769) (xy 357.292375 -137.723306) (xy 357.288328 -137.726674) (xy 362.28782 -137.726674)
			(xy 362.288266 -137.699303) (xy 362.296088 -137.645123) (xy 362.311581 -137.592619) (xy 362.334428 -137.542873)
			(xy 362.364157 -137.496907) (xy 362.3818 -137.475976) (xy 362.382054 -137.475722) (xy 362.387644 -137.468638)
			(xy 362.393887 -137.451719) (xy 362.394246 -137.442702) (xy 362.394246 -137.375646) (xy 362.393879 -137.36663)
			(xy 362.38764 -137.349712) (xy 362.382054 -137.342626) (xy 362.3818 -137.342626) (xy 362.3818 -137.342372)
			(xy 362.364181 -137.321424) (xy 362.334466 -137.275455) (xy 362.311626 -137.225712) (xy 362.296131 -137.173215)
			(xy 362.288297 -137.119042) (xy 362.28782 -137.091674) (xy 362.288306 -137.064423) (xy 362.296062 -137.010475)
			(xy 362.311417 -136.95818) (xy 362.334059 -136.908603) (xy 362.363525 -136.862753) (xy 362.399216 -136.821562)
			(xy 362.440407 -136.785871) (xy 362.486257 -136.756405) (xy 362.535834 -136.733763) (xy 362.588129 -136.718408)
			(xy 362.642077 -136.710652) (xy 362.696579 -136.710652) (xy 362.750527 -136.718408) (xy 362.802822 -136.733763)
			(xy 362.852399 -136.756405) (xy 362.898249 -136.785871) (xy 362.93944 -136.821562) (xy 362.975131 -136.862753)
			(xy 363.004597 -136.908603) (xy 363.027239 -136.95818) (xy 363.042594 -137.010475) (xy 363.05035 -137.064423)
			(xy 363.050836 -137.091674) (xy 363.05037 -137.119044) (xy 363.042555 -137.173224) (xy 363.027066 -137.225728)
			(xy 363.004224 -137.275475) (xy 362.974498 -137.321441) (xy 362.956856 -137.342372) (xy 362.956602 -137.342626)
			(xy 362.95104 -137.34973) (xy 362.944779 -137.366633) (xy 362.94441 -137.375646) (xy 362.94441 -137.442702)
			(xy 362.944764 -137.451719) (xy 362.951013 -137.468636) (xy 362.956602 -137.475722) (xy 362.956856 -137.475722)
			(xy 362.956856 -137.475976) (xy 362.97449 -137.496912) (xy 363.004205 -137.542883) (xy 363.027042 -137.592629)
			(xy 363.042534 -137.64513) (xy 363.050362 -137.699305) (xy 363.050836 -137.726674) (xy 363.05035 -137.753925)
			(xy 363.042594 -137.807873) (xy 363.027239 -137.860168) (xy 363.004597 -137.909745) (xy 362.975131 -137.955595)
			(xy 362.93944 -137.996786) (xy 362.898249 -138.032477) (xy 362.852399 -138.061943) (xy 362.802822 -138.084585)
			(xy 362.750527 -138.09994) (xy 362.696579 -138.107696) (xy 362.642077 -138.107696) (xy 362.588129 -138.09994)
			(xy 362.535834 -138.084585) (xy 362.486257 -138.061943) (xy 362.440407 -138.032477) (xy 362.399216 -137.996786)
			(xy 362.363525 -137.955595) (xy 362.334059 -137.909745) (xy 362.311417 -137.860168) (xy 362.296062 -137.807873)
			(xy 362.288306 -137.753925) (xy 362.28782 -137.726674) (xy 357.288328 -137.726674) (xy 357.249507 -137.758981)
			(xy 357.201901 -137.788035) (xy 357.150572 -137.809847) (xy 357.096615 -137.823953) (xy 357.041178 -137.830053)
			(xy 356.985444 -137.828016) (xy 356.930601 -137.817886) (xy 356.877817 -137.799879) (xy 356.828217 -137.774378)
			(xy 356.782859 -137.741927) (xy 356.74271 -137.703218) (xy 356.708624 -137.659075) (xy 356.681328 -137.61044)
			(xy 356.661405 -137.558349) (xy 356.649279 -137.503912) (xy 356.645208 -137.44829) (xy 352.756724 -137.44829)
			(xy 352.756724 -138.360404) (xy 354.476048 -138.360404) (xy 354.480119 -138.304782) (xy 354.492245 -138.250345)
			(xy 354.512168 -138.198254) (xy 354.539464 -138.149619) (xy 354.57355 -138.105476) (xy 354.613699 -138.066767)
			(xy 354.659057 -138.034316) (xy 354.708657 -138.008815) (xy 354.761441 -137.990808) (xy 354.816284 -137.980678)
			(xy 354.872018 -137.978641) (xy 354.927455 -137.984741) (xy 354.981412 -137.998847) (xy 355.032741 -138.020659)
			(xy 355.080347 -138.049713) (xy 355.123215 -138.085388) (xy 355.160432 -138.126925) (xy 355.191205 -138.173438)
			(xy 355.214877 -138.223935) (xy 355.230945 -138.277342) (xy 355.239065 -138.332518) (xy 355.239574 -138.360404)
			(xy 355.239065 -138.38829) (xy 355.236852 -138.40333) (xy 363.496352 -138.40333) (xy 363.496863 -138.375665)
			(xy 363.50486 -138.320914) (xy 363.520675 -138.267892) (xy 363.543977 -138.217707) (xy 363.574279 -138.171411)
			(xy 363.610946 -138.129973) (xy 363.65321 -138.094262) (xy 363.676438 -138.079226) (xy 363.686103 -138.072575)
			(xy 363.698554 -138.052724) (xy 363.700314 -138.041126) (xy 363.708188 -137.961116) (xy 363.708791 -137.949479)
			(xy 363.700729 -137.927644) (xy 363.692694 -137.919206) (xy 363.69244 -137.918952) (xy 363.673861 -137.900869)
			(xy 363.641281 -137.860538) (xy 363.614466 -137.816165) (xy 363.593913 -137.768567) (xy 363.58 -137.718622)
			(xy 363.572983 -137.667253) (xy 363.572552 -137.64133) (xy 363.573106 -137.614081) (xy 363.580857 -137.560138)
			(xy 363.596207 -137.507847) (xy 363.618841 -137.458273) (xy 363.648301 -137.412424) (xy 363.683985 -137.371235)
			(xy 363.725168 -137.335543) (xy 363.771011 -137.306075) (xy 363.820582 -137.283431) (xy 363.87287 -137.268072)
			(xy 363.926811 -137.260311) (xy 363.95406 -137.259822) (xy 363.98143 -137.260306) (xy 364.035608 -137.268119)
			(xy 364.088111 -137.283603) (xy 364.137858 -137.306441) (xy 364.183826 -137.336162) (xy 364.204758 -137.353802)
			(xy 364.205012 -137.354056) (xy 364.212086 -137.35966) (xy 364.229013 -137.365895) (xy 364.238032 -137.366248)
			(xy 364.305088 -137.366248) (xy 364.314106 -137.365896) (xy 364.331023 -137.359646) (xy 364.338108 -137.354056)
			(xy 364.338108 -137.353802) (xy 364.338362 -137.353802) (xy 364.359298 -137.336168) (xy 364.40527 -137.306455)
			(xy 364.455016 -137.283618) (xy 364.507516 -137.268126) (xy 364.561691 -137.260297) (xy 364.58906 -137.259822)
			(xy 364.616313 -137.260293) (xy 364.670265 -137.268045) (xy 364.722565 -137.283397) (xy 364.772147 -137.306037)
			(xy 364.818002 -137.335504) (xy 364.859196 -137.371197) (xy 364.89489 -137.41239) (xy 364.924358 -137.458244)
			(xy 364.946999 -137.507826) (xy 364.962353 -137.560125) (xy 364.970107 -137.614077) (xy 364.970568 -137.64133)
			(xy 364.970012 -137.670246) (xy 364.961292 -137.727416) (xy 364.944043 -137.782614) (xy 364.918658 -137.834576)
			(xy 364.885721 -137.882111) (xy 364.845985 -137.924129) (xy 364.823502 -137.94232) (xy 364.814696 -137.949929)
			(xy 364.804512 -137.970828) (xy 364.803944 -137.982452) (xy 364.803944 -138.062208) (xy 364.804478 -138.073841)
			(xy 364.814669 -138.094751) (xy 364.823502 -138.10234) (xy 364.846005 -138.120508) (xy 364.885739 -138.162533)
			(xy 364.918676 -138.210072) (xy 364.944061 -138.262038) (xy 364.961312 -138.31724) (xy 364.970036 -138.374413)
			(xy 364.970568 -138.40333) (xy 364.970173 -138.430585) (xy 364.962411 -138.484541) (xy 364.947049 -138.536843)
			(xy 364.9244 -138.586426) (xy 364.894925 -138.63228) (xy 364.859224 -138.673474) (xy 364.818024 -138.709167)
			(xy 364.772164 -138.738634) (xy 364.722577 -138.761273) (xy 364.670272 -138.776626) (xy 364.616316 -138.784378)
			(xy 364.58906 -138.784838) (xy 364.562744 -138.784417) (xy 364.510613 -138.777175) (xy 364.459969 -138.762849)
			(xy 364.411769 -138.741708) (xy 364.366927 -138.714152) (xy 364.32629 -138.680704) (xy 364.308136 -138.661648)
			(xy 364.300596 -138.654267) (xy 364.28133 -138.645729) (xy 364.270798 -138.645138) (xy 364.196122 -138.645138)
			(xy 364.18557 -138.645654) (xy 364.166274 -138.654197) (xy 364.158784 -138.661648) (xy 364.140639 -138.680713)
			(xy 364.100006 -138.714168) (xy 364.055163 -138.741724) (xy 364.00696 -138.762861) (xy 363.956312 -138.777176)
			(xy 363.904177 -138.7844) (xy 363.87786 -138.784838) (xy 363.850609 -138.784359) (xy 363.796663 -138.776598)
			(xy 363.74437 -138.76124) (xy 363.694794 -138.738596) (xy 363.648946 -138.709128) (xy 363.607757 -138.673436)
			(xy 363.572066 -138.632246) (xy 363.542599 -138.586397) (xy 363.519957 -138.536821) (xy 363.5046 -138.484527)
			(xy 363.49684 -138.430581) (xy 363.496352 -138.40333) (xy 355.236852 -138.40333) (xy 355.230945 -138.443466)
			(xy 355.214877 -138.496873) (xy 355.191205 -138.54737) (xy 355.160432 -138.593883) (xy 355.123215 -138.63542)
			(xy 355.080347 -138.671095) (xy 355.032741 -138.700149) (xy 354.981412 -138.721961) (xy 354.927455 -138.736067)
			(xy 354.872018 -138.742167) (xy 354.816284 -138.74013) (xy 354.761441 -138.73) (xy 354.708657 -138.711993)
			(xy 354.659057 -138.686492) (xy 354.613699 -138.654041) (xy 354.57355 -138.615332) (xy 354.539464 -138.571189)
			(xy 354.512168 -138.522554) (xy 354.492245 -138.470463) (xy 354.480119 -138.416026) (xy 354.476048 -138.360404)
			(xy 352.756724 -138.360404) (xy 352.756724 -138.824462) (xy 356.661972 -138.824462) (xy 356.666043 -138.76884)
			(xy 356.678169 -138.714403) (xy 356.698092 -138.662312) (xy 356.725388 -138.613677) (xy 356.759474 -138.569534)
			(xy 356.799623 -138.530825) (xy 356.844981 -138.498374) (xy 356.894581 -138.472873) (xy 356.947365 -138.454866)
			(xy 357.002208 -138.444736) (xy 357.057942 -138.442699) (xy 357.113379 -138.448799) (xy 357.167336 -138.462905)
			(xy 357.218665 -138.484717) (xy 357.266271 -138.513771) (xy 357.309139 -138.549446) (xy 357.346356 -138.590983)
			(xy 357.377129 -138.637496) (xy 357.400801 -138.687993) (xy 357.416869 -138.7414) (xy 357.424989 -138.796576)
			(xy 357.425498 -138.824462) (xy 357.424989 -138.852348) (xy 357.416869 -138.907524) (xy 357.400801 -138.960931)
			(xy 357.377129 -139.011428) (xy 357.346356 -139.057941) (xy 357.309139 -139.099478) (xy 357.266271 -139.135153)
			(xy 357.218665 -139.164207) (xy 357.167336 -139.186019) (xy 357.113379 -139.200125) (xy 357.057942 -139.206225)
			(xy 357.002208 -139.204188) (xy 356.947365 -139.194058) (xy 356.894581 -139.176051) (xy 356.844981 -139.15055)
			(xy 356.799623 -139.118099) (xy 356.759474 -139.07939) (xy 356.725388 -139.035247) (xy 356.698092 -138.986612)
			(xy 356.678169 -138.934521) (xy 356.666043 -138.880084) (xy 356.661972 -138.824462) (xy 352.756724 -138.824462)
			(xy 352.756724 -139.376404) (xy 354.476048 -139.376404) (xy 354.480119 -139.320782) (xy 354.492245 -139.266345)
			(xy 354.512168 -139.214254) (xy 354.539464 -139.165619) (xy 354.57355 -139.121476) (xy 354.613699 -139.082767)
			(xy 354.659057 -139.050316) (xy 354.708657 -139.024815) (xy 354.761441 -139.006808) (xy 354.816284 -138.996678)
			(xy 354.872018 -138.994641) (xy 354.927455 -139.000741) (xy 354.981412 -139.014847) (xy 355.032741 -139.036659)
			(xy 355.080347 -139.065713) (xy 355.123215 -139.101388) (xy 355.160432 -139.142925) (xy 355.191205 -139.189438)
			(xy 355.214877 -139.239935) (xy 355.230945 -139.293342) (xy 355.239065 -139.348518) (xy 355.239574 -139.376404)
			(xy 355.239065 -139.40429) (xy 355.230945 -139.459466) (xy 355.214877 -139.512873) (xy 355.191205 -139.56337)
			(xy 355.160432 -139.609883) (xy 355.123215 -139.65142) (xy 355.080347 -139.687095) (xy 355.032741 -139.716149)
			(xy 354.981412 -139.737961) (xy 354.927455 -139.752067) (xy 354.872018 -139.758167) (xy 354.816284 -139.75613)
			(xy 354.761441 -139.746) (xy 354.708657 -139.727993) (xy 354.659057 -139.702492) (xy 354.613699 -139.670041)
			(xy 354.57355 -139.631332) (xy 354.539464 -139.587189) (xy 354.512168 -139.538554) (xy 354.492245 -139.486463)
			(xy 354.480119 -139.432026) (xy 354.476048 -139.376404) (xy 352.756724 -139.376404) (xy 352.756724 -140.392404)
			(xy 356.667814 -140.392404) (xy 356.671885 -140.336782) (xy 356.684011 -140.282345) (xy 356.703934 -140.230254)
			(xy 356.73123 -140.181619) (xy 356.765316 -140.137476) (xy 356.805465 -140.098767) (xy 356.850823 -140.066316)
			(xy 356.900423 -140.040815) (xy 356.953207 -140.022808) (xy 357.00805 -140.012678) (xy 357.063784 -140.010641)
			(xy 357.119221 -140.016741) (xy 357.173178 -140.030847) (xy 357.224507 -140.052659) (xy 357.272113 -140.081713)
			(xy 357.314981 -140.117388) (xy 357.352198 -140.158925) (xy 357.382971 -140.205438) (xy 357.406643 -140.255935)
			(xy 357.422711 -140.309342) (xy 357.430831 -140.364518) (xy 357.43134 -140.392404) (xy 357.430831 -140.42029)
			(xy 357.422711 -140.475466) (xy 357.406643 -140.528873) (xy 357.382971 -140.57937) (xy 357.352198 -140.625883)
			(xy 357.314981 -140.66742) (xy 357.272113 -140.703095) (xy 357.224507 -140.732149) (xy 357.173178 -140.753961)
			(xy 357.119221 -140.768067) (xy 357.063784 -140.774167) (xy 357.00805 -140.77213) (xy 356.953207 -140.762)
			(xy 356.900423 -140.743993) (xy 356.850823 -140.718492) (xy 356.805465 -140.686041) (xy 356.765316 -140.647332)
			(xy 356.73123 -140.603189) (xy 356.703934 -140.554554) (xy 356.684011 -140.502463) (xy 356.671885 -140.448026)
			(xy 356.667814 -140.392404) (xy 352.756724 -140.392404) (xy 352.756724 -141.279118) (xy 354.101652 -141.279118)
			(xy 354.105723 -141.223496) (xy 354.117849 -141.169059) (xy 354.137772 -141.116968) (xy 354.165068 -141.068333)
			(xy 354.199154 -141.02419) (xy 354.239303 -140.985481) (xy 354.284661 -140.95303) (xy 354.334261 -140.927529)
			(xy 354.387045 -140.909522) (xy 354.441888 -140.899392) (xy 354.497622 -140.897355) (xy 354.553059 -140.903455)
			(xy 354.607016 -140.917561) (xy 354.658345 -140.939373) (xy 354.705951 -140.968427) (xy 354.748819 -141.004102)
			(xy 354.786036 -141.045639) (xy 354.786639 -141.046551) (xy 359.055154 -141.046551) (xy 359.055154 -140.992049)
			(xy 359.06291 -140.938101) (xy 359.078264 -140.885806) (xy 359.100904 -140.836228) (xy 359.130368 -140.790377)
			(xy 359.166058 -140.749185) (xy 359.207246 -140.713491) (xy 359.253095 -140.684022) (xy 359.30267 -140.661377)
			(xy 359.354964 -140.646018) (xy 359.408911 -140.638256) (xy 359.436162 -140.637768) (xy 359.462477 -140.638204)
			(xy 359.514606 -140.645447) (xy 359.565249 -140.659773) (xy 359.613448 -140.680911) (xy 359.658291 -140.708462)
			(xy 359.69893 -140.741905) (xy 359.717086 -140.760958) (xy 359.724617 -140.768349) (xy 359.74389 -140.776881)
			(xy 359.754424 -140.777468) (xy 359.8291 -140.777468) (xy 359.839653 -140.776962) (xy 359.858948 -140.768412)
			(xy 359.866438 -140.760958) (xy 359.884574 -140.741883) (xy 359.925209 -140.708429) (xy 359.970053 -140.680874)
			(xy 360.018258 -140.659739) (xy 360.068908 -140.645426) (xy 360.121045 -140.638205) (xy 360.147362 -140.637768)
			(xy 360.174615 -140.638277) (xy 360.228567 -140.646029) (xy 360.280866 -140.661381) (xy 360.330447 -140.684019)
			(xy 360.376302 -140.713485) (xy 360.417497 -140.749176) (xy 360.453193 -140.790367) (xy 360.482662 -140.836219)
			(xy 360.505306 -140.885799) (xy 360.520663 -140.938096) (xy 360.528421 -140.992047) (xy 360.528421 -141.046553)
			(xy 360.520663 -141.100504) (xy 360.505306 -141.152801) (xy 360.482662 -141.202381) (xy 360.453193 -141.248233)
			(xy 360.417497 -141.289424) (xy 360.376302 -141.325115) (xy 360.330447 -141.354581) (xy 360.280866 -141.377219)
			(xy 360.228567 -141.392571) (xy 360.174615 -141.400323) (xy 360.147362 -141.400784) (xy 360.121047 -141.400347)
			(xy 360.068917 -141.393107) (xy 360.018273 -141.378782) (xy 359.970074 -141.357644) (xy 359.925232 -141.330092)
			(xy 359.884594 -141.296648) (xy 359.866438 -141.277594) (xy 359.858905 -141.270206) (xy 359.839634 -141.261674)
			(xy 359.8291 -141.261084) (xy 359.754424 -141.261084) (xy 359.743875 -141.261618) (xy 359.72458 -141.27015)
			(xy 359.717086 -141.277594) (xy 359.698929 -141.296648) (xy 359.6583 -141.330106) (xy 359.61346 -141.357665)
			(xy 359.565259 -141.378804) (xy 359.514612 -141.393121) (xy 359.462478 -141.400346) (xy 359.436162 -141.400784)
			(xy 359.408911 -141.400344) (xy 359.354964 -141.392582) (xy 359.30267 -141.377223) (xy 359.253095 -141.354578)
			(xy 359.207246 -141.325109) (xy 359.166058 -141.289415) (xy 359.130368 -141.248223) (xy 359.100904 -141.202372)
			(xy 359.078264 -141.152794) (xy 359.06291 -141.100499) (xy 359.055154 -141.046551) (xy 354.786639 -141.046551)
			(xy 354.816809 -141.092152) (xy 354.840481 -141.142649) (xy 354.856549 -141.196056) (xy 354.864669 -141.251232)
			(xy 354.865178 -141.279118) (xy 354.864669 -141.307004) (xy 354.856549 -141.36218) (xy 354.840481 -141.415587)
			(xy 354.816809 -141.466084) (xy 354.786036 -141.512597) (xy 354.748819 -141.554134) (xy 354.705951 -141.589809)
			(xy 354.658345 -141.618863) (xy 354.607016 -141.640675) (xy 354.553059 -141.654781) (xy 354.497622 -141.660881)
			(xy 354.441888 -141.658844) (xy 354.387045 -141.648714) (xy 354.334261 -141.630707) (xy 354.284661 -141.605206)
			(xy 354.239303 -141.572755) (xy 354.199154 -141.534046) (xy 354.165068 -141.489903) (xy 354.137772 -141.441268)
			(xy 354.117849 -141.389177) (xy 354.105723 -141.33474) (xy 354.101652 -141.279118) (xy 352.756724 -141.279118)
			(xy 352.756724 -142.494) (xy 352.866196 -142.494) (xy 352.870267 -142.438378) (xy 352.882393 -142.383941)
			(xy 352.902316 -142.33185) (xy 352.929612 -142.283215) (xy 352.963698 -142.239072) (xy 353.003847 -142.200363)
			(xy 353.049205 -142.167912) (xy 353.098805 -142.142411) (xy 353.151589 -142.124404) (xy 353.206432 -142.114274)
			(xy 353.262166 -142.112237) (xy 353.317603 -142.118337) (xy 353.37156 -142.132443) (xy 353.422889 -142.154255)
			(xy 353.470495 -142.183309) (xy 353.513363 -142.218984) (xy 353.55058 -142.260521) (xy 353.581353 -142.307034)
			(xy 353.605025 -142.357531) (xy 353.621093 -142.410938) (xy 353.629213 -142.466114) (xy 353.629722 -142.494)
			(xy 353.629213 -142.521886) (xy 353.621093 -142.577062) (xy 353.605025 -142.630469) (xy 353.581353 -142.680966)
			(xy 353.55058 -142.727479) (xy 353.513363 -142.769016) (xy 353.470495 -142.804691) (xy 353.422889 -142.833745)
			(xy 353.37156 -142.855557) (xy 353.317603 -142.869663) (xy 353.262166 -142.875763) (xy 353.206432 -142.873726)
			(xy 353.151589 -142.863596) (xy 353.098805 -142.845589) (xy 353.049205 -142.820088) (xy 353.003847 -142.787637)
			(xy 352.963698 -142.748928) (xy 352.929612 -142.704785) (xy 352.902316 -142.65615) (xy 352.882393 -142.604059)
			(xy 352.870267 -142.549622) (xy 352.866196 -142.494) (xy 352.756724 -142.494) (xy 352.756724 -143.078551)
			(xy 359.055154 -143.078551) (xy 359.055154 -143.024049) (xy 359.06291 -142.970101) (xy 359.078264 -142.917806)
			(xy 359.100904 -142.868228) (xy 359.130368 -142.822377) (xy 359.166058 -142.781185) (xy 359.207246 -142.745491)
			(xy 359.253095 -142.716022) (xy 359.30267 -142.693377) (xy 359.354964 -142.678018) (xy 359.408911 -142.670256)
			(xy 359.436162 -142.669768) (xy 359.462477 -142.670204) (xy 359.514606 -142.677447) (xy 359.565249 -142.691773)
			(xy 359.613448 -142.712911) (xy 359.658291 -142.740462) (xy 359.69893 -142.773905) (xy 359.717086 -142.792958)
			(xy 359.724617 -142.800349) (xy 359.74389 -142.808881) (xy 359.754424 -142.809468) (xy 359.8291 -142.809468)
			(xy 359.839653 -142.808962) (xy 359.858948 -142.800412) (xy 359.866438 -142.792958) (xy 359.884574 -142.773883)
			(xy 359.925209 -142.740429) (xy 359.970053 -142.712874) (xy 360.018258 -142.691739) (xy 360.068908 -142.677426)
			(xy 360.121045 -142.670205) (xy 360.147362 -142.669768) (xy 360.174615 -142.670277) (xy 360.228567 -142.678029)
			(xy 360.280866 -142.693381) (xy 360.330447 -142.716019) (xy 360.376302 -142.745485) (xy 360.417497 -142.781176)
			(xy 360.453193 -142.822367) (xy 360.482662 -142.868219) (xy 360.505306 -142.917799) (xy 360.520663 -142.970096)
			(xy 360.528421 -143.024047) (xy 360.528421 -143.078553) (xy 360.520663 -143.132504) (xy 360.505306 -143.184801)
			(xy 360.482662 -143.234381) (xy 360.453193 -143.280233) (xy 360.417497 -143.321424) (xy 360.376302 -143.357115)
			(xy 360.330447 -143.386581) (xy 360.280866 -143.409219) (xy 360.228567 -143.424571) (xy 360.174615 -143.432323)
			(xy 360.147362 -143.432784) (xy 360.121047 -143.432347) (xy 360.068917 -143.425107) (xy 360.018273 -143.410782)
			(xy 359.970074 -143.389644) (xy 359.925232 -143.362092) (xy 359.884594 -143.328648) (xy 359.866438 -143.309594)
			(xy 359.858905 -143.302206) (xy 359.839634 -143.293674) (xy 359.8291 -143.293084) (xy 359.754424 -143.293084)
			(xy 359.743875 -143.293618) (xy 359.72458 -143.30215) (xy 359.717086 -143.309594) (xy 359.698929 -143.328648)
			(xy 359.6583 -143.362106) (xy 359.61346 -143.389665) (xy 359.565259 -143.410804) (xy 359.514612 -143.425121)
			(xy 359.462478 -143.432346) (xy 359.436162 -143.432784) (xy 359.408911 -143.432344) (xy 359.354964 -143.424582)
			(xy 359.30267 -143.409223) (xy 359.253095 -143.386578) (xy 359.207246 -143.357109) (xy 359.166058 -143.321415)
			(xy 359.130368 -143.280223) (xy 359.100904 -143.234372) (xy 359.078264 -143.184794) (xy 359.06291 -143.132499)
			(xy 359.055154 -143.078551) (xy 352.756724 -143.078551) (xy 352.756724 -143.51) (xy 352.866196 -143.51)
			(xy 352.870267 -143.454378) (xy 352.882393 -143.399941) (xy 352.902316 -143.34785) (xy 352.929612 -143.299215)
			(xy 352.963698 -143.255072) (xy 353.003847 -143.216363) (xy 353.049205 -143.183912) (xy 353.098805 -143.158411)
			(xy 353.151589 -143.140404) (xy 353.206432 -143.130274) (xy 353.262166 -143.128237) (xy 353.317603 -143.134337)
			(xy 353.37156 -143.148443) (xy 353.422889 -143.170255) (xy 353.470495 -143.199309) (xy 353.513363 -143.234984)
			(xy 353.55058 -143.276521) (xy 353.581353 -143.323034) (xy 353.605025 -143.373531) (xy 353.621093 -143.426938)
			(xy 353.629213 -143.482114) (xy 353.629722 -143.51) (xy 353.629213 -143.537886) (xy 353.621093 -143.593062)
			(xy 353.605025 -143.646469) (xy 353.581353 -143.696966) (xy 353.55058 -143.743479) (xy 353.513363 -143.785016)
			(xy 353.470495 -143.820691) (xy 353.422889 -143.849745) (xy 353.37156 -143.871557) (xy 353.317603 -143.885663)
			(xy 353.262166 -143.891763) (xy 353.206432 -143.889726) (xy 353.151589 -143.879596) (xy 353.098805 -143.861589)
			(xy 353.049205 -143.836088) (xy 353.003847 -143.803637) (xy 352.963698 -143.764928) (xy 352.929612 -143.720785)
			(xy 352.902316 -143.67215) (xy 352.882393 -143.620059) (xy 352.870267 -143.565622) (xy 352.866196 -143.51)
			(xy 352.756724 -143.51) (xy 352.756724 -144.526) (xy 352.866196 -144.526) (xy 352.870267 -144.470378)
			(xy 352.882393 -144.415941) (xy 352.902316 -144.36385) (xy 352.929612 -144.315215) (xy 352.963698 -144.271072)
			(xy 353.003847 -144.232363) (xy 353.049205 -144.199912) (xy 353.098805 -144.174411) (xy 353.151589 -144.156404)
			(xy 353.206432 -144.146274) (xy 353.262166 -144.144237) (xy 353.317603 -144.150337) (xy 353.37156 -144.164443)
			(xy 353.422889 -144.186255) (xy 353.470495 -144.215309) (xy 353.513363 -144.250984) (xy 353.55058 -144.292521)
			(xy 353.581353 -144.339034) (xy 353.605025 -144.389531) (xy 353.621093 -144.442938) (xy 353.629213 -144.498114)
			(xy 353.629722 -144.526) (xy 353.629213 -144.553886) (xy 353.621093 -144.609062) (xy 353.605025 -144.662469)
			(xy 353.581353 -144.712966) (xy 353.55058 -144.759479) (xy 353.513363 -144.801016) (xy 353.470495 -144.836691)
			(xy 353.422889 -144.865745) (xy 353.37156 -144.887557) (xy 353.317603 -144.901663) (xy 353.262166 -144.907763)
			(xy 353.206432 -144.905726) (xy 353.151589 -144.895596) (xy 353.098805 -144.877589) (xy 353.049205 -144.852088)
			(xy 353.003847 -144.819637) (xy 352.963698 -144.780928) (xy 352.929612 -144.736785) (xy 352.902316 -144.68815)
			(xy 352.882393 -144.636059) (xy 352.870267 -144.581622) (xy 352.866196 -144.526) (xy 352.756724 -144.526)
			(xy 352.756724 -145.110551) (xy 359.055154 -145.110551) (xy 359.055154 -145.056049) (xy 359.06291 -145.002101)
			(xy 359.078264 -144.949806) (xy 359.100904 -144.900228) (xy 359.130368 -144.854377) (xy 359.166058 -144.813185)
			(xy 359.207246 -144.777491) (xy 359.253095 -144.748022) (xy 359.30267 -144.725377) (xy 359.354964 -144.710018)
			(xy 359.408911 -144.702256) (xy 359.436162 -144.701768) (xy 359.462477 -144.702204) (xy 359.514606 -144.709447)
			(xy 359.565249 -144.723773) (xy 359.613448 -144.744911) (xy 359.658291 -144.772462) (xy 359.69893 -144.805905)
			(xy 359.717086 -144.824958) (xy 359.724617 -144.832349) (xy 359.74389 -144.840881) (xy 359.754424 -144.841468)
			(xy 359.8291 -144.841468) (xy 359.839653 -144.840962) (xy 359.858948 -144.832412) (xy 359.866438 -144.824958)
			(xy 359.884574 -144.805883) (xy 359.925209 -144.772429) (xy 359.970053 -144.744874) (xy 360.018258 -144.723739)
			(xy 360.068908 -144.709426) (xy 360.121045 -144.702205) (xy 360.147362 -144.701768) (xy 360.174615 -144.702277)
			(xy 360.228567 -144.710029) (xy 360.280866 -144.725381) (xy 360.330447 -144.748019) (xy 360.376302 -144.777485)
			(xy 360.417497 -144.813176) (xy 360.453193 -144.854367) (xy 360.482662 -144.900219) (xy 360.505306 -144.949799)
			(xy 360.506611 -144.954244) (xy 366.239044 -144.954244) (xy 366.239619 -144.926996) (xy 366.247368 -144.873054)
			(xy 366.262715 -144.820764) (xy 366.285348 -144.77119) (xy 366.314805 -144.725342) (xy 366.350487 -144.684152)
			(xy 366.391668 -144.64846) (xy 366.437509 -144.618992) (xy 366.487078 -144.596348) (xy 366.539364 -144.580988)
			(xy 366.593304 -144.573226) (xy 366.620552 -144.572736) (xy 366.649326 -144.573259) (xy 366.706221 -144.581909)
			(xy 366.761172 -144.599005) (xy 366.812932 -144.624159) (xy 366.860328 -144.656801) (xy 366.881664 -144.676114)
			(xy 366.889538 -144.68348) (xy 366.90935 -144.690592) (xy 367.005616 -144.683226) (xy 367.024412 -144.67332)
			(xy 367.031016 -144.664938) (xy 367.049197 -144.642716) (xy 367.091141 -144.603508) (xy 367.138486 -144.571026)
			(xy 367.190162 -144.546004) (xy 367.245004 -144.529006) (xy 367.301774 -144.520416) (xy 367.330482 -144.519904)
			(xy 367.357735 -144.520372) (xy 367.411686 -144.528127) (xy 367.463985 -144.543481) (xy 367.513566 -144.566123)
			(xy 367.559419 -144.59559) (xy 367.600613 -144.631283) (xy 367.636307 -144.672476) (xy 367.665775 -144.718329)
			(xy 367.688417 -144.76791) (xy 367.703772 -144.820208) (xy 367.711527 -144.874159) (xy 367.71199 -144.901412)
			(xy 367.711543 -144.928315) (xy 367.703969 -144.981586) (xy 367.688988 -145.033265) (xy 367.666895 -145.082327)
			(xy 367.63813 -145.127799) (xy 367.603263 -145.16878) (xy 367.562985 -145.204457) (xy 367.540794 -145.219674)
			(xy 367.529872 -145.226786) (xy 367.517934 -145.249646) (xy 367.519966 -145.361914) (xy 367.53292 -145.384266)
			(xy 367.544096 -145.391124) (xy 367.567696 -145.406048) (xy 367.610649 -145.441726) (xy 367.647942 -145.483283)
			(xy 367.67878 -145.529833) (xy 367.702504 -145.58038) (xy 367.718606 -145.633846) (xy 367.726744 -145.689087)
			(xy 367.72723 -145.717006) (xy 367.726776 -145.744) (xy 367.719169 -145.797448) (xy 367.704107 -145.849292)
			(xy 367.681891 -145.898496) (xy 367.652965 -145.94408) (xy 367.63579 -145.96491) (xy 367.628678 -145.973038)
			(xy 367.622582 -145.993612) (xy 367.633504 -146.078956) (xy 367.635295 -146.089496) (xy 367.646338 -146.107781)
			(xy 367.65484 -146.114262) (xy 367.676045 -146.12965) (xy 367.714499 -146.165231) (xy 367.74772 -146.205741)
			(xy 367.775082 -146.250419) (xy 367.79607 -146.298421) (xy 367.810288 -146.348845) (xy 367.817469 -146.400741)
			(xy 367.817908 -146.426936) (xy 367.817422 -146.454187) (xy 367.809666 -146.508135) (xy 367.794311 -146.56043)
			(xy 367.771669 -146.610007) (xy 367.742203 -146.655857) (xy 367.706512 -146.697048) (xy 367.665321 -146.732739)
			(xy 367.619471 -146.762205) (xy 367.569894 -146.784847) (xy 367.517599 -146.800202) (xy 367.463651 -146.807958)
			(xy 367.409149 -146.807958) (xy 367.355201 -146.800202) (xy 367.302906 -146.784847) (xy 367.253329 -146.762205)
			(xy 367.207479 -146.732739) (xy 367.166288 -146.697048) (xy 367.130597 -146.655857) (xy 367.101131 -146.610007)
			(xy 367.078489 -146.56043) (xy 367.063134 -146.508135) (xy 367.055378 -146.454187) (xy 367.054892 -146.426936)
			(xy 367.055365 -146.399943) (xy 367.062967 -146.346495) (xy 367.078024 -146.294651) (xy 367.100235 -146.245447)
			(xy 367.129158 -146.199862) (xy 367.146332 -146.179032) (xy 367.153444 -146.170904) (xy 367.15954 -146.15033)
			(xy 367.148618 -146.064986) (xy 367.146848 -146.054441) (xy 367.135789 -146.036159) (xy 367.127282 -146.02968)
			(xy 367.102981 -146.012068) (xy 367.059722 -145.970472) (xy 367.041176 -145.946876) (xy 367.035334 -145.939002)
			(xy 367.017808 -145.928588) (xy 366.927384 -145.91538) (xy 366.90808 -145.920206) (xy 366.900206 -145.926048)
			(xy 366.899952 -145.926048) (xy 366.87521 -145.943554) (xy 366.821357 -145.971357) (xy 366.763784 -145.990292)
			(xy 366.703941 -145.999884) (xy 366.673638 -146.00047) (xy 366.646384 -146.000009) (xy 366.592431 -145.992256)
			(xy 366.540131 -145.976903) (xy 366.490549 -145.954262) (xy 366.444693 -145.924795) (xy 366.403499 -145.889101)
			(xy 366.367805 -145.847907) (xy 366.338338 -145.802051) (xy 366.315697 -145.752469) (xy 366.300344 -145.700169)
			(xy 366.292591 -145.646216) (xy 366.29213 -145.618962) (xy 366.292566 -145.592928) (xy 366.299657 -145.541345)
			(xy 366.31369 -145.491203) (xy 366.334403 -145.443433) (xy 366.361413 -145.398918) (xy 366.377474 -145.378424)
			(xy 366.383214 -145.370666) (xy 366.388956 -145.352256) (xy 366.38865 -145.34261) (xy 366.3823 -145.262854)
			(xy 366.373664 -145.245074) (xy 366.366298 -145.238724) (xy 366.346658 -145.220536) (xy 366.312132 -145.179632)
			(xy 366.28366 -145.134305) (xy 366.261801 -145.085445) (xy 366.246983 -145.034009) (xy 366.239498 -144.981008)
			(xy 366.239044 -144.954244) (xy 360.506611 -144.954244) (xy 360.520663 -145.002096) (xy 360.528421 -145.056047)
			(xy 360.528421 -145.110553) (xy 360.520663 -145.164504) (xy 360.505306 -145.216801) (xy 360.482662 -145.266381)
			(xy 360.453193 -145.312233) (xy 360.417497 -145.353424) (xy 360.376302 -145.389115) (xy 360.330447 -145.418581)
			(xy 360.280866 -145.441219) (xy 360.228567 -145.456571) (xy 360.174615 -145.464323) (xy 360.147362 -145.464784)
			(xy 360.121047 -145.464347) (xy 360.068917 -145.457107) (xy 360.018273 -145.442782) (xy 359.970074 -145.421644)
			(xy 359.925232 -145.394092) (xy 359.884594 -145.360648) (xy 359.866438 -145.341594) (xy 359.858905 -145.334206)
			(xy 359.839634 -145.325674) (xy 359.8291 -145.325084) (xy 359.754424 -145.325084) (xy 359.743875 -145.325618)
			(xy 359.72458 -145.33415) (xy 359.717086 -145.341594) (xy 359.698929 -145.360648) (xy 359.6583 -145.394106)
			(xy 359.61346 -145.421665) (xy 359.565259 -145.442804) (xy 359.514612 -145.457121) (xy 359.462478 -145.464346)
			(xy 359.436162 -145.464784) (xy 359.408911 -145.464344) (xy 359.354964 -145.456582) (xy 359.30267 -145.441223)
			(xy 359.253095 -145.418578) (xy 359.207246 -145.389109) (xy 359.166058 -145.353415) (xy 359.130368 -145.312223)
			(xy 359.100904 -145.266372) (xy 359.078264 -145.216794) (xy 359.06291 -145.164499) (xy 359.055154 -145.110551)
			(xy 352.756724 -145.110551) (xy 352.756724 -146.91487) (xy 367.916204 -146.91487) (xy 367.920275 -146.859248)
			(xy 367.932401 -146.804811) (xy 367.952324 -146.75272) (xy 367.97962 -146.704085) (xy 368.013706 -146.659942)
			(xy 368.053855 -146.621233) (xy 368.099213 -146.588782) (xy 368.148813 -146.563281) (xy 368.201597 -146.545274)
			(xy 368.25644 -146.535144) (xy 368.312174 -146.533107) (xy 368.367611 -146.539207) (xy 368.421568 -146.553313)
			(xy 368.472897 -146.575125) (xy 368.520503 -146.604179) (xy 368.563371 -146.639854) (xy 368.600588 -146.681391)
			(xy 368.631361 -146.727904) (xy 368.655033 -146.778401) (xy 368.671101 -146.831808) (xy 368.679221 -146.886984)
			(xy 368.67973 -146.91487) (xy 368.679221 -146.942756) (xy 368.671101 -146.997932) (xy 368.655033 -147.051339)
			(xy 368.649827 -147.062444) (xy 369.294408 -147.062444) (xy 369.298479 -147.006822) (xy 369.310605 -146.952385)
			(xy 369.330528 -146.900294) (xy 369.357824 -146.851659) (xy 369.39191 -146.807516) (xy 369.432059 -146.768807)
			(xy 369.477417 -146.736356) (xy 369.527017 -146.710855) (xy 369.579801 -146.692848) (xy 369.634644 -146.682718)
			(xy 369.690378 -146.680681) (xy 369.745815 -146.686781) (xy 369.799772 -146.700887) (xy 369.851101 -146.722699)
			(xy 369.898707 -146.751753) (xy 369.941575 -146.787428) (xy 369.978792 -146.828965) (xy 370.009565 -146.875478)
			(xy 370.033237 -146.925975) (xy 370.049305 -146.979382) (xy 370.057425 -147.034558) (xy 370.057934 -147.062444)
			(xy 370.057425 -147.09033) (xy 370.049305 -147.145506) (xy 370.033237 -147.198913) (xy 370.009565 -147.24941)
			(xy 369.978792 -147.295923) (xy 369.941575 -147.33746) (xy 369.898707 -147.373135) (xy 369.851101 -147.402189)
			(xy 369.799772 -147.424001) (xy 369.745815 -147.438107) (xy 369.690378 -147.444207) (xy 369.634644 -147.44217)
			(xy 369.579801 -147.43204) (xy 369.527017 -147.414033) (xy 369.477417 -147.388532) (xy 369.432059 -147.356081)
			(xy 369.39191 -147.317372) (xy 369.357824 -147.273229) (xy 369.330528 -147.224594) (xy 369.310605 -147.172503)
			(xy 369.298479 -147.118066) (xy 369.294408 -147.062444) (xy 368.649827 -147.062444) (xy 368.631361 -147.101836)
			(xy 368.600588 -147.148349) (xy 368.563371 -147.189886) (xy 368.520503 -147.225561) (xy 368.472897 -147.254615)
			(xy 368.421568 -147.276427) (xy 368.367611 -147.290533) (xy 368.312174 -147.296633) (xy 368.25644 -147.294596)
			(xy 368.201597 -147.284466) (xy 368.148813 -147.266459) (xy 368.099213 -147.240958) (xy 368.053855 -147.208507)
			(xy 368.013706 -147.169798) (xy 367.97962 -147.125655) (xy 367.952324 -147.07702) (xy 367.932401 -147.024929)
			(xy 367.920275 -146.970492) (xy 367.916204 -146.91487) (xy 352.756724 -146.91487) (xy 352.756724 -147.654518)
			(xy 352.95408 -147.654518) (xy 352.958151 -147.598896) (xy 352.970277 -147.544459) (xy 352.9902 -147.492368)
			(xy 353.017496 -147.443733) (xy 353.051582 -147.39959) (xy 353.091731 -147.360881) (xy 353.137089 -147.32843)
			(xy 353.186689 -147.302929) (xy 353.239473 -147.284922) (xy 353.294316 -147.274792) (xy 353.35005 -147.272755)
			(xy 353.405487 -147.278855) (xy 353.459444 -147.292961) (xy 353.510773 -147.314773) (xy 353.558379 -147.343827)
			(xy 353.601247 -147.379502) (xy 353.638464 -147.421039) (xy 353.669237 -147.467552) (xy 353.692909 -147.518049)
			(xy 353.708977 -147.571456) (xy 353.717097 -147.626632) (xy 353.717606 -147.654518) (xy 353.717549 -147.657656)
			(xy 359.450543 -147.657656) (xy 359.450543 -147.603144) (xy 359.458301 -147.549188) (xy 359.47366 -147.496885)
			(xy 359.496306 -147.447301) (xy 359.525779 -147.401445) (xy 359.561478 -147.360249) (xy 359.602677 -147.324555)
			(xy 359.648536 -147.295087) (xy 359.698123 -147.272446) (xy 359.750427 -147.257093) (xy 359.804384 -147.24934)
			(xy 359.83164 -147.24888) (xy 359.857955 -147.249327) (xy 359.910084 -147.256567) (xy 359.960727 -147.270891)
			(xy 360.008925 -147.292027) (xy 360.053768 -147.319576) (xy 360.094408 -147.353017) (xy 360.112564 -147.37207)
			(xy 360.120101 -147.379453) (xy 360.139369 -147.387989) (xy 360.149902 -147.38858) (xy 360.224578 -147.38858)
			(xy 360.235129 -147.388058) (xy 360.254424 -147.379519) (xy 360.261916 -147.37207) (xy 360.281736 -147.351282)
			(xy 360.326508 -147.315307) (xy 360.376166 -147.286447) (xy 360.429588 -147.265354) (xy 360.485567 -147.252505)
			(xy 360.54284 -147.24819) (xy 360.600113 -147.252505) (xy 360.656092 -147.265354) (xy 360.709514 -147.286447)
			(xy 360.759172 -147.315307) (xy 360.803944 -147.351282) (xy 360.823764 -147.37207) (xy 360.831301 -147.379453)
			(xy 360.850569 -147.387989) (xy 360.861102 -147.38858) (xy 360.935778 -147.38858) (xy 360.946329 -147.388058)
			(xy 360.965624 -147.379519) (xy 360.973116 -147.37207) (xy 360.991265 -147.353008) (xy 361.031897 -147.319553)
			(xy 361.076739 -147.291995) (xy 361.124941 -147.270858) (xy 361.175589 -147.256542) (xy 361.227724 -147.249318)
			(xy 361.25404 -147.24888) (xy 361.281288 -147.249393) (xy 361.33523 -147.257154) (xy 361.387518 -147.272512)
			(xy 361.437089 -147.295155) (xy 361.482933 -147.324621) (xy 361.524117 -147.360311) (xy 361.559803 -147.401499)
			(xy 361.589265 -147.447346) (xy 361.611902 -147.496919) (xy 361.627255 -147.549209) (xy 361.63501 -147.603151)
			(xy 361.63501 -147.657649) (xy 361.627255 -147.711591) (xy 361.611902 -147.763881) (xy 361.589265 -147.813454)
			(xy 361.559803 -147.859301) (xy 361.524117 -147.900489) (xy 361.482933 -147.936179) (xy 361.437089 -147.965645)
			(xy 361.387518 -147.988288) (xy 361.33523 -148.003646) (xy 361.281288 -148.011407) (xy 361.25404 -148.011896)
			(xy 361.227725 -148.01147) (xy 361.175594 -148.004227) (xy 361.124951 -147.9899) (xy 361.076752 -147.968759)
			(xy 361.031909 -147.941206) (xy 360.991271 -147.907761) (xy 360.973116 -147.888706) (xy 360.965589 -147.88131)
			(xy 360.946313 -147.872782) (xy 360.935778 -147.872196) (xy 360.861102 -147.872196) (xy 360.850551 -147.872714)
			(xy 360.831256 -147.881257) (xy 360.823764 -147.888706) (xy 360.803944 -147.909494) (xy 360.759172 -147.945469)
			(xy 360.709514 -147.974329) (xy 360.656092 -147.995422) (xy 360.600113 -148.008271) (xy 360.54284 -148.012586)
			(xy 360.485567 -148.008271) (xy 360.429588 -147.995422) (xy 360.376166 -147.974329) (xy 360.326508 -147.945469)
			(xy 360.281736 -147.909494) (xy 360.261916 -147.888706) (xy 360.254389 -147.88131) (xy 360.235113 -147.872782)
			(xy 360.224578 -147.872196) (xy 360.149902 -147.872196) (xy 360.139351 -147.872714) (xy 360.120056 -147.881257)
			(xy 360.112564 -147.888706) (xy 360.09442 -147.907773) (xy 360.053788 -147.941229) (xy 360.008945 -147.968786)
			(xy 359.960742 -147.989923) (xy 359.910092 -148.004237) (xy 359.857957 -148.011459) (xy 359.83164 -148.011896)
			(xy 359.804384 -148.01146) (xy 359.750427 -148.003707) (xy 359.698123 -147.988354) (xy 359.648536 -147.965713)
			(xy 359.602677 -147.936245) (xy 359.561478 -147.900551) (xy 359.525779 -147.859355) (xy 359.496306 -147.813499)
			(xy 359.47366 -147.763915) (xy 359.458301 -147.711612) (xy 359.450543 -147.657656) (xy 353.717549 -147.657656)
			(xy 353.717097 -147.682404) (xy 353.708977 -147.73758) (xy 353.692909 -147.790987) (xy 353.669237 -147.841484)
			(xy 353.638464 -147.887997) (xy 353.601247 -147.929534) (xy 353.558379 -147.965209) (xy 353.510773 -147.994263)
			(xy 353.459444 -148.016075) (xy 353.453083 -148.017738) (xy 364.277654 -148.017738) (xy 364.281725 -147.962116)
			(xy 364.293851 -147.907679) (xy 364.313774 -147.855588) (xy 364.34107 -147.806953) (xy 364.375156 -147.76281)
			(xy 364.415305 -147.724101) (xy 364.460663 -147.69165) (xy 364.510263 -147.666149) (xy 364.563047 -147.648142)
			(xy 364.61789 -147.638012) (xy 364.673624 -147.635975) (xy 364.729061 -147.642075) (xy 364.783018 -147.656181)
			(xy 364.834347 -147.677993) (xy 364.881953 -147.707047) (xy 364.924821 -147.742722) (xy 364.962038 -147.784259)
			(xy 364.992811 -147.830772) (xy 365.016483 -147.881269) (xy 365.032551 -147.934676) (xy 365.040671 -147.989852)
			(xy 365.04118 -148.017738) (xy 365.040671 -148.045624) (xy 365.032551 -148.1008) (xy 365.016483 -148.154207)
			(xy 364.992811 -148.204704) (xy 364.962038 -148.251217) (xy 364.924821 -148.292754) (xy 364.881953 -148.328429)
			(xy 364.834347 -148.357483) (xy 364.783018 -148.379295) (xy 364.729061 -148.393401) (xy 364.673624 -148.399501)
			(xy 364.61789 -148.397464) (xy 364.563047 -148.387334) (xy 364.510263 -148.369327) (xy 364.460663 -148.343826)
			(xy 364.415305 -148.311375) (xy 364.375156 -148.272666) (xy 364.34107 -148.228523) (xy 364.313774 -148.179888)
			(xy 364.293851 -148.127797) (xy 364.281725 -148.07336) (xy 364.277654 -148.017738) (xy 353.453083 -148.017738)
			(xy 353.405487 -148.030181) (xy 353.35005 -148.036281) (xy 353.294316 -148.034244) (xy 353.239473 -148.024114)
			(xy 353.186689 -148.006107) (xy 353.137089 -147.980606) (xy 353.091731 -147.948155) (xy 353.051582 -147.909446)
			(xy 353.017496 -147.865303) (xy 352.9902 -147.816668) (xy 352.970277 -147.764577) (xy 352.958151 -147.71014)
			(xy 352.95408 -147.654518) (xy 352.756724 -147.654518) (xy 352.756724 -148.050504) (xy 352.757148 -148.060573)
			(xy 352.764867 -148.079175) (xy 352.77171 -148.086572) (xy 353.853496 -149.168104) (xy 353.871526 -149.186876)
			(xy 353.902102 -149.228994) (xy 353.925724 -149.27537) (xy 353.941813 -149.324867) (xy 353.949974 -149.376269)
			(xy 353.950524 -149.402292) (xy 353.950524 -150.195854) (xy 359.450565 -150.195854) (xy 359.450565 -150.141346)
			(xy 359.458323 -150.087393) (xy 359.473681 -150.035093) (xy 359.496326 -149.985512) (xy 359.525797 -149.939658)
			(xy 359.561494 -149.898465) (xy 359.60269 -149.862773) (xy 359.648547 -149.833307) (xy 359.698131 -149.810667)
			(xy 359.750432 -149.795315) (xy 359.804386 -149.787563) (xy 359.83164 -149.787102) (xy 359.857955 -149.787542)
			(xy 359.910085 -149.794782) (xy 359.960728 -149.809107) (xy 360.008927 -149.830244) (xy 360.05377 -149.857795)
			(xy 360.094408 -149.891238) (xy 360.112564 -149.910292) (xy 360.120098 -149.917679) (xy 360.139369 -149.926212)
			(xy 360.149902 -149.926802) (xy 360.224578 -149.926802) (xy 360.235128 -149.926274) (xy 360.254423 -149.917738)
			(xy 360.261916 -149.910292) (xy 360.281736 -149.889504) (xy 360.326508 -149.853529) (xy 360.376166 -149.824669)
			(xy 360.429588 -149.803576) (xy 360.485567 -149.790727) (xy 360.54284 -149.786412) (xy 360.600113 -149.790727)
			(xy 360.656092 -149.803576) (xy 360.709514 -149.824669) (xy 360.759172 -149.853529) (xy 360.803944 -149.889504)
			(xy 360.823764 -149.910292) (xy 360.831298 -149.917679) (xy 360.850569 -149.926212) (xy 360.861102 -149.926802)
			(xy 360.935778 -149.926802) (xy 360.946328 -149.926274) (xy 360.965623 -149.917738) (xy 360.973116 -149.910292)
			(xy 360.991269 -149.891234) (xy 361.0319 -149.857778) (xy 361.07674 -149.830219) (xy 361.124942 -149.809081)
			(xy 361.175589 -149.794764) (xy 361.227724 -149.78754) (xy 361.25404 -149.787102) (xy 361.28129 -149.787571)
			(xy 361.335235 -149.795332) (xy 361.387526 -149.810691) (xy 361.4371 -149.833335) (xy 361.482946 -149.862803)
			(xy 361.524133 -149.898495) (xy 361.559821 -149.939686) (xy 361.589284 -149.985535) (xy 361.611923 -150.035111)
			(xy 361.627277 -150.087404) (xy 361.6311 -150.114) (xy 363.091982 -150.114) (xy 363.096053 -150.058378)
			(xy 363.108179 -150.003941) (xy 363.128102 -149.95185) (xy 363.155398 -149.903215) (xy 363.189484 -149.859072)
			(xy 363.229633 -149.820363) (xy 363.274991 -149.787912) (xy 363.324591 -149.762411) (xy 363.377375 -149.744404)
			(xy 363.432218 -149.734274) (xy 363.487952 -149.732237) (xy 363.543389 -149.738337) (xy 363.597346 -149.752443)
			(xy 363.648675 -149.774255) (xy 363.696281 -149.803309) (xy 363.739149 -149.838984) (xy 363.776366 -149.880521)
			(xy 363.807139 -149.927034) (xy 363.830811 -149.977531) (xy 363.846879 -150.030938) (xy 363.851664 -150.063454)
			(xy 364.138208 -150.063454) (xy 364.142279 -150.007832) (xy 364.154405 -149.953395) (xy 364.174328 -149.901304)
			(xy 364.201624 -149.852669) (xy 364.23571 -149.808526) (xy 364.275859 -149.769817) (xy 364.321217 -149.737366)
			(xy 364.370817 -149.711865) (xy 364.423601 -149.693858) (xy 364.478444 -149.683728) (xy 364.534178 -149.681691)
			(xy 364.589615 -149.687791) (xy 364.643572 -149.701897) (xy 364.694901 -149.723709) (xy 364.742507 -149.752763)
			(xy 364.785375 -149.788438) (xy 364.822592 -149.829975) (xy 364.853365 -149.876488) (xy 364.877037 -149.926985)
			(xy 364.893105 -149.980392) (xy 364.901225 -150.035568) (xy 364.901734 -150.063454) (xy 364.901225 -150.09134)
			(xy 364.893105 -150.146516) (xy 364.877037 -150.199923) (xy 364.853365 -150.25042) (xy 364.822592 -150.296933)
			(xy 364.785375 -150.33847) (xy 364.742507 -150.374145) (xy 364.694901 -150.403199) (xy 364.643572 -150.425011)
			(xy 364.589615 -150.439117) (xy 364.534178 -150.445217) (xy 364.478444 -150.44318) (xy 364.423601 -150.43305)
			(xy 364.370817 -150.415043) (xy 364.321217 -150.389542) (xy 364.275859 -150.357091) (xy 364.23571 -150.318382)
			(xy 364.201624 -150.274239) (xy 364.174328 -150.225604) (xy 364.154405 -150.173513) (xy 364.142279 -150.119076)
			(xy 364.138208 -150.063454) (xy 363.851664 -150.063454) (xy 363.854999 -150.086114) (xy 363.855508 -150.114)
			(xy 363.854999 -150.141886) (xy 363.846879 -150.197062) (xy 363.830811 -150.250469) (xy 363.807139 -150.300966)
			(xy 363.776366 -150.347479) (xy 363.739149 -150.389016) (xy 363.696281 -150.424691) (xy 363.648675 -150.453745)
			(xy 363.597346 -150.475557) (xy 363.543389 -150.489663) (xy 363.487952 -150.495763) (xy 363.432218 -150.493726)
			(xy 363.377375 -150.483596) (xy 363.324591 -150.465589) (xy 363.274991 -150.440088) (xy 363.229633 -150.407637)
			(xy 363.189484 -150.368928) (xy 363.155398 -150.324785) (xy 363.128102 -150.27615) (xy 363.108179 -150.224059)
			(xy 363.096053 -150.169622) (xy 363.091982 -150.114) (xy 361.6311 -150.114) (xy 361.635032 -150.14135)
			(xy 361.635032 -150.19585) (xy 361.627277 -150.249796) (xy 361.611923 -150.302089) (xy 361.589284 -150.351665)
			(xy 361.559821 -150.397514) (xy 361.524133 -150.438705) (xy 361.482946 -150.474397) (xy 361.4371 -150.503865)
			(xy 361.387526 -150.526509) (xy 361.335235 -150.541868) (xy 361.28129 -150.549629) (xy 361.25404 -150.550118)
			(xy 361.227725 -150.549685) (xy 361.175595 -150.542442) (xy 361.124952 -150.528116) (xy 361.076753 -150.506977)
			(xy 361.031911 -150.479425) (xy 360.991272 -150.445982) (xy 360.973116 -150.426928) (xy 360.965587 -150.419535)
			(xy 360.946313 -150.411005) (xy 360.935778 -150.410418) (xy 360.861102 -150.410418) (xy 360.85055 -150.410929)
			(xy 360.831255 -150.419477) (xy 360.823764 -150.426928) (xy 360.803944 -150.447716) (xy 360.759172 -150.483691)
			(xy 360.709514 -150.512551) (xy 360.656092 -150.533644) (xy 360.600113 -150.546493) (xy 360.54284 -150.550808)
			(xy 360.485567 -150.546493) (xy 360.429588 -150.533644) (xy 360.376166 -150.512551) (xy 360.326508 -150.483691)
			(xy 360.281736 -150.447716) (xy 360.261916 -150.426928) (xy 360.254387 -150.419535) (xy 360.235113 -150.411005)
			(xy 360.224578 -150.410418) (xy 360.149902 -150.410418) (xy 360.13935 -150.410929) (xy 360.120055 -150.419477)
			(xy 360.112564 -150.426928) (xy 360.094424 -150.445999) (xy 360.053791 -150.479454) (xy 360.008947 -150.50701)
			(xy 359.960743 -150.528146) (xy 359.910093 -150.54246) (xy 359.857957 -150.549681) (xy 359.83164 -150.550118)
			(xy 359.804386 -150.549637) (xy 359.750432 -150.541885) (xy 359.698131 -150.526533) (xy 359.648547 -150.503893)
			(xy 359.60269 -150.474427) (xy 359.561494 -150.438735) (xy 359.525797 -150.397542) (xy 359.496326 -150.351688)
			(xy 359.473681 -150.302107) (xy 359.458323 -150.249807) (xy 359.450565 -150.195854) (xy 353.950524 -150.195854)
			(xy 353.950524 -151.67102) (xy 364.093758 -151.67102) (xy 364.097829 -151.615398) (xy 364.109955 -151.560961)
			(xy 364.129878 -151.50887) (xy 364.157174 -151.460235) (xy 364.19126 -151.416092) (xy 364.231409 -151.377383)
			(xy 364.276767 -151.344932) (xy 364.326367 -151.319431) (xy 364.379151 -151.301424) (xy 364.433994 -151.291294)
			(xy 364.489728 -151.289257) (xy 364.545165 -151.295357) (xy 364.599122 -151.309463) (xy 364.650451 -151.331275)
			(xy 364.698057 -151.360329) (xy 364.740925 -151.396004) (xy 364.778142 -151.437541) (xy 364.808915 -151.484054)
			(xy 364.832587 -151.534551) (xy 364.848655 -151.587958) (xy 364.856775 -151.643134) (xy 364.857284 -151.67102)
			(xy 364.856811 -151.696928) (xy 365.109758 -151.696928) (xy 365.113829 -151.641306) (xy 365.125955 -151.586869)
			(xy 365.145878 -151.534778) (xy 365.173174 -151.486143) (xy 365.20726 -151.442) (xy 365.247409 -151.403291)
			(xy 365.292767 -151.37084) (xy 365.342367 -151.345339) (xy 365.395151 -151.327332) (xy 365.449994 -151.317202)
			(xy 365.505728 -151.315165) (xy 365.561165 -151.321265) (xy 365.615122 -151.335371) (xy 365.666451 -151.357183)
			(xy 365.714057 -151.386237) (xy 365.738533 -151.406606) (xy 366.336832 -151.406606) (xy 366.340903 -151.350984)
			(xy 366.353029 -151.296547) (xy 366.372952 -151.244456) (xy 366.400248 -151.195821) (xy 366.434334 -151.151678)
			(xy 366.474483 -151.112969) (xy 366.519841 -151.080518) (xy 366.569441 -151.055017) (xy 366.622225 -151.03701)
			(xy 366.677068 -151.02688) (xy 366.732802 -151.024843) (xy 366.788239 -151.030943) (xy 366.842196 -151.045049)
			(xy 366.893525 -151.066861) (xy 366.941131 -151.095915) (xy 366.983999 -151.13159) (xy 367.021216 -151.173127)
			(xy 367.051989 -151.21964) (xy 367.075661 -151.270137) (xy 367.091729 -151.323544) (xy 367.099849 -151.37872)
			(xy 367.100358 -151.406606) (xy 367.099849 -151.434492) (xy 367.091729 -151.489668) (xy 367.075661 -151.543075)
			(xy 367.057119 -151.582628) (xy 367.662458 -151.582628) (xy 367.666529 -151.527006) (xy 367.678655 -151.472569)
			(xy 367.698578 -151.420478) (xy 367.725874 -151.371843) (xy 367.75996 -151.3277) (xy 367.800109 -151.288991)
			(xy 367.845467 -151.25654) (xy 367.895067 -151.231039) (xy 367.947851 -151.213032) (xy 368.002694 -151.202902)
			(xy 368.058428 -151.200865) (xy 368.113865 -151.206965) (xy 368.167822 -151.221071) (xy 368.219151 -151.242883)
			(xy 368.266757 -151.271937) (xy 368.309625 -151.307612) (xy 368.346842 -151.349149) (xy 368.377615 -151.395662)
			(xy 368.401287 -151.446159) (xy 368.417355 -151.499566) (xy 368.425475 -151.554742) (xy 368.425738 -151.569166)
			(xy 369.173758 -151.569166) (xy 369.177829 -151.513544) (xy 369.189955 -151.459107) (xy 369.209878 -151.407016)
			(xy 369.237174 -151.358381) (xy 369.27126 -151.314238) (xy 369.311409 -151.275529) (xy 369.356767 -151.243078)
			(xy 369.406367 -151.217577) (xy 369.459151 -151.19957) (xy 369.513994 -151.18944) (xy 369.569728 -151.187403)
			(xy 369.625165 -151.193503) (xy 369.679122 -151.207609) (xy 369.730451 -151.229421) (xy 369.778057 -151.258475)
			(xy 369.820925 -151.29415) (xy 369.858142 -151.335687) (xy 369.888915 -151.3822) (xy 369.912587 -151.432697)
			(xy 369.928655 -151.486104) (xy 369.936775 -151.54128) (xy 369.937284 -151.569166) (xy 369.936775 -151.597052)
			(xy 369.928655 -151.652228) (xy 369.912587 -151.705635) (xy 369.888915 -151.756132) (xy 369.858142 -151.802645)
			(xy 369.820925 -151.844182) (xy 369.778057 -151.879857) (xy 369.730451 -151.908911) (xy 369.679122 -151.930723)
			(xy 369.625165 -151.944829) (xy 369.569728 -151.950929) (xy 369.513994 -151.948892) (xy 369.459151 -151.938762)
			(xy 369.406367 -151.920755) (xy 369.356767 -151.895254) (xy 369.311409 -151.862803) (xy 369.27126 -151.824094)
			(xy 369.237174 -151.779951) (xy 369.209878 -151.731316) (xy 369.189955 -151.679225) (xy 369.177829 -151.624788)
			(xy 369.173758 -151.569166) (xy 368.425738 -151.569166) (xy 368.425984 -151.582628) (xy 368.425475 -151.610514)
			(xy 368.417355 -151.66569) (xy 368.401287 -151.719097) (xy 368.377615 -151.769594) (xy 368.346842 -151.816107)
			(xy 368.309625 -151.857644) (xy 368.266757 -151.893319) (xy 368.219151 -151.922373) (xy 368.167822 -151.944185)
			(xy 368.113865 -151.958291) (xy 368.058428 -151.964391) (xy 368.002694 -151.962354) (xy 367.947851 -151.952224)
			(xy 367.895067 -151.934217) (xy 367.845467 -151.908716) (xy 367.800109 -151.876265) (xy 367.75996 -151.837556)
			(xy 367.725874 -151.793413) (xy 367.698578 -151.744778) (xy 367.678655 -151.692687) (xy 367.666529 -151.63825)
			(xy 367.662458 -151.582628) (xy 367.057119 -151.582628) (xy 367.051989 -151.593572) (xy 367.021216 -151.640085)
			(xy 366.983999 -151.681622) (xy 366.941131 -151.717297) (xy 366.893525 -151.746351) (xy 366.842196 -151.768163)
			(xy 366.788239 -151.782269) (xy 366.732802 -151.788369) (xy 366.677068 -151.786332) (xy 366.622225 -151.776202)
			(xy 366.569441 -151.758195) (xy 366.519841 -151.732694) (xy 366.474483 -151.700243) (xy 366.434334 -151.661534)
			(xy 366.400248 -151.617391) (xy 366.372952 -151.568756) (xy 366.353029 -151.516665) (xy 366.340903 -151.462228)
			(xy 366.336832 -151.406606) (xy 365.738533 -151.406606) (xy 365.756925 -151.421912) (xy 365.794142 -151.463449)
			(xy 365.824915 -151.509962) (xy 365.848587 -151.560459) (xy 365.864655 -151.613866) (xy 365.872775 -151.669042)
			(xy 365.873284 -151.696928) (xy 365.872775 -151.724814) (xy 365.864655 -151.77999) (xy 365.848587 -151.833397)
			(xy 365.824915 -151.883894) (xy 365.794142 -151.930407) (xy 365.756925 -151.971944) (xy 365.714057 -152.007619)
			(xy 365.666451 -152.036673) (xy 365.615122 -152.058485) (xy 365.561165 -152.072591) (xy 365.505728 -152.078691)
			(xy 365.449994 -152.076654) (xy 365.395151 -152.066524) (xy 365.342367 -152.048517) (xy 365.292767 -152.023016)
			(xy 365.247409 -151.990565) (xy 365.20726 -151.951856) (xy 365.173174 -151.907713) (xy 365.145878 -151.859078)
			(xy 365.125955 -151.806987) (xy 365.113829 -151.75255) (xy 365.109758 -151.696928) (xy 364.856811 -151.696928)
			(xy 364.856775 -151.698906) (xy 364.848655 -151.754082) (xy 364.832587 -151.807489) (xy 364.808915 -151.857986)
			(xy 364.778142 -151.904499) (xy 364.740925 -151.946036) (xy 364.698057 -151.981711) (xy 364.650451 -152.010765)
			(xy 364.599122 -152.032577) (xy 364.545165 -152.046683) (xy 364.489728 -152.052783) (xy 364.433994 -152.050746)
			(xy 364.379151 -152.040616) (xy 364.326367 -152.022609) (xy 364.276767 -151.997108) (xy 364.231409 -151.964657)
			(xy 364.19126 -151.925948) (xy 364.157174 -151.881805) (xy 364.129878 -151.83317) (xy 364.109955 -151.781079)
			(xy 364.097829 -151.726642) (xy 364.093758 -151.67102) (xy 353.950524 -151.67102) (xy 353.950524 -153.282904)
			(xy 353.950948 -153.292973) (xy 353.958667 -153.311575) (xy 353.96551 -153.318972) (xy 354.361496 -153.714704)
			(xy 354.379526 -153.733476) (xy 354.410102 -153.775594) (xy 354.413631 -153.782522) (xy 363.077758 -153.782522)
			(xy 363.081829 -153.7269) (xy 363.093955 -153.672463) (xy 363.113878 -153.620372) (xy 363.141174 -153.571737)
			(xy 363.17526 -153.527594) (xy 363.215409 -153.488885) (xy 363.260767 -153.456434) (xy 363.310367 -153.430933)
			(xy 363.363151 -153.412926) (xy 363.417994 -153.402796) (xy 363.473728 -153.400759) (xy 363.529165 -153.406859)
			(xy 363.583122 -153.420965) (xy 363.634451 -153.442777) (xy 363.682057 -153.471831) (xy 363.724925 -153.507506)
			(xy 363.762142 -153.549043) (xy 363.792915 -153.595556) (xy 363.816587 -153.646053) (xy 363.832655 -153.69946)
			(xy 363.840775 -153.754636) (xy 363.841284 -153.782522) (xy 364.093758 -153.782522) (xy 364.097829 -153.7269)
			(xy 364.109955 -153.672463) (xy 364.129878 -153.620372) (xy 364.157174 -153.571737) (xy 364.19126 -153.527594)
			(xy 364.231409 -153.488885) (xy 364.276767 -153.456434) (xy 364.326367 -153.430933) (xy 364.379151 -153.412926)
			(xy 364.433994 -153.402796) (xy 364.489728 -153.400759) (xy 364.545165 -153.406859) (xy 364.599122 -153.420965)
			(xy 364.650451 -153.442777) (xy 364.698057 -153.471831) (xy 364.740925 -153.507506) (xy 364.778142 -153.549043)
			(xy 364.808915 -153.595556) (xy 364.832587 -153.646053) (xy 364.848655 -153.69946) (xy 364.856775 -153.754636)
			(xy 364.857284 -153.782522) (xy 364.856775 -153.810408) (xy 364.853627 -153.831798) (xy 365.109758 -153.831798)
			(xy 365.113829 -153.776176) (xy 365.125955 -153.721739) (xy 365.145878 -153.669648) (xy 365.173174 -153.621013)
			(xy 365.20726 -153.57687) (xy 365.247409 -153.538161) (xy 365.292767 -153.50571) (xy 365.342367 -153.480209)
			(xy 365.395151 -153.462202) (xy 365.449994 -153.452072) (xy 365.505728 -153.450035) (xy 365.561165 -153.456135)
			(xy 365.615122 -153.470241) (xy 365.666451 -153.492053) (xy 365.714057 -153.521107) (xy 365.756925 -153.556782)
			(xy 365.794142 -153.598319) (xy 365.824915 -153.644832) (xy 365.848587 -153.695329) (xy 365.864655 -153.748736)
			(xy 365.869627 -153.782522) (xy 368.157758 -153.782522) (xy 368.161829 -153.7269) (xy 368.173955 -153.672463)
			(xy 368.193878 -153.620372) (xy 368.221174 -153.571737) (xy 368.25526 -153.527594) (xy 368.295409 -153.488885)
			(xy 368.340767 -153.456434) (xy 368.390367 -153.430933) (xy 368.443151 -153.412926) (xy 368.497994 -153.402796)
			(xy 368.553728 -153.400759) (xy 368.609165 -153.406859) (xy 368.663122 -153.420965) (xy 368.714451 -153.442777)
			(xy 368.762057 -153.471831) (xy 368.804925 -153.507506) (xy 368.842142 -153.549043) (xy 368.872915 -153.595556)
			(xy 368.896587 -153.646053) (xy 368.912655 -153.69946) (xy 368.920775 -153.754636) (xy 368.921284 -153.782522)
			(xy 368.920775 -153.810408) (xy 368.912655 -153.865584) (xy 368.896587 -153.918991) (xy 368.872915 -153.969488)
			(xy 368.842142 -154.016001) (xy 368.804925 -154.057538) (xy 368.762057 -154.093213) (xy 368.714451 -154.122267)
			(xy 368.663122 -154.144079) (xy 368.609165 -154.158185) (xy 368.553728 -154.164285) (xy 368.497994 -154.162248)
			(xy 368.443151 -154.152118) (xy 368.390367 -154.134111) (xy 368.340767 -154.10861) (xy 368.295409 -154.076159)
			(xy 368.25526 -154.03745) (xy 368.221174 -153.993307) (xy 368.193878 -153.944672) (xy 368.173955 -153.892581)
			(xy 368.161829 -153.838144) (xy 368.157758 -153.782522) (xy 365.869627 -153.782522) (xy 365.872775 -153.803912)
			(xy 365.873284 -153.831798) (xy 365.872775 -153.859684) (xy 365.864655 -153.91486) (xy 365.848587 -153.968267)
			(xy 365.824915 -154.018764) (xy 365.794142 -154.065277) (xy 365.756925 -154.106814) (xy 365.714057 -154.142489)
			(xy 365.666451 -154.171543) (xy 365.615122 -154.193355) (xy 365.561165 -154.207461) (xy 365.505728 -154.213561)
			(xy 365.449994 -154.211524) (xy 365.395151 -154.201394) (xy 365.342367 -154.183387) (xy 365.292767 -154.157886)
			(xy 365.247409 -154.125435) (xy 365.20726 -154.086726) (xy 365.173174 -154.042583) (xy 365.145878 -153.993948)
			(xy 365.125955 -153.941857) (xy 365.113829 -153.88742) (xy 365.109758 -153.831798) (xy 364.853627 -153.831798)
			(xy 364.848655 -153.865584) (xy 364.832587 -153.918991) (xy 364.808915 -153.969488) (xy 364.778142 -154.016001)
			(xy 364.740925 -154.057538) (xy 364.698057 -154.093213) (xy 364.650451 -154.122267) (xy 364.599122 -154.144079)
			(xy 364.545165 -154.158185) (xy 364.489728 -154.164285) (xy 364.433994 -154.162248) (xy 364.379151 -154.152118)
			(xy 364.326367 -154.134111) (xy 364.276767 -154.10861) (xy 364.231409 -154.076159) (xy 364.19126 -154.03745)
			(xy 364.157174 -153.993307) (xy 364.129878 -153.944672) (xy 364.109955 -153.892581) (xy 364.097829 -153.838144)
			(xy 364.093758 -153.782522) (xy 363.841284 -153.782522) (xy 363.840775 -153.810408) (xy 363.832655 -153.865584)
			(xy 363.816587 -153.918991) (xy 363.792915 -153.969488) (xy 363.762142 -154.016001) (xy 363.724925 -154.057538)
			(xy 363.682057 -154.093213) (xy 363.634451 -154.122267) (xy 363.583122 -154.144079) (xy 363.529165 -154.158185)
			(xy 363.473728 -154.164285) (xy 363.417994 -154.162248) (xy 363.363151 -154.152118) (xy 363.310367 -154.134111)
			(xy 363.260767 -154.10861) (xy 363.215409 -154.076159) (xy 363.17526 -154.03745) (xy 363.141174 -153.993307)
			(xy 363.113878 -153.944672) (xy 363.093955 -153.892581) (xy 363.081829 -153.838144) (xy 363.077758 -153.782522)
			(xy 354.413631 -153.782522) (xy 354.433724 -153.82197) (xy 354.449813 -153.871467) (xy 354.457974 -153.922869)
			(xy 354.458524 -153.948892) (xy 354.458524 -155.212034) (xy 355.569264 -155.212034) (xy 355.573335 -155.156412)
			(xy 355.585461 -155.101975) (xy 355.605384 -155.049884) (xy 355.63268 -155.001249) (xy 355.666766 -154.957106)
			(xy 355.706915 -154.918397) (xy 355.752273 -154.885946) (xy 355.801873 -154.860445) (xy 355.854657 -154.842438)
			(xy 355.9095 -154.832308) (xy 355.965234 -154.830271) (xy 356.020671 -154.836371) (xy 356.074628 -154.850477)
			(xy 356.125957 -154.872289) (xy 356.173563 -154.901343) (xy 356.216431 -154.937018) (xy 356.253648 -154.978555)
			(xy 356.284421 -155.025068) (xy 356.308093 -155.075565) (xy 356.309184 -155.079192) (xy 358.16997 -155.079192)
			(xy 358.174041 -155.02357) (xy 358.186167 -154.969133) (xy 358.20609 -154.917042) (xy 358.233386 -154.868407)
			(xy 358.267472 -154.824264) (xy 358.307621 -154.785555) (xy 358.352979 -154.753104) (xy 358.402579 -154.727603)
			(xy 358.455363 -154.709596) (xy 358.510206 -154.699466) (xy 358.56594 -154.697429) (xy 358.621377 -154.703529)
			(xy 358.675334 -154.717635) (xy 358.726663 -154.739447) (xy 358.774269 -154.768501) (xy 358.817137 -154.804176)
			(xy 358.854354 -154.845713) (xy 358.885127 -154.892226) (xy 358.908799 -154.942723) (xy 358.924867 -154.99613)
			(xy 358.932987 -155.051306) (xy 358.933496 -155.079192) (xy 358.933431 -155.082748) (xy 359.49382 -155.082748)
			(xy 359.494246 -155.056433) (xy 359.501489 -155.004302) (xy 359.515815 -154.953658) (xy 359.536956 -154.905459)
			(xy 359.564509 -154.860617) (xy 359.597955 -154.819979) (xy 359.61701 -154.801824) (xy 359.624405 -154.794297)
			(xy 359.632933 -154.775021) (xy 359.63352 -154.764486) (xy 359.63352 -154.68981) (xy 359.632993 -154.67926)
			(xy 359.624456 -154.659965) (xy 359.61701 -154.652472) (xy 359.59795 -154.634321) (xy 359.564493 -154.593691)
			(xy 359.536934 -154.548849) (xy 359.515796 -154.500648) (xy 359.50148 -154.449999) (xy 359.494257 -154.397864)
			(xy 359.49382 -154.371548) (xy 359.4943 -154.344295) (xy 359.502051 -154.290343) (xy 359.517403 -154.238044)
			(xy 359.540042 -154.188462) (xy 359.569507 -154.142607) (xy 359.605199 -154.101414) (xy 359.646391 -154.065719)
			(xy 359.692245 -154.036251) (xy 359.741825 -154.01361) (xy 359.794124 -153.998255) (xy 359.848075 -153.990501)
			(xy 359.875328 -153.99004) (xy 359.901643 -153.990476) (xy 359.953774 -153.997715) (xy 360.004417 -154.01204)
			(xy 360.052617 -154.033178) (xy 360.097459 -154.06073) (xy 360.138097 -154.094175) (xy 360.156252 -154.11323)
			(xy 360.163762 -154.120646) (xy 360.18305 -154.129165) (xy 360.19359 -154.12974) (xy 360.268266 -154.12974)
			(xy 360.278813 -154.129194) (xy 360.298108 -154.12067) (xy 360.305604 -154.11323) (xy 360.325424 -154.092442)
			(xy 360.370196 -154.056467) (xy 360.419854 -154.027607) (xy 360.473276 -154.006514) (xy 360.529255 -153.993665)
			(xy 360.586528 -153.98935) (xy 360.643801 -153.993665) (xy 360.69978 -154.006514) (xy 360.753202 -154.027607)
			(xy 360.80286 -154.056467) (xy 360.847632 -154.092442) (xy 360.867452 -154.11323) (xy 360.874962 -154.120646)
			(xy 360.89425 -154.129165) (xy 360.90479 -154.12974) (xy 360.979466 -154.12974) (xy 360.990013 -154.129194)
			(xy 361.009308 -154.12067) (xy 361.016804 -154.11323) (xy 361.036624 -154.092442) (xy 361.081396 -154.056467)
			(xy 361.131054 -154.027607) (xy 361.184476 -154.006514) (xy 361.240455 -153.993665) (xy 361.297728 -153.98935)
			(xy 361.355001 -153.993665) (xy 361.41098 -154.006514) (xy 361.464402 -154.027607) (xy 361.51406 -154.056467)
			(xy 361.558832 -154.092442) (xy 361.578652 -154.11323) (xy 361.586162 -154.120646) (xy 361.60545 -154.129165)
			(xy 361.61599 -154.12974) (xy 361.690666 -154.12974) (xy 361.701213 -154.129194) (xy 361.720508 -154.12067)
			(xy 361.728004 -154.11323) (xy 361.746171 -154.094185) (xy 361.786797 -154.060726) (xy 361.831635 -154.033165)
			(xy 361.879834 -154.012024) (xy 361.93048 -153.997705) (xy 361.982612 -153.990479) (xy 362.008928 -153.99004)
			(xy 362.036184 -153.990429) (xy 362.09014 -153.998191) (xy 362.142442 -154.013553) (xy 362.192026 -154.036202)
			(xy 362.237881 -154.065678) (xy 362.279075 -154.101379) (xy 362.314768 -154.14258) (xy 362.344234 -154.188441)
			(xy 362.366874 -154.238029) (xy 362.382225 -154.290334) (xy 362.389976 -154.344292) (xy 362.390436 -154.371548)
			(xy 362.389989 -154.397863) (xy 362.382748 -154.449991) (xy 362.368424 -154.500634) (xy 362.347288 -154.548833)
			(xy 362.319739 -154.593676) (xy 362.286298 -154.634315) (xy 362.267246 -154.652472) (xy 362.259862 -154.660008)
			(xy 362.251326 -154.679277) (xy 362.250736 -154.68981) (xy 362.250736 -154.764486) (xy 362.251248 -154.775038)
			(xy 362.259794 -154.794334) (xy 362.267246 -154.801824) (xy 362.286315 -154.819966) (xy 362.319769 -154.8606)
			(xy 362.347325 -154.905443) (xy 362.368461 -154.953646) (xy 362.382776 -155.004296) (xy 362.389998 -155.056431)
			(xy 362.390436 -155.082748) (xy 362.389967 -155.109999) (xy 362.382205 -155.163946) (xy 362.366845 -155.216239)
			(xy 362.3442 -155.265815) (xy 362.314731 -155.311664) (xy 362.279038 -155.352853) (xy 362.237848 -155.388543)
			(xy 362.191997 -155.41801) (xy 362.142421 -155.440652) (xy 362.090126 -155.456009) (xy 362.036179 -155.463768)
			(xy 362.008928 -155.464256) (xy 361.982612 -155.463851) (xy 361.93048 -155.456605) (xy 361.879836 -155.442275)
			(xy 361.831636 -155.421131) (xy 361.786795 -155.393573) (xy 361.746158 -155.360123) (xy 361.728004 -155.341066)
			(xy 361.720474 -155.333674) (xy 361.701201 -155.325142) (xy 361.690666 -155.324556) (xy 361.61599 -155.324556)
			(xy 361.60544 -155.325079) (xy 361.586146 -155.33362) (xy 361.578652 -155.341066) (xy 361.558832 -155.361854)
			(xy 361.51406 -155.397829) (xy 361.464402 -155.426689) (xy 361.41098 -155.447782) (xy 361.355001 -155.460631)
			(xy 361.297728 -155.464946) (xy 361.240455 -155.460631) (xy 361.184476 -155.447782) (xy 361.131054 -155.426689)
			(xy 361.081396 -155.397829) (xy 361.036624 -155.361854) (xy 361.016804 -155.341066) (xy 361.009274 -155.333674)
			(xy 360.990001 -155.325142) (xy 360.979466 -155.324556) (xy 360.90479 -155.324556) (xy 360.89424 -155.325079)
			(xy 360.874946 -155.33362) (xy 360.867452 -155.341066) (xy 360.847632 -155.361854) (xy 360.80286 -155.397829)
			(xy 360.753202 -155.426689) (xy 360.69978 -155.447782) (xy 360.643801 -155.460631) (xy 360.586528 -155.464946)
			(xy 360.529255 -155.460631) (xy 360.473276 -155.447782) (xy 360.419854 -155.426689) (xy 360.370196 -155.397829)
			(xy 360.325424 -155.361854) (xy 360.305604 -155.341066) (xy 360.298074 -155.333674) (xy 360.278801 -155.325142)
			(xy 360.268266 -155.324556) (xy 360.19359 -155.324556) (xy 360.18304 -155.325079) (xy 360.163746 -155.33362)
			(xy 360.156252 -155.341066) (xy 360.138126 -155.36015) (xy 360.097488 -155.393602) (xy 360.052641 -155.421156)
			(xy 360.004435 -155.442289) (xy 359.953783 -155.456601) (xy 359.901646 -155.46382) (xy 359.875328 -155.464256)
			(xy 359.84808 -155.463696) (xy 359.794137 -155.455944) (xy 359.741847 -155.440595) (xy 359.692273 -155.417961)
			(xy 359.646425 -155.388502) (xy 359.605235 -155.352818) (xy 359.569544 -155.311636) (xy 359.540076 -155.265794)
			(xy 359.517431 -155.216225) (xy 359.502072 -155.163937) (xy 359.49431 -155.109996) (xy 359.49382 -155.082748)
			(xy 358.933431 -155.082748) (xy 358.932987 -155.107078) (xy 358.924867 -155.162254) (xy 358.908799 -155.215661)
			(xy 358.885127 -155.266158) (xy 358.854354 -155.312671) (xy 358.817137 -155.354208) (xy 358.774269 -155.389883)
			(xy 358.726663 -155.418937) (xy 358.675334 -155.440749) (xy 358.621377 -155.454855) (xy 358.56594 -155.460955)
			(xy 358.510206 -155.458918) (xy 358.455363 -155.448788) (xy 358.402579 -155.430781) (xy 358.352979 -155.40528)
			(xy 358.307621 -155.372829) (xy 358.267472 -155.33412) (xy 358.233386 -155.289977) (xy 358.20609 -155.241342)
			(xy 358.186167 -155.189251) (xy 358.174041 -155.134814) (xy 358.16997 -155.079192) (xy 356.309184 -155.079192)
			(xy 356.324161 -155.128972) (xy 356.332281 -155.184148) (xy 356.33279 -155.212034) (xy 356.332281 -155.23992)
			(xy 356.324161 -155.295096) (xy 356.308093 -155.348503) (xy 356.284421 -155.399) (xy 356.253648 -155.445513)
			(xy 356.216431 -155.48705) (xy 356.173563 -155.522725) (xy 356.125957 -155.551779) (xy 356.074628 -155.573591)
			(xy 356.020671 -155.587697) (xy 355.965234 -155.593797) (xy 355.9095 -155.59176) (xy 355.854657 -155.58163)
			(xy 355.801873 -155.563623) (xy 355.752273 -155.538122) (xy 355.706915 -155.505671) (xy 355.666766 -155.466962)
			(xy 355.63268 -155.422819) (xy 355.605384 -155.374184) (xy 355.585461 -155.322093) (xy 355.573335 -155.267656)
			(xy 355.569264 -155.212034) (xy 354.458524 -155.212034) (xy 354.458524 -156.693108) (xy 354.458508 -156.69387)
			(xy 357.187498 -156.69387) (xy 357.191569 -156.638248) (xy 357.203695 -156.583811) (xy 357.223618 -156.53172)
			(xy 357.250914 -156.483085) (xy 357.285 -156.438942) (xy 357.325149 -156.400233) (xy 357.370507 -156.367782)
			(xy 357.420107 -156.342281) (xy 357.472891 -156.324274) (xy 357.527734 -156.314144) (xy 357.583468 -156.312107)
			(xy 357.638905 -156.318207) (xy 357.692862 -156.332313) (xy 357.744191 -156.354125) (xy 357.791797 -156.383179)
			(xy 357.834665 -156.418854) (xy 357.871882 -156.460391) (xy 357.902655 -156.506904) (xy 357.926327 -156.557401)
			(xy 357.942395 -156.610808) (xy 357.950515 -156.665984) (xy 357.951024 -156.69387) (xy 357.950515 -156.721756)
			(xy 357.942395 -156.776932) (xy 357.926327 -156.830339) (xy 357.902655 -156.880836) (xy 357.871882 -156.927349)
			(xy 357.834665 -156.968886) (xy 357.791797 -157.004561) (xy 357.744191 -157.033615) (xy 357.692862 -157.055427)
			(xy 357.638905 -157.069533) (xy 357.583468 -157.075633) (xy 357.527734 -157.073596) (xy 357.472891 -157.063466)
			(xy 357.420107 -157.045459) (xy 357.370507 -157.019958) (xy 357.325149 -156.987507) (xy 357.285 -156.948798)
			(xy 357.250914 -156.904655) (xy 357.223618 -156.85602) (xy 357.203695 -156.803929) (xy 357.191569 -156.749492)
			(xy 357.187498 -156.69387) (xy 354.458508 -156.69387) (xy 354.457992 -156.71913) (xy 354.449817 -156.770528)
			(xy 354.433715 -156.820019) (xy 354.410082 -156.866388) (xy 354.379498 -156.908497) (xy 354.361496 -156.927296)
			(xy 354.29571 -156.992828) (xy 354.288867 -157.000228) (xy 354.281141 -157.018826) (xy 354.280724 -157.028896)
			(xy 354.280724 -157.812994) (xy 354.950266 -157.812994) (xy 354.954337 -157.757372) (xy 354.966463 -157.702935)
			(xy 354.986386 -157.650844) (xy 355.013682 -157.602209) (xy 355.047768 -157.558066) (xy 355.087917 -157.519357)
			(xy 355.133275 -157.486906) (xy 355.182875 -157.461405) (xy 355.235659 -157.443398) (xy 355.290502 -157.433268)
			(xy 355.346236 -157.431231) (xy 355.401673 -157.437331) (xy 355.45563 -157.451437) (xy 355.506959 -157.473249)
			(xy 355.554565 -157.502303) (xy 355.597433 -157.537978) (xy 355.63465 -157.579515) (xy 355.665423 -157.626028)
			(xy 355.675673 -157.647894) (xy 359.313988 -157.647894) (xy 359.314524 -157.621251) (xy 359.323048 -157.568653)
			(xy 359.339905 -157.518105) (xy 359.364658 -157.470919) (xy 359.396665 -157.428318) (xy 359.435096 -157.391409)
			(xy 359.456736 -157.37586) (xy 359.468026 -157.367502) (xy 359.485877 -157.345826) (xy 359.497157 -157.320111)
			(xy 359.501013 -157.292297) (xy 359.497155 -157.264483) (xy 359.485874 -157.238768) (xy 359.468021 -157.217094)
			(xy 359.456736 -157.208728) (xy 359.435134 -157.193132) (xy 359.396719 -157.156218) (xy 359.364719 -157.113623)
			(xy 359.339961 -157.066449) (xy 359.323086 -157.015916) (xy 359.31453 -156.963332) (xy 359.313988 -156.936694)
			(xy 359.314498 -156.910707) (xy 359.322628 -156.859372) (xy 359.338689 -156.809942) (xy 359.362285 -156.763632)
			(xy 359.392835 -156.721584) (xy 359.429586 -156.684833) (xy 359.471634 -156.654283) (xy 359.517944 -156.630687)
			(xy 359.567374 -156.614626) (xy 359.618709 -156.606496) (xy 359.670683 -156.606496) (xy 359.722018 -156.614626)
			(xy 359.771448 -156.630687) (xy 359.817758 -156.654283) (xy 359.859806 -156.684833) (xy 359.896557 -156.721584)
			(xy 359.927107 -156.763632) (xy 359.950703 -156.809942) (xy 359.966764 -156.859372) (xy 359.974894 -156.910707)
			(xy 359.975404 -156.936694) (xy 359.974862 -156.963336) (xy 359.96634 -157.015935) (xy 359.949485 -157.066483)
			(xy 359.924733 -157.113669) (xy 359.892726 -157.15627) (xy 359.854296 -157.193179) (xy 359.832656 -157.208728)
			(xy 359.821379 -157.217101) (xy 359.803529 -157.238774) (xy 359.79225 -157.264486) (xy 359.788392 -157.292297)
			(xy 359.792248 -157.320108) (xy 359.803525 -157.34582) (xy 359.821374 -157.367494) (xy 359.832656 -157.37586)
			(xy 359.854251 -157.391466) (xy 359.892666 -157.428378) (xy 359.924667 -157.47097) (xy 359.949427 -157.518142)
			(xy 359.966303 -157.568674) (xy 359.974861 -157.621257) (xy 359.975404 -157.647894) (xy 360.21391 -157.647894)
			(xy 360.214437 -157.621251) (xy 360.222961 -157.568652) (xy 360.239819 -157.518103) (xy 360.264574 -157.470917)
			(xy 360.296583 -157.428317) (xy 360.335017 -157.391408) (xy 360.356658 -157.37586) (xy 360.367946 -157.3675)
			(xy 360.385793 -157.345824) (xy 360.39707 -157.320109) (xy 360.400926 -157.292297) (xy 360.397068 -157.264484)
			(xy 360.38579 -157.23877) (xy 360.367941 -157.217095) (xy 360.356658 -157.208728) (xy 360.335061 -157.193125)
			(xy 360.296645 -157.156214) (xy 360.264643 -157.11362) (xy 360.239884 -157.066447) (xy 360.223009 -157.015915)
			(xy 360.214452 -156.963332) (xy 360.21391 -156.936694) (xy 360.21442 -156.910707) (xy 360.22255 -156.859372)
			(xy 360.238611 -156.809942) (xy 360.262207 -156.763632) (xy 360.292757 -156.721584) (xy 360.329508 -156.684833)
			(xy 360.371556 -156.654283) (xy 360.417866 -156.630687) (xy 360.467296 -156.614626) (xy 360.518631 -156.606496)
			(xy 360.570605 -156.606496) (xy 360.62194 -156.614626) (xy 360.67137 -156.630687) (xy 360.71768 -156.654283)
			(xy 360.759728 -156.684833) (xy 360.796479 -156.721584) (xy 360.827029 -156.763632) (xy 360.850625 -156.809942)
			(xy 360.866686 -156.859372) (xy 360.874816 -156.910707) (xy 360.875326 -156.936694) (xy 360.874817 -156.963338)
			(xy 360.866294 -157.01594) (xy 360.849434 -157.06649) (xy 360.824675 -157.113677) (xy 360.792661 -157.156276)
			(xy 360.754222 -157.193182) (xy 360.732578 -157.208728) (xy 360.721299 -157.2171) (xy 360.703445 -157.238772)
			(xy 360.692163 -157.264484) (xy 360.688305 -157.292297) (xy 360.692161 -157.320109) (xy 360.703441 -157.345823)
			(xy 360.721294 -157.367495) (xy 360.732578 -157.37586) (xy 360.754178 -157.391459) (xy 360.792592 -157.428373)
			(xy 360.824592 -157.470967) (xy 360.84935 -157.518141) (xy 360.866226 -157.568673) (xy 360.874783 -157.621256)
			(xy 360.875326 -157.647894) (xy 361.113832 -157.647894) (xy 361.11435 -157.62125) (xy 361.122874 -157.56865)
			(xy 361.139734 -157.518101) (xy 361.16449 -157.470914) (xy 361.196502 -157.428315) (xy 361.234937 -157.391407)
			(xy 361.25658 -157.37586) (xy 361.267875 -157.367505) (xy 361.285736 -157.345832) (xy 361.297022 -157.320115)
			(xy 361.300881 -157.292297) (xy 361.29702 -157.264479) (xy 361.285732 -157.238762) (xy 361.26787 -157.217091)
			(xy 361.25658 -157.208728) (xy 361.234987 -157.193119) (xy 361.19657 -157.156209) (xy 361.164567 -157.113617)
			(xy 361.139808 -157.066446) (xy 361.122931 -157.015915) (xy 361.114374 -156.963331) (xy 361.113832 -156.936694)
			(xy 361.114342 -156.910707) (xy 361.122472 -156.859372) (xy 361.138533 -156.809942) (xy 361.162129 -156.763632)
			(xy 361.192679 -156.721584) (xy 361.22943 -156.684833) (xy 361.271478 -156.654283) (xy 361.317788 -156.630687)
			(xy 361.367218 -156.614626) (xy 361.418553 -156.606496) (xy 361.470527 -156.606496) (xy 361.521862 -156.614626)
			(xy 361.571292 -156.630687) (xy 361.617602 -156.654283) (xy 361.65965 -156.684833) (xy 361.696401 -156.721584)
			(xy 361.726951 -156.763632) (xy 361.750547 -156.809942) (xy 361.766608 -156.859372) (xy 361.774738 -156.910707)
			(xy 361.775248 -156.936694) (xy 361.77473 -156.963338) (xy 361.766207 -157.015938) (xy 361.749348 -157.066488)
			(xy 361.724592 -157.113675) (xy 361.69258 -157.156274) (xy 361.654143 -157.193181) (xy 361.6325 -157.208728)
			(xy 361.621219 -157.217099) (xy 361.603362 -157.23877) (xy 361.592077 -157.264483) (xy 361.588218 -157.292297)
			(xy 361.592075 -157.320111) (xy 361.603358 -157.345825) (xy 361.621214 -157.367496) (xy 361.6325 -157.37586)
			(xy 361.654083 -157.391483) (xy 361.692501 -157.428389) (xy 361.724506 -157.470977) (xy 361.749267 -157.518147)
			(xy 361.766146 -157.568676) (xy 361.774705 -157.621257) (xy 361.775248 -157.647894) (xy 362.014008 -157.647894)
			(xy 362.014536 -157.621251) (xy 362.02306 -157.568652) (xy 362.039918 -157.518103) (xy 362.064672 -157.470917)
			(xy 362.096682 -157.428317) (xy 362.135115 -157.391408) (xy 362.156756 -157.37586) (xy 362.168044 -157.367501)
			(xy 362.185892 -157.345824) (xy 362.197169 -157.320109) (xy 362.201024 -157.292297) (xy 362.197167 -157.264484)
			(xy 362.185888 -157.23877) (xy 362.168039 -157.217095) (xy 362.156756 -157.208728) (xy 362.135158 -157.193126)
			(xy 362.096742 -157.156214) (xy 362.064741 -157.113621) (xy 362.039982 -157.066448) (xy 362.023107 -157.015916)
			(xy 362.01455 -156.963332) (xy 362.014008 -156.936694) (xy 362.014518 -156.910707) (xy 362.022648 -156.859372)
			(xy 362.038709 -156.809942) (xy 362.062305 -156.763632) (xy 362.092855 -156.721584) (xy 362.129606 -156.684833)
			(xy 362.171654 -156.654283) (xy 362.217964 -156.630687) (xy 362.267394 -156.614626) (xy 362.318729 -156.606496)
			(xy 362.370703 -156.606496) (xy 362.422038 -156.614626) (xy 362.471468 -156.630687) (xy 362.517778 -156.654283)
			(xy 362.559826 -156.684833) (xy 362.596577 -156.721584) (xy 362.627127 -156.763632) (xy 362.650723 -156.809942)
			(xy 362.666784 -156.859372) (xy 362.674914 -156.910707) (xy 362.675424 -156.936694) (xy 362.674916 -156.963338)
			(xy 362.666392 -157.01594) (xy 362.649532 -157.06649) (xy 362.624774 -157.113677) (xy 362.59276 -157.156276)
			(xy 362.55432 -157.193182) (xy 362.532676 -157.208728) (xy 362.521397 -157.2171) (xy 362.503544 -157.238772)
			(xy 362.492262 -157.264484) (xy 362.488404 -157.292297) (xy 362.49226 -157.320109) (xy 362.50354 -157.345822)
			(xy 362.521392 -157.367495) (xy 362.532676 -157.37586) (xy 362.554275 -157.39146) (xy 362.592689 -157.428374)
			(xy 362.624689 -157.470968) (xy 362.649448 -157.518141) (xy 362.666324 -157.568673) (xy 362.674881 -157.621256)
			(xy 362.675383 -157.645862) (xy 363.629448 -157.645862) (xy 363.629875 -157.619546) (xy 363.637116 -157.567416)
			(xy 363.651442 -157.516771) (xy 363.672582 -157.468572) (xy 363.700136 -157.42373) (xy 363.733582 -157.383093)
			(xy 363.752638 -157.364938) (xy 363.760016 -157.357396) (xy 363.768556 -157.338132) (xy 363.769148 -157.3276)
			(xy 363.769148 -157.252924) (xy 363.768605 -157.242376) (xy 363.760078 -157.223082) (xy 363.752638 -157.215586)
			(xy 363.733571 -157.197442) (xy 363.700117 -157.156809) (xy 363.672561 -157.111965) (xy 363.651425 -157.063763)
			(xy 363.63711 -157.013114) (xy 363.629886 -156.960979) (xy 363.629448 -156.934662) (xy 363.629934 -156.907411)
			(xy 363.63769 -156.853463) (xy 363.653045 -156.801168) (xy 363.675687 -156.751591) (xy 363.705153 -156.705741)
			(xy 363.740844 -156.66455) (xy 363.782035 -156.628859) (xy 363.827885 -156.599393) (xy 363.877462 -156.576751)
			(xy 363.929757 -156.561396) (xy 363.983705 -156.55364) (xy 364.038207 -156.55364) (xy 364.092155 -156.561396)
			(xy 364.14445 -156.576751) (xy 364.194027 -156.599393) (xy 364.239877 -156.628859) (xy 364.258622 -156.645101)
			(xy 365.614017 -156.645101) (xy 365.618332 -156.587828) (xy 365.631182 -156.531849) (xy 365.652276 -156.478427)
			(xy 365.681137 -156.428769) (xy 365.717113 -156.383997) (xy 365.737902 -156.364178) (xy 365.745315 -156.356667)
			(xy 365.753833 -156.337379) (xy 365.754412 -156.32684) (xy 365.754412 -156.252164) (xy 365.753858 -156.241617)
			(xy 365.74534 -156.222322) (xy 365.737902 -156.214826) (xy 365.718866 -156.19665) (xy 365.685407 -156.156025)
			(xy 365.657846 -156.111189) (xy 365.636704 -156.062992) (xy 365.622382 -156.012348) (xy 365.615153 -155.960217)
			(xy 365.614712 -155.933902) (xy 365.615198 -155.906651) (xy 365.622954 -155.852703) (xy 365.638309 -155.800408)
			(xy 365.660951 -155.750831) (xy 365.690417 -155.704981) (xy 365.726108 -155.66379) (xy 365.767299 -155.628099)
			(xy 365.813149 -155.598633) (xy 365.862726 -155.575991) (xy 365.915021 -155.560636) (xy 365.968969 -155.55288)
			(xy 366.023471 -155.55288) (xy 366.077419 -155.560636) (xy 366.129714 -155.575991) (xy 366.179291 -155.598633)
			(xy 366.225141 -155.628099) (xy 366.266332 -155.66379) (xy 366.302023 -155.704981) (xy 366.331489 -155.750831)
			(xy 366.354131 -155.800408) (xy 366.369486 -155.852703) (xy 366.377242 -155.906651) (xy 366.377728 -155.933902)
			(xy 366.377253 -155.960216) (xy 366.370018 -156.012343) (xy 366.3557 -156.062986) (xy 366.334569 -156.111184)
			(xy 366.307025 -156.156028) (xy 366.273588 -156.196669) (xy 366.254538 -156.214826) (xy 366.247129 -156.222341)
			(xy 366.238608 -156.241626) (xy 366.238028 -156.252164) (xy 366.238028 -156.32684) (xy 366.238568 -156.337389)
			(xy 366.247095 -156.356685) (xy 366.254538 -156.364178) (xy 366.275327 -156.383996) (xy 366.3113 -156.42877)
			(xy 366.340158 -156.478428) (xy 366.36125 -156.53185) (xy 366.374098 -156.587829) (xy 366.378413 -156.645101)
			(xy 366.374098 -156.702374) (xy 366.372962 -156.707322) (xy 368.679825 -156.707322) (xy 368.684137 -156.650052)
			(xy 368.696983 -156.594076) (xy 368.718071 -156.540656) (xy 368.746926 -156.491) (xy 368.782897 -156.446228)
			(xy 368.803682 -156.426408) (xy 368.811079 -156.418883) (xy 368.819607 -156.399606) (xy 368.820192 -156.38907)
			(xy 368.820192 -156.314394) (xy 368.819682 -156.303842) (xy 368.811133 -156.284547) (xy 368.803682 -156.277056)
			(xy 368.784609 -156.258918) (xy 368.751154 -156.218284) (xy 368.723598 -156.17344) (xy 368.702462 -156.125236)
			(xy 368.688149 -156.074586) (xy 368.680928 -156.022449) (xy 368.680492 -155.996132) (xy 368.680978 -155.968881)
			(xy 368.688734 -155.914933) (xy 368.704089 -155.862638) (xy 368.726731 -155.813061) (xy 368.756197 -155.767211)
			(xy 368.791888 -155.72602) (xy 368.833079 -155.690329) (xy 368.878929 -155.660863) (xy 368.928506 -155.638221)
			(xy 368.980801 -155.622866) (xy 369.034749 -155.61511) (xy 369.089251 -155.61511) (xy 369.143199 -155.622866)
			(xy 369.195494 -155.638221) (xy 369.245071 -155.660863) (xy 369.290921 -155.690329) (xy 369.332112 -155.72602)
			(xy 369.367803 -155.767211) (xy 369.397269 -155.813061) (xy 369.419911 -155.862638) (xy 369.435266 -155.914933)
			(xy 369.443022 -155.968881) (xy 369.443508 -155.996132) (xy 369.443059 -156.022447) (xy 369.43582 -156.074576)
			(xy 369.421497 -156.125219) (xy 369.400361 -156.173418) (xy 369.372812 -156.218261) (xy 369.339371 -156.2589)
			(xy 369.320318 -156.277056) (xy 369.312936 -156.284594) (xy 369.3044 -156.303862) (xy 369.303808 -156.314394)
			(xy 369.303808 -156.38907) (xy 369.304337 -156.39962) (xy 369.312872 -156.418915) (xy 369.320318 -156.426408)
			(xy 369.341138 -156.446196) (xy 369.377113 -156.490973) (xy 369.405971 -156.540635) (xy 369.427062 -156.594062)
			(xy 369.439909 -156.650045) (xy 369.444222 -156.707322) (xy 369.439903 -156.764598) (xy 369.427049 -156.82058)
			(xy 369.405952 -156.874004) (xy 369.377088 -156.923663) (xy 369.341108 -156.968436) (xy 369.320318 -156.988256)
			(xy 369.312936 -156.995794) (xy 369.3044 -157.015062) (xy 369.303808 -157.025594) (xy 369.303808 -157.10027)
			(xy 369.304337 -157.11082) (xy 369.312872 -157.130115) (xy 369.320318 -157.137608) (xy 369.339374 -157.155763)
			(xy 369.37283 -157.196393) (xy 369.400389 -157.241234) (xy 369.421527 -157.289435) (xy 369.435844 -157.340082)
			(xy 369.443069 -157.392216) (xy 369.443508 -157.418532) (xy 369.443022 -157.445783) (xy 369.435266 -157.499731)
			(xy 369.419911 -157.552026) (xy 369.397269 -157.601603) (xy 369.367803 -157.647453) (xy 369.332112 -157.688644)
			(xy 369.290921 -157.724335) (xy 369.245071 -157.753801) (xy 369.195494 -157.776443) (xy 369.143199 -157.791798)
			(xy 369.089251 -157.799554) (xy 369.034749 -157.799554) (xy 368.980801 -157.791798) (xy 368.928506 -157.776443)
			(xy 368.878929 -157.753801) (xy 368.833079 -157.724335) (xy 368.791888 -157.688644) (xy 368.756197 -157.647453)
			(xy 368.726731 -157.601603) (xy 368.704089 -157.552026) (xy 368.688734 -157.499731) (xy 368.680978 -157.445783)
			(xy 368.680492 -157.418532) (xy 368.680917 -157.392217) (xy 368.688161 -157.340086) (xy 368.702488 -157.289443)
			(xy 368.723629 -157.241244) (xy 368.751182 -157.196402) (xy 368.784627 -157.155764) (xy 368.803682 -157.137608)
			(xy 368.811079 -157.130083) (xy 368.819607 -157.110806) (xy 368.820192 -157.10027) (xy 368.820192 -157.025594)
			(xy 368.819682 -157.015042) (xy 368.811133 -156.995747) (xy 368.803682 -156.988256) (xy 368.782926 -156.968404)
			(xy 368.746951 -156.923636) (xy 368.71809 -156.873983) (xy 368.696996 -156.820566) (xy 368.684144 -156.764591)
			(xy 368.679825 -156.707322) (xy 366.372962 -156.707322) (xy 366.361249 -156.758353) (xy 366.340157 -156.811774)
			(xy 366.311299 -156.861432) (xy 366.275325 -156.906205) (xy 366.254538 -156.926026) (xy 366.247129 -156.933541)
			(xy 366.238608 -156.952826) (xy 366.238028 -156.963364) (xy 366.238028 -157.03804) (xy 366.238568 -157.048589)
			(xy 366.247095 -157.067885) (xy 366.254538 -157.075378) (xy 366.273583 -157.093544) (xy 366.30704 -157.134172)
			(xy 366.334599 -157.179011) (xy 366.355739 -157.227209) (xy 366.370059 -157.277854) (xy 366.377287 -157.329987)
			(xy 366.377728 -157.356302) (xy 366.377242 -157.383553) (xy 366.369486 -157.437501) (xy 366.354131 -157.489796)
			(xy 366.331489 -157.539373) (xy 366.302023 -157.585223) (xy 366.266332 -157.626414) (xy 366.225141 -157.662105)
			(xy 366.179291 -157.691571) (xy 366.129714 -157.714213) (xy 366.077419 -157.729568) (xy 366.023471 -157.737324)
			(xy 365.968969 -157.737324) (xy 365.915021 -157.729568) (xy 365.862726 -157.714213) (xy 365.813149 -157.691571)
			(xy 365.767299 -157.662105) (xy 365.726108 -157.626414) (xy 365.690417 -157.585223) (xy 365.660951 -157.539373)
			(xy 365.638309 -157.489796) (xy 365.622954 -157.437501) (xy 365.615198 -157.383553) (xy 365.614712 -157.356302)
			(xy 365.615177 -157.329988) (xy 365.622412 -157.277859) (xy 365.636731 -157.227216) (xy 365.657864 -157.179017)
			(xy 365.685411 -157.134174) (xy 365.71885 -157.093534) (xy 365.737902 -157.075378) (xy 365.745315 -157.067867)
			(xy 365.753833 -157.048579) (xy 365.754412 -157.03804) (xy 365.754412 -156.963364) (xy 365.753858 -156.952817)
			(xy 365.74534 -156.933522) (xy 365.737902 -156.926026) (xy 365.717115 -156.906205) (xy 365.681138 -156.861433)
			(xy 365.652277 -156.811776) (xy 365.631183 -156.758354) (xy 365.618333 -156.702374) (xy 365.614017 -156.645101)
			(xy 364.258622 -156.645101) (xy 364.281068 -156.66455) (xy 364.316759 -156.705741) (xy 364.346225 -156.751591)
			(xy 364.368867 -156.801168) (xy 364.384222 -156.853463) (xy 364.391978 -156.907411) (xy 364.392464 -156.934662)
			(xy 364.392049 -156.960978) (xy 364.384805 -157.013109) (xy 364.370477 -157.063753) (xy 364.349334 -157.111952)
			(xy 364.321778 -157.156794) (xy 364.28833 -157.197431) (xy 364.269274 -157.215586) (xy 364.261887 -157.223121)
			(xy 364.253352 -157.24239) (xy 364.252764 -157.252924) (xy 364.252764 -157.3276) (xy 364.25329 -157.33815)
			(xy 364.261829 -157.357444) (xy 364.269274 -157.364938) (xy 364.288336 -157.383087) (xy 364.321794 -157.423718)
			(xy 364.349352 -157.468559) (xy 364.37049 -157.516761) (xy 364.384805 -157.56741) (xy 364.392027 -157.619545)
			(xy 364.392464 -157.645862) (xy 364.391978 -157.673113) (xy 364.384222 -157.727061) (xy 364.368867 -157.779356)
			(xy 364.346225 -157.828933) (xy 364.316759 -157.874783) (xy 364.281068 -157.915974) (xy 364.239877 -157.951665)
			(xy 364.194027 -157.981131) (xy 364.14445 -158.003773) (xy 364.092155 -158.019128) (xy 364.038207 -158.026884)
			(xy 363.983705 -158.026884) (xy 363.929757 -158.019128) (xy 363.877462 -158.003773) (xy 363.827885 -157.981131)
			(xy 363.782035 -157.951665) (xy 363.740844 -157.915974) (xy 363.705153 -157.874783) (xy 363.675687 -157.828933)
			(xy 363.653045 -157.779356) (xy 363.63769 -157.727061) (xy 363.629934 -157.673113) (xy 363.629448 -157.645862)
			(xy 362.675383 -157.645862) (xy 362.675424 -157.647894) (xy 362.674914 -157.673881) (xy 362.666784 -157.725216)
			(xy 362.650723 -157.774646) (xy 362.627127 -157.820956) (xy 362.596577 -157.863004) (xy 362.559826 -157.899755)
			(xy 362.517778 -157.930305) (xy 362.471468 -157.953901) (xy 362.422038 -157.969962) (xy 362.370703 -157.978092)
			(xy 362.318729 -157.978092) (xy 362.267394 -157.969962) (xy 362.217964 -157.953901) (xy 362.171654 -157.930305)
			(xy 362.129606 -157.899755) (xy 362.092855 -157.863004) (xy 362.062305 -157.820956) (xy 362.038709 -157.774646)
			(xy 362.022648 -157.725216) (xy 362.014518 -157.673881) (xy 362.014008 -157.647894) (xy 361.775248 -157.647894)
			(xy 361.774738 -157.673881) (xy 361.766608 -157.725216) (xy 361.750547 -157.774646) (xy 361.726951 -157.820956)
			(xy 361.696401 -157.863004) (xy 361.65965 -157.899755) (xy 361.617602 -157.930305) (xy 361.571292 -157.953901)
			(xy 361.521862 -157.969962) (xy 361.470527 -157.978092) (xy 361.418553 -157.978092) (xy 361.367218 -157.969962)
			(xy 361.317788 -157.953901) (xy 361.271478 -157.930305) (xy 361.22943 -157.899755) (xy 361.192679 -157.863004)
			(xy 361.162129 -157.820956) (xy 361.138533 -157.774646) (xy 361.122472 -157.725216) (xy 361.114342 -157.673881)
			(xy 361.113832 -157.647894) (xy 360.875326 -157.647894) (xy 360.874816 -157.673881) (xy 360.866686 -157.725216)
			(xy 360.850625 -157.774646) (xy 360.827029 -157.820956) (xy 360.796479 -157.863004) (xy 360.759728 -157.899755)
			(xy 360.71768 -157.930305) (xy 360.67137 -157.953901) (xy 360.62194 -157.969962) (xy 360.570605 -157.978092)
			(xy 360.518631 -157.978092) (xy 360.467296 -157.969962) (xy 360.417866 -157.953901) (xy 360.371556 -157.930305)
			(xy 360.329508 -157.899755) (xy 360.292757 -157.863004) (xy 360.262207 -157.820956) (xy 360.238611 -157.774646)
			(xy 360.22255 -157.725216) (xy 360.21442 -157.673881) (xy 360.21391 -157.647894) (xy 359.975404 -157.647894)
			(xy 359.974894 -157.673881) (xy 359.966764 -157.725216) (xy 359.950703 -157.774646) (xy 359.927107 -157.820956)
			(xy 359.896557 -157.863004) (xy 359.859806 -157.899755) (xy 359.817758 -157.930305) (xy 359.771448 -157.953901)
			(xy 359.722018 -157.969962) (xy 359.670683 -157.978092) (xy 359.618709 -157.978092) (xy 359.567374 -157.969962)
			(xy 359.517944 -157.953901) (xy 359.471634 -157.930305) (xy 359.429586 -157.899755) (xy 359.392835 -157.863004)
			(xy 359.362285 -157.820956) (xy 359.338689 -157.774646) (xy 359.322628 -157.725216) (xy 359.314498 -157.673881)
			(xy 359.313988 -157.647894) (xy 355.675673 -157.647894) (xy 355.689095 -157.676525) (xy 355.705163 -157.729932)
			(xy 355.713283 -157.785108) (xy 355.713792 -157.812994) (xy 355.713283 -157.84088) (xy 355.705163 -157.896056)
			(xy 355.689095 -157.949463) (xy 355.665423 -157.99996) (xy 355.63465 -158.046473) (xy 355.62218 -158.06039)
			(xy 357.139746 -158.06039) (xy 357.143817 -158.004768) (xy 357.155943 -157.950331) (xy 357.175866 -157.89824)
			(xy 357.203162 -157.849605) (xy 357.237248 -157.805462) (xy 357.277397 -157.766753) (xy 357.322755 -157.734302)
			(xy 357.372355 -157.708801) (xy 357.425139 -157.690794) (xy 357.479982 -157.680664) (xy 357.535716 -157.678627)
			(xy 357.591153 -157.684727) (xy 357.64511 -157.698833) (xy 357.696439 -157.720645) (xy 357.744045 -157.749699)
			(xy 357.786913 -157.785374) (xy 357.82413 -157.826911) (xy 357.854903 -157.873424) (xy 357.878575 -157.923921)
			(xy 357.894643 -157.977328) (xy 357.902763 -158.032504) (xy 357.903272 -158.06039) (xy 357.902763 -158.088276)
			(xy 357.894643 -158.143452) (xy 357.878575 -158.196859) (xy 357.854903 -158.247356) (xy 357.82413 -158.293869)
			(xy 357.786913 -158.335406) (xy 357.744045 -158.371081) (xy 357.696439 -158.400135) (xy 357.64511 -158.421947)
			(xy 357.591153 -158.436053) (xy 357.535716 -158.442153) (xy 357.479982 -158.440116) (xy 357.425139 -158.429986)
			(xy 357.372355 -158.411979) (xy 357.322755 -158.386478) (xy 357.277397 -158.354027) (xy 357.237248 -158.315318)
			(xy 357.203162 -158.271175) (xy 357.175866 -158.22254) (xy 357.155943 -158.170449) (xy 357.143817 -158.116012)
			(xy 357.139746 -158.06039) (xy 355.62218 -158.06039) (xy 355.597433 -158.08801) (xy 355.554565 -158.123685)
			(xy 355.506959 -158.152739) (xy 355.45563 -158.174551) (xy 355.401673 -158.188657) (xy 355.346236 -158.194757)
			(xy 355.290502 -158.19272) (xy 355.235659 -158.18259) (xy 355.182875 -158.164583) (xy 355.133275 -158.139082)
			(xy 355.087917 -158.106631) (xy 355.047768 -158.067922) (xy 355.013682 -158.023779) (xy 354.986386 -157.975144)
			(xy 354.966463 -157.923053) (xy 354.954337 -157.868616) (xy 354.950266 -157.812994) (xy 354.280724 -157.812994)
			(xy 354.280724 -158.828994) (xy 354.950266 -158.828994) (xy 354.954337 -158.773372) (xy 354.966463 -158.718935)
			(xy 354.986386 -158.666844) (xy 355.013682 -158.618209) (xy 355.047768 -158.574066) (xy 355.087917 -158.535357)
			(xy 355.133275 -158.502906) (xy 355.182875 -158.477405) (xy 355.235659 -158.459398) (xy 355.290502 -158.449268)
			(xy 355.346236 -158.447231) (xy 355.401673 -158.453331) (xy 355.45563 -158.467437) (xy 355.506959 -158.489249)
			(xy 355.554565 -158.518303) (xy 355.597433 -158.553978) (xy 355.63465 -158.595515) (xy 355.665423 -158.642028)
			(xy 355.689095 -158.692525) (xy 355.705163 -158.745932) (xy 355.706248 -158.753302) (xy 364.816642 -158.753302)
			(xy 364.820713 -158.69768) (xy 364.832839 -158.643243) (xy 364.852762 -158.591152) (xy 364.880058 -158.542517)
			(xy 364.914144 -158.498374) (xy 364.954293 -158.459665) (xy 364.999651 -158.427214) (xy 365.049251 -158.401713)
			(xy 365.102035 -158.383706) (xy 365.156878 -158.373576) (xy 365.212612 -158.371539) (xy 365.268049 -158.377639)
			(xy 365.322006 -158.391745) (xy 365.373335 -158.413557) (xy 365.420941 -158.442611) (xy 365.463809 -158.478286)
			(xy 365.501026 -158.519823) (xy 365.531799 -158.566336) (xy 365.555471 -158.616833) (xy 365.571539 -158.67024)
			(xy 365.579659 -158.725416) (xy 365.580168 -158.753302) (xy 365.579659 -158.781188) (xy 365.571539 -158.836364)
			(xy 365.555471 -158.889771) (xy 365.531799 -158.940268) (xy 365.501026 -158.986781) (xy 365.463809 -159.028318)
			(xy 365.420941 -159.063993) (xy 365.373335 -159.093047) (xy 365.322006 -159.114859) (xy 365.268049 -159.128965)
			(xy 365.212612 -159.135065) (xy 365.156878 -159.133028) (xy 365.102035 -159.122898) (xy 365.049251 -159.104891)
			(xy 364.999651 -159.07939) (xy 364.954293 -159.046939) (xy 364.914144 -159.00823) (xy 364.880058 -158.964087)
			(xy 364.852762 -158.915452) (xy 364.832839 -158.863361) (xy 364.820713 -158.808924) (xy 364.816642 -158.753302)
			(xy 355.706248 -158.753302) (xy 355.713283 -158.801108) (xy 355.713792 -158.828994) (xy 355.713283 -158.85688)
			(xy 355.705163 -158.912056) (xy 355.689095 -158.965463) (xy 355.665423 -159.01596) (xy 355.63465 -159.062473)
			(xy 355.597433 -159.10401) (xy 355.554565 -159.139685) (xy 355.506959 -159.168739) (xy 355.45563 -159.190551)
			(xy 355.401673 -159.204657) (xy 355.346236 -159.210757) (xy 355.290502 -159.20872) (xy 355.235659 -159.19859)
			(xy 355.182875 -159.180583) (xy 355.133275 -159.155082) (xy 355.087917 -159.122631) (xy 355.047768 -159.083922)
			(xy 355.013682 -159.039779) (xy 354.986386 -158.991144) (xy 354.966463 -158.939053) (xy 354.954337 -158.884616)
			(xy 354.950266 -158.828994) (xy 354.280724 -158.828994) (xy 354.280724 -159.439102) (xy 357.208072 -159.439102)
			(xy 357.212143 -159.38348) (xy 357.224269 -159.329043) (xy 357.244192 -159.276952) (xy 357.271488 -159.228317)
			(xy 357.305574 -159.184174) (xy 357.345723 -159.145465) (xy 357.391081 -159.113014) (xy 357.440681 -159.087513)
			(xy 357.493465 -159.069506) (xy 357.548308 -159.059376) (xy 357.604042 -159.057339) (xy 357.659479 -159.063439)
			(xy 357.713436 -159.077545) (xy 357.764765 -159.099357) (xy 357.812371 -159.128411) (xy 357.855239 -159.164086)
			(xy 357.892456 -159.205623) (xy 357.923229 -159.252136) (xy 357.946901 -159.302633) (xy 357.962969 -159.35604)
			(xy 357.971089 -159.411216) (xy 357.971598 -159.439102) (xy 357.971089 -159.466988) (xy 357.962969 -159.522164)
			(xy 357.960066 -159.531812) (xy 360.41279 -159.531812) (xy 360.416861 -159.47619) (xy 360.428987 -159.421753)
			(xy 360.44891 -159.369662) (xy 360.476206 -159.321027) (xy 360.510292 -159.276884) (xy 360.550441 -159.238175)
			(xy 360.595799 -159.205724) (xy 360.645399 -159.180223) (xy 360.698183 -159.162216) (xy 360.753026 -159.152086)
			(xy 360.80876 -159.150049) (xy 360.864197 -159.156149) (xy 360.918154 -159.170255) (xy 360.969483 -159.192067)
			(xy 361.017089 -159.221121) (xy 361.059957 -159.256796) (xy 361.097174 -159.298333) (xy 361.127947 -159.344846)
			(xy 361.151619 -159.395343) (xy 361.167687 -159.44875) (xy 361.171463 -159.474408) (xy 362.882432 -159.474408)
			(xy 362.886503 -159.418786) (xy 362.898629 -159.364349) (xy 362.918552 -159.312258) (xy 362.945848 -159.263623)
			(xy 362.979934 -159.21948) (xy 363.020083 -159.180771) (xy 363.065441 -159.14832) (xy 363.115041 -159.122819)
			(xy 363.167825 -159.104812) (xy 363.222668 -159.094682) (xy 363.278402 -159.092645) (xy 363.333839 -159.098745)
			(xy 363.387796 -159.112851) (xy 363.439125 -159.134663) (xy 363.486731 -159.163717) (xy 363.529599 -159.199392)
			(xy 363.566816 -159.240929) (xy 363.597589 -159.287442) (xy 363.621261 -159.337939) (xy 363.637329 -159.391346)
			(xy 363.645449 -159.446522) (xy 363.645958 -159.474408) (xy 363.645449 -159.502294) (xy 363.637329 -159.55747)
			(xy 363.621261 -159.610877) (xy 363.597589 -159.661374) (xy 363.566816 -159.707887) (xy 363.529599 -159.749424)
			(xy 363.486731 -159.785099) (xy 363.439125 -159.814153) (xy 363.387796 -159.835965) (xy 363.333839 -159.850071)
			(xy 363.278402 -159.856171) (xy 363.222668 -159.854134) (xy 363.167825 -159.844004) (xy 363.115041 -159.825997)
			(xy 363.065441 -159.800496) (xy 363.020083 -159.768045) (xy 362.979934 -159.729336) (xy 362.945848 -159.685193)
			(xy 362.918552 -159.636558) (xy 362.898629 -159.584467) (xy 362.886503 -159.53003) (xy 362.882432 -159.474408)
			(xy 361.171463 -159.474408) (xy 361.175807 -159.503926) (xy 361.176316 -159.531812) (xy 361.175807 -159.559698)
			(xy 361.167687 -159.614874) (xy 361.151619 -159.668281) (xy 361.127947 -159.718778) (xy 361.097174 -159.765291)
			(xy 361.059957 -159.806828) (xy 361.017089 -159.842503) (xy 360.969483 -159.871557) (xy 360.918154 -159.893369)
			(xy 360.864197 -159.907475) (xy 360.80876 -159.913575) (xy 360.753026 -159.911538) (xy 360.698183 -159.901408)
			(xy 360.645399 -159.883401) (xy 360.595799 -159.8579) (xy 360.550441 -159.825449) (xy 360.510292 -159.78674)
			(xy 360.476206 -159.742597) (xy 360.44891 -159.693962) (xy 360.428987 -159.641871) (xy 360.416861 -159.587434)
			(xy 360.41279 -159.531812) (xy 357.960066 -159.531812) (xy 357.946901 -159.575571) (xy 357.923229 -159.626068)
			(xy 357.892456 -159.672581) (xy 357.855239 -159.714118) (xy 357.812371 -159.749793) (xy 357.764765 -159.778847)
			(xy 357.713436 -159.800659) (xy 357.659479 -159.814765) (xy 357.604042 -159.820865) (xy 357.548308 -159.818828)
			(xy 357.493465 -159.808698) (xy 357.440681 -159.790691) (xy 357.391081 -159.76519) (xy 357.345723 -159.732739)
			(xy 357.305574 -159.69403) (xy 357.271488 -159.649887) (xy 357.244192 -159.601252) (xy 357.224269 -159.549161)
			(xy 357.212143 -159.494724) (xy 357.208072 -159.439102) (xy 354.280724 -159.439102) (xy 354.280724 -159.715708)
			(xy 354.280192 -159.74173) (xy 354.272017 -159.793128) (xy 354.255915 -159.842619) (xy 354.254705 -159.844994)
			(xy 354.950266 -159.844994) (xy 354.954337 -159.789372) (xy 354.966463 -159.734935) (xy 354.986386 -159.682844)
			(xy 355.013682 -159.634209) (xy 355.047768 -159.590066) (xy 355.087917 -159.551357) (xy 355.133275 -159.518906)
			(xy 355.182875 -159.493405) (xy 355.235659 -159.475398) (xy 355.290502 -159.465268) (xy 355.346236 -159.463231)
			(xy 355.401673 -159.469331) (xy 355.45563 -159.483437) (xy 355.506959 -159.505249) (xy 355.554565 -159.534303)
			(xy 355.597433 -159.569978) (xy 355.63465 -159.611515) (xy 355.665423 -159.658028) (xy 355.689095 -159.708525)
			(xy 355.705163 -159.761932) (xy 355.713283 -159.817108) (xy 355.713792 -159.844994) (xy 355.713283 -159.87288)
			(xy 355.705163 -159.928056) (xy 355.689095 -159.981463) (xy 355.665423 -160.03196) (xy 355.63465 -160.078473)
			(xy 355.597433 -160.12001) (xy 355.554565 -160.155685) (xy 355.506959 -160.184739) (xy 355.45563 -160.206551)
			(xy 355.401673 -160.220657) (xy 355.346236 -160.226757) (xy 355.290502 -160.22472) (xy 355.235659 -160.21459)
			(xy 355.182875 -160.196583) (xy 355.133275 -160.171082) (xy 355.087917 -160.138631) (xy 355.047768 -160.099922)
			(xy 355.013682 -160.055779) (xy 354.986386 -160.007144) (xy 354.966463 -159.955053) (xy 354.954337 -159.900616)
			(xy 354.950266 -159.844994) (xy 354.254705 -159.844994) (xy 354.232282 -159.888988) (xy 354.201698 -159.931097)
			(xy 354.183696 -159.949896) (xy 353.167696 -160.965896) (xy 357.23779 -160.965896) (xy 357.241861 -160.910274)
			(xy 357.253987 -160.855837) (xy 357.27391 -160.803746) (xy 357.301206 -160.755111) (xy 357.335292 -160.710968)
			(xy 357.375441 -160.672259) (xy 357.420799 -160.639808) (xy 357.470399 -160.614307) (xy 357.523183 -160.5963)
			(xy 357.578026 -160.58617) (xy 357.63376 -160.584133) (xy 357.689197 -160.590233) (xy 357.743154 -160.604339)
			(xy 357.794483 -160.626151) (xy 357.842089 -160.655205) (xy 357.884957 -160.69088) (xy 357.922174 -160.732417)
			(xy 357.952947 -160.77893) (xy 357.976619 -160.829427) (xy 357.992687 -160.882834) (xy 358.000807 -160.93801)
			(xy 358.001279 -160.963864) (xy 358.62971 -160.963864) (xy 358.633781 -160.908242) (xy 358.645907 -160.853805)
			(xy 358.66583 -160.801714) (xy 358.693126 -160.753079) (xy 358.727212 -160.708936) (xy 358.767361 -160.670227)
			(xy 358.812719 -160.637776) (xy 358.862319 -160.612275) (xy 358.915103 -160.594268) (xy 358.969946 -160.584138)
			(xy 359.02568 -160.582101) (xy 359.081117 -160.588201) (xy 359.135074 -160.602307) (xy 359.186403 -160.624119)
			(xy 359.234009 -160.653173) (xy 359.276877 -160.688848) (xy 359.314094 -160.730385) (xy 359.344867 -160.776898)
			(xy 359.368539 -160.827395) (xy 359.384607 -160.880802) (xy 359.392727 -160.935978) (xy 359.393236 -160.963864)
			(xy 359.393143 -160.968944) (xy 359.901488 -160.968944) (xy 359.905559 -160.913322) (xy 359.917685 -160.858885)
			(xy 359.937608 -160.806794) (xy 359.964904 -160.758159) (xy 359.99899 -160.714016) (xy 360.039139 -160.675307)
			(xy 360.084497 -160.642856) (xy 360.134097 -160.617355) (xy 360.186881 -160.599348) (xy 360.241724 -160.589218)
			(xy 360.297458 -160.587181) (xy 360.352895 -160.593281) (xy 360.406852 -160.607387) (xy 360.458181 -160.629199)
			(xy 360.505787 -160.658253) (xy 360.548655 -160.693928) (xy 360.585872 -160.735465) (xy 360.616645 -160.781978)
			(xy 360.640317 -160.832475) (xy 360.656385 -160.885882) (xy 360.658778 -160.902142) (xy 361.68279 -160.902142)
			(xy 361.686861 -160.84652) (xy 361.698987 -160.792083) (xy 361.71891 -160.739992) (xy 361.746206 -160.691357)
			(xy 361.780292 -160.647214) (xy 361.820441 -160.608505) (xy 361.865799 -160.576054) (xy 361.915399 -160.550553)
			(xy 361.968183 -160.532546) (xy 362.023026 -160.522416) (xy 362.07876 -160.520379) (xy 362.134197 -160.526479)
			(xy 362.188154 -160.540585) (xy 362.239483 -160.562397) (xy 362.287089 -160.591451) (xy 362.329957 -160.627126)
			(xy 362.367174 -160.668663) (xy 362.397947 -160.715176) (xy 362.421619 -160.765673) (xy 362.437687 -160.81908)
			(xy 362.445807 -160.874256) (xy 362.446316 -160.902142) (xy 362.445807 -160.930028) (xy 362.437687 -160.985204)
			(xy 362.421619 -161.038611) (xy 362.397947 -161.089108) (xy 362.367174 -161.135621) (xy 362.329957 -161.177158)
			(xy 362.287089 -161.212833) (xy 362.239483 -161.241887) (xy 362.188154 -161.263699) (xy 362.134197 -161.277805)
			(xy 362.07876 -161.283905) (xy 362.023026 -161.281868) (xy 361.968183 -161.271738) (xy 361.915399 -161.253731)
			(xy 361.865799 -161.22823) (xy 361.820441 -161.195779) (xy 361.780292 -161.15707) (xy 361.746206 -161.112927)
			(xy 361.71891 -161.064292) (xy 361.698987 -161.012201) (xy 361.686861 -160.957764) (xy 361.68279 -160.902142)
			(xy 360.658778 -160.902142) (xy 360.664505 -160.941058) (xy 360.665014 -160.968944) (xy 360.664505 -160.99683)
			(xy 360.656385 -161.052006) (xy 360.640317 -161.105413) (xy 360.616645 -161.15591) (xy 360.585872 -161.202423)
			(xy 360.548655 -161.24396) (xy 360.505787 -161.279635) (xy 360.458181 -161.308689) (xy 360.406852 -161.330501)
			(xy 360.352895 -161.344607) (xy 360.297458 -161.350707) (xy 360.241724 -161.34867) (xy 360.186881 -161.33854)
			(xy 360.134097 -161.320533) (xy 360.084497 -161.295032) (xy 360.039139 -161.262581) (xy 359.99899 -161.223872)
			(xy 359.964904 -161.179729) (xy 359.937608 -161.131094) (xy 359.917685 -161.079003) (xy 359.905559 -161.024566)
			(xy 359.901488 -160.968944) (xy 359.393143 -160.968944) (xy 359.392727 -160.99175) (xy 359.384607 -161.046926)
			(xy 359.368539 -161.100333) (xy 359.344867 -161.15083) (xy 359.314094 -161.197343) (xy 359.276877 -161.23888)
			(xy 359.234009 -161.274555) (xy 359.186403 -161.303609) (xy 359.135074 -161.325421) (xy 359.081117 -161.339527)
			(xy 359.02568 -161.345627) (xy 358.969946 -161.34359) (xy 358.915103 -161.33346) (xy 358.862319 -161.315453)
			(xy 358.812719 -161.289952) (xy 358.767361 -161.257501) (xy 358.727212 -161.218792) (xy 358.693126 -161.174649)
			(xy 358.66583 -161.126014) (xy 358.645907 -161.073923) (xy 358.633781 -161.019486) (xy 358.62971 -160.963864)
			(xy 358.001279 -160.963864) (xy 358.001316 -160.965896) (xy 358.000807 -160.993782) (xy 357.992687 -161.048958)
			(xy 357.976619 -161.102365) (xy 357.952947 -161.152862) (xy 357.922174 -161.199375) (xy 357.884957 -161.240912)
			(xy 357.842089 -161.276587) (xy 357.794483 -161.305641) (xy 357.743154 -161.327453) (xy 357.689197 -161.341559)
			(xy 357.63376 -161.347659) (xy 357.578026 -161.345622) (xy 357.523183 -161.335492) (xy 357.470399 -161.317485)
			(xy 357.420799 -161.291984) (xy 357.375441 -161.259533) (xy 357.335292 -161.220824) (xy 357.301206 -161.176681)
			(xy 357.27391 -161.128046) (xy 357.253987 -161.075955) (xy 357.241861 -161.021518) (xy 357.23779 -160.965896)
			(xy 353.167696 -160.965896) (xy 353.027742 -161.10585) (xy 353.020899 -161.113249) (xy 353.013176 -161.131848)
			(xy 353.012756 -161.141918) (xy 353.012756 -163.114736) (xy 364.34979 -163.114736) (xy 364.353861 -163.059114)
			(xy 364.365987 -163.004677) (xy 364.38591 -162.952586) (xy 364.413206 -162.903951) (xy 364.447292 -162.859808)
			(xy 364.487441 -162.821099) (xy 364.532799 -162.788648) (xy 364.582399 -162.763147) (xy 364.635183 -162.74514)
			(xy 364.690026 -162.73501) (xy 364.74576 -162.732973) (xy 364.801197 -162.739073) (xy 364.855154 -162.753179)
			(xy 364.906483 -162.774991) (xy 364.954089 -162.804045) (xy 364.996957 -162.83972) (xy 365.034174 -162.881257)
			(xy 365.064947 -162.92777) (xy 365.088619 -162.978267) (xy 365.104687 -163.031674) (xy 365.112807 -163.08685)
			(xy 365.113316 -163.114736) (xy 365.112807 -163.142622) (xy 365.104687 -163.197798) (xy 365.088619 -163.251205)
			(xy 365.064947 -163.301702) (xy 365.034174 -163.348215) (xy 364.996957 -163.389752) (xy 364.954089 -163.425427)
			(xy 364.906483 -163.454481) (xy 364.855154 -163.476293) (xy 364.801197 -163.490399) (xy 364.74576 -163.496499)
			(xy 364.690026 -163.494462) (xy 364.635183 -163.484332) (xy 364.582399 -163.466325) (xy 364.532799 -163.440824)
			(xy 364.487441 -163.408373) (xy 364.447292 -163.369664) (xy 364.413206 -163.325521) (xy 364.38591 -163.276886)
			(xy 364.365987 -163.224795) (xy 364.353861 -163.170358) (xy 364.34979 -163.114736) (xy 353.012756 -163.114736)
			(xy 353.012756 -165.608) (xy 354.455982 -165.608) (xy 354.460053 -165.552378) (xy 354.472179 -165.497941)
			(xy 354.492102 -165.44585) (xy 354.519398 -165.397215) (xy 354.553484 -165.353072) (xy 354.593633 -165.314363)
			(xy 354.638991 -165.281912) (xy 354.688591 -165.256411) (xy 354.741375 -165.238404) (xy 354.796218 -165.228274)
			(xy 354.851952 -165.226237) (xy 354.907389 -165.232337) (xy 354.961346 -165.246443) (xy 355.012675 -165.268255)
			(xy 355.060281 -165.297309) (xy 355.103149 -165.332984) (xy 355.140366 -165.374521) (xy 355.171139 -165.421034)
			(xy 355.194811 -165.471531) (xy 355.210879 -165.524938) (xy 355.218999 -165.580114) (xy 355.219508 -165.608)
			(xy 355.219378 -165.615112) (xy 356.546148 -165.615112) (xy 356.550219 -165.55949) (xy 356.562345 -165.505053)
			(xy 356.582268 -165.452962) (xy 356.609564 -165.404327) (xy 356.64365 -165.360184) (xy 356.683799 -165.321475)
			(xy 356.729157 -165.289024) (xy 356.778757 -165.263523) (xy 356.831541 -165.245516) (xy 356.886384 -165.235386)
			(xy 356.942118 -165.233349) (xy 356.997555 -165.239449) (xy 357.051512 -165.253555) (xy 357.102841 -165.275367)
			(xy 357.150447 -165.304421) (xy 357.193315 -165.340096) (xy 357.230532 -165.381633) (xy 357.261305 -165.428146)
			(xy 357.284977 -165.478643) (xy 357.301045 -165.53205) (xy 357.309165 -165.587226) (xy 357.309674 -165.615112)
			(xy 357.309165 -165.642998) (xy 357.301045 -165.698174) (xy 357.284977 -165.751581) (xy 357.261305 -165.802078)
			(xy 357.230532 -165.848591) (xy 357.193315 -165.890128) (xy 357.150447 -165.925803) (xy 357.102841 -165.954857)
			(xy 357.051512 -165.976669) (xy 356.997555 -165.990775) (xy 356.942118 -165.996875) (xy 356.886384 -165.994838)
			(xy 356.831541 -165.984708) (xy 356.778757 -165.966701) (xy 356.729157 -165.9412) (xy 356.683799 -165.908749)
			(xy 356.64365 -165.87004) (xy 356.609564 -165.825897) (xy 356.582268 -165.777262) (xy 356.562345 -165.725171)
			(xy 356.550219 -165.670734) (xy 356.546148 -165.615112) (xy 355.219378 -165.615112) (xy 355.218999 -165.635886)
			(xy 355.210879 -165.691062) (xy 355.194811 -165.744469) (xy 355.171139 -165.794966) (xy 355.140366 -165.841479)
			(xy 355.103149 -165.883016) (xy 355.060281 -165.918691) (xy 355.012675 -165.947745) (xy 354.961346 -165.969557)
			(xy 354.907389 -165.983663) (xy 354.851952 -165.989763) (xy 354.796218 -165.987726) (xy 354.741375 -165.977596)
			(xy 354.688591 -165.959589) (xy 354.638991 -165.934088) (xy 354.593633 -165.901637) (xy 354.553484 -165.862928)
			(xy 354.519398 -165.818785) (xy 354.492102 -165.77015) (xy 354.472179 -165.718059) (xy 354.460053 -165.663622)
			(xy 354.455982 -165.608) (xy 353.012756 -165.608) (xy 353.012756 -166.624) (xy 354.455982 -166.624)
			(xy 354.460053 -166.568378) (xy 354.472179 -166.513941) (xy 354.492102 -166.46185) (xy 354.519398 -166.413215)
			(xy 354.553484 -166.369072) (xy 354.593633 -166.330363) (xy 354.638991 -166.297912) (xy 354.688591 -166.272411)
			(xy 354.741375 -166.254404) (xy 354.796218 -166.244274) (xy 354.851952 -166.242237) (xy 354.907389 -166.248337)
			(xy 354.961346 -166.262443) (xy 355.012675 -166.284255) (xy 355.060281 -166.313309) (xy 355.103149 -166.348984)
			(xy 355.140366 -166.390521) (xy 355.171139 -166.437034) (xy 355.194811 -166.487531) (xy 355.210879 -166.540938)
			(xy 355.215889 -166.574978) (xy 370.832378 -166.574978) (xy 370.836449 -166.519356) (xy 370.848575 -166.464919)
			(xy 370.868498 -166.412828) (xy 370.895794 -166.364193) (xy 370.92988 -166.32005) (xy 370.970029 -166.281341)
			(xy 371.015387 -166.24889) (xy 371.064987 -166.223389) (xy 371.117771 -166.205382) (xy 371.172614 -166.195252)
			(xy 371.228348 -166.193215) (xy 371.283785 -166.199315) (xy 371.337742 -166.213421) (xy 371.389071 -166.235233)
			(xy 371.436677 -166.264287) (xy 371.479545 -166.299962) (xy 371.516762 -166.341499) (xy 371.547535 -166.388012)
			(xy 371.571207 -166.438509) (xy 371.587275 -166.491916) (xy 371.595395 -166.547092) (xy 371.595904 -166.574978)
			(xy 371.595395 -166.602864) (xy 371.587275 -166.65804) (xy 371.571207 -166.711447) (xy 371.547535 -166.761944)
			(xy 371.516762 -166.808457) (xy 371.479545 -166.849994) (xy 371.436677 -166.885669) (xy 371.389071 -166.914723)
			(xy 371.337742 -166.936535) (xy 371.283785 -166.950641) (xy 371.228348 -166.956741) (xy 371.172614 -166.954704)
			(xy 371.117771 -166.944574) (xy 371.064987 -166.926567) (xy 371.015387 -166.901066) (xy 370.970029 -166.868615)
			(xy 370.92988 -166.829906) (xy 370.895794 -166.785763) (xy 370.868498 -166.737128) (xy 370.848575 -166.685037)
			(xy 370.836449 -166.6306) (xy 370.832378 -166.574978) (xy 355.215889 -166.574978) (xy 355.218999 -166.596114)
			(xy 355.219508 -166.624) (xy 355.218999 -166.651886) (xy 355.210879 -166.707062) (xy 355.194811 -166.760469)
			(xy 355.171139 -166.810966) (xy 355.140366 -166.857479) (xy 355.103149 -166.899016) (xy 355.060281 -166.934691)
			(xy 355.012675 -166.963745) (xy 354.961346 -166.985557) (xy 354.907389 -166.999663) (xy 354.851952 -167.005763)
			(xy 354.796218 -167.003726) (xy 354.741375 -166.993596) (xy 354.688591 -166.975589) (xy 354.638991 -166.950088)
			(xy 354.593633 -166.917637) (xy 354.553484 -166.878928) (xy 354.519398 -166.834785) (xy 354.492102 -166.78615)
			(xy 354.472179 -166.734059) (xy 354.460053 -166.679622) (xy 354.455982 -166.624) (xy 353.012756 -166.624)
			(xy 353.012756 -167.64) (xy 354.455982 -167.64) (xy 354.460053 -167.584378) (xy 354.472179 -167.529941)
			(xy 354.492102 -167.47785) (xy 354.519398 -167.429215) (xy 354.553484 -167.385072) (xy 354.593633 -167.346363)
			(xy 354.638991 -167.313912) (xy 354.688591 -167.288411) (xy 354.741375 -167.270404) (xy 354.796218 -167.260274)
			(xy 354.851952 -167.258237) (xy 354.907389 -167.264337) (xy 354.961346 -167.278443) (xy 355.012675 -167.300255)
			(xy 355.060281 -167.329309) (xy 355.103149 -167.364984) (xy 355.140366 -167.406521) (xy 355.171139 -167.453034)
			(xy 355.194811 -167.503531) (xy 355.210879 -167.556938) (xy 355.218999 -167.612114) (xy 355.219508 -167.64)
			(xy 356.487982 -167.64) (xy 356.492053 -167.584378) (xy 356.504179 -167.529941) (xy 356.524102 -167.47785)
			(xy 356.551398 -167.429215) (xy 356.585484 -167.385072) (xy 356.625633 -167.346363) (xy 356.670991 -167.313912)
			(xy 356.720591 -167.288411) (xy 356.773375 -167.270404) (xy 356.828218 -167.260274) (xy 356.883952 -167.258237)
			(xy 356.939389 -167.264337) (xy 356.993346 -167.278443) (xy 357.044675 -167.300255) (xy 357.092281 -167.329309)
			(xy 357.135149 -167.364984) (xy 357.172366 -167.406521) (xy 357.203139 -167.453034) (xy 357.226811 -167.503531)
			(xy 357.242879 -167.556938) (xy 357.250999 -167.612114) (xy 357.251508 -167.64) (xy 357.250999 -167.667886)
			(xy 357.242879 -167.723062) (xy 357.226811 -167.776469) (xy 357.203139 -167.826966) (xy 357.172366 -167.873479)
			(xy 357.135149 -167.915016) (xy 357.092281 -167.950691) (xy 357.044675 -167.979745) (xy 356.993346 -168.001557)
			(xy 356.939389 -168.015663) (xy 356.883952 -168.021763) (xy 356.828218 -168.019726) (xy 356.773375 -168.009596)
			(xy 356.720591 -167.991589) (xy 356.670991 -167.966088) (xy 356.625633 -167.933637) (xy 356.585484 -167.894928)
			(xy 356.551398 -167.850785) (xy 356.524102 -167.80215) (xy 356.504179 -167.750059) (xy 356.492053 -167.695622)
			(xy 356.487982 -167.64) (xy 355.219508 -167.64) (xy 355.218999 -167.667886) (xy 355.210879 -167.723062)
			(xy 355.194811 -167.776469) (xy 355.171139 -167.826966) (xy 355.140366 -167.873479) (xy 355.103149 -167.915016)
			(xy 355.060281 -167.950691) (xy 355.012675 -167.979745) (xy 354.961346 -168.001557) (xy 354.907389 -168.015663)
			(xy 354.851952 -168.021763) (xy 354.796218 -168.019726) (xy 354.741375 -168.009596) (xy 354.688591 -167.991589)
			(xy 354.638991 -167.966088) (xy 354.593633 -167.933637) (xy 354.553484 -167.894928) (xy 354.519398 -167.850785)
			(xy 354.492102 -167.80215) (xy 354.472179 -167.750059) (xy 354.460053 -167.695622) (xy 354.455982 -167.64)
			(xy 353.012756 -167.64) (xy 353.012756 -168.709594) (xy 353.013772 -168.719246) (xy 353.015401 -168.726489)
			(xy 353.022245 -168.739656) (xy 353.027234 -168.745154) (xy 354.775516 -170.493436) (xy 354.782366 -170.500832)
			(xy 354.790101 -170.519431) (xy 354.790502 -170.529504) (xy 354.790502 -171.45) (xy 356.360982 -171.45)
			(xy 356.365053 -171.394378) (xy 356.377179 -171.339941) (xy 356.397102 -171.28785) (xy 356.424398 -171.239215)
			(xy 356.458484 -171.195072) (xy 356.498633 -171.156363) (xy 356.543991 -171.123912) (xy 356.593591 -171.098411)
			(xy 356.646375 -171.080404) (xy 356.701218 -171.070274) (xy 356.756952 -171.068237) (xy 356.812389 -171.074337)
			(xy 356.866346 -171.088443) (xy 356.917675 -171.110255) (xy 356.965281 -171.139309) (xy 357.008149 -171.174984)
			(xy 357.045366 -171.216521) (xy 357.076139 -171.263034) (xy 357.099811 -171.313531) (xy 357.115879 -171.366938)
			(xy 357.123999 -171.422114) (xy 357.124508 -171.45) (xy 357.123999 -171.477886) (xy 357.115879 -171.533062)
			(xy 357.099811 -171.586469) (xy 357.076139 -171.636966) (xy 357.045366 -171.683479) (xy 357.008149 -171.725016)
			(xy 356.965281 -171.760691) (xy 356.917675 -171.789745) (xy 356.866346 -171.811557) (xy 356.812389 -171.825663)
			(xy 356.756952 -171.831763) (xy 356.701218 -171.829726) (xy 356.646375 -171.819596) (xy 356.593591 -171.801589)
			(xy 356.543991 -171.776088) (xy 356.498633 -171.743637) (xy 356.458484 -171.704928) (xy 356.424398 -171.660785)
			(xy 356.397102 -171.61215) (xy 356.377179 -171.560059) (xy 356.365053 -171.505622) (xy 356.360982 -171.45)
			(xy 354.790502 -171.45) (xy 354.790502 -172.974) (xy 357.757982 -172.974) (xy 357.762053 -172.918378)
			(xy 357.774179 -172.863941) (xy 357.794102 -172.81185) (xy 357.821398 -172.763215) (xy 357.855484 -172.719072)
			(xy 357.895633 -172.680363) (xy 357.940991 -172.647912) (xy 357.990591 -172.622411) (xy 358.043375 -172.604404)
			(xy 358.098218 -172.594274) (xy 358.153952 -172.592237) (xy 358.209389 -172.598337) (xy 358.263346 -172.612443)
			(xy 358.314675 -172.634255) (xy 358.362281 -172.663309) (xy 358.405149 -172.698984) (xy 358.442366 -172.740521)
			(xy 358.473139 -172.787034) (xy 358.496811 -172.837531) (xy 358.512879 -172.890938) (xy 358.520999 -172.946114)
			(xy 358.521508 -172.974) (xy 358.520999 -173.001886) (xy 358.512879 -173.057062) (xy 358.496811 -173.110469)
			(xy 358.473139 -173.160966) (xy 358.442366 -173.207479) (xy 358.405149 -173.249016) (xy 358.362281 -173.284691)
			(xy 358.314675 -173.313745) (xy 358.263346 -173.335557) (xy 358.209389 -173.349663) (xy 358.153952 -173.355763)
			(xy 358.098218 -173.353726) (xy 358.043375 -173.343596) (xy 357.990591 -173.325589) (xy 357.940991 -173.300088)
			(xy 357.895633 -173.267637) (xy 357.855484 -173.228928) (xy 357.821398 -173.184785) (xy 357.794102 -173.13615)
			(xy 357.774179 -173.084059) (xy 357.762053 -173.029622) (xy 357.757982 -172.974) (xy 354.790502 -172.974)
			(xy 354.790502 -173.99) (xy 357.757982 -173.99) (xy 357.762053 -173.934378) (xy 357.774179 -173.879941)
			(xy 357.794102 -173.82785) (xy 357.821398 -173.779215) (xy 357.855484 -173.735072) (xy 357.895633 -173.696363)
			(xy 357.940991 -173.663912) (xy 357.990591 -173.638411) (xy 358.043375 -173.620404) (xy 358.098218 -173.610274)
			(xy 358.153952 -173.608237) (xy 358.209389 -173.614337) (xy 358.263346 -173.628443) (xy 358.314675 -173.650255)
			(xy 358.362281 -173.679309) (xy 358.405149 -173.714984) (xy 358.442366 -173.756521) (xy 358.473139 -173.803034)
			(xy 358.496811 -173.853531) (xy 358.512879 -173.906938) (xy 358.520999 -173.962114) (xy 358.521508 -173.99)
			(xy 358.520999 -174.017886) (xy 358.512879 -174.073062) (xy 358.496811 -174.126469) (xy 358.473139 -174.176966)
			(xy 358.442366 -174.223479) (xy 358.405149 -174.265016) (xy 358.362281 -174.300691) (xy 358.314675 -174.329745)
			(xy 358.263346 -174.351557) (xy 358.209389 -174.365663) (xy 358.153952 -174.371763) (xy 358.098218 -174.369726)
			(xy 358.043375 -174.359596) (xy 357.990591 -174.341589) (xy 357.940991 -174.316088) (xy 357.895633 -174.283637)
			(xy 357.855484 -174.244928) (xy 357.821398 -174.200785) (xy 357.794102 -174.15215) (xy 357.774179 -174.100059)
			(xy 357.762053 -174.045622) (xy 357.757982 -173.99) (xy 354.790502 -173.99) (xy 354.790502 -177.038)
			(xy 357.757982 -177.038) (xy 357.762053 -176.982378) (xy 357.774179 -176.927941) (xy 357.794102 -176.87585)
			(xy 357.821398 -176.827215) (xy 357.855484 -176.783072) (xy 357.895633 -176.744363) (xy 357.940991 -176.711912)
			(xy 357.990591 -176.686411) (xy 358.043375 -176.668404) (xy 358.098218 -176.658274) (xy 358.153952 -176.656237)
			(xy 358.209389 -176.662337) (xy 358.263346 -176.676443) (xy 358.314675 -176.698255) (xy 358.362281 -176.727309)
			(xy 358.405149 -176.762984) (xy 358.442366 -176.804521) (xy 358.473139 -176.851034) (xy 358.496811 -176.901531)
			(xy 358.512879 -176.954938) (xy 358.520999 -177.010114) (xy 358.521508 -177.038) (xy 358.520999 -177.065886)
			(xy 358.512879 -177.121062) (xy 358.496811 -177.174469) (xy 358.473139 -177.224966) (xy 358.442366 -177.271479)
			(xy 358.405149 -177.313016) (xy 358.362281 -177.348691) (xy 358.314675 -177.377745) (xy 358.263346 -177.399557)
			(xy 358.209389 -177.413663) (xy 358.153952 -177.419763) (xy 358.098218 -177.417726) (xy 358.043375 -177.407596)
			(xy 357.990591 -177.389589) (xy 357.940991 -177.364088) (xy 357.895633 -177.331637) (xy 357.855484 -177.292928)
			(xy 357.821398 -177.248785) (xy 357.794102 -177.20015) (xy 357.774179 -177.148059) (xy 357.762053 -177.093622)
			(xy 357.757982 -177.038) (xy 354.790502 -177.038) (xy 354.790502 -177.092864) (xy 354.790908 -177.10227)
			(xy 354.797818 -177.119769) (xy 354.803964 -177.1269) (xy 354.819966 -177.143156) (xy 354.82331 -177.146435)
			(xy 354.830978 -177.15181) (xy 354.835206 -177.153824) (xy 354.85959 -177.165) (xy 354.859844 -177.165)
			(xy 354.863146 -177.165254) (xy 354.86848 -177.165508) (xy 354.895466 -177.168147) (xy 354.948358 -177.180081)
			(xy 354.999029 -177.19938) (xy 355.046458 -177.225655) (xy 355.089693 -177.258378) (xy 355.127861 -177.296889)
			(xy 355.160196 -177.340415) (xy 355.186046 -177.388077) (xy 355.204891 -177.438919) (xy 355.216352 -177.491915)
			(xy 355.220198 -177.546) (xy 355.216352 -177.600085) (xy 355.204891 -177.653081) (xy 355.186046 -177.703923)
			(xy 355.160196 -177.751585) (xy 355.127861 -177.795111) (xy 355.089693 -177.833622) (xy 355.046458 -177.866345)
			(xy 354.999029 -177.89262) (xy 354.948358 -177.911919) (xy 354.895466 -177.923853) (xy 354.86848 -177.926492)
			(xy 354.863146 -177.926746) (xy 354.859844 -177.927) (xy 354.85959 -177.927) (xy 354.835206 -177.938176)
			(xy 354.830991 -177.940214) (xy 354.82332 -177.945579) (xy 354.819966 -177.948844) (xy 354.803964 -177.9651)
			(xy 354.797942 -177.972307) (xy 354.791048 -177.98976) (xy 354.790502 -177.999136) (xy 354.790502 -178.054)
			(xy 357.757982 -178.054) (xy 357.762053 -177.998378) (xy 357.774179 -177.943941) (xy 357.794102 -177.89185)
			(xy 357.821398 -177.843215) (xy 357.855484 -177.799072) (xy 357.895633 -177.760363) (xy 357.940991 -177.727912)
			(xy 357.990591 -177.702411) (xy 358.043375 -177.684404) (xy 358.098218 -177.674274) (xy 358.153952 -177.672237)
			(xy 358.209389 -177.678337) (xy 358.263346 -177.692443) (xy 358.314675 -177.714255) (xy 358.362281 -177.743309)
			(xy 358.405149 -177.778984) (xy 358.442366 -177.820521) (xy 358.473139 -177.867034) (xy 358.496811 -177.917531)
			(xy 358.512879 -177.970938) (xy 358.520999 -178.026114) (xy 358.521508 -178.054) (xy 358.520999 -178.081886)
			(xy 358.512879 -178.137062) (xy 358.496811 -178.190469) (xy 358.473139 -178.240966) (xy 358.442366 -178.287479)
			(xy 358.405149 -178.329016) (xy 358.362281 -178.364691) (xy 358.314675 -178.393745) (xy 358.263346 -178.415557)
			(xy 358.209389 -178.429663) (xy 358.153952 -178.435763) (xy 358.098218 -178.433726) (xy 358.043375 -178.423596)
			(xy 357.990591 -178.405589) (xy 357.940991 -178.380088) (xy 357.895633 -178.347637) (xy 357.855484 -178.308928)
			(xy 357.821398 -178.264785) (xy 357.794102 -178.21615) (xy 357.774179 -178.164059) (xy 357.762053 -178.109622)
			(xy 357.757982 -178.054) (xy 354.790502 -178.054) (xy 354.790502 -178.108864) (xy 354.790908 -178.11827)
			(xy 354.797818 -178.135769) (xy 354.803964 -178.1429) (xy 354.819966 -178.159156) (xy 354.82331 -178.162435)
			(xy 354.830978 -178.16781) (xy 354.835206 -178.169824) (xy 354.85959 -178.181) (xy 354.859844 -178.181)
			(xy 354.863146 -178.181254) (xy 354.86848 -178.181508) (xy 354.895466 -178.184147) (xy 354.948358 -178.196081)
			(xy 354.999029 -178.21538) (xy 355.046458 -178.241655) (xy 355.089693 -178.274378) (xy 355.127861 -178.312889)
			(xy 355.160196 -178.356415) (xy 355.186046 -178.404077) (xy 355.204891 -178.454919) (xy 355.216352 -178.507915)
			(xy 355.220198 -178.562) (xy 356.487982 -178.562) (xy 356.492053 -178.506378) (xy 356.504179 -178.451941)
			(xy 356.524102 -178.39985) (xy 356.551398 -178.351215) (xy 356.585484 -178.307072) (xy 356.625633 -178.268363)
			(xy 356.670991 -178.235912) (xy 356.720591 -178.210411) (xy 356.773375 -178.192404) (xy 356.828218 -178.182274)
			(xy 356.883952 -178.180237) (xy 356.939389 -178.186337) (xy 356.993346 -178.200443) (xy 357.044675 -178.222255)
			(xy 357.092281 -178.251309) (xy 357.135149 -178.286984) (xy 357.172366 -178.328521) (xy 357.203139 -178.375034)
			(xy 357.226811 -178.425531) (xy 357.242879 -178.478938) (xy 357.250999 -178.534114) (xy 357.251508 -178.562)
			(xy 357.250999 -178.589886) (xy 357.242879 -178.645062) (xy 357.226811 -178.698469) (xy 357.203139 -178.748966)
			(xy 357.172366 -178.795479) (xy 357.135149 -178.837016) (xy 357.092281 -178.872691) (xy 357.044675 -178.901745)
			(xy 356.993346 -178.923557) (xy 356.939389 -178.937663) (xy 356.883952 -178.943763) (xy 356.828218 -178.941726)
			(xy 356.773375 -178.931596) (xy 356.720591 -178.913589) (xy 356.670991 -178.888088) (xy 356.625633 -178.855637)
			(xy 356.585484 -178.816928) (xy 356.551398 -178.772785) (xy 356.524102 -178.72415) (xy 356.504179 -178.672059)
			(xy 356.492053 -178.617622) (xy 356.487982 -178.562) (xy 355.220198 -178.562) (xy 355.216352 -178.616085)
			(xy 355.204891 -178.669081) (xy 355.186046 -178.719923) (xy 355.160196 -178.767585) (xy 355.127861 -178.811111)
			(xy 355.089693 -178.849622) (xy 355.046458 -178.882345) (xy 354.999029 -178.90862) (xy 354.948358 -178.927919)
			(xy 354.895466 -178.939853) (xy 354.86848 -178.942492) (xy 354.863146 -178.942746) (xy 354.859844 -178.943)
			(xy 354.85959 -178.943) (xy 354.835206 -178.954176) (xy 354.830991 -178.956214) (xy 354.82332 -178.961579)
			(xy 354.819966 -178.964844) (xy 354.803964 -178.9811) (xy 354.797942 -178.988307) (xy 354.791048 -179.00576)
			(xy 354.790502 -179.015136) (xy 354.790502 -179.124864) (xy 354.790908 -179.13427) (xy 354.797818 -179.151769)
			(xy 354.803964 -179.1589) (xy 354.819966 -179.175156) (xy 354.82331 -179.178435) (xy 354.830978 -179.18381)
			(xy 354.835206 -179.185824) (xy 354.85959 -179.197) (xy 354.859844 -179.197) (xy 354.863146 -179.197254)
			(xy 354.86848 -179.197508) (xy 354.895466 -179.200147) (xy 354.948358 -179.212081) (xy 354.999029 -179.23138)
			(xy 355.046458 -179.257655) (xy 355.089693 -179.290378) (xy 355.127861 -179.328889) (xy 355.160196 -179.372415)
			(xy 355.186046 -179.420077) (xy 355.204891 -179.470919) (xy 355.216352 -179.523915) (xy 355.220198 -179.578)
			(xy 356.487982 -179.578) (xy 356.492053 -179.522378) (xy 356.504179 -179.467941) (xy 356.524102 -179.41585)
			(xy 356.551398 -179.367215) (xy 356.585484 -179.323072) (xy 356.625633 -179.284363) (xy 356.670991 -179.251912)
			(xy 356.720591 -179.226411) (xy 356.773375 -179.208404) (xy 356.828218 -179.198274) (xy 356.883952 -179.196237)
			(xy 356.939389 -179.202337) (xy 356.993346 -179.216443) (xy 357.044675 -179.238255) (xy 357.092281 -179.267309)
			(xy 357.135149 -179.302984) (xy 357.172366 -179.344521) (xy 357.203139 -179.391034) (xy 357.226811 -179.441531)
			(xy 357.242879 -179.494938) (xy 357.250999 -179.550114) (xy 357.251508 -179.578) (xy 357.250999 -179.605886)
			(xy 357.242879 -179.661062) (xy 357.226811 -179.714469) (xy 357.203139 -179.764966) (xy 357.172366 -179.811479)
			(xy 357.135149 -179.853016) (xy 357.092281 -179.888691) (xy 357.044675 -179.917745) (xy 356.993346 -179.939557)
			(xy 356.939389 -179.953663) (xy 356.883952 -179.959763) (xy 356.828218 -179.957726) (xy 356.773375 -179.947596)
			(xy 356.720591 -179.929589) (xy 356.670991 -179.904088) (xy 356.625633 -179.871637) (xy 356.585484 -179.832928)
			(xy 356.551398 -179.788785) (xy 356.524102 -179.74015) (xy 356.504179 -179.688059) (xy 356.492053 -179.633622)
			(xy 356.487982 -179.578) (xy 355.220198 -179.578) (xy 355.216352 -179.632085) (xy 355.204891 -179.685081)
			(xy 355.186046 -179.735923) (xy 355.160196 -179.783585) (xy 355.127861 -179.827111) (xy 355.089693 -179.865622)
			(xy 355.046458 -179.898345) (xy 354.999029 -179.92462) (xy 354.948358 -179.943919) (xy 354.895466 -179.955853)
			(xy 354.86848 -179.958492) (xy 354.863146 -179.958746) (xy 354.859844 -179.959) (xy 354.85959 -179.959)
			(xy 354.835206 -179.970176) (xy 354.830991 -179.972214) (xy 354.82332 -179.977579) (xy 354.819966 -179.980844)
			(xy 354.803964 -179.9971) (xy 354.797942 -180.004307) (xy 354.791048 -180.02176) (xy 354.790502 -180.031136)
			(xy 354.790502 -180.086) (xy 357.757982 -180.086) (xy 357.762053 -180.030378) (xy 357.774179 -179.975941)
			(xy 357.794102 -179.92385) (xy 357.821398 -179.875215) (xy 357.855484 -179.831072) (xy 357.895633 -179.792363)
			(xy 357.940991 -179.759912) (xy 357.990591 -179.734411) (xy 358.043375 -179.716404) (xy 358.098218 -179.706274)
			(xy 358.153952 -179.704237) (xy 358.209389 -179.710337) (xy 358.263346 -179.724443) (xy 358.314675 -179.746255)
			(xy 358.362281 -179.775309) (xy 358.405149 -179.810984) (xy 358.442366 -179.852521) (xy 358.473139 -179.899034)
			(xy 358.496811 -179.949531) (xy 358.512879 -180.002938) (xy 358.520999 -180.058114) (xy 358.521508 -180.086)
			(xy 358.520999 -180.113886) (xy 358.512879 -180.169062) (xy 358.496811 -180.222469) (xy 358.473139 -180.272966)
			(xy 358.442366 -180.319479) (xy 358.405149 -180.361016) (xy 358.362281 -180.396691) (xy 358.314675 -180.425745)
			(xy 358.263346 -180.447557) (xy 358.209389 -180.461663) (xy 358.153952 -180.467763) (xy 358.098218 -180.465726)
			(xy 358.043375 -180.455596) (xy 357.990591 -180.437589) (xy 357.940991 -180.412088) (xy 357.895633 -180.379637)
			(xy 357.855484 -180.340928) (xy 357.821398 -180.296785) (xy 357.794102 -180.24815) (xy 357.774179 -180.196059)
			(xy 357.762053 -180.141622) (xy 357.757982 -180.086) (xy 354.790502 -180.086) (xy 354.790502 -181.102)
			(xy 357.757982 -181.102) (xy 357.762053 -181.046378) (xy 357.774179 -180.991941) (xy 357.794102 -180.93985)
			(xy 357.821398 -180.891215) (xy 357.855484 -180.847072) (xy 357.895633 -180.808363) (xy 357.940991 -180.775912)
			(xy 357.990591 -180.750411) (xy 358.043375 -180.732404) (xy 358.098218 -180.722274) (xy 358.153952 -180.720237)
			(xy 358.209389 -180.726337) (xy 358.263346 -180.740443) (xy 358.314675 -180.762255) (xy 358.362281 -180.791309)
			(xy 358.405149 -180.826984) (xy 358.442366 -180.868521) (xy 358.473139 -180.915034) (xy 358.496811 -180.965531)
			(xy 358.512879 -181.018938) (xy 358.520999 -181.074114) (xy 358.521508 -181.102) (xy 358.520999 -181.129886)
			(xy 358.512879 -181.185062) (xy 358.496811 -181.238469) (xy 358.473139 -181.288966) (xy 358.442366 -181.335479)
			(xy 358.405149 -181.377016) (xy 358.362281 -181.412691) (xy 358.314675 -181.441745) (xy 358.263346 -181.463557)
			(xy 358.209389 -181.477663) (xy 358.153952 -181.483763) (xy 358.098218 -181.481726) (xy 358.043375 -181.471596)
			(xy 357.990591 -181.453589) (xy 357.940991 -181.428088) (xy 357.895633 -181.395637) (xy 357.855484 -181.356928)
			(xy 357.821398 -181.312785) (xy 357.794102 -181.26415) (xy 357.774179 -181.212059) (xy 357.762053 -181.157622)
			(xy 357.757982 -181.102) (xy 354.790502 -181.102) (xy 354.790502 -182.118) (xy 357.757982 -182.118)
			(xy 357.762053 -182.062378) (xy 357.774179 -182.007941) (xy 357.794102 -181.95585) (xy 357.821398 -181.907215)
			(xy 357.855484 -181.863072) (xy 357.895633 -181.824363) (xy 357.940991 -181.791912) (xy 357.990591 -181.766411)
			(xy 358.043375 -181.748404) (xy 358.098218 -181.738274) (xy 358.153952 -181.736237) (xy 358.209389 -181.742337)
			(xy 358.263346 -181.756443) (xy 358.314675 -181.778255) (xy 358.362281 -181.807309) (xy 358.405149 -181.842984)
			(xy 358.442366 -181.884521) (xy 358.473139 -181.931034) (xy 358.496811 -181.981531) (xy 358.512879 -182.034938)
			(xy 358.520999 -182.090114) (xy 358.521508 -182.118) (xy 358.520999 -182.145886) (xy 358.512879 -182.201062)
			(xy 358.496811 -182.254469) (xy 358.473139 -182.304966) (xy 358.442366 -182.351479) (xy 358.405149 -182.393016)
			(xy 358.362281 -182.428691) (xy 358.314675 -182.457745) (xy 358.263346 -182.479557) (xy 358.209389 -182.493663)
			(xy 358.153952 -182.499763) (xy 358.098218 -182.497726) (xy 358.043375 -182.487596) (xy 357.990591 -182.469589)
			(xy 357.940991 -182.444088) (xy 357.895633 -182.411637) (xy 357.855484 -182.372928) (xy 357.821398 -182.328785)
			(xy 357.794102 -182.28015) (xy 357.774179 -182.228059) (xy 357.762053 -182.173622) (xy 357.757982 -182.118)
			(xy 354.790502 -182.118) (xy 354.790502 -183.388) (xy 356.360982 -183.388) (xy 356.365053 -183.332378)
			(xy 356.377179 -183.277941) (xy 356.397102 -183.22585) (xy 356.424398 -183.177215) (xy 356.458484 -183.133072)
			(xy 356.498633 -183.094363) (xy 356.543991 -183.061912) (xy 356.593591 -183.036411) (xy 356.646375 -183.018404)
			(xy 356.701218 -183.008274) (xy 356.756952 -183.006237) (xy 356.812389 -183.012337) (xy 356.866346 -183.026443)
			(xy 356.917675 -183.048255) (xy 356.965281 -183.077309) (xy 357.008149 -183.112984) (xy 357.045366 -183.154521)
			(xy 357.076139 -183.201034) (xy 357.099811 -183.251531) (xy 357.115879 -183.304938) (xy 357.123999 -183.360114)
			(xy 357.124508 -183.388) (xy 357.123999 -183.415886) (xy 357.115879 -183.471062) (xy 357.099811 -183.524469)
			(xy 357.076139 -183.574966) (xy 357.045366 -183.621479) (xy 357.008149 -183.663016) (xy 356.965281 -183.698691)
			(xy 356.917675 -183.727745) (xy 356.866346 -183.749557) (xy 356.812389 -183.763663) (xy 356.756952 -183.769763)
			(xy 356.701218 -183.767726) (xy 356.646375 -183.757596) (xy 356.593591 -183.739589) (xy 356.543991 -183.714088)
			(xy 356.498633 -183.681637) (xy 356.458484 -183.642928) (xy 356.424398 -183.598785) (xy 356.397102 -183.55015)
			(xy 356.377179 -183.498059) (xy 356.365053 -183.443622) (xy 356.360982 -183.388) (xy 354.790502 -183.388)
			(xy 354.790502 -184.15) (xy 357.757982 -184.15) (xy 357.762053 -184.094378) (xy 357.774179 -184.039941)
			(xy 357.794102 -183.98785) (xy 357.821398 -183.939215) (xy 357.855484 -183.895072) (xy 357.895633 -183.856363)
			(xy 357.940991 -183.823912) (xy 357.990591 -183.798411) (xy 358.043375 -183.780404) (xy 358.098218 -183.770274)
			(xy 358.153952 -183.768237) (xy 358.209389 -183.774337) (xy 358.263346 -183.788443) (xy 358.314675 -183.810255)
			(xy 358.362281 -183.839309) (xy 358.405149 -183.874984) (xy 358.442366 -183.916521) (xy 358.473139 -183.963034)
			(xy 358.496811 -184.013531) (xy 358.512879 -184.066938) (xy 358.520999 -184.122114) (xy 358.521508 -184.15)
			(xy 358.520999 -184.177886) (xy 358.512879 -184.233062) (xy 358.496811 -184.286469) (xy 358.473139 -184.336966)
			(xy 358.442366 -184.383479) (xy 358.405149 -184.425016) (xy 358.362281 -184.460691) (xy 358.314675 -184.489745)
			(xy 358.263346 -184.511557) (xy 358.209389 -184.525663) (xy 358.153952 -184.531763) (xy 358.098218 -184.529726)
			(xy 358.043375 -184.519596) (xy 357.990591 -184.501589) (xy 357.940991 -184.476088) (xy 357.895633 -184.443637)
			(xy 357.855484 -184.404928) (xy 357.821398 -184.360785) (xy 357.794102 -184.31215) (xy 357.774179 -184.260059)
			(xy 357.762053 -184.205622) (xy 357.757982 -184.15) (xy 354.790502 -184.15) (xy 354.790502 -185.166)
			(xy 357.757982 -185.166) (xy 357.762053 -185.110378) (xy 357.774179 -185.055941) (xy 357.794102 -185.00385)
			(xy 357.821398 -184.955215) (xy 357.855484 -184.911072) (xy 357.895633 -184.872363) (xy 357.940991 -184.839912)
			(xy 357.990591 -184.814411) (xy 358.043375 -184.796404) (xy 358.098218 -184.786274) (xy 358.153952 -184.784237)
			(xy 358.209389 -184.790337) (xy 358.263346 -184.804443) (xy 358.314675 -184.826255) (xy 358.362281 -184.855309)
			(xy 358.405149 -184.890984) (xy 358.442366 -184.932521) (xy 358.473139 -184.979034) (xy 358.496811 -185.029531)
			(xy 358.512879 -185.082938) (xy 358.520999 -185.138114) (xy 358.521508 -185.166) (xy 358.520999 -185.193886)
			(xy 358.512879 -185.249062) (xy 358.496811 -185.302469) (xy 358.473139 -185.352966) (xy 358.442366 -185.399479)
			(xy 358.405149 -185.441016) (xy 358.362281 -185.476691) (xy 358.314675 -185.505745) (xy 358.263346 -185.527557)
			(xy 358.209389 -185.541663) (xy 358.153952 -185.547763) (xy 358.098218 -185.545726) (xy 358.043375 -185.535596)
			(xy 357.990591 -185.517589) (xy 357.940991 -185.492088) (xy 357.895633 -185.459637) (xy 357.855484 -185.420928)
			(xy 357.821398 -185.376785) (xy 357.794102 -185.32815) (xy 357.774179 -185.276059) (xy 357.762053 -185.221622)
			(xy 357.757982 -185.166) (xy 354.790502 -185.166) (xy 354.790502 -186.137296) (xy 354.791518 -186.146948)
			(xy 354.793145 -186.154193) (xy 354.799984 -186.167364) (xy 354.80498 -186.172856) (xy 355.540056 -186.907932)
			(xy 356.297228 -186.907932) (xy 356.301299 -186.85231) (xy 356.313425 -186.797873) (xy 356.333348 -186.745782)
			(xy 356.360644 -186.697147) (xy 356.39473 -186.653004) (xy 356.434879 -186.614295) (xy 356.480237 -186.581844)
			(xy 356.529837 -186.556343) (xy 356.582621 -186.538336) (xy 356.637464 -186.528206) (xy 356.693198 -186.526169)
			(xy 356.748635 -186.532269) (xy 356.802592 -186.546375) (xy 356.853921 -186.568187) (xy 356.901527 -186.597241)
			(xy 356.944395 -186.632916) (xy 356.981612 -186.674453) (xy 357.012385 -186.720966) (xy 357.036057 -186.771463)
			(xy 357.052125 -186.82487) (xy 357.060245 -186.880046) (xy 357.060754 -186.907932) (xy 357.060245 -186.935818)
			(xy 357.052125 -186.990994) (xy 357.036057 -187.044401) (xy 357.012385 -187.094898) (xy 356.981612 -187.141411)
			(xy 356.944395 -187.182948) (xy 356.901527 -187.218623) (xy 356.853921 -187.247677) (xy 356.802592 -187.269489)
			(xy 356.748635 -187.283595) (xy 356.693198 -187.289695) (xy 356.637464 -187.287658) (xy 356.582621 -187.277528)
			(xy 356.529837 -187.259521) (xy 356.480237 -187.23402) (xy 356.434879 -187.201569) (xy 356.39473 -187.16286)
			(xy 356.360644 -187.118717) (xy 356.333348 -187.070082) (xy 356.313425 -187.017991) (xy 356.301299 -186.963554)
			(xy 356.297228 -186.907932) (xy 355.540056 -186.907932) (xy 356.846124 -188.214) (xy 357.757982 -188.214)
			(xy 357.762053 -188.158378) (xy 357.774179 -188.103941) (xy 357.794102 -188.05185) (xy 357.821398 -188.003215)
			(xy 357.855484 -187.959072) (xy 357.895633 -187.920363) (xy 357.940991 -187.887912) (xy 357.990591 -187.862411)
			(xy 358.043375 -187.844404) (xy 358.098218 -187.834274) (xy 358.153952 -187.832237) (xy 358.209389 -187.838337)
			(xy 358.263346 -187.852443) (xy 358.314675 -187.874255) (xy 358.362281 -187.903309) (xy 358.405149 -187.938984)
			(xy 358.442366 -187.980521) (xy 358.473139 -188.027034) (xy 358.496811 -188.077531) (xy 358.512879 -188.130938)
			(xy 358.520999 -188.186114) (xy 358.521508 -188.214) (xy 358.520999 -188.241886) (xy 358.512879 -188.297062)
			(xy 358.496811 -188.350469) (xy 358.473139 -188.400966) (xy 358.442366 -188.447479) (xy 358.405149 -188.489016)
			(xy 358.362281 -188.524691) (xy 358.314675 -188.553745) (xy 358.263346 -188.575557) (xy 358.209389 -188.589663)
			(xy 358.153952 -188.595763) (xy 358.098218 -188.593726) (xy 358.043375 -188.583596) (xy 357.990591 -188.565589)
			(xy 357.940991 -188.540088) (xy 357.895633 -188.507637) (xy 357.855484 -188.468928) (xy 357.821398 -188.424785)
			(xy 357.794102 -188.37615) (xy 357.774179 -188.324059) (xy 357.762053 -188.269622) (xy 357.757982 -188.214)
			(xy 356.846124 -188.214) (xy 357.66629 -189.034166) (xy 357.669084 -189.036706) (xy 357.670608 -189.037976)
			(xy 357.678216 -189.0434) (xy 357.696065 -189.048873) (xy 357.705406 -189.048644) (xy 357.784908 -189.04077)
			(xy 357.790611 -189.040102) (xy 357.801513 -189.036508) (xy 357.806498 -189.033658) (xy 357.806752 -189.033658)
			(xy 357.811312 -189.030691) (xy 357.819131 -189.023131) (xy 357.822246 -189.018672) (xy 357.8225 -189.018418)
			(xy 357.837739 -188.996367) (xy 357.873413 -188.956361) (xy 357.914336 -188.921744) (xy 357.959704 -188.893198)
			(xy 358.008621 -188.871285) (xy 358.060124 -188.856437) (xy 358.113199 -188.848946) (xy 358.14 -188.848492)
			(xy 358.167251 -188.848978) (xy 358.221199 -188.856734) (xy 358.273494 -188.872089) (xy 358.323071 -188.894731)
			(xy 358.368921 -188.924197) (xy 358.410112 -188.959888) (xy 358.445803 -189.001079) (xy 358.475269 -189.046929)
			(xy 358.497911 -189.096506) (xy 358.513266 -189.148801) (xy 358.521022 -189.202749) (xy 358.521508 -189.23)
			(xy 358.521054 -189.2568) (xy 358.513554 -189.309873) (xy 358.498701 -189.361373) (xy 358.476787 -189.410289)
			(xy 358.448244 -189.455657) (xy 358.413633 -189.496584) (xy 358.373636 -189.532266) (xy 358.351582 -189.5475)
			(xy 358.351328 -189.5475) (xy 358.351328 -189.547754) (xy 358.346894 -189.550898) (xy 358.339348 -189.558718)
			(xy 358.336342 -189.563248) (xy 358.336342 -189.563502) (xy 358.333525 -189.568501) (xy 358.329931 -189.579397)
			(xy 358.32923 -189.585092) (xy 358.321356 -189.664594) (xy 358.321113 -189.673938) (xy 358.326576 -189.691798)
			(xy 358.332024 -189.699392) (xy 358.333294 -189.700916) (xy 358.335834 -189.70371) (xy 358.518206 -189.886082)
			(xy 358.527055 -189.893988) (xy 358.549569 -189.901394) (xy 358.561386 -189.900306) (xy 359.037382 -189.42431)
			(xy 359.044232 -189.416913) (xy 359.051973 -189.398315) (xy 359.052368 -189.388242) (xy 359.052368 -188.493654)
			(xy 359.052847 -188.460777) (xy 359.060241 -188.39544) (xy 359.074897 -188.331339) (xy 359.096632 -188.269281)
			(xy 359.125173 -188.210043) (xy 359.16016 -188.15437) (xy 359.201156 -188.10296) (xy 359.224072 -188.07938)
			(xy 359.757726 -187.545726) (xy 359.781304 -187.522816) (xy 359.832718 -187.481843) (xy 359.888396 -187.446882)
			(xy 359.947637 -187.418373) (xy 360.009697 -187.396675) (xy 360.073796 -187.38206) (xy 360.139128 -187.374712)
			(xy 360.172 -187.374276) (xy 360.185035 -187.374345) (xy 360.211079 -187.375489) (xy 360.22407 -187.376562)
			(xy 360.245152 -187.37834) (xy 360.253026 -187.372498) (xy 360.307636 -187.321698) (xy 360.314969 -187.314226)
			(xy 360.32336 -187.29507) (xy 360.323892 -187.284614) (xy 360.323892 -186.662568) (xy 360.323638 -186.657234)
			(xy 360.322568 -186.649484) (xy 360.316354 -186.635134) (xy 360.311446 -186.62904) (xy 360.307128 -186.624722)
			(xy 360.25074 -186.574176) (xy 360.246735 -186.570784) (xy 360.237645 -186.56554) (xy 360.232706 -186.563762)
			(xy 360.222546 -186.56046) (xy 360.211878 -186.561476) (xy 360.201937 -186.562443) (xy 360.181988 -186.563461)
			(xy 360.172 -186.563508) (xy 360.144749 -186.563022) (xy 360.090801 -186.555266) (xy 360.038506 -186.539911)
			(xy 359.988929 -186.517269) (xy 359.943079 -186.487803) (xy 359.901888 -186.452112) (xy 359.866197 -186.410921)
			(xy 359.836731 -186.365071) (xy 359.814089 -186.315494) (xy 359.798734 -186.263199) (xy 359.790978 -186.209251)
			(xy 359.790978 -186.154749) (xy 359.798734 -186.100801) (xy 359.814089 -186.048506) (xy 359.836731 -185.998929)
			(xy 359.866197 -185.953079) (xy 359.901888 -185.911888) (xy 359.943079 -185.876197) (xy 359.988929 -185.846731)
			(xy 360.038506 -185.824089) (xy 360.090801 -185.808734) (xy 360.144749 -185.800978) (xy 360.172 -185.800492)
			(xy 360.181988 -185.800544) (xy 360.201937 -185.801559) (xy 360.211878 -185.802524) (xy 360.222546 -185.80354)
			(xy 360.232706 -185.800238) (xy 360.237662 -185.798497) (xy 360.246758 -185.793249) (xy 360.25074 -185.789824)
			(xy 360.307128 -185.739278) (xy 360.311446 -185.73496) (xy 360.316361 -185.72887) (xy 360.322583 -185.714519)
			(xy 360.323638 -185.706766) (xy 360.323892 -185.701432) (xy 360.323892 -185.646568) (xy 360.323638 -185.641234)
			(xy 360.322568 -185.633484) (xy 360.316354 -185.619134) (xy 360.311446 -185.61304) (xy 360.307128 -185.608722)
			(xy 360.25074 -185.558176) (xy 360.246735 -185.554784) (xy 360.237645 -185.54954) (xy 360.232706 -185.547762)
			(xy 360.222546 -185.54446) (xy 360.211878 -185.545476) (xy 360.201937 -185.546443) (xy 360.181988 -185.547461)
			(xy 360.172 -185.547508) (xy 360.144749 -185.547022) (xy 360.090801 -185.539266) (xy 360.038506 -185.523911)
			(xy 359.988929 -185.501269) (xy 359.943079 -185.471803) (xy 359.901888 -185.436112) (xy 359.866197 -185.394921)
			(xy 359.836731 -185.349071) (xy 359.814089 -185.299494) (xy 359.798734 -185.247199) (xy 359.790978 -185.193251)
			(xy 359.790978 -185.138749) (xy 359.798734 -185.084801) (xy 359.814089 -185.032506) (xy 359.836731 -184.982929)
			(xy 359.866197 -184.937079) (xy 359.901888 -184.895888) (xy 359.943079 -184.860197) (xy 359.988929 -184.830731)
			(xy 360.038506 -184.808089) (xy 360.090801 -184.792734) (xy 360.144749 -184.784978) (xy 360.172 -184.784492)
			(xy 360.181988 -184.784544) (xy 360.201937 -184.785559) (xy 360.211878 -184.786524) (xy 360.222546 -184.78754)
			(xy 360.232706 -184.784238) (xy 360.237662 -184.782497) (xy 360.246758 -184.777249) (xy 360.25074 -184.773824)
			(xy 360.307128 -184.723278) (xy 360.311446 -184.71896) (xy 360.316361 -184.71287) (xy 360.322583 -184.698519)
			(xy 360.323638 -184.690766) (xy 360.323892 -184.685432) (xy 360.323892 -184.376568) (xy 360.323638 -184.371234)
			(xy 360.322568 -184.363484) (xy 360.316354 -184.349134) (xy 360.311446 -184.34304) (xy 360.307128 -184.338722)
			(xy 360.25074 -184.288176) (xy 360.246735 -184.284784) (xy 360.237645 -184.27954) (xy 360.232706 -184.277762)
			(xy 360.222546 -184.27446) (xy 360.211878 -184.275476) (xy 360.201937 -184.276443) (xy 360.181988 -184.277461)
			(xy 360.172 -184.277508) (xy 360.144749 -184.277022) (xy 360.090801 -184.269266) (xy 360.038506 -184.253911)
			(xy 359.988929 -184.231269) (xy 359.943079 -184.201803) (xy 359.901888 -184.166112) (xy 359.866197 -184.124921)
			(xy 359.836731 -184.079071) (xy 359.814089 -184.029494) (xy 359.798734 -183.977199) (xy 359.790978 -183.923251)
			(xy 359.790492 -183.896) (xy 359.790917 -183.870218) (xy 359.79786 -183.819125) (xy 359.81162 -183.769432)
			(xy 359.831946 -183.722044) (xy 359.858468 -183.677825) (xy 359.890703 -183.63758) (xy 359.928064 -183.602042)
			(xy 359.948734 -183.586628) (xy 359.953814 -183.583072) (xy 359.961434 -183.574182) (xy 359.964228 -183.568594)
			(xy 359.966786 -183.563032) (xy 359.969479 -183.551093) (xy 359.969562 -183.544972) (xy 359.969054 -183.474106)
			(xy 359.968761 -183.46807) (xy 359.965681 -183.456387) (xy 359.962958 -183.450992) (xy 359.94721 -183.42102)
			(xy 359.944924 -183.419242) (xy 359.923772 -183.403887) (xy 359.885477 -183.368313) (xy 359.852403 -183.327841)
			(xy 359.82517 -183.283227) (xy 359.80429 -183.235311) (xy 359.790154 -183.18499) (xy 359.783027 -183.13321)
			(xy 359.782618 -183.107076) (xy 359.783083 -183.079825) (xy 359.790843 -183.025878) (xy 359.806201 -182.973585)
			(xy 359.828845 -182.924009) (xy 359.858315 -182.878161) (xy 359.894009 -182.836973) (xy 359.935201 -182.801285)
			(xy 359.981053 -182.771821) (xy 360.030631 -182.749184) (xy 360.082927 -182.733832) (xy 360.136875 -182.726079)
			(xy 360.164126 -182.725568) (xy 360.175327 -182.725626) (xy 360.197694 -182.726897) (xy 360.20883 -182.728108)
			(xy 360.210354 -182.728362) (xy 360.216196 -182.728616) (xy 360.225452 -182.728259) (xy 360.242774 -182.72174)
			(xy 360.249978 -182.715916) (xy 360.30662 -182.665878) (xy 360.312208 -182.660036) (xy 360.316889 -182.653941)
			(xy 360.322706 -182.639724) (xy 360.323638 -182.632096) (xy 360.323892 -182.627778) (xy 360.323892 -182.598568)
			(xy 360.323638 -182.593234) (xy 360.322568 -182.585484) (xy 360.316354 -182.571134) (xy 360.311446 -182.56504)
			(xy 360.307128 -182.560722) (xy 360.25074 -182.510176) (xy 360.246735 -182.506784) (xy 360.237645 -182.50154)
			(xy 360.232706 -182.499762) (xy 360.222546 -182.49646) (xy 360.211878 -182.497476) (xy 360.201937 -182.498443)
			(xy 360.181988 -182.499461) (xy 360.172 -182.499508) (xy 360.144749 -182.499022) (xy 360.090801 -182.491266)
			(xy 360.038506 -182.475911) (xy 359.988929 -182.453269) (xy 359.943079 -182.423803) (xy 359.901888 -182.388112)
			(xy 359.866197 -182.346921) (xy 359.836731 -182.301071) (xy 359.814089 -182.251494) (xy 359.798734 -182.199199)
			(xy 359.790978 -182.145251) (xy 359.790978 -182.090749) (xy 359.798734 -182.036801) (xy 359.814089 -181.984506)
			(xy 359.836731 -181.934929) (xy 359.866197 -181.889079) (xy 359.901888 -181.847888) (xy 359.943079 -181.812197)
			(xy 359.988929 -181.782731) (xy 360.038506 -181.760089) (xy 360.090801 -181.744734) (xy 360.144749 -181.736978)
			(xy 360.172 -181.736492) (xy 360.181988 -181.736544) (xy 360.201937 -181.737559) (xy 360.211878 -181.738524)
			(xy 360.222546 -181.73954) (xy 360.232706 -181.736238) (xy 360.237662 -181.734497) (xy 360.246758 -181.729249)
			(xy 360.25074 -181.725824) (xy 360.307128 -181.675278) (xy 360.311446 -181.67096) (xy 360.316361 -181.66487)
			(xy 360.322583 -181.650519) (xy 360.323638 -181.642766) (xy 360.323892 -181.637432) (xy 360.323892 -179.550568)
			(xy 360.323638 -179.545234) (xy 360.322568 -179.537484) (xy 360.316354 -179.523134) (xy 360.311446 -179.51704)
			(xy 360.307128 -179.512722) (xy 360.25074 -179.462176) (xy 360.246735 -179.458784) (xy 360.237645 -179.45354)
			(xy 360.232706 -179.451762) (xy 360.222546 -179.44846) (xy 360.211878 -179.449476) (xy 360.201937 -179.450443)
			(xy 360.181988 -179.451461) (xy 360.172 -179.451508) (xy 360.144749 -179.451022) (xy 360.090801 -179.443266)
			(xy 360.038506 -179.427911) (xy 359.988929 -179.405269) (xy 359.943079 -179.375803) (xy 359.901888 -179.340112)
			(xy 359.866197 -179.298921) (xy 359.836731 -179.253071) (xy 359.814089 -179.203494) (xy 359.798734 -179.151199)
			(xy 359.790978 -179.097251) (xy 359.790978 -179.042749) (xy 359.798734 -178.988801) (xy 359.814089 -178.936506)
			(xy 359.836731 -178.886929) (xy 359.866197 -178.841079) (xy 359.901888 -178.799888) (xy 359.943079 -178.764197)
			(xy 359.988929 -178.734731) (xy 360.038506 -178.712089) (xy 360.090801 -178.696734) (xy 360.144749 -178.688978)
			(xy 360.172 -178.688492) (xy 360.181988 -178.688544) (xy 360.201937 -178.689559) (xy 360.211878 -178.690524)
			(xy 360.222546 -178.69154) (xy 360.232706 -178.688238) (xy 360.237662 -178.686497) (xy 360.246758 -178.681249)
			(xy 360.25074 -178.677824) (xy 360.307128 -178.627278) (xy 360.311446 -178.62296) (xy 360.316361 -178.61687)
			(xy 360.322583 -178.602519) (xy 360.323638 -178.594766) (xy 360.323892 -178.589432) (xy 360.323892 -178.534568)
			(xy 360.323638 -178.529234) (xy 360.322568 -178.521484) (xy 360.316354 -178.507134) (xy 360.311446 -178.50104)
			(xy 360.307128 -178.496722) (xy 360.25074 -178.446176) (xy 360.246735 -178.442784) (xy 360.237645 -178.43754)
			(xy 360.232706 -178.435762) (xy 360.222546 -178.43246) (xy 360.211878 -178.433476) (xy 360.201937 -178.434443)
			(xy 360.181988 -178.435461) (xy 360.172 -178.435508) (xy 360.144749 -178.435022) (xy 360.090801 -178.427266)
			(xy 360.038506 -178.411911) (xy 359.988929 -178.389269) (xy 359.943079 -178.359803) (xy 359.901888 -178.324112)
			(xy 359.866197 -178.282921) (xy 359.836731 -178.237071) (xy 359.814089 -178.187494) (xy 359.798734 -178.135199)
			(xy 359.790978 -178.081251) (xy 359.790978 -178.026749) (xy 359.798734 -177.972801) (xy 359.814089 -177.920506)
			(xy 359.836731 -177.870929) (xy 359.866197 -177.825079) (xy 359.901888 -177.783888) (xy 359.943079 -177.748197)
			(xy 359.988929 -177.718731) (xy 360.038506 -177.696089) (xy 360.090801 -177.680734) (xy 360.144749 -177.672978)
			(xy 360.172 -177.672492) (xy 360.181988 -177.672544) (xy 360.201937 -177.673559) (xy 360.211878 -177.674524)
			(xy 360.222546 -177.67554) (xy 360.232706 -177.672238) (xy 360.237662 -177.670497) (xy 360.246758 -177.665249)
			(xy 360.25074 -177.661824) (xy 360.307128 -177.611278) (xy 360.311446 -177.60696) (xy 360.316361 -177.60087)
			(xy 360.322583 -177.586519) (xy 360.323638 -177.578766) (xy 360.323892 -177.573432) (xy 360.323892 -177.264568)
			(xy 360.323638 -177.259234) (xy 360.322568 -177.251484) (xy 360.316354 -177.237134) (xy 360.311446 -177.23104)
			(xy 360.307128 -177.226722) (xy 360.25074 -177.176176) (xy 360.246735 -177.172784) (xy 360.237645 -177.16754)
			(xy 360.232706 -177.165762) (xy 360.222546 -177.16246) (xy 360.211878 -177.163476) (xy 360.201937 -177.164443)
			(xy 360.181988 -177.165461) (xy 360.172 -177.165508) (xy 360.144749 -177.165022) (xy 360.090801 -177.157266)
			(xy 360.038506 -177.141911) (xy 359.988929 -177.119269) (xy 359.943079 -177.089803) (xy 359.901888 -177.054112)
			(xy 359.866197 -177.012921) (xy 359.836731 -176.967071) (xy 359.814089 -176.917494) (xy 359.798734 -176.865199)
			(xy 359.790978 -176.811251) (xy 359.790978 -176.756749) (xy 359.798734 -176.702801) (xy 359.814089 -176.650506)
			(xy 359.836731 -176.600929) (xy 359.866197 -176.555079) (xy 359.901888 -176.513888) (xy 359.943079 -176.478197)
			(xy 359.988929 -176.448731) (xy 360.038506 -176.426089) (xy 360.090801 -176.410734) (xy 360.144749 -176.402978)
			(xy 360.172 -176.402492) (xy 360.181988 -176.402544) (xy 360.201937 -176.403559) (xy 360.211878 -176.404524)
			(xy 360.222546 -176.40554) (xy 360.232706 -176.402238) (xy 360.237662 -176.400497) (xy 360.246758 -176.395249)
			(xy 360.25074 -176.391824) (xy 360.307128 -176.341278) (xy 360.311446 -176.33696) (xy 360.316361 -176.33087)
			(xy 360.322583 -176.316519) (xy 360.323638 -176.308766) (xy 360.323892 -176.303432) (xy 360.323892 -175.486568)
			(xy 360.323638 -175.481234) (xy 360.322568 -175.473484) (xy 360.316354 -175.459134) (xy 360.311446 -175.45304)
			(xy 360.307128 -175.448722) (xy 360.25074 -175.398176) (xy 360.246735 -175.394784) (xy 360.237645 -175.38954)
			(xy 360.232706 -175.387762) (xy 360.222546 -175.38446) (xy 360.211878 -175.385476) (xy 360.201937 -175.386443)
			(xy 360.181988 -175.387461) (xy 360.172 -175.387508) (xy 360.144749 -175.387022) (xy 360.090801 -175.379266)
			(xy 360.038506 -175.363911) (xy 359.988929 -175.341269) (xy 359.943079 -175.311803) (xy 359.901888 -175.276112)
			(xy 359.866197 -175.234921) (xy 359.836731 -175.189071) (xy 359.814089 -175.139494) (xy 359.798734 -175.087199)
			(xy 359.790978 -175.033251) (xy 359.790978 -174.978749) (xy 359.798734 -174.924801) (xy 359.814089 -174.872506)
			(xy 359.836731 -174.822929) (xy 359.866197 -174.777079) (xy 359.901888 -174.735888) (xy 359.943079 -174.700197)
			(xy 359.988929 -174.670731) (xy 360.038506 -174.648089) (xy 360.090801 -174.632734) (xy 360.144749 -174.624978)
			(xy 360.172 -174.624492) (xy 360.181988 -174.624544) (xy 360.201937 -174.625559) (xy 360.211878 -174.626524)
			(xy 360.222546 -174.62754) (xy 360.232706 -174.624238) (xy 360.237662 -174.622497) (xy 360.246758 -174.617249)
			(xy 360.25074 -174.613824) (xy 360.307128 -174.563278) (xy 360.311446 -174.55896) (xy 360.316361 -174.55287)
			(xy 360.322583 -174.538519) (xy 360.323638 -174.530766) (xy 360.323892 -174.525432) (xy 360.323892 -174.470568)
			(xy 360.323638 -174.465234) (xy 360.322568 -174.457484) (xy 360.316354 -174.443134) (xy 360.311446 -174.43704)
			(xy 360.307128 -174.432722) (xy 360.25074 -174.382176) (xy 360.246735 -174.378784) (xy 360.237645 -174.37354)
			(xy 360.232706 -174.371762) (xy 360.222546 -174.36846) (xy 360.211878 -174.369476) (xy 360.201937 -174.370443)
			(xy 360.181988 -174.371461) (xy 360.172 -174.371508) (xy 360.144749 -174.371022) (xy 360.090801 -174.363266)
			(xy 360.038506 -174.347911) (xy 359.988929 -174.325269) (xy 359.943079 -174.295803) (xy 359.901888 -174.260112)
			(xy 359.866197 -174.218921) (xy 359.836731 -174.173071) (xy 359.814089 -174.123494) (xy 359.798734 -174.071199)
			(xy 359.790978 -174.017251) (xy 359.790978 -173.962749) (xy 359.798734 -173.908801) (xy 359.814089 -173.856506)
			(xy 359.836731 -173.806929) (xy 359.866197 -173.761079) (xy 359.901888 -173.719888) (xy 359.943079 -173.684197)
			(xy 359.988929 -173.654731) (xy 360.038506 -173.632089) (xy 360.090801 -173.616734) (xy 360.144749 -173.608978)
			(xy 360.172 -173.608492) (xy 360.181988 -173.608544) (xy 360.201937 -173.609559) (xy 360.211878 -173.610524)
			(xy 360.222546 -173.61154) (xy 360.232706 -173.608238) (xy 360.237662 -173.606497) (xy 360.246758 -173.601249)
			(xy 360.25074 -173.597824) (xy 360.307128 -173.547278) (xy 360.311446 -173.54296) (xy 360.316361 -173.53687)
			(xy 360.322583 -173.522519) (xy 360.323638 -173.514766) (xy 360.323892 -173.509432) (xy 360.323892 -173.454568)
			(xy 360.323638 -173.449234) (xy 360.322568 -173.441484) (xy 360.316354 -173.427134) (xy 360.311446 -173.42104)
			(xy 360.307128 -173.416722) (xy 360.25074 -173.366176) (xy 360.246735 -173.362784) (xy 360.237645 -173.35754)
			(xy 360.232706 -173.355762) (xy 360.222546 -173.35246) (xy 360.211878 -173.353476) (xy 360.201937 -173.354443)
			(xy 360.181988 -173.355461) (xy 360.172 -173.355508) (xy 360.144749 -173.355022) (xy 360.090801 -173.347266)
			(xy 360.038506 -173.331911) (xy 359.988929 -173.309269) (xy 359.943079 -173.279803) (xy 359.901888 -173.244112)
			(xy 359.866197 -173.202921) (xy 359.836731 -173.157071) (xy 359.814089 -173.107494) (xy 359.798734 -173.055199)
			(xy 359.790978 -173.001251) (xy 359.790978 -172.946749) (xy 359.798734 -172.892801) (xy 359.814089 -172.840506)
			(xy 359.836731 -172.790929) (xy 359.866197 -172.745079) (xy 359.901888 -172.703888) (xy 359.943079 -172.668197)
			(xy 359.988929 -172.638731) (xy 360.038506 -172.616089) (xy 360.090801 -172.600734) (xy 360.144749 -172.592978)
			(xy 360.172 -172.592492) (xy 360.181988 -172.592544) (xy 360.201937 -172.593559) (xy 360.211878 -172.594524)
			(xy 360.222546 -172.59554) (xy 360.232706 -172.592238) (xy 360.237662 -172.590497) (xy 360.246758 -172.585249)
			(xy 360.25074 -172.581824) (xy 360.307128 -172.531278) (xy 360.311446 -172.52696) (xy 360.316361 -172.52087)
			(xy 360.322583 -172.506519) (xy 360.323638 -172.498766) (xy 360.323892 -172.493432) (xy 360.323892 -169.867326)
			(xy 360.324378 -169.84152) (xy 360.332569 -169.790562) (xy 360.348793 -169.741566) (xy 360.372634 -169.695791)
			(xy 360.387646 -169.674794) (xy 360.391202 -169.66946) (xy 360.402568 -169.650134) (xy 360.429708 -169.614447)
			(xy 360.445304 -169.59834) (xy 362.974128 -167.069516) (xy 362.97743 -167.05961) (xy 362.985748 -167.033891)
			(xy 363.008629 -166.984918) (xy 363.038196 -166.939669) (xy 363.073859 -166.899048) (xy 363.1149 -166.863872)
			(xy 363.160499 -166.834844) (xy 363.209739 -166.812547) (xy 363.261636 -166.797429) (xy 363.315147 -166.789791)
			(xy 363.342174 -166.789354) (xy 363.369427 -166.789838) (xy 363.42338 -166.797591) (xy 363.47568 -166.812944)
			(xy 363.525263 -166.835583) (xy 363.571119 -166.865048) (xy 363.612316 -166.900739) (xy 363.648014 -166.941929)
			(xy 363.677486 -166.987781) (xy 363.700134 -167.03736) (xy 363.715495 -167.089657) (xy 363.723257 -167.143609)
			(xy 363.723682 -167.170862) (xy 363.723214 -167.19789) (xy 363.715585 -167.251403) (xy 363.700474 -167.303303)
			(xy 363.678185 -167.352549) (xy 363.649163 -167.398153) (xy 363.613992 -167.439201) (xy 363.573376 -167.47487)
			(xy 363.52813 -167.504445) (xy 363.47916 -167.527333) (xy 363.453426 -167.535606) (xy 363.44352 -167.538908)
			(xy 363.199146 -167.783256) (xy 363.734348 -167.783256) (xy 363.738419 -167.727634) (xy 363.750545 -167.673197)
			(xy 363.770468 -167.621106) (xy 363.797764 -167.572471) (xy 363.83185 -167.528328) (xy 363.871999 -167.489619)
			(xy 363.917357 -167.457168) (xy 363.966957 -167.431667) (xy 364.019741 -167.41366) (xy 364.074584 -167.40353)
			(xy 364.130318 -167.401493) (xy 364.185755 -167.407593) (xy 364.239712 -167.421699) (xy 364.291041 -167.443511)
			(xy 364.338647 -167.472565) (xy 364.381515 -167.50824) (xy 364.418732 -167.549777) (xy 364.449505 -167.59629)
			(xy 364.473177 -167.646787) (xy 364.489245 -167.700194) (xy 364.497365 -167.75537) (xy 364.497874 -167.783256)
			(xy 364.497365 -167.811142) (xy 364.489245 -167.866318) (xy 364.473177 -167.919725) (xy 364.449505 -167.970222)
			(xy 364.418732 -168.016735) (xy 364.381515 -168.058272) (xy 364.338647 -168.093947) (xy 364.291041 -168.123001)
			(xy 364.239712 -168.144813) (xy 364.185755 -168.158919) (xy 364.130318 -168.165019) (xy 364.074584 -168.162982)
			(xy 364.019741 -168.152852) (xy 363.966957 -168.134845) (xy 363.917357 -168.109344) (xy 363.871999 -168.076893)
			(xy 363.83185 -168.038184) (xy 363.797764 -167.994041) (xy 363.770468 -167.945406) (xy 363.750545 -167.893315)
			(xy 363.738419 -167.838878) (xy 363.734348 -167.783256) (xy 363.199146 -167.783256) (xy 361.02671 -169.955464)
			(xy 361.019873 -169.962866) (xy 361.01216 -169.981464) (xy 361.011724 -169.991532) (xy 361.011724 -176.121568)
			(xy 361.012143 -176.131616) (xy 361.019845 -176.150177) (xy 361.034081 -176.164361) (xy 361.04322 -176.168558)
			(xy 361.057444 -176.174654) (xy 361.087416 -176.168558) (xy 361.634278 -175.621696) (xy 361.638088 -175.610774)
			(xy 361.647821 -175.584422) (xy 361.673914 -175.534675) (xy 361.70701 -175.489285) (xy 361.746394 -175.44923)
			(xy 361.791219 -175.415373) (xy 361.815634 -175.401478) (xy 361.822495 -175.397426) (xy 361.833494 -175.385913)
			(xy 361.837224 -175.378872) (xy 361.850238 -175.353091) (xy 361.882864 -175.305442) (xy 361.922298 -175.263254)
			(xy 361.96764 -175.227491) (xy 362.017855 -175.19897) (xy 362.071794 -175.178344) (xy 362.128226 -175.166082)
			(xy 362.15701 -175.163734) (xy 362.166272 -175.162776) (xy 362.183217 -175.155094) (xy 362.19003 -175.148748)
			(xy 362.211112 -175.126904) (xy 362.21776 -175.119547) (xy 362.22534 -175.101247) (xy 362.225844 -175.091344)
			(xy 362.225844 -174.85614) (xy 362.225408 -174.846076) (xy 362.217672 -174.827493) (xy 362.210858 -174.820072)
			(xy 362.057696 -174.66691) (xy 362.034752 -174.643355) (xy 361.993736 -174.591954) (xy 361.958737 -174.536282)
			(xy 361.930196 -174.47704) (xy 361.908471 -174.414972) (xy 361.893836 -174.350862) (xy 361.886476 -174.285516)
			(xy 361.885992 -174.252636) (xy 361.885992 -171.58462) (xy 361.885736 -171.576974) (xy 361.881219 -171.562366)
			(xy 361.877102 -171.555918) (xy 361.857578 -171.526567) (xy 361.824928 -171.464088) (xy 361.800016 -171.398141)
			(xy 361.783204 -171.32968) (xy 361.774733 -171.259696) (xy 361.774232 -171.224448) (xy 361.774743 -171.189037)
			(xy 361.783276 -171.11873) (xy 361.800224 -171.049965) (xy 361.82534 -170.983745) (xy 361.858256 -170.921037)
			(xy 361.898493 -170.862754) (xy 361.945463 -170.809749) (xy 361.998482 -170.762793) (xy 362.056776 -170.722572)
			(xy 362.119493 -170.689673) (xy 362.18572 -170.664576) (xy 362.25449 -170.647647) (xy 362.324799 -170.639133)
			(xy 362.36021 -170.638724) (xy 362.393084 -170.639153) (xy 362.45842 -170.646486) (xy 362.522523 -170.661092)
			(xy 362.584587 -170.682788) (xy 362.64383 -170.7113) (xy 362.699505 -170.746269) (xy 362.750912 -170.787256)
			(xy 362.774484 -170.810174) (xy 362.886244 -170.921934) (xy 362.909192 -170.945487) (xy 362.94351 -170.988482)
			(xy 366.984024 -170.988482) (xy 366.988095 -170.93286) (xy 367.000221 -170.878423) (xy 367.020144 -170.826332)
			(xy 367.04744 -170.777697) (xy 367.081526 -170.733554) (xy 367.121675 -170.694845) (xy 367.167033 -170.662394)
			(xy 367.216633 -170.636893) (xy 367.269417 -170.618886) (xy 367.32426 -170.608756) (xy 367.379994 -170.606719)
			(xy 367.435431 -170.612819) (xy 367.489388 -170.626925) (xy 367.540717 -170.648737) (xy 367.588323 -170.677791)
			(xy 367.631191 -170.713466) (xy 367.668408 -170.755003) (xy 367.699181 -170.801516) (xy 367.722853 -170.852013)
			(xy 367.738921 -170.90542) (xy 367.747041 -170.960596) (xy 367.74755 -170.988482) (xy 367.74723 -171.006008)
			(xy 368.280694 -171.006008) (xy 368.284765 -170.950386) (xy 368.296891 -170.895949) (xy 368.316814 -170.843858)
			(xy 368.34411 -170.795223) (xy 368.378196 -170.75108) (xy 368.418345 -170.712371) (xy 368.463703 -170.67992)
			(xy 368.513303 -170.654419) (xy 368.566087 -170.636412) (xy 368.62093 -170.626282) (xy 368.676664 -170.624245)
			(xy 368.732101 -170.630345) (xy 368.786058 -170.644451) (xy 368.837387 -170.666263) (xy 368.884993 -170.695317)
			(xy 368.927861 -170.730992) (xy 368.965078 -170.772529) (xy 368.995851 -170.819042) (xy 369.019523 -170.869539)
			(xy 369.035591 -170.922946) (xy 369.043711 -170.978122) (xy 369.04422 -171.006008) (xy 369.043711 -171.033894)
			(xy 369.035591 -171.08907) (xy 369.019523 -171.142477) (xy 369.016818 -171.148248) (xy 372.58447 -171.148248)
			(xy 372.588541 -171.092626) (xy 372.600667 -171.038189) (xy 372.62059 -170.986098) (xy 372.647886 -170.937463)
			(xy 372.681972 -170.89332) (xy 372.722121 -170.854611) (xy 372.767479 -170.82216) (xy 372.817079 -170.796659)
			(xy 372.869863 -170.778652) (xy 372.924706 -170.768522) (xy 372.98044 -170.766485) (xy 373.035877 -170.772585)
			(xy 373.089834 -170.786691) (xy 373.141163 -170.808503) (xy 373.188769 -170.837557) (xy 373.231637 -170.873232)
			(xy 373.268854 -170.914769) (xy 373.299627 -170.961282) (xy 373.323299 -171.011779) (xy 373.339367 -171.065186)
			(xy 373.347487 -171.120362) (xy 373.347996 -171.148248) (xy 373.347487 -171.176134) (xy 373.339367 -171.23131)
			(xy 373.323299 -171.284717) (xy 373.299627 -171.335214) (xy 373.268854 -171.381727) (xy 373.231637 -171.423264)
			(xy 373.188769 -171.458939) (xy 373.141163 -171.487993) (xy 373.089834 -171.509805) (xy 373.035877 -171.523911)
			(xy 372.98044 -171.530011) (xy 372.924706 -171.527974) (xy 372.869863 -171.517844) (xy 372.817079 -171.499837)
			(xy 372.767479 -171.474336) (xy 372.722121 -171.441885) (xy 372.681972 -171.403176) (xy 372.647886 -171.359033)
			(xy 372.62059 -171.310398) (xy 372.600667 -171.258307) (xy 372.588541 -171.20387) (xy 372.58447 -171.148248)
			(xy 369.016818 -171.148248) (xy 368.995851 -171.192974) (xy 368.965078 -171.239487) (xy 368.927861 -171.281024)
			(xy 368.884993 -171.316699) (xy 368.837387 -171.345753) (xy 368.786058 -171.367565) (xy 368.732101 -171.381671)
			(xy 368.676664 -171.387771) (xy 368.62093 -171.385734) (xy 368.566087 -171.375604) (xy 368.513303 -171.357597)
			(xy 368.463703 -171.332096) (xy 368.418345 -171.299645) (xy 368.378196 -171.260936) (xy 368.34411 -171.216793)
			(xy 368.316814 -171.168158) (xy 368.296891 -171.116067) (xy 368.284765 -171.06163) (xy 368.280694 -171.006008)
			(xy 367.74723 -171.006008) (xy 367.747041 -171.016368) (xy 367.738921 -171.071544) (xy 367.722853 -171.124951)
			(xy 367.699181 -171.175448) (xy 367.668408 -171.221961) (xy 367.631191 -171.263498) (xy 367.588323 -171.299173)
			(xy 367.540717 -171.328227) (xy 367.489388 -171.350039) (xy 367.435431 -171.364145) (xy 367.379994 -171.370245)
			(xy 367.32426 -171.368208) (xy 367.269417 -171.358078) (xy 367.216633 -171.340071) (xy 367.167033 -171.31457)
			(xy 367.121675 -171.282119) (xy 367.081526 -171.24341) (xy 367.04744 -171.199267) (xy 367.020144 -171.150632)
			(xy 367.000221 -171.098541) (xy 366.988095 -171.044104) (xy 366.984024 -170.988482) (xy 362.94351 -170.988482)
			(xy 362.950217 -170.996885) (xy 362.985225 -171.052555) (xy 363.013775 -171.111798) (xy 363.035509 -171.173866)
			(xy 363.050151 -171.237978) (xy 363.057518 -171.303327) (xy 363.057948 -171.336208) (xy 363.057948 -173.581822)
			(xy 363.058465 -173.592324) (xy 363.059976 -173.595792) (xy 369.381276 -173.595792) (xy 369.385347 -173.54017)
			(xy 369.397473 -173.485733) (xy 369.417396 -173.433642) (xy 369.444692 -173.385007) (xy 369.478778 -173.340864)
			(xy 369.518927 -173.302155) (xy 369.564285 -173.269704) (xy 369.613885 -173.244203) (xy 369.666669 -173.226196)
			(xy 369.721512 -173.216066) (xy 369.777246 -173.214029) (xy 369.832683 -173.220129) (xy 369.88664 -173.234235)
			(xy 369.937969 -173.256047) (xy 369.985575 -173.285101) (xy 370.028443 -173.320776) (xy 370.06566 -173.362313)
			(xy 370.096433 -173.408826) (xy 370.120105 -173.459323) (xy 370.136173 -173.51273) (xy 370.144293 -173.567906)
			(xy 370.144802 -173.595792) (xy 370.144394 -173.618144) (xy 370.486176 -173.618144) (xy 370.490247 -173.562522)
			(xy 370.502373 -173.508085) (xy 370.522296 -173.455994) (xy 370.549592 -173.407359) (xy 370.583678 -173.363216)
			(xy 370.623827 -173.324507) (xy 370.669185 -173.292056) (xy 370.718785 -173.266555) (xy 370.771569 -173.248548)
			(xy 370.826412 -173.238418) (xy 370.882146 -173.236381) (xy 370.937583 -173.242481) (xy 370.99154 -173.256587)
			(xy 371.042869 -173.278399) (xy 371.090475 -173.307453) (xy 371.133343 -173.343128) (xy 371.17056 -173.384665)
			(xy 371.201333 -173.431178) (xy 371.225005 -173.481675) (xy 371.241073 -173.535082) (xy 371.249193 -173.590258)
			(xy 371.249702 -173.618144) (xy 371.249193 -173.64603) (xy 371.241073 -173.701206) (xy 371.225005 -173.754613)
			(xy 371.201333 -173.80511) (xy 371.17056 -173.851623) (xy 371.133343 -173.89316) (xy 371.090475 -173.928835)
			(xy 371.042869 -173.957889) (xy 370.99154 -173.979701) (xy 370.937583 -173.993807) (xy 370.882146 -173.999907)
			(xy 370.826412 -173.99787) (xy 370.771569 -173.98774) (xy 370.718785 -173.969733) (xy 370.669185 -173.944232)
			(xy 370.623827 -173.911781) (xy 370.583678 -173.873072) (xy 370.549592 -173.828929) (xy 370.522296 -173.780294)
			(xy 370.502373 -173.728203) (xy 370.490247 -173.673766) (xy 370.486176 -173.618144) (xy 370.144394 -173.618144)
			(xy 370.144293 -173.623678) (xy 370.136173 -173.678854) (xy 370.120105 -173.732261) (xy 370.096433 -173.782758)
			(xy 370.06566 -173.829271) (xy 370.028443 -173.870808) (xy 369.985575 -173.906483) (xy 369.937969 -173.935537)
			(xy 369.88664 -173.957349) (xy 369.832683 -173.971455) (xy 369.777246 -173.977555) (xy 369.721512 -173.975518)
			(xy 369.666669 -173.965388) (xy 369.613885 -173.947381) (xy 369.564285 -173.92188) (xy 369.518927 -173.889429)
			(xy 369.478778 -173.85072) (xy 369.444692 -173.806577) (xy 369.417396 -173.757942) (xy 369.397473 -173.705851)
			(xy 369.385347 -173.651414) (xy 369.381276 -173.595792) (xy 363.059976 -173.595792) (xy 363.066857 -173.61158)
			(xy 363.082238 -173.625886) (xy 363.091984 -173.629828) (xy 363.116552 -173.638875) (xy 363.163145 -173.66275)
			(xy 363.206035 -173.692772) (xy 363.244417 -173.728378) (xy 363.277568 -173.768899) (xy 363.304866 -173.813573)
			(xy 363.325798 -173.86156) (xy 363.339971 -173.911959) (xy 363.347117 -173.963823) (xy 363.347508 -173.99)
			(xy 363.34701 -174.01714) (xy 363.341888 -174.052738) (xy 374.195084 -174.052738) (xy 374.199155 -173.997116)
			(xy 374.211281 -173.942679) (xy 374.231204 -173.890588) (xy 374.2585 -173.841953) (xy 374.292586 -173.79781)
			(xy 374.332735 -173.759101) (xy 374.378093 -173.72665) (xy 374.427693 -173.701149) (xy 374.480477 -173.683142)
			(xy 374.53532 -173.673012) (xy 374.591054 -173.670975) (xy 374.646491 -173.677075) (xy 374.700448 -173.691181)
			(xy 374.751777 -173.712993) (xy 374.799383 -173.742047) (xy 374.842251 -173.777722) (xy 374.879468 -173.819259)
			(xy 374.910241 -173.865772) (xy 374.933913 -173.916269) (xy 374.949981 -173.969676) (xy 374.958101 -174.024852)
			(xy 374.95861 -174.052738) (xy 374.958101 -174.080624) (xy 374.949981 -174.1358) (xy 374.933913 -174.189207)
			(xy 374.910241 -174.239704) (xy 374.879468 -174.286217) (xy 374.842251 -174.327754) (xy 374.799383 -174.363429)
			(xy 374.751777 -174.392483) (xy 374.700448 -174.414295) (xy 374.646491 -174.428401) (xy 374.591054 -174.434501)
			(xy 374.53532 -174.432464) (xy 374.480477 -174.422334) (xy 374.427693 -174.404327) (xy 374.378093 -174.378826)
			(xy 374.332735 -174.346375) (xy 374.292586 -174.307666) (xy 374.2585 -174.263523) (xy 374.231204 -174.214888)
			(xy 374.211281 -174.162797) (xy 374.199155 -174.10836) (xy 374.195084 -174.052738) (xy 363.341888 -174.052738)
			(xy 363.339279 -174.070868) (xy 363.324018 -174.12296) (xy 363.301532 -174.172365) (xy 363.28731 -174.195486)
			(xy 363.282223 -174.204244) (xy 363.278758 -174.224181) (xy 363.283294 -174.243903) (xy 363.288834 -174.252382)
			(xy 363.30948 -174.282249) (xy 363.344033 -174.34611) (xy 363.370429 -174.41375) (xy 363.388263 -174.484135)
			(xy 363.389741 -174.495968) (xy 364.803434 -174.495968) (xy 364.807505 -174.440346) (xy 364.819631 -174.385909)
			(xy 364.839554 -174.333818) (xy 364.86685 -174.285183) (xy 364.900936 -174.24104) (xy 364.941085 -174.202331)
			(xy 364.986443 -174.16988) (xy 365.036043 -174.144379) (xy 365.088827 -174.126372) (xy 365.14367 -174.116242)
			(xy 365.199404 -174.114205) (xy 365.254841 -174.120305) (xy 365.308798 -174.134411) (xy 365.360127 -174.156223)
			(xy 365.407733 -174.185277) (xy 365.450601 -174.220952) (xy 365.487818 -174.262489) (xy 365.518591 -174.309002)
			(xy 365.542263 -174.359499) (xy 365.558331 -174.412906) (xy 365.566451 -174.468082) (xy 365.56696 -174.495968)
			(xy 365.566451 -174.523854) (xy 365.558331 -174.57903) (xy 365.542263 -174.632437) (xy 365.518591 -174.682934)
			(xy 365.487818 -174.729447) (xy 365.450601 -174.770984) (xy 365.407733 -174.806659) (xy 365.360127 -174.835713)
			(xy 365.308798 -174.857525) (xy 365.254841 -174.871631) (xy 365.199404 -174.877731) (xy 365.14367 -174.875694)
			(xy 365.088827 -174.865564) (xy 365.036043 -174.847557) (xy 364.986443 -174.822056) (xy 364.941085 -174.789605)
			(xy 364.900936 -174.750896) (xy 364.86685 -174.706753) (xy 364.839554 -174.658118) (xy 364.819631 -174.606027)
			(xy 364.807505 -174.55159) (xy 364.803434 -174.495968) (xy 363.389741 -174.495968) (xy 363.397263 -174.556184)
			(xy 363.3978 -174.592488) (xy 363.3978 -175.935132) (xy 363.717838 -175.935132) (xy 363.721909 -175.87951)
			(xy 363.734035 -175.825073) (xy 363.753958 -175.772982) (xy 363.781254 -175.724347) (xy 363.81534 -175.680204)
			(xy 363.855489 -175.641495) (xy 363.900847 -175.609044) (xy 363.950447 -175.583543) (xy 364.003231 -175.565536)
			(xy 364.058074 -175.555406) (xy 364.113808 -175.553369) (xy 364.169245 -175.559469) (xy 364.223202 -175.573575)
			(xy 364.274531 -175.595387) (xy 364.322137 -175.624441) (xy 364.365005 -175.660116) (xy 364.402222 -175.701653)
			(xy 364.432995 -175.748166) (xy 364.456667 -175.798663) (xy 364.472735 -175.85207) (xy 364.480855 -175.907246)
			(xy 364.481364 -175.935132) (xy 364.480855 -175.963018) (xy 364.472735 -176.018194) (xy 364.456667 -176.071601)
			(xy 364.432995 -176.122098) (xy 364.402222 -176.168611) (xy 364.365005 -176.210148) (xy 364.322137 -176.245823)
			(xy 364.274531 -176.274877) (xy 364.223202 -176.296689) (xy 364.169245 -176.310795) (xy 364.113808 -176.316895)
			(xy 364.058074 -176.314858) (xy 364.003231 -176.304728) (xy 363.950447 -176.286721) (xy 363.900847 -176.26122)
			(xy 363.855489 -176.228769) (xy 363.81534 -176.19006) (xy 363.781254 -176.145917) (xy 363.753958 -176.097282)
			(xy 363.734035 -176.045191) (xy 363.721909 -175.990754) (xy 363.717838 -175.935132) (xy 363.3978 -175.935132)
			(xy 363.3978 -176.339246) (xy 363.397321 -176.372123) (xy 363.393844 -176.402856) (xy 367.662623 -176.402856)
			(xy 367.662623 -176.348344) (xy 367.670381 -176.294387) (xy 367.685739 -176.242084) (xy 367.708384 -176.192499)
			(xy 367.737856 -176.146641) (xy 367.773554 -176.105445) (xy 367.814752 -176.069748) (xy 367.860611 -176.040278)
			(xy 367.910197 -176.017634) (xy 367.962501 -176.002278) (xy 368.016458 -175.994522) (xy 368.043714 -175.99406)
			(xy 368.072036 -175.994596) (xy 368.128055 -176.002983) (xy 368.18222 -176.019556) (xy 368.233342 -176.043952)
			(xy 368.280297 -176.075634) (xy 368.301524 -176.09439) (xy 368.311723 -176.103125) (xy 368.335572 -176.115449)
			(xy 368.361805 -176.121144) (xy 368.388616 -176.119817) (xy 368.414159 -176.111561) (xy 368.436675 -176.096944)
			(xy 368.454612 -176.076972) (xy 368.461036 -176.06518) (xy 368.473209 -176.041786) (xy 368.503134 -175.99836)
			(xy 368.538758 -175.959473) (xy 368.5794 -175.925865) (xy 368.624286 -175.898179) (xy 368.672559 -175.876942)
			(xy 368.723298 -175.86256) (xy 368.775535 -175.855307) (xy 368.801904 -175.854868) (xy 368.829153 -175.855402)
			(xy 368.883097 -175.863159) (xy 368.935388 -175.878513) (xy 368.984962 -175.901153) (xy 369.030809 -175.930618)
			(xy 369.071996 -175.966307) (xy 369.107685 -176.007495) (xy 369.137149 -176.053342) (xy 369.159788 -176.102916)
			(xy 369.175142 -176.155207) (xy 369.182898 -176.209151) (xy 369.182898 -176.263649) (xy 369.175142 -176.317593)
			(xy 369.159788 -176.369884) (xy 369.137149 -176.419458) (xy 369.107685 -176.465305) (xy 369.071996 -176.506493)
			(xy 369.030809 -176.542182) (xy 368.984962 -176.571647) (xy 368.935388 -176.594287) (xy 368.883097 -176.609641)
			(xy 368.829153 -176.617398) (xy 368.801904 -176.617884) (xy 368.773582 -176.617352) (xy 368.717562 -176.608966)
			(xy 368.663396 -176.592393) (xy 368.612275 -176.567996) (xy 368.56532 -176.536312) (xy 368.544094 -176.517554)
			(xy 368.533887 -176.508826) (xy 368.510042 -176.496494) (xy 368.483809 -176.490793) (xy 368.456996 -176.492117)
			(xy 368.431452 -176.500373) (xy 368.408937 -176.514994) (xy 368.391003 -176.53497) (xy 368.384582 -176.546764)
			(xy 368.372372 -176.570138) (xy 368.342454 -176.613565) (xy 368.306837 -176.652455) (xy 368.2662 -176.686066)
			(xy 368.221319 -176.713755) (xy 368.173051 -176.734995) (xy 368.122315 -176.74938) (xy 368.070082 -176.756636)
			(xy 368.043714 -176.757076) (xy 368.016458 -176.756678) (xy 367.962501 -176.748922) (xy 367.910197 -176.733566)
			(xy 367.860611 -176.710922) (xy 367.814752 -176.681452) (xy 367.773554 -176.645755) (xy 367.737856 -176.604559)
			(xy 367.708384 -176.558701) (xy 367.685739 -176.509116) (xy 367.670381 -176.456813) (xy 367.662623 -176.402856)
			(xy 363.393844 -176.402856) (xy 363.389928 -176.437462) (xy 363.375273 -176.501563) (xy 363.35354 -176.563623)
			(xy 363.325002 -176.622863) (xy 363.290017 -176.678539) (xy 363.249024 -176.729952) (xy 363.226096 -176.75352)
			(xy 362.362496 -177.61712) (xy 364.751364 -177.61712) (xy 364.755435 -177.561498) (xy 364.767561 -177.507061)
			(xy 364.787484 -177.45497) (xy 364.81478 -177.406335) (xy 364.848866 -177.362192) (xy 364.889015 -177.323483)
			(xy 364.934373 -177.291032) (xy 364.983973 -177.265531) (xy 365.036757 -177.247524) (xy 365.0916 -177.237394)
			(xy 365.147334 -177.235357) (xy 365.202771 -177.241457) (xy 365.256728 -177.255563) (xy 365.308057 -177.277375)
			(xy 365.355663 -177.306429) (xy 365.398531 -177.342104) (xy 365.435748 -177.383641) (xy 365.466521 -177.430154)
			(xy 365.490193 -177.480651) (xy 365.506261 -177.534058) (xy 365.514381 -177.589234) (xy 365.51489 -177.61712)
			(xy 365.514381 -177.645006) (xy 365.506261 -177.700182) (xy 365.490193 -177.753589) (xy 365.466521 -177.804086)
			(xy 365.435748 -177.850599) (xy 365.398531 -177.892136) (xy 365.355663 -177.927811) (xy 365.308057 -177.956865)
			(xy 365.256728 -177.978677) (xy 365.202771 -177.992783) (xy 365.147334 -177.998883) (xy 365.0916 -177.996846)
			(xy 365.036757 -177.986716) (xy 364.983973 -177.968709) (xy 364.934373 -177.943208) (xy 364.889015 -177.910757)
			(xy 364.848866 -177.872048) (xy 364.81478 -177.827905) (xy 364.787484 -177.77927) (xy 364.767561 -177.727179)
			(xy 364.755435 -177.672742) (xy 364.751364 -177.61712) (xy 362.362496 -177.61712) (xy 362.321094 -177.658522)
			(xy 362.314252 -177.665922) (xy 362.306526 -177.68452) (xy 362.306108 -177.69459) (xy 362.306108 -178.267106)
			(xy 363.613444 -178.267106) (xy 363.617515 -178.211484) (xy 363.629641 -178.157047) (xy 363.649564 -178.104956)
			(xy 363.67686 -178.056321) (xy 363.710946 -178.012178) (xy 363.751095 -177.973469) (xy 363.796453 -177.941018)
			(xy 363.846053 -177.915517) (xy 363.898837 -177.89751) (xy 363.95368 -177.88738) (xy 364.009414 -177.885343)
			(xy 364.064851 -177.891443) (xy 364.118808 -177.905549) (xy 364.170137 -177.927361) (xy 364.217743 -177.956415)
			(xy 364.260611 -177.99209) (xy 364.297828 -178.033627) (xy 364.328601 -178.08014) (xy 364.352273 -178.130637)
			(xy 364.368341 -178.184044) (xy 364.376461 -178.23922) (xy 364.37697 -178.267106) (xy 364.376461 -178.294992)
			(xy 364.368341 -178.350168) (xy 364.352273 -178.403575) (xy 364.328601 -178.454072) (xy 364.297828 -178.500585)
			(xy 364.260611 -178.542122) (xy 364.217743 -178.577797) (xy 364.170137 -178.606851) (xy 364.118808 -178.628663)
			(xy 364.064851 -178.642769) (xy 364.009414 -178.648869) (xy 363.95368 -178.646832) (xy 363.898837 -178.636702)
			(xy 363.846053 -178.618695) (xy 363.796453 -178.593194) (xy 363.751095 -178.560743) (xy 363.710946 -178.522034)
			(xy 363.67686 -178.477891) (xy 363.649564 -178.429256) (xy 363.629641 -178.377165) (xy 363.617515 -178.322728)
			(xy 363.613444 -178.267106) (xy 362.306108 -178.267106) (xy 362.306108 -178.917092) (xy 364.751364 -178.917092)
			(xy 364.755435 -178.86147) (xy 364.767561 -178.807033) (xy 364.787484 -178.754942) (xy 364.81478 -178.706307)
			(xy 364.848866 -178.662164) (xy 364.889015 -178.623455) (xy 364.934373 -178.591004) (xy 364.983973 -178.565503)
			(xy 365.036757 -178.547496) (xy 365.0916 -178.537366) (xy 365.147334 -178.535329) (xy 365.202771 -178.541429)
			(xy 365.256728 -178.555535) (xy 365.308057 -178.577347) (xy 365.355663 -178.606401) (xy 365.398531 -178.642076)
			(xy 365.435748 -178.683613) (xy 365.466521 -178.730126) (xy 365.490193 -178.780623) (xy 365.506261 -178.83403)
			(xy 365.514381 -178.889206) (xy 365.51489 -178.917092) (xy 365.514381 -178.944978) (xy 365.506261 -179.000154)
			(xy 365.490193 -179.053561) (xy 365.466521 -179.104058) (xy 365.435748 -179.150571) (xy 365.398531 -179.192108)
			(xy 365.355663 -179.227783) (xy 365.308057 -179.256837) (xy 365.256728 -179.278649) (xy 365.202771 -179.292755)
			(xy 365.147334 -179.298855) (xy 365.0916 -179.296818) (xy 365.036757 -179.286688) (xy 364.983973 -179.268681)
			(xy 364.934373 -179.24318) (xy 364.889015 -179.210729) (xy 364.848866 -179.17202) (xy 364.81478 -179.127877)
			(xy 364.787484 -179.079242) (xy 364.767561 -179.027151) (xy 364.755435 -178.972714) (xy 364.751364 -178.917092)
			(xy 362.306108 -178.917092) (xy 362.306108 -179.67579) (xy 362.306396 -179.683665) (xy 362.311171 -179.698674)
			(xy 362.315506 -179.705254) (xy 362.321094 -179.713128) (xy 362.325541 -179.718925) (xy 362.337016 -179.727958)
			(xy 362.3437 -179.730908) (xy 362.368525 -179.741166) (xy 362.415258 -179.767647) (xy 362.457816 -179.80042)
			(xy 362.495357 -179.838837) (xy 362.52714 -179.882139) (xy 362.552536 -179.929471) (xy 362.571043 -179.979896)
			(xy 362.573804 -179.992782) (xy 363.22457 -179.992782) (xy 363.228641 -179.93716) (xy 363.240767 -179.882723)
			(xy 363.26069 -179.830632) (xy 363.287986 -179.781997) (xy 363.322072 -179.737854) (xy 363.362221 -179.699145)
			(xy 363.407579 -179.666694) (xy 363.457179 -179.641193) (xy 363.509963 -179.623186) (xy 363.564806 -179.613056)
			(xy 363.62054 -179.611019) (xy 363.675977 -179.617119) (xy 363.729934 -179.631225) (xy 363.781263 -179.653037)
			(xy 363.828869 -179.682091) (xy 363.871737 -179.717766) (xy 363.908954 -179.759303) (xy 363.939727 -179.805816)
			(xy 363.963399 -179.856313) (xy 363.979467 -179.90972) (xy 363.987587 -179.964896) (xy 363.988096 -179.992782)
			(xy 363.987587 -180.020668) (xy 363.979467 -180.075844) (xy 363.963399 -180.129251) (xy 363.939727 -180.179748)
			(xy 363.908954 -180.226261) (xy 363.871737 -180.267798) (xy 363.828869 -180.303473) (xy 363.781263 -180.332527)
			(xy 363.729934 -180.354339) (xy 363.675977 -180.368445) (xy 363.62054 -180.374545) (xy 363.564806 -180.372508)
			(xy 363.509963 -180.362378) (xy 363.457179 -180.344371) (xy 363.407579 -180.31887) (xy 363.362221 -180.286419)
			(xy 363.322072 -180.24771) (xy 363.287986 -180.203567) (xy 363.26069 -180.154932) (xy 363.240767 -180.102841)
			(xy 363.228641 -180.048404) (xy 363.22457 -179.992782) (xy 362.573804 -179.992782) (xy 362.582296 -180.032419)
			(xy 362.586072 -180.086) (xy 362.582296 -180.139581) (xy 362.571043 -180.192104) (xy 362.552536 -180.242529)
			(xy 362.52714 -180.289861) (xy 362.495357 -180.333163) (xy 362.457816 -180.37158) (xy 362.415258 -180.404353)
			(xy 362.368525 -180.430834) (xy 362.3437 -180.441092) (xy 362.336842 -180.443886) (xy 362.325412 -180.452776)
			(xy 362.315506 -180.466746) (xy 362.311186 -180.473333) (xy 362.306414 -180.488337) (xy 362.306108 -180.49621)
			(xy 362.306108 -180.69179) (xy 362.306396 -180.699665) (xy 362.311171 -180.714674) (xy 362.315506 -180.721254)
			(xy 362.321094 -180.729128) (xy 362.325541 -180.734925) (xy 362.337016 -180.743958) (xy 362.3437 -180.746908)
			(xy 362.368525 -180.757166) (xy 362.415258 -180.783647) (xy 362.457816 -180.81642) (xy 362.495357 -180.854837)
			(xy 362.52714 -180.898139) (xy 362.552536 -180.945471) (xy 362.571043 -180.995896) (xy 362.582296 -181.048419)
			(xy 362.58532 -181.091332) (xy 363.853982 -181.091332) (xy 363.858053 -181.03571) (xy 363.870179 -180.981273)
			(xy 363.890102 -180.929182) (xy 363.917398 -180.880547) (xy 363.951484 -180.836404) (xy 363.991633 -180.797695)
			(xy 364.036991 -180.765244) (xy 364.086591 -180.739743) (xy 364.139375 -180.721736) (xy 364.194218 -180.711606)
			(xy 364.249952 -180.709569) (xy 364.305389 -180.715669) (xy 364.359346 -180.729775) (xy 364.410675 -180.751587)
			(xy 364.458281 -180.780641) (xy 364.501149 -180.816316) (xy 364.538366 -180.857853) (xy 364.569139 -180.904366)
			(xy 364.592811 -180.954863) (xy 364.608879 -181.00827) (xy 364.616999 -181.063446) (xy 364.617508 -181.091332)
			(xy 364.616999 -181.119218) (xy 364.608879 -181.174394) (xy 364.592811 -181.227801) (xy 364.569139 -181.278298)
			(xy 364.538366 -181.324811) (xy 364.501149 -181.366348) (xy 364.458281 -181.402023) (xy 364.410675 -181.431077)
			(xy 364.359346 -181.452889) (xy 364.305389 -181.466995) (xy 364.249952 -181.473095) (xy 364.194218 -181.471058)
			(xy 364.139375 -181.460928) (xy 364.086591 -181.442921) (xy 364.036991 -181.41742) (xy 363.991633 -181.384969)
			(xy 363.951484 -181.34626) (xy 363.917398 -181.302117) (xy 363.890102 -181.253482) (xy 363.870179 -181.201391)
			(xy 363.858053 -181.146954) (xy 363.853982 -181.091332) (xy 362.58532 -181.091332) (xy 362.586072 -181.102)
			(xy 362.582296 -181.155581) (xy 362.571043 -181.208104) (xy 362.552536 -181.258529) (xy 362.52714 -181.305861)
			(xy 362.495357 -181.349163) (xy 362.457816 -181.38758) (xy 362.415258 -181.420353) (xy 362.368525 -181.446834)
			(xy 362.3437 -181.457092) (xy 362.336842 -181.459886) (xy 362.325412 -181.468776) (xy 362.315506 -181.482746)
			(xy 362.311186 -181.489333) (xy 362.306414 -181.504337) (xy 362.306108 -181.51221) (xy 362.306108 -181.740302)
			(xy 362.310088 -181.74538) (xy 362.320116 -181.753488) (xy 362.32592 -181.756304) (xy 362.333032 -181.758844)
			(xy 362.35878 -181.768607) (xy 362.407389 -181.79448) (xy 362.451775 -181.827071) (xy 362.491016 -181.865702)
			(xy 362.524297 -181.909572) (xy 362.550061 -181.956202) (xy 365.106202 -181.956202) (xy 365.110273 -181.90058)
			(xy 365.122399 -181.846143) (xy 365.142322 -181.794052) (xy 365.169618 -181.745417) (xy 365.203704 -181.701274)
			(xy 365.243853 -181.662565) (xy 365.289211 -181.630114) (xy 365.338811 -181.604613) (xy 365.391595 -181.586606)
			(xy 365.446438 -181.576476) (xy 365.502172 -181.574439) (xy 365.557609 -181.580539) (xy 365.611566 -181.594645)
			(xy 365.662895 -181.616457) (xy 365.710501 -181.645511) (xy 365.753369 -181.681186) (xy 365.790586 -181.722723)
			(xy 365.821359 -181.769236) (xy 365.845031 -181.819733) (xy 365.861099 -181.87314) (xy 365.869219 -181.928316)
			(xy 365.869728 -181.956202) (xy 365.869219 -181.984088) (xy 365.861099 -182.039264) (xy 365.845031 -182.092671)
			(xy 365.821359 -182.143168) (xy 365.790586 -182.189681) (xy 365.753369 -182.231218) (xy 365.710501 -182.266893)
			(xy 365.662895 -182.295947) (xy 365.611566 -182.317759) (xy 365.557609 -182.331865) (xy 365.502172 -182.337965)
			(xy 365.446438 -182.335928) (xy 365.391595 -182.325798) (xy 365.338811 -182.307791) (xy 365.289211 -182.28229)
			(xy 365.243853 -182.249839) (xy 365.203704 -182.21113) (xy 365.169618 -182.166987) (xy 365.142322 -182.118352)
			(xy 365.122399 -182.066261) (xy 365.110273 -182.011824) (xy 365.106202 -181.956202) (xy 362.550061 -181.956202)
			(xy 362.550927 -181.95777) (xy 362.570354 -182.009295) (xy 362.582174 -182.063077) (xy 362.586142 -182.118)
			(xy 362.582174 -182.172923) (xy 362.570354 -182.226705) (xy 362.550927 -182.27823) (xy 362.524297 -182.326428)
			(xy 362.491016 -182.370298) (xy 362.451775 -182.408929) (xy 362.407389 -182.44152) (xy 362.35878 -182.467393)
			(xy 362.333032 -182.477156) (xy 362.32592 -182.479696) (xy 362.320149 -182.482563) (xy 362.310132 -182.490664)
			(xy 362.306108 -182.495698) (xy 362.306108 -182.765192) (xy 367.038634 -182.765192) (xy 367.042705 -182.70957)
			(xy 367.054831 -182.655133) (xy 367.074754 -182.603042) (xy 367.10205 -182.554407) (xy 367.136136 -182.510264)
			(xy 367.176285 -182.471555) (xy 367.221643 -182.439104) (xy 367.271243 -182.413603) (xy 367.324027 -182.395596)
			(xy 367.37887 -182.385466) (xy 367.434604 -182.383429) (xy 367.490041 -182.389529) (xy 367.543998 -182.403635)
			(xy 367.595327 -182.425447) (xy 367.642933 -182.454501) (xy 367.685801 -182.490176) (xy 367.723018 -182.531713)
			(xy 367.753791 -182.578226) (xy 367.777463 -182.628723) (xy 367.780847 -182.63997) (xy 372.773956 -182.63997)
			(xy 372.774442 -182.611802) (xy 372.782745 -182.556081) (xy 372.79915 -182.502186) (xy 372.823301 -182.45129)
			(xy 372.854673 -182.404497) (xy 372.892584 -182.362826) (xy 372.936211 -182.327182) (xy 372.984604 -182.29834)
			(xy 373.036712 -182.276926) (xy 373.091402 -182.263408) (xy 373.119396 -182.26024) (xy 373.131694 -182.258468)
			(xy 373.152466 -182.244887) (xy 373.15902 -182.234332) (xy 373.19966 -182.160926) (xy 373.205036 -182.149786)
			(xy 373.205694 -182.125098) (xy 373.20093 -182.113682) (xy 373.200676 -182.113428) (xy 373.185891 -182.082825)
			(xy 373.162691 -182.018939) (xy 373.147053 -181.952795) (xy 373.139186 -181.885284) (xy 373.1387 -181.8513)
			(xy 373.1387 -180.186076) (xy 373.138314 -180.176002) (xy 373.130568 -180.157403) (xy 373.123714 -180.150008)
			(xy 372.954804 -179.981352) (xy 372.931891 -179.95777) (xy 372.890897 -179.906359) (xy 372.855911 -179.850686)
			(xy 372.827371 -179.791448) (xy 372.805635 -179.729391) (xy 372.790977 -179.665291) (xy 372.783581 -179.599955)
			(xy 372.7831 -179.567078) (xy 372.783636 -179.531666) (xy 372.792175 -179.461357) (xy 372.809126 -179.392591)
			(xy 372.834243 -179.326369) (xy 372.867157 -179.263657) (xy 372.907391 -179.20537) (xy 372.954357 -179.152357)
			(xy 373.00737 -179.105391) (xy 373.065657 -179.065157) (xy 373.128369 -179.032243) (xy 373.194591 -179.007126)
			(xy 373.263357 -178.990175) (xy 373.333666 -178.981636) (xy 373.369078 -178.9811) (xy 373.401959 -178.981554)
			(xy 373.467306 -178.988919) (xy 373.531417 -179.003558) (xy 373.593485 -179.025288) (xy 373.652727 -179.053834)
			(xy 373.708398 -179.088838) (xy 373.759797 -179.129858) (xy 373.783352 -179.152804) (xy 373.816626 -179.186078)
			(xy 373.824295 -179.193096) (xy 373.84357 -179.200832) (xy 373.853964 -179.201064) (xy 373.937784 -179.199032)
			(xy 373.95658 -179.190396) (xy 373.963438 -179.182776) (xy 373.987278 -179.157472) (xy 374.039935 -179.112077)
			(xy 374.097594 -179.073233) (xy 374.159446 -179.041486) (xy 374.22462 -179.017284) (xy 374.292201 -179.000965)
			(xy 374.361238 -178.99276) (xy 374.396 -178.992276) (xy 374.425843 -178.99262) (xy 374.485226 -178.998615)
			(xy 374.543693 -179.010614) (xy 374.572276 -179.0192) (xy 374.58396 -179.02301) (xy 374.607836 -179.018946)
			(xy 374.683782 -178.962812) (xy 374.693087 -178.955104) (xy 374.703811 -178.933483) (xy 374.704356 -178.92141)
			(xy 374.704356 -178.917092) (xy 374.704842 -178.889841) (xy 374.712598 -178.835893) (xy 374.727953 -178.783598)
			(xy 374.750595 -178.734021) (xy 374.780061 -178.688171) (xy 374.815752 -178.64698) (xy 374.856943 -178.611289)
			(xy 374.902793 -178.581823) (xy 374.95237 -178.559181) (xy 375.004665 -178.543826) (xy 375.058613 -178.53607)
			(xy 375.113115 -178.53607) (xy 375.167063 -178.543826) (xy 375.219358 -178.559181) (xy 375.268935 -178.581823)
			(xy 375.314785 -178.611289) (xy 375.355976 -178.64698) (xy 375.391667 -178.688171) (xy 375.421133 -178.734021)
			(xy 375.443775 -178.783598) (xy 375.45913 -178.835893) (xy 375.466886 -178.889841) (xy 375.467372 -178.917092)
			(xy 375.46682 -178.946196) (xy 375.457957 -179.003726) (xy 375.440466 -179.059245) (xy 375.414752 -179.111466)
			(xy 375.381411 -179.159181) (xy 375.341214 -179.201282) (xy 375.295094 -179.236796) (xy 375.244119 -179.264899)
			(xy 375.189469 -179.28494) (xy 375.161048 -179.291234) (xy 375.147078 -179.294028) (xy 375.126504 -179.31257)
			(xy 375.096532 -179.411884) (xy 375.094165 -179.42079) (xy 375.095334 -179.439167) (xy 375.102967 -179.455925)
			(xy 375.109232 -179.462684) (xy 375.445274 -179.798726) (xy 375.459243 -179.81298) (xy 375.485428 -179.843106)
			(xy 375.497598 -179.858924) (xy 375.503996 -179.866495) (xy 375.521124 -179.876431) (xy 375.530872 -179.878228)
			(xy 375.611644 -179.889912) (xy 375.631202 -179.884832) (xy 375.63933 -179.878736) (xy 375.664165 -179.860942)
			(xy 375.718336 -179.832693) (xy 375.776315 -179.813436) (xy 375.836622 -179.803665) (xy 375.867168 -179.803044)
			(xy 375.867676 -179.803044) (xy 375.894927 -179.803602) (xy 375.948873 -179.811355) (xy 376.001167 -179.826707)
			(xy 376.050744 -179.849345) (xy 376.096595 -179.878809) (xy 376.137785 -179.914498) (xy 376.173477 -179.955686)
			(xy 376.202943 -180.001535) (xy 376.225585 -180.05111) (xy 376.24094 -180.103403) (xy 376.248697 -180.157349)
			(xy 376.248697 -180.211851) (xy 376.24094 -180.265797) (xy 376.225585 -180.31809) (xy 376.202943 -180.367665)
			(xy 376.173477 -180.413514) (xy 376.137785 -180.454702) (xy 376.096595 -180.490391) (xy 376.050744 -180.519855)
			(xy 376.001167 -180.542493) (xy 375.948873 -180.557845) (xy 375.894927 -180.565598) (xy 375.867676 -180.56606)
			(xy 375.866914 -180.56606) (xy 375.837139 -180.565468) (xy 375.778321 -180.556154) (xy 375.74982 -180.547518)
			(xy 375.738136 -180.543708) (xy 375.714006 -180.547518) (xy 375.637806 -180.60289) (xy 375.62841 -180.610494)
			(xy 375.617397 -180.63197) (xy 375.616724 -180.644038) (xy 375.616724 -181.121304) (xy 375.617141 -181.131374)
			(xy 375.624867 -181.149972) (xy 375.63171 -181.157372) (xy 377.610878 -183.136286) (xy 377.633767 -183.15986)
			(xy 377.674731 -183.211235) (xy 377.709687 -183.266873) (xy 377.738194 -183.326075) (xy 377.759893 -183.388097)
			(xy 377.774512 -183.452157) (xy 377.781868 -183.517452) (xy 377.782328 -183.550306) (xy 377.782328 -185.322718)
			(xy 377.782831 -185.333647) (xy 377.791933 -185.353522) (xy 377.799854 -185.361072) (xy 377.857766 -185.411364)
			(xy 377.866332 -185.418149) (xy 377.887272 -185.424325) (xy 377.898152 -185.423302) (xy 377.898406 -185.423302)
			(xy 377.911733 -185.421524) (xy 377.938555 -185.419619) (xy 377.952 -185.419492) (xy 377.979251 -185.419978)
			(xy 378.033199 -185.427734) (xy 378.085494 -185.443089) (xy 378.135071 -185.465731) (xy 378.180921 -185.495197)
			(xy 378.222112 -185.530888) (xy 378.257803 -185.572079) (xy 378.287269 -185.617929) (xy 378.309911 -185.667506)
			(xy 378.325266 -185.719801) (xy 378.333022 -185.773749) (xy 378.333022 -185.828251) (xy 378.325266 -185.882199)
			(xy 378.309911 -185.934494) (xy 378.287269 -185.984071) (xy 378.257803 -186.029921) (xy 378.222112 -186.071112)
			(xy 378.180921 -186.106803) (xy 378.135071 -186.136269) (xy 378.085494 -186.158911) (xy 378.033199 -186.174266)
			(xy 377.979251 -186.182022) (xy 377.952 -186.182508) (xy 377.938555 -186.182392) (xy 377.911733 -186.180483)
			(xy 377.898406 -186.178698) (xy 377.898152 -186.178698) (xy 377.887275 -186.177689) (xy 377.866348 -186.183878)
			(xy 377.857766 -186.190636) (xy 377.799854 -186.240928) (xy 377.791952 -186.248492) (xy 377.782857 -186.268358)
			(xy 377.782328 -186.279282) (xy 377.782328 -187.421774) (xy 377.782676 -187.430822) (xy 377.788959 -187.447793)
			(xy 377.800752 -187.46152) (xy 377.80849 -187.466224) (xy 377.898406 -187.516262) (xy 377.925584 -187.5155)
			(xy 377.937268 -187.508388) (xy 377.959942 -187.494882) (xy 378.008241 -187.47361) (xy 378.059013 -187.459203)
			(xy 378.111286 -187.451934) (xy 378.137674 -187.451492) (xy 378.164928 -187.451954) (xy 378.218882 -187.459708)
			(xy 378.271183 -187.475061) (xy 378.320766 -187.497702) (xy 378.366623 -187.52717) (xy 378.407818 -187.562863)
			(xy 378.443515 -187.604057) (xy 378.472985 -187.649911) (xy 378.49563 -187.699493) (xy 378.510987 -187.751793)
			(xy 378.518745 -187.805746) (xy 378.518745 -187.860254) (xy 378.510987 -187.914207) (xy 378.49563 -187.966507)
			(xy 378.472985 -188.016089) (xy 378.443515 -188.061943) (xy 378.407818 -188.103137) (xy 378.366623 -188.13883)
			(xy 378.320766 -188.168298) (xy 378.271183 -188.190939) (xy 378.218882 -188.206292) (xy 378.164928 -188.214046)
			(xy 378.137674 -188.214508) (xy 378.107839 -188.213958) (xy 378.048898 -188.204651) (xy 377.992124 -188.186285)
			(xy 377.9389 -188.159307) (xy 377.890523 -188.124373) (xy 377.868942 -188.103764) (xy 377.86183 -188.096652)
			(xy 377.843288 -188.089032) (xy 377.833128 -188.089032) (xy 377.823105 -188.089443) (xy 377.804582 -188.09711)
			(xy 377.790408 -188.111286) (xy 377.782743 -188.129809) (xy 377.782328 -188.139832) (xy 377.782328 -188.143134)
			(xy 377.782729 -188.153206) (xy 377.790466 -188.171804) (xy 377.797314 -188.179202) (xy 378.63145 -189.013084)
			(xy 378.654333 -189.036663) (xy 378.695299 -189.088037) (xy 378.730255 -189.143674) (xy 378.758763 -189.202875)
			(xy 378.780464 -189.264896) (xy 378.795084 -189.328956) (xy 378.80244 -189.39425) (xy 378.8029 -189.427104)
			(xy 378.8029 -190.627) (xy 379.474982 -190.627) (xy 379.479053 -190.571378) (xy 379.491179 -190.516941)
			(xy 379.511102 -190.46485) (xy 379.538398 -190.416215) (xy 379.572484 -190.372072) (xy 379.612633 -190.333363)
			(xy 379.657991 -190.300912) (xy 379.707591 -190.275411) (xy 379.760375 -190.257404) (xy 379.815218 -190.247274)
			(xy 379.870952 -190.245237) (xy 379.926389 -190.251337) (xy 379.980346 -190.265443) (xy 380.031675 -190.287255)
			(xy 380.079281 -190.316309) (xy 380.122149 -190.351984) (xy 380.159366 -190.393521) (xy 380.190139 -190.440034)
			(xy 380.213811 -190.490531) (xy 380.229879 -190.543938) (xy 380.237999 -190.599114) (xy 380.238508 -190.627)
			(xy 380.237999 -190.654886) (xy 380.229879 -190.710062) (xy 380.213811 -190.763469) (xy 380.190139 -190.813966)
			(xy 380.159366 -190.860479) (xy 380.122149 -190.902016) (xy 380.079281 -190.937691) (xy 380.031675 -190.966745)
			(xy 379.980346 -190.988557) (xy 379.926389 -191.002663) (xy 379.870952 -191.008763) (xy 379.815218 -191.006726)
			(xy 379.760375 -190.996596) (xy 379.707591 -190.978589) (xy 379.657991 -190.953088) (xy 379.612633 -190.920637)
			(xy 379.572484 -190.881928) (xy 379.538398 -190.837785) (xy 379.511102 -190.78915) (xy 379.491179 -190.737059)
			(xy 379.479053 -190.682622) (xy 379.474982 -190.627) (xy 378.8029 -190.627) (xy 378.8029 -194.31)
			(xy 379.761748 -194.31) (xy 379.765819 -194.254378) (xy 379.777945 -194.199941) (xy 379.797868 -194.14785)
			(xy 379.825164 -194.099215) (xy 379.85925 -194.055072) (xy 379.899399 -194.016363) (xy 379.944757 -193.983912)
			(xy 379.994357 -193.958411) (xy 380.047141 -193.940404) (xy 380.101984 -193.930274) (xy 380.157718 -193.928237)
			(xy 380.213155 -193.934337) (xy 380.267112 -193.948443) (xy 380.318441 -193.970255) (xy 380.366047 -193.999309)
			(xy 380.408915 -194.034984) (xy 380.446132 -194.076521) (xy 380.476905 -194.123034) (xy 380.500577 -194.173531)
			(xy 380.516645 -194.226938) (xy 380.524765 -194.282114) (xy 380.525274 -194.31) (xy 380.524765 -194.337886)
			(xy 380.516645 -194.393062) (xy 380.500577 -194.446469) (xy 380.476905 -194.496966) (xy 380.446132 -194.543479)
			(xy 380.408915 -194.585016) (xy 380.366047 -194.620691) (xy 380.318441 -194.649745) (xy 380.267112 -194.671557)
			(xy 380.213155 -194.685663) (xy 380.157718 -194.691763) (xy 380.101984 -194.689726) (xy 380.047141 -194.679596)
			(xy 379.994357 -194.661589) (xy 379.944757 -194.636088) (xy 379.899399 -194.603637) (xy 379.85925 -194.564928)
			(xy 379.825164 -194.520785) (xy 379.797868 -194.47215) (xy 379.777945 -194.420059) (xy 379.765819 -194.365622)
			(xy 379.761748 -194.31) (xy 378.8029 -194.31) (xy 378.8029 -196.342) (xy 379.808738 -196.342) (xy 379.812809 -196.286378)
			(xy 379.824935 -196.231941) (xy 379.844858 -196.17985) (xy 379.872154 -196.131215) (xy 379.90624 -196.087072)
			(xy 379.946389 -196.048363) (xy 379.991747 -196.015912) (xy 380.041347 -195.990411) (xy 380.094131 -195.972404)
			(xy 380.148974 -195.962274) (xy 380.204708 -195.960237) (xy 380.260145 -195.966337) (xy 380.314102 -195.980443)
			(xy 380.365431 -196.002255) (xy 380.413037 -196.031309) (xy 380.455905 -196.066984) (xy 380.493122 -196.108521)
			(xy 380.523895 -196.155034) (xy 380.547567 -196.205531) (xy 380.563635 -196.258938) (xy 380.571755 -196.314114)
			(xy 380.572264 -196.342) (xy 380.571755 -196.369886) (xy 380.563635 -196.425062) (xy 380.547567 -196.478469)
			(xy 380.523895 -196.528966) (xy 380.493122 -196.575479) (xy 380.455905 -196.617016) (xy 380.413037 -196.652691)
			(xy 380.365431 -196.681745) (xy 380.314102 -196.703557) (xy 380.260145 -196.717663) (xy 380.204708 -196.723763)
			(xy 380.148974 -196.721726) (xy 380.094131 -196.711596) (xy 380.041347 -196.693589) (xy 379.991747 -196.668088)
			(xy 379.946389 -196.635637) (xy 379.90624 -196.596928) (xy 379.872154 -196.552785) (xy 379.844858 -196.50415)
			(xy 379.824935 -196.452059) (xy 379.812809 -196.397622) (xy 379.808738 -196.342) (xy 378.8029 -196.342)
			(xy 378.8029 -197.335394) (xy 378.916436 -197.335394) (xy 378.920507 -197.279772) (xy 378.932633 -197.225335)
			(xy 378.952556 -197.173244) (xy 378.979852 -197.124609) (xy 379.013938 -197.080466) (xy 379.054087 -197.041757)
			(xy 379.099445 -197.009306) (xy 379.149045 -196.983805) (xy 379.201829 -196.965798) (xy 379.256672 -196.955668)
			(xy 379.312406 -196.953631) (xy 379.367843 -196.959731) (xy 379.4218 -196.973837) (xy 379.473129 -196.995649)
			(xy 379.520735 -197.024703) (xy 379.563603 -197.060378) (xy 379.60082 -197.101915) (xy 379.631593 -197.148428)
			(xy 379.655265 -197.198925) (xy 379.671333 -197.252332) (xy 379.679453 -197.307508) (xy 379.679962 -197.335394)
			(xy 379.679549 -197.358) (xy 379.795784 -197.358) (xy 379.799855 -197.302378) (xy 379.811981 -197.247941)
			(xy 379.831904 -197.19585) (xy 379.8592 -197.147215) (xy 379.893286 -197.103072) (xy 379.933435 -197.064363)
			(xy 379.978793 -197.031912) (xy 380.028393 -197.006411) (xy 380.081177 -196.988404) (xy 380.13602 -196.978274)
			(xy 380.191754 -196.976237) (xy 380.247191 -196.982337) (xy 380.301148 -196.996443) (xy 380.352477 -197.018255)
			(xy 380.400083 -197.047309) (xy 380.442951 -197.082984) (xy 380.480168 -197.124521) (xy 380.510941 -197.171034)
			(xy 380.534613 -197.221531) (xy 380.550681 -197.274938) (xy 380.558801 -197.330114) (xy 380.55931 -197.358)
			(xy 380.558801 -197.385886) (xy 380.550681 -197.441062) (xy 380.534613 -197.494469) (xy 380.510941 -197.544966)
			(xy 380.480168 -197.591479) (xy 380.442951 -197.633016) (xy 380.400083 -197.668691) (xy 380.352477 -197.697745)
			(xy 380.301148 -197.719557) (xy 380.247191 -197.733663) (xy 380.191754 -197.739763) (xy 380.13602 -197.737726)
			(xy 380.081177 -197.727596) (xy 380.028393 -197.709589) (xy 379.978793 -197.684088) (xy 379.933435 -197.651637)
			(xy 379.893286 -197.612928) (xy 379.8592 -197.568785) (xy 379.831904 -197.52015) (xy 379.811981 -197.468059)
			(xy 379.799855 -197.413622) (xy 379.795784 -197.358) (xy 379.679549 -197.358) (xy 379.679453 -197.36328)
			(xy 379.671333 -197.418456) (xy 379.655265 -197.471863) (xy 379.631593 -197.52236) (xy 379.60082 -197.568873)
			(xy 379.563603 -197.61041) (xy 379.520735 -197.646085) (xy 379.473129 -197.675139) (xy 379.4218 -197.696951)
			(xy 379.367843 -197.711057) (xy 379.312406 -197.717157) (xy 379.256672 -197.71512) (xy 379.201829 -197.70499)
			(xy 379.149045 -197.686983) (xy 379.099445 -197.661482) (xy 379.054087 -197.629031) (xy 379.013938 -197.590322)
			(xy 378.979852 -197.546179) (xy 378.952556 -197.497544) (xy 378.932633 -197.445453) (xy 378.920507 -197.391016)
			(xy 378.916436 -197.335394) (xy 378.8029 -197.335394) (xy 378.8029 -198.374) (xy 379.855982 -198.374)
			(xy 379.860053 -198.318378) (xy 379.872179 -198.263941) (xy 379.892102 -198.21185) (xy 379.919398 -198.163215)
			(xy 379.953484 -198.119072) (xy 379.993633 -198.080363) (xy 380.038991 -198.047912) (xy 380.088591 -198.022411)
			(xy 380.141375 -198.004404) (xy 380.196218 -197.994274) (xy 380.251952 -197.992237) (xy 380.307389 -197.998337)
			(xy 380.361346 -198.012443) (xy 380.412675 -198.034255) (xy 380.460281 -198.063309) (xy 380.503149 -198.098984)
			(xy 380.540366 -198.140521) (xy 380.571139 -198.187034) (xy 380.594811 -198.237531) (xy 380.610879 -198.290938)
			(xy 380.618999 -198.346114) (xy 380.619508 -198.374) (xy 380.618999 -198.401886) (xy 380.610879 -198.457062)
			(xy 380.594811 -198.510469) (xy 380.571139 -198.560966) (xy 380.540366 -198.607479) (xy 380.503149 -198.649016)
			(xy 380.460281 -198.684691) (xy 380.412675 -198.713745) (xy 380.361346 -198.735557) (xy 380.307389 -198.749663)
			(xy 380.251952 -198.755763) (xy 380.196218 -198.753726) (xy 380.141375 -198.743596) (xy 380.088591 -198.725589)
			(xy 380.038991 -198.700088) (xy 379.993633 -198.667637) (xy 379.953484 -198.628928) (xy 379.919398 -198.584785)
			(xy 379.892102 -198.53615) (xy 379.872179 -198.484059) (xy 379.860053 -198.429622) (xy 379.855982 -198.374)
			(xy 378.8029 -198.374) (xy 378.8029 -199.39) (xy 379.794006 -199.39) (xy 379.798077 -199.334378)
			(xy 379.810203 -199.279941) (xy 379.830126 -199.22785) (xy 379.857422 -199.179215) (xy 379.891508 -199.135072)
			(xy 379.931657 -199.096363) (xy 379.977015 -199.063912) (xy 380.026615 -199.038411) (xy 380.079399 -199.020404)
			(xy 380.134242 -199.010274) (xy 380.189976 -199.008237) (xy 380.245413 -199.014337) (xy 380.29937 -199.028443)
			(xy 380.350699 -199.050255) (xy 380.398305 -199.079309) (xy 380.441173 -199.114984) (xy 380.47839 -199.156521)
			(xy 380.509163 -199.203034) (xy 380.532835 -199.253531) (xy 380.548903 -199.306938) (xy 380.557023 -199.362114)
			(xy 380.557532 -199.39) (xy 380.557023 -199.417886) (xy 380.548903 -199.473062) (xy 380.532835 -199.526469)
			(xy 380.509163 -199.576966) (xy 380.47839 -199.623479) (xy 380.441173 -199.665016) (xy 380.398305 -199.700691)
			(xy 380.350699 -199.729745) (xy 380.29937 -199.751557) (xy 380.245413 -199.765663) (xy 380.189976 -199.771763)
			(xy 380.134242 -199.769726) (xy 380.079399 -199.759596) (xy 380.026615 -199.741589) (xy 379.977015 -199.716088)
			(xy 379.931657 -199.683637) (xy 379.891508 -199.644928) (xy 379.857422 -199.600785) (xy 379.830126 -199.55215)
			(xy 379.810203 -199.500059) (xy 379.798077 -199.445622) (xy 379.794006 -199.39) (xy 378.8029 -199.39)
			(xy 378.8029 -199.899524) (xy 378.803286 -199.909598) (xy 378.811032 -199.928197) (xy 378.817886 -199.935592)
			(xy 378.982085 -200.099676) (xy 380.524764 -200.099676) (xy 380.528835 -200.044054) (xy 380.540961 -199.989617)
			(xy 380.560884 -199.937526) (xy 380.58818 -199.888891) (xy 380.622266 -199.844748) (xy 380.662415 -199.806039)
			(xy 380.707773 -199.773588) (xy 380.757373 -199.748087) (xy 380.810157 -199.73008) (xy 380.865 -199.71995)
			(xy 380.920734 -199.717913) (xy 380.976171 -199.724013) (xy 381.030128 -199.738119) (xy 381.081457 -199.759931)
			(xy 381.129063 -199.788985) (xy 381.171931 -199.82466) (xy 381.209148 -199.866197) (xy 381.239921 -199.91271)
			(xy 381.263593 -199.963207) (xy 381.279661 -200.016614) (xy 381.287781 -200.07179) (xy 381.28829 -200.099676)
			(xy 381.287781 -200.127562) (xy 381.279661 -200.182738) (xy 381.263593 -200.236145) (xy 381.239921 -200.286642)
			(xy 381.209148 -200.333155) (xy 381.171931 -200.374692) (xy 381.129063 -200.410367) (xy 381.081457 -200.439421)
			(xy 381.030128 -200.461233) (xy 380.976171 -200.475339) (xy 380.920734 -200.481439) (xy 380.865 -200.479402)
			(xy 380.810157 -200.469272) (xy 380.757373 -200.451265) (xy 380.707773 -200.425764) (xy 380.662415 -200.393313)
			(xy 380.622266 -200.354604) (xy 380.58818 -200.310461) (xy 380.560884 -200.261826) (xy 380.540961 -200.209735)
			(xy 380.528835 -200.155298) (xy 380.524764 -200.099676) (xy 378.982085 -200.099676) (xy 379.180598 -200.29805)
			(xy 379.21311 -200.30313) (xy 379.228096 -200.29551) (xy 379.255407 -200.282003) (xy 379.313252 -200.262874)
			(xy 379.373401 -200.253183) (xy 379.403864 -200.252584) (xy 379.431116 -200.253089) (xy 379.485065 -200.260841)
			(xy 379.537361 -200.276192) (xy 379.586941 -200.298829) (xy 379.632794 -200.328293) (xy 379.673986 -200.363982)
			(xy 379.709681 -200.405171) (xy 379.739149 -200.451021) (xy 379.761793 -200.500597) (xy 379.77715 -200.552892)
			(xy 379.784908 -200.60684) (xy 379.785372 -200.634092) (xy 379.784799 -200.664556) (xy 379.775106 -200.724709)
			(xy 379.755966 -200.782553) (xy 379.742446 -200.80986) (xy 379.738002 -200.819622) (xy 379.736822 -200.841017)
			(xy 379.744436 -200.861047) (xy 379.75159 -200.869042) (xy 380.187454 -201.304906) (xy 380.210348 -201.328475)
			(xy 380.251313 -201.37985) (xy 380.286268 -201.435489) (xy 380.314775 -201.494692) (xy 380.336473 -201.556715)
			(xy 380.351091 -201.620776) (xy 380.358445 -201.686072) (xy 380.358904 -201.718926) (xy 380.358904 -202.35418)
			(xy 380.358392 -202.389579) (xy 380.357324 -202.398376) (xy 381.759712 -202.398376) (xy 381.763783 -202.342754)
			(xy 381.775909 -202.288317) (xy 381.795832 -202.236226) (xy 381.823128 -202.187591) (xy 381.857214 -202.143448)
			(xy 381.897363 -202.104739) (xy 381.942721 -202.072288) (xy 381.992321 -202.046787) (xy 382.045105 -202.02878)
			(xy 382.099948 -202.01865) (xy 382.155682 -202.016613) (xy 382.211119 -202.022713) (xy 382.265076 -202.036819)
			(xy 382.316405 -202.058631) (xy 382.364011 -202.087685) (xy 382.406879 -202.12336) (xy 382.444096 -202.164897)
			(xy 382.474869 -202.21141) (xy 382.498541 -202.261907) (xy 382.514609 -202.315314) (xy 382.522729 -202.37049)
			(xy 382.523238 -202.398376) (xy 382.522729 -202.426262) (xy 382.514609 -202.481438) (xy 382.498541 -202.534845)
			(xy 382.474869 -202.585342) (xy 382.444096 -202.631855) (xy 382.406879 -202.673392) (xy 382.364011 -202.709067)
			(xy 382.316405 -202.738121) (xy 382.265076 -202.759933) (xy 382.211119 -202.774039) (xy 382.155682 -202.780139)
			(xy 382.099948 -202.778102) (xy 382.045105 -202.767972) (xy 381.992321 -202.749965) (xy 381.942721 -202.724464)
			(xy 381.897363 -202.692013) (xy 381.857214 -202.653304) (xy 381.823128 -202.609161) (xy 381.795832 -202.560526)
			(xy 381.775909 -202.508435) (xy 381.763783 -202.453998) (xy 381.759712 -202.398376) (xy 380.357324 -202.398376)
			(xy 380.34986 -202.459861) (xy 380.332919 -202.528603) (xy 380.307815 -202.5948) (xy 380.274914 -202.657489)
			(xy 380.234696 -202.715755) (xy 380.187749 -202.768749) (xy 380.134755 -202.815696) (xy 380.076489 -202.855914)
			(xy 380.0138 -202.888815) (xy 379.947603 -202.913919) (xy 379.878861 -202.93086) (xy 379.808579 -202.939392)
			(xy 379.77318 -202.939904) (xy 379.736298 -202.939309) (xy 379.663118 -202.930051) (xy 379.591678 -202.911682)
			(xy 379.523108 -202.884495) (xy 379.458491 -202.848917) (xy 379.398849 -202.805513) (xy 379.371606 -202.780646)
			(xy 379.364471 -202.774597) (xy 379.347152 -202.767579) (xy 379.328468 -202.767206) (xy 379.319536 -202.769978)
			(xy 379.220222 -202.8063) (xy 379.202442 -202.828906) (xy 379.200918 -202.84313) (xy 379.197284 -202.870707)
			(xy 379.183046 -202.924475) (xy 379.161148 -202.975604) (xy 379.132055 -203.023011) (xy 379.096384 -203.065687)
			(xy 379.054892 -203.10273) (xy 379.008458 -203.133351) (xy 378.958069 -203.156903) (xy 378.904793 -203.172885)
			(xy 378.849761 -203.180958) (xy 378.82195 -203.181458) (xy 378.794705 -203.180868) (xy 378.74077 -203.173107)
			(xy 378.688488 -203.15775) (xy 378.638923 -203.135109) (xy 378.593085 -203.105645) (xy 378.551906 -203.069958)
			(xy 378.516225 -203.028775) (xy 378.486767 -202.982933) (xy 378.464133 -202.933365) (xy 378.448782 -202.881082)
			(xy 378.441028 -202.827145) (xy 378.441028 -202.772655) (xy 378.448782 -202.718718) (xy 378.464133 -202.666435)
			(xy 378.486767 -202.616867) (xy 378.516225 -202.571025) (xy 378.551906 -202.529842) (xy 378.593085 -202.494155)
			(xy 378.638923 -202.464691) (xy 378.688488 -202.44205) (xy 378.74077 -202.426693) (xy 378.794705 -202.418932)
			(xy 378.82195 -202.418442) (xy 378.849652 -202.418958) (xy 378.904474 -202.42696) (xy 378.957564 -202.442804)
			(xy 379.007806 -202.466155) (xy 379.031246 -202.480926) (xy 379.043438 -202.489054) (xy 379.071886 -202.489816)
			(xy 379.163326 -202.436984) (xy 379.17119 -202.431862) (xy 379.182915 -202.417237) (xy 379.188604 -202.399375)
			(xy 379.188472 -202.389994) (xy 379.187456 -202.35418) (xy 379.187456 -201.982832) (xy 379.187025 -201.972763)
			(xy 379.17931 -201.954165) (xy 379.17247 -201.946764) (xy 378.985018 -201.759312) (xy 378.976643 -201.751849)
			(xy 378.955568 -201.744252) (xy 378.93326 -201.746289) (xy 378.923296 -201.751438) (xy 378.901211 -201.763963)
			(xy 378.854432 -201.783697) (xy 378.805452 -201.797065) (xy 378.755133 -201.803832) (xy 378.729748 -201.80427)
			(xy 378.702495 -201.8038) (xy 378.648542 -201.796049) (xy 378.596242 -201.780697) (xy 378.546659 -201.758057)
			(xy 378.500804 -201.72859) (xy 378.45961 -201.692897) (xy 378.423916 -201.651704) (xy 378.394448 -201.605849)
			(xy 378.371807 -201.556268) (xy 378.356454 -201.503968) (xy 378.348701 -201.450015) (xy 378.34824 -201.422762)
			(xy 378.34867 -201.397406) (xy 378.355432 -201.347147) (xy 378.368803 -201.298229) (xy 378.388548 -201.251519)
			(xy 378.401072 -201.229468) (xy 378.406289 -201.219509) (xy 378.408424 -201.197162) (xy 378.400763 -201.17606)
			(xy 378.393198 -201.167746) (xy 378.348494 -201.123042) (xy 378.318522 -201.1172) (xy 378.304298 -201.123042)
			(xy 378.295273 -201.127371) (xy 378.281182 -201.141555) (xy 378.273548 -201.160035) (xy 378.273056 -201.170032)
			(xy 378.273056 -201.284078) (xy 378.27256 -201.318178) (xy 378.264643 -201.385918) (xy 378.248914 -201.452281)
			(xy 378.225588 -201.516369) (xy 378.19498 -201.577315) (xy 378.157503 -201.634296) (xy 378.113664 -201.686541)
			(xy 378.064057 -201.733344) (xy 378.009351 -201.77407) (xy 377.950287 -201.808171) (xy 377.887664 -201.835184)
			(xy 377.822328 -201.854744) (xy 377.755164 -201.866587) (xy 377.687078 -201.870553) (xy 377.618992 -201.866587)
			(xy 377.551828 -201.854744) (xy 377.486492 -201.835184) (xy 377.423869 -201.808171) (xy 377.364805 -201.77407)
			(xy 377.310099 -201.733344) (xy 377.260492 -201.686541) (xy 377.216653 -201.634296) (xy 377.179176 -201.577315)
			(xy 377.148568 -201.516369) (xy 377.125242 -201.452281) (xy 377.109513 -201.385918) (xy 377.101596 -201.318178)
			(xy 377.1011 -201.284078) (xy 377.1011 -190.162434) (xy 377.100683 -190.152363) (xy 377.092959 -190.133764)
			(xy 377.086114 -190.126366) (xy 376.244358 -189.28461) (xy 376.227185 -189.267069) (xy 376.195521 -189.229553)
			(xy 376.181112 -189.20968) (xy 376.181112 -189.209426) (xy 376.175307 -189.202075) (xy 376.159681 -189.191777)
			(xy 376.150632 -189.18936) (xy 376.074686 -189.172596) (xy 376.056398 -189.17539) (xy 376.048016 -189.180216)
			(xy 376.026332 -189.19218) (xy 375.980521 -189.210995) (xy 375.932657 -189.223713) (xy 375.883548 -189.230119)
			(xy 375.858786 -189.230508) (xy 375.831535 -189.230021) (xy 375.777589 -189.222263) (xy 375.725296 -189.206907)
			(xy 375.675721 -189.184265) (xy 375.629872 -189.154798) (xy 375.588683 -189.119107) (xy 375.552993 -189.077917)
			(xy 375.523528 -189.032067) (xy 375.500888 -188.982491) (xy 375.485534 -188.930197) (xy 375.477778 -188.876251)
			(xy 375.477778 -188.821749) (xy 375.485534 -188.767803) (xy 375.500888 -188.715509) (xy 375.523528 -188.665933)
			(xy 375.552993 -188.620083) (xy 375.588683 -188.578893) (xy 375.629872 -188.543202) (xy 375.675721 -188.513735)
			(xy 375.725296 -188.491093) (xy 375.777589 -188.475737) (xy 375.831535 -188.467979) (xy 375.858786 -188.467492)
			(xy 375.85904 -188.467492) (xy 375.881349 -188.467801) (xy 375.925661 -188.473026) (xy 375.947432 -188.477906)
			(xy 375.958803 -188.480172) (xy 375.98144 -188.475262) (xy 375.990866 -188.468508) (xy 376.053604 -188.418978)
			(xy 376.062324 -188.411408) (xy 376.072366 -188.390636) (xy 376.072908 -188.3791) (xy 376.072908 -188.313314)
			(xy 376.07251 -188.302587) (xy 376.063811 -188.282982) (xy 376.056144 -188.275468) (xy 375.991628 -188.21781)
			(xy 375.971308 -188.211206) (xy 375.960386 -188.212476) (xy 375.950318 -188.213452) (xy 375.930115 -188.214469)
			(xy 375.92 -188.214508) (xy 375.892749 -188.214022) (xy 375.838801 -188.206266) (xy 375.786506 -188.190911)
			(xy 375.736929 -188.168269) (xy 375.691079 -188.138803) (xy 375.649888 -188.103112) (xy 375.614197 -188.061921)
			(xy 375.584731 -188.016071) (xy 375.562089 -187.966494) (xy 375.546734 -187.914199) (xy 375.538978 -187.860251)
			(xy 375.538978 -187.805749) (xy 375.546734 -187.751801) (xy 375.562089 -187.699506) (xy 375.584731 -187.649929)
			(xy 375.614197 -187.604079) (xy 375.649888 -187.562888) (xy 375.691079 -187.527197) (xy 375.736929 -187.497731)
			(xy 375.786506 -187.475089) (xy 375.838801 -187.459734) (xy 375.892749 -187.451978) (xy 375.92 -187.451492)
			(xy 375.930115 -187.451529) (xy 375.950319 -187.452546) (xy 375.960386 -187.453524) (xy 375.971308 -187.454794)
			(xy 375.991628 -187.44819) (xy 376.056144 -187.390532) (xy 376.063703 -187.382948) (xy 376.072352 -187.363381)
			(xy 376.072908 -187.352686) (xy 376.072908 -187.279788) (xy 376.072262 -187.267907) (xy 376.061522 -187.246709)
			(xy 376.052334 -187.239148) (xy 375.977404 -187.183268) (xy 375.953528 -187.17895) (xy 375.942098 -187.182506)
			(xy 375.915414 -187.189984) (xy 375.860585 -187.198015) (xy 375.832878 -187.198508) (xy 375.805628 -187.198021)
			(xy 375.751682 -187.190262) (xy 375.69939 -187.174905) (xy 375.649816 -187.152262) (xy 375.603968 -187.122795)
			(xy 375.562781 -187.087104) (xy 375.527091 -187.045914) (xy 375.497627 -187.000065) (xy 375.474988 -186.950489)
			(xy 375.459634 -186.898196) (xy 375.451878 -186.84425) (xy 375.451878 -186.78975) (xy 375.459634 -186.735804)
			(xy 375.474988 -186.683511) (xy 375.497627 -186.633935) (xy 375.527091 -186.588086) (xy 375.562781 -186.546896)
			(xy 375.603968 -186.511205) (xy 375.649816 -186.481738) (xy 375.69939 -186.459095) (xy 375.751682 -186.443738)
			(xy 375.805628 -186.435979) (xy 375.832878 -186.435492) (xy 375.860584 -186.435996) (xy 375.91541 -186.444035)
			(xy 375.942098 -186.451494) (xy 375.953528 -186.45505) (xy 375.977404 -186.450732) (xy 376.052334 -186.394852)
			(xy 376.061488 -186.387264) (xy 376.072219 -186.366081) (xy 376.072908 -186.354212) (xy 376.072908 -186.281314)
			(xy 376.07251 -186.270587) (xy 376.063811 -186.250982) (xy 376.056144 -186.243468) (xy 375.991628 -186.18581)
			(xy 375.971308 -186.179206) (xy 375.960386 -186.180476) (xy 375.950318 -186.181452) (xy 375.930115 -186.182469)
			(xy 375.92 -186.182508) (xy 375.892749 -186.182022) (xy 375.838801 -186.174266) (xy 375.786506 -186.158911)
			(xy 375.736929 -186.136269) (xy 375.691079 -186.106803) (xy 375.649888 -186.071112) (xy 375.614197 -186.029921)
			(xy 375.584731 -185.984071) (xy 375.562089 -185.934494) (xy 375.546734 -185.882199) (xy 375.538978 -185.828251)
			(xy 375.538978 -185.773749) (xy 375.546734 -185.719801) (xy 375.562089 -185.667506) (xy 375.584731 -185.617929)
			(xy 375.614197 -185.572079) (xy 375.649888 -185.530888) (xy 375.691079 -185.495197) (xy 375.736929 -185.465731)
			(xy 375.786506 -185.443089) (xy 375.838801 -185.427734) (xy 375.892749 -185.419978) (xy 375.92 -185.419492)
			(xy 375.930115 -185.419529) (xy 375.950319 -185.420546) (xy 375.960386 -185.421524) (xy 375.971308 -185.422794)
			(xy 375.991628 -185.41619) (xy 376.056144 -185.358532) (xy 376.063703 -185.350948) (xy 376.072352 -185.331381)
			(xy 376.072908 -185.320686) (xy 376.072908 -184.435496) (xy 376.072509 -184.425423) (xy 376.064773 -184.406824)
			(xy 376.057922 -184.399428) (xy 376.01652 -184.358026) (xy 376.009104 -184.351206) (xy 375.990517 -184.343474)
			(xy 375.980452 -184.34304) (xy 375.63044 -184.34304) (xy 375.597586 -184.34259) (xy 375.532293 -184.335221)
			(xy 375.468235 -184.320594) (xy 375.406214 -184.298893) (xy 375.347011 -184.270389) (xy 375.291368 -184.235441)
			(xy 375.239985 -184.194487) (xy 375.21642 -184.17159) (xy 373.702072 -182.657242) (xy 373.695286 -182.651039)
			(xy 373.678505 -182.643558) (xy 373.660164 -182.642456) (xy 373.651272 -182.644796) (xy 373.551704 -182.67553)
			(xy 373.532908 -182.696612) (xy 373.530368 -182.710328) (xy 373.525046 -182.736226) (xy 373.508226 -182.786348)
			(xy 373.484644 -182.833667) (xy 373.454753 -182.877276) (xy 373.419124 -182.916337) (xy 373.378441 -182.950103)
			(xy 373.333485 -182.977925) (xy 373.285116 -182.999272) (xy 373.234262 -183.013732) (xy 373.181899 -183.02103)
			(xy 373.155464 -183.021478) (xy 373.12821 -183.021056) (xy 373.074259 -183.013293) (xy 373.021961 -182.997932)
			(xy 372.972382 -182.975285) (xy 372.92653 -182.945812) (xy 372.88534 -182.910114) (xy 372.849649 -182.868917)
			(xy 372.820184 -182.82306) (xy 372.797545 -182.773477) (xy 372.782193 -182.721176) (xy 372.77444 -182.667224)
			(xy 372.773956 -182.63997) (xy 367.780847 -182.63997) (xy 367.793531 -182.68213) (xy 367.801651 -182.737306)
			(xy 367.80216 -182.765192) (xy 367.801651 -182.793078) (xy 367.793531 -182.848254) (xy 367.777463 -182.901661)
			(xy 367.753791 -182.952158) (xy 367.723018 -182.998671) (xy 367.685801 -183.040208) (xy 367.642933 -183.075883)
			(xy 367.595327 -183.104937) (xy 367.543998 -183.126749) (xy 367.490041 -183.140855) (xy 367.434604 -183.146955)
			(xy 367.37887 -183.144918) (xy 367.324027 -183.134788) (xy 367.271243 -183.116781) (xy 367.221643 -183.09128)
			(xy 367.176285 -183.058829) (xy 367.136136 -183.02012) (xy 367.10205 -182.975977) (xy 367.074754 -182.927342)
			(xy 367.054831 -182.875251) (xy 367.042705 -182.820814) (xy 367.038634 -182.765192) (xy 362.306108 -182.765192)
			(xy 362.306108 -185.166) (xy 362.583982 -185.166) (xy 362.588053 -185.110378) (xy 362.600179 -185.055941)
			(xy 362.620102 -185.00385) (xy 362.647398 -184.955215) (xy 362.681484 -184.911072) (xy 362.721633 -184.872363)
			(xy 362.766991 -184.839912) (xy 362.816591 -184.814411) (xy 362.869375 -184.796404) (xy 362.924218 -184.786274)
			(xy 362.979952 -184.784237) (xy 363.035389 -184.790337) (xy 363.089346 -184.804443) (xy 363.140675 -184.826255)
			(xy 363.188281 -184.855309) (xy 363.231149 -184.890984) (xy 363.268366 -184.932521) (xy 363.299139 -184.979034)
			(xy 363.322811 -185.029531) (xy 363.338879 -185.082938) (xy 363.346999 -185.138114) (xy 363.347508 -185.166)
			(xy 363.346999 -185.193886) (xy 363.338879 -185.249062) (xy 363.322811 -185.302469) (xy 363.299139 -185.352966)
			(xy 363.268366 -185.399479) (xy 363.231149 -185.441016) (xy 363.188281 -185.476691) (xy 363.140675 -185.505745)
			(xy 363.089346 -185.527557) (xy 363.035389 -185.541663) (xy 362.979952 -185.547763) (xy 362.924218 -185.545726)
			(xy 362.869375 -185.535596) (xy 362.816591 -185.517589) (xy 362.766991 -185.492088) (xy 362.721633 -185.459637)
			(xy 362.681484 -185.420928) (xy 362.647398 -185.376785) (xy 362.620102 -185.32815) (xy 362.600179 -185.276059)
			(xy 362.588053 -185.221622) (xy 362.583982 -185.166) (xy 362.306108 -185.166) (xy 362.306108 -185.671968)
			(xy 364.803434 -185.671968) (xy 364.807505 -185.616346) (xy 364.819631 -185.561909) (xy 364.839554 -185.509818)
			(xy 364.86685 -185.461183) (xy 364.900936 -185.41704) (xy 364.941085 -185.378331) (xy 364.986443 -185.34588)
			(xy 365.036043 -185.320379) (xy 365.088827 -185.302372) (xy 365.14367 -185.292242) (xy 365.199404 -185.290205)
			(xy 365.254841 -185.296305) (xy 365.308798 -185.310411) (xy 365.360127 -185.332223) (xy 365.407733 -185.361277)
			(xy 365.450601 -185.396952) (xy 365.487818 -185.438489) (xy 365.518591 -185.485002) (xy 365.542263 -185.535499)
			(xy 365.558331 -185.588906) (xy 365.560948 -185.60669) (xy 367.120422 -185.60669) (xy 367.124493 -185.551068)
			(xy 367.136619 -185.496631) (xy 367.156542 -185.44454) (xy 367.183838 -185.395905) (xy 367.217924 -185.351762)
			(xy 367.258073 -185.313053) (xy 367.303431 -185.280602) (xy 367.353031 -185.255101) (xy 367.405815 -185.237094)
			(xy 367.460658 -185.226964) (xy 367.516392 -185.224927) (xy 367.571829 -185.231027) (xy 367.625786 -185.245133)
			(xy 367.677115 -185.266945) (xy 367.724721 -185.295999) (xy 367.767589 -185.331674) (xy 367.804806 -185.373211)
			(xy 367.835579 -185.419724) (xy 367.859251 -185.470221) (xy 367.875319 -185.523628) (xy 367.883439 -185.578804)
			(xy 367.883948 -185.60669) (xy 367.883439 -185.634576) (xy 367.875319 -185.689752) (xy 367.859251 -185.743159)
			(xy 367.835579 -185.793656) (xy 367.804806 -185.840169) (xy 367.767589 -185.881706) (xy 367.724721 -185.917381)
			(xy 367.677115 -185.946435) (xy 367.625786 -185.968247) (xy 367.571829 -185.982353) (xy 367.516392 -185.988453)
			(xy 367.460658 -185.986416) (xy 367.405815 -185.976286) (xy 367.353031 -185.958279) (xy 367.303431 -185.932778)
			(xy 367.258073 -185.900327) (xy 367.217924 -185.861618) (xy 367.183838 -185.817475) (xy 367.156542 -185.76884)
			(xy 367.136619 -185.716749) (xy 367.124493 -185.662312) (xy 367.120422 -185.60669) (xy 365.560948 -185.60669)
			(xy 365.566451 -185.644082) (xy 365.56696 -185.671968) (xy 365.566451 -185.699854) (xy 365.558331 -185.75503)
			(xy 365.542263 -185.808437) (xy 365.518591 -185.858934) (xy 365.487818 -185.905447) (xy 365.450601 -185.946984)
			(xy 365.407733 -185.982659) (xy 365.360127 -186.011713) (xy 365.308798 -186.033525) (xy 365.254841 -186.047631)
			(xy 365.199404 -186.053731) (xy 365.14367 -186.051694) (xy 365.088827 -186.041564) (xy 365.036043 -186.023557)
			(xy 364.986443 -185.998056) (xy 364.941085 -185.965605) (xy 364.900936 -185.926896) (xy 364.86685 -185.882753)
			(xy 364.839554 -185.834118) (xy 364.819631 -185.782027) (xy 364.807505 -185.72759) (xy 364.803434 -185.671968)
			(xy 362.306108 -185.671968) (xy 362.306108 -186.680094) (xy 362.911388 -186.680094) (xy 362.915459 -186.624472)
			(xy 362.927585 -186.570035) (xy 362.947508 -186.517944) (xy 362.974804 -186.469309) (xy 363.00889 -186.425166)
			(xy 363.049039 -186.386457) (xy 363.094397 -186.354006) (xy 363.143997 -186.328505) (xy 363.196781 -186.310498)
			(xy 363.251624 -186.300368) (xy 363.307358 -186.298331) (xy 363.362795 -186.304431) (xy 363.416752 -186.318537)
			(xy 363.468081 -186.340349) (xy 363.515687 -186.369403) (xy 363.558555 -186.405078) (xy 363.595772 -186.446615)
			(xy 363.626545 -186.493128) (xy 363.650217 -186.543625) (xy 363.666285 -186.597032) (xy 363.674405 -186.652208)
			(xy 363.674914 -186.680094) (xy 363.674405 -186.70798) (xy 363.666285 -186.763156) (xy 363.650217 -186.816563)
			(xy 363.645726 -186.826144) (xy 367.0841 -186.826144) (xy 367.088171 -186.770522) (xy 367.100297 -186.716085)
			(xy 367.12022 -186.663994) (xy 367.147516 -186.615359) (xy 367.181602 -186.571216) (xy 367.221751 -186.532507)
			(xy 367.267109 -186.500056) (xy 367.316709 -186.474555) (xy 367.369493 -186.456548) (xy 367.424336 -186.446418)
			(xy 367.48007 -186.444381) (xy 367.535507 -186.450481) (xy 367.589464 -186.464587) (xy 367.640793 -186.486399)
			(xy 367.688399 -186.515453) (xy 367.731267 -186.551128) (xy 367.768484 -186.592665) (xy 367.799257 -186.639178)
			(xy 367.822929 -186.689675) (xy 367.838997 -186.743082) (xy 367.847117 -186.798258) (xy 367.847626 -186.826144)
			(xy 367.847117 -186.85403) (xy 367.838997 -186.909206) (xy 367.822929 -186.962613) (xy 367.799257 -187.01311)
			(xy 367.768484 -187.059623) (xy 367.731267 -187.10116) (xy 367.688399 -187.136835) (xy 367.640793 -187.165889)
			(xy 367.589464 -187.187701) (xy 367.535507 -187.201807) (xy 367.48007 -187.207907) (xy 367.424336 -187.20587)
			(xy 367.369493 -187.19574) (xy 367.316709 -187.177733) (xy 367.267109 -187.152232) (xy 367.221751 -187.119781)
			(xy 367.181602 -187.081072) (xy 367.147516 -187.036929) (xy 367.12022 -186.988294) (xy 367.100297 -186.936203)
			(xy 367.088171 -186.881766) (xy 367.0841 -186.826144) (xy 363.645726 -186.826144) (xy 363.626545 -186.86706)
			(xy 363.595772 -186.913573) (xy 363.558555 -186.95511) (xy 363.515687 -186.990785) (xy 363.468081 -187.019839)
			(xy 363.416752 -187.041651) (xy 363.362795 -187.055757) (xy 363.307358 -187.061857) (xy 363.251624 -187.05982)
			(xy 363.196781 -187.04969) (xy 363.143997 -187.031683) (xy 363.094397 -187.006182) (xy 363.049039 -186.973731)
			(xy 363.00889 -186.935022) (xy 362.974804 -186.890879) (xy 362.947508 -186.842244) (xy 362.927585 -186.790153)
			(xy 362.915459 -186.735716) (xy 362.911388 -186.680094) (xy 362.306108 -186.680094) (xy 362.306108 -189.856872)
			(xy 362.3066 -189.86687) (xy 362.31423 -189.885355) (xy 362.328317 -189.89955) (xy 362.33735 -189.903862)
			(xy 362.351574 -189.909704) (xy 362.381546 -189.903862) (xy 364.44936 -187.836048) (xy 364.46813 -187.818013)
			(xy 364.510245 -187.787428) (xy 364.556621 -187.763796) (xy 364.606119 -187.747699) (xy 364.657524 -187.73953)
			(xy 364.683548 -187.73902) (xy 367.72088 -187.73902) (xy 367.730944 -187.738583) (xy 367.749529 -187.73085)
			(xy 367.756948 -187.724034) (xy 370.679218 -184.80151) (xy 370.68252 -184.791604) (xy 370.690838 -184.765885)
			(xy 370.713719 -184.716912) (xy 370.743287 -184.671662) (xy 370.778949 -184.631042) (xy 370.819991 -184.595865)
			(xy 370.865589 -184.566836) (xy 370.914829 -184.544539) (xy 370.966726 -184.529419) (xy 371.020237 -184.52178)
			(xy 371.047264 -184.521348) (xy 371.074518 -184.521831) (xy 371.128472 -184.529583) (xy 371.180774 -184.544935)
			(xy 371.230358 -184.567573) (xy 371.276216 -184.597038) (xy 371.317414 -184.632729) (xy 371.353114 -184.67392)
			(xy 371.382588 -184.719772) (xy 371.405237 -184.769351) (xy 371.409834 -184.785) (xy 373.505982 -184.785)
			(xy 373.510053 -184.729378) (xy 373.522179 -184.674941) (xy 373.542102 -184.62285) (xy 373.569398 -184.574215)
			(xy 373.603484 -184.530072) (xy 373.643633 -184.491363) (xy 373.688991 -184.458912) (xy 373.738591 -184.433411)
			(xy 373.791375 -184.415404) (xy 373.846218 -184.405274) (xy 373.901952 -184.403237) (xy 373.957389 -184.409337)
			(xy 374.011346 -184.423443) (xy 374.062675 -184.445255) (xy 374.110281 -184.474309) (xy 374.153149 -184.509984)
			(xy 374.190366 -184.551521) (xy 374.221139 -184.598034) (xy 374.244811 -184.648531) (xy 374.260879 -184.701938)
			(xy 374.268999 -184.757114) (xy 374.269508 -184.785) (xy 374.268999 -184.812886) (xy 374.260879 -184.868062)
			(xy 374.244811 -184.921469) (xy 374.221139 -184.971966) (xy 374.190366 -185.018479) (xy 374.153149 -185.060016)
			(xy 374.110281 -185.095691) (xy 374.062675 -185.124745) (xy 374.011346 -185.146557) (xy 373.957389 -185.160663)
			(xy 373.901952 -185.166763) (xy 373.846218 -185.164726) (xy 373.791375 -185.154596) (xy 373.738591 -185.136589)
			(xy 373.688991 -185.111088) (xy 373.643633 -185.078637) (xy 373.603484 -185.039928) (xy 373.569398 -184.995785)
			(xy 373.542102 -184.94715) (xy 373.522179 -184.895059) (xy 373.510053 -184.840622) (xy 373.505982 -184.785)
			(xy 371.409834 -184.785) (xy 371.4206 -184.82165) (xy 371.428363 -184.875602) (xy 371.428772 -184.902856)
			(xy 371.428304 -184.929884) (xy 371.420676 -184.983398) (xy 371.405565 -185.035298) (xy 371.383276 -185.084544)
			(xy 371.354255 -185.130147) (xy 371.319083 -185.171195) (xy 371.278467 -185.206864) (xy 371.23322 -185.236439)
			(xy 371.184249 -185.259326) (xy 371.158516 -185.2676) (xy 371.14861 -185.270902) (xy 368.642392 -187.77712)
			(xy 373.201436 -187.77712) (xy 373.205507 -187.721498) (xy 373.217633 -187.667061) (xy 373.237556 -187.61497)
			(xy 373.264852 -187.566335) (xy 373.298938 -187.522192) (xy 373.339087 -187.483483) (xy 373.384445 -187.451032)
			(xy 373.434045 -187.425531) (xy 373.486829 -187.407524) (xy 373.541672 -187.397394) (xy 373.597406 -187.395357)
			(xy 373.652843 -187.401457) (xy 373.7068 -187.415563) (xy 373.758129 -187.437375) (xy 373.805735 -187.466429)
			(xy 373.848603 -187.502104) (xy 373.88582 -187.543641) (xy 373.916593 -187.590154) (xy 373.940265 -187.640651)
			(xy 373.956333 -187.694058) (xy 373.964453 -187.749234) (xy 373.964962 -187.77712) (xy 373.964453 -187.805006)
			(xy 373.956333 -187.860182) (xy 373.940265 -187.913589) (xy 373.916593 -187.964086) (xy 373.88582 -188.010599)
			(xy 373.848603 -188.052136) (xy 373.805735 -188.087811) (xy 373.758129 -188.116865) (xy 373.7068 -188.138677)
			(xy 373.652843 -188.152783) (xy 373.597406 -188.158883) (xy 373.541672 -188.156846) (xy 373.486829 -188.146716)
			(xy 373.434045 -188.128709) (xy 373.384445 -188.103208) (xy 373.339087 -188.070757) (xy 373.298938 -188.032048)
			(xy 373.264852 -187.987905) (xy 373.237556 -187.93927) (xy 373.217633 -187.887179) (xy 373.205507 -187.832742)
			(xy 373.201436 -187.77712) (xy 368.642392 -187.77712) (xy 368.114072 -188.30544) (xy 368.095301 -188.323471)
			(xy 368.053184 -188.354048) (xy 368.006807 -188.377671) (xy 367.95731 -188.39376) (xy 367.905907 -188.401919)
			(xy 367.879884 -188.402468) (xy 365.482124 -188.402468) (xy 365.47771 -188.405904) (xy 365.470396 -188.414362)
			(xy 365.467646 -188.419232) (xy 365.466884 -188.42101) (xy 365.42726 -188.50356) (xy 365.424422 -188.509962)
			(xy 365.421988 -188.523748) (xy 365.422434 -188.530738) (xy 365.423196 -188.538104) (xy 365.42853 -188.551312)
			(xy 365.433102 -188.5569) (xy 365.448513 -188.57716) (xy 365.474403 -188.620988) (xy 365.494241 -188.667867)
			(xy 365.507676 -188.716966) (xy 365.514469 -188.767414) (xy 365.51489 -188.792866) (xy 365.51489 -188.800994)
			(xy 365.513879 -188.827879) (xy 365.505233 -188.88098) (xy 365.489212 -188.932339) (xy 365.466134 -188.980938)
			(xy 365.436457 -189.025812) (xy 365.400769 -189.066071) (xy 365.359778 -189.100916) (xy 365.314298 -189.129656)
			(xy 365.265231 -189.151722) (xy 365.213551 -189.166674) (xy 365.160282 -189.174217) (xy 365.133382 -189.174628)
			(xy 365.106131 -189.174141) (xy 365.052184 -189.166383) (xy 364.99989 -189.151026) (xy 364.950314 -189.128384)
			(xy 364.904465 -189.098918) (xy 364.863275 -189.063226) (xy 364.827584 -189.022037) (xy 364.798117 -188.976187)
			(xy 364.775475 -188.926611) (xy 364.760118 -188.874318) (xy 364.752359 -188.820371) (xy 364.751874 -188.79312)
			(xy 364.75192 -188.78243) (xy 364.753066 -188.761082) (xy 364.75416 -188.750448) (xy 364.754779 -188.742693)
			(xy 364.751796 -188.727435) (xy 364.748318 -188.720476) (xy 364.744264 -188.713618) (xy 364.732745 -188.702629)
			(xy 364.725712 -188.698886) (xy 364.639352 -188.657484) (xy 364.638082 -188.656976) (xy 364.628539 -188.653195)
			(xy 364.608037 -188.652791) (xy 364.589023 -188.660471) (xy 364.58144 -188.66739) (xy 364.253018 -188.995812)
			(xy 364.245884 -189.003777) (xy 364.23826 -189.023728) (xy 364.238286 -189.03442) (xy 364.24235 -189.110112)
			(xy 364.242748 -189.115394) (xy 364.245431 -189.125639) (xy 364.247684 -189.130432) (xy 364.25251 -189.13983)
			(xy 364.261146 -189.146688) (xy 364.282795 -189.164918) (xy 364.300041 -189.183772) (xy 373.253506 -189.183772)
			(xy 373.257577 -189.12815) (xy 373.269703 -189.073713) (xy 373.289626 -189.021622) (xy 373.316922 -188.972987)
			(xy 373.351008 -188.928844) (xy 373.391157 -188.890135) (xy 373.436515 -188.857684) (xy 373.486115 -188.832183)
			(xy 373.538899 -188.814176) (xy 373.593742 -188.804046) (xy 373.649476 -188.802009) (xy 373.704913 -188.808109)
			(xy 373.75887 -188.822215) (xy 373.810199 -188.844027) (xy 373.857805 -188.873081) (xy 373.900673 -188.908756)
			(xy 373.93789 -188.950293) (xy 373.968663 -188.996806) (xy 373.992335 -189.047303) (xy 374.008403 -189.10071)
			(xy 374.016523 -189.155886) (xy 374.017032 -189.183772) (xy 374.016523 -189.211658) (xy 374.008403 -189.266834)
			(xy 373.992335 -189.320241) (xy 373.968663 -189.370738) (xy 373.93789 -189.417251) (xy 373.900673 -189.458788)
			(xy 373.857805 -189.494463) (xy 373.810199 -189.523517) (xy 373.75887 -189.545329) (xy 373.704913 -189.559435)
			(xy 373.649476 -189.565535) (xy 373.593742 -189.563498) (xy 373.538899 -189.553368) (xy 373.486115 -189.535361)
			(xy 373.436515 -189.50986) (xy 373.391157 -189.477409) (xy 373.351008 -189.4387) (xy 373.316922 -189.394557)
			(xy 373.289626 -189.345922) (xy 373.269703 -189.293831) (xy 373.257577 -189.239394) (xy 373.253506 -189.183772)
			(xy 364.300041 -189.183772) (xy 364.320994 -189.206678) (xy 364.352611 -189.253618) (xy 364.376954 -189.30471)
			(xy 364.39349 -189.358835) (xy 364.401857 -189.414809) (xy 364.40237 -189.443106) (xy 364.401906 -189.470358)
			(xy 364.394148 -189.524306) (xy 364.378791 -189.576601) (xy 364.356148 -189.626178) (xy 364.326679 -189.672027)
			(xy 364.290985 -189.713216) (xy 364.249792 -189.748906) (xy 364.203939 -189.778369) (xy 364.15436 -189.801007)
			(xy 364.102063 -189.816358) (xy 364.048114 -189.824109) (xy 364.020862 -189.824614) (xy 363.992563 -189.824104)
			(xy 363.936583 -189.815754) (xy 363.882451 -189.799227) (xy 363.831354 -189.774885) (xy 363.784412 -189.743264)
			(xy 363.742656 -189.705056) (xy 363.724444 -189.68339) (xy 363.721142 -189.679072) (xy 363.712506 -189.672214)
			(xy 363.708188 -189.669928) (xy 363.703401 -189.667654) (xy 363.693155 -189.664955) (xy 363.687868 -189.664594)
			(xy 363.612176 -189.66053) (xy 363.601462 -189.660399) (xy 363.581454 -189.668011) (xy 363.573568 -189.675262)
			(xy 363.155738 -190.093092) (xy 364.751364 -190.093092) (xy 364.755435 -190.03747) (xy 364.767561 -189.983033)
			(xy 364.787484 -189.930942) (xy 364.81478 -189.882307) (xy 364.848866 -189.838164) (xy 364.889015 -189.799455)
			(xy 364.934373 -189.767004) (xy 364.983973 -189.741503) (xy 365.036757 -189.723496) (xy 365.0916 -189.713366)
			(xy 365.147334 -189.711329) (xy 365.202771 -189.717429) (xy 365.256728 -189.731535) (xy 365.308057 -189.753347)
			(xy 365.355663 -189.782401) (xy 365.398531 -189.818076) (xy 365.435748 -189.859613) (xy 365.466521 -189.906126)
			(xy 365.490193 -189.956623) (xy 365.506261 -190.01003) (xy 365.514381 -190.065206) (xy 365.51489 -190.093092)
			(xy 374.703846 -190.093092) (xy 374.707917 -190.03747) (xy 374.720043 -189.983033) (xy 374.739966 -189.930942)
			(xy 374.767262 -189.882307) (xy 374.801348 -189.838164) (xy 374.841497 -189.799455) (xy 374.886855 -189.767004)
			(xy 374.936455 -189.741503) (xy 374.989239 -189.723496) (xy 375.044082 -189.713366) (xy 375.099816 -189.711329)
			(xy 375.155253 -189.717429) (xy 375.20921 -189.731535) (xy 375.260539 -189.753347) (xy 375.308145 -189.782401)
			(xy 375.351013 -189.818076) (xy 375.38823 -189.859613) (xy 375.419003 -189.906126) (xy 375.442675 -189.956623)
			(xy 375.458743 -190.01003) (xy 375.466863 -190.065206) (xy 375.467372 -190.093092) (xy 375.466863 -190.120978)
			(xy 375.458743 -190.176154) (xy 375.442675 -190.229561) (xy 375.419003 -190.280058) (xy 375.38823 -190.326571)
			(xy 375.351013 -190.368108) (xy 375.308145 -190.403783) (xy 375.260539 -190.432837) (xy 375.20921 -190.454649)
			(xy 375.155253 -190.468755) (xy 375.099816 -190.474855) (xy 375.044082 -190.472818) (xy 374.989239 -190.462688)
			(xy 374.936455 -190.444681) (xy 374.886855 -190.41918) (xy 374.841497 -190.386729) (xy 374.801348 -190.34802)
			(xy 374.767262 -190.303877) (xy 374.739966 -190.255242) (xy 374.720043 -190.203151) (xy 374.707917 -190.148714)
			(xy 374.703846 -190.093092) (xy 365.51489 -190.093092) (xy 365.514381 -190.120978) (xy 365.506261 -190.176154)
			(xy 365.490193 -190.229561) (xy 365.466521 -190.280058) (xy 365.435748 -190.326571) (xy 365.398531 -190.368108)
			(xy 365.355663 -190.403783) (xy 365.308057 -190.432837) (xy 365.256728 -190.454649) (xy 365.202771 -190.468755)
			(xy 365.147334 -190.474855) (xy 365.0916 -190.472818) (xy 365.036757 -190.462688) (xy 364.983973 -190.444681)
			(xy 364.934373 -190.41918) (xy 364.889015 -190.386729) (xy 364.848866 -190.34802) (xy 364.81478 -190.303877)
			(xy 364.787484 -190.255242) (xy 364.767561 -190.203151) (xy 364.755435 -190.148714) (xy 364.751364 -190.093092)
			(xy 363.155738 -190.093092) (xy 362.251498 -190.997332) (xy 363.853982 -190.997332) (xy 363.858053 -190.94171)
			(xy 363.870179 -190.887273) (xy 363.890102 -190.835182) (xy 363.917398 -190.786547) (xy 363.951484 -190.742404)
			(xy 363.991633 -190.703695) (xy 364.036991 -190.671244) (xy 364.086591 -190.645743) (xy 364.139375 -190.627736)
			(xy 364.194218 -190.617606) (xy 364.249952 -190.615569) (xy 364.305389 -190.621669) (xy 364.359346 -190.635775)
			(xy 364.410675 -190.657587) (xy 364.458281 -190.686641) (xy 364.501149 -190.722316) (xy 364.538366 -190.763853)
			(xy 364.569139 -190.810366) (xy 364.592811 -190.860863) (xy 364.608879 -190.91427) (xy 364.616999 -190.969446)
			(xy 364.617508 -190.997332) (xy 364.616999 -191.025218) (xy 364.608879 -191.080394) (xy 364.592811 -191.133801)
			(xy 364.569139 -191.184298) (xy 364.538366 -191.230811) (xy 364.501149 -191.272348) (xy 364.458281 -191.308023)
			(xy 364.410675 -191.337077) (xy 364.359346 -191.358889) (xy 364.305389 -191.372995) (xy 364.249952 -191.379095)
			(xy 364.194218 -191.377058) (xy 364.139375 -191.366928) (xy 364.086591 -191.348921) (xy 364.036991 -191.32342)
			(xy 363.991633 -191.290969) (xy 363.951484 -191.25226) (xy 363.917398 -191.208117) (xy 363.890102 -191.159482)
			(xy 363.870179 -191.107391) (xy 363.858053 -191.052954) (xy 363.853982 -190.997332) (xy 362.251498 -190.997332)
			(xy 361.812332 -191.436498) (xy 361.805726 -191.443783) (xy 361.798144 -191.461908) (xy 361.79796 -191.481554)
			(xy 361.801156 -191.490854) (xy 361.80141 -191.491616) (xy 361.804204 -191.498728) (xy 361.813856 -191.510412)
			(xy 361.820206 -191.51473) (xy 361.826536 -191.518595) (xy 361.840734 -191.522857) (xy 361.848146 -191.523112)
			(xy 366.028986 -191.523112) (xy 366.039049 -191.523551) (xy 366.05763 -191.531289) (xy 366.065054 -191.538098)
			(xy 367.47958 -192.952624) (xy 369.261896 -192.952624) (xy 369.265967 -192.897002) (xy 369.278093 -192.842565)
			(xy 369.298016 -192.790474) (xy 369.325312 -192.741839) (xy 369.359398 -192.697696) (xy 369.399547 -192.658987)
			(xy 369.444905 -192.626536) (xy 369.494505 -192.601035) (xy 369.547289 -192.583028) (xy 369.602132 -192.572898)
			(xy 369.657866 -192.570861) (xy 369.713303 -192.576961) (xy 369.76726 -192.591067) (xy 369.818589 -192.612879)
			(xy 369.866195 -192.641933) (xy 369.909063 -192.677608) (xy 369.94628 -192.719145) (xy 369.977053 -192.765658)
			(xy 370.000725 -192.816155) (xy 370.016793 -192.869562) (xy 370.024913 -192.924738) (xy 370.025422 -192.952624)
			(xy 370.024913 -192.98051) (xy 370.016793 -193.035686) (xy 370.000725 -193.089093) (xy 369.977053 -193.13959)
			(xy 369.94628 -193.186103) (xy 369.909063 -193.22764) (xy 369.866195 -193.263315) (xy 369.818589 -193.292369)
			(xy 369.76726 -193.314181) (xy 369.713303 -193.328287) (xy 369.657866 -193.334387) (xy 369.602132 -193.33235)
			(xy 369.547289 -193.32222) (xy 369.494505 -193.304213) (xy 369.444905 -193.278712) (xy 369.399547 -193.246261)
			(xy 369.359398 -193.207552) (xy 369.325312 -193.163409) (xy 369.298016 -193.114774) (xy 369.278093 -193.062683)
			(xy 369.265967 -193.008246) (xy 369.261896 -192.952624) (xy 367.47958 -192.952624) (xy 368.510312 -193.983356)
			(xy 369.228368 -193.983356) (xy 369.232439 -193.927734) (xy 369.244565 -193.873297) (xy 369.264488 -193.821206)
			(xy 369.291784 -193.772571) (xy 369.32587 -193.728428) (xy 369.366019 -193.689719) (xy 369.411377 -193.657268)
			(xy 369.460977 -193.631767) (xy 369.513761 -193.61376) (xy 369.568604 -193.60363) (xy 369.624338 -193.601593)
			(xy 369.679775 -193.607693) (xy 369.733732 -193.621799) (xy 369.785061 -193.643611) (xy 369.832667 -193.672665)
			(xy 369.875535 -193.70834) (xy 369.912752 -193.749877) (xy 369.943525 -193.79639) (xy 369.967197 -193.846887)
			(xy 369.983265 -193.900294) (xy 369.991385 -193.95547) (xy 369.991894 -193.983356) (xy 369.991385 -194.011242)
			(xy 369.983265 -194.066418) (xy 369.967197 -194.119825) (xy 369.943525 -194.170322) (xy 369.912752 -194.216835)
			(xy 369.875535 -194.258372) (xy 369.832667 -194.294047) (xy 369.785061 -194.323101) (xy 369.733732 -194.344913)
			(xy 369.679775 -194.359019) (xy 369.624338 -194.365119) (xy 369.568604 -194.363082) (xy 369.513761 -194.352952)
			(xy 369.460977 -194.334945) (xy 369.411377 -194.309444) (xy 369.366019 -194.276993) (xy 369.32587 -194.238284)
			(xy 369.291784 -194.194141) (xy 369.264488 -194.145506) (xy 369.244565 -194.093415) (xy 369.232439 -194.038978)
			(xy 369.228368 -193.983356) (xy 368.510312 -193.983356) (xy 369.189508 -194.662552) (xy 369.196345 -194.669954)
			(xy 369.20406 -194.688552) (xy 369.204494 -194.69862) (xy 369.204494 -194.94373) (xy 369.205256 -194.951604)
			(xy 369.205256 -194.952112) (xy 369.207652 -194.963051) (xy 369.220293 -194.981507) (xy 369.22964 -194.987672)
			(xy 369.23345 -194.98945) (xy 369.257583 -195.001376) (xy 369.302523 -195.031008) (xy 369.342847 -195.066668)
			(xy 369.377752 -195.107648) (xy 369.406543 -195.153131) (xy 369.428649 -195.202212) (xy 369.443629 -195.253916)
			(xy 369.451185 -195.307213) (xy 369.451636 -195.334128) (xy 369.451557 -195.346866) (xy 369.449901 -195.372287)
			(xy 369.448334 -195.384928) (xy 369.444345 -195.411196) (xy 369.430039 -195.462365) (xy 369.40877 -195.511052)
			(xy 369.380949 -195.556316) (xy 369.347115 -195.597281) (xy 369.307923 -195.633154) (xy 369.264132 -195.663241)
			(xy 369.240562 -195.675504) (xy 369.232942 -195.679314) (xy 369.219226 -195.69303) (xy 369.216522 -195.695882)
			(xy 369.211933 -195.702263) (xy 369.210082 -195.70573) (xy 369.207498 -195.711157) (xy 369.204673 -195.722836)
			(xy 369.204494 -195.728844) (xy 369.204494 -195.772278) (xy 369.20513 -195.783404) (xy 369.214629 -195.803538)
			(xy 369.222782 -195.81114) (xy 369.225322 -195.813172) (xy 369.235482 -195.819776) (xy 369.297966 -195.860162)
			(xy 369.306534 -195.865162) (xy 369.326012 -195.868816) (xy 369.335812 -195.867274) (xy 369.347242 -195.864734)
			(xy 369.351814 -195.862702) (xy 369.375816 -195.852821) (xy 369.425819 -195.838899) (xy 369.477246 -195.831874)
			(xy 369.503198 -195.83146) (xy 369.508278 -195.83146) (xy 369.535305 -195.83227) (xy 369.588732 -195.840574)
			(xy 369.640452 -195.85634) (xy 369.689428 -195.87925) (xy 369.734677 -195.908847) (xy 369.775294 -195.944537)
			(xy 369.810465 -195.985604) (xy 369.839485 -196.031226) (xy 369.861771 -196.080488) (xy 369.876879 -196.132404)
			(xy 369.884504 -196.185933) (xy 369.88496 -196.212968) (xy 369.884496 -196.240256) (xy 369.876723 -196.294277)
			(xy 369.86133 -196.346637) (xy 369.838632 -196.39627) (xy 369.809092 -196.442161) (xy 369.773313 -196.483374)
			(xy 369.732026 -196.519067) (xy 369.686074 -196.548512) (xy 369.636394 -196.571107) (xy 369.584001 -196.586391)
			(xy 369.557046 -196.590666) (xy 369.533932 -196.593968) (xy 369.52682 -196.594476) (xy 369.503452 -196.594476)
			(xy 369.466876 -196.592698) (xy 369.437702 -196.589327) (xy 369.380803 -196.57479) (xy 369.353592 -196.563742)
			(xy 369.353084 -196.563742) (xy 369.347242 -196.561456) (xy 369.335812 -196.558408) (xy 369.326076 -196.556941)
			(xy 369.306748 -196.560599) (xy 369.29822 -196.56552) (xy 369.297966 -196.565774) (xy 369.226084 -196.612256)
			(xy 369.217486 -196.618901) (xy 369.20644 -196.63759) (xy 369.204748 -196.648324) (xy 369.204494 -196.651118)
			(xy 369.204494 -197.041262) (xy 369.206272 -197.054724) (xy 369.209828 -197.063868) (xy 369.212482 -197.068748)
			(xy 369.219531 -197.077329) (xy 369.223798 -197.080886) (xy 369.257834 -197.10654) (xy 369.258342 -197.10654)
			(xy 369.266978 -197.113144) (xy 369.277316 -197.119824) (xy 369.301605 -197.123558) (xy 369.31346 -197.120256)
			(xy 369.345094 -197.1102) (xy 369.410576 -197.099359) (xy 369.443762 -197.098666) (xy 369.444016 -197.098666)
			(xy 369.472968 -197.099184) (xy 369.530283 -197.107426) (xy 369.585842 -197.123742) (xy 369.638514 -197.147798)
			(xy 369.687225 -197.179105) (xy 369.730986 -197.217025) (xy 369.768905 -197.260788) (xy 369.80021 -197.309501)
			(xy 369.824264 -197.362173) (xy 369.840577 -197.417732) (xy 369.848817 -197.475048) (xy 369.848817 -197.532952)
			(xy 369.840577 -197.590268) (xy 369.824264 -197.645827) (xy 369.80021 -197.698499) (xy 369.768905 -197.747212)
			(xy 369.730986 -197.790975) (xy 369.687225 -197.828895) (xy 369.638514 -197.860202) (xy 369.585842 -197.884258)
			(xy 369.530283 -197.900574) (xy 369.472968 -197.908816) (xy 369.444016 -197.909434) (xy 369.410957 -197.908719)
			(xy 369.34573 -197.897877) (xy 369.314222 -197.887844) (xy 369.312444 -197.887082) (xy 369.309904 -197.886574)
			(xy 369.306348 -197.885812) (xy 369.295838 -197.884281) (xy 369.275179 -197.889134) (xy 369.26647 -197.89521)
			(xy 369.263676 -197.897242) (xy 369.223036 -197.927468) (xy 369.215601 -197.934261) (xy 369.206193 -197.952044)
			(xy 369.204748 -197.962012) (xy 369.204748 -197.96252) (xy 369.204494 -197.966838) (xy 369.204494 -198.873364)
			(xy 369.204748 -198.87692) (xy 369.204748 -198.877428) (xy 369.206166 -198.888039) (xy 369.216408 -198.90681)
			(xy 369.22456 -198.91375) (xy 369.258088 -198.938642) (xy 369.258596 -198.938642) (xy 369.293394 -198.964042)
			(xy 369.297939 -198.966914) (xy 369.307931 -198.970878) (xy 369.313206 -198.971916) (xy 369.320826 -198.973186)
			(xy 369.332256 -198.971408) (xy 369.333272 -198.971154) (xy 369.33632 -198.970138) (xy 369.336828 -198.970138)
			(xy 369.33759 -198.969884) (xy 369.337844 -198.969884) (xy 369.33886 -198.969376) (xy 369.364844 -198.961888)
			(xy 369.418259 -198.953474) (xy 369.445286 -198.952612) (xy 369.456208 -198.952612) (xy 369.483235 -198.953423)
			(xy 369.536662 -198.961731) (xy 369.588381 -198.977498) (xy 369.637356 -199.00041) (xy 369.682605 -199.030007)
			(xy 369.723223 -199.065696) (xy 369.758395 -199.106762) (xy 369.787416 -199.152382) (xy 369.809706 -199.201643)
			(xy 369.824818 -199.253557) (xy 369.832449 -199.307085) (xy 369.83289 -199.33412) (xy 369.832402 -199.36137)
			(xy 369.824643 -199.415314) (xy 369.809286 -199.467606) (xy 369.786644 -199.517179) (xy 369.757177 -199.563026)
			(xy 369.721485 -199.604212) (xy 369.680295 -199.6399) (xy 369.634446 -199.669362) (xy 369.58487 -199.692)
			(xy 369.532577 -199.707352) (xy 369.478632 -199.715105) (xy 369.451382 -199.715628) (xy 369.422155 -199.715129)
			(xy 369.364369 -199.70633) (xy 369.33632 -199.698102) (xy 369.33251 -199.696832) (xy 369.327551 -199.695849)
			(xy 369.317447 -199.695595) (xy 369.312444 -199.696324) (xy 369.301014 -199.698356) (xy 369.258342 -199.729852)
			(xy 369.250214 -199.735948) (xy 369.222528 -199.756014) (xy 369.215131 -199.762787) (xy 369.205952 -199.780602)
			(xy 369.204748 -199.790558) (xy 369.204748 -199.791574) (xy 369.204494 -199.794876) (xy 369.204494 -200.173336)
			(xy 369.204748 -200.176892) (xy 369.204748 -200.1774) (xy 369.206161 -200.188014) (xy 369.216397 -200.206793)
			(xy 369.22456 -200.213722) (xy 369.258088 -200.238614) (xy 369.258596 -200.238614) (xy 369.293394 -200.264014)
			(xy 369.297938 -200.266887) (xy 369.30793 -200.270854) (xy 369.313206 -200.271888) (xy 369.320826 -200.273158)
			(xy 369.332256 -200.27138) (xy 369.333272 -200.271126) (xy 369.33632 -200.27011) (xy 369.336828 -200.27011)
			(xy 369.33759 -200.269856) (xy 369.337844 -200.269856) (xy 369.33886 -200.269348) (xy 369.364843 -200.261859)
			(xy 369.418259 -200.253443) (xy 369.445286 -200.252584) (xy 369.456208 -200.252584) (xy 369.483233 -200.253396)
			(xy 369.536656 -200.261704) (xy 369.588371 -200.277472) (xy 369.637341 -200.300385) (xy 369.682585 -200.329983)
			(xy 369.723197 -200.365673) (xy 369.758362 -200.406739) (xy 369.787376 -200.45236) (xy 369.809658 -200.50162)
			(xy 369.824761 -200.553534) (xy 369.832382 -200.607059) (xy 369.83289 -200.634092) (xy 369.832427 -200.661345)
			(xy 369.824671 -200.715296) (xy 369.809316 -200.767593) (xy 369.786673 -200.817173) (xy 369.757205 -200.863026)
			(xy 369.721511 -200.904218) (xy 369.680318 -200.939911) (xy 369.634465 -200.969378) (xy 369.584884 -200.992019)
			(xy 369.532586 -201.007373) (xy 369.478635 -201.015128) (xy 369.451382 -201.0156) (xy 369.422155 -201.015101)
			(xy 369.36437 -201.006301) (xy 369.33632 -200.998074) (xy 369.33251 -200.996804) (xy 369.327551 -200.995821)
			(xy 369.317447 -200.995568) (xy 369.312444 -200.996296) (xy 369.301014 -200.998328) (xy 369.258342 -201.029824)
			(xy 369.250214 -201.03592) (xy 369.222528 -201.055986) (xy 369.215141 -201.062764) (xy 369.205987 -201.08058)
			(xy 369.204748 -201.09053) (xy 369.204748 -201.091546) (xy 369.204494 -201.094848) (xy 369.204494 -207.44815)
			(xy 372.698772 -207.44815) (xy 372.698772 -191.380618) (xy 372.699425 -191.342548) (xy 372.709383 -191.26706)
			(xy 372.729042 -191.1935) (xy 372.758071 -191.123109) (xy 372.776496 -191.089788) (xy 372.779535 -191.083948)
			(xy 372.782885 -191.071221) (xy 372.7831 -191.064642) (xy 372.7831 -190.743078) (xy 372.783596 -190.708978)
			(xy 372.791513 -190.641238) (xy 372.807242 -190.574875) (xy 372.830568 -190.510787) (xy 372.861176 -190.449841)
			(xy 372.898653 -190.39286) (xy 372.942492 -190.340615) (xy 372.992099 -190.293812) (xy 373.046805 -190.253086)
			(xy 373.105869 -190.218985) (xy 373.168492 -190.191972) (xy 373.233828 -190.172412) (xy 373.300992 -190.160569)
			(xy 373.369078 -190.156604) (xy 373.437164 -190.160569) (xy 373.504328 -190.172412) (xy 373.569664 -190.191972)
			(xy 373.632287 -190.218985) (xy 373.691351 -190.253086) (xy 373.746057 -190.293812) (xy 373.795664 -190.340615)
			(xy 373.839503 -190.39286) (xy 373.87698 -190.449841) (xy 373.907588 -190.510787) (xy 373.930914 -190.574875)
			(xy 373.946643 -190.641238) (xy 373.95456 -190.708978) (xy 373.955056 -190.743078) (xy 373.955056 -190.782702)
			(xy 373.955585 -190.792704) (xy 373.963237 -190.811188) (xy 373.977377 -190.825339) (xy 373.995854 -190.833006)
			(xy 374.005856 -190.833502) (xy 374.014238 -190.833502) (xy 374.03024 -190.828168) (xy 374.036844 -190.822834)
			(xy 374.062554 -190.80339) (xy 374.117499 -190.769675) (xy 374.175813 -190.742196) (xy 374.236791 -190.721285)
			(xy 374.299696 -190.707195) (xy 374.363768 -190.700096) (xy 374.396 -190.699644) (xy 374.431407 -190.70019)
			(xy 374.501705 -190.708727) (xy 374.570461 -190.725678) (xy 374.636672 -190.750795) (xy 374.699371 -190.783712)
			(xy 374.757644 -190.823948) (xy 374.810642 -190.870916) (xy 374.857589 -190.923931) (xy 374.897803 -190.982219)
			(xy 374.930696 -191.044931) (xy 374.955788 -191.111151) (xy 374.972713 -191.179913) (xy 374.981224 -191.250215)
			(xy 374.981724 -191.285622) (xy 374.981237 -191.318493) (xy 374.973898 -191.383823) (xy 374.959291 -191.44792)
			(xy 374.937601 -191.50998) (xy 374.9091 -191.569222) (xy 374.874147 -191.624901) (xy 374.848596 -191.65697)
			(xy 375.452892 -191.65697) (xy 375.456963 -191.601348) (xy 375.469089 -191.546911) (xy 375.489012 -191.49482)
			(xy 375.516308 -191.446185) (xy 375.550394 -191.402042) (xy 375.590543 -191.363333) (xy 375.635901 -191.330882)
			(xy 375.685501 -191.305381) (xy 375.738285 -191.287374) (xy 375.793128 -191.277244) (xy 375.848862 -191.275207)
			(xy 375.904299 -191.281307) (xy 375.958256 -191.295413) (xy 376.009585 -191.317225) (xy 376.057191 -191.346279)
			(xy 376.100059 -191.381954) (xy 376.137276 -191.423491) (xy 376.168049 -191.470004) (xy 376.191721 -191.520501)
			(xy 376.207789 -191.573908) (xy 376.215909 -191.629084) (xy 376.216418 -191.65697) (xy 376.215909 -191.684856)
			(xy 376.207789 -191.740032) (xy 376.191721 -191.793439) (xy 376.168049 -191.843936) (xy 376.137276 -191.890449)
			(xy 376.100059 -191.931986) (xy 376.057191 -191.967661) (xy 376.009585 -191.996715) (xy 375.958256 -192.018527)
			(xy 375.904299 -192.032633) (xy 375.848862 -192.038733) (xy 375.793128 -192.036696) (xy 375.738285 -192.026566)
			(xy 375.685501 -192.008559) (xy 375.635901 -191.983058) (xy 375.590543 -191.950607) (xy 375.550394 -191.911898)
			(xy 375.516308 -191.867755) (xy 375.489012 -191.81912) (xy 375.469089 -191.767029) (xy 375.456963 -191.712592)
			(xy 375.452892 -191.65697) (xy 374.848596 -191.65697) (xy 374.833181 -191.676317) (xy 374.810274 -191.699896)
			(xy 374.71477 -191.7954) (xy 374.707321 -191.803551) (xy 374.699682 -191.824241) (xy 374.700038 -191.835278)
			(xy 374.70715 -191.92367) (xy 374.718072 -191.942974) (xy 374.727216 -191.949578) (xy 374.747852 -191.965036)
			(xy 374.785216 -192.000565) (xy 374.817455 -192.040802) (xy 374.843982 -192.085013) (xy 374.864314 -192.132394)
			(xy 374.87808 -192.182082) (xy 374.88503 -192.23317) (xy 374.885458 -192.25895) (xy 374.884998 -192.286204)
			(xy 374.877247 -192.340158) (xy 374.861894 -192.392459) (xy 374.839254 -192.442042) (xy 374.809787 -192.487898)
			(xy 374.774092 -192.529092) (xy 374.732898 -192.564787) (xy 374.687042 -192.594254) (xy 374.637459 -192.616894)
			(xy 374.585158 -192.632247) (xy 374.531204 -192.639998) (xy 374.50395 -192.640458) (xy 374.483376 -192.63995)
			(xy 374.472962 -192.639442) (xy 374.45315 -192.646554) (xy 374.39219 -192.704466) (xy 374.384983 -192.711927)
			(xy 374.376728 -192.730937) (xy 374.376188 -192.741296) (xy 374.376188 -205.590902) (xy 377.328682 -205.590902)
			(xy 377.332753 -205.53528) (xy 377.344879 -205.480843) (xy 377.364802 -205.428752) (xy 377.392098 -205.380117)
			(xy 377.426184 -205.335974) (xy 377.466333 -205.297265) (xy 377.511691 -205.264814) (xy 377.561291 -205.239313)
			(xy 377.614075 -205.221306) (xy 377.668918 -205.211176) (xy 377.724652 -205.209139) (xy 377.780089 -205.215239)
			(xy 377.834046 -205.229345) (xy 377.885375 -205.251157) (xy 377.932981 -205.280211) (xy 377.975849 -205.315886)
			(xy 378.013066 -205.357423) (xy 378.043839 -205.403936) (xy 378.067511 -205.454433) (xy 378.077008 -205.486)
			(xy 379.816612 -205.486) (xy 379.820683 -205.430378) (xy 379.832809 -205.375941) (xy 379.852732 -205.32385)
			(xy 379.880028 -205.275215) (xy 379.914114 -205.231072) (xy 379.954263 -205.192363) (xy 379.999621 -205.159912)
			(xy 380.049221 -205.134411) (xy 380.102005 -205.116404) (xy 380.156848 -205.106274) (xy 380.212582 -205.104237)
			(xy 380.268019 -205.110337) (xy 380.321976 -205.124443) (xy 380.373305 -205.146255) (xy 380.420911 -205.175309)
			(xy 380.463779 -205.210984) (xy 380.500996 -205.252521) (xy 380.531769 -205.299034) (xy 380.555441 -205.349531)
			(xy 380.571509 -205.402938) (xy 380.579629 -205.458114) (xy 380.580138 -205.486) (xy 380.579629 -205.513886)
			(xy 380.571509 -205.569062) (xy 380.555441 -205.622469) (xy 380.531769 -205.672966) (xy 380.500996 -205.719479)
			(xy 380.463779 -205.761016) (xy 380.420911 -205.796691) (xy 380.373305 -205.825745) (xy 380.321976 -205.847557)
			(xy 380.268019 -205.861663) (xy 380.212582 -205.867763) (xy 380.156848 -205.865726) (xy 380.102005 -205.855596)
			(xy 380.049221 -205.837589) (xy 379.999621 -205.812088) (xy 379.954263 -205.779637) (xy 379.914114 -205.740928)
			(xy 379.880028 -205.696785) (xy 379.852732 -205.64815) (xy 379.832809 -205.596059) (xy 379.820683 -205.541622)
			(xy 379.816612 -205.486) (xy 378.077008 -205.486) (xy 378.083579 -205.50784) (xy 378.091699 -205.563016)
			(xy 378.092208 -205.590902) (xy 378.091699 -205.618788) (xy 378.083579 -205.673964) (xy 378.067511 -205.727371)
			(xy 378.043839 -205.777868) (xy 378.013066 -205.824381) (xy 377.975849 -205.865918) (xy 377.932981 -205.901593)
			(xy 377.885375 -205.930647) (xy 377.834046 -205.952459) (xy 377.780089 -205.966565) (xy 377.724652 -205.972665)
			(xy 377.668918 -205.970628) (xy 377.614075 -205.960498) (xy 377.561291 -205.942491) (xy 377.511691 -205.91699)
			(xy 377.466333 -205.884539) (xy 377.426184 -205.84583) (xy 377.392098 -205.801687) (xy 377.364802 -205.753052)
			(xy 377.344879 -205.700961) (xy 377.332753 -205.646524) (xy 377.328682 -205.590902) (xy 374.376188 -205.590902)
			(xy 374.376188 -206.939134) (xy 374.376572 -206.949208) (xy 374.384319 -206.967807) (xy 374.391174 -206.975202)
			(xy 374.934025 -207.518) (xy 379.806706 -207.518) (xy 379.810777 -207.462378) (xy 379.822903 -207.407941)
			(xy 379.842826 -207.35585) (xy 379.870122 -207.307215) (xy 379.904208 -207.263072) (xy 379.944357 -207.224363)
			(xy 379.989715 -207.191912) (xy 380.039315 -207.166411) (xy 380.092099 -207.148404) (xy 380.146942 -207.138274)
			(xy 380.202676 -207.136237) (xy 380.258113 -207.142337) (xy 380.31207 -207.156443) (xy 380.363399 -207.178255)
			(xy 380.411005 -207.207309) (xy 380.453873 -207.242984) (xy 380.49109 -207.284521) (xy 380.521863 -207.331034)
			(xy 380.545535 -207.381531) (xy 380.561603 -207.434938) (xy 380.569723 -207.490114) (xy 380.570232 -207.518)
			(xy 380.569723 -207.545886) (xy 380.561603 -207.601062) (xy 380.545535 -207.654469) (xy 380.521863 -207.704966)
			(xy 380.49109 -207.751479) (xy 380.453873 -207.793016) (xy 380.411005 -207.828691) (xy 380.363399 -207.857745)
			(xy 380.31207 -207.879557) (xy 380.258113 -207.893663) (xy 380.202676 -207.899763) (xy 380.146942 -207.897726)
			(xy 380.092099 -207.887596) (xy 380.039315 -207.869589) (xy 379.989715 -207.844088) (xy 379.944357 -207.811637)
			(xy 379.904208 -207.772928) (xy 379.870122 -207.728785) (xy 379.842826 -207.68015) (xy 379.822903 -207.628059)
			(xy 379.810777 -207.573622) (xy 379.806706 -207.518) (xy 374.934025 -207.518) (xy 375.836165 -208.420052)
			(xy 378.864354 -208.420052) (xy 378.864354 -208.365548) (xy 378.87211 -208.3116) (xy 378.887464 -208.259305)
			(xy 378.910105 -208.209726) (xy 378.93957 -208.163875) (xy 378.97526 -208.122683) (xy 379.016449 -208.086989)
			(xy 379.062298 -208.05752) (xy 379.111875 -208.034876) (xy 379.164169 -208.019517) (xy 379.218117 -208.011756)
			(xy 379.245368 -208.011268) (xy 379.272317 -208.011677) (xy 379.325678 -208.019259) (xy 379.377441 -208.034276)
			(xy 379.426575 -208.056429) (xy 379.472102 -208.085277) (xy 379.513116 -208.120246) (xy 379.548799 -208.16064)
			(xy 379.578441 -208.205654) (xy 379.601453 -208.254391) (xy 379.609858 -208.28) (xy 379.614511 -208.293269)
			(xy 379.629862 -208.31681) (xy 379.651049 -208.335274) (xy 379.676468 -208.347263) (xy 379.704192 -208.351868)
			(xy 379.732122 -208.34874) (xy 379.75814 -208.338115) (xy 379.780277 -208.3208) (xy 379.788928 -208.309718)
			(xy 379.804341 -208.289161) (xy 379.839856 -208.252028) (xy 379.880034 -208.219999) (xy 379.924147 -208.193652)
			(xy 379.971397 -208.173464) (xy 380.020929 -208.1598) (xy 380.071847 -208.152909) (xy 380.097538 -208.152492)
			(xy 380.124787 -208.15298) (xy 380.178731 -208.160741) (xy 380.231021 -208.1761) (xy 380.280594 -208.198743)
			(xy 380.326439 -208.22821) (xy 380.367625 -208.263902) (xy 380.403312 -208.305091) (xy 380.432775 -208.35094)
			(xy 380.455414 -208.400514) (xy 380.470767 -208.452806) (xy 380.478522 -208.50675) (xy 380.478522 -208.56125)
			(xy 380.470767 -208.615194) (xy 380.455414 -208.667486) (xy 380.432775 -208.71706) (xy 380.403312 -208.762909)
			(xy 380.367625 -208.804098) (xy 380.326439 -208.83979) (xy 380.280594 -208.869257) (xy 380.231021 -208.8919)
			(xy 380.178731 -208.907259) (xy 380.124787 -208.91502) (xy 380.097538 -208.915508) (xy 380.070592 -208.91504)
			(xy 380.017235 -208.907461) (xy 379.965476 -208.892449) (xy 379.916345 -208.870302) (xy 379.87082 -208.841461)
			(xy 379.829807 -208.8065) (xy 379.794121 -208.766115) (xy 379.764475 -208.72111) (xy 379.741457 -208.672381)
			(xy 379.733048 -208.646776) (xy 379.728389 -208.633511) (xy 379.713037 -208.609974) (xy 379.69185 -208.591514)
			(xy 379.666433 -208.579527) (xy 379.638712 -208.574923) (xy 379.610785 -208.578049) (xy 379.584768 -208.588669)
			(xy 379.562631 -208.605979) (xy 379.553978 -208.617058) (xy 379.538554 -208.637607) (xy 379.503042 -208.674741)
			(xy 379.462867 -208.706772) (xy 379.418755 -208.733121) (xy 379.371507 -208.75331) (xy 379.321976 -208.766974)
			(xy 379.271059 -208.773867) (xy 379.245368 -208.774284) (xy 379.218117 -208.773844) (xy 379.164169 -208.766083)
			(xy 379.111875 -208.750724) (xy 379.062298 -208.72808) (xy 379.016449 -208.698611) (xy 378.97526 -208.662917)
			(xy 378.93957 -208.621725) (xy 378.910105 -208.575874) (xy 378.887464 -208.526295) (xy 378.87211 -208.474)
			(xy 378.864354 -208.420052) (xy 375.836165 -208.420052) (xy 377.000516 -209.58429) (xy 377.007119 -209.590459)
			(xy 377.023515 -209.59803) (xy 377.041522 -209.599394) (xy 377.0503 -209.597244) (xy 377.148598 -209.569304)
			(xy 377.167902 -209.549492) (xy 377.17095 -209.53603) (xy 377.178087 -209.508626) (xy 377.199323 -209.456131)
			(xy 377.228083 -209.407351) (xy 377.263735 -209.363357) (xy 377.305497 -209.325114) (xy 377.352452 -209.293461)
			(xy 377.403568 -209.269095) (xy 377.457724 -209.252549) (xy 377.51373 -209.244188) (xy 377.542044 -209.243676)
			(xy 377.569296 -209.244137) (xy 377.623243 -209.251899) (xy 377.675538 -209.267259) (xy 377.725114 -209.289904)
			(xy 377.770963 -209.319373) (xy 377.812153 -209.355067) (xy 377.847844 -209.396259) (xy 377.87731 -209.442111)
			(xy 377.899951 -209.491689) (xy 377.915307 -209.543984) (xy 377.916172 -209.55) (xy 379.408942 -209.55)
			(xy 379.413013 -209.494378) (xy 379.425139 -209.439941) (xy 379.445062 -209.38785) (xy 379.472358 -209.339215)
			(xy 379.506444 -209.295072) (xy 379.546593 -209.256363) (xy 379.591951 -209.223912) (xy 379.641551 -209.198411)
			(xy 379.694335 -209.180404) (xy 379.749178 -209.170274) (xy 379.804912 -209.168237) (xy 379.860349 -209.174337)
			(xy 379.914306 -209.188443) (xy 379.965635 -209.210255) (xy 380.013241 -209.239309) (xy 380.056109 -209.274984)
			(xy 380.093326 -209.316521) (xy 380.124099 -209.363034) (xy 380.147771 -209.413531) (xy 380.163839 -209.466938)
			(xy 380.171959 -209.522114) (xy 380.172468 -209.55) (xy 380.171959 -209.577886) (xy 380.163839 -209.633062)
			(xy 380.147771 -209.686469) (xy 380.124099 -209.736966) (xy 380.093326 -209.783479) (xy 380.056109 -209.825016)
			(xy 380.013241 -209.860691) (xy 379.965635 -209.889745) (xy 379.914306 -209.911557) (xy 379.860349 -209.925663)
			(xy 379.804912 -209.931763) (xy 379.749178 -209.929726) (xy 379.694335 -209.919596) (xy 379.641551 -209.901589)
			(xy 379.591951 -209.876088) (xy 379.546593 -209.843637) (xy 379.506444 -209.804928) (xy 379.472358 -209.760785)
			(xy 379.445062 -209.71215) (xy 379.425139 -209.660059) (xy 379.413013 -209.605622) (xy 379.408942 -209.55)
			(xy 377.916172 -209.55) (xy 377.923065 -209.597932) (xy 377.923552 -209.625184) (xy 377.922995 -209.653494)
			(xy 377.914621 -209.709491) (xy 377.89807 -209.763638) (xy 377.873704 -209.814747) (xy 377.842057 -209.861697)
			(xy 377.803824 -209.903458) (xy 377.759843 -209.939116) (xy 377.711078 -209.967888) (xy 377.658599 -209.989142)
			(xy 377.631198 -209.996278) (xy 377.617736 -209.999326) (xy 377.597924 -210.01863) (xy 377.569984 -210.116928)
			(xy 377.567838 -210.125697) (xy 377.569262 -210.143687) (xy 377.576815 -210.160076) (xy 377.582938 -210.166712)
			(xy 377.982226 -210.566) (xy 379.759716 -210.566) (xy 379.763787 -210.510378) (xy 379.775913 -210.455941)
			(xy 379.795836 -210.40385) (xy 379.823132 -210.355215) (xy 379.857218 -210.311072) (xy 379.897367 -210.272363)
			(xy 379.942725 -210.239912) (xy 379.992325 -210.214411) (xy 380.045109 -210.196404) (xy 380.099952 -210.186274)
			(xy 380.155686 -210.184237) (xy 380.211123 -210.190337) (xy 380.26508 -210.204443) (xy 380.316409 -210.226255)
			(xy 380.364015 -210.255309) (xy 380.406883 -210.290984) (xy 380.4441 -210.332521) (xy 380.474873 -210.379034)
			(xy 380.498545 -210.429531) (xy 380.514613 -210.482938) (xy 380.522733 -210.538114) (xy 380.523242 -210.566)
			(xy 380.522733 -210.593886) (xy 380.514613 -210.649062) (xy 380.498545 -210.702469) (xy 380.474873 -210.752966)
			(xy 380.4441 -210.799479) (xy 380.406883 -210.841016) (xy 380.364015 -210.876691) (xy 380.316409 -210.905745)
			(xy 380.26508 -210.927557) (xy 380.211123 -210.941663) (xy 380.155686 -210.947763) (xy 380.099952 -210.945726)
			(xy 380.045109 -210.935596) (xy 379.992325 -210.917589) (xy 379.942725 -210.892088) (xy 379.897367 -210.859637)
			(xy 379.857218 -210.820928) (xy 379.823132 -210.776785) (xy 379.795836 -210.72815) (xy 379.775913 -210.676059)
			(xy 379.763787 -210.621622) (xy 379.759716 -210.566) (xy 377.982226 -210.566) (xy 378.925074 -211.508848)
			(xy 378.931944 -211.515166) (xy 378.948964 -211.522792) (xy 378.967585 -211.523836) (xy 378.985351 -211.518159)
			(xy 378.992892 -211.512658) (xy 379.013293 -211.496841) (xy 379.057537 -211.470247) (xy 379.10496 -211.449853)
			(xy 379.154696 -211.436031) (xy 379.205842 -211.429033) (xy 379.231652 -211.428584) (xy 379.258903 -211.4291)
			(xy 379.312852 -211.43685) (xy 379.365148 -211.4522) (xy 379.414728 -211.474836) (xy 379.460581 -211.504298)
			(xy 379.501774 -211.539987) (xy 379.537468 -211.581174) (xy 379.566937 -211.627023) (xy 379.589581 -211.676599)
			(xy 379.599096 -211.709) (xy 383.29184 -211.709) (xy 383.295911 -211.653378) (xy 383.308037 -211.598941)
			(xy 383.32796 -211.54685) (xy 383.355256 -211.498215) (xy 383.389342 -211.454072) (xy 383.429491 -211.415363)
			(xy 383.474849 -211.382912) (xy 383.524449 -211.357411) (xy 383.577233 -211.339404) (xy 383.632076 -211.329274)
			(xy 383.68781 -211.327237) (xy 383.743247 -211.333337) (xy 383.797204 -211.347443) (xy 383.848533 -211.369255)
			(xy 383.896139 -211.398309) (xy 383.939007 -211.433984) (xy 383.976224 -211.475521) (xy 384.006997 -211.522034)
			(xy 384.030669 -211.572531) (xy 384.046737 -211.625938) (xy 384.054857 -211.681114) (xy 384.055366 -211.709)
			(xy 384.054857 -211.736886) (xy 384.046737 -211.792062) (xy 384.030669 -211.845469) (xy 384.006997 -211.895966)
			(xy 383.976224 -211.942479) (xy 383.939007 -211.984016) (xy 383.896139 -212.019691) (xy 383.848533 -212.048745)
			(xy 383.797204 -212.070557) (xy 383.743247 -212.084663) (xy 383.68781 -212.090763) (xy 383.632076 -212.088726)
			(xy 383.577233 -212.078596) (xy 383.524449 -212.060589) (xy 383.474849 -212.035088) (xy 383.429491 -212.002637)
			(xy 383.389342 -211.963928) (xy 383.355256 -211.919785) (xy 383.32796 -211.87115) (xy 383.308037 -211.819059)
			(xy 383.295911 -211.764622) (xy 383.29184 -211.709) (xy 379.599096 -211.709) (xy 379.604938 -211.728893)
			(xy 379.612696 -211.782841) (xy 379.61316 -211.810092) (xy 379.61316 -211.810346) (xy 379.612552 -211.840468)
			(xy 379.60308 -211.899962) (xy 379.584378 -211.95723) (xy 379.55691 -212.010848) (xy 379.521359 -212.059484)
			(xy 379.500384 -212.08111) (xy 379.493272 -212.088222) (xy 379.485398 -212.106764) (xy 379.485144 -212.18906)
			(xy 379.485579 -212.199128) (xy 379.493292 -212.217727) (xy 379.50013 -212.225128) (xy 379.541024 -212.266022)
			(xy 379.563959 -212.289583) (xy 379.604954 -212.340997) (xy 379.63994 -212.396673) (xy 379.668477 -212.455914)
			(xy 379.690209 -212.517976) (xy 379.704862 -212.582078) (xy 379.712251 -212.647418) (xy 379.712728 -212.680296)
			(xy 379.712207 -212.715704) (xy 379.703669 -212.786004) (xy 379.686717 -212.854762) (xy 379.661599 -212.920974)
			(xy 379.628681 -212.983675) (xy 379.588443 -213.041949) (xy 379.541473 -213.094947) (xy 379.488455 -213.141895)
			(xy 379.430164 -213.182108) (xy 379.36745 -213.215) (xy 379.301227 -213.24009) (xy 379.232462 -213.257013)
			(xy 379.162158 -213.265521) (xy 379.12675 -213.26602) (xy 379.093879 -213.265552) (xy 379.028548 -213.25821)
			(xy 378.96445 -213.2436) (xy 378.90239 -213.221907) (xy 378.843148 -213.193403) (xy 378.78747 -213.158447)
			(xy 378.736055 -213.117478) (xy 378.712476 -213.09457) (xy 378.574554 -212.956648) (xy 378.56718 -212.949848)
			(xy 378.548617 -212.942277) (xy 378.52857 -212.94244) (xy 378.519182 -212.94598) (xy 378.495648 -212.955412)
			(xy 378.446713 -212.968672) (xy 378.396451 -212.97532) (xy 378.3711 -212.975698) (xy 378.346158 -212.97531)
			(xy 378.296703 -212.96878) (xy 378.248521 -212.955856) (xy 378.202437 -212.936759) (xy 378.159235 -212.911817)
			(xy 378.139198 -212.896958) (xy 378.129486 -212.890383) (xy 378.106498 -212.885888) (xy 378.083878 -212.891969)
			(xy 378.074682 -212.899244) (xy 378.047861 -212.922223) (xy 377.989695 -212.962289) (xy 377.927133 -212.995069)
			(xy 377.861084 -213.020088) (xy 377.792505 -213.036984) (xy 377.722392 -213.04551) (xy 377.687078 -213.046056)
			(xy 377.651664 -213.045564) (xy 377.581352 -213.037024) (xy 377.512583 -213.020071) (xy 377.446358 -212.994953)
			(xy 377.383644 -212.962035) (xy 377.325355 -212.921797) (xy 377.272341 -212.874828) (xy 377.225375 -212.82181)
			(xy 377.185143 -212.763518) (xy 377.152229 -212.700802) (xy 377.127116 -212.634575) (xy 377.110168 -212.565804)
			(xy 377.101633 -212.495492) (xy 377.1011 -212.460078) (xy 377.1011 -212.11413) (xy 377.100685 -212.104059)
			(xy 377.09296 -212.08546) (xy 377.086114 -212.078062) (xy 375.492264 -210.483958) (xy 375.484875 -210.477104)
			(xy 375.466267 -210.469394) (xy 375.456196 -210.468972) (xy 375.373646 -210.46948) (xy 375.355104 -210.477354)
			(xy 375.347992 -210.48472) (xy 375.326347 -210.505848) (xy 375.27764 -210.541709) (xy 375.223884 -210.569433)
			(xy 375.166427 -210.588325) (xy 375.106708 -210.597913) (xy 375.076466 -210.598512) (xy 375.075958 -210.598512)
			(xy 375.048706 -210.598061) (xy 374.994757 -210.590299) (xy 374.942462 -210.574939) (xy 374.892885 -210.552293)
			(xy 374.847035 -210.522823) (xy 374.805845 -210.487128) (xy 374.770154 -210.445935) (xy 374.740689 -210.400082)
			(xy 374.718048 -210.350502) (xy 374.702693 -210.298206) (xy 374.694936 -210.244256) (xy 374.69445 -210.217004)
			(xy 374.69445 -210.216496) (xy 374.695074 -210.186256) (xy 374.704661 -210.126538) (xy 374.723548 -210.069081)
			(xy 374.751261 -210.015322) (xy 374.787107 -209.966607) (xy 374.808242 -209.94497) (xy 374.815608 -209.937858)
			(xy 374.823482 -209.919316) (xy 374.82399 -209.836766) (xy 374.823585 -209.826694) (xy 374.81585 -209.808097)
			(xy 374.809004 -209.800698) (xy 372.870222 -207.86217) (xy 372.847312 -207.838617) (xy 372.806349 -207.787238)
			(xy 372.771396 -207.731596) (xy 372.742892 -207.67239) (xy 372.721196 -207.610366) (xy 372.706581 -207.546302)
			(xy 372.699229 -207.481005) (xy 372.698772 -207.44815) (xy 369.204494 -207.44815) (xy 369.204494 -208.161382)
			(xy 369.204748 -208.166462) (xy 369.205471 -208.17218) (xy 369.209187 -208.183087) (xy 369.212114 -208.188052)
			(xy 369.212368 -208.188052) (xy 369.215678 -208.192989) (xy 369.224146 -208.201326) (xy 369.229132 -208.204562)
			(xy 369.23599 -208.208118) (xy 369.261626 -208.219412) (xy 369.309556 -208.248411) (xy 369.352731 -208.284105)
			(xy 369.390224 -208.325727) (xy 369.421229 -208.372383) (xy 369.44508 -208.423071) (xy 369.461265 -208.476701)
			(xy 369.469436 -208.532121) (xy 369.469417 -208.58814) (xy 369.461208 -208.643554) (xy 369.444987 -208.697173)
			(xy 369.421101 -208.747845) (xy 369.390063 -208.79448) (xy 369.352542 -208.836076) (xy 369.309342 -208.871741)
			(xy 369.261393 -208.900706) (xy 369.235736 -208.911952) (xy 369.231418 -208.91373) (xy 369.225738 -208.916916)
			(xy 369.216091 -208.925659) (xy 369.212368 -208.931002) (xy 369.208558 -208.936844) (xy 369.206526 -208.943956)
			(xy 369.205576 -208.947435) (xy 369.204553 -208.954574) (xy 369.204494 -208.95818) (xy 369.204494 -209.532474)
			(xy 369.204748 -209.537554) (xy 369.20547 -209.543272) (xy 369.209184 -209.554181) (xy 369.212114 -209.559144)
			(xy 369.212368 -209.559144) (xy 369.215677 -209.564082) (xy 369.224145 -209.572419) (xy 369.229132 -209.575654)
			(xy 369.23599 -209.57921) (xy 369.261627 -209.590504) (xy 369.309557 -209.619503) (xy 369.352734 -209.655197)
			(xy 369.390228 -209.69682) (xy 369.421234 -209.743477) (xy 369.445086 -209.794165) (xy 369.461272 -209.847796)
			(xy 369.469443 -209.903217) (xy 369.469424 -209.959237) (xy 369.461216 -210.014653) (xy 369.444995 -210.068273)
			(xy 369.421108 -210.118946) (xy 369.390071 -210.165582) (xy 369.352549 -210.20718) (xy 369.309349 -210.242845)
			(xy 369.261399 -210.271811) (xy 369.235736 -210.283044) (xy 369.231418 -210.284822) (xy 369.225738 -210.288008)
			(xy 369.216089 -210.29675) (xy 369.212368 -210.302094) (xy 369.208558 -210.307936) (xy 369.206526 -210.315048)
			(xy 369.205575 -210.318527) (xy 369.204551 -210.325666) (xy 369.204494 -210.329272) (xy 369.204494 -210.702906)
			(xy 369.205581 -210.713696) (xy 369.215579 -210.732916) (xy 369.223798 -210.73999) (xy 369.231418 -210.745578)
			(xy 369.258088 -210.764628) (xy 369.264946 -210.769708) (xy 369.292124 -210.789774) (xy 369.300816 -210.795375)
			(xy 369.321015 -210.799697) (xy 369.33124 -210.798156) (xy 369.335812 -210.79714) (xy 369.336066 -210.79714)
			(xy 369.338352 -210.796378) (xy 369.33886 -210.796124) (xy 369.339114 -210.796124) (xy 369.365877 -210.788257)
			(xy 369.42096 -210.779462) (xy 369.448842 -210.778598) (xy 369.453414 -210.778598) (xy 369.480664 -210.779085)
			(xy 369.53461 -210.786843) (xy 369.586902 -210.802199) (xy 369.636476 -210.82484) (xy 369.682324 -210.854307)
			(xy 369.723512 -210.889998) (xy 369.759202 -210.931187) (xy 369.788666 -210.977036) (xy 369.811306 -211.026611)
			(xy 369.82666 -211.078904) (xy 369.834416 -211.13285) (xy 369.834416 -211.18735) (xy 369.82666 -211.241296)
			(xy 369.811306 -211.293589) (xy 369.788666 -211.343164) (xy 369.759202 -211.389013) (xy 369.723512 -211.430202)
			(xy 369.682324 -211.465893) (xy 369.636476 -211.49536) (xy 369.586902 -211.518001) (xy 369.53461 -211.533357)
			(xy 369.480664 -211.541115) (xy 369.453414 -211.541614) (xy 369.423775 -211.541055) (xy 369.365215 -211.531868)
			(xy 369.336828 -211.523326) (xy 369.336574 -211.523326) (xy 369.330824 -211.521661) (xy 369.318889 -211.520773)
			(xy 369.312952 -211.521548) (xy 369.301522 -211.523326) (xy 369.225576 -211.579206) (xy 369.225068 -211.57946)
			(xy 369.220496 -211.582762) (xy 369.217345 -211.585955) (xy 369.212105 -211.593236) (xy 369.210082 -211.59724)
			(xy 369.207288 -211.602574) (xy 369.204494 -211.614004) (xy 369.204494 -212.134958) (xy 369.207034 -212.145626)
			(xy 369.221004 -212.176614) (xy 369.22837 -212.183726) (xy 369.248382 -212.203473) (xy 369.282968 -212.247795)
			(xy 369.310676 -212.296712) (xy 369.330909 -212.349164) (xy 369.343227 -212.404018) (xy 369.347364 -212.460085)
			(xy 369.343232 -212.516152) (xy 369.330918 -212.571007) (xy 369.310689 -212.623461) (xy 369.282984 -212.67238)
			(xy 369.248402 -212.716705) (xy 369.22837 -212.73643) (xy 369.221004 -212.743542) (xy 369.209066 -212.770212)
			(xy 369.20696 -212.77516) (xy 369.204661 -212.785664) (xy 369.204494 -212.79104) (xy 369.204494 -213.97595)
			(xy 378.439932 -213.97595) (xy 378.444003 -213.920328) (xy 378.456129 -213.865891) (xy 378.476052 -213.8138)
			(xy 378.503348 -213.765165) (xy 378.537434 -213.721022) (xy 378.577583 -213.682313) (xy 378.622941 -213.649862)
			(xy 378.672541 -213.624361) (xy 378.725325 -213.606354) (xy 378.780168 -213.596224) (xy 378.835902 -213.594187)
			(xy 378.891339 -213.600287) (xy 378.945296 -213.614393) (xy 378.996625 -213.636205) (xy 379.044231 -213.665259)
			(xy 379.087099 -213.700934) (xy 379.124316 -213.742471) (xy 379.155089 -213.788984) (xy 379.178761 -213.839481)
			(xy 379.194829 -213.892888) (xy 379.202949 -213.948064) (xy 379.203458 -213.97595) (xy 379.202949 -214.003836)
			(xy 379.194829 -214.059012) (xy 379.178761 -214.112419) (xy 379.155089 -214.162916) (xy 379.124316 -214.209429)
			(xy 379.087099 -214.250966) (xy 379.044231 -214.286641) (xy 378.996625 -214.315695) (xy 378.945296 -214.337507)
			(xy 378.891339 -214.351613) (xy 378.835902 -214.357713) (xy 378.780168 -214.355676) (xy 378.725325 -214.345546)
			(xy 378.672541 -214.327539) (xy 378.622941 -214.302038) (xy 378.577583 -214.269587) (xy 378.537434 -214.230878)
			(xy 378.503348 -214.186735) (xy 378.476052 -214.1381) (xy 378.456129 -214.086009) (xy 378.444003 -214.031572)
			(xy 378.439932 -213.97595) (xy 369.204494 -213.97595) (xy 369.204494 -216.694258) (xy 369.204748 -216.699084)
			(xy 369.204748 -216.699338) (xy 369.205707 -216.706064) (xy 369.210733 -216.718681) (xy 369.214654 -216.72423)
			(xy 369.219226 -216.729564) (xy 371.273578 -218.783916) (xy 373.884188 -218.783916) (xy 373.888259 -218.728294)
			(xy 373.900385 -218.673857) (xy 373.920308 -218.621766) (xy 373.947604 -218.573131) (xy 373.98169 -218.528988)
			(xy 374.021839 -218.490279) (xy 374.067197 -218.457828) (xy 374.116797 -218.432327) (xy 374.169581 -218.41432)
			(xy 374.224424 -218.40419) (xy 374.280158 -218.402153) (xy 374.289401 -218.40317) (xy 380.707644 -218.40317)
			(xy 380.711715 -218.347548) (xy 380.723841 -218.293111) (xy 380.743764 -218.24102) (xy 380.77106 -218.192385)
			(xy 380.805146 -218.148242) (xy 380.845295 -218.109533) (xy 380.890653 -218.077082) (xy 380.940253 -218.051581)
			(xy 380.993037 -218.033574) (xy 381.04788 -218.023444) (xy 381.103614 -218.021407) (xy 381.159051 -218.027507)
			(xy 381.213008 -218.041613) (xy 381.264337 -218.063425) (xy 381.311943 -218.092479) (xy 381.354811 -218.128154)
			(xy 381.392028 -218.169691) (xy 381.422801 -218.216204) (xy 381.446473 -218.266701) (xy 381.462541 -218.320108)
			(xy 381.469382 -218.366594) (xy 381.872234 -218.366594) (xy 381.876305 -218.310972) (xy 381.888431 -218.256535)
			(xy 381.908354 -218.204444) (xy 381.93565 -218.155809) (xy 381.969736 -218.111666) (xy 382.009885 -218.072957)
			(xy 382.055243 -218.040506) (xy 382.104843 -218.015005) (xy 382.157627 -217.996998) (xy 382.21247 -217.986868)
			(xy 382.268204 -217.984831) (xy 382.323641 -217.990931) (xy 382.377598 -218.005037) (xy 382.428927 -218.026849)
			(xy 382.476533 -218.055903) (xy 382.519401 -218.091578) (xy 382.556618 -218.133115) (xy 382.587391 -218.179628)
			(xy 382.611063 -218.230125) (xy 382.627131 -218.283532) (xy 382.635251 -218.338708) (xy 382.63576 -218.366594)
			(xy 382.635251 -218.39448) (xy 382.627131 -218.449656) (xy 382.611063 -218.503063) (xy 382.587391 -218.55356)
			(xy 382.556618 -218.600073) (xy 382.519401 -218.64161) (xy 382.476533 -218.677285) (xy 382.428927 -218.706339)
			(xy 382.377598 -218.728151) (xy 382.323641 -218.742257) (xy 382.268204 -218.748357) (xy 382.21247 -218.74632)
			(xy 382.157627 -218.73619) (xy 382.104843 -218.718183) (xy 382.055243 -218.692682) (xy 382.009885 -218.660231)
			(xy 381.969736 -218.621522) (xy 381.93565 -218.577379) (xy 381.908354 -218.528744) (xy 381.888431 -218.476653)
			(xy 381.876305 -218.422216) (xy 381.872234 -218.366594) (xy 381.469382 -218.366594) (xy 381.470661 -218.375284)
			(xy 381.47117 -218.40317) (xy 381.470661 -218.431056) (xy 381.462541 -218.486232) (xy 381.446473 -218.539639)
			(xy 381.422801 -218.590136) (xy 381.392028 -218.636649) (xy 381.354811 -218.678186) (xy 381.311943 -218.713861)
			(xy 381.264337 -218.742915) (xy 381.213008 -218.764727) (xy 381.159051 -218.778833) (xy 381.103614 -218.784933)
			(xy 381.04788 -218.782896) (xy 380.993037 -218.772766) (xy 380.940253 -218.754759) (xy 380.890653 -218.729258)
			(xy 380.845295 -218.696807) (xy 380.805146 -218.658098) (xy 380.77106 -218.613955) (xy 380.743764 -218.56532)
			(xy 380.723841 -218.513229) (xy 380.711715 -218.458792) (xy 380.707644 -218.40317) (xy 374.289401 -218.40317)
			(xy 374.335595 -218.408253) (xy 374.389552 -218.422359) (xy 374.440881 -218.444171) (xy 374.488487 -218.473225)
			(xy 374.531355 -218.5089) (xy 374.568572 -218.550437) (xy 374.599345 -218.59695) (xy 374.623017 -218.647447)
			(xy 374.639085 -218.700854) (xy 374.647205 -218.75603) (xy 374.647714 -218.783916) (xy 374.647205 -218.811802)
			(xy 374.639085 -218.866978) (xy 374.623017 -218.920385) (xy 374.599345 -218.970882) (xy 374.568572 -219.017395)
			(xy 374.531355 -219.058932) (xy 374.488487 -219.094607) (xy 374.440881 -219.123661) (xy 374.389552 -219.145473)
			(xy 374.335595 -219.159579) (xy 374.280158 -219.165679) (xy 374.224424 -219.163642) (xy 374.169581 -219.153512)
			(xy 374.116797 -219.135505) (xy 374.067197 -219.110004) (xy 374.021839 -219.077553) (xy 373.98169 -219.038844)
			(xy 373.947604 -218.994701) (xy 373.920308 -218.946066) (xy 373.900385 -218.893975) (xy 373.888259 -218.839538)
			(xy 373.884188 -218.783916) (xy 371.273578 -218.783916) (xy 372.68658 -220.196918) (xy 372.692168 -220.201744)
			(xy 372.69891 -220.206406) (xy 372.714457 -220.211573) (xy 372.722648 -220.211904) (xy 374.188482 -220.211904)
			(xy 374.209915 -220.212297) (xy 374.252351 -220.218367) (xy 374.293515 -220.230332) (xy 374.313196 -220.238828)
			(xy 374.313704 -220.239082) (xy 374.319038 -220.241368) (xy 374.32615 -220.242892) (xy 374.329794 -220.243545)
			(xy 374.337189 -220.243921) (xy 374.340882 -220.243654) (xy 374.350788 -220.241622) (xy 374.353328 -220.24086)
			(xy 374.359424 -220.238574) (xy 374.365012 -220.236542) (xy 374.368772 -220.235009) (xy 374.375791 -220.230926)
			(xy 374.378982 -220.228414) (xy 374.401828 -220.210484) (xy 374.451874 -220.181022) (xy 374.505805 -220.159478)
			(xy 374.562375 -220.14635) (xy 374.620282 -220.14194) (xy 374.678189 -220.14635) (xy 374.734759 -220.159478)
			(xy 374.78869 -220.181022) (xy 374.838736 -220.210484) (xy 374.861582 -220.228414) (xy 374.864775 -220.230922)
			(xy 374.871797 -220.234998) (xy 374.875552 -220.236542) (xy 374.88114 -220.238574) (xy 374.887236 -220.24086)
			(xy 374.889776 -220.241622) (xy 374.899682 -220.243654) (xy 374.903375 -220.243944) (xy 374.910771 -220.243562)
			(xy 374.914414 -220.242892) (xy 374.921526 -220.241368) (xy 374.92686 -220.239082) (xy 374.927368 -220.238828)
			(xy 374.947061 -220.230366) (xy 374.988224 -220.218415) (xy 375.030652 -220.212329) (xy 375.052082 -220.211904)
			(xy 378.37364 -220.211904) (xy 378.397606 -220.212398) (xy 378.444943 -220.219931) (xy 378.490524 -220.234761)
			(xy 378.533232 -220.256523) (xy 378.57202 -220.284685) (xy 378.589286 -220.301312) (xy 378.612129 -220.324172)
			(xy 383.84683 -220.324172) (xy 383.850901 -220.26855) (xy 383.863027 -220.214113) (xy 383.88295 -220.162022)
			(xy 383.910246 -220.113387) (xy 383.944332 -220.069244) (xy 383.984481 -220.030535) (xy 384.029839 -219.998084)
			(xy 384.079439 -219.972583) (xy 384.132223 -219.954576) (xy 384.187066 -219.944446) (xy 384.2428 -219.942409)
			(xy 384.298237 -219.948509) (xy 384.352194 -219.962615) (xy 384.403523 -219.984427) (xy 384.451129 -220.013481)
			(xy 384.493997 -220.049156) (xy 384.531214 -220.090693) (xy 384.561987 -220.137206) (xy 384.585659 -220.187703)
			(xy 384.601727 -220.24111) (xy 384.609847 -220.296286) (xy 384.610356 -220.324172) (xy 384.609847 -220.352058)
			(xy 384.601727 -220.407234) (xy 384.585659 -220.460641) (xy 384.561987 -220.511138) (xy 384.531214 -220.557651)
			(xy 384.493997 -220.599188) (xy 384.451129 -220.634863) (xy 384.403523 -220.663917) (xy 384.352194 -220.685729)
			(xy 384.298237 -220.699835) (xy 384.2428 -220.705935) (xy 384.187066 -220.703898) (xy 384.132223 -220.693768)
			(xy 384.079439 -220.675761) (xy 384.029839 -220.65026) (xy 383.984481 -220.617809) (xy 383.944332 -220.5791)
			(xy 383.910246 -220.534957) (xy 383.88295 -220.486322) (xy 383.863027 -220.434231) (xy 383.850901 -220.379794)
			(xy 383.84683 -220.324172) (xy 378.612129 -220.324172) (xy 378.940568 -220.652848) (xy 378.946727 -220.658136)
			(xy 378.961494 -220.664857) (xy 378.969524 -220.666056) (xy 378.974096 -220.66631) (xy 379.145292 -220.66631)
			(xy 379.155363 -220.666732) (xy 379.173968 -220.674445) (xy 379.18136 -220.681296) (xy 379.503686 -221.003622)
			(xy 379.51053 -221.011021) (xy 379.518259 -221.029619) (xy 379.518672 -221.03969) (xy 379.518672 -221.955106)
			(xy 380.780034 -221.955106) (xy 380.784105 -221.899484) (xy 380.796231 -221.845047) (xy 380.816154 -221.792956)
			(xy 380.84345 -221.744321) (xy 380.877536 -221.700178) (xy 380.917685 -221.661469) (xy 380.963043 -221.629018)
			(xy 381.012643 -221.603517) (xy 381.065427 -221.58551) (xy 381.12027 -221.57538) (xy 381.176004 -221.573343)
			(xy 381.231441 -221.579443) (xy 381.285398 -221.593549) (xy 381.336727 -221.615361) (xy 381.384333 -221.644415)
			(xy 381.427201 -221.68009) (xy 381.464418 -221.721627) (xy 381.495191 -221.76814) (xy 381.518863 -221.818637)
			(xy 381.534931 -221.872044) (xy 381.543051 -221.92722) (xy 381.543286 -221.94012) (xy 385.30479 -221.94012)
			(xy 385.308861 -221.884498) (xy 385.320987 -221.830061) (xy 385.34091 -221.77797) (xy 385.368206 -221.729335)
			(xy 385.402292 -221.685192) (xy 385.442441 -221.646483) (xy 385.487799 -221.614032) (xy 385.537399 -221.588531)
			(xy 385.590183 -221.570524) (xy 385.645026 -221.560394) (xy 385.70076 -221.558357) (xy 385.756197 -221.564457)
			(xy 385.810154 -221.578563) (xy 385.861483 -221.600375) (xy 385.909089 -221.629429) (xy 385.951957 -221.665104)
			(xy 385.989174 -221.706641) (xy 386.019947 -221.753154) (xy 386.043619 -221.803651) (xy 386.059687 -221.857058)
			(xy 386.067807 -221.912234) (xy 386.068316 -221.94012) (xy 386.067807 -221.968006) (xy 386.059687 -222.023182)
			(xy 386.043619 -222.076589) (xy 386.019947 -222.127086) (xy 385.989174 -222.173599) (xy 385.951957 -222.215136)
			(xy 385.909089 -222.250811) (xy 385.861483 -222.279865) (xy 385.810154 -222.301677) (xy 385.756197 -222.315783)
			(xy 385.70076 -222.321883) (xy 385.645026 -222.319846) (xy 385.590183 -222.309716) (xy 385.537399 -222.291709)
			(xy 385.487799 -222.266208) (xy 385.442441 -222.233757) (xy 385.402292 -222.195048) (xy 385.368206 -222.150905)
			(xy 385.34091 -222.10227) (xy 385.320987 -222.050179) (xy 385.308861 -221.995742) (xy 385.30479 -221.94012)
			(xy 381.543286 -221.94012) (xy 381.54356 -221.955106) (xy 381.543051 -221.982992) (xy 381.534931 -222.038168)
			(xy 381.518863 -222.091575) (xy 381.495191 -222.142072) (xy 381.464418 -222.188585) (xy 381.427201 -222.230122)
			(xy 381.384333 -222.265797) (xy 381.336727 -222.294851) (xy 381.285398 -222.316663) (xy 381.231441 -222.330769)
			(xy 381.176004 -222.336869) (xy 381.12027 -222.334832) (xy 381.065427 -222.324702) (xy 381.012643 -222.306695)
			(xy 380.963043 -222.281194) (xy 380.917685 -222.248743) (xy 380.877536 -222.210034) (xy 380.84345 -222.165891)
			(xy 380.816154 -222.117256) (xy 380.796231 -222.065165) (xy 380.784105 -222.010728) (xy 380.780034 -221.955106)
			(xy 379.518672 -221.955106) (xy 379.518672 -223.240092) (xy 385.3213 -223.240092) (xy 385.325371 -223.18447)
			(xy 385.337497 -223.130033) (xy 385.35742 -223.077942) (xy 385.384716 -223.029307) (xy 385.418802 -222.985164)
			(xy 385.458951 -222.946455) (xy 385.504309 -222.914004) (xy 385.553909 -222.888503) (xy 385.606693 -222.870496)
			(xy 385.661536 -222.860366) (xy 385.71727 -222.858329) (xy 385.772707 -222.864429) (xy 385.826664 -222.878535)
			(xy 385.877993 -222.900347) (xy 385.925599 -222.929401) (xy 385.968467 -222.965076) (xy 386.005684 -223.006613)
			(xy 386.036457 -223.053126) (xy 386.060129 -223.103623) (xy 386.076197 -223.15703) (xy 386.084317 -223.212206)
			(xy 386.084826 -223.240092) (xy 386.084317 -223.267978) (xy 386.076197 -223.323154) (xy 386.060129 -223.376561)
			(xy 386.036457 -223.427058) (xy 386.005684 -223.473571) (xy 385.968467 -223.515108) (xy 385.925599 -223.550783)
			(xy 385.877993 -223.579837) (xy 385.826664 -223.601649) (xy 385.772707 -223.615755) (xy 385.71727 -223.621855)
			(xy 385.661536 -223.619818) (xy 385.606693 -223.609688) (xy 385.553909 -223.591681) (xy 385.504309 -223.56618)
			(xy 385.458951 -223.533729) (xy 385.418802 -223.49502) (xy 385.384716 -223.450877) (xy 385.35742 -223.402242)
			(xy 385.337497 -223.350151) (xy 385.325371 -223.295714) (xy 385.3213 -223.240092) (xy 379.518672 -223.240092)
			(xy 379.518672 -224.114106) (xy 379.518672 -224.11436) (xy 379.519271 -224.125407) (xy 379.528621 -224.145431)
			(xy 379.545493 -224.159704) (xy 379.55601 -224.163128) (xy 379.55855 -224.163636) (xy 379.584982 -224.169967)
			(xy 379.635851 -224.189106) (xy 379.683487 -224.215274) (xy 379.726925 -224.24794) (xy 379.765286 -224.286442)
			(xy 379.797791 -224.330001) (xy 379.823782 -224.377734) (xy 379.842732 -224.428673) (xy 379.854259 -224.481788)
			(xy 379.858127 -224.536) (xy 379.854259 -224.590212) (xy 379.842732 -224.643327) (xy 379.823782 -224.694266)
			(xy 379.797791 -224.741999) (xy 379.765286 -224.785558) (xy 379.726925 -224.82406) (xy 379.683487 -224.856726)
			(xy 379.635851 -224.882894) (xy 379.584982 -224.902033) (xy 379.55855 -224.908364) (xy 379.55601 -224.908872)
			(xy 379.545497 -224.912319) (xy 379.528604 -224.926566) (xy 379.519258 -224.946592) (xy 379.518672 -224.95764)
			(xy 379.518672 -226.924108) (xy 379.519275 -226.935438) (xy 379.529038 -226.955884) (xy 379.537468 -226.963478)
			(xy 379.598428 -227.013008) (xy 379.602884 -227.016532) (xy 379.613016 -227.021666) (xy 379.618494 -227.023168)
			(xy 379.62967 -227.025708) (xy 379.640846 -227.023422) (xy 379.659809 -227.01974) (xy 379.698238 -227.015791)
			(xy 379.717554 -227.015548) (xy 379.718316 -227.015548) (xy 379.74557 -227.016035) (xy 379.799522 -227.023794)
			(xy 379.851821 -227.039153) (xy 379.901402 -227.061797) (xy 379.947255 -227.091267) (xy 379.988448 -227.126963)
			(xy 380.024142 -227.168158) (xy 380.05361 -227.214012) (xy 380.076253 -227.263594) (xy 380.091609 -227.315894)
			(xy 380.099366 -227.369846) (xy 380.099366 -227.424354) (xy 380.091609 -227.478306) (xy 380.076253 -227.530606)
			(xy 380.05361 -227.580188) (xy 380.024142 -227.626042) (xy 379.988448 -227.667237) (xy 379.947255 -227.702933)
			(xy 379.901402 -227.732403) (xy 379.851821 -227.755047) (xy 379.799522 -227.770406) (xy 379.74557 -227.778165)
			(xy 379.718316 -227.778564) (xy 379.717554 -227.778564) (xy 379.69824 -227.778292) (xy 379.659813 -227.774343)
			(xy 379.640846 -227.77069) (xy 379.62967 -227.768404) (xy 379.618494 -227.770944) (xy 379.613029 -227.772484)
			(xy 379.602899 -227.777606) (xy 379.598428 -227.781104) (xy 379.537468 -227.830634) (xy 379.529068 -227.83825)
			(xy 379.51931 -227.858684) (xy 379.518672 -227.870004) (xy 379.518672 -228.467666) (xy 381.166114 -228.467666)
			(xy 381.170185 -228.412044) (xy 381.182311 -228.357607) (xy 381.202234 -228.305516) (xy 381.22953 -228.256881)
			(xy 381.263616 -228.212738) (xy 381.303765 -228.174029) (xy 381.349123 -228.141578) (xy 381.398723 -228.116077)
			(xy 381.451507 -228.09807) (xy 381.50635 -228.08794) (xy 381.562084 -228.085903) (xy 381.617521 -228.092003)
			(xy 381.671478 -228.106109) (xy 381.722807 -228.127921) (xy 381.770413 -228.156975) (xy 381.813281 -228.19265)
			(xy 381.850498 -228.234187) (xy 381.881271 -228.2807) (xy 381.904943 -228.331197) (xy 381.921011 -228.384604)
			(xy 381.929131 -228.43978) (xy 381.92964 -228.467666) (xy 381.929131 -228.495552) (xy 381.921011 -228.550728)
			(xy 381.904943 -228.604135) (xy 381.881271 -228.654632) (xy 381.850498 -228.701145) (xy 381.813281 -228.742682)
			(xy 381.770413 -228.778357) (xy 381.722807 -228.807411) (xy 381.671478 -228.829223) (xy 381.617521 -228.843329)
			(xy 381.562084 -228.849429) (xy 381.50635 -228.847392) (xy 381.451507 -228.837262) (xy 381.398723 -228.819255)
			(xy 381.349123 -228.793754) (xy 381.303765 -228.761303) (xy 381.263616 -228.722594) (xy 381.22953 -228.678451)
			(xy 381.202234 -228.629816) (xy 381.182311 -228.577725) (xy 381.170185 -228.523288) (xy 381.166114 -228.467666)
			(xy 379.518672 -228.467666) (xy 379.518672 -228.862636) (xy 386.430266 -228.862636) (xy 386.430729 -228.836217)
			(xy 386.43801 -228.783882) (xy 386.45245 -228.733056) (xy 386.473773 -228.684711) (xy 386.50157 -228.639775)
			(xy 386.535308 -228.59911) (xy 386.57434 -228.563496) (xy 386.595874 -228.548184) (xy 386.606928 -228.540017)
			(xy 386.6246 -228.518983) (xy 386.636016 -228.493996) (xy 386.640347 -228.466868) (xy 386.63728 -228.439568)
			(xy 386.627037 -228.414077) (xy 386.61036 -228.392246) (xy 386.599684 -228.383592) (xy 386.576676 -228.365401)
			(xy 386.535941 -228.323205) (xy 386.502137 -228.275277) (xy 386.476061 -228.222742) (xy 386.458325 -228.166838)
			(xy 386.449348 -228.108879) (xy 386.448808 -228.079554) (xy 386.449294 -228.052303) (xy 386.45705 -227.998355)
			(xy 386.472405 -227.94606) (xy 386.495047 -227.896483) (xy 386.524513 -227.850633) (xy 386.560204 -227.809442)
			(xy 386.601395 -227.773751) (xy 386.647245 -227.744285) (xy 386.696822 -227.721643) (xy 386.749117 -227.706288)
			(xy 386.803065 -227.698532) (xy 386.857567 -227.698532) (xy 386.911515 -227.706288) (xy 386.96381 -227.721643)
			(xy 387.013387 -227.744285) (xy 387.059237 -227.773751) (xy 387.100428 -227.809442) (xy 387.136119 -227.850633)
			(xy 387.165585 -227.896483) (xy 387.188227 -227.94606) (xy 387.203582 -227.998355) (xy 387.211338 -228.052303)
			(xy 387.211824 -228.079554) (xy 387.211358 -228.105973) (xy 387.204078 -228.158308) (xy 387.189639 -228.209135)
			(xy 387.168317 -228.257479) (xy 387.14052 -228.302415) (xy 387.106782 -228.34308) (xy 387.06775 -228.378694)
			(xy 387.046216 -228.394006) (xy 387.035172 -228.402186) (xy 387.017502 -228.423217) (xy 387.006087 -228.448201)
			(xy 387.001755 -228.475326) (xy 387.00482 -228.502624) (xy 387.01506 -228.528113) (xy 387.031732 -228.549943)
			(xy 387.042406 -228.558598) (xy 387.065455 -228.57674) (xy 387.106188 -228.618945) (xy 387.139987 -228.666884)
			(xy 387.166057 -228.719428) (xy 387.183783 -228.775342) (xy 387.192749 -228.833308) (xy 387.193282 -228.862636)
			(xy 387.192796 -228.889887) (xy 387.18504 -228.943835) (xy 387.169685 -228.99613) (xy 387.147043 -229.045707)
			(xy 387.117577 -229.091557) (xy 387.081886 -229.132748) (xy 387.040695 -229.168439) (xy 386.994845 -229.197905)
			(xy 386.945268 -229.220547) (xy 386.892973 -229.235902) (xy 386.839025 -229.243658) (xy 386.784523 -229.243658)
			(xy 386.730575 -229.235902) (xy 386.67828 -229.220547) (xy 386.628703 -229.197905) (xy 386.582853 -229.168439)
			(xy 386.541662 -229.132748) (xy 386.505971 -229.091557) (xy 386.476505 -229.045707) (xy 386.453863 -228.99613)
			(xy 386.438508 -228.943835) (xy 386.430752 -228.889887) (xy 386.430266 -228.862636) (xy 379.518672 -228.862636)
			(xy 379.518672 -229.013512) (xy 379.519688 -229.023164) (xy 379.521316 -229.030408) (xy 379.528155 -229.043579)
			(xy 379.53315 -229.049072) (xy 379.763274 -229.279196) (xy 379.770124 -229.286593) (xy 379.777864 -229.305191)
			(xy 379.77826 -229.315264) (xy 379.77826 -229.37724) (xy 392.719558 -229.37724) (xy 392.723629 -229.321618)
			(xy 392.735755 -229.267181) (xy 392.755678 -229.21509) (xy 392.782974 -229.166455) (xy 392.81706 -229.122312)
			(xy 392.857209 -229.083603) (xy 392.902567 -229.051152) (xy 392.952167 -229.025651) (xy 393.004951 -229.007644)
			(xy 393.059794 -228.997514) (xy 393.115528 -228.995477) (xy 393.170965 -229.001577) (xy 393.224922 -229.015683)
			(xy 393.276251 -229.037495) (xy 393.323857 -229.066549) (xy 393.366725 -229.102224) (xy 393.403942 -229.143761)
			(xy 393.434715 -229.190274) (xy 393.458387 -229.240771) (xy 393.474455 -229.294178) (xy 393.482575 -229.349354)
			(xy 393.483084 -229.37724) (xy 393.482575 -229.405126) (xy 393.474455 -229.460302) (xy 393.458387 -229.513709)
			(xy 393.434715 -229.564206) (xy 393.403942 -229.610719) (xy 393.366725 -229.652256) (xy 393.323857 -229.687931)
			(xy 393.276251 -229.716985) (xy 393.224922 -229.738797) (xy 393.170965 -229.752903) (xy 393.115528 -229.759003)
			(xy 393.059794 -229.756966) (xy 393.004951 -229.746836) (xy 392.952167 -229.728829) (xy 392.902567 -229.703328)
			(xy 392.857209 -229.670877) (xy 392.81706 -229.632168) (xy 392.782974 -229.588025) (xy 392.755678 -229.53939)
			(xy 392.735755 -229.487299) (xy 392.723629 -229.432862) (xy 392.719558 -229.37724) (xy 379.77826 -229.37724)
			(xy 379.77826 -231.07396) (xy 381.686814 -231.07396) (xy 381.690885 -231.018338) (xy 381.703011 -230.963901)
			(xy 381.722934 -230.91181) (xy 381.75023 -230.863175) (xy 381.784316 -230.819032) (xy 381.824465 -230.780323)
			(xy 381.869823 -230.747872) (xy 381.919423 -230.722371) (xy 381.972207 -230.704364) (xy 382.02705 -230.694234)
			(xy 382.082784 -230.692197) (xy 382.138221 -230.698297) (xy 382.192178 -230.712403) (xy 382.243507 -230.734215)
			(xy 382.291113 -230.763269) (xy 382.333981 -230.798944) (xy 382.371198 -230.840481) (xy 382.401971 -230.886994)
			(xy 382.40975 -230.903589) (xy 383.216061 -230.903589) (xy 383.216061 -230.843611) (xy 383.22389 -230.784147)
			(xy 383.239413 -230.726213) (xy 383.262366 -230.670801) (xy 383.292355 -230.618858) (xy 383.328867 -230.571275)
			(xy 383.371278 -230.528865) (xy 383.418862 -230.492353) (xy 383.470804 -230.462364) (xy 383.526216 -230.439412)
			(xy 383.584151 -230.423889) (xy 383.643615 -230.416061) (xy 383.673604 -230.415592) (xy 384.537204 -230.415592)
			(xy 384.567185 -230.416174) (xy 384.626634 -230.424001) (xy 384.684553 -230.439521) (xy 384.739951 -230.462468)
			(xy 384.79188 -230.492449) (xy 384.839451 -230.528952) (xy 384.88185 -230.571352) (xy 384.918353 -230.618924)
			(xy 384.948334 -230.670853) (xy 384.97128 -230.726251) (xy 384.986799 -230.78417) (xy 384.994626 -230.843619)
			(xy 384.994626 -230.903581) (xy 384.986799 -230.96303) (xy 384.97128 -231.020949) (xy 384.96847 -231.027732)
			(xy 386.97357 -231.027732) (xy 386.977641 -230.97211) (xy 386.989767 -230.917673) (xy 387.00969 -230.865582)
			(xy 387.036986 -230.816947) (xy 387.071072 -230.772804) (xy 387.111221 -230.734095) (xy 387.156579 -230.701644)
			(xy 387.206179 -230.676143) (xy 387.258963 -230.658136) (xy 387.313806 -230.648006) (xy 387.36954 -230.645969)
			(xy 387.424977 -230.652069) (xy 387.478934 -230.666175) (xy 387.530263 -230.687987) (xy 387.577869 -230.717041)
			(xy 387.620737 -230.752716) (xy 387.657954 -230.794253) (xy 387.688727 -230.840766) (xy 387.712399 -230.891263)
			(xy 387.728467 -230.94467) (xy 387.736587 -230.999846) (xy 387.737096 -231.027732) (xy 387.736587 -231.055618)
			(xy 387.728467 -231.110794) (xy 387.712399 -231.164201) (xy 387.688727 -231.214698) (xy 387.657954 -231.261211)
			(xy 387.620737 -231.302748) (xy 387.585253 -231.332278) (xy 392.830302 -231.332278) (xy 392.834373 -231.276656)
			(xy 392.846499 -231.222219) (xy 392.866422 -231.170128) (xy 392.893718 -231.121493) (xy 392.927804 -231.07735)
			(xy 392.967953 -231.038641) (xy 393.013311 -231.00619) (xy 393.062911 -230.980689) (xy 393.115695 -230.962682)
			(xy 393.170538 -230.952552) (xy 393.226272 -230.950515) (xy 393.281709 -230.956615) (xy 393.335666 -230.970721)
			(xy 393.386995 -230.992533) (xy 393.434601 -231.021587) (xy 393.477469 -231.057262) (xy 393.514686 -231.098799)
			(xy 393.545459 -231.145312) (xy 393.569131 -231.195809) (xy 393.585199 -231.249216) (xy 393.593319 -231.304392)
			(xy 393.593828 -231.332278) (xy 393.593319 -231.360164) (xy 393.585199 -231.41534) (xy 393.569131 -231.468747)
			(xy 393.545459 -231.519244) (xy 393.514686 -231.565757) (xy 393.477469 -231.607294) (xy 393.434601 -231.642969)
			(xy 393.386995 -231.672023) (xy 393.335666 -231.693835) (xy 393.281709 -231.707941) (xy 393.226272 -231.714041)
			(xy 393.170538 -231.712004) (xy 393.115695 -231.701874) (xy 393.062911 -231.683867) (xy 393.013311 -231.658366)
			(xy 392.967953 -231.625915) (xy 392.927804 -231.587206) (xy 392.893718 -231.543063) (xy 392.866422 -231.494428)
			(xy 392.846499 -231.442337) (xy 392.834373 -231.3879) (xy 392.830302 -231.332278) (xy 387.585253 -231.332278)
			(xy 387.577869 -231.338423) (xy 387.530263 -231.367477) (xy 387.478934 -231.389289) (xy 387.424977 -231.403395)
			(xy 387.36954 -231.409495) (xy 387.313806 -231.407458) (xy 387.258963 -231.397328) (xy 387.206179 -231.379321)
			(xy 387.156579 -231.35382) (xy 387.111221 -231.321369) (xy 387.071072 -231.28266) (xy 387.036986 -231.238517)
			(xy 387.00969 -231.189882) (xy 386.989767 -231.137791) (xy 386.977641 -231.083354) (xy 386.97357 -231.027732)
			(xy 384.96847 -231.027732) (xy 384.948334 -231.076347) (xy 384.918353 -231.128276) (xy 384.88185 -231.175848)
			(xy 384.839451 -231.218248) (xy 384.79188 -231.254751) (xy 384.739951 -231.284732) (xy 384.684553 -231.307679)
			(xy 384.626634 -231.323199) (xy 384.567185 -231.331026) (xy 384.537204 -231.331516) (xy 383.673604 -231.331516)
			(xy 383.643615 -231.331139) (xy 383.584151 -231.323311) (xy 383.526216 -231.307788) (xy 383.470804 -231.284836)
			(xy 383.418862 -231.254847) (xy 383.371278 -231.218335) (xy 383.328867 -231.175925) (xy 383.292355 -231.128342)
			(xy 383.262366 -231.076399) (xy 383.239413 -231.020987) (xy 383.22389 -230.963053) (xy 383.216061 -230.903589)
			(xy 382.40975 -230.903589) (xy 382.425643 -230.937491) (xy 382.441711 -230.990898) (xy 382.449831 -231.046074)
			(xy 382.45034 -231.07396) (xy 382.449831 -231.101846) (xy 382.441711 -231.157022) (xy 382.425643 -231.210429)
			(xy 382.401971 -231.260926) (xy 382.371198 -231.307439) (xy 382.333981 -231.348976) (xy 382.291113 -231.384651)
			(xy 382.243507 -231.413705) (xy 382.192178 -231.435517) (xy 382.138221 -231.449623) (xy 382.082784 -231.455723)
			(xy 382.02705 -231.453686) (xy 381.972207 -231.443556) (xy 381.919423 -231.425549) (xy 381.869823 -231.400048)
			(xy 381.824465 -231.367597) (xy 381.784316 -231.328888) (xy 381.75023 -231.284745) (xy 381.722934 -231.23611)
			(xy 381.703011 -231.184019) (xy 381.690885 -231.129582) (xy 381.686814 -231.07396) (xy 379.77826 -231.07396)
			(xy 379.77826 -232.585006) (xy 392.937998 -232.585006) (xy 392.942069 -232.529384) (xy 392.954195 -232.474947)
			(xy 392.974118 -232.422856) (xy 393.001414 -232.374221) (xy 393.0355 -232.330078) (xy 393.075649 -232.291369)
			(xy 393.121007 -232.258918) (xy 393.170607 -232.233417) (xy 393.223391 -232.21541) (xy 393.278234 -232.20528)
			(xy 393.333968 -232.203243) (xy 393.389405 -232.209343) (xy 393.443362 -232.223449) (xy 393.494691 -232.245261)
			(xy 393.542297 -232.274315) (xy 393.585165 -232.30999) (xy 393.622382 -232.351527) (xy 393.653155 -232.39804)
			(xy 393.676827 -232.448537) (xy 393.692895 -232.501944) (xy 393.701015 -232.55712) (xy 393.701524 -232.585006)
			(xy 393.701015 -232.612892) (xy 393.692895 -232.668068) (xy 393.676827 -232.721475) (xy 393.653155 -232.771972)
			(xy 393.622382 -232.818485) (xy 393.585165 -232.860022) (xy 393.542297 -232.895697) (xy 393.494691 -232.924751)
			(xy 393.443362 -232.946563) (xy 393.389405 -232.960669) (xy 393.333968 -232.966769) (xy 393.278234 -232.964732)
			(xy 393.223391 -232.954602) (xy 393.170607 -232.936595) (xy 393.121007 -232.911094) (xy 393.075649 -232.878643)
			(xy 393.0355 -232.839934) (xy 393.001414 -232.795791) (xy 392.974118 -232.747156) (xy 392.954195 -232.695065)
			(xy 392.942069 -232.640628) (xy 392.937998 -232.585006) (xy 379.77826 -232.585006) (xy 379.77826 -233.99496)
			(xy 381.97358 -233.99496) (xy 381.977651 -233.939338) (xy 381.989777 -233.884901) (xy 382.0097 -233.83281)
			(xy 382.036996 -233.784175) (xy 382.071082 -233.740032) (xy 382.111231 -233.701323) (xy 382.156589 -233.668872)
			(xy 382.206189 -233.643371) (xy 382.258973 -233.625364) (xy 382.313816 -233.615234) (xy 382.36955 -233.613197)
			(xy 382.424987 -233.619297) (xy 382.478944 -233.633403) (xy 382.530273 -233.655215) (xy 382.577879 -233.684269)
			(xy 382.620747 -233.719944) (xy 382.657964 -233.761481) (xy 382.688737 -233.807994) (xy 382.712409 -233.858491)
			(xy 382.728477 -233.911898) (xy 382.736597 -233.967074) (xy 382.737041 -233.991404) (xy 382.973578 -233.991404)
			(xy 382.977649 -233.935782) (xy 382.989775 -233.881345) (xy 383.009698 -233.829254) (xy 383.036994 -233.780619)
			(xy 383.07108 -233.736476) (xy 383.111229 -233.697767) (xy 383.156587 -233.665316) (xy 383.206187 -233.639815)
			(xy 383.258971 -233.621808) (xy 383.313814 -233.611678) (xy 383.369548 -233.609641) (xy 383.424985 -233.615741)
			(xy 383.478942 -233.629847) (xy 383.530271 -233.651659) (xy 383.577877 -233.680713) (xy 383.620745 -233.716388)
			(xy 383.657962 -233.757925) (xy 383.688735 -233.804438) (xy 383.712407 -233.854935) (xy 383.728475 -233.908342)
			(xy 383.735765 -233.957876) (xy 384.473448 -233.957876) (xy 384.477519 -233.902254) (xy 384.489645 -233.847817)
			(xy 384.509568 -233.795726) (xy 384.536864 -233.747091) (xy 384.57095 -233.702948) (xy 384.611099 -233.664239)
			(xy 384.656457 -233.631788) (xy 384.706057 -233.606287) (xy 384.758841 -233.58828) (xy 384.813684 -233.57815)
			(xy 384.869418 -233.576113) (xy 384.924855 -233.582213) (xy 384.978812 -233.596319) (xy 385.030141 -233.618131)
			(xy 385.077747 -233.647185) (xy 385.120615 -233.68286) (xy 385.157832 -233.724397) (xy 385.188605 -233.77091)
			(xy 385.212277 -233.821407) (xy 385.228345 -233.874814) (xy 385.236465 -233.92999) (xy 385.236974 -233.957876)
			(xy 385.973572 -233.957876) (xy 385.977643 -233.902254) (xy 385.989769 -233.847817) (xy 386.009692 -233.795726)
			(xy 386.036988 -233.747091) (xy 386.071074 -233.702948) (xy 386.111223 -233.664239) (xy 386.156581 -233.631788)
			(xy 386.206181 -233.606287) (xy 386.258965 -233.58828) (xy 386.313808 -233.57815) (xy 386.369542 -233.576113)
			(xy 386.424979 -233.582213) (xy 386.478936 -233.596319) (xy 386.530265 -233.618131) (xy 386.577871 -233.647185)
			(xy 386.620739 -233.68286) (xy 386.657956 -233.724397) (xy 386.688729 -233.77091) (xy 386.712401 -233.821407)
			(xy 386.728469 -233.874814) (xy 386.736589 -233.92999) (xy 386.737098 -233.957876) (xy 386.736589 -233.985762)
			(xy 386.728469 -234.040938) (xy 386.712401 -234.094345) (xy 386.688729 -234.144842) (xy 386.657956 -234.191355)
			(xy 386.620739 -234.232892) (xy 386.577871 -234.268567) (xy 386.530265 -234.297621) (xy 386.478936 -234.319433)
			(xy 386.424979 -234.333539) (xy 386.369542 -234.339639) (xy 386.313808 -234.337602) (xy 386.258965 -234.327472)
			(xy 386.206181 -234.309465) (xy 386.156581 -234.283964) (xy 386.111223 -234.251513) (xy 386.071074 -234.212804)
			(xy 386.036988 -234.168661) (xy 386.009692 -234.120026) (xy 385.989769 -234.067935) (xy 385.977643 -234.013498)
			(xy 385.973572 -233.957876) (xy 385.236974 -233.957876) (xy 385.236465 -233.985762) (xy 385.228345 -234.040938)
			(xy 385.212277 -234.094345) (xy 385.188605 -234.144842) (xy 385.157832 -234.191355) (xy 385.120615 -234.232892)
			(xy 385.077747 -234.268567) (xy 385.030141 -234.297621) (xy 384.978812 -234.319433) (xy 384.924855 -234.333539)
			(xy 384.869418 -234.339639) (xy 384.813684 -234.337602) (xy 384.758841 -234.327472) (xy 384.706057 -234.309465)
			(xy 384.656457 -234.283964) (xy 384.611099 -234.251513) (xy 384.57095 -234.212804) (xy 384.536864 -234.168661)
			(xy 384.509568 -234.120026) (xy 384.489645 -234.067935) (xy 384.477519 -234.013498) (xy 384.473448 -233.957876)
			(xy 383.735765 -233.957876) (xy 383.736595 -233.963518) (xy 383.737104 -233.991404) (xy 383.736595 -234.01929)
			(xy 383.728475 -234.074466) (xy 383.712407 -234.127873) (xy 383.688735 -234.17837) (xy 383.657962 -234.224883)
			(xy 383.620745 -234.26642) (xy 383.577877 -234.302095) (xy 383.530271 -234.331149) (xy 383.478942 -234.352961)
			(xy 383.424985 -234.367067) (xy 383.369548 -234.373167) (xy 383.313814 -234.37113) (xy 383.258971 -234.361)
			(xy 383.206187 -234.342993) (xy 383.156587 -234.317492) (xy 383.111229 -234.285041) (xy 383.07108 -234.246332)
			(xy 383.036994 -234.202189) (xy 383.009698 -234.153554) (xy 382.989775 -234.101463) (xy 382.977649 -234.047026)
			(xy 382.973578 -233.991404) (xy 382.737041 -233.991404) (xy 382.737106 -233.99496) (xy 382.736597 -234.022846)
			(xy 382.728477 -234.078022) (xy 382.712409 -234.131429) (xy 382.688737 -234.181926) (xy 382.657964 -234.228439)
			(xy 382.620747 -234.269976) (xy 382.577879 -234.305651) (xy 382.530273 -234.334705) (xy 382.478944 -234.356517)
			(xy 382.424987 -234.370623) (xy 382.36955 -234.376723) (xy 382.313816 -234.374686) (xy 382.258973 -234.364556)
			(xy 382.206189 -234.346549) (xy 382.156589 -234.321048) (xy 382.111231 -234.288597) (xy 382.071082 -234.249888)
			(xy 382.036996 -234.205745) (xy 382.0097 -234.15711) (xy 381.989777 -234.105019) (xy 381.977651 -234.050582)
			(xy 381.97358 -233.99496) (xy 379.77826 -233.99496) (xy 379.77826 -235.670344) (xy 392.969748 -235.670344)
			(xy 392.973819 -235.614722) (xy 392.985945 -235.560285) (xy 393.005868 -235.508194) (xy 393.033164 -235.459559)
			(xy 393.06725 -235.415416) (xy 393.107399 -235.376707) (xy 393.152757 -235.344256) (xy 393.202357 -235.318755)
			(xy 393.255141 -235.300748) (xy 393.309984 -235.290618) (xy 393.365718 -235.288581) (xy 393.421155 -235.294681)
			(xy 393.475112 -235.308787) (xy 393.526441 -235.330599) (xy 393.574047 -235.359653) (xy 393.616915 -235.395328)
			(xy 393.654132 -235.436865) (xy 393.684905 -235.483378) (xy 393.708577 -235.533875) (xy 393.724645 -235.587282)
			(xy 393.732765 -235.642458) (xy 393.733274 -235.670344) (xy 393.732765 -235.69823) (xy 393.724645 -235.753406)
			(xy 393.708577 -235.806813) (xy 393.684905 -235.85731) (xy 393.654132 -235.903823) (xy 393.616915 -235.94536)
			(xy 393.574047 -235.981035) (xy 393.526441 -236.010089) (xy 393.475112 -236.031901) (xy 393.421155 -236.046007)
			(xy 393.365718 -236.052107) (xy 393.309984 -236.05007) (xy 393.255141 -236.03994) (xy 393.202357 -236.021933)
			(xy 393.152757 -235.996432) (xy 393.107399 -235.963981) (xy 393.06725 -235.925272) (xy 393.033164 -235.881129)
			(xy 393.005868 -235.832494) (xy 392.985945 -235.780403) (xy 392.973819 -235.725966) (xy 392.969748 -235.670344)
			(xy 379.77826 -235.670344) (xy 379.77826 -236.932978) (xy 379.779023 -236.941379) (xy 379.785379 -236.956995)
			(xy 379.796496 -236.96967) (xy 379.80366 -236.974126) (xy 379.811788 -236.977936) (xy 379.866144 -236.997494)
			(xy 379.88748 -237.005114) (xy 379.899672 -237.009432) (xy 379.90018 -237.009686) (xy 379.903482 -237.010956)
			(xy 379.910695 -237.012986) (xy 379.92567 -237.013255) (xy 379.932946 -237.011464) (xy 379.933454 -237.011464)
			(xy 379.948948 -237.001304) (xy 379.951977 -236.999177) (xy 379.957463 -236.994209) (xy 379.95987 -236.991398)
			(xy 379.97813 -236.970201) (xy 380.019788 -236.932854) (xy 380.066443 -236.901976) (xy 380.117099 -236.878226)
			(xy 380.170675 -236.86211) (xy 380.226028 -236.853973) (xy 380.254002 -236.853476) (xy 380.281326 -236.853964)
			(xy 380.335417 -236.861741) (xy 380.387851 -236.877137) (xy 380.421136 -236.892338) (xy 387.5438 -236.892338)
			(xy 387.547871 -236.836716) (xy 387.559997 -236.782279) (xy 387.57992 -236.730188) (xy 387.607216 -236.681553)
			(xy 387.641302 -236.63741) (xy 387.681451 -236.598701) (xy 387.726809 -236.56625) (xy 387.776409 -236.540749)
			(xy 387.829193 -236.522742) (xy 387.884036 -236.512612) (xy 387.93977 -236.510575) (xy 387.995207 -236.516675)
			(xy 388.049164 -236.530781) (xy 388.100493 -236.552593) (xy 388.148099 -236.581647) (xy 388.190967 -236.617322)
			(xy 388.199556 -236.626908) (xy 392.966446 -236.626908) (xy 392.970517 -236.571286) (xy 392.982643 -236.516849)
			(xy 393.002566 -236.464758) (xy 393.029862 -236.416123) (xy 393.063948 -236.37198) (xy 393.104097 -236.333271)
			(xy 393.149455 -236.30082) (xy 393.199055 -236.275319) (xy 393.251839 -236.257312) (xy 393.306682 -236.247182)
			(xy 393.362416 -236.245145) (xy 393.417853 -236.251245) (xy 393.47181 -236.265351) (xy 393.523139 -236.287163)
			(xy 393.570745 -236.316217) (xy 393.613613 -236.351892) (xy 393.65083 -236.393429) (xy 393.681603 -236.439942)
			(xy 393.705275 -236.490439) (xy 393.721343 -236.543846) (xy 393.729463 -236.599022) (xy 393.729972 -236.626908)
			(xy 393.729463 -236.654794) (xy 393.721343 -236.70997) (xy 393.705275 -236.763377) (xy 393.681603 -236.813874)
			(xy 393.65083 -236.860387) (xy 393.613613 -236.901924) (xy 393.570745 -236.937599) (xy 393.523139 -236.966653)
			(xy 393.47181 -236.988465) (xy 393.417853 -237.002571) (xy 393.362416 -237.008671) (xy 393.306682 -237.006634)
			(xy 393.251839 -236.996504) (xy 393.199055 -236.978497) (xy 393.149455 -236.952996) (xy 393.104097 -236.920545)
			(xy 393.063948 -236.881836) (xy 393.029862 -236.837693) (xy 393.002566 -236.789058) (xy 392.982643 -236.736967)
			(xy 392.970517 -236.68253) (xy 392.966446 -236.626908) (xy 388.199556 -236.626908) (xy 388.228184 -236.658859)
			(xy 388.258957 -236.705372) (xy 388.282629 -236.755869) (xy 388.298697 -236.809276) (xy 388.306817 -236.864452)
			(xy 388.307326 -236.892338) (xy 388.306817 -236.920224) (xy 388.298697 -236.9754) (xy 388.282629 -237.028807)
			(xy 388.258957 -237.079304) (xy 388.228184 -237.125817) (xy 388.190967 -237.167354) (xy 388.148099 -237.203029)
			(xy 388.100493 -237.232083) (xy 388.049164 -237.253895) (xy 387.995207 -237.268001) (xy 387.93977 -237.274101)
			(xy 387.884036 -237.272064) (xy 387.829193 -237.261934) (xy 387.776409 -237.243927) (xy 387.726809 -237.218426)
			(xy 387.681451 -237.185975) (xy 387.641302 -237.147266) (xy 387.607216 -237.103123) (xy 387.57992 -237.054488)
			(xy 387.559997 -237.002397) (xy 387.547871 -236.94796) (xy 387.5438 -236.892338) (xy 380.421136 -236.892338)
			(xy 380.43756 -236.899839) (xy 380.483532 -236.929383) (xy 380.524831 -236.96517) (xy 380.560618 -237.00647)
			(xy 380.590162 -237.052442) (xy 380.612864 -237.102151) (xy 380.62826 -237.154585) (xy 380.636037 -237.208676)
			(xy 380.636037 -237.263324) (xy 380.62826 -237.317415) (xy 380.612864 -237.369849) (xy 380.590162 -237.419558)
			(xy 380.560618 -237.46553) (xy 380.524831 -237.50683) (xy 380.483532 -237.542617) (xy 380.43756 -237.572161)
			(xy 380.387851 -237.594863) (xy 380.335417 -237.610259) (xy 380.281326 -237.618036) (xy 380.254002 -237.618524)
			(xy 380.226028 -237.618038) (xy 380.170677 -237.609891) (xy 380.117102 -237.59377) (xy 380.066446 -237.570019)
			(xy 380.019789 -237.539144) (xy 379.978125 -237.501804) (xy 379.95987 -237.480602) (xy 379.957479 -237.477774)
			(xy 379.951996 -237.472798) (xy 379.948948 -237.470696) (xy 379.933454 -237.460536) (xy 379.932946 -237.460536)
			(xy 379.925607 -237.458724) (xy 379.910499 -237.458975) (xy 379.903228 -237.461044) (xy 379.90018 -237.462314)
			(xy 379.899672 -237.462568) (xy 379.88748 -237.466886) (xy 379.866144 -237.474506) (xy 379.811788 -237.494064)
			(xy 379.80366 -237.497874) (xy 379.793023 -237.504817) (xy 379.779689 -237.526401) (xy 379.77826 -237.539022)
			(xy 379.77826 -238.343694) (xy 379.778708 -238.352838) (xy 381.07823 -238.352838) (xy 381.082301 -238.297216)
			(xy 381.094427 -238.242779) (xy 381.11435 -238.190688) (xy 381.141646 -238.142053) (xy 381.175732 -238.09791)
			(xy 381.215881 -238.059201) (xy 381.261239 -238.02675) (xy 381.310839 -238.001249) (xy 381.363623 -237.983242)
			(xy 381.418466 -237.973112) (xy 381.4742 -237.971075) (xy 381.529637 -237.977175) (xy 381.583594 -237.991281)
			(xy 381.599405 -237.998) (xy 383.030982 -237.998) (xy 383.035053 -237.942378) (xy 383.047179 -237.887941)
			(xy 383.067102 -237.83585) (xy 383.094398 -237.787215) (xy 383.128484 -237.743072) (xy 383.168633 -237.704363)
			(xy 383.213991 -237.671912) (xy 383.263591 -237.646411) (xy 383.316375 -237.628404) (xy 383.371218 -237.618274)
			(xy 383.426952 -237.616237) (xy 383.482389 -237.622337) (xy 383.536346 -237.636443) (xy 383.587675 -237.658255)
			(xy 383.635281 -237.687309) (xy 383.678149 -237.722984) (xy 383.715366 -237.764521) (xy 383.746139 -237.811034)
			(xy 383.769811 -237.861531) (xy 383.785879 -237.914938) (xy 383.793999 -237.970114) (xy 383.794508 -237.998)
			(xy 383.793999 -238.025886) (xy 383.785879 -238.081062) (xy 383.769811 -238.134469) (xy 383.746139 -238.184966)
			(xy 383.727668 -238.212884) (xy 386.259068 -238.212884) (xy 386.263139 -238.157262) (xy 386.275265 -238.102825)
			(xy 386.295188 -238.050734) (xy 386.322484 -238.002099) (xy 386.35657 -237.957956) (xy 386.396719 -237.919247)
			(xy 386.442077 -237.886796) (xy 386.491677 -237.861295) (xy 386.544461 -237.843288) (xy 386.599304 -237.833158)
			(xy 386.655038 -237.831121) (xy 386.710475 -237.837221) (xy 386.764432 -237.851327) (xy 386.815761 -237.873139)
			(xy 386.863367 -237.902193) (xy 386.906235 -237.937868) (xy 386.943452 -237.979405) (xy 386.974225 -238.025918)
			(xy 386.997897 -238.076415) (xy 387.013965 -238.129822) (xy 387.022085 -238.184998) (xy 387.022594 -238.212884)
			(xy 387.022085 -238.24077) (xy 387.013965 -238.295946) (xy 386.997897 -238.349353) (xy 386.974225 -238.39985)
			(xy 386.943452 -238.446363) (xy 386.906235 -238.4879) (xy 386.863367 -238.523575) (xy 386.815761 -238.552629)
			(xy 386.764432 -238.574441) (xy 386.710475 -238.588547) (xy 386.655038 -238.594647) (xy 386.599304 -238.59261)
			(xy 386.544461 -238.58248) (xy 386.491677 -238.564473) (xy 386.442077 -238.538972) (xy 386.396719 -238.506521)
			(xy 386.35657 -238.467812) (xy 386.322484 -238.423669) (xy 386.295188 -238.375034) (xy 386.275265 -238.322943)
			(xy 386.263139 -238.268506) (xy 386.259068 -238.212884) (xy 383.727668 -238.212884) (xy 383.715366 -238.231479)
			(xy 383.678149 -238.273016) (xy 383.635281 -238.308691) (xy 383.587675 -238.337745) (xy 383.536346 -238.359557)
			(xy 383.482389 -238.373663) (xy 383.426952 -238.379763) (xy 383.371218 -238.377726) (xy 383.316375 -238.367596)
			(xy 383.263591 -238.349589) (xy 383.213991 -238.324088) (xy 383.168633 -238.291637) (xy 383.128484 -238.252928)
			(xy 383.094398 -238.208785) (xy 383.067102 -238.16015) (xy 383.047179 -238.108059) (xy 383.035053 -238.053622)
			(xy 383.030982 -237.998) (xy 381.599405 -237.998) (xy 381.634923 -238.013093) (xy 381.682529 -238.042147)
			(xy 381.725397 -238.077822) (xy 381.762614 -238.119359) (xy 381.793387 -238.165872) (xy 381.817059 -238.216369)
			(xy 381.833127 -238.269776) (xy 381.841247 -238.324952) (xy 381.841756 -238.352838) (xy 381.841247 -238.380724)
			(xy 381.833127 -238.4359) (xy 381.817059 -238.489307) (xy 381.793387 -238.539804) (xy 381.762614 -238.586317)
			(xy 381.725397 -238.627854) (xy 381.682529 -238.663529) (xy 381.634923 -238.692583) (xy 381.583594 -238.714395)
			(xy 381.529637 -238.728501) (xy 381.4742 -238.734601) (xy 381.418466 -238.732564) (xy 381.363623 -238.722434)
			(xy 381.310839 -238.704427) (xy 381.261239 -238.678926) (xy 381.215881 -238.646475) (xy 381.175732 -238.607766)
			(xy 381.141646 -238.563623) (xy 381.11435 -238.514988) (xy 381.094427 -238.462897) (xy 381.082301 -238.40846)
			(xy 381.07823 -238.352838) (xy 379.778708 -238.352838) (xy 379.778831 -238.35536) (xy 379.789158 -238.376279)
			(xy 379.798072 -238.383826) (xy 379.86208 -238.433102) (xy 379.866639 -238.436447) (xy 379.876898 -238.441195)
			(xy 379.8824 -238.4425) (xy 379.89383 -238.44504) (xy 379.905514 -238.441992) (xy 379.929216 -238.43616)
			(xy 379.977628 -238.429921) (xy 380.002034 -238.429546) (xy 380.004828 -238.429546) (xy 380.03196 -238.430204)
			(xy 380.085631 -238.438252) (xy 380.13762 -238.453825) (xy 380.186877 -238.47661) (xy 380.232407 -238.506146)
			(xy 380.273291 -238.541837) (xy 380.308705 -238.582962) (xy 380.337932 -238.628691) (xy 380.360383 -238.678101)
			(xy 380.375604 -238.730194) (xy 380.383288 -238.783918) (xy 380.383796 -238.811054) (xy 380.383336 -238.838309)
			(xy 380.375584 -238.892264) (xy 380.360232 -238.944567) (xy 380.337592 -238.994152) (xy 380.308125 -239.04001)
			(xy 380.272431 -239.081207) (xy 380.231237 -239.116905) (xy 380.185382 -239.146376) (xy 380.135799 -239.16902)
			(xy 380.083497 -239.184377) (xy 380.029543 -239.192133) (xy 380.002288 -239.192562) (xy 380.002034 -239.192562)
			(xy 379.97763 -239.192156) (xy 379.929222 -239.185915) (xy 379.905514 -239.180116) (xy 379.89383 -239.177068)
			(xy 379.8824 -239.179608) (xy 379.87691 -239.180948) (xy 379.866653 -239.185686) (xy 379.86208 -239.189006)
			(xy 379.798072 -239.238282) (xy 379.789204 -239.245864) (xy 379.778889 -239.266764) (xy 379.77826 -239.278414)
			(xy 379.77826 -239.811052) (xy 383.030982 -239.811052) (xy 383.035053 -239.75543) (xy 383.047179 -239.700993)
			(xy 383.067102 -239.648902) (xy 383.094398 -239.600267) (xy 383.128484 -239.556124) (xy 383.168633 -239.517415)
			(xy 383.213991 -239.484964) (xy 383.263591 -239.459463) (xy 383.316375 -239.441456) (xy 383.371218 -239.431326)
			(xy 383.426952 -239.429289) (xy 383.482389 -239.435389) (xy 383.536346 -239.449495) (xy 383.587675 -239.471307)
			(xy 383.635281 -239.500361) (xy 383.678149 -239.536036) (xy 383.715366 -239.577573) (xy 383.746139 -239.624086)
			(xy 383.769811 -239.674583) (xy 383.785879 -239.72799) (xy 383.793999 -239.783166) (xy 383.794508 -239.811052)
			(xy 383.793999 -239.838938) (xy 383.785879 -239.894114) (xy 383.769811 -239.947521) (xy 383.746139 -239.998018)
			(xy 383.715366 -240.044531) (xy 383.678149 -240.086068) (xy 383.635281 -240.121743) (xy 383.587675 -240.150797)
			(xy 383.536346 -240.172609) (xy 383.482389 -240.186715) (xy 383.426952 -240.192815) (xy 383.371218 -240.190778)
			(xy 383.316375 -240.180648) (xy 383.263591 -240.162641) (xy 383.213991 -240.13714) (xy 383.168633 -240.104689)
			(xy 383.128484 -240.06598) (xy 383.094398 -240.021837) (xy 383.067102 -239.973202) (xy 383.047179 -239.921111)
			(xy 383.035053 -239.866674) (xy 383.030982 -239.811052) (xy 379.77826 -239.811052) (xy 379.77826 -240.665)
			(xy 384.808982 -240.665) (xy 384.813053 -240.609378) (xy 384.825179 -240.554941) (xy 384.845102 -240.50285)
			(xy 384.872398 -240.454215) (xy 384.906484 -240.410072) (xy 384.946633 -240.371363) (xy 384.991991 -240.338912)
			(xy 385.041591 -240.313411) (xy 385.094375 -240.295404) (xy 385.149218 -240.285274) (xy 385.204952 -240.283237)
			(xy 385.260389 -240.289337) (xy 385.314346 -240.303443) (xy 385.365675 -240.325255) (xy 385.413281 -240.354309)
			(xy 385.456149 -240.389984) (xy 385.493366 -240.431521) (xy 385.524139 -240.478034) (xy 385.547811 -240.528531)
			(xy 385.563879 -240.581938) (xy 385.571999 -240.637114) (xy 385.572508 -240.665) (xy 386.078982 -240.665)
			(xy 386.083053 -240.609378) (xy 386.095179 -240.554941) (xy 386.115102 -240.50285) (xy 386.142398 -240.454215)
			(xy 386.176484 -240.410072) (xy 386.216633 -240.371363) (xy 386.261991 -240.338912) (xy 386.311591 -240.313411)
			(xy 386.364375 -240.295404) (xy 386.419218 -240.285274) (xy 386.474952 -240.283237) (xy 386.530389 -240.289337)
			(xy 386.584346 -240.303443) (xy 386.635675 -240.325255) (xy 386.683281 -240.354309) (xy 386.726149 -240.389984)
			(xy 386.763366 -240.431521) (xy 386.794139 -240.478034) (xy 386.817811 -240.528531) (xy 386.833879 -240.581938)
			(xy 386.841999 -240.637114) (xy 386.842508 -240.665) (xy 386.841999 -240.692886) (xy 386.841916 -240.693448)
			(xy 387.856982 -240.693448) (xy 387.861053 -240.637826) (xy 387.873179 -240.583389) (xy 387.893102 -240.531298)
			(xy 387.920398 -240.482663) (xy 387.954484 -240.43852) (xy 387.994633 -240.399811) (xy 388.039991 -240.36736)
			(xy 388.089591 -240.341859) (xy 388.142375 -240.323852) (xy 388.197218 -240.313722) (xy 388.252952 -240.311685)
			(xy 388.308389 -240.317785) (xy 388.362346 -240.331891) (xy 388.413675 -240.353703) (xy 388.461281 -240.382757)
			(xy 388.504149 -240.418432) (xy 388.541366 -240.459969) (xy 388.572139 -240.506482) (xy 388.595811 -240.556979)
			(xy 388.611879 -240.610386) (xy 388.619999 -240.665562) (xy 388.620508 -240.693448) (xy 388.619999 -240.721334)
			(xy 388.611879 -240.77651) (xy 388.595811 -240.829917) (xy 388.572139 -240.880414) (xy 388.541366 -240.926927)
			(xy 388.504149 -240.968464) (xy 388.461281 -241.004139) (xy 388.413675 -241.033193) (xy 388.362346 -241.055005)
			(xy 388.308389 -241.069111) (xy 388.252952 -241.075211) (xy 388.197218 -241.073174) (xy 388.142375 -241.063044)
			(xy 388.089591 -241.045037) (xy 388.039991 -241.019536) (xy 387.994633 -240.987085) (xy 387.954484 -240.948376)
			(xy 387.920398 -240.904233) (xy 387.893102 -240.855598) (xy 387.873179 -240.803507) (xy 387.861053 -240.74907)
			(xy 387.856982 -240.693448) (xy 386.841916 -240.693448) (xy 386.833879 -240.748062) (xy 386.817811 -240.801469)
			(xy 386.794139 -240.851966) (xy 386.763366 -240.898479) (xy 386.726149 -240.940016) (xy 386.683281 -240.975691)
			(xy 386.635675 -241.004745) (xy 386.584346 -241.026557) (xy 386.530389 -241.040663) (xy 386.474952 -241.046763)
			(xy 386.419218 -241.044726) (xy 386.364375 -241.034596) (xy 386.311591 -241.016589) (xy 386.261991 -240.991088)
			(xy 386.216633 -240.958637) (xy 386.176484 -240.919928) (xy 386.142398 -240.875785) (xy 386.115102 -240.82715)
			(xy 386.095179 -240.775059) (xy 386.083053 -240.720622) (xy 386.078982 -240.665) (xy 385.572508 -240.665)
			(xy 385.571999 -240.692886) (xy 385.563879 -240.748062) (xy 385.547811 -240.801469) (xy 385.524139 -240.851966)
			(xy 385.493366 -240.898479) (xy 385.456149 -240.940016) (xy 385.413281 -240.975691) (xy 385.365675 -241.004745)
			(xy 385.314346 -241.026557) (xy 385.260389 -241.040663) (xy 385.204952 -241.046763) (xy 385.149218 -241.044726)
			(xy 385.094375 -241.034596) (xy 385.041591 -241.016589) (xy 384.991991 -240.991088) (xy 384.946633 -240.958637)
			(xy 384.906484 -240.919928) (xy 384.872398 -240.875785) (xy 384.845102 -240.82715) (xy 384.825179 -240.775059)
			(xy 384.813053 -240.720622) (xy 384.808982 -240.665) (xy 379.77826 -240.665) (xy 379.77826 -241.427)
			(xy 383.030982 -241.427) (xy 383.035053 -241.371378) (xy 383.047179 -241.316941) (xy 383.067102 -241.26485)
			(xy 383.094398 -241.216215) (xy 383.128484 -241.172072) (xy 383.168633 -241.133363) (xy 383.213991 -241.100912)
			(xy 383.263591 -241.075411) (xy 383.316375 -241.057404) (xy 383.371218 -241.047274) (xy 383.426952 -241.045237)
			(xy 383.482389 -241.051337) (xy 383.536346 -241.065443) (xy 383.587675 -241.087255) (xy 383.635281 -241.116309)
			(xy 383.678149 -241.151984) (xy 383.715366 -241.193521) (xy 383.746139 -241.240034) (xy 383.769811 -241.290531)
			(xy 383.785879 -241.343938) (xy 383.793999 -241.399114) (xy 383.794508 -241.427) (xy 383.793999 -241.454886)
			(xy 383.785879 -241.510062) (xy 383.769811 -241.563469) (xy 383.746139 -241.613966) (xy 383.715366 -241.660479)
			(xy 383.678149 -241.702016) (xy 383.635281 -241.737691) (xy 383.587675 -241.766745) (xy 383.536346 -241.788557)
			(xy 383.482389 -241.802663) (xy 383.426952 -241.808763) (xy 383.371218 -241.806726) (xy 383.316375 -241.796596)
			(xy 383.263591 -241.778589) (xy 383.213991 -241.753088) (xy 383.168633 -241.720637) (xy 383.128484 -241.681928)
			(xy 383.094398 -241.637785) (xy 383.067102 -241.58915) (xy 383.047179 -241.537059) (xy 383.035053 -241.482622)
			(xy 383.030982 -241.427) (xy 379.77826 -241.427) (xy 379.77826 -241.843814) (xy 379.778835 -241.855478)
			(xy 379.789167 -241.87639) (xy 379.798072 -241.883946) (xy 379.86208 -241.933222) (xy 379.86664 -241.936566)
			(xy 379.876899 -241.941312) (xy 379.8824 -241.94262) (xy 379.89383 -241.94516) (xy 379.905514 -241.942112)
			(xy 379.929216 -241.93628) (xy 379.977628 -241.930041) (xy 380.002034 -241.929666) (xy 380.004828 -241.929666)
			(xy 380.031962 -241.930323) (xy 380.085638 -241.938371) (xy 380.137631 -241.953943) (xy 380.186893 -241.976727)
			(xy 380.232429 -242.006262) (xy 380.27332 -242.041951) (xy 380.285776 -242.056412) (xy 388.016494 -242.056412)
			(xy 388.020565 -242.00079) (xy 388.032691 -241.946353) (xy 388.052614 -241.894262) (xy 388.07991 -241.845627)
			(xy 388.113996 -241.801484) (xy 388.154145 -241.762775) (xy 388.199503 -241.730324) (xy 388.249103 -241.704823)
			(xy 388.301887 -241.686816) (xy 388.35673 -241.676686) (xy 388.412464 -241.674649) (xy 388.467901 -241.680749)
			(xy 388.521858 -241.694855) (xy 388.573187 -241.716667) (xy 388.620793 -241.745721) (xy 388.663661 -241.781396)
			(xy 388.700878 -241.822933) (xy 388.731651 -241.869446) (xy 388.755323 -241.919943) (xy 388.771391 -241.97335)
			(xy 388.779511 -242.028526) (xy 388.779603 -242.033552) (xy 393.613384 -242.033552) (xy 393.617455 -241.97793)
			(xy 393.629581 -241.923493) (xy 393.649504 -241.871402) (xy 393.6768 -241.822767) (xy 393.710886 -241.778624)
			(xy 393.751035 -241.739915) (xy 393.796393 -241.707464) (xy 393.845993 -241.681963) (xy 393.898777 -241.663956)
			(xy 393.95362 -241.653826) (xy 394.009354 -241.651789) (xy 394.064791 -241.657889) (xy 394.118748 -241.671995)
			(xy 394.170077 -241.693807) (xy 394.217683 -241.722861) (xy 394.260551 -241.758536) (xy 394.297768 -241.800073)
			(xy 394.328541 -241.846586) (xy 394.352213 -241.897083) (xy 394.368281 -241.95049) (xy 394.376401 -242.005666)
			(xy 394.37691 -242.033552) (xy 394.376401 -242.061438) (xy 394.368281 -242.116614) (xy 394.352213 -242.170021)
			(xy 394.328541 -242.220518) (xy 394.297768 -242.267031) (xy 394.260551 -242.308568) (xy 394.217683 -242.344243)
			(xy 394.170077 -242.373297) (xy 394.118748 -242.395109) (xy 394.064791 -242.409215) (xy 394.009354 -242.415315)
			(xy 393.95362 -242.413278) (xy 393.898777 -242.403148) (xy 393.845993 -242.385141) (xy 393.796393 -242.35964)
			(xy 393.751035 -242.327189) (xy 393.710886 -242.28848) (xy 393.6768 -242.244337) (xy 393.649504 -242.195702)
			(xy 393.629581 -242.143611) (xy 393.617455 -242.089174) (xy 393.613384 -242.033552) (xy 388.779603 -242.033552)
			(xy 388.78002 -242.056412) (xy 388.779511 -242.084298) (xy 388.771391 -242.139474) (xy 388.755323 -242.192881)
			(xy 388.731651 -242.243378) (xy 388.700878 -242.289891) (xy 388.663661 -242.331428) (xy 388.620793 -242.367103)
			(xy 388.573187 -242.396157) (xy 388.521858 -242.417969) (xy 388.467901 -242.432075) (xy 388.412464 -242.438175)
			(xy 388.35673 -242.436138) (xy 388.301887 -242.426008) (xy 388.249103 -242.408001) (xy 388.199503 -242.3825)
			(xy 388.154145 -242.350049) (xy 388.113996 -242.31134) (xy 388.07991 -242.267197) (xy 388.052614 -242.218562)
			(xy 388.032691 -242.166471) (xy 388.020565 -242.112034) (xy 388.016494 -242.056412) (xy 380.285776 -242.056412)
			(xy 380.308741 -242.083075) (xy 380.337976 -242.128804) (xy 380.360436 -242.178215) (xy 380.375668 -242.230309)
			(xy 380.383363 -242.284036) (xy 380.383796 -242.311174) (xy 380.383345 -242.336984) (xy 380.376344 -242.388127)
			(xy 380.362518 -242.437861) (xy 380.342122 -242.485281) (xy 380.315525 -242.529522) (xy 380.299722 -242.549934)
			(xy 380.294249 -242.557435) (xy 380.288579 -242.575102) (xy 380.289559 -242.59363) (xy 380.297059 -242.610601)
			(xy 380.303278 -242.617498) (xy 380.901194 -243.215414) (xy 383.706876 -243.215414) (xy 383.710947 -243.159792)
			(xy 383.723073 -243.105355) (xy 383.742996 -243.053264) (xy 383.770292 -243.004629) (xy 383.804378 -242.960486)
			(xy 383.844527 -242.921777) (xy 383.889885 -242.889326) (xy 383.939485 -242.863825) (xy 383.992269 -242.845818)
			(xy 384.047112 -242.835688) (xy 384.102846 -242.833651) (xy 384.158283 -242.839751) (xy 384.21224 -242.853857)
			(xy 384.263569 -242.875669) (xy 384.311175 -242.904723) (xy 384.354043 -242.940398) (xy 384.39126 -242.981935)
			(xy 384.422033 -243.028448) (xy 384.445705 -243.078945) (xy 384.461773 -243.132352) (xy 384.466483 -243.16436)
			(xy 385.973572 -243.16436) (xy 385.977643 -243.108738) (xy 385.989769 -243.054301) (xy 386.009692 -243.00221)
			(xy 386.036988 -242.953575) (xy 386.071074 -242.909432) (xy 386.111223 -242.870723) (xy 386.156581 -242.838272)
			(xy 386.206181 -242.812771) (xy 386.258965 -242.794764) (xy 386.313808 -242.784634) (xy 386.369542 -242.782597)
			(xy 386.424979 -242.788697) (xy 386.478936 -242.802803) (xy 386.530265 -242.824615) (xy 386.577871 -242.853669)
			(xy 386.620739 -242.889344) (xy 386.657956 -242.930881) (xy 386.688729 -242.977394) (xy 386.712401 -243.027891)
			(xy 386.728469 -243.081298) (xy 386.736589 -243.136474) (xy 386.737098 -243.16436) (xy 386.736589 -243.192246)
			(xy 386.728469 -243.247422) (xy 386.712401 -243.300829) (xy 386.688729 -243.351326) (xy 386.657956 -243.397839)
			(xy 386.620739 -243.439376) (xy 386.577871 -243.475051) (xy 386.530265 -243.504105) (xy 386.478936 -243.525917)
			(xy 386.424979 -243.540023) (xy 386.369542 -243.546123) (xy 386.313808 -243.544086) (xy 386.258965 -243.533956)
			(xy 386.206181 -243.515949) (xy 386.156581 -243.490448) (xy 386.111223 -243.457997) (xy 386.071074 -243.419288)
			(xy 386.036988 -243.375145) (xy 386.009692 -243.32651) (xy 385.989769 -243.274419) (xy 385.977643 -243.219982)
			(xy 385.973572 -243.16436) (xy 384.466483 -243.16436) (xy 384.469893 -243.187528) (xy 384.470402 -243.215414)
			(xy 384.469893 -243.2433) (xy 384.461773 -243.298476) (xy 384.445705 -243.351883) (xy 384.422033 -243.40238)
			(xy 384.39126 -243.448893) (xy 384.354043 -243.49043) (xy 384.311175 -243.526105) (xy 384.263569 -243.555159)
			(xy 384.21224 -243.576971) (xy 384.158283 -243.591077) (xy 384.102846 -243.597177) (xy 384.047112 -243.59514)
			(xy 383.992269 -243.58501) (xy 383.939485 -243.567003) (xy 383.889885 -243.541502) (xy 383.844527 -243.509051)
			(xy 383.804378 -243.470342) (xy 383.770292 -243.426199) (xy 383.742996 -243.377564) (xy 383.723073 -243.325473)
			(xy 383.710947 -243.271036) (xy 383.706876 -243.215414) (xy 380.901194 -243.215414) (xy 382.546098 -244.860318)
			(xy 382.55244 -244.866212) (xy 382.568019 -244.87374) (xy 382.576578 -244.87505) (xy 382.579372 -244.875304)
			(xy 389.885936 -244.875304) (xy 389.896003 -244.875734) (xy 389.914598 -244.883458) (xy 389.922004 -244.89029)
			(xy 390.560052 -245.528338) (xy 390.566898 -245.535736) (xy 390.574626 -245.554335) (xy 390.575038 -245.564406)
			(xy 390.575038 -246.3419) (xy 393.825982 -246.3419) (xy 393.830053 -246.286278) (xy 393.842179 -246.231841)
			(xy 393.862102 -246.17975) (xy 393.889398 -246.131115) (xy 393.923484 -246.086972) (xy 393.963633 -246.048263)
			(xy 394.008991 -246.015812) (xy 394.058591 -245.990311) (xy 394.111375 -245.972304) (xy 394.166218 -245.962174)
			(xy 394.221952 -245.960137) (xy 394.277389 -245.966237) (xy 394.331346 -245.980343) (xy 394.382675 -246.002155)
			(xy 394.430281 -246.031209) (xy 394.473149 -246.066884) (xy 394.510366 -246.108421) (xy 394.541139 -246.154934)
			(xy 394.564811 -246.205431) (xy 394.580879 -246.258838) (xy 394.588999 -246.314014) (xy 394.589508 -246.3419)
			(xy 394.588999 -246.369786) (xy 394.580879 -246.424962) (xy 394.564811 -246.478369) (xy 394.541139 -246.528866)
			(xy 394.510366 -246.575379) (xy 394.473149 -246.616916) (xy 394.430281 -246.652591) (xy 394.382675 -246.681645)
			(xy 394.331346 -246.703457) (xy 394.277389 -246.717563) (xy 394.221952 -246.723663) (xy 394.166218 -246.721626)
			(xy 394.111375 -246.711496) (xy 394.058591 -246.693489) (xy 394.008991 -246.667988) (xy 393.963633 -246.635537)
			(xy 393.923484 -246.596828) (xy 393.889398 -246.552685) (xy 393.862102 -246.50405) (xy 393.842179 -246.451959)
			(xy 393.830053 -246.397522) (xy 393.825982 -246.3419) (xy 390.575038 -246.3419) (xy 390.575038 -257.491992)
			(xy 390.57546 -257.502062) (xy 390.583177 -257.520665) (xy 390.590024 -257.52806) (xy 391.079736 -258.017772)
			(xy 391.086578 -258.025171) (xy 391.094297 -258.04377) (xy 391.094722 -258.05384) (xy 391.094722 -270.774414)
			(xy 391.095148 -270.784483) (xy 391.102869 -270.803081) (xy 391.109708 -270.810482) (xy 391.653014 -271.353788)
			(xy 391.659872 -271.361182) (xy 391.667624 -271.379781) (xy 391.668 -271.389856) (xy 391.668 -273.125492)
			(xy 392.423138 -273.125492) (xy 392.423138 -273.074076) (xy 392.431181 -273.023294) (xy 392.447069 -272.974395)
			(xy 392.470412 -272.928583) (xy 392.500633 -272.886987) (xy 392.536989 -272.850631) (xy 392.578585 -272.82041)
			(xy 392.624397 -272.797067) (xy 392.673296 -272.781179) (xy 392.724078 -272.773136) (xy 392.775494 -272.773136)
			(xy 392.826276 -272.781179) (xy 392.875175 -272.797067) (xy 392.920987 -272.82041) (xy 392.962583 -272.850631)
			(xy 392.998939 -272.886987) (xy 393.02916 -272.928583) (xy 393.052503 -272.974395) (xy 393.068391 -273.023294)
			(xy 393.076434 -273.074076) (xy 393.076938 -273.099784) (xy 393.076434 -273.125492) (xy 394.323312 -273.125492)
			(xy 394.323312 -273.074076) (xy 394.331355 -273.023294) (xy 394.347243 -272.974395) (xy 394.370586 -272.928583)
			(xy 394.400807 -272.886987) (xy 394.437163 -272.850631) (xy 394.478759 -272.82041) (xy 394.524571 -272.797067)
			(xy 394.57347 -272.781179) (xy 394.624252 -272.773136) (xy 394.675668 -272.773136) (xy 394.72645 -272.781179)
			(xy 394.775349 -272.797067) (xy 394.821161 -272.82041) (xy 394.862757 -272.850631) (xy 394.899113 -272.886987)
			(xy 394.929334 -272.928583) (xy 394.952677 -272.974395) (xy 394.968565 -273.023294) (xy 394.976608 -273.074076)
			(xy 394.977112 -273.099784) (xy 394.976608 -273.125492) (xy 396.223232 -273.125492) (xy 396.223232 -273.074076)
			(xy 396.231275 -273.023294) (xy 396.247163 -272.974395) (xy 396.270506 -272.928583) (xy 396.300727 -272.886987)
			(xy 396.337083 -272.850631) (xy 396.378679 -272.82041) (xy 396.424491 -272.797067) (xy 396.47339 -272.781179)
			(xy 396.524172 -272.773136) (xy 396.575588 -272.773136) (xy 396.62637 -272.781179) (xy 396.675269 -272.797067)
			(xy 396.721081 -272.82041) (xy 396.762677 -272.850631) (xy 396.799033 -272.886987) (xy 396.829254 -272.928583)
			(xy 396.852597 -272.974395) (xy 396.868485 -273.023294) (xy 396.876528 -273.074076) (xy 396.877032 -273.099784)
			(xy 396.876528 -273.125492) (xy 398.123152 -273.125492) (xy 398.123152 -273.074076) (xy 398.131195 -273.023294)
			(xy 398.147083 -272.974395) (xy 398.170426 -272.928583) (xy 398.200647 -272.886987) (xy 398.237003 -272.850631)
			(xy 398.278599 -272.82041) (xy 398.324411 -272.797067) (xy 398.37331 -272.781179) (xy 398.424092 -272.773136)
			(xy 398.475508 -272.773136) (xy 398.52629 -272.781179) (xy 398.575189 -272.797067) (xy 398.621001 -272.82041)
			(xy 398.662597 -272.850631) (xy 398.698953 -272.886987) (xy 398.729174 -272.928583) (xy 398.752517 -272.974395)
			(xy 398.768405 -273.023294) (xy 398.776448 -273.074076) (xy 398.776952 -273.099784) (xy 398.776448 -273.125492)
			(xy 400.023326 -273.125492) (xy 400.023326 -273.074076) (xy 400.031369 -273.023294) (xy 400.047257 -272.974395)
			(xy 400.0706 -272.928583) (xy 400.100821 -272.886987) (xy 400.137177 -272.850631) (xy 400.178773 -272.82041)
			(xy 400.224585 -272.797067) (xy 400.273484 -272.781179) (xy 400.324266 -272.773136) (xy 400.375682 -272.773136)
			(xy 400.426464 -272.781179) (xy 400.475363 -272.797067) (xy 400.521175 -272.82041) (xy 400.562771 -272.850631)
			(xy 400.599127 -272.886987) (xy 400.629348 -272.928583) (xy 400.652691 -272.974395) (xy 400.668579 -273.023294)
			(xy 400.676622 -273.074076) (xy 400.677126 -273.099784) (xy 400.676622 -273.125492) (xy 401.923246 -273.125492)
			(xy 401.923246 -273.074076) (xy 401.931289 -273.023294) (xy 401.947177 -272.974395) (xy 401.97052 -272.928583)
			(xy 402.000741 -272.886987) (xy 402.037097 -272.850631) (xy 402.078693 -272.82041) (xy 402.124505 -272.797067)
			(xy 402.173404 -272.781179) (xy 402.224186 -272.773136) (xy 402.275602 -272.773136) (xy 402.326384 -272.781179)
			(xy 402.375283 -272.797067) (xy 402.421095 -272.82041) (xy 402.462691 -272.850631) (xy 402.499047 -272.886987)
			(xy 402.529268 -272.928583) (xy 402.552611 -272.974395) (xy 402.568499 -273.023294) (xy 402.576542 -273.074076)
			(xy 402.577046 -273.099784) (xy 402.576542 -273.125492) (xy 403.823166 -273.125492) (xy 403.823166 -273.074076)
			(xy 403.831209 -273.023294) (xy 403.847097 -272.974395) (xy 403.87044 -272.928583) (xy 403.900661 -272.886987)
			(xy 403.937017 -272.850631) (xy 403.978613 -272.82041) (xy 404.024425 -272.797067) (xy 404.073324 -272.781179)
			(xy 404.124106 -272.773136) (xy 404.175522 -272.773136) (xy 404.226304 -272.781179) (xy 404.275203 -272.797067)
			(xy 404.321015 -272.82041) (xy 404.362611 -272.850631) (xy 404.398967 -272.886987) (xy 404.429188 -272.928583)
			(xy 404.452531 -272.974395) (xy 404.468419 -273.023294) (xy 404.476462 -273.074076) (xy 404.476966 -273.099784)
			(xy 404.476462 -273.125492) (xy 404.468419 -273.176274) (xy 404.452531 -273.225173) (xy 404.429188 -273.270985)
			(xy 404.398967 -273.312581) (xy 404.362611 -273.348937) (xy 404.321015 -273.379158) (xy 404.275203 -273.402501)
			(xy 404.226304 -273.418389) (xy 404.175522 -273.426432) (xy 404.124106 -273.426432) (xy 404.073324 -273.418389)
			(xy 404.024425 -273.402501) (xy 403.978613 -273.379158) (xy 403.937017 -273.348937) (xy 403.900661 -273.312581)
			(xy 403.87044 -273.270985) (xy 403.847097 -273.225173) (xy 403.831209 -273.176274) (xy 403.823166 -273.125492)
			(xy 402.576542 -273.125492) (xy 402.568499 -273.176274) (xy 402.552611 -273.225173) (xy 402.529268 -273.270985)
			(xy 402.499047 -273.312581) (xy 402.462691 -273.348937) (xy 402.421095 -273.379158) (xy 402.375283 -273.402501)
			(xy 402.326384 -273.418389) (xy 402.275602 -273.426432) (xy 402.224186 -273.426432) (xy 402.173404 -273.418389)
			(xy 402.124505 -273.402501) (xy 402.078693 -273.379158) (xy 402.037097 -273.348937) (xy 402.000741 -273.312581)
			(xy 401.97052 -273.270985) (xy 401.947177 -273.225173) (xy 401.931289 -273.176274) (xy 401.923246 -273.125492)
			(xy 400.676622 -273.125492) (xy 400.668579 -273.176274) (xy 400.652691 -273.225173) (xy 400.629348 -273.270985)
			(xy 400.599127 -273.312581) (xy 400.562771 -273.348937) (xy 400.521175 -273.379158) (xy 400.475363 -273.402501)
			(xy 400.426464 -273.418389) (xy 400.375682 -273.426432) (xy 400.324266 -273.426432) (xy 400.273484 -273.418389)
			(xy 400.224585 -273.402501) (xy 400.178773 -273.379158) (xy 400.137177 -273.348937) (xy 400.100821 -273.312581)
			(xy 400.0706 -273.270985) (xy 400.047257 -273.225173) (xy 400.031369 -273.176274) (xy 400.023326 -273.125492)
			(xy 398.776448 -273.125492) (xy 398.768405 -273.176274) (xy 398.752517 -273.225173) (xy 398.729174 -273.270985)
			(xy 398.698953 -273.312581) (xy 398.662597 -273.348937) (xy 398.621001 -273.379158) (xy 398.575189 -273.402501)
			(xy 398.52629 -273.418389) (xy 398.475508 -273.426432) (xy 398.424092 -273.426432) (xy 398.37331 -273.418389)
			(xy 398.324411 -273.402501) (xy 398.278599 -273.379158) (xy 398.237003 -273.348937) (xy 398.200647 -273.312581)
			(xy 398.170426 -273.270985) (xy 398.147083 -273.225173) (xy 398.131195 -273.176274) (xy 398.123152 -273.125492)
			(xy 396.876528 -273.125492) (xy 396.868485 -273.176274) (xy 396.852597 -273.225173) (xy 396.829254 -273.270985)
			(xy 396.799033 -273.312581) (xy 396.762677 -273.348937) (xy 396.721081 -273.379158) (xy 396.675269 -273.402501)
			(xy 396.62637 -273.418389) (xy 396.575588 -273.426432) (xy 396.524172 -273.426432) (xy 396.47339 -273.418389)
			(xy 396.424491 -273.402501) (xy 396.378679 -273.379158) (xy 396.337083 -273.348937) (xy 396.300727 -273.312581)
			(xy 396.270506 -273.270985) (xy 396.247163 -273.225173) (xy 396.231275 -273.176274) (xy 396.223232 -273.125492)
			(xy 394.976608 -273.125492) (xy 394.968565 -273.176274) (xy 394.952677 -273.225173) (xy 394.929334 -273.270985)
			(xy 394.899113 -273.312581) (xy 394.862757 -273.348937) (xy 394.821161 -273.379158) (xy 394.775349 -273.402501)
			(xy 394.72645 -273.418389) (xy 394.675668 -273.426432) (xy 394.624252 -273.426432) (xy 394.57347 -273.418389)
			(xy 394.524571 -273.402501) (xy 394.478759 -273.379158) (xy 394.437163 -273.348937) (xy 394.400807 -273.312581)
			(xy 394.370586 -273.270985) (xy 394.347243 -273.225173) (xy 394.331355 -273.176274) (xy 394.323312 -273.125492)
			(xy 393.076434 -273.125492) (xy 393.068391 -273.176274) (xy 393.052503 -273.225173) (xy 393.02916 -273.270985)
			(xy 392.998939 -273.312581) (xy 392.962583 -273.348937) (xy 392.920987 -273.379158) (xy 392.875175 -273.402501)
			(xy 392.826276 -273.418389) (xy 392.775494 -273.426432) (xy 392.724078 -273.426432) (xy 392.673296 -273.418389)
			(xy 392.624397 -273.402501) (xy 392.578585 -273.379158) (xy 392.536989 -273.348937) (xy 392.500633 -273.312581)
			(xy 392.470412 -273.270985) (xy 392.447069 -273.225173) (xy 392.431181 -273.176274) (xy 392.423138 -273.125492)
			(xy 391.668 -273.125492) (xy 391.668 -274.075452) (xy 392.423138 -274.075452) (xy 392.423138 -274.024036)
			(xy 392.431181 -273.973254) (xy 392.447069 -273.924355) (xy 392.470412 -273.878543) (xy 392.500633 -273.836947)
			(xy 392.536989 -273.800591) (xy 392.578585 -273.77037) (xy 392.624397 -273.747027) (xy 392.673296 -273.731139)
			(xy 392.724078 -273.723096) (xy 392.775494 -273.723096) (xy 392.826276 -273.731139) (xy 392.875175 -273.747027)
			(xy 392.920987 -273.77037) (xy 392.962583 -273.800591) (xy 392.998939 -273.836947) (xy 393.02916 -273.878543)
			(xy 393.052503 -273.924355) (xy 393.068391 -273.973254) (xy 393.076434 -274.024036) (xy 393.076938 -274.049744)
			(xy 393.076434 -274.075452) (xy 394.323312 -274.075452) (xy 394.323312 -274.024036) (xy 394.331355 -273.973254)
			(xy 394.347243 -273.924355) (xy 394.370586 -273.878543) (xy 394.400807 -273.836947) (xy 394.437163 -273.800591)
			(xy 394.478759 -273.77037) (xy 394.524571 -273.747027) (xy 394.57347 -273.731139) (xy 394.624252 -273.723096)
			(xy 394.675668 -273.723096) (xy 394.72645 -273.731139) (xy 394.775349 -273.747027) (xy 394.821161 -273.77037)
			(xy 394.862757 -273.800591) (xy 394.899113 -273.836947) (xy 394.929334 -273.878543) (xy 394.952677 -273.924355)
			(xy 394.968565 -273.973254) (xy 394.976608 -274.024036) (xy 394.977112 -274.049744) (xy 394.976608 -274.075452)
			(xy 396.223232 -274.075452) (xy 396.223232 -274.024036) (xy 396.231275 -273.973254) (xy 396.247163 -273.924355)
			(xy 396.270506 -273.878543) (xy 396.300727 -273.836947) (xy 396.337083 -273.800591) (xy 396.378679 -273.77037)
			(xy 396.424491 -273.747027) (xy 396.47339 -273.731139) (xy 396.524172 -273.723096) (xy 396.575588 -273.723096)
			(xy 396.62637 -273.731139) (xy 396.675269 -273.747027) (xy 396.721081 -273.77037) (xy 396.762677 -273.800591)
			(xy 396.799033 -273.836947) (xy 396.829254 -273.878543) (xy 396.852597 -273.924355) (xy 396.868485 -273.973254)
			(xy 396.876528 -274.024036) (xy 396.877032 -274.049744) (xy 396.876528 -274.075452) (xy 398.123152 -274.075452)
			(xy 398.123152 -274.024036) (xy 398.131195 -273.973254) (xy 398.147083 -273.924355) (xy 398.170426 -273.878543)
			(xy 398.200647 -273.836947) (xy 398.237003 -273.800591) (xy 398.278599 -273.77037) (xy 398.324411 -273.747027)
			(xy 398.37331 -273.731139) (xy 398.424092 -273.723096) (xy 398.475508 -273.723096) (xy 398.52629 -273.731139)
			(xy 398.575189 -273.747027) (xy 398.621001 -273.77037) (xy 398.662597 -273.800591) (xy 398.698953 -273.836947)
			(xy 398.729174 -273.878543) (xy 398.752517 -273.924355) (xy 398.768405 -273.973254) (xy 398.776448 -274.024036)
			(xy 398.776952 -274.049744) (xy 398.776448 -274.075452) (xy 400.023326 -274.075452) (xy 400.023326 -274.024036)
			(xy 400.031369 -273.973254) (xy 400.047257 -273.924355) (xy 400.0706 -273.878543) (xy 400.100821 -273.836947)
			(xy 400.137177 -273.800591) (xy 400.178773 -273.77037) (xy 400.224585 -273.747027) (xy 400.273484 -273.731139)
			(xy 400.324266 -273.723096) (xy 400.375682 -273.723096) (xy 400.426464 -273.731139) (xy 400.475363 -273.747027)
			(xy 400.521175 -273.77037) (xy 400.562771 -273.800591) (xy 400.599127 -273.836947) (xy 400.629348 -273.878543)
			(xy 400.652691 -273.924355) (xy 400.668579 -273.973254) (xy 400.676622 -274.024036) (xy 400.677126 -274.049744)
			(xy 400.676622 -274.075452) (xy 401.923246 -274.075452) (xy 401.923246 -274.024036) (xy 401.931289 -273.973254)
			(xy 401.947177 -273.924355) (xy 401.97052 -273.878543) (xy 402.000741 -273.836947) (xy 402.037097 -273.800591)
			(xy 402.078693 -273.77037) (xy 402.124505 -273.747027) (xy 402.173404 -273.731139) (xy 402.224186 -273.723096)
			(xy 402.275602 -273.723096) (xy 402.326384 -273.731139) (xy 402.375283 -273.747027) (xy 402.421095 -273.77037)
			(xy 402.462691 -273.800591) (xy 402.499047 -273.836947) (xy 402.529268 -273.878543) (xy 402.552611 -273.924355)
			(xy 402.568499 -273.973254) (xy 402.576542 -274.024036) (xy 402.577046 -274.049744) (xy 402.576542 -274.075452)
			(xy 403.823166 -274.075452) (xy 403.823166 -274.024036) (xy 403.831209 -273.973254) (xy 403.847097 -273.924355)
			(xy 403.87044 -273.878543) (xy 403.900661 -273.836947) (xy 403.937017 -273.800591) (xy 403.978613 -273.77037)
			(xy 404.024425 -273.747027) (xy 404.073324 -273.731139) (xy 404.124106 -273.723096) (xy 404.175522 -273.723096)
			(xy 404.226304 -273.731139) (xy 404.275203 -273.747027) (xy 404.321015 -273.77037) (xy 404.362611 -273.800591)
			(xy 404.398967 -273.836947) (xy 404.429188 -273.878543) (xy 404.452531 -273.924355) (xy 404.468419 -273.973254)
			(xy 404.476462 -274.024036) (xy 404.476966 -274.049744) (xy 404.476462 -274.075452) (xy 404.468419 -274.126234)
			(xy 404.452531 -274.175133) (xy 404.429188 -274.220945) (xy 404.398967 -274.262541) (xy 404.362611 -274.298897)
			(xy 404.321015 -274.329118) (xy 404.275203 -274.352461) (xy 404.226304 -274.368349) (xy 404.175522 -274.376392)
			(xy 404.124106 -274.376392) (xy 404.073324 -274.368349) (xy 404.024425 -274.352461) (xy 403.978613 -274.329118)
			(xy 403.937017 -274.298897) (xy 403.900661 -274.262541) (xy 403.87044 -274.220945) (xy 403.847097 -274.175133)
			(xy 403.831209 -274.126234) (xy 403.823166 -274.075452) (xy 402.576542 -274.075452) (xy 402.568499 -274.126234)
			(xy 402.552611 -274.175133) (xy 402.529268 -274.220945) (xy 402.499047 -274.262541) (xy 402.462691 -274.298897)
			(xy 402.421095 -274.329118) (xy 402.375283 -274.352461) (xy 402.326384 -274.368349) (xy 402.275602 -274.376392)
			(xy 402.224186 -274.376392) (xy 402.173404 -274.368349) (xy 402.124505 -274.352461) (xy 402.078693 -274.329118)
			(xy 402.037097 -274.298897) (xy 402.000741 -274.262541) (xy 401.97052 -274.220945) (xy 401.947177 -274.175133)
			(xy 401.931289 -274.126234) (xy 401.923246 -274.075452) (xy 400.676622 -274.075452) (xy 400.668579 -274.126234)
			(xy 400.652691 -274.175133) (xy 400.629348 -274.220945) (xy 400.599127 -274.262541) (xy 400.562771 -274.298897)
			(xy 400.521175 -274.329118) (xy 400.475363 -274.352461) (xy 400.426464 -274.368349) (xy 400.375682 -274.376392)
			(xy 400.324266 -274.376392) (xy 400.273484 -274.368349) (xy 400.224585 -274.352461) (xy 400.178773 -274.329118)
			(xy 400.137177 -274.298897) (xy 400.100821 -274.262541) (xy 400.0706 -274.220945) (xy 400.047257 -274.175133)
			(xy 400.031369 -274.126234) (xy 400.023326 -274.075452) (xy 398.776448 -274.075452) (xy 398.768405 -274.126234)
			(xy 398.752517 -274.175133) (xy 398.729174 -274.220945) (xy 398.698953 -274.262541) (xy 398.662597 -274.298897)
			(xy 398.621001 -274.329118) (xy 398.575189 -274.352461) (xy 398.52629 -274.368349) (xy 398.475508 -274.376392)
			(xy 398.424092 -274.376392) (xy 398.37331 -274.368349) (xy 398.324411 -274.352461) (xy 398.278599 -274.329118)
			(xy 398.237003 -274.298897) (xy 398.200647 -274.262541) (xy 398.170426 -274.220945) (xy 398.147083 -274.175133)
			(xy 398.131195 -274.126234) (xy 398.123152 -274.075452) (xy 396.876528 -274.075452) (xy 396.868485 -274.126234)
			(xy 396.852597 -274.175133) (xy 396.829254 -274.220945) (xy 396.799033 -274.262541) (xy 396.762677 -274.298897)
			(xy 396.721081 -274.329118) (xy 396.675269 -274.352461) (xy 396.62637 -274.368349) (xy 396.575588 -274.376392)
			(xy 396.524172 -274.376392) (xy 396.47339 -274.368349) (xy 396.424491 -274.352461) (xy 396.378679 -274.329118)
			(xy 396.337083 -274.298897) (xy 396.300727 -274.262541) (xy 396.270506 -274.220945) (xy 396.247163 -274.175133)
			(xy 396.231275 -274.126234) (xy 396.223232 -274.075452) (xy 394.976608 -274.075452) (xy 394.968565 -274.126234)
			(xy 394.952677 -274.175133) (xy 394.929334 -274.220945) (xy 394.899113 -274.262541) (xy 394.862757 -274.298897)
			(xy 394.821161 -274.329118) (xy 394.775349 -274.352461) (xy 394.72645 -274.368349) (xy 394.675668 -274.376392)
			(xy 394.624252 -274.376392) (xy 394.57347 -274.368349) (xy 394.524571 -274.352461) (xy 394.478759 -274.329118)
			(xy 394.437163 -274.298897) (xy 394.400807 -274.262541) (xy 394.370586 -274.220945) (xy 394.347243 -274.175133)
			(xy 394.331355 -274.126234) (xy 394.323312 -274.075452) (xy 393.076434 -274.075452) (xy 393.068391 -274.126234)
			(xy 393.052503 -274.175133) (xy 393.02916 -274.220945) (xy 392.998939 -274.262541) (xy 392.962583 -274.298897)
			(xy 392.920987 -274.329118) (xy 392.875175 -274.352461) (xy 392.826276 -274.368349) (xy 392.775494 -274.376392)
			(xy 392.724078 -274.376392) (xy 392.673296 -274.368349) (xy 392.624397 -274.352461) (xy 392.578585 -274.329118)
			(xy 392.536989 -274.298897) (xy 392.500633 -274.262541) (xy 392.470412 -274.220945) (xy 392.447069 -274.175133)
			(xy 392.431181 -274.126234) (xy 392.423138 -274.075452) (xy 391.668 -274.075452) (xy 391.668 -275.025666)
			(xy 393.373352 -275.025666) (xy 393.373352 -274.97425) (xy 393.381395 -274.923468) (xy 393.397283 -274.874569)
			(xy 393.420626 -274.828757) (xy 393.450847 -274.787161) (xy 393.487203 -274.750805) (xy 393.528799 -274.720584)
			(xy 393.574611 -274.697241) (xy 393.62351 -274.681353) (xy 393.674292 -274.67331) (xy 393.725708 -274.67331)
			(xy 393.77649 -274.681353) (xy 393.825389 -274.697241) (xy 393.871201 -274.720584) (xy 393.912797 -274.750805)
			(xy 393.949153 -274.787161) (xy 393.979374 -274.828757) (xy 394.002717 -274.874569) (xy 394.018605 -274.923468)
			(xy 394.026648 -274.97425) (xy 394.027152 -274.999958) (xy 394.026648 -275.025666) (xy 395.273272 -275.025666)
			(xy 395.273272 -274.97425) (xy 395.281315 -274.923468) (xy 395.297203 -274.874569) (xy 395.320546 -274.828757)
			(xy 395.350767 -274.787161) (xy 395.387123 -274.750805) (xy 395.428719 -274.720584) (xy 395.474531 -274.697241)
			(xy 395.52343 -274.681353) (xy 395.574212 -274.67331) (xy 395.625628 -274.67331) (xy 395.67641 -274.681353)
			(xy 395.725309 -274.697241) (xy 395.771121 -274.720584) (xy 395.812717 -274.750805) (xy 395.849073 -274.787161)
			(xy 395.879294 -274.828757) (xy 395.902637 -274.874569) (xy 395.918525 -274.923468) (xy 395.926568 -274.97425)
			(xy 395.927072 -274.999958) (xy 395.926568 -275.025666) (xy 397.173192 -275.025666) (xy 397.173192 -274.97425)
			(xy 397.181235 -274.923468) (xy 397.197123 -274.874569) (xy 397.220466 -274.828757) (xy 397.250687 -274.787161)
			(xy 397.287043 -274.750805) (xy 397.328639 -274.720584) (xy 397.374451 -274.697241) (xy 397.42335 -274.681353)
			(xy 397.474132 -274.67331) (xy 397.525548 -274.67331) (xy 397.57633 -274.681353) (xy 397.625229 -274.697241)
			(xy 397.671041 -274.720584) (xy 397.712637 -274.750805) (xy 397.748993 -274.787161) (xy 397.779214 -274.828757)
			(xy 397.802557 -274.874569) (xy 397.818445 -274.923468) (xy 397.826488 -274.97425) (xy 397.826992 -274.999958)
			(xy 397.826488 -275.025666) (xy 399.073366 -275.025666) (xy 399.073366 -274.97425) (xy 399.081409 -274.923468)
			(xy 399.097297 -274.874569) (xy 399.12064 -274.828757) (xy 399.150861 -274.787161) (xy 399.187217 -274.750805)
			(xy 399.228813 -274.720584) (xy 399.274625 -274.697241) (xy 399.323524 -274.681353) (xy 399.374306 -274.67331)
			(xy 399.425722 -274.67331) (xy 399.476504 -274.681353) (xy 399.525403 -274.697241) (xy 399.571215 -274.720584)
			(xy 399.612811 -274.750805) (xy 399.649167 -274.787161) (xy 399.679388 -274.828757) (xy 399.702731 -274.874569)
			(xy 399.718619 -274.923468) (xy 399.726662 -274.97425) (xy 399.727166 -274.999958) (xy 399.726662 -275.025666)
			(xy 400.973286 -275.025666) (xy 400.973286 -274.97425) (xy 400.981329 -274.923468) (xy 400.997217 -274.874569)
			(xy 401.02056 -274.828757) (xy 401.050781 -274.787161) (xy 401.087137 -274.750805) (xy 401.128733 -274.720584)
			(xy 401.174545 -274.697241) (xy 401.223444 -274.681353) (xy 401.274226 -274.67331) (xy 401.325642 -274.67331)
			(xy 401.376424 -274.681353) (xy 401.425323 -274.697241) (xy 401.471135 -274.720584) (xy 401.512731 -274.750805)
			(xy 401.549087 -274.787161) (xy 401.579308 -274.828757) (xy 401.602651 -274.874569) (xy 401.618539 -274.923468)
			(xy 401.626582 -274.97425) (xy 401.627086 -274.999958) (xy 401.626582 -275.025666) (xy 402.873206 -275.025666)
			(xy 402.873206 -274.97425) (xy 402.881249 -274.923468) (xy 402.897137 -274.874569) (xy 402.92048 -274.828757)
			(xy 402.950701 -274.787161) (xy 402.987057 -274.750805) (xy 403.028653 -274.720584) (xy 403.074465 -274.697241)
			(xy 403.123364 -274.681353) (xy 403.174146 -274.67331) (xy 403.225562 -274.67331) (xy 403.276344 -274.681353)
			(xy 403.325243 -274.697241) (xy 403.371055 -274.720584) (xy 403.412651 -274.750805) (xy 403.449007 -274.787161)
			(xy 403.479228 -274.828757) (xy 403.502571 -274.874569) (xy 403.518459 -274.923468) (xy 403.526502 -274.97425)
			(xy 403.527006 -274.999958) (xy 403.526502 -275.025666) (xy 404.77338 -275.025666) (xy 404.77338 -274.97425)
			(xy 404.781423 -274.923468) (xy 404.797311 -274.874569) (xy 404.820654 -274.828757) (xy 404.850875 -274.787161)
			(xy 404.887231 -274.750805) (xy 404.928827 -274.720584) (xy 404.974639 -274.697241) (xy 405.023538 -274.681353)
			(xy 405.07432 -274.67331) (xy 405.125736 -274.67331) (xy 405.176518 -274.681353) (xy 405.225417 -274.697241)
			(xy 405.271229 -274.720584) (xy 405.312825 -274.750805) (xy 405.349181 -274.787161) (xy 405.379402 -274.828757)
			(xy 405.402745 -274.874569) (xy 405.418633 -274.923468) (xy 405.426676 -274.97425) (xy 405.42718 -274.999958)
			(xy 405.426676 -275.025666) (xy 405.418633 -275.076448) (xy 405.402745 -275.125347) (xy 405.379402 -275.171159)
			(xy 405.349181 -275.212755) (xy 405.312825 -275.249111) (xy 405.271229 -275.279332) (xy 405.225417 -275.302675)
			(xy 405.176518 -275.318563) (xy 405.125736 -275.326606) (xy 405.07432 -275.326606) (xy 405.023538 -275.318563)
			(xy 404.974639 -275.302675) (xy 404.928827 -275.279332) (xy 404.887231 -275.249111) (xy 404.850875 -275.212755)
			(xy 404.820654 -275.171159) (xy 404.797311 -275.125347) (xy 404.781423 -275.076448) (xy 404.77338 -275.025666)
			(xy 403.526502 -275.025666) (xy 403.518459 -275.076448) (xy 403.502571 -275.125347) (xy 403.479228 -275.171159)
			(xy 403.449007 -275.212755) (xy 403.412651 -275.249111) (xy 403.371055 -275.279332) (xy 403.325243 -275.302675)
			(xy 403.276344 -275.318563) (xy 403.225562 -275.326606) (xy 403.174146 -275.326606) (xy 403.123364 -275.318563)
			(xy 403.074465 -275.302675) (xy 403.028653 -275.279332) (xy 402.987057 -275.249111) (xy 402.950701 -275.212755)
			(xy 402.92048 -275.171159) (xy 402.897137 -275.125347) (xy 402.881249 -275.076448) (xy 402.873206 -275.025666)
			(xy 401.626582 -275.025666) (xy 401.618539 -275.076448) (xy 401.602651 -275.125347) (xy 401.579308 -275.171159)
			(xy 401.549087 -275.212755) (xy 401.512731 -275.249111) (xy 401.471135 -275.279332) (xy 401.425323 -275.302675)
			(xy 401.376424 -275.318563) (xy 401.325642 -275.326606) (xy 401.274226 -275.326606) (xy 401.223444 -275.318563)
			(xy 401.174545 -275.302675) (xy 401.128733 -275.279332) (xy 401.087137 -275.249111) (xy 401.050781 -275.212755)
			(xy 401.02056 -275.171159) (xy 400.997217 -275.125347) (xy 400.981329 -275.076448) (xy 400.973286 -275.025666)
			(xy 399.726662 -275.025666) (xy 399.718619 -275.076448) (xy 399.702731 -275.125347) (xy 399.679388 -275.171159)
			(xy 399.649167 -275.212755) (xy 399.612811 -275.249111) (xy 399.571215 -275.279332) (xy 399.525403 -275.302675)
			(xy 399.476504 -275.318563) (xy 399.425722 -275.326606) (xy 399.374306 -275.326606) (xy 399.323524 -275.318563)
			(xy 399.274625 -275.302675) (xy 399.228813 -275.279332) (xy 399.187217 -275.249111) (xy 399.150861 -275.212755)
			(xy 399.12064 -275.171159) (xy 399.097297 -275.125347) (xy 399.081409 -275.076448) (xy 399.073366 -275.025666)
			(xy 397.826488 -275.025666) (xy 397.818445 -275.076448) (xy 397.802557 -275.125347) (xy 397.779214 -275.171159)
			(xy 397.748993 -275.212755) (xy 397.712637 -275.249111) (xy 397.671041 -275.279332) (xy 397.625229 -275.302675)
			(xy 397.57633 -275.318563) (xy 397.525548 -275.326606) (xy 397.474132 -275.326606) (xy 397.42335 -275.318563)
			(xy 397.374451 -275.302675) (xy 397.328639 -275.279332) (xy 397.287043 -275.249111) (xy 397.250687 -275.212755)
			(xy 397.220466 -275.171159) (xy 397.197123 -275.125347) (xy 397.181235 -275.076448) (xy 397.173192 -275.025666)
			(xy 395.926568 -275.025666) (xy 395.918525 -275.076448) (xy 395.902637 -275.125347) (xy 395.879294 -275.171159)
			(xy 395.849073 -275.212755) (xy 395.812717 -275.249111) (xy 395.771121 -275.279332) (xy 395.725309 -275.302675)
			(xy 395.67641 -275.318563) (xy 395.625628 -275.326606) (xy 395.574212 -275.326606) (xy 395.52343 -275.318563)
			(xy 395.474531 -275.302675) (xy 395.428719 -275.279332) (xy 395.387123 -275.249111) (xy 395.350767 -275.212755)
			(xy 395.320546 -275.171159) (xy 395.297203 -275.125347) (xy 395.281315 -275.076448) (xy 395.273272 -275.025666)
			(xy 394.026648 -275.025666) (xy 394.018605 -275.076448) (xy 394.002717 -275.125347) (xy 393.979374 -275.171159)
			(xy 393.949153 -275.212755) (xy 393.912797 -275.249111) (xy 393.871201 -275.279332) (xy 393.825389 -275.302675)
			(xy 393.77649 -275.318563) (xy 393.725708 -275.326606) (xy 393.674292 -275.326606) (xy 393.62351 -275.318563)
			(xy 393.574611 -275.302675) (xy 393.528799 -275.279332) (xy 393.487203 -275.249111) (xy 393.450847 -275.212755)
			(xy 393.420626 -275.171159) (xy 393.397283 -275.125347) (xy 393.381395 -275.076448) (xy 393.373352 -275.025666)
			(xy 391.668 -275.025666) (xy 391.668 -275.975626) (xy 393.373352 -275.975626) (xy 393.373352 -275.92421)
			(xy 393.381395 -275.873428) (xy 393.397283 -275.824529) (xy 393.420626 -275.778717) (xy 393.450847 -275.737121)
			(xy 393.487203 -275.700765) (xy 393.528799 -275.670544) (xy 393.574611 -275.647201) (xy 393.62351 -275.631313)
			(xy 393.674292 -275.62327) (xy 393.725708 -275.62327) (xy 393.77649 -275.631313) (xy 393.825389 -275.647201)
			(xy 393.871201 -275.670544) (xy 393.912797 -275.700765) (xy 393.949153 -275.737121) (xy 393.979374 -275.778717)
			(xy 394.002717 -275.824529) (xy 394.018605 -275.873428) (xy 394.026648 -275.92421) (xy 394.027152 -275.949918)
			(xy 394.026648 -275.975626) (xy 395.273272 -275.975626) (xy 395.273272 -275.92421) (xy 395.281315 -275.873428)
			(xy 395.297203 -275.824529) (xy 395.320546 -275.778717) (xy 395.350767 -275.737121) (xy 395.387123 -275.700765)
			(xy 395.428719 -275.670544) (xy 395.474531 -275.647201) (xy 395.52343 -275.631313) (xy 395.574212 -275.62327)
			(xy 395.625628 -275.62327) (xy 395.67641 -275.631313) (xy 395.725309 -275.647201) (xy 395.771121 -275.670544)
			(xy 395.812717 -275.700765) (xy 395.849073 -275.737121) (xy 395.879294 -275.778717) (xy 395.902637 -275.824529)
			(xy 395.918525 -275.873428) (xy 395.926568 -275.92421) (xy 395.927072 -275.949918) (xy 395.926568 -275.975626)
			(xy 397.173192 -275.975626) (xy 397.173192 -275.92421) (xy 397.181235 -275.873428) (xy 397.197123 -275.824529)
			(xy 397.220466 -275.778717) (xy 397.250687 -275.737121) (xy 397.287043 -275.700765) (xy 397.328639 -275.670544)
			(xy 397.374451 -275.647201) (xy 397.42335 -275.631313) (xy 397.474132 -275.62327) (xy 397.525548 -275.62327)
			(xy 397.57633 -275.631313) (xy 397.625229 -275.647201) (xy 397.671041 -275.670544) (xy 397.712637 -275.700765)
			(xy 397.748993 -275.737121) (xy 397.779214 -275.778717) (xy 397.802557 -275.824529) (xy 397.818445 -275.873428)
			(xy 397.826488 -275.92421) (xy 397.826992 -275.949918) (xy 397.826488 -275.975626) (xy 399.073366 -275.975626)
			(xy 399.073366 -275.92421) (xy 399.081409 -275.873428) (xy 399.097297 -275.824529) (xy 399.12064 -275.778717)
			(xy 399.150861 -275.737121) (xy 399.187217 -275.700765) (xy 399.228813 -275.670544) (xy 399.274625 -275.647201)
			(xy 399.323524 -275.631313) (xy 399.374306 -275.62327) (xy 399.425722 -275.62327) (xy 399.476504 -275.631313)
			(xy 399.525403 -275.647201) (xy 399.571215 -275.670544) (xy 399.612811 -275.700765) (xy 399.649167 -275.737121)
			(xy 399.679388 -275.778717) (xy 399.702731 -275.824529) (xy 399.718619 -275.873428) (xy 399.726662 -275.92421)
			(xy 399.727166 -275.949918) (xy 399.726662 -275.975626) (xy 400.973286 -275.975626) (xy 400.973286 -275.92421)
			(xy 400.981329 -275.873428) (xy 400.997217 -275.824529) (xy 401.02056 -275.778717) (xy 401.050781 -275.737121)
			(xy 401.087137 -275.700765) (xy 401.128733 -275.670544) (xy 401.174545 -275.647201) (xy 401.223444 -275.631313)
			(xy 401.274226 -275.62327) (xy 401.325642 -275.62327) (xy 401.376424 -275.631313) (xy 401.425323 -275.647201)
			(xy 401.471135 -275.670544) (xy 401.512731 -275.700765) (xy 401.549087 -275.737121) (xy 401.579308 -275.778717)
			(xy 401.602651 -275.824529) (xy 401.618539 -275.873428) (xy 401.626582 -275.92421) (xy 401.627086 -275.949918)
			(xy 401.626582 -275.975626) (xy 402.873206 -275.975626) (xy 402.873206 -275.92421) (xy 402.881249 -275.873428)
			(xy 402.897137 -275.824529) (xy 402.92048 -275.778717) (xy 402.950701 -275.737121) (xy 402.987057 -275.700765)
			(xy 403.028653 -275.670544) (xy 403.074465 -275.647201) (xy 403.123364 -275.631313) (xy 403.174146 -275.62327)
			(xy 403.225562 -275.62327) (xy 403.276344 -275.631313) (xy 403.325243 -275.647201) (xy 403.371055 -275.670544)
			(xy 403.412651 -275.700765) (xy 403.449007 -275.737121) (xy 403.479228 -275.778717) (xy 403.502571 -275.824529)
			(xy 403.518459 -275.873428) (xy 403.526502 -275.92421) (xy 403.527006 -275.949918) (xy 403.526502 -275.975626)
			(xy 404.77338 -275.975626) (xy 404.77338 -275.92421) (xy 404.781423 -275.873428) (xy 404.797311 -275.824529)
			(xy 404.820654 -275.778717) (xy 404.850875 -275.737121) (xy 404.887231 -275.700765) (xy 404.928827 -275.670544)
			(xy 404.974639 -275.647201) (xy 405.023538 -275.631313) (xy 405.07432 -275.62327) (xy 405.125736 -275.62327)
			(xy 405.176518 -275.631313) (xy 405.225417 -275.647201) (xy 405.271229 -275.670544) (xy 405.312825 -275.700765)
			(xy 405.349181 -275.737121) (xy 405.379402 -275.778717) (xy 405.402745 -275.824529) (xy 405.418633 -275.873428)
			(xy 405.426676 -275.92421) (xy 405.42718 -275.949918) (xy 405.426676 -275.975626) (xy 405.418633 -276.026408)
			(xy 405.402745 -276.075307) (xy 405.379402 -276.121119) (xy 405.349181 -276.162715) (xy 405.312825 -276.199071)
			(xy 405.271229 -276.229292) (xy 405.225417 -276.252635) (xy 405.176518 -276.268523) (xy 405.125736 -276.276566)
			(xy 405.07432 -276.276566) (xy 405.023538 -276.268523) (xy 404.974639 -276.252635) (xy 404.928827 -276.229292)
			(xy 404.887231 -276.199071) (xy 404.850875 -276.162715) (xy 404.820654 -276.121119) (xy 404.797311 -276.075307)
			(xy 404.781423 -276.026408) (xy 404.77338 -275.975626) (xy 403.526502 -275.975626) (xy 403.518459 -276.026408)
			(xy 403.502571 -276.075307) (xy 403.479228 -276.121119) (xy 403.449007 -276.162715) (xy 403.412651 -276.199071)
			(xy 403.371055 -276.229292) (xy 403.325243 -276.252635) (xy 403.276344 -276.268523) (xy 403.225562 -276.276566)
			(xy 403.174146 -276.276566) (xy 403.123364 -276.268523) (xy 403.074465 -276.252635) (xy 403.028653 -276.229292)
			(xy 402.987057 -276.199071) (xy 402.950701 -276.162715) (xy 402.92048 -276.121119) (xy 402.897137 -276.075307)
			(xy 402.881249 -276.026408) (xy 402.873206 -275.975626) (xy 401.626582 -275.975626) (xy 401.618539 -276.026408)
			(xy 401.602651 -276.075307) (xy 401.579308 -276.121119) (xy 401.549087 -276.162715) (xy 401.512731 -276.199071)
			(xy 401.471135 -276.229292) (xy 401.425323 -276.252635) (xy 401.376424 -276.268523) (xy 401.325642 -276.276566)
			(xy 401.274226 -276.276566) (xy 401.223444 -276.268523) (xy 401.174545 -276.252635) (xy 401.128733 -276.229292)
			(xy 401.087137 -276.199071) (xy 401.050781 -276.162715) (xy 401.02056 -276.121119) (xy 400.997217 -276.075307)
			(xy 400.981329 -276.026408) (xy 400.973286 -275.975626) (xy 399.726662 -275.975626) (xy 399.718619 -276.026408)
			(xy 399.702731 -276.075307) (xy 399.679388 -276.121119) (xy 399.649167 -276.162715) (xy 399.612811 -276.199071)
			(xy 399.571215 -276.229292) (xy 399.525403 -276.252635) (xy 399.476504 -276.268523) (xy 399.425722 -276.276566)
			(xy 399.374306 -276.276566) (xy 399.323524 -276.268523) (xy 399.274625 -276.252635) (xy 399.228813 -276.229292)
			(xy 399.187217 -276.199071) (xy 399.150861 -276.162715) (xy 399.12064 -276.121119) (xy 399.097297 -276.075307)
			(xy 399.081409 -276.026408) (xy 399.073366 -275.975626) (xy 397.826488 -275.975626) (xy 397.818445 -276.026408)
			(xy 397.802557 -276.075307) (xy 397.779214 -276.121119) (xy 397.748993 -276.162715) (xy 397.712637 -276.199071)
			(xy 397.671041 -276.229292) (xy 397.625229 -276.252635) (xy 397.57633 -276.268523) (xy 397.525548 -276.276566)
			(xy 397.474132 -276.276566) (xy 397.42335 -276.268523) (xy 397.374451 -276.252635) (xy 397.328639 -276.229292)
			(xy 397.287043 -276.199071) (xy 397.250687 -276.162715) (xy 397.220466 -276.121119) (xy 397.197123 -276.075307)
			(xy 397.181235 -276.026408) (xy 397.173192 -275.975626) (xy 395.926568 -275.975626) (xy 395.918525 -276.026408)
			(xy 395.902637 -276.075307) (xy 395.879294 -276.121119) (xy 395.849073 -276.162715) (xy 395.812717 -276.199071)
			(xy 395.771121 -276.229292) (xy 395.725309 -276.252635) (xy 395.67641 -276.268523) (xy 395.625628 -276.276566)
			(xy 395.574212 -276.276566) (xy 395.52343 -276.268523) (xy 395.474531 -276.252635) (xy 395.428719 -276.229292)
			(xy 395.387123 -276.199071) (xy 395.350767 -276.162715) (xy 395.320546 -276.121119) (xy 395.297203 -276.075307)
			(xy 395.281315 -276.026408) (xy 395.273272 -275.975626) (xy 394.026648 -275.975626) (xy 394.018605 -276.026408)
			(xy 394.002717 -276.075307) (xy 393.979374 -276.121119) (xy 393.949153 -276.162715) (xy 393.912797 -276.199071)
			(xy 393.871201 -276.229292) (xy 393.825389 -276.252635) (xy 393.77649 -276.268523) (xy 393.725708 -276.276566)
			(xy 393.674292 -276.276566) (xy 393.62351 -276.268523) (xy 393.574611 -276.252635) (xy 393.528799 -276.229292)
			(xy 393.487203 -276.199071) (xy 393.450847 -276.162715) (xy 393.420626 -276.121119) (xy 393.397283 -276.075307)
			(xy 393.381395 -276.026408) (xy 393.373352 -275.975626) (xy 391.668 -275.975626) (xy 391.668 -277.849838)
			(xy 392.443982 -277.849838) (xy 392.447942 -277.800784) (xy 392.459719 -277.753) (xy 392.47901 -277.707724)
			(xy 392.505313 -277.666128) (xy 392.537948 -277.629291) (xy 392.576069 -277.598166) (xy 392.61869 -277.573559)
			(xy 392.664706 -277.556107) (xy 392.712925 -277.546263) (xy 392.7621 -277.544282) (xy 392.810955 -277.550214)
			(xy 392.858226 -277.563906) (xy 392.902688 -277.585004) (xy 392.943191 -277.61296) (xy 392.978684 -277.647052)
			(xy 393.008249 -277.686396) (xy 393.03112 -277.729973) (xy 393.046704 -277.776654) (xy 393.054599 -277.825231)
			(xy 393.055094 -277.849838) (xy 394.344156 -277.849838) (xy 394.348116 -277.800784) (xy 394.359893 -277.753)
			(xy 394.379184 -277.707724) (xy 394.405487 -277.666128) (xy 394.438122 -277.629291) (xy 394.476243 -277.598166)
			(xy 394.518864 -277.573559) (xy 394.56488 -277.556107) (xy 394.613099 -277.546263) (xy 394.662274 -277.544282)
			(xy 394.711129 -277.550214) (xy 394.7584 -277.563906) (xy 394.802862 -277.585004) (xy 394.843365 -277.61296)
			(xy 394.878858 -277.647052) (xy 394.908423 -277.686396) (xy 394.931294 -277.729973) (xy 394.946878 -277.776654)
			(xy 394.954773 -277.825231) (xy 394.955268 -277.849838) (xy 396.244076 -277.849838) (xy 396.248036 -277.800784)
			(xy 396.259813 -277.753) (xy 396.279104 -277.707724) (xy 396.305407 -277.666128) (xy 396.338042 -277.629291)
			(xy 396.376163 -277.598166) (xy 396.418784 -277.573559) (xy 396.4648 -277.556107) (xy 396.513019 -277.546263)
			(xy 396.562194 -277.544282) (xy 396.611049 -277.550214) (xy 396.65832 -277.563906) (xy 396.702782 -277.585004)
			(xy 396.743285 -277.61296) (xy 396.778778 -277.647052) (xy 396.808343 -277.686396) (xy 396.831214 -277.729973)
			(xy 396.846798 -277.776654) (xy 396.854693 -277.825231) (xy 396.855188 -277.849838) (xy 398.143996 -277.849838)
			(xy 398.147956 -277.800784) (xy 398.159733 -277.753) (xy 398.179024 -277.707724) (xy 398.205327 -277.666128)
			(xy 398.237962 -277.629291) (xy 398.276083 -277.598166) (xy 398.318704 -277.573559) (xy 398.36472 -277.556107)
			(xy 398.412939 -277.546263) (xy 398.462114 -277.544282) (xy 398.510969 -277.550214) (xy 398.55824 -277.563906)
			(xy 398.602702 -277.585004) (xy 398.643205 -277.61296) (xy 398.678698 -277.647052) (xy 398.708263 -277.686396)
			(xy 398.731134 -277.729973) (xy 398.746718 -277.776654) (xy 398.754613 -277.825231) (xy 398.755108 -277.849838)
			(xy 400.04417 -277.849838) (xy 400.04813 -277.800784) (xy 400.059907 -277.753) (xy 400.079198 -277.707724)
			(xy 400.105501 -277.666128) (xy 400.138136 -277.629291) (xy 400.176257 -277.598166) (xy 400.218878 -277.573559)
			(xy 400.264894 -277.556107) (xy 400.313113 -277.546263) (xy 400.362288 -277.544282) (xy 400.411143 -277.550214)
			(xy 400.458414 -277.563906) (xy 400.502876 -277.585004) (xy 400.543379 -277.61296) (xy 400.578872 -277.647052)
			(xy 400.608437 -277.686396) (xy 400.631308 -277.729973) (xy 400.646892 -277.776654) (xy 400.654787 -277.825231)
			(xy 400.655282 -277.849838) (xy 401.94409 -277.849838) (xy 401.94805 -277.800784) (xy 401.959827 -277.753)
			(xy 401.979118 -277.707724) (xy 402.005421 -277.666128) (xy 402.038056 -277.629291) (xy 402.076177 -277.598166)
			(xy 402.118798 -277.573559) (xy 402.164814 -277.556107) (xy 402.213033 -277.546263) (xy 402.262208 -277.544282)
			(xy 402.311063 -277.550214) (xy 402.358334 -277.563906) (xy 402.402796 -277.585004) (xy 402.443299 -277.61296)
			(xy 402.478792 -277.647052) (xy 402.508357 -277.686396) (xy 402.531228 -277.729973) (xy 402.546812 -277.776654)
			(xy 402.554707 -277.825231) (xy 402.555202 -277.849838) (xy 403.84401 -277.849838) (xy 403.84797 -277.800784)
			(xy 403.859747 -277.753) (xy 403.879038 -277.707724) (xy 403.905341 -277.666128) (xy 403.937976 -277.629291)
			(xy 403.976097 -277.598166) (xy 404.018718 -277.573559) (xy 404.064734 -277.556107) (xy 404.112953 -277.546263)
			(xy 404.162128 -277.544282) (xy 404.210983 -277.550214) (xy 404.258254 -277.563906) (xy 404.302716 -277.585004)
			(xy 404.343219 -277.61296) (xy 404.378712 -277.647052) (xy 404.408277 -277.686396) (xy 404.431148 -277.729973)
			(xy 404.446732 -277.776654) (xy 404.454627 -277.825231) (xy 404.455122 -277.849838) (xy 404.454627 -277.874445)
			(xy 404.446732 -277.923022) (xy 404.431148 -277.969703) (xy 404.408277 -278.01328) (xy 404.378712 -278.052624)
			(xy 404.343219 -278.086716) (xy 404.302716 -278.114672) (xy 404.258254 -278.13577) (xy 404.210983 -278.149462)
			(xy 404.162128 -278.155394) (xy 404.112953 -278.153413) (xy 404.064734 -278.143569) (xy 404.018718 -278.126117)
			(xy 403.976097 -278.10151) (xy 403.937976 -278.070385) (xy 403.905341 -278.033548) (xy 403.879038 -277.991952)
			(xy 403.859747 -277.946676) (xy 403.84797 -277.898892) (xy 403.84401 -277.849838) (xy 402.555202 -277.849838)
			(xy 402.554707 -277.874445) (xy 402.546812 -277.923022) (xy 402.531228 -277.969703) (xy 402.508357 -278.01328)
			(xy 402.478792 -278.052624) (xy 402.443299 -278.086716) (xy 402.402796 -278.114672) (xy 402.358334 -278.13577)
			(xy 402.311063 -278.149462) (xy 402.262208 -278.155394) (xy 402.213033 -278.153413) (xy 402.164814 -278.143569)
			(xy 402.118798 -278.126117) (xy 402.076177 -278.10151) (xy 402.038056 -278.070385) (xy 402.005421 -278.033548)
			(xy 401.979118 -277.991952) (xy 401.959827 -277.946676) (xy 401.94805 -277.898892) (xy 401.94409 -277.849838)
			(xy 400.655282 -277.849838) (xy 400.654787 -277.874445) (xy 400.646892 -277.923022) (xy 400.631308 -277.969703)
			(xy 400.608437 -278.01328) (xy 400.578872 -278.052624) (xy 400.543379 -278.086716) (xy 400.502876 -278.114672)
			(xy 400.458414 -278.13577) (xy 400.411143 -278.149462) (xy 400.362288 -278.155394) (xy 400.313113 -278.153413)
			(xy 400.264894 -278.143569) (xy 400.218878 -278.126117) (xy 400.176257 -278.10151) (xy 400.138136 -278.070385)
			(xy 400.105501 -278.033548) (xy 400.079198 -277.991952) (xy 400.059907 -277.946676) (xy 400.04813 -277.898892)
			(xy 400.04417 -277.849838) (xy 398.755108 -277.849838) (xy 398.754613 -277.874445) (xy 398.746718 -277.923022)
			(xy 398.731134 -277.969703) (xy 398.708263 -278.01328) (xy 398.678698 -278.052624) (xy 398.643205 -278.086716)
			(xy 398.602702 -278.114672) (xy 398.55824 -278.13577) (xy 398.510969 -278.149462) (xy 398.462114 -278.155394)
			(xy 398.412939 -278.153413) (xy 398.36472 -278.143569) (xy 398.318704 -278.126117) (xy 398.276083 -278.10151)
			(xy 398.237962 -278.070385) (xy 398.205327 -278.033548) (xy 398.179024 -277.991952) (xy 398.159733 -277.946676)
			(xy 398.147956 -277.898892) (xy 398.143996 -277.849838) (xy 396.855188 -277.849838) (xy 396.854693 -277.874445)
			(xy 396.846798 -277.923022) (xy 396.831214 -277.969703) (xy 396.808343 -278.01328) (xy 396.778778 -278.052624)
			(xy 396.743285 -278.086716) (xy 396.702782 -278.114672) (xy 396.65832 -278.13577) (xy 396.611049 -278.149462)
			(xy 396.562194 -278.155394) (xy 396.513019 -278.153413) (xy 396.4648 -278.143569) (xy 396.418784 -278.126117)
			(xy 396.376163 -278.10151) (xy 396.338042 -278.070385) (xy 396.305407 -278.033548) (xy 396.279104 -277.991952)
			(xy 396.259813 -277.946676) (xy 396.248036 -277.898892) (xy 396.244076 -277.849838) (xy 394.955268 -277.849838)
			(xy 394.954773 -277.874445) (xy 394.946878 -277.923022) (xy 394.931294 -277.969703) (xy 394.908423 -278.01328)
			(xy 394.878858 -278.052624) (xy 394.843365 -278.086716) (xy 394.802862 -278.114672) (xy 394.7584 -278.13577)
			(xy 394.711129 -278.149462) (xy 394.662274 -278.155394) (xy 394.613099 -278.153413) (xy 394.56488 -278.143569)
			(xy 394.518864 -278.126117) (xy 394.476243 -278.10151) (xy 394.438122 -278.070385) (xy 394.405487 -278.033548)
			(xy 394.379184 -277.991952) (xy 394.359893 -277.946676) (xy 394.348116 -277.898892) (xy 394.344156 -277.849838)
			(xy 393.055094 -277.849838) (xy 393.054599 -277.874445) (xy 393.046704 -277.923022) (xy 393.03112 -277.969703)
			(xy 393.008249 -278.01328) (xy 392.978684 -278.052624) (xy 392.943191 -278.086716) (xy 392.902688 -278.114672)
			(xy 392.858226 -278.13577) (xy 392.810955 -278.149462) (xy 392.7621 -278.155394) (xy 392.712925 -278.153413)
			(xy 392.664706 -278.143569) (xy 392.61869 -278.126117) (xy 392.576069 -278.10151) (xy 392.537948 -278.070385)
			(xy 392.505313 -278.033548) (xy 392.47901 -277.991952) (xy 392.459719 -277.946676) (xy 392.447942 -277.898892)
			(xy 392.443982 -277.849838) (xy 391.668 -277.849838) (xy 391.668 -278.799798) (xy 392.443982 -278.799798)
			(xy 392.447942 -278.750744) (xy 392.459719 -278.70296) (xy 392.47901 -278.657684) (xy 392.505313 -278.616088)
			(xy 392.537948 -278.579251) (xy 392.576069 -278.548126) (xy 392.61869 -278.523519) (xy 392.664706 -278.506067)
			(xy 392.712925 -278.496223) (xy 392.7621 -278.494242) (xy 392.810955 -278.500174) (xy 392.858226 -278.513866)
			(xy 392.902688 -278.534964) (xy 392.943191 -278.56292) (xy 392.978684 -278.597012) (xy 393.008249 -278.636356)
			(xy 393.03112 -278.679933) (xy 393.046704 -278.726614) (xy 393.054599 -278.775191) (xy 393.055094 -278.799798)
			(xy 394.344156 -278.799798) (xy 394.348116 -278.750744) (xy 394.359893 -278.70296) (xy 394.379184 -278.657684)
			(xy 394.405487 -278.616088) (xy 394.438122 -278.579251) (xy 394.476243 -278.548126) (xy 394.518864 -278.523519)
			(xy 394.56488 -278.506067) (xy 394.613099 -278.496223) (xy 394.662274 -278.494242) (xy 394.711129 -278.500174)
			(xy 394.7584 -278.513866) (xy 394.802862 -278.534964) (xy 394.843365 -278.56292) (xy 394.878858 -278.597012)
			(xy 394.908423 -278.636356) (xy 394.931294 -278.679933) (xy 394.946878 -278.726614) (xy 394.954773 -278.775191)
			(xy 394.955268 -278.799798) (xy 396.244076 -278.799798) (xy 396.248036 -278.750744) (xy 396.259813 -278.70296)
			(xy 396.279104 -278.657684) (xy 396.305407 -278.616088) (xy 396.338042 -278.579251) (xy 396.376163 -278.548126)
			(xy 396.418784 -278.523519) (xy 396.4648 -278.506067) (xy 396.513019 -278.496223) (xy 396.562194 -278.494242)
			(xy 396.611049 -278.500174) (xy 396.65832 -278.513866) (xy 396.702782 -278.534964) (xy 396.743285 -278.56292)
			(xy 396.778778 -278.597012) (xy 396.808343 -278.636356) (xy 396.831214 -278.679933) (xy 396.846798 -278.726614)
			(xy 396.854693 -278.775191) (xy 396.855188 -278.799798) (xy 398.143996 -278.799798) (xy 398.147956 -278.750744)
			(xy 398.159733 -278.70296) (xy 398.179024 -278.657684) (xy 398.205327 -278.616088) (xy 398.237962 -278.579251)
			(xy 398.276083 -278.548126) (xy 398.318704 -278.523519) (xy 398.36472 -278.506067) (xy 398.412939 -278.496223)
			(xy 398.462114 -278.494242) (xy 398.510969 -278.500174) (xy 398.55824 -278.513866) (xy 398.602702 -278.534964)
			(xy 398.643205 -278.56292) (xy 398.678698 -278.597012) (xy 398.708263 -278.636356) (xy 398.731134 -278.679933)
			(xy 398.746718 -278.726614) (xy 398.754613 -278.775191) (xy 398.755108 -278.799798) (xy 400.04417 -278.799798)
			(xy 400.04813 -278.750744) (xy 400.059907 -278.70296) (xy 400.079198 -278.657684) (xy 400.105501 -278.616088)
			(xy 400.138136 -278.579251) (xy 400.176257 -278.548126) (xy 400.218878 -278.523519) (xy 400.264894 -278.506067)
			(xy 400.313113 -278.496223) (xy 400.362288 -278.494242) (xy 400.411143 -278.500174) (xy 400.458414 -278.513866)
			(xy 400.502876 -278.534964) (xy 400.543379 -278.56292) (xy 400.578872 -278.597012) (xy 400.608437 -278.636356)
			(xy 400.631308 -278.679933) (xy 400.646892 -278.726614) (xy 400.654787 -278.775191) (xy 400.655282 -278.799798)
			(xy 401.94409 -278.799798) (xy 401.94805 -278.750744) (xy 401.959827 -278.70296) (xy 401.979118 -278.657684)
			(xy 402.005421 -278.616088) (xy 402.038056 -278.579251) (xy 402.076177 -278.548126) (xy 402.118798 -278.523519)
			(xy 402.164814 -278.506067) (xy 402.213033 -278.496223) (xy 402.262208 -278.494242) (xy 402.311063 -278.500174)
			(xy 402.358334 -278.513866) (xy 402.402796 -278.534964) (xy 402.443299 -278.56292) (xy 402.478792 -278.597012)
			(xy 402.508357 -278.636356) (xy 402.531228 -278.679933) (xy 402.546812 -278.726614) (xy 402.554707 -278.775191)
			(xy 402.555202 -278.799798) (xy 403.84401 -278.799798) (xy 403.84797 -278.750744) (xy 403.859747 -278.70296)
			(xy 403.879038 -278.657684) (xy 403.905341 -278.616088) (xy 403.937976 -278.579251) (xy 403.976097 -278.548126)
			(xy 404.018718 -278.523519) (xy 404.064734 -278.506067) (xy 404.112953 -278.496223) (xy 404.162128 -278.494242)
			(xy 404.210983 -278.500174) (xy 404.258254 -278.513866) (xy 404.302716 -278.534964) (xy 404.343219 -278.56292)
			(xy 404.378712 -278.597012) (xy 404.408277 -278.636356) (xy 404.431148 -278.679933) (xy 404.446732 -278.726614)
			(xy 404.454627 -278.775191) (xy 404.455122 -278.799798) (xy 405.744184 -278.799798) (xy 405.748144 -278.750744)
			(xy 405.759921 -278.70296) (xy 405.779212 -278.657684) (xy 405.805515 -278.616088) (xy 405.83815 -278.579251)
			(xy 405.876271 -278.548126) (xy 405.918892 -278.523519) (xy 405.964908 -278.506067) (xy 406.013127 -278.496223)
			(xy 406.062302 -278.494242) (xy 406.111157 -278.500174) (xy 406.158428 -278.513866) (xy 406.20289 -278.534964)
			(xy 406.243393 -278.56292) (xy 406.278886 -278.597012) (xy 406.308451 -278.636356) (xy 406.331322 -278.679933)
			(xy 406.346906 -278.726614) (xy 406.354801 -278.775191) (xy 406.355296 -278.799798) (xy 406.354801 -278.824405)
			(xy 406.346906 -278.872982) (xy 406.331322 -278.919663) (xy 406.308451 -278.96324) (xy 406.278886 -279.002584)
			(xy 406.243393 -279.036676) (xy 406.20289 -279.064632) (xy 406.158428 -279.08573) (xy 406.111157 -279.099422)
			(xy 406.062302 -279.105354) (xy 406.013127 -279.103373) (xy 405.964908 -279.093529) (xy 405.918892 -279.076077)
			(xy 405.876271 -279.05147) (xy 405.83815 -279.020345) (xy 405.805515 -278.983508) (xy 405.779212 -278.941912)
			(xy 405.759921 -278.896636) (xy 405.748144 -278.848852) (xy 405.744184 -278.799798) (xy 404.455122 -278.799798)
			(xy 404.454627 -278.824405) (xy 404.446732 -278.872982) (xy 404.431148 -278.919663) (xy 404.408277 -278.96324)
			(xy 404.378712 -279.002584) (xy 404.343219 -279.036676) (xy 404.302716 -279.064632) (xy 404.258254 -279.08573)
			(xy 404.210983 -279.099422) (xy 404.162128 -279.105354) (xy 404.112953 -279.103373) (xy 404.064734 -279.093529)
			(xy 404.018718 -279.076077) (xy 403.976097 -279.05147) (xy 403.937976 -279.020345) (xy 403.905341 -278.983508)
			(xy 403.879038 -278.941912) (xy 403.859747 -278.896636) (xy 403.84797 -278.848852) (xy 403.84401 -278.799798)
			(xy 402.555202 -278.799798) (xy 402.554707 -278.824405) (xy 402.546812 -278.872982) (xy 402.531228 -278.919663)
			(xy 402.508357 -278.96324) (xy 402.478792 -279.002584) (xy 402.443299 -279.036676) (xy 402.402796 -279.064632)
			(xy 402.358334 -279.08573) (xy 402.311063 -279.099422) (xy 402.262208 -279.105354) (xy 402.213033 -279.103373)
			(xy 402.164814 -279.093529) (xy 402.118798 -279.076077) (xy 402.076177 -279.05147) (xy 402.038056 -279.020345)
			(xy 402.005421 -278.983508) (xy 401.979118 -278.941912) (xy 401.959827 -278.896636) (xy 401.94805 -278.848852)
			(xy 401.94409 -278.799798) (xy 400.655282 -278.799798) (xy 400.654787 -278.824405) (xy 400.646892 -278.872982)
			(xy 400.631308 -278.919663) (xy 400.608437 -278.96324) (xy 400.578872 -279.002584) (xy 400.543379 -279.036676)
			(xy 400.502876 -279.064632) (xy 400.458414 -279.08573) (xy 400.411143 -279.099422) (xy 400.362288 -279.105354)
			(xy 400.313113 -279.103373) (xy 400.264894 -279.093529) (xy 400.218878 -279.076077) (xy 400.176257 -279.05147)
			(xy 400.138136 -279.020345) (xy 400.105501 -278.983508) (xy 400.079198 -278.941912) (xy 400.059907 -278.896636)
			(xy 400.04813 -278.848852) (xy 400.04417 -278.799798) (xy 398.755108 -278.799798) (xy 398.754613 -278.824405)
			(xy 398.746718 -278.872982) (xy 398.731134 -278.919663) (xy 398.708263 -278.96324) (xy 398.678698 -279.002584)
			(xy 398.643205 -279.036676) (xy 398.602702 -279.064632) (xy 398.55824 -279.08573) (xy 398.510969 -279.099422)
			(xy 398.462114 -279.105354) (xy 398.412939 -279.103373) (xy 398.36472 -279.093529) (xy 398.318704 -279.076077)
			(xy 398.276083 -279.05147) (xy 398.237962 -279.020345) (xy 398.205327 -278.983508) (xy 398.179024 -278.941912)
			(xy 398.159733 -278.896636) (xy 398.147956 -278.848852) (xy 398.143996 -278.799798) (xy 396.855188 -278.799798)
			(xy 396.854693 -278.824405) (xy 396.846798 -278.872982) (xy 396.831214 -278.919663) (xy 396.808343 -278.96324)
			(xy 396.778778 -279.002584) (xy 396.743285 -279.036676) (xy 396.702782 -279.064632) (xy 396.65832 -279.08573)
			(xy 396.611049 -279.099422) (xy 396.562194 -279.105354) (xy 396.513019 -279.103373) (xy 396.4648 -279.093529)
			(xy 396.418784 -279.076077) (xy 396.376163 -279.05147) (xy 396.338042 -279.020345) (xy 396.305407 -278.983508)
			(xy 396.279104 -278.941912) (xy 396.259813 -278.896636) (xy 396.248036 -278.848852) (xy 396.244076 -278.799798)
			(xy 394.955268 -278.799798) (xy 394.954773 -278.824405) (xy 394.946878 -278.872982) (xy 394.931294 -278.919663)
			(xy 394.908423 -278.96324) (xy 394.878858 -279.002584) (xy 394.843365 -279.036676) (xy 394.802862 -279.064632)
			(xy 394.7584 -279.08573) (xy 394.711129 -279.099422) (xy 394.662274 -279.105354) (xy 394.613099 -279.103373)
			(xy 394.56488 -279.093529) (xy 394.518864 -279.076077) (xy 394.476243 -279.05147) (xy 394.438122 -279.020345)
			(xy 394.405487 -278.983508) (xy 394.379184 -278.941912) (xy 394.359893 -278.896636) (xy 394.348116 -278.848852)
			(xy 394.344156 -278.799798) (xy 393.055094 -278.799798) (xy 393.054599 -278.824405) (xy 393.046704 -278.872982)
			(xy 393.03112 -278.919663) (xy 393.008249 -278.96324) (xy 392.978684 -279.002584) (xy 392.943191 -279.036676)
			(xy 392.902688 -279.064632) (xy 392.858226 -279.08573) (xy 392.810955 -279.099422) (xy 392.7621 -279.105354)
			(xy 392.712925 -279.103373) (xy 392.664706 -279.093529) (xy 392.61869 -279.076077) (xy 392.576069 -279.05147)
			(xy 392.537948 -279.020345) (xy 392.505313 -278.983508) (xy 392.47901 -278.941912) (xy 392.459719 -278.896636)
			(xy 392.447942 -278.848852) (xy 392.443982 -278.799798) (xy 391.668 -278.799798) (xy 391.668 -279.749504)
			(xy 393.394196 -279.749504) (xy 393.398156 -279.70045) (xy 393.409933 -279.652666) (xy 393.429224 -279.60739)
			(xy 393.455527 -279.565794) (xy 393.488162 -279.528957) (xy 393.526283 -279.497832) (xy 393.568904 -279.473225)
			(xy 393.61492 -279.455773) (xy 393.663139 -279.445929) (xy 393.712314 -279.443948) (xy 393.761169 -279.44988)
			(xy 393.80844 -279.463572) (xy 393.852902 -279.48467) (xy 393.893405 -279.512626) (xy 393.928898 -279.546718)
			(xy 393.958463 -279.586062) (xy 393.981334 -279.629639) (xy 393.996918 -279.67632) (xy 394.004813 -279.724897)
			(xy 394.005308 -279.749504) (xy 395.294116 -279.749504) (xy 395.298076 -279.70045) (xy 395.309853 -279.652666)
			(xy 395.329144 -279.60739) (xy 395.355447 -279.565794) (xy 395.388082 -279.528957) (xy 395.426203 -279.497832)
			(xy 395.468824 -279.473225) (xy 395.51484 -279.455773) (xy 395.563059 -279.445929) (xy 395.612234 -279.443948)
			(xy 395.661089 -279.44988) (xy 395.70836 -279.463572) (xy 395.752822 -279.48467) (xy 395.793325 -279.512626)
			(xy 395.828818 -279.546718) (xy 395.858383 -279.586062) (xy 395.881254 -279.629639) (xy 395.896838 -279.67632)
			(xy 395.904733 -279.724897) (xy 395.905228 -279.749504) (xy 397.194036 -279.749504) (xy 397.197996 -279.70045)
			(xy 397.209773 -279.652666) (xy 397.229064 -279.60739) (xy 397.255367 -279.565794) (xy 397.288002 -279.528957)
			(xy 397.326123 -279.497832) (xy 397.368744 -279.473225) (xy 397.41476 -279.455773) (xy 397.462979 -279.445929)
			(xy 397.512154 -279.443948) (xy 397.561009 -279.44988) (xy 397.60828 -279.463572) (xy 397.652742 -279.48467)
			(xy 397.693245 -279.512626) (xy 397.728738 -279.546718) (xy 397.758303 -279.586062) (xy 397.781174 -279.629639)
			(xy 397.796758 -279.67632) (xy 397.804653 -279.724897) (xy 397.805148 -279.749504) (xy 399.09421 -279.749504)
			(xy 399.09817 -279.70045) (xy 399.109947 -279.652666) (xy 399.129238 -279.60739) (xy 399.155541 -279.565794)
			(xy 399.188176 -279.528957) (xy 399.226297 -279.497832) (xy 399.268918 -279.473225) (xy 399.314934 -279.455773)
			(xy 399.363153 -279.445929) (xy 399.412328 -279.443948) (xy 399.461183 -279.44988) (xy 399.508454 -279.463572)
			(xy 399.552916 -279.48467) (xy 399.593419 -279.512626) (xy 399.628912 -279.546718) (xy 399.658477 -279.586062)
			(xy 399.681348 -279.629639) (xy 399.696932 -279.67632) (xy 399.704827 -279.724897) (xy 399.705322 -279.749504)
			(xy 400.99413 -279.749504) (xy 400.99809 -279.70045) (xy 401.009867 -279.652666) (xy 401.029158 -279.60739)
			(xy 401.055461 -279.565794) (xy 401.088096 -279.528957) (xy 401.126217 -279.497832) (xy 401.168838 -279.473225)
			(xy 401.214854 -279.455773) (xy 401.263073 -279.445929) (xy 401.312248 -279.443948) (xy 401.361103 -279.44988)
			(xy 401.408374 -279.463572) (xy 401.452836 -279.48467) (xy 401.493339 -279.512626) (xy 401.528832 -279.546718)
			(xy 401.558397 -279.586062) (xy 401.581268 -279.629639) (xy 401.596852 -279.67632) (xy 401.604747 -279.724897)
			(xy 401.605242 -279.749504) (xy 402.89405 -279.749504) (xy 402.89801 -279.70045) (xy 402.909787 -279.652666)
			(xy 402.929078 -279.60739) (xy 402.955381 -279.565794) (xy 402.988016 -279.528957) (xy 403.026137 -279.497832)
			(xy 403.068758 -279.473225) (xy 403.114774 -279.455773) (xy 403.162993 -279.445929) (xy 403.212168 -279.443948)
			(xy 403.261023 -279.44988) (xy 403.308294 -279.463572) (xy 403.352756 -279.48467) (xy 403.393259 -279.512626)
			(xy 403.428752 -279.546718) (xy 403.458317 -279.586062) (xy 403.481188 -279.629639) (xy 403.496772 -279.67632)
			(xy 403.504667 -279.724897) (xy 403.505162 -279.749504) (xy 404.79397 -279.749504) (xy 404.79793 -279.70045)
			(xy 404.809707 -279.652666) (xy 404.828998 -279.60739) (xy 404.855301 -279.565794) (xy 404.887936 -279.528957)
			(xy 404.926057 -279.497832) (xy 404.968678 -279.473225) (xy 405.014694 -279.455773) (xy 405.062913 -279.445929)
			(xy 405.112088 -279.443948) (xy 405.160943 -279.44988) (xy 405.208214 -279.463572) (xy 405.252676 -279.48467)
			(xy 405.293179 -279.512626) (xy 405.328672 -279.546718) (xy 405.358237 -279.586062) (xy 405.381108 -279.629639)
			(xy 405.396692 -279.67632) (xy 405.404587 -279.724897) (xy 405.405082 -279.749504) (xy 405.404587 -279.774111)
			(xy 405.396692 -279.822688) (xy 405.381108 -279.869369) (xy 405.358237 -279.912946) (xy 405.328672 -279.95229)
			(xy 405.293179 -279.986382) (xy 405.252676 -280.014338) (xy 405.208214 -280.035436) (xy 405.160943 -280.049128)
			(xy 405.112088 -280.05506) (xy 405.062913 -280.053079) (xy 405.014694 -280.043235) (xy 404.968678 -280.025783)
			(xy 404.926057 -280.001176) (xy 404.887936 -279.970051) (xy 404.855301 -279.933214) (xy 404.828998 -279.891618)
			(xy 404.809707 -279.846342) (xy 404.79793 -279.798558) (xy 404.79397 -279.749504) (xy 403.505162 -279.749504)
			(xy 403.504667 -279.774111) (xy 403.496772 -279.822688) (xy 403.481188 -279.869369) (xy 403.458317 -279.912946)
			(xy 403.428752 -279.95229) (xy 403.393259 -279.986382) (xy 403.352756 -280.014338) (xy 403.308294 -280.035436)
			(xy 403.261023 -280.049128) (xy 403.212168 -280.05506) (xy 403.162993 -280.053079) (xy 403.114774 -280.043235)
			(xy 403.068758 -280.025783) (xy 403.026137 -280.001176) (xy 402.988016 -279.970051) (xy 402.955381 -279.933214)
			(xy 402.929078 -279.891618) (xy 402.909787 -279.846342) (xy 402.89801 -279.798558) (xy 402.89405 -279.749504)
			(xy 401.605242 -279.749504) (xy 401.604747 -279.774111) (xy 401.596852 -279.822688) (xy 401.581268 -279.869369)
			(xy 401.558397 -279.912946) (xy 401.528832 -279.95229) (xy 401.493339 -279.986382) (xy 401.452836 -280.014338)
			(xy 401.408374 -280.035436) (xy 401.361103 -280.049128) (xy 401.312248 -280.05506) (xy 401.263073 -280.053079)
			(xy 401.214854 -280.043235) (xy 401.168838 -280.025783) (xy 401.126217 -280.001176) (xy 401.088096 -279.970051)
			(xy 401.055461 -279.933214) (xy 401.029158 -279.891618) (xy 401.009867 -279.846342) (xy 400.99809 -279.798558)
			(xy 400.99413 -279.749504) (xy 399.705322 -279.749504) (xy 399.704827 -279.774111) (xy 399.696932 -279.822688)
			(xy 399.681348 -279.869369) (xy 399.658477 -279.912946) (xy 399.628912 -279.95229) (xy 399.593419 -279.986382)
			(xy 399.552916 -280.014338) (xy 399.508454 -280.035436) (xy 399.461183 -280.049128) (xy 399.412328 -280.05506)
			(xy 399.363153 -280.053079) (xy 399.314934 -280.043235) (xy 399.268918 -280.025783) (xy 399.226297 -280.001176)
			(xy 399.188176 -279.970051) (xy 399.155541 -279.933214) (xy 399.129238 -279.891618) (xy 399.109947 -279.846342)
			(xy 399.09817 -279.798558) (xy 399.09421 -279.749504) (xy 397.805148 -279.749504) (xy 397.804653 -279.774111)
			(xy 397.796758 -279.822688) (xy 397.781174 -279.869369) (xy 397.758303 -279.912946) (xy 397.728738 -279.95229)
			(xy 397.693245 -279.986382) (xy 397.652742 -280.014338) (xy 397.60828 -280.035436) (xy 397.561009 -280.049128)
			(xy 397.512154 -280.05506) (xy 397.462979 -280.053079) (xy 397.41476 -280.043235) (xy 397.368744 -280.025783)
			(xy 397.326123 -280.001176) (xy 397.288002 -279.970051) (xy 397.255367 -279.933214) (xy 397.229064 -279.891618)
			(xy 397.209773 -279.846342) (xy 397.197996 -279.798558) (xy 397.194036 -279.749504) (xy 395.905228 -279.749504)
			(xy 395.904733 -279.774111) (xy 395.896838 -279.822688) (xy 395.881254 -279.869369) (xy 395.858383 -279.912946)
			(xy 395.828818 -279.95229) (xy 395.793325 -279.986382) (xy 395.752822 -280.014338) (xy 395.70836 -280.035436)
			(xy 395.661089 -280.049128) (xy 395.612234 -280.05506) (xy 395.563059 -280.053079) (xy 395.51484 -280.043235)
			(xy 395.468824 -280.025783) (xy 395.426203 -280.001176) (xy 395.388082 -279.970051) (xy 395.355447 -279.933214)
			(xy 395.329144 -279.891618) (xy 395.309853 -279.846342) (xy 395.298076 -279.798558) (xy 395.294116 -279.749504)
			(xy 394.005308 -279.749504) (xy 394.004813 -279.774111) (xy 393.996918 -279.822688) (xy 393.981334 -279.869369)
			(xy 393.958463 -279.912946) (xy 393.928898 -279.95229) (xy 393.893405 -279.986382) (xy 393.852902 -280.014338)
			(xy 393.80844 -280.035436) (xy 393.761169 -280.049128) (xy 393.712314 -280.05506) (xy 393.663139 -280.053079)
			(xy 393.61492 -280.043235) (xy 393.568904 -280.025783) (xy 393.526283 -280.001176) (xy 393.488162 -279.970051)
			(xy 393.455527 -279.933214) (xy 393.429224 -279.891618) (xy 393.409933 -279.846342) (xy 393.398156 -279.798558)
			(xy 393.394196 -279.749504) (xy 391.668 -279.749504) (xy 391.668 -280.699718) (xy 393.394196 -280.699718)
			(xy 393.398156 -280.650664) (xy 393.409933 -280.60288) (xy 393.429224 -280.557604) (xy 393.455527 -280.516008)
			(xy 393.488162 -280.479171) (xy 393.526283 -280.448046) (xy 393.568904 -280.423439) (xy 393.61492 -280.405987)
			(xy 393.663139 -280.396143) (xy 393.712314 -280.394162) (xy 393.761169 -280.400094) (xy 393.80844 -280.413786)
			(xy 393.852902 -280.434884) (xy 393.893405 -280.46284) (xy 393.928898 -280.496932) (xy 393.958463 -280.536276)
			(xy 393.981334 -280.579853) (xy 393.996918 -280.626534) (xy 394.004813 -280.675111) (xy 394.005308 -280.699718)
			(xy 395.294116 -280.699718) (xy 395.298076 -280.650664) (xy 395.309853 -280.60288) (xy 395.329144 -280.557604)
			(xy 395.355447 -280.516008) (xy 395.388082 -280.479171) (xy 395.426203 -280.448046) (xy 395.468824 -280.423439)
			(xy 395.51484 -280.405987) (xy 395.563059 -280.396143) (xy 395.612234 -280.394162) (xy 395.661089 -280.400094)
			(xy 395.70836 -280.413786) (xy 395.752822 -280.434884) (xy 395.793325 -280.46284) (xy 395.828818 -280.496932)
			(xy 395.858383 -280.536276) (xy 395.881254 -280.579853) (xy 395.896838 -280.626534) (xy 395.904733 -280.675111)
			(xy 395.905228 -280.699718) (xy 397.194036 -280.699718) (xy 397.197996 -280.650664) (xy 397.209773 -280.60288)
			(xy 397.229064 -280.557604) (xy 397.255367 -280.516008) (xy 397.288002 -280.479171) (xy 397.326123 -280.448046)
			(xy 397.368744 -280.423439) (xy 397.41476 -280.405987) (xy 397.462979 -280.396143) (xy 397.512154 -280.394162)
			(xy 397.561009 -280.400094) (xy 397.60828 -280.413786) (xy 397.652742 -280.434884) (xy 397.693245 -280.46284)
			(xy 397.728738 -280.496932) (xy 397.758303 -280.536276) (xy 397.781174 -280.579853) (xy 397.796758 -280.626534)
			(xy 397.804653 -280.675111) (xy 397.805148 -280.699718) (xy 399.09421 -280.699718) (xy 399.09817 -280.650664)
			(xy 399.109947 -280.60288) (xy 399.129238 -280.557604) (xy 399.155541 -280.516008) (xy 399.188176 -280.479171)
			(xy 399.226297 -280.448046) (xy 399.268918 -280.423439) (xy 399.314934 -280.405987) (xy 399.363153 -280.396143)
			(xy 399.412328 -280.394162) (xy 399.461183 -280.400094) (xy 399.508454 -280.413786) (xy 399.552916 -280.434884)
			(xy 399.593419 -280.46284) (xy 399.628912 -280.496932) (xy 399.658477 -280.536276) (xy 399.681348 -280.579853)
			(xy 399.696932 -280.626534) (xy 399.704827 -280.675111) (xy 399.705322 -280.699718) (xy 400.99413 -280.699718)
			(xy 400.99809 -280.650664) (xy 401.009867 -280.60288) (xy 401.029158 -280.557604) (xy 401.055461 -280.516008)
			(xy 401.088096 -280.479171) (xy 401.126217 -280.448046) (xy 401.168838 -280.423439) (xy 401.214854 -280.405987)
			(xy 401.263073 -280.396143) (xy 401.312248 -280.394162) (xy 401.361103 -280.400094) (xy 401.408374 -280.413786)
			(xy 401.452836 -280.434884) (xy 401.493339 -280.46284) (xy 401.528832 -280.496932) (xy 401.558397 -280.536276)
			(xy 401.581268 -280.579853) (xy 401.596852 -280.626534) (xy 401.604747 -280.675111) (xy 401.605242 -280.699718)
			(xy 402.89405 -280.699718) (xy 402.89801 -280.650664) (xy 402.909787 -280.60288) (xy 402.929078 -280.557604)
			(xy 402.955381 -280.516008) (xy 402.988016 -280.479171) (xy 403.026137 -280.448046) (xy 403.068758 -280.423439)
			(xy 403.114774 -280.405987) (xy 403.162993 -280.396143) (xy 403.212168 -280.394162) (xy 403.261023 -280.400094)
			(xy 403.308294 -280.413786) (xy 403.352756 -280.434884) (xy 403.393259 -280.46284) (xy 403.428752 -280.496932)
			(xy 403.458317 -280.536276) (xy 403.481188 -280.579853) (xy 403.496772 -280.626534) (xy 403.504667 -280.675111)
			(xy 403.505162 -280.699718) (xy 404.79397 -280.699718) (xy 404.79793 -280.650664) (xy 404.809707 -280.60288)
			(xy 404.828998 -280.557604) (xy 404.855301 -280.516008) (xy 404.887936 -280.479171) (xy 404.926057 -280.448046)
			(xy 404.968678 -280.423439) (xy 405.014694 -280.405987) (xy 405.062913 -280.396143) (xy 405.112088 -280.394162)
			(xy 405.160943 -280.400094) (xy 405.208214 -280.413786) (xy 405.252676 -280.434884) (xy 405.293179 -280.46284)
			(xy 405.328672 -280.496932) (xy 405.358237 -280.536276) (xy 405.381108 -280.579853) (xy 405.396692 -280.626534)
			(xy 405.404587 -280.675111) (xy 405.405082 -280.699718) (xy 405.404587 -280.724325) (xy 405.396692 -280.772902)
			(xy 405.381108 -280.819583) (xy 405.358237 -280.86316) (xy 405.328672 -280.902504) (xy 405.293179 -280.936596)
			(xy 405.252676 -280.964552) (xy 405.208214 -280.98565) (xy 405.160943 -280.999342) (xy 405.112088 -281.005274)
			(xy 405.062913 -281.003293) (xy 405.014694 -280.993449) (xy 404.968678 -280.975997) (xy 404.926057 -280.95139)
			(xy 404.887936 -280.920265) (xy 404.855301 -280.883428) (xy 404.828998 -280.841832) (xy 404.809707 -280.796556)
			(xy 404.79793 -280.748772) (xy 404.79397 -280.699718) (xy 403.505162 -280.699718) (xy 403.504667 -280.724325)
			(xy 403.496772 -280.772902) (xy 403.481188 -280.819583) (xy 403.458317 -280.86316) (xy 403.428752 -280.902504)
			(xy 403.393259 -280.936596) (xy 403.352756 -280.964552) (xy 403.308294 -280.98565) (xy 403.261023 -280.999342)
			(xy 403.212168 -281.005274) (xy 403.162993 -281.003293) (xy 403.114774 -280.993449) (xy 403.068758 -280.975997)
			(xy 403.026137 -280.95139) (xy 402.988016 -280.920265) (xy 402.955381 -280.883428) (xy 402.929078 -280.841832)
			(xy 402.909787 -280.796556) (xy 402.89801 -280.748772) (xy 402.89405 -280.699718) (xy 401.605242 -280.699718)
			(xy 401.604747 -280.724325) (xy 401.596852 -280.772902) (xy 401.581268 -280.819583) (xy 401.558397 -280.86316)
			(xy 401.528832 -280.902504) (xy 401.493339 -280.936596) (xy 401.452836 -280.964552) (xy 401.408374 -280.98565)
			(xy 401.361103 -280.999342) (xy 401.312248 -281.005274) (xy 401.263073 -281.003293) (xy 401.214854 -280.993449)
			(xy 401.168838 -280.975997) (xy 401.126217 -280.95139) (xy 401.088096 -280.920265) (xy 401.055461 -280.883428)
			(xy 401.029158 -280.841832) (xy 401.009867 -280.796556) (xy 400.99809 -280.748772) (xy 400.99413 -280.699718)
			(xy 399.705322 -280.699718) (xy 399.704827 -280.724325) (xy 399.696932 -280.772902) (xy 399.681348 -280.819583)
			(xy 399.658477 -280.86316) (xy 399.628912 -280.902504) (xy 399.593419 -280.936596) (xy 399.552916 -280.964552)
			(xy 399.508454 -280.98565) (xy 399.461183 -280.999342) (xy 399.412328 -281.005274) (xy 399.363153 -281.003293)
			(xy 399.314934 -280.993449) (xy 399.268918 -280.975997) (xy 399.226297 -280.95139) (xy 399.188176 -280.920265)
			(xy 399.155541 -280.883428) (xy 399.129238 -280.841832) (xy 399.109947 -280.796556) (xy 399.09817 -280.748772)
			(xy 399.09421 -280.699718) (xy 397.805148 -280.699718) (xy 397.804653 -280.724325) (xy 397.796758 -280.772902)
			(xy 397.781174 -280.819583) (xy 397.758303 -280.86316) (xy 397.728738 -280.902504) (xy 397.693245 -280.936596)
			(xy 397.652742 -280.964552) (xy 397.60828 -280.98565) (xy 397.561009 -280.999342) (xy 397.512154 -281.005274)
			(xy 397.462979 -281.003293) (xy 397.41476 -280.993449) (xy 397.368744 -280.975997) (xy 397.326123 -280.95139)
			(xy 397.288002 -280.920265) (xy 397.255367 -280.883428) (xy 397.229064 -280.841832) (xy 397.209773 -280.796556)
			(xy 397.197996 -280.748772) (xy 397.194036 -280.699718) (xy 395.905228 -280.699718) (xy 395.904733 -280.724325)
			(xy 395.896838 -280.772902) (xy 395.881254 -280.819583) (xy 395.858383 -280.86316) (xy 395.828818 -280.902504)
			(xy 395.793325 -280.936596) (xy 395.752822 -280.964552) (xy 395.70836 -280.98565) (xy 395.661089 -280.999342)
			(xy 395.612234 -281.005274) (xy 395.563059 -281.003293) (xy 395.51484 -280.993449) (xy 395.468824 -280.975997)
			(xy 395.426203 -280.95139) (xy 395.388082 -280.920265) (xy 395.355447 -280.883428) (xy 395.329144 -280.841832)
			(xy 395.309853 -280.796556) (xy 395.298076 -280.748772) (xy 395.294116 -280.699718) (xy 394.005308 -280.699718)
			(xy 394.004813 -280.724325) (xy 393.996918 -280.772902) (xy 393.981334 -280.819583) (xy 393.958463 -280.86316)
			(xy 393.928898 -280.902504) (xy 393.893405 -280.936596) (xy 393.852902 -280.964552) (xy 393.80844 -280.98565)
			(xy 393.761169 -280.999342) (xy 393.712314 -281.005274) (xy 393.663139 -281.003293) (xy 393.61492 -280.993449)
			(xy 393.568904 -280.975997) (xy 393.526283 -280.95139) (xy 393.488162 -280.920265) (xy 393.455527 -280.883428)
			(xy 393.429224 -280.841832) (xy 393.409933 -280.796556) (xy 393.398156 -280.748772) (xy 393.394196 -280.699718)
			(xy 391.668 -280.699718) (xy 391.668 -282.20543) (xy 391.668429 -282.215498) (xy 391.676151 -282.234094)
			(xy 391.682986 -282.241498) (xy 391.700766 -282.259278) (xy 391.708167 -282.266116) (xy 391.726766 -282.27383)
			(xy 391.736834 -282.274264) (xy 403.141942 -282.274264)
		)
		(stroke
			(width 0)
			(type solid)
		)
		(fill yes)
		(layer "In9.Cu")
		(net "GND")
	)
	(gr_poly
		(pts
			(xy 307.696362 -416.508438) (xy 307.69687 -416.508438) (xy 307.704031 -416.506736) (xy 307.717063 -416.49991)
			(xy 307.722524 -416.494976) (xy 307.728112 -416.489388) (xy 307.737256 -416.485578) (xy 307.741883 -416.483799)
			(xy 307.751604 -416.48187) (xy 307.75656 -416.481768) (xy 313.023504 -416.481768) (xy 313.032722 -416.48135)
			(xy 313.049945 -416.474772) (xy 313.063715 -416.462511) (xy 313.072237 -416.446162) (xy 313.073796 -416.437064)
			(xy 313.073796 -394.32992) (xy 313.073796 -394.27912) (xy 326.480424 -394.27912) (xy 326.485504 -394.280136)
			(xy 326.494211 -394.282363) (xy 326.509391 -394.291962) (xy 326.520314 -394.306219) (xy 326.52335 -394.31468)
			(xy 326.525636 -394.321792) (xy 326.525636 -416.434524) (xy 326.526762 -416.444028) (xy 326.535073 -416.461253)
			(xy 326.549085 -416.47427) (xy 326.566875 -416.481291) (xy 326.576436 -416.481768) (xy 391.922762 -416.481768)
			(xy 391.932786 -416.481354) (xy 391.95131 -416.47369) (xy 391.965487 -416.459515) (xy 391.973153 -416.440992)
			(xy 391.973562 -416.430968) (xy 391.973562 -413.58566) (xy 391.973404 -413.580426) (xy 391.971227 -413.570186)
			(xy 391.969244 -413.56534) (xy 381.03302 -413.56534) (xy 381.006997 -413.56481) (xy 380.955597 -413.556639)
			(xy 380.906103 -413.540541) (xy 380.85973 -413.516912) (xy 380.817616 -413.48633) (xy 380.798832 -413.468312)
			(xy 379.921262 -412.590742) (xy 379.913984 -412.584062) (xy 379.895817 -412.576354) (xy 379.885956 -412.575756)
			(xy 379.885702 -412.575756) (xy 379.854088 -412.574968) (xy 379.791459 -412.566205) (xy 379.730497 -412.549388)
			(xy 379.672234 -412.5248) (xy 379.617655 -412.492859) (xy 379.567683 -412.454103) (xy 379.523164 -412.409189)
			(xy 379.484851 -412.358877) (xy 379.453393 -412.304018) (xy 379.429321 -412.24554) (xy 379.413043 -412.184431)
			(xy 379.404834 -412.121728) (xy 379.404372 -412.090108) (xy 379.404869 -412.05831) (xy 379.413169 -411.995257)
			(xy 379.429629 -411.933827) (xy 379.453966 -411.875072) (xy 379.485765 -411.819996) (xy 379.52448 -411.769541)
			(xy 379.56945 -411.724572) (xy 379.619905 -411.685858) (xy 379.674982 -411.654061) (xy 379.733739 -411.629725)
			(xy 379.795169 -411.613267) (xy 379.858222 -411.604968) (xy 379.89002 -411.60446) (xy 379.921636 -411.604969)
			(xy 379.984334 -411.613179) (xy 380.045435 -411.629456) (xy 380.103907 -411.653527) (xy 380.15876 -411.684982)
			(xy 380.209067 -411.723291) (xy 380.253976 -411.767805) (xy 380.292728 -411.817772) (xy 380.324667 -411.872345)
			(xy 380.349253 -411.930602) (xy 380.366069 -411.991558) (xy 380.374832 -412.05418) (xy 380.375668 -412.08579)
			(xy 380.375668 -412.086044) (xy 380.375923 -412.090108) (xy 383.803914 -412.090108) (xy 383.807905 -412.027941)
			(xy 383.819814 -411.966794) (xy 383.839443 -411.907673) (xy 383.866472 -411.851547) (xy 383.900456 -411.799338)
			(xy 383.940838 -411.751903) (xy 383.986954 -411.710022) (xy 384.038046 -411.674382) (xy 384.093277 -411.645568)
			(xy 384.151739 -411.624054) (xy 384.212473 -411.610192) (xy 384.27448 -411.60421) (xy 384.336743 -411.606206)
			(xy 384.39824 -411.616149) (xy 384.457961 -411.633873) (xy 384.514924 -411.65909) (xy 384.568195 -411.691383)
			(xy 384.6169 -411.730223) (xy 384.660237 -411.774973) (xy 384.697497 -411.824897) (xy 384.728066 -411.879176)
			(xy 384.751444 -411.936919) (xy 384.767245 -411.997177) (xy 384.775211 -412.05896) (xy 384.77571 -412.090108)
			(xy 384.775211 -412.121256) (xy 384.767245 -412.183039) (xy 384.751444 -412.243297) (xy 384.728066 -412.30104)
			(xy 384.697497 -412.355319) (xy 384.660237 -412.405243) (xy 384.6169 -412.449993) (xy 384.568195 -412.488833)
			(xy 384.514924 -412.521126) (xy 384.457961 -412.546343) (xy 384.39824 -412.564067) (xy 384.336743 -412.57401)
			(xy 384.27448 -412.576006) (xy 384.212473 -412.570024) (xy 384.151739 -412.556162) (xy 384.093277 -412.534648)
			(xy 384.038046 -412.505834) (xy 383.986954 -412.470194) (xy 383.940838 -412.428313) (xy 383.900456 -412.380878)
			(xy 383.866472 -412.328669) (xy 383.839443 -412.272543) (xy 383.819814 -412.213422) (xy 383.807905 -412.152275)
			(xy 383.803914 -412.090108) (xy 380.375923 -412.090108) (xy 380.376287 -412.095897) (xy 380.384011 -412.114045)
			(xy 380.390654 -412.12135) (xy 381.160528 -412.891224) (xy 381.16764 -412.891732) (xy 388.913878 -412.891732)
			(xy 388.91946 -412.891587) (xy 388.930356 -412.889152) (xy 388.935468 -412.886906) (xy 388.94639 -412.86049)
			(xy 388.949938 -412.851045) (xy 388.950045 -412.830885) (xy 388.942331 -412.812259) (xy 388.935468 -412.804864)
			(xy 388.721092 -412.590742) (xy 388.713816 -412.584058) (xy 388.695649 -412.576338) (xy 388.685786 -412.575756)
			(xy 388.685532 -412.575756) (xy 388.653917 -412.57497) (xy 388.591285 -412.56621) (xy 388.53032 -412.549396)
			(xy 388.472053 -412.52481) (xy 388.41747 -412.492869) (xy 388.367495 -412.454114) (xy 388.322973 -412.409199)
			(xy 388.284658 -412.358886) (xy 388.253197 -412.304026) (xy 388.229123 -412.245545) (xy 388.212844 -412.184435)
			(xy 388.204634 -412.121729) (xy 388.204202 -412.090108) (xy 388.204699 -412.05831) (xy 388.212999 -411.995259)
			(xy 388.229459 -411.933831) (xy 388.253797 -411.875077) (xy 388.285596 -411.820003) (xy 388.324312 -411.769551)
			(xy 388.369282 -411.724584) (xy 388.419738 -411.685872) (xy 388.474815 -411.654078) (xy 388.533571 -411.629746)
			(xy 388.595 -411.613291) (xy 388.658052 -411.604996) (xy 388.68985 -411.60446) (xy 388.721465 -411.604971)
			(xy 388.784159 -411.613184) (xy 388.845258 -411.629464) (xy 388.903726 -411.653536) (xy 388.958576 -411.684993)
			(xy 389.008879 -411.723302) (xy 389.053785 -411.767816) (xy 389.092534 -411.817781) (xy 389.124471 -411.872353)
			(xy 389.149055 -411.930608) (xy 389.16587 -411.991562) (xy 389.174632 -412.054181) (xy 389.175498 -412.08579)
			(xy 389.175498 -412.086044) (xy 389.176115 -412.095898) (xy 389.183831 -412.114053) (xy 389.190484 -412.12135)
			(xy 389.597646 -412.528766) (xy 389.605045 -412.535609) (xy 389.623644 -412.543332) (xy 389.633714 -412.543752)
			(xy 391.953242 -412.543752) (xy 391.962355 -412.536153) (xy 391.972964 -412.514961) (xy 391.973562 -412.503112)
			(xy 391.973562 -409.533598) (xy 391.973114 -409.523571) (xy 391.965523 -409.505012) (xy 391.95883 -409.49753)
			(xy 391.77341 -409.31211) (xy 391.752542 -409.29046) (xy 391.717193 -409.241818) (xy 391.689893 -409.188243)
			(xy 391.671316 -409.131056) (xy 391.661919 -409.071665) (xy 391.661396 -409.0416) (xy 391.661396 -394.924534)
			(xy 391.661939 -394.895033) (xy 391.670992 -394.83673) (xy 391.67943 -394.808456) (xy 391.681716 -394.800836)
			(xy 391.681716 -394.187426) (xy 391.682153 -394.177362) (xy 391.689888 -394.158779) (xy 391.696702 -394.151358)
			(xy 393.003786 -392.844274) (xy 393.011186 -392.837433) (xy 393.029785 -392.829718) (xy 393.039854 -392.829288)
			(xy 394.27023 -392.829288) (xy 394.279628 -392.828272) (xy 394.280136 -392.828272) (xy 394.287291 -392.82656)
			(xy 394.300306 -392.819715) (xy 394.30579 -392.81481) (xy 402.872194 -384.248406) (xy 402.87717 -384.242974)
			(xy 402.884005 -384.229932) (xy 402.885656 -384.222752) (xy 402.885656 -384.222244) (xy 402.886672 -384.212846)
			(xy 402.886672 -375.64695) (xy 402.886239 -375.636884) (xy 402.878509 -375.618296) (xy 402.871686 -375.610882)
			(xy 395.698218 -368.437414) (xy 395.690818 -368.430726) (xy 395.672403 -368.423115) (xy 395.652477 -368.423099)
			(xy 395.6431 -368.426492) (xy 395.628622 -368.432334) (xy 395.611604 -368.457988) (xy 395.611604 -368.593624)
			(xy 395.611719 -368.598721) (xy 395.613769 -368.608705) (xy 395.615668 -368.613436) (xy 395.626844 -368.640106)
			(xy 395.633956 -368.647218) (xy 395.656001 -368.670056) (xy 395.694582 -368.720461) (xy 395.726268 -368.775463)
			(xy 395.750516 -368.834124) (xy 395.766914 -368.895445) (xy 395.775183 -368.95838) (xy 395.775688 -368.990118)
			(xy 395.775167 -369.021915) (xy 395.766865 -369.084965) (xy 395.750404 -369.146392) (xy 395.726067 -369.205146)
			(xy 395.69427 -369.26022) (xy 395.655557 -369.310673) (xy 395.61059 -369.355642) (xy 395.560138 -369.394358)
			(xy 395.505065 -369.426157) (xy 395.446313 -369.450497) (xy 395.384887 -369.46696) (xy 395.321837 -369.475266)
			(xy 395.29004 -369.475766) (xy 395.258079 -369.475261) (xy 395.194708 -369.466882) (xy 395.132984 -369.450264)
			(xy 395.073972 -369.425694) (xy 395.018693 -369.393596) (xy 394.968102 -369.354525) (xy 394.923072 -369.309156)
			(xy 394.884381 -369.258273) (xy 394.852699 -369.202755) (xy 394.828572 -369.143561) (xy 394.812417 -369.081713)
			(xy 394.807948 -369.050062) (xy 394.806932 -369.04168) (xy 394.799566 -369.02644) (xy 392.146028 -366.372648)
			(xy 392.138628 -366.365808) (xy 392.120029 -366.358092) (xy 392.10996 -366.357662) (xy 391.516616 -366.357662)
			(xy 391.506603 -366.358147) (xy 391.4881 -366.365802) (xy 391.473932 -366.379954) (xy 391.466257 -366.39845)
			(xy 391.465816 -366.408462) (xy 391.465816 -368.882168) (xy 391.466578 -368.886486) (xy 391.470953 -368.912171)
			(xy 391.47566 -368.964065) (xy 391.475976 -368.990118) (xy 391.47544 -369.02553) (xy 391.466901 -369.095838)
			(xy 391.44995 -369.164603) (xy 391.424834 -369.230824) (xy 391.391919 -369.293535) (xy 391.351685 -369.351822)
			(xy 391.304719 -369.404833) (xy 391.251706 -369.451798) (xy 391.193418 -369.492029) (xy 391.130706 -369.524942)
			(xy 391.064484 -369.550056) (xy 390.995718 -369.567005) (xy 390.92541 -369.575542) (xy 390.889998 -369.576096)
			(xy 390.85712 -369.575619) (xy 390.791779 -369.568231) (xy 390.727675 -369.553579) (xy 390.665612 -369.53185)
			(xy 390.606369 -369.503315) (xy 390.550689 -369.468332) (xy 390.499272 -369.427341) (xy 390.475724 -369.404392)
			(xy 388.644384 -367.573052) (xy 388.637272 -367.572544) (xy 387.11632 -367.572544) (xy 387.106299 -367.572961)
			(xy 387.087783 -367.580629) (xy 387.073615 -367.594803) (xy 387.065956 -367.613323) (xy 387.06552 -367.623344)
			(xy 387.06552 -368.880644) (xy 387.066282 -368.885216) (xy 387.070661 -368.911029) (xy 387.075364 -368.963177)
			(xy 387.07568 -368.989356) (xy 387.07568 -368.990118) (xy 387.075145 -369.02552) (xy 387.066611 -369.095809)
			(xy 387.049669 -369.164557) (xy 387.024566 -369.230763) (xy 386.991669 -369.293461) (xy 386.951456 -369.351738)
			(xy 386.904513 -369.404745) (xy 386.851526 -369.451709) (xy 386.793265 -369.491946) (xy 386.73058 -369.524869)
			(xy 386.664384 -369.549998) (xy 386.595643 -369.566968) (xy 386.525358 -369.575531) (xy 386.489956 -369.576096)
			(xy 386.457079 -369.575617) (xy 386.39174 -369.568224) (xy 386.327639 -369.553569) (xy 386.265579 -369.531836)
			(xy 386.206339 -369.503298) (xy 386.150663 -369.468313) (xy 386.099249 -369.427321) (xy 386.075682 -369.404392)
			(xy 385.127246 -368.455956) (xy 385.11988 -368.455448) (xy 382.462532 -368.455448) (xy 382.45251 -368.455863)
			(xy 382.43399 -368.463529) (xy 382.41982 -368.477704) (xy 382.41216 -368.496226) (xy 382.411732 -368.506248)
			(xy 382.411732 -368.594132) (xy 382.411871 -368.599164) (xy 382.413918 -368.609019) (xy 382.415796 -368.61369)
			(xy 382.427226 -368.64036) (xy 382.434084 -368.647218) (xy 382.456078 -368.67006) (xy 382.494567 -368.720452)
			(xy 382.52618 -368.775421) (xy 382.550379 -368.834032) (xy 382.566754 -368.895291) (xy 382.575028 -368.958159)
			(xy 382.575562 -368.989864) (xy 382.575562 -368.990118) (xy 382.575041 -369.021915) (xy 382.566738 -369.084963)
			(xy 382.550278 -369.146389) (xy 382.52594 -369.205141) (xy 382.494143 -369.260214) (xy 382.45543 -369.310665)
			(xy 382.410462 -369.355632) (xy 382.36001 -369.394345) (xy 382.304937 -369.426142) (xy 382.246185 -369.450479)
			(xy 382.184759 -369.466939) (xy 382.121711 -369.475241) (xy 382.089914 -369.475766) (xy 382.073866 -369.475674)
			(xy 382.041837 -369.473639) (xy 382.025906 -369.471702) (xy 381.998767 -369.467679) (xy 381.945555 -369.454307)
			(xy 381.919734 -369.445032) (xy 381.887604 -369.432431) (xy 381.826982 -369.399444) (xy 381.771647 -369.3582)
			(xy 381.74676 -369.334288) (xy 381.731012 -369.32362) (xy 381.713486 -369.316) (xy 381.708746 -369.314131)
			(xy 381.698767 -369.312088) (xy 381.693674 -369.311936) (xy 380.936754 -369.311936) (xy 380.911465 -369.311437)
			(xy 380.86151 -369.303523) (xy 380.813407 -369.287897) (xy 380.768337 -369.264943) (xy 380.727411 -369.235225)
			(xy 380.70917 -369.217702) (xy 379.067314 -367.575592) (xy 379.062027 -367.570722) (xy 379.049394 -367.563878)
			(xy 379.042422 -367.56213) (xy 379.0315 -367.56086) (xy 378.518166 -367.56086) (xy 378.512156 -367.561025)
			(xy 378.500471 -367.563844) (xy 378.495052 -367.566448) (xy 378.49158 -367.568291) (xy 378.485207 -367.57289)
			(xy 378.482352 -367.575592) (xy 378.026168 -368.031776) (xy 378.02346 -368.034625) (xy 378.018861 -368.041001)
			(xy 378.017024 -368.044476) (xy 378.014443 -368.049903) (xy 378.011626 -368.061583) (xy 378.011436 -368.06759)
			(xy 378.011436 -368.593624) (xy 378.011551 -368.59872) (xy 378.013603 -368.608704) (xy 378.0155 -368.613436)
			(xy 378.026676 -368.640106) (xy 378.033788 -368.647218) (xy 378.055831 -368.670057) (xy 378.094411 -368.720462)
			(xy 378.126094 -368.775465) (xy 378.15034 -368.834126) (xy 378.166738 -368.895446) (xy 378.175005 -368.958381)
			(xy 378.17552 -368.990118) (xy 378.175 -369.021915) (xy 378.166699 -369.084965) (xy 378.15024 -369.146392)
			(xy 378.125904 -369.205145) (xy 378.094107 -369.260219) (xy 378.055393 -369.310671) (xy 378.010425 -369.355639)
			(xy 377.959973 -369.394353) (xy 377.904899 -369.42615) (xy 377.846146 -369.450486) (xy 377.784719 -369.466945)
			(xy 377.721669 -369.475246) (xy 377.658075 -369.475246) (xy 377.595025 -369.466945) (xy 377.533598 -369.450486)
			(xy 377.474845 -369.42615) (xy 377.419771 -369.394353) (xy 377.369319 -369.355639) (xy 377.324351 -369.310671)
			(xy 377.285637 -369.260219) (xy 377.25384 -369.205145) (xy 377.229504 -369.146392) (xy 377.213045 -369.084965)
			(xy 377.204744 -369.021915) (xy 377.204224 -368.990118) (xy 377.204224 -368.981482) (xy 377.204478 -368.971068)
			(xy 377.200668 -368.96167) (xy 377.19866 -368.956948) (xy 377.193024 -368.948375) (xy 377.189492 -368.944652)
			(xy 371.731032 -363.486192) (xy 371.728181 -363.483486) (xy 371.721802 -363.478893) (xy 371.718332 -363.477048)
			(xy 371.712905 -363.474465) (xy 371.701225 -363.471645) (xy 371.695218 -363.47146) (xy 366.171734 -363.47146)
			(xy 366.146533 -363.470928) (xy 366.096757 -363.462988) (xy 366.048827 -363.44739) (xy 366.003911 -363.424517)
			(xy 365.963107 -363.394925) (xy 365.944912 -363.37748) (xy 363.565948 -360.998516) (xy 363.54849 -360.98033)
			(xy 363.518881 -360.939533) (xy 363.496 -360.894616) (xy 363.480406 -360.84668) (xy 363.472481 -360.796898)
			(xy 363.471968 -360.771694) (xy 363.471968 -359.534206) (xy 363.47019 -359.520998) (xy 363.464856 -359.502202)
			(xy 363.461808 -359.496868) (xy 363.449745 -359.474794) (xy 363.430885 -359.428159) (xy 363.424216 -359.403904)
			(xy 363.423708 -359.401618) (xy 363.421795 -359.396036) (xy 363.415765 -359.385895) (xy 363.41177 -359.381552)
			(xy 363.294168 -359.264204) (xy 363.276709 -359.246019) (xy 363.247101 -359.205222) (xy 363.22422 -359.160305)
			(xy 363.208626 -359.112368) (xy 363.200703 -359.062586) (xy 363.200188 -359.037382) (xy 363.200188 -346.460318)
			(xy 363.200188 -346.459556) (xy 363.200188 -342.163654) (xy 363.200021 -342.157644) (xy 363.197198 -342.145962)
			(xy 363.1946 -342.14054) (xy 363.192764 -342.137063) (xy 363.188175 -342.130679) (xy 363.185456 -342.12784)
			(xy 361.834684 -340.777068) (xy 361.83443 -340.777068) (xy 361.827021 -340.770382) (xy 361.808585 -340.762794)
			(xy 361.798616 -340.762336) (xy 358.023668 -340.762336) (xy 357.992028 -340.761584) (xy 357.929976 -340.749169)
			(xy 357.900478 -340.737698) (xy 357.576374 -340.603332) (xy 357.572539 -340.602174) (xy 357.56463 -340.600903)
			(xy 357.560626 -340.600792) (xy 357.559864 -340.600792) (xy 350.140778 -340.588854) (xy 350.131894 -340.590018)
			(xy 350.115651 -340.597551) (xy 350.109028 -340.603586) (xy 350.106742 -340.606126) (xy 350.102984 -340.610471)
			(xy 350.097344 -340.620475) (xy 350.095566 -340.625938) (xy 350.093026 -340.634828) (xy 350.121982 -340.871556)
			(xy 350.156272 -341.147908) (xy 350.159574 -341.160862) (xy 350.187768 -341.229442) (xy 350.264222 -341.416132)
			(xy 350.41078 -341.774272) (xy 350.426112 -341.812794) (xy 350.451016 -341.891884) (xy 350.469198 -341.972784)
			(xy 350.475296 -342.013794) (xy 350.476566 -342.022938) (xy 350.485202 -342.039448) (xy 350.492314 -342.04529)
			(xy 350.499434 -342.050975) (xy 350.516485 -342.057361) (xy 350.525588 -342.057736) (xy 350.966786 -342.057736)
			(xy 350.994058 -342.058199) (xy 351.048046 -342.065959) (xy 351.100381 -342.081324) (xy 351.149996 -342.103981)
			(xy 351.195882 -342.133469) (xy 351.237104 -342.169186) (xy 351.272823 -342.210407) (xy 351.302312 -342.256291)
			(xy 351.324971 -342.305906) (xy 351.340338 -342.35824) (xy 351.3481 -342.412228) (xy 351.3481 -342.466772)
			(xy 351.340338 -342.52076) (xy 351.324971 -342.573094) (xy 351.302312 -342.622709) (xy 351.272823 -342.668593)
			(xy 351.237104 -342.709814) (xy 351.195882 -342.745531) (xy 351.149996 -342.775019) (xy 351.100381 -342.797676)
			(xy 351.048046 -342.813041) (xy 350.994058 -342.820801) (xy 350.966786 -342.82126) (xy 350.53524 -342.82126)
			(xy 350.525224 -342.821741) (xy 350.506712 -342.829392) (xy 350.492536 -342.843545) (xy 350.484856 -342.862045)
			(xy 350.48444 -342.87206) (xy 350.48444 -343.808304) (xy 350.484694 -343.812876) (xy 350.484948 -343.813892)
			(xy 350.484948 -343.8144) (xy 350.49079 -343.860628) (xy 350.493584 -343.872312) (xy 350.94164 -345.051126)
			(xy 350.945538 -345.060132) (xy 350.958853 -345.074523) (xy 350.976582 -345.082895) (xy 350.986344 -345.083892)
			(xy 350.986598 -345.083892) (xy 351.015538 -345.085936) (xy 351.072352 -345.097677) (xy 351.126734 -345.11788)
			(xy 351.177434 -345.14608) (xy 351.223282 -345.181626) (xy 351.263224 -345.223701) (xy 351.296339 -345.271336)
			(xy 351.321864 -345.323432) (xy 351.339213 -345.378792) (xy 351.347985 -345.436139) (xy 351.348548 -345.465146)
			(xy 351.348104 -345.490884) (xy 351.341146 -345.541889) (xy 351.327401 -345.591498) (xy 351.30712 -345.638812)
			(xy 351.280669 -345.682974) (xy 351.248528 -345.723184) (xy 351.230184 -345.741244) (xy 351.229168 -345.74226)
			(xy 351.22358 -345.747848) (xy 351.217484 -345.776804) (xy 352.127566 -348.171262) (xy 352.131653 -348.180699)
			(xy 352.14589 -348.195515) (xy 352.164791 -348.203574) (xy 352.175064 -348.204028) (xy 352.312986 -348.204028)
			(xy 352.340258 -348.204491) (xy 352.394247 -348.212251) (xy 352.446582 -348.227616) (xy 352.496197 -348.250273)
			(xy 352.542083 -348.27976) (xy 352.583306 -348.315477) (xy 352.619026 -348.356697) (xy 352.648516 -348.402582)
			(xy 352.671176 -348.452196) (xy 352.686544 -348.50453) (xy 352.694308 -348.558518) (xy 352.694748 -348.58579)
			(xy 352.694278 -348.613258) (xy 352.686415 -348.667628) (xy 352.670836 -348.720308) (xy 352.647863 -348.770209)
			(xy 352.61797 -348.816299) (xy 352.581777 -348.857626) (xy 352.540031 -348.893336) (xy 352.493595 -348.922688)
			(xy 352.468688 -348.934278) (xy 352.433382 -348.950026) (xy 352.426016 -348.956884) (xy 355.652578 -357.446072)
			(xy 355.652578 -357.44658) (xy 356.790498 -360.363516) (xy 357.447596 -362.048044) (xy 357.451254 -362.056364)
			(xy 357.463349 -362.069914) (xy 357.471218 -362.07446) (xy 357.478838 -362.078524) (xy 357.496872 -362.081064)
			(xy 357.505762 -362.079032) (xy 357.525955 -362.074886) (xy 357.566938 -362.070435) (xy 357.58755 -362.070142)
			(xy 357.614804 -362.070602) (xy 357.668758 -362.078353) (xy 357.721059 -362.093706) (xy 357.770642 -362.116346)
			(xy 357.816498 -362.145813) (xy 357.857692 -362.181508) (xy 357.893387 -362.222702) (xy 357.922854 -362.268558)
			(xy 357.945494 -362.318141) (xy 357.960847 -362.370442) (xy 357.968598 -362.424396) (xy 357.969058 -362.45165)
			(xy 357.968537 -362.48035) (xy 357.959933 -362.537103) (xy 357.942928 -362.591927) (xy 357.917904 -362.643586)
			(xy 357.885427 -362.690915) (xy 357.846228 -362.732847) (xy 357.801191 -362.768436) (xy 357.776526 -362.78312)
			(xy 357.776272 -362.78312) (xy 357.77084 -362.786522) (xy 357.76171 -362.795513) (xy 357.758238 -362.8009)
			(xy 357.738172 -362.834174) (xy 357.740204 -362.848144) (xy 358.084374 -363.84484) (xy 358.084882 -363.846364)
			(xy 359.78084 -368.30889) (xy 359.793892 -368.344134) (xy 359.815286 -368.416187) (xy 359.831195 -368.489647)
			(xy 359.83672 -368.526822) (xy 359.881932 -368.854482) (xy 359.884472 -368.864388) (xy 359.988866 -369.161568)
			(xy 360.002185 -369.200679) (xy 360.02303 -369.280634) (xy 360.037128 -369.362051) (xy 360.044378 -369.44436)
			(xy 360.045 -369.485672) (xy 360.045 -369.48999) (xy 360.044746 -369.51031) (xy 360.035348 -369.968018)
			(xy 360.035856 -369.971066) (xy 360.038697 -369.998409) (xy 360.041744 -370.053304) (xy 360.041952 -370.080794)
			(xy 360.041698 -370.101114) (xy 360.033077 -370.522709) (xy 375.004922 -370.522709) (xy 375.004924 -370.457271)
			(xy 375.013709 -370.392425) (xy 375.03112 -370.329346) (xy 375.05684 -370.269175) (xy 375.073164 -370.240814)
			(xy 375.076471 -370.234785) (xy 375.080082 -370.221525) (xy 375.080276 -370.214652) (xy 375.080276 -369.928902)
			(xy 375.080666 -369.918726) (xy 375.088458 -369.899924) (xy 375.102854 -369.885538) (xy 375.121661 -369.877759)
			(xy 375.131838 -369.87734) (xy 375.848118 -369.87734) (xy 375.858277 -369.877818) (xy 375.877047 -369.885599)
			(xy 375.891412 -369.89997) (xy 375.899185 -369.918743) (xy 375.89968 -369.928902) (xy 375.89968 -370.214652)
			(xy 375.899893 -370.221524) (xy 375.903487 -370.234786) (xy 375.906792 -370.240814) (xy 375.923103 -370.269181)
			(xy 375.94882 -370.329351) (xy 375.966228 -370.392429) (xy 375.975012 -370.457272) (xy 375.975014 -370.522707)
			(xy 375.966232 -370.587551) (xy 375.948827 -370.650629) (xy 375.923112 -370.7108) (xy 375.906792 -370.739162)
			(xy 375.90349 -370.745193) (xy 375.899877 -370.758452) (xy 375.89968 -370.765324) (xy 375.89968 -371.514878)
			(xy 375.899883 -371.52175) (xy 375.903484 -371.535013) (xy 375.906792 -371.54104) (xy 375.923125 -371.569395)
			(xy 375.94884 -371.629568) (xy 375.966246 -371.692648) (xy 375.975027 -371.757493) (xy 375.975026 -371.822931)
			(xy 375.966241 -371.887776) (xy 375.948832 -371.950855) (xy 375.923114 -372.011026) (xy 375.906792 -372.039388)
			(xy 375.903481 -372.045414) (xy 375.899873 -372.058677) (xy 375.89968 -372.06555) (xy 375.89968 -372.351554)
			(xy 375.899199 -372.36172) (xy 375.891432 -372.380511) (xy 375.877064 -372.394896) (xy 375.858284 -372.402686)
			(xy 375.848118 -372.403116) (xy 375.131838 -372.403116) (xy 375.121663 -372.402704) (xy 375.102861 -372.394923)
			(xy 375.088473 -372.380533) (xy 375.080695 -372.361729) (xy 375.080276 -372.351554) (xy 375.080276 -372.06555)
			(xy 375.080068 -372.058678) (xy 375.076471 -372.045415) (xy 375.073164 -372.039388) (xy 375.056853 -372.01102)
			(xy 375.031133 -371.950851) (xy 375.013722 -371.887774) (xy 375.004937 -371.82293) (xy 375.004935 -371.757494)
			(xy 375.013718 -371.69265) (xy 375.031125 -371.629572) (xy 375.056842 -371.569401) (xy 375.073164 -371.54104)
			(xy 375.076462 -371.535007) (xy 375.080078 -371.52175) (xy 375.080276 -371.514878) (xy 375.080276 -370.765324)
			(xy 375.080078 -370.758451) (xy 375.076474 -370.745188) (xy 375.073164 -370.739162) (xy 375.056831 -370.710807)
			(xy 375.031113 -370.650634) (xy 375.013705 -370.587554) (xy 375.004922 -370.522709) (xy 360.033077 -370.522709)
			(xy 359.984666 -372.890034) (xy 377.204224 -372.890034) (xy 377.204779 -372.857304) (xy 377.213638 -372.792445)
			(xy 377.231131 -372.729365) (xy 377.256942 -372.669208) (xy 377.273312 -372.64086) (xy 377.276642 -372.634843)
			(xy 377.280238 -372.621573) (xy 377.280424 -372.614698) (xy 377.280424 -371.865398) (xy 377.28023 -371.858525)
			(xy 377.276623 -371.845262) (xy 377.273312 -371.839236) (xy 377.256962 -371.810878) (xy 377.231156 -371.750722)
			(xy 377.213662 -371.687645) (xy 377.204797 -371.62279) (xy 377.204224 -371.590062) (xy 377.204792 -371.557333)
			(xy 377.213647 -371.492474) (xy 377.231136 -371.429394) (xy 377.256943 -371.369236) (xy 377.273312 -371.340888)
			(xy 377.276632 -371.334866) (xy 377.280234 -371.3216) (xy 377.280424 -371.314726) (xy 377.280424 -371.028722)
			(xy 377.280944 -371.018599) (xy 377.288662 -370.999881) (xy 377.302938 -370.985524) (xy 377.321612 -370.977702)
			(xy 377.331732 -370.97716) (xy 378.048012 -370.97716) (xy 378.058162 -370.977611) (xy 378.076907 -370.985403)
			(xy 378.091229 -370.99979) (xy 378.098935 -371.01857) (xy 378.09932 -371.028722) (xy 378.09932 -371.314726)
			(xy 378.099499 -371.3216) (xy 378.103116 -371.334863) (xy 378.106432 -371.340888) (xy 378.122786 -371.369244)
			(xy 378.148592 -371.4294) (xy 378.166086 -371.492478) (xy 378.174949 -371.557333) (xy 378.17552 -371.590062)
			(xy 378.174957 -371.622792) (xy 378.1661 -371.68765) (xy 378.148609 -371.75073) (xy 378.13167 -371.790214)
			(xy 379.404372 -371.790214) (xy 379.404925 -371.757484) (xy 379.413785 -371.692625) (xy 379.431279 -371.629545)
			(xy 379.45709 -371.569388) (xy 379.47346 -371.54104) (xy 379.476757 -371.535007) (xy 379.480374 -371.52175)
			(xy 379.480572 -371.514878) (xy 379.480572 -370.765324) (xy 379.480374 -370.758451) (xy 379.47677 -370.745188)
			(xy 379.47346 -370.739162) (xy 379.457085 -370.710818) (xy 379.431284 -370.650657) (xy 379.413797 -370.587576)
			(xy 379.40494 -370.522718) (xy 379.404372 -370.489988) (xy 379.404959 -370.457259) (xy 379.413809 -370.392402)
			(xy 379.431293 -370.329322) (xy 379.457095 -370.269163) (xy 379.47346 -370.240814) (xy 379.476766 -370.234785)
			(xy 379.480378 -370.221525) (xy 379.480572 -370.214652) (xy 379.480572 -369.928902) (xy 379.481029 -369.918772)
			(xy 379.488762 -369.900044) (xy 379.503058 -369.885687) (xy 379.521752 -369.877873) (xy 379.53188 -369.87734)
			(xy 380.24816 -369.87734) (xy 380.258316 -369.877755) (xy 380.277076 -369.885545) (xy 380.291402 -369.899945)
			(xy 380.299096 -369.918743) (xy 380.299468 -369.928902) (xy 380.299468 -370.214652) (xy 380.299682 -370.221524)
			(xy 380.303276 -370.234786) (xy 380.30658 -370.240814) (xy 380.322949 -370.269161) (xy 380.348751 -370.329321)
			(xy 380.366239 -370.392401) (xy 380.375098 -370.457259) (xy 380.375668 -370.489988) (xy 380.37511 -370.522709)
			(xy 383.805008 -370.522709) (xy 383.80501 -370.457271) (xy 383.813795 -370.392426) (xy 383.831205 -370.329346)
			(xy 383.856925 -370.269175) (xy 383.873248 -370.240814) (xy 383.876554 -370.234785) (xy 383.880166 -370.221525)
			(xy 383.88036 -370.214652) (xy 383.88036 -369.928902) (xy 383.880766 -369.918728) (xy 383.888554 -369.899929)
			(xy 383.902946 -369.885543) (xy 383.921748 -369.877762) (xy 383.931922 -369.87734) (xy 384.648202 -369.87734)
			(xy 384.65836 -369.877832) (xy 384.67713 -369.885607) (xy 384.691495 -369.899974) (xy 384.699269 -369.918744)
			(xy 384.699764 -369.928902) (xy 384.699764 -370.214652) (xy 384.699979 -370.221524) (xy 384.703572 -370.234786)
			(xy 384.706876 -370.240814) (xy 384.723188 -370.269181) (xy 384.748905 -370.329351) (xy 384.766314 -370.392428)
			(xy 384.775099 -370.457272) (xy 384.7751 -370.522708) (xy 388.204798 -370.522708) (xy 388.204799 -370.457271)
			(xy 388.213584 -370.392426) (xy 388.230994 -370.329347) (xy 388.256713 -370.269175) (xy 388.273036 -370.240814)
			(xy 388.276341 -370.234784) (xy 388.279954 -370.221525) (xy 388.280148 -370.214652) (xy 388.280148 -369.928902)
			(xy 388.280566 -369.918729) (xy 388.288352 -369.899933) (xy 388.302739 -369.885547) (xy 388.321537 -369.877764)
			(xy 388.33171 -369.87734) (xy 389.04799 -369.87734) (xy 389.058161 -369.877772) (xy 389.076956 -369.885554)
			(xy 389.091341 -369.899937) (xy 389.099126 -369.918731) (xy 389.099552 -369.928902) (xy 389.099552 -370.214652)
			(xy 389.099756 -370.221524) (xy 389.103355 -370.234788) (xy 389.106664 -370.240814) (xy 389.122976 -370.269181)
			(xy 389.148694 -370.329351) (xy 389.166103 -370.392428) (xy 389.174888 -370.457272) (xy 389.174889 -370.489988)
			(xy 392.603744 -370.489988) (xy 392.607735 -370.427821) (xy 392.619644 -370.366674) (xy 392.639273 -370.307553)
			(xy 392.666302 -370.251427) (xy 392.700286 -370.199218) (xy 392.740668 -370.151783) (xy 392.786784 -370.109902)
			(xy 392.837876 -370.074262) (xy 392.893107 -370.045448) (xy 392.951569 -370.023934) (xy 393.012303 -370.010072)
			(xy 393.07431 -370.00409) (xy 393.136573 -370.006086) (xy 393.19807 -370.016029) (xy 393.257791 -370.033753)
			(xy 393.314754 -370.05897) (xy 393.368025 -370.091263) (xy 393.41673 -370.130103) (xy 393.460067 -370.174853)
			(xy 393.497327 -370.224777) (xy 393.527896 -370.279056) (xy 393.551274 -370.336799) (xy 393.567075 -370.397057)
			(xy 393.575041 -370.45884) (xy 393.57554 -370.489988) (xy 393.575041 -370.521136) (xy 393.567075 -370.582919)
			(xy 393.551274 -370.643177) (xy 393.527896 -370.70092) (xy 393.497327 -370.755199) (xy 393.460067 -370.805123)
			(xy 393.41673 -370.849873) (xy 393.368025 -370.888713) (xy 393.314754 -370.921006) (xy 393.257791 -370.946223)
			(xy 393.19807 -370.963947) (xy 393.136573 -370.97389) (xy 393.07431 -370.975886) (xy 393.012303 -370.969904)
			(xy 392.951569 -370.956042) (xy 392.893107 -370.934528) (xy 392.837876 -370.905714) (xy 392.786784 -370.870074)
			(xy 392.740668 -370.828193) (xy 392.700286 -370.780758) (xy 392.666302 -370.728549) (xy 392.639273 -370.672423)
			(xy 392.619644 -370.613302) (xy 392.607735 -370.552155) (xy 392.603744 -370.489988) (xy 389.174889 -370.489988)
			(xy 389.17489 -370.522708) (xy 389.166108 -370.587552) (xy 389.148701 -370.65063) (xy 389.122985 -370.710801)
			(xy 389.106664 -370.739162) (xy 389.103368 -370.745196) (xy 389.09975 -370.758452) (xy 389.099552 -370.765324)
			(xy 389.099552 -371.514878) (xy 389.099746 -371.521751) (xy 389.103352 -371.535014) (xy 389.106664 -371.54104)
			(xy 389.122998 -371.569395) (xy 389.145816 -371.622787) (xy 390.404925 -371.622787) (xy 390.404929 -371.557347)
			(xy 390.413718 -371.4925) (xy 390.431133 -371.42942) (xy 390.456858 -371.369249) (xy 390.473184 -371.340888)
			(xy 390.476502 -371.334865) (xy 390.480106 -371.3216) (xy 390.480296 -371.314726) (xy 390.480296 -371.028722)
			(xy 390.48085 -371.018571) (xy 390.48861 -370.99981) (xy 390.502956 -370.985446) (xy 390.521707 -370.977663)
			(xy 390.531858 -370.97716) (xy 391.248138 -370.97716) (xy 391.258301 -370.977603) (xy 391.277075 -370.985394)
			(xy 391.29144 -370.999775) (xy 391.299209 -371.018558) (xy 391.2997 -371.028722) (xy 391.2997 -371.314726)
			(xy 391.299882 -371.3216) (xy 391.303497 -371.334863) (xy 391.306812 -371.340888) (xy 391.3231 -371.369268)
			(xy 391.348818 -371.429435) (xy 391.366228 -371.49251) (xy 391.375015 -371.557351) (xy 391.375019 -371.622784)
			(xy 391.366241 -371.687626) (xy 391.34884 -371.750703) (xy 391.331958 -371.790214) (xy 392.603744 -371.790214)
			(xy 392.607735 -371.728047) (xy 392.619644 -371.6669) (xy 392.639273 -371.607779) (xy 392.666302 -371.551653)
			(xy 392.700286 -371.499444) (xy 392.740668 -371.452009) (xy 392.786784 -371.410128) (xy 392.837876 -371.374488)
			(xy 392.893107 -371.345674) (xy 392.951569 -371.32416) (xy 393.012303 -371.310298) (xy 393.07431 -371.304316)
			(xy 393.136573 -371.306312) (xy 393.19807 -371.316255) (xy 393.257791 -371.333979) (xy 393.314754 -371.359196)
			(xy 393.368025 -371.391489) (xy 393.41673 -371.430329) (xy 393.460067 -371.475079) (xy 393.497327 -371.525003)
			(xy 393.527896 -371.579282) (xy 393.53226 -371.590062) (xy 394.803892 -371.590062) (xy 394.807883 -371.527895)
			(xy 394.819792 -371.466748) (xy 394.839421 -371.407627) (xy 394.86645 -371.351501) (xy 394.900434 -371.299292)
			(xy 394.940816 -371.251857) (xy 394.986932 -371.209976) (xy 395.038024 -371.174336) (xy 395.093255 -371.145522)
			(xy 395.151717 -371.124008) (xy 395.212451 -371.110146) (xy 395.274458 -371.104164) (xy 395.336721 -371.10616)
			(xy 395.398218 -371.116103) (xy 395.457939 -371.133827) (xy 395.514902 -371.159044) (xy 395.568173 -371.191337)
			(xy 395.616878 -371.230177) (xy 395.660215 -371.274927) (xy 395.697475 -371.324851) (xy 395.728044 -371.37913)
			(xy 395.751422 -371.436873) (xy 395.767223 -371.497131) (xy 395.775189 -371.558914) (xy 395.775688 -371.590062)
			(xy 395.775189 -371.62121) (xy 395.767223 -371.682993) (xy 395.751422 -371.743251) (xy 395.728044 -371.800994)
			(xy 395.697475 -371.855273) (xy 395.660215 -371.905197) (xy 395.616878 -371.949947) (xy 395.568173 -371.988787)
			(xy 395.514902 -372.02108) (xy 395.457939 -372.046297) (xy 395.398218 -372.064021) (xy 395.336721 -372.073964)
			(xy 395.274458 -372.07596) (xy 395.212451 -372.069978) (xy 395.151717 -372.056116) (xy 395.093255 -372.034602)
			(xy 395.038024 -372.005788) (xy 394.986932 -371.970148) (xy 394.940816 -371.928267) (xy 394.900434 -371.880832)
			(xy 394.86645 -371.828623) (xy 394.839421 -371.772497) (xy 394.819792 -371.713376) (xy 394.807883 -371.652229)
			(xy 394.803892 -371.590062) (xy 393.53226 -371.590062) (xy 393.551274 -371.637025) (xy 393.567075 -371.697283)
			(xy 393.575041 -371.759066) (xy 393.57554 -371.790214) (xy 393.575041 -371.821362) (xy 393.567075 -371.883145)
			(xy 393.551274 -371.943403) (xy 393.527896 -372.001146) (xy 393.497327 -372.055425) (xy 393.460067 -372.105349)
			(xy 393.41673 -372.150099) (xy 393.368025 -372.188939) (xy 393.314754 -372.221232) (xy 393.257791 -372.246449)
			(xy 393.19807 -372.264173) (xy 393.136573 -372.274116) (xy 393.07431 -372.276112) (xy 393.012303 -372.27013)
			(xy 392.951569 -372.256268) (xy 392.893107 -372.234754) (xy 392.837876 -372.20594) (xy 392.786784 -372.1703)
			(xy 392.740668 -372.128419) (xy 392.700286 -372.080984) (xy 392.666302 -372.028775) (xy 392.639273 -371.972649)
			(xy 392.619644 -371.913528) (xy 392.607735 -371.852381) (xy 392.603744 -371.790214) (xy 391.331958 -371.790214)
			(xy 391.32313 -371.810874) (xy 391.306812 -371.839236) (xy 391.303485 -371.845255) (xy 391.299887 -371.858523)
			(xy 391.2997 -371.865398) (xy 391.2997 -372.614698) (xy 391.299893 -372.621571) (xy 391.3035 -372.634834)
			(xy 391.306812 -372.64086) (xy 391.323161 -372.669206) (xy 391.348874 -372.729381) (xy 391.366277 -372.792463)
			(xy 391.375056 -372.85731) (xy 391.375054 -372.890034) (xy 394.803892 -372.890034) (xy 394.807883 -372.827867)
			(xy 394.819792 -372.76672) (xy 394.839421 -372.707599) (xy 394.86645 -372.651473) (xy 394.900434 -372.599264)
			(xy 394.940816 -372.551829) (xy 394.986932 -372.509948) (xy 395.038024 -372.474308) (xy 395.093255 -372.445494)
			(xy 395.151717 -372.42398) (xy 395.212451 -372.410118) (xy 395.274458 -372.404136) (xy 395.336721 -372.406132)
			(xy 395.398218 -372.416075) (xy 395.457939 -372.433799) (xy 395.514902 -372.459016) (xy 395.568173 -372.491309)
			(xy 395.616878 -372.530149) (xy 395.660215 -372.574899) (xy 395.697475 -372.624823) (xy 395.728044 -372.679102)
			(xy 395.751422 -372.736845) (xy 395.767223 -372.797103) (xy 395.775189 -372.858886) (xy 395.775688 -372.890034)
			(xy 395.775189 -372.921182) (xy 395.767223 -372.982965) (xy 395.751422 -373.043223) (xy 395.728044 -373.100966)
			(xy 395.697475 -373.155245) (xy 395.660215 -373.205169) (xy 395.616878 -373.249919) (xy 395.568173 -373.288759)
			(xy 395.514902 -373.321052) (xy 395.457939 -373.346269) (xy 395.398218 -373.363993) (xy 395.336721 -373.373936)
			(xy 395.274458 -373.375932) (xy 395.212451 -373.36995) (xy 395.151717 -373.356088) (xy 395.093255 -373.334574)
			(xy 395.038024 -373.30576) (xy 394.986932 -373.27012) (xy 394.940816 -373.228239) (xy 394.900434 -373.180804)
			(xy 394.86645 -373.128595) (xy 394.839421 -373.072469) (xy 394.819792 -373.013348) (xy 394.807883 -372.952201)
			(xy 394.803892 -372.890034) (xy 391.375054 -372.890034) (xy 391.375052 -372.922748) (xy 391.366265 -372.987594)
			(xy 391.348854 -373.050674) (xy 391.323135 -373.110846) (xy 391.306812 -373.139208) (xy 391.303495 -373.145232)
			(xy 391.299891 -373.158496) (xy 391.2997 -373.16537) (xy 391.2997 -373.451374) (xy 391.299146 -373.461525)
			(xy 391.291388 -373.480287) (xy 391.277041 -373.494652) (xy 391.258289 -373.502434) (xy 391.248138 -373.502936)
			(xy 390.531858 -373.502936) (xy 390.521694 -373.5025) (xy 390.502919 -373.494707) (xy 390.488555 -373.480324)
			(xy 390.480786 -373.461538) (xy 390.480296 -373.451374) (xy 390.480296 -373.16537) (xy 390.480116 -373.158496)
			(xy 390.4765 -373.145233) (xy 390.473184 -373.139208) (xy 390.456889 -373.110831) (xy 390.431167 -373.050664)
			(xy 390.413754 -372.987589) (xy 390.404966 -372.922747) (xy 390.404962 -372.857312) (xy 390.413742 -372.792468)
			(xy 390.431147 -372.729391) (xy 390.456863 -372.669221) (xy 390.473184 -372.64086) (xy 390.476512 -372.634842)
			(xy 390.480109 -372.621573) (xy 390.480296 -372.614698) (xy 390.480296 -371.865398) (xy 390.480105 -371.858525)
			(xy 390.476496 -371.845262) (xy 390.473184 -371.839236) (xy 390.456828 -371.810893) (xy 390.431111 -371.750718)
			(xy 390.413705 -371.687636) (xy 390.404925 -371.622787) (xy 389.145816 -371.622787) (xy 389.148714 -371.629567)
			(xy 389.166121 -371.692648) (xy 389.174903 -371.757493) (xy 389.174901 -371.822931) (xy 389.166116 -371.887776)
			(xy 389.148706 -371.950855) (xy 389.122987 -372.011027) (xy 389.106664 -372.039388) (xy 389.103359 -372.045417)
			(xy 389.099746 -372.058677) (xy 389.099552 -372.06555) (xy 389.099552 -372.351554) (xy 389.099098 -372.361724)
			(xy 389.091327 -372.380519) (xy 389.07695 -372.394906) (xy 389.05816 -372.402691) (xy 389.04799 -372.403116)
			(xy 388.33171 -372.403116) (xy 388.321533 -372.402727) (xy 388.30273 -372.394937) (xy 388.288343 -372.38054)
			(xy 388.280566 -372.361731) (xy 388.280148 -372.351554) (xy 388.280148 -372.06555) (xy 388.279944 -372.058678)
			(xy 388.276345 -372.045415) (xy 388.273036 -372.039388) (xy 388.256726 -372.01102) (xy 388.231007 -371.950851)
			(xy 388.213598 -371.887773) (xy 388.204813 -371.82293) (xy 388.204811 -371.757494) (xy 388.213593 -371.69265)
			(xy 388.230999 -371.629572) (xy 388.256715 -371.569401) (xy 388.273036 -371.54104) (xy 388.276332 -371.535006)
			(xy 388.27995 -371.52175) (xy 388.280148 -371.514878) (xy 388.280148 -370.765324) (xy 388.279953 -370.758451)
			(xy 388.276348 -370.745188) (xy 388.273036 -370.739162) (xy 388.256704 -370.710806) (xy 388.230987 -370.650634)
			(xy 388.21358 -370.587554) (xy 388.204798 -370.522708) (xy 384.7751 -370.522708) (xy 384.766318 -370.587551)
			(xy 384.748912 -370.65063) (xy 384.723197 -370.710801) (xy 384.706876 -370.739162) (xy 384.703573 -370.745192)
			(xy 384.69996 -370.758452) (xy 384.699764 -370.765324) (xy 384.699764 -371.514878) (xy 384.699969 -371.52175)
			(xy 384.703569 -371.535013) (xy 384.706876 -371.54104) (xy 384.72321 -371.569395) (xy 384.748925 -371.629568)
			(xy 384.766332 -371.692648) (xy 384.775113 -371.757493) (xy 384.775112 -371.822931) (xy 384.766327 -371.887776)
			(xy 384.748917 -371.950855) (xy 384.723199 -372.011027) (xy 384.706876 -372.039388) (xy 384.703564 -372.045414)
			(xy 384.699957 -372.058677) (xy 384.699764 -372.06555) (xy 384.699764 -372.351554) (xy 384.699299 -372.361722)
			(xy 384.691529 -372.380516) (xy 384.677156 -372.394902) (xy 384.65837 -372.402689) (xy 384.648202 -372.403116)
			(xy 383.931922 -372.403116) (xy 383.921746 -372.402717) (xy 383.902943 -372.394931) (xy 383.888556 -372.380537)
			(xy 383.880778 -372.36173) (xy 383.88036 -372.351554) (xy 383.88036 -372.06555) (xy 383.880154 -372.058678)
			(xy 383.876556 -372.045415) (xy 383.873248 -372.039388) (xy 383.856937 -372.01102) (xy 383.831218 -371.950851)
			(xy 383.813808 -371.887773) (xy 383.805023 -371.82293) (xy 383.805022 -371.757494) (xy 383.813804 -371.69265)
			(xy 383.83121 -371.629572) (xy 383.856926 -371.569401) (xy 383.873248 -371.54104) (xy 383.876544 -371.535006)
			(xy 383.880162 -371.52175) (xy 383.88036 -371.514878) (xy 383.88036 -370.765324) (xy 383.880164 -370.758451)
			(xy 383.876559 -370.745188) (xy 383.873248 -370.739162) (xy 383.856915 -370.710806) (xy 383.831198 -370.650634)
			(xy 383.813791 -370.587554) (xy 383.805008 -370.522709) (xy 380.37511 -370.522709) (xy 380.37511 -370.522718)
			(xy 380.36625 -370.587576) (xy 380.348758 -370.650656) (xy 380.322949 -370.710814) (xy 380.30658 -370.739162)
			(xy 380.303277 -370.745193) (xy 380.299664 -370.758452) (xy 380.299468 -370.765324) (xy 380.299468 -371.514878)
			(xy 380.299672 -371.52175) (xy 380.303273 -371.535013) (xy 380.30658 -371.54104) (xy 380.32296 -371.569382)
			(xy 380.345861 -371.622787) (xy 381.604852 -371.622787) (xy 381.604857 -371.557348) (xy 381.613644 -371.492502)
			(xy 381.631056 -371.429422) (xy 381.656776 -371.36925) (xy 381.6731 -371.340888) (xy 381.676419 -371.334865)
			(xy 381.680022 -371.3216) (xy 381.680212 -371.314726) (xy 381.680212 -371.028722) (xy 381.680751 -371.018569)
			(xy 381.688513 -370.999805) (xy 381.702865 -370.98544) (xy 381.721621 -370.97766) (xy 381.731774 -370.97716)
			(xy 382.448054 -370.97716) (xy 382.458225 -370.977602) (xy 382.477023 -370.985376) (xy 382.491411 -370.999757)
			(xy 382.499193 -371.018551) (xy 382.499616 -371.028722) (xy 382.499616 -371.314726) (xy 382.499796 -371.3216)
			(xy 382.503412 -371.334863) (xy 382.506728 -371.340888) (xy 382.523019 -371.369267) (xy 382.548741 -371.429433)
			(xy 382.566154 -371.492508) (xy 382.574942 -371.55735) (xy 382.574947 -371.622785) (xy 382.566167 -371.687628)
			(xy 382.548763 -371.750705) (xy 382.523049 -371.810875) (xy 382.506728 -371.839236) (xy 382.503402 -371.845255)
			(xy 382.499803 -371.858523) (xy 382.499616 -371.865398) (xy 382.499616 -372.614698) (xy 382.499807 -372.621571)
			(xy 382.503416 -372.634834) (xy 382.506728 -372.64086) (xy 382.52308 -372.669205) (xy 382.548797 -372.72938)
			(xy 382.566203 -372.792462) (xy 382.574983 -372.857309) (xy 382.574981 -372.890034) (xy 386.004308 -372.890034)
			(xy 386.004866 -372.857304) (xy 386.013724 -372.792446) (xy 386.031216 -372.729365) (xy 386.057026 -372.669208)
			(xy 386.073396 -372.64086) (xy 386.076725 -372.634842) (xy 386.080322 -372.621573) (xy 386.080508 -372.614698)
			(xy 386.080508 -371.865398) (xy 386.080316 -371.858525) (xy 386.076708 -371.845262) (xy 386.073396 -371.839236)
			(xy 386.057044 -371.810879) (xy 386.031239 -371.750722) (xy 386.013746 -371.687645) (xy 386.004881 -371.62279)
			(xy 386.004308 -371.590062) (xy 386.004878 -371.557333) (xy 386.013732 -371.492475) (xy 386.031221 -371.429394)
			(xy 386.057028 -371.369236) (xy 386.073396 -371.340888) (xy 386.076715 -371.334865) (xy 386.080318 -371.3216)
			(xy 386.080508 -371.314726) (xy 386.080508 -371.028722) (xy 386.081044 -371.018601) (xy 386.088758 -370.999886)
			(xy 386.103029 -370.98553) (xy 386.121698 -370.977704) (xy 386.131816 -370.97716) (xy 386.848096 -370.97716)
			(xy 386.858245 -370.977624) (xy 386.876989 -370.985411) (xy 386.891311 -370.999794) (xy 386.899019 -371.018571)
			(xy 386.899404 -371.028722) (xy 386.899404 -371.314726) (xy 386.899585 -371.3216) (xy 386.903201 -371.334863)
			(xy 386.906516 -371.340888) (xy 386.922878 -371.369239) (xy 386.948681 -371.429398) (xy 386.966171 -371.492477)
			(xy 386.975033 -371.557333) (xy 386.975604 -371.590062) (xy 386.975043 -371.622792) (xy 386.966186 -371.68765)
			(xy 386.948694 -371.75073) (xy 386.922885 -371.810888) (xy 386.906516 -371.839236) (xy 386.90319 -371.845255)
			(xy 386.899591 -371.858523) (xy 386.899404 -371.865398) (xy 386.899404 -372.614698) (xy 386.899596 -372.621571)
			(xy 386.903204 -372.634834) (xy 386.906516 -372.64086) (xy 386.922867 -372.669217) (xy 386.948672 -372.729374)
			(xy 386.966166 -372.792451) (xy 386.975031 -372.857306) (xy 386.975604 -372.890034) (xy 386.97503 -372.922763)
			(xy 386.966177 -372.987621) (xy 386.948689 -373.050701) (xy 386.922883 -373.11086) (xy 386.906516 -373.139208)
			(xy 386.9032 -373.145232) (xy 386.899595 -373.158496) (xy 386.899404 -373.16537) (xy 386.899404 -373.451374)
			(xy 386.898854 -373.461494) (xy 386.891142 -373.480206) (xy 386.876876 -373.494562) (xy 386.858212 -373.50239)
			(xy 386.848096 -373.502936) (xy 386.131816 -373.502936) (xy 386.121667 -373.502466) (xy 386.102922 -373.494683)
			(xy 386.0886 -373.480301) (xy 386.080893 -373.461524) (xy 386.080508 -373.451374) (xy 386.080508 -373.16537)
			(xy 386.080327 -373.158496) (xy 386.076711 -373.145233) (xy 386.073396 -373.139208) (xy 386.057033 -373.110857)
			(xy 386.031231 -373.050698) (xy 386.01374 -372.987619) (xy 386.004879 -372.922763) (xy 386.004308 -372.890034)
			(xy 382.574981 -372.890034) (xy 382.57498 -372.922749) (xy 382.566191 -372.987596) (xy 382.548777 -373.050676)
			(xy 382.523054 -373.110847) (xy 382.506728 -373.139208) (xy 382.503412 -373.145232) (xy 382.499807 -373.158496)
			(xy 382.499616 -373.16537) (xy 382.499616 -373.451374) (xy 382.499214 -373.46155) (xy 382.491429 -373.480352)
			(xy 382.477036 -373.49474) (xy 382.45823 -373.502517) (xy 382.448054 -373.502936) (xy 381.731774 -373.502936)
			(xy 381.721611 -373.502487) (xy 381.702837 -373.4947) (xy 381.688471 -373.48032) (xy 381.680702 -373.461537)
			(xy 381.680212 -373.451374) (xy 381.680212 -373.16537) (xy 381.68003 -373.158496) (xy 381.676415 -373.145233)
			(xy 381.6731 -373.139208) (xy 381.656808 -373.11083) (xy 381.63109 -373.050663) (xy 381.61368 -372.987587)
			(xy 381.604893 -372.922746) (xy 381.604889 -372.857312) (xy 381.613668 -372.79247) (xy 381.63107 -372.729393)
			(xy 381.656781 -372.669222) (xy 381.6731 -372.64086) (xy 381.676429 -372.634842) (xy 381.680026 -372.621573)
			(xy 381.680212 -372.614698) (xy 381.680212 -371.865398) (xy 381.680019 -371.858525) (xy 381.676412 -371.845262)
			(xy 381.6731 -371.839236) (xy 381.656747 -371.810892) (xy 381.631034 -371.750716) (xy 381.613631 -371.687634)
			(xy 381.604852 -371.622787) (xy 380.345861 -371.622787) (xy 380.348758 -371.629544) (xy 380.366244 -371.692626)
			(xy 380.3751 -371.757484) (xy 380.375668 -371.790214) (xy 380.375077 -371.822943) (xy 380.366227 -371.8878)
			(xy 380.348744 -371.95088) (xy 380.322945 -372.011039) (xy 380.30658 -372.039388) (xy 380.303268 -372.045414)
			(xy 380.299661 -372.058677) (xy 380.299468 -372.06555) (xy 380.299468 -372.351554) (xy 380.298936 -372.361677)
			(xy 380.291225 -372.380395) (xy 380.276952 -372.394753) (xy 380.25828 -372.402575) (xy 380.24816 -372.403116)
			(xy 379.53188 -372.403116) (xy 379.521727 -372.402695) (xy 379.502977 -372.394896) (xy 379.488655 -372.3805)
			(xy 379.480953 -372.36171) (xy 379.480572 -372.351554) (xy 379.480572 -372.06555) (xy 379.480364 -372.058678)
			(xy 379.476767 -372.045415) (xy 379.47346 -372.039388) (xy 379.457095 -372.011038) (xy 379.431292 -371.950879)
			(xy 379.413802 -371.8878) (xy 379.404942 -371.822943) (xy 379.404372 -371.790214) (xy 378.13167 -371.790214)
			(xy 378.122801 -371.810888) (xy 378.106432 -371.839236) (xy 378.103107 -371.845256) (xy 378.099508 -371.858523)
			(xy 378.09932 -371.865398) (xy 378.09932 -372.614698) (xy 378.09951 -372.621571) (xy 378.10312 -372.634834)
			(xy 378.106432 -372.64086) (xy 378.122775 -372.669222) (xy 378.148584 -372.729376) (xy 378.16608 -372.792452)
			(xy 378.174947 -372.857306) (xy 378.17552 -372.890034) (xy 378.174944 -372.922763) (xy 378.166091 -372.987621)
			(xy 378.148603 -373.050701) (xy 378.122799 -373.110859) (xy 378.106432 -373.139208) (xy 378.103117 -373.145233)
			(xy 378.099511 -373.158496) (xy 378.09932 -373.16537) (xy 378.09932 -373.451374) (xy 378.098851 -373.461504)
			(xy 378.091125 -373.480232) (xy 378.076832 -373.494591) (xy 378.05814 -373.502404) (xy 378.048012 -373.502936)
			(xy 377.331732 -373.502936) (xy 377.321584 -373.502453) (xy 377.30284 -373.494675) (xy 377.288516 -373.480297)
			(xy 377.280809 -373.461523) (xy 377.280424 -373.451374) (xy 377.280424 -373.16537) (xy 377.28024 -373.158496)
			(xy 377.276626 -373.145234) (xy 377.273312 -373.139208) (xy 377.256951 -373.110856) (xy 377.231148 -373.050698)
			(xy 377.213657 -372.987619) (xy 377.204795 -372.922763) (xy 377.204224 -372.890034) (xy 359.984666 -372.890034)
			(xy 359.95332 -374.422884) (xy 375.004905 -374.422884) (xy 375.00491 -374.357444) (xy 375.013699 -374.292597)
			(xy 375.031114 -374.229517) (xy 375.056838 -374.169345) (xy 375.073164 -374.140984) (xy 375.076481 -374.134961)
			(xy 375.080086 -374.121696) (xy 375.080276 -374.114822) (xy 375.080276 -373.828818) (xy 375.080679 -373.818643)
			(xy 375.088465 -373.799841) (xy 375.102858 -373.785454) (xy 375.121663 -373.777675) (xy 375.131838 -373.777256)
			(xy 375.848118 -373.777256) (xy 375.858279 -373.777719) (xy 375.877052 -373.785503) (xy 375.891418 -373.799878)
			(xy 375.899188 -373.818656) (xy 375.89968 -373.828818) (xy 375.89968 -374.114822) (xy 375.899866 -374.121696)
			(xy 375.903479 -374.134958) (xy 375.906792 -374.140984) (xy 375.923078 -374.169365) (xy 375.948797 -374.229532)
			(xy 375.966208 -374.292607) (xy 375.974995 -374.357447) (xy 375.975 -374.422881) (xy 375.966222 -374.487723)
			(xy 375.948821 -374.5508) (xy 375.92311 -374.61097) (xy 375.906792 -374.639332) (xy 375.903465 -374.645351)
			(xy 375.899867 -374.658619) (xy 375.89968 -374.665494) (xy 375.89968 -375.414794) (xy 375.899877 -375.421667)
			(xy 375.903482 -375.43493) (xy 375.906792 -375.440956) (xy 375.923139 -375.469304) (xy 375.948852 -375.529478)
			(xy 375.966256 -375.59256) (xy 375.975036 -375.657407) (xy 375.975033 -375.722845) (xy 375.966246 -375.787691)
			(xy 375.948835 -375.85077) (xy 375.923115 -375.910942) (xy 375.906792 -375.939304) (xy 375.903475 -375.945328)
			(xy 375.899871 -375.958592) (xy 375.89968 -375.965466) (xy 375.89968 -376.25147) (xy 375.899212 -376.261637)
			(xy 375.89144 -376.280428) (xy 375.877068 -376.294813) (xy 375.858285 -376.302602) (xy 375.848118 -376.303032)
			(xy 375.131838 -376.303032) (xy 375.121665 -376.302604) (xy 375.102866 -376.294826) (xy 375.088478 -376.280441)
			(xy 375.080697 -376.261643) (xy 375.080276 -376.25147) (xy 375.080276 -375.965466) (xy 375.0801 -375.958592)
			(xy 375.076481 -375.945329) (xy 375.073164 -375.939304) (xy 375.056866 -375.910929) (xy 375.031145 -375.850761)
			(xy 375.013733 -375.787685) (xy 375.004946 -375.722843) (xy 375.004943 -375.657408) (xy 375.013723 -375.592565)
			(xy 375.031128 -375.529487) (xy 375.056843 -375.469317) (xy 375.073164 -375.440956) (xy 375.076491 -375.434938)
			(xy 375.080089 -375.421669) (xy 375.080276 -375.414794) (xy 375.080276 -374.665494) (xy 375.080089 -374.65862)
			(xy 375.076478 -374.645358) (xy 375.073164 -374.639332) (xy 375.056805 -374.610991) (xy 375.03109 -374.550815)
			(xy 375.013685 -374.487732) (xy 375.004905 -374.422884) (xy 359.95332 -374.422884) (xy 359.904909 -376.790204)
			(xy 377.204224 -376.790204) (xy 377.204766 -376.757474) (xy 377.213628 -376.692614) (xy 377.231126 -376.629534)
			(xy 377.25694 -376.569377) (xy 377.273312 -376.54103) (xy 377.276617 -376.535001) (xy 377.280229 -376.521741)
			(xy 377.280424 -376.514868) (xy 377.280424 -375.765568) (xy 377.280241 -375.758694) (xy 377.276626 -375.745431)
			(xy 377.273312 -375.739406) (xy 377.25695 -375.711055) (xy 377.231147 -375.650896) (xy 377.213656 -375.587817)
			(xy 377.204795 -375.522961) (xy 377.204224 -375.490232) (xy 377.204779 -375.457502) (xy 377.213637 -375.392643)
			(xy 377.231131 -375.329563) (xy 377.256942 -375.269406) (xy 377.273312 -375.241058) (xy 377.276643 -375.235041)
			(xy 377.280238 -375.221771) (xy 377.280424 -375.214896) (xy 377.280424 -374.928638) (xy 377.280957 -374.918516)
			(xy 377.28867 -374.899799) (xy 377.302942 -374.885442) (xy 377.321613 -374.877618) (xy 377.331732 -374.877076)
			(xy 378.048012 -374.877076) (xy 378.058164 -374.877511) (xy 378.076912 -374.885306) (xy 378.091234 -374.899698)
			(xy 378.098938 -374.918484) (xy 378.09932 -374.928638) (xy 378.09932 -375.214896) (xy 378.099511 -375.221769)
			(xy 378.10312 -375.235032) (xy 378.106432 -375.241058) (xy 378.122774 -375.26942) (xy 378.148583 -375.329574)
			(xy 378.16608 -375.39265) (xy 378.174947 -375.457504) (xy 378.17552 -375.490232) (xy 378.174943 -375.522961)
			(xy 378.16609 -375.587819) (xy 378.148603 -375.650899) (xy 378.131775 -375.69013) (xy 379.404372 -375.69013)
			(xy 379.404932 -375.6574) (xy 379.41379 -375.592542) (xy 379.431282 -375.529462) (xy 379.457091 -375.469304)
			(xy 379.47346 -375.440956) (xy 379.476787 -375.434937) (xy 379.480385 -375.421669) (xy 379.480572 -375.414794)
			(xy 379.480572 -374.665494) (xy 379.480386 -374.65862) (xy 379.476774 -374.645357) (xy 379.47346 -374.639332)
			(xy 379.457113 -374.610973) (xy 379.431305 -374.550817) (xy 379.41381 -374.487741) (xy 379.404945 -374.422886)
			(xy 379.404372 -374.390158) (xy 379.404945 -374.357429) (xy 379.413799 -374.292571) (xy 379.431287 -374.229491)
			(xy 379.457092 -374.169332) (xy 379.47346 -374.140984) (xy 379.476777 -374.13496) (xy 379.480382 -374.121696)
			(xy 379.480572 -374.114822) (xy 379.480572 -373.828818) (xy 379.481042 -373.818688) (xy 379.48877 -373.799962)
			(xy 379.503062 -373.785604) (xy 379.521753 -373.777789) (xy 379.53188 -373.777256) (xy 380.24816 -373.777256)
			(xy 380.258306 -373.777754) (xy 380.277049 -373.785528) (xy 380.291372 -373.799901) (xy 380.299081 -373.818671)
			(xy 380.299468 -373.828818) (xy 380.299468 -374.114822) (xy 380.299656 -374.121695) (xy 380.303267 -374.134958)
			(xy 380.30658 -374.140984) (xy 380.322937 -374.169338) (xy 380.348742 -374.229496) (xy 380.366234 -374.292574)
			(xy 380.375096 -374.357429) (xy 380.375668 -374.390158) (xy 380.375097 -374.422884) (xy 383.804991 -374.422884)
			(xy 383.804996 -374.357444) (xy 383.813785 -374.292597) (xy 383.831199 -374.229517) (xy 383.856923 -374.169345)
			(xy 383.873248 -374.140984) (xy 383.876564 -374.13496) (xy 383.88017 -374.121696) (xy 383.88036 -374.114822)
			(xy 383.88036 -373.828818) (xy 383.880779 -373.818645) (xy 383.888562 -373.799846) (xy 383.90295 -373.78546)
			(xy 383.921749 -373.777678) (xy 383.931922 -373.777256) (xy 384.648202 -373.777256) (xy 384.658376 -373.777663)
			(xy 384.677174 -373.785452) (xy 384.69156 -373.799843) (xy 384.699341 -373.818644) (xy 384.699764 -373.828818)
			(xy 384.699764 -374.114822) (xy 384.699952 -374.121695) (xy 384.703564 -374.134958) (xy 384.706876 -374.140984)
			(xy 384.723162 -374.169365) (xy 384.748882 -374.229532) (xy 384.766294 -374.292606) (xy 384.775081 -374.357447)
			(xy 384.775086 -374.422881) (xy 384.775086 -374.422884) (xy 388.204781 -374.422884) (xy 388.204786 -374.357444)
			(xy 388.213575 -374.292597) (xy 388.230988 -374.229517) (xy 388.256711 -374.169345) (xy 388.273036 -374.140984)
			(xy 388.276351 -374.13496) (xy 388.279957 -374.121696) (xy 388.280148 -374.114822) (xy 388.280148 -373.828818)
			(xy 388.280579 -373.818646) (xy 388.28836 -373.79985) (xy 388.302743 -373.785464) (xy 388.321538 -373.77768)
			(xy 388.33171 -373.777256) (xy 389.04799 -373.777256) (xy 389.058163 -373.777672) (xy 389.076961 -373.785457)
			(xy 389.091347 -373.799846) (xy 389.099129 -373.818645) (xy 389.099552 -373.828818) (xy 389.099552 -374.114822)
			(xy 389.099729 -374.121696) (xy 389.103347 -374.134959) (xy 389.106664 -374.140984) (xy 389.122951 -374.169365)
			(xy 389.148671 -374.229532) (xy 389.166083 -374.292606) (xy 389.174871 -374.357447) (xy 389.174873 -374.390158)
			(xy 392.603744 -374.390158) (xy 392.607735 -374.327991) (xy 392.619644 -374.266844) (xy 392.639273 -374.207723)
			(xy 392.666302 -374.151597) (xy 392.700286 -374.099388) (xy 392.740668 -374.051953) (xy 392.786784 -374.010072)
			(xy 392.837876 -373.974432) (xy 392.893107 -373.945618) (xy 392.951569 -373.924104) (xy 393.012303 -373.910242)
			(xy 393.07431 -373.90426) (xy 393.136573 -373.906256) (xy 393.19807 -373.916199) (xy 393.257791 -373.933923)
			(xy 393.314754 -373.95914) (xy 393.368025 -373.991433) (xy 393.41673 -374.030273) (xy 393.460067 -374.075023)
			(xy 393.497327 -374.124947) (xy 393.527896 -374.179226) (xy 393.551274 -374.236969) (xy 393.567075 -374.297227)
			(xy 393.575041 -374.35901) (xy 393.57554 -374.390158) (xy 393.575041 -374.421306) (xy 393.567075 -374.483089)
			(xy 393.551274 -374.543347) (xy 393.527896 -374.60109) (xy 393.497327 -374.655369) (xy 393.460067 -374.705293)
			(xy 393.41673 -374.750043) (xy 393.368025 -374.788883) (xy 393.314754 -374.821176) (xy 393.257791 -374.846393)
			(xy 393.19807 -374.864117) (xy 393.136573 -374.87406) (xy 393.07431 -374.876056) (xy 393.012303 -374.870074)
			(xy 392.951569 -374.856212) (xy 392.893107 -374.834698) (xy 392.837876 -374.805884) (xy 392.786784 -374.770244)
			(xy 392.740668 -374.728363) (xy 392.700286 -374.680928) (xy 392.666302 -374.628719) (xy 392.639273 -374.572593)
			(xy 392.619644 -374.513472) (xy 392.607735 -374.452325) (xy 392.603744 -374.390158) (xy 389.174873 -374.390158)
			(xy 389.174876 -374.422881) (xy 389.166098 -374.487723) (xy 389.148695 -374.5508) (xy 389.122983 -374.610971)
			(xy 389.106664 -374.639332) (xy 389.103343 -374.645354) (xy 389.09974 -374.65862) (xy 389.099552 -374.665494)
			(xy 389.099552 -375.414794) (xy 389.09974 -375.421668) (xy 389.10335 -375.434931) (xy 389.106664 -375.440956)
			(xy 389.123012 -375.469303) (xy 389.148727 -375.529478) (xy 389.166132 -375.592559) (xy 389.174912 -375.657406)
			(xy 389.174909 -375.722845) (xy 389.166121 -375.787691) (xy 389.14871 -375.850771) (xy 389.122988 -375.910943)
			(xy 389.106664 -375.939304) (xy 389.103353 -375.94533) (xy 389.099744 -375.958593) (xy 389.099552 -375.965466)
			(xy 389.099552 -376.25147) (xy 389.099111 -376.261641) (xy 389.091334 -376.280437) (xy 389.076954 -376.294823)
			(xy 389.058161 -376.302607) (xy 389.04799 -376.303032) (xy 388.33171 -376.303032) (xy 388.321535 -376.302627)
			(xy 388.302735 -376.29484) (xy 388.288349 -376.280448) (xy 388.280569 -376.261645) (xy 388.280148 -376.25147)
			(xy 388.280148 -375.965466) (xy 388.279975 -375.958591) (xy 388.276355 -375.945328) (xy 388.273036 -375.939304)
			(xy 388.256739 -375.910929) (xy 388.231019 -375.850761) (xy 388.213609 -375.787685) (xy 388.204822 -375.722843)
			(xy 388.204819 -375.657408) (xy 388.213598 -375.592566) (xy 388.231002 -375.529488) (xy 388.256716 -375.469317)
			(xy 388.273036 -375.440956) (xy 388.276361 -375.434936) (xy 388.279961 -375.421669) (xy 388.280148 -375.414794)
			(xy 388.280148 -374.665494) (xy 388.279965 -374.65862) (xy 388.276351 -374.645357) (xy 388.273036 -374.639332)
			(xy 388.256678 -374.61099) (xy 388.230964 -374.550815) (xy 388.21356 -374.487732) (xy 388.204781 -374.422884)
			(xy 384.775086 -374.422884) (xy 384.766308 -374.487723) (xy 384.748906 -374.5508) (xy 384.723195 -374.610971)
			(xy 384.706876 -374.639332) (xy 384.703548 -374.64535) (xy 384.699951 -374.658619) (xy 384.699764 -374.665494)
			(xy 384.699764 -375.414794) (xy 384.699963 -375.421667) (xy 384.703567 -375.434929) (xy 384.706876 -375.440956)
			(xy 384.723223 -375.469303) (xy 384.748938 -375.529478) (xy 384.766342 -375.59256) (xy 384.775122 -375.657406)
			(xy 384.775119 -375.722845) (xy 384.766332 -375.787691) (xy 384.748921 -375.850771) (xy 384.7232 -375.910943)
			(xy 384.706876 -375.939304) (xy 384.703558 -375.945327) (xy 384.699955 -375.958592) (xy 384.699764 -375.965466)
			(xy 384.699764 -376.25147) (xy 384.699311 -376.261639) (xy 384.691537 -376.280433) (xy 384.67716 -376.294819)
			(xy 384.658371 -376.302605) (xy 384.648202 -376.303032) (xy 383.931922 -376.303032) (xy 383.921748 -376.302617)
			(xy 383.902948 -376.294834) (xy 383.888562 -376.280445) (xy 383.880781 -376.261644) (xy 383.88036 -376.25147)
			(xy 383.88036 -375.965466) (xy 383.880186 -375.958591) (xy 383.876566 -375.945328) (xy 383.873248 -375.939304)
			(xy 383.856951 -375.910929) (xy 383.83123 -375.850761) (xy 383.813819 -375.787685) (xy 383.805032 -375.722843)
			(xy 383.805029 -375.657408) (xy 383.813809 -375.592565) (xy 383.831213 -375.529488) (xy 383.856927 -375.469317)
			(xy 383.873248 -375.440956) (xy 383.876574 -375.434937) (xy 383.880173 -375.421669) (xy 383.88036 -375.414794)
			(xy 383.88036 -374.665494) (xy 383.880175 -374.65862) (xy 383.876563 -374.645357) (xy 383.873248 -374.639332)
			(xy 383.85689 -374.61099) (xy 383.831175 -374.550815) (xy 383.813771 -374.487732) (xy 383.804991 -374.422884)
			(xy 380.375097 -374.422884) (xy 380.375097 -374.422887) (xy 380.366241 -374.487745) (xy 380.348752 -374.550825)
			(xy 380.322947 -374.610984) (xy 380.30658 -374.639332) (xy 380.303252 -374.64535) (xy 380.299655 -374.658619)
			(xy 380.299468 -374.665494) (xy 380.299468 -375.414794) (xy 380.299666 -375.421667) (xy 380.303271 -375.434929)
			(xy 380.30658 -375.440956) (xy 380.322926 -375.469316) (xy 380.348733 -375.529471) (xy 380.366228 -375.592548)
			(xy 380.375095 -375.657402) (xy 380.375668 -375.69013) (xy 380.375084 -375.722859) (xy 380.366232 -375.787716)
			(xy 380.348747 -375.850796) (xy 380.322946 -375.910955) (xy 380.30658 -375.939304) (xy 380.303262 -375.945327)
			(xy 380.299659 -375.958592) (xy 380.299468 -375.965466) (xy 380.299468 -376.25147) (xy 380.298949 -376.261594)
			(xy 380.291233 -376.280313) (xy 380.276956 -376.29467) (xy 380.258281 -376.302492) (xy 380.24816 -376.303032)
			(xy 379.53188 -376.303032) (xy 379.521729 -376.302596) (xy 379.502982 -376.294799) (xy 379.48866 -376.280408)
			(xy 379.480955 -376.261623) (xy 379.480572 -376.25147) (xy 379.480572 -375.965466) (xy 379.480397 -375.958591)
			(xy 379.476778 -375.945328) (xy 379.47346 -375.939304) (xy 379.457102 -375.910951) (xy 379.431297 -375.850793)
			(xy 379.413805 -375.787715) (xy 379.404943 -375.722859) (xy 379.404372 -375.69013) (xy 378.131775 -375.69013)
			(xy 378.122799 -375.711057) (xy 378.106432 -375.739406) (xy 378.103118 -375.745431) (xy 378.099512 -375.758694)
			(xy 378.09932 -375.765568) (xy 378.09932 -376.514868) (xy 378.099522 -376.521741) (xy 378.103123 -376.535003)
			(xy 378.106432 -376.54103) (xy 378.122803 -376.569376) (xy 378.148605 -376.629536) (xy 378.166093 -376.692617)
			(xy 378.174951 -376.757475) (xy 378.17552 -376.790204) (xy 378.174976 -376.822921) (xy 381.604876 -376.822921)
			(xy 381.604876 -376.757485) (xy 381.613658 -376.692642) (xy 381.631064 -376.629563) (xy 381.656779 -376.569392)
			(xy 381.6731 -376.54103) (xy 381.676404 -376.535) (xy 381.680016 -376.52174) (xy 381.680212 -376.514868)
			(xy 381.680212 -375.765568) (xy 381.680031 -375.758694) (xy 381.676415 -375.745431) (xy 381.6731 -375.739406)
			(xy 381.656806 -375.711029) (xy 381.631088 -375.650861) (xy 381.613678 -375.587786) (xy 381.604892 -375.522944)
			(xy 381.604888 -375.45751) (xy 381.613667 -375.392668) (xy 381.63107 -375.329591) (xy 381.656781 -375.26942)
			(xy 381.6731 -375.241058) (xy 381.67643 -375.235041) (xy 381.680026 -375.221771) (xy 381.680212 -375.214896)
			(xy 381.680212 -374.928638) (xy 381.680694 -374.918472) (xy 381.688462 -374.899683) (xy 381.702829 -374.885298)
			(xy 381.721609 -374.877507) (xy 381.731774 -374.877076) (xy 382.448054 -374.877076) (xy 382.458227 -374.877502)
			(xy 382.477028 -374.885279) (xy 382.491416 -374.899665) (xy 382.499196 -374.918465) (xy 382.499616 -374.928638)
			(xy 382.499616 -375.214896) (xy 382.499808 -375.221769) (xy 382.503416 -375.235032) (xy 382.506728 -375.241058)
			(xy 382.523078 -375.269404) (xy 382.548795 -375.329578) (xy 382.566202 -375.39266) (xy 382.574982 -375.457508)
			(xy 382.574979 -375.522947) (xy 382.56619 -375.587794) (xy 382.548777 -375.650874) (xy 382.523053 -375.711045)
			(xy 382.506728 -375.739406) (xy 382.503413 -375.745431) (xy 382.499807 -375.758694) (xy 382.499616 -375.765568)
			(xy 382.499616 -376.514868) (xy 382.499818 -376.52174) (xy 382.503419 -376.535003) (xy 382.506728 -376.54103)
			(xy 382.523055 -376.569389) (xy 382.548774 -376.62956) (xy 382.566183 -376.69264) (xy 382.574966 -376.757485)
			(xy 382.574966 -376.790204) (xy 386.004308 -376.790204) (xy 386.004852 -376.757474) (xy 386.013714 -376.692615)
			(xy 386.031211 -376.629535) (xy 386.057025 -376.569377) (xy 386.073396 -376.54103) (xy 386.0767 -376.535)
			(xy 386.080312 -376.52174) (xy 386.080508 -376.514868) (xy 386.080508 -375.765568) (xy 386.080327 -375.758694)
			(xy 386.076711 -375.745431) (xy 386.073396 -375.739406) (xy 386.057032 -375.711056) (xy 386.03123 -375.650897)
			(xy 386.01374 -375.587817) (xy 386.004879 -375.522961) (xy 386.004308 -375.490232) (xy 386.004865 -375.457502)
			(xy 386.013723 -375.392644) (xy 386.031216 -375.329563) (xy 386.057026 -375.269406) (xy 386.073396 -375.241058)
			(xy 386.076725 -375.235041) (xy 386.080322 -375.221771) (xy 386.080508 -375.214896) (xy 386.080508 -374.928638)
			(xy 386.081057 -374.918518) (xy 386.088766 -374.899804) (xy 386.103033 -374.885447) (xy 386.121699 -374.877621)
			(xy 386.131816 -374.877076) (xy 386.848096 -374.877076) (xy 386.858247 -374.877524) (xy 386.876995 -374.885314)
			(xy 386.891317 -374.899702) (xy 386.899021 -374.918485) (xy 386.899404 -374.928638) (xy 386.899404 -375.214896)
			(xy 386.899597 -375.221769) (xy 386.903204 -375.235032) (xy 386.906516 -375.241058) (xy 386.922866 -375.269416)
			(xy 386.948672 -375.329572) (xy 386.966165 -375.392649) (xy 386.975031 -375.457504) (xy 386.975604 -375.490232)
			(xy 386.97503 -375.522961) (xy 386.966176 -375.587819) (xy 386.948688 -375.650899) (xy 386.922883 -375.711058)
			(xy 386.906516 -375.739406) (xy 386.9032 -375.74543) (xy 386.899595 -375.758694) (xy 386.899404 -375.765568)
			(xy 386.899404 -376.514868) (xy 386.899608 -376.52174) (xy 386.903208 -376.535003) (xy 386.906516 -376.54103)
			(xy 386.922895 -376.569372) (xy 386.948693 -376.629534) (xy 386.966179 -376.692616) (xy 386.975036 -376.757474)
			(xy 386.975036 -376.757485) (xy 390.404948 -376.757485) (xy 390.413732 -376.69264) (xy 390.431141 -376.629561)
			(xy 390.456861 -376.569391) (xy 390.473184 -376.54103) (xy 390.476487 -376.535) (xy 390.4801 -376.52174)
			(xy 390.480296 -376.514868) (xy 390.480296 -375.765568) (xy 390.480117 -375.758694) (xy 390.4765 -375.745431)
			(xy 390.473184 -375.739406) (xy 390.456887 -375.71103) (xy 390.431165 -375.650863) (xy 390.413752 -375.587787)
			(xy 390.404964 -375.522945) (xy 390.404961 -375.45751) (xy 390.413741 -375.392667) (xy 390.431147 -375.329589)
			(xy 390.456863 -375.269419) (xy 390.473184 -375.241058) (xy 390.476513 -375.23504) (xy 390.48011 -375.221771)
			(xy 390.480296 -375.214896) (xy 390.480296 -374.928638) (xy 390.480864 -374.918488) (xy 390.488618 -374.899728)
			(xy 390.502961 -374.885363) (xy 390.521709 -374.877579) (xy 390.531858 -374.877076) (xy 391.248138 -374.877076)
			(xy 391.258303 -374.877503) (xy 391.27708 -374.885297) (xy 391.291445 -374.899684) (xy 391.299212 -374.918472)
			(xy 391.2997 -374.928638) (xy 391.2997 -375.214896) (xy 391.299893 -375.221769) (xy 391.3035 -375.235032)
			(xy 391.306812 -375.241058) (xy 391.32316 -375.269405) (xy 391.348872 -375.32958) (xy 391.366275 -375.392662)
			(xy 391.375055 -375.457508) (xy 391.375051 -375.522947) (xy 391.366264 -375.587792) (xy 391.348854 -375.650872)
			(xy 391.332074 -375.69013) (xy 392.603744 -375.69013) (xy 392.607735 -375.627963) (xy 392.619644 -375.566816)
			(xy 392.639273 -375.507695) (xy 392.666302 -375.451569) (xy 392.700286 -375.39936) (xy 392.740668 -375.351925)
			(xy 392.786784 -375.310044) (xy 392.837876 -375.274404) (xy 392.893107 -375.24559) (xy 392.951569 -375.224076)
			(xy 393.012303 -375.210214) (xy 393.07431 -375.204232) (xy 393.136573 -375.206228) (xy 393.19807 -375.216171)
			(xy 393.257791 -375.233895) (xy 393.314754 -375.259112) (xy 393.368025 -375.291405) (xy 393.41673 -375.330245)
			(xy 393.460067 -375.374995) (xy 393.497327 -375.424919) (xy 393.527896 -375.479198) (xy 393.532363 -375.490232)
			(xy 394.803892 -375.490232) (xy 394.807883 -375.428065) (xy 394.819792 -375.366918) (xy 394.839421 -375.307797)
			(xy 394.86645 -375.251671) (xy 394.900434 -375.199462) (xy 394.940816 -375.152027) (xy 394.986932 -375.110146)
			(xy 395.038024 -375.074506) (xy 395.093255 -375.045692) (xy 395.151717 -375.024178) (xy 395.212451 -375.010316)
			(xy 395.274458 -375.004334) (xy 395.336721 -375.00633) (xy 395.398218 -375.016273) (xy 395.457939 -375.033997)
			(xy 395.514902 -375.059214) (xy 395.568173 -375.091507) (xy 395.616878 -375.130347) (xy 395.660215 -375.175097)
			(xy 395.697475 -375.225021) (xy 395.728044 -375.2793) (xy 395.751422 -375.337043) (xy 395.767223 -375.397301)
			(xy 395.775189 -375.459084) (xy 395.775688 -375.490232) (xy 395.775189 -375.52138) (xy 395.767223 -375.583163)
			(xy 395.751422 -375.643421) (xy 395.728044 -375.701164) (xy 395.697475 -375.755443) (xy 395.660215 -375.805367)
			(xy 395.616878 -375.850117) (xy 395.568173 -375.888957) (xy 395.514902 -375.92125) (xy 395.457939 -375.946467)
			(xy 395.398218 -375.964191) (xy 395.336721 -375.974134) (xy 395.274458 -375.97613) (xy 395.212451 -375.970148)
			(xy 395.151717 -375.956286) (xy 395.093255 -375.934772) (xy 395.038024 -375.905958) (xy 394.986932 -375.870318)
			(xy 394.940816 -375.828437) (xy 394.900434 -375.781002) (xy 394.86645 -375.728793) (xy 394.839421 -375.672667)
			(xy 394.819792 -375.613546) (xy 394.807883 -375.552399) (xy 394.803892 -375.490232) (xy 393.532363 -375.490232)
			(xy 393.551274 -375.536941) (xy 393.567075 -375.597199) (xy 393.575041 -375.658982) (xy 393.57554 -375.69013)
			(xy 393.575041 -375.721278) (xy 393.567075 -375.783061) (xy 393.551274 -375.843319) (xy 393.527896 -375.901062)
			(xy 393.497327 -375.955341) (xy 393.460067 -376.005265) (xy 393.41673 -376.050015) (xy 393.368025 -376.088855)
			(xy 393.314754 -376.121148) (xy 393.257791 -376.146365) (xy 393.19807 -376.164089) (xy 393.136573 -376.174032)
			(xy 393.07431 -376.176028) (xy 393.012303 -376.170046) (xy 392.951569 -376.156184) (xy 392.893107 -376.13467)
			(xy 392.837876 -376.105856) (xy 392.786784 -376.070216) (xy 392.740668 -376.028335) (xy 392.700286 -375.9809)
			(xy 392.666302 -375.928691) (xy 392.639273 -375.872565) (xy 392.619644 -375.813444) (xy 392.607735 -375.752297)
			(xy 392.603744 -375.69013) (xy 391.332074 -375.69013) (xy 391.323135 -375.711044) (xy 391.306812 -375.739406)
			(xy 391.303496 -375.74543) (xy 391.299891 -375.758694) (xy 391.2997 -375.765568) (xy 391.2997 -376.514868)
			(xy 391.299904 -376.52174) (xy 391.303504 -376.535003) (xy 391.306812 -376.54103) (xy 391.323136 -376.56939)
			(xy 391.348851 -376.629562) (xy 391.366257 -376.692641) (xy 391.375039 -376.757485) (xy 391.375038 -376.790204)
			(xy 394.803892 -376.790204) (xy 394.807883 -376.728037) (xy 394.819792 -376.66689) (xy 394.839421 -376.607769)
			(xy 394.86645 -376.551643) (xy 394.900434 -376.499434) (xy 394.940816 -376.451999) (xy 394.986932 -376.410118)
			(xy 395.038024 -376.374478) (xy 395.093255 -376.345664) (xy 395.151717 -376.32415) (xy 395.212451 -376.310288)
			(xy 395.274458 -376.304306) (xy 395.336721 -376.306302) (xy 395.398218 -376.316245) (xy 395.457939 -376.333969)
			(xy 395.514902 -376.359186) (xy 395.568173 -376.391479) (xy 395.616878 -376.430319) (xy 395.660215 -376.475069)
			(xy 395.697475 -376.524993) (xy 395.728044 -376.579272) (xy 395.751422 -376.637015) (xy 395.767223 -376.697273)
			(xy 395.775189 -376.759056) (xy 395.775688 -376.790204) (xy 395.775189 -376.821352) (xy 395.767223 -376.883135)
			(xy 395.751422 -376.943393) (xy 395.728044 -377.001136) (xy 395.697475 -377.055415) (xy 395.660215 -377.105339)
			(xy 395.616878 -377.150089) (xy 395.568173 -377.188929) (xy 395.514902 -377.221222) (xy 395.457939 -377.246439)
			(xy 395.398218 -377.264163) (xy 395.336721 -377.274106) (xy 395.274458 -377.276102) (xy 395.212451 -377.27012)
			(xy 395.151717 -377.256258) (xy 395.093255 -377.234744) (xy 395.038024 -377.20593) (xy 394.986932 -377.17029)
			(xy 394.940816 -377.128409) (xy 394.900434 -377.080974) (xy 394.86645 -377.028765) (xy 394.839421 -376.972639)
			(xy 394.819792 -376.913518) (xy 394.807883 -376.852371) (xy 394.803892 -376.790204) (xy 391.375038 -376.790204)
			(xy 391.375038 -376.822922) (xy 391.366255 -376.887766) (xy 391.348848 -376.950845) (xy 391.323133 -377.011016)
			(xy 391.306812 -377.039378) (xy 391.303506 -377.045407) (xy 391.299895 -377.058667) (xy 391.2997 -377.06554)
			(xy 391.2997 -377.35129) (xy 391.299159 -377.361442) (xy 391.291395 -377.380204) (xy 391.277044 -377.394568)
			(xy 391.25829 -377.40235) (xy 391.248138 -377.402852) (xy 390.531858 -377.402852) (xy 390.521696 -377.402401)
			(xy 390.502924 -377.394611) (xy 390.48856 -377.380232) (xy 390.480789 -377.361452) (xy 390.480296 -377.35129)
			(xy 390.480296 -377.06554) (xy 390.480089 -377.058668) (xy 390.476491 -377.045405) (xy 390.473184 -377.039378)
			(xy 390.456864 -377.011015) (xy 390.431143 -376.950845) (xy 390.413733 -376.887767) (xy 390.404949 -376.822922)
			(xy 390.404948 -376.757485) (xy 386.975036 -376.757485) (xy 386.975604 -376.790204) (xy 386.975062 -376.822934)
			(xy 386.966199 -376.887794) (xy 386.948702 -376.950874) (xy 386.922888 -377.011031) (xy 386.906516 -377.039378)
			(xy 386.90321 -377.045407) (xy 386.899599 -377.058667) (xy 386.899404 -377.06554) (xy 386.899404 -377.35129)
			(xy 386.898867 -377.361411) (xy 386.89115 -377.380123) (xy 386.87688 -377.394478) (xy 386.858214 -377.402306)
			(xy 386.848096 -377.402852) (xy 386.131816 -377.402852) (xy 386.121669 -377.402366) (xy 386.102927 -377.394586)
			(xy 386.088605 -377.380209) (xy 386.080896 -377.361438) (xy 386.080508 -377.35129) (xy 386.080508 -377.06554)
			(xy 386.0803 -377.058668) (xy 386.076702 -377.045405) (xy 386.073396 -377.039378) (xy 386.057021 -377.011034)
			(xy 386.031222 -376.950872) (xy 386.013735 -376.887791) (xy 386.004877 -376.822933) (xy 386.004308 -376.790204)
			(xy 382.574966 -376.790204) (xy 382.574966 -376.822922) (xy 382.566181 -376.887767) (xy 382.548771 -376.950846)
			(xy 382.523052 -377.011017) (xy 382.506728 -377.039378) (xy 382.503423 -377.045407) (xy 382.499811 -377.058667)
			(xy 382.499616 -377.06554) (xy 382.499616 -377.35129) (xy 382.499227 -377.361467) (xy 382.491437 -377.38027)
			(xy 382.47704 -377.394657) (xy 382.458231 -377.402434) (xy 382.448054 -377.402852) (xy 381.731774 -377.402852)
			(xy 381.721613 -377.402388) (xy 381.702842 -377.394603) (xy 381.688477 -377.380228) (xy 381.680705 -377.361451)
			(xy 381.680212 -377.35129) (xy 381.680212 -377.06554) (xy 381.680003 -377.058668) (xy 381.676406 -377.045405)
			(xy 381.6731 -377.039378) (xy 381.656782 -377.011014) (xy 381.631067 -376.950843) (xy 381.613659 -376.887765)
			(xy 381.604876 -376.822921) (xy 378.174976 -376.822921) (xy 378.174976 -376.822934) (xy 378.166113 -376.887793)
			(xy 378.148617 -376.950873) (xy 378.122803 -377.011031) (xy 378.106432 -377.039378) (xy 378.103128 -377.045408)
			(xy 378.099515 -377.058668) (xy 378.09932 -377.06554) (xy 378.09932 -377.35129) (xy 378.098864 -377.361421)
			(xy 378.091132 -377.38015) (xy 378.076836 -377.394508) (xy 378.058141 -377.40232) (xy 378.048012 -377.402852)
			(xy 377.331732 -377.402852) (xy 377.321586 -377.402353) (xy 377.302845 -377.394578) (xy 377.288522 -377.380206)
			(xy 377.280812 -377.361437) (xy 377.280424 -377.35129) (xy 377.280424 -377.06554) (xy 377.280214 -377.058668)
			(xy 377.276618 -377.045405) (xy 377.273312 -377.039378) (xy 377.256939 -377.011033) (xy 377.231139 -376.950872)
			(xy 377.213651 -376.887791) (xy 377.204793 -376.822933) (xy 377.204224 -376.790204) (xy 359.904909 -376.790204)
			(xy 359.873568 -378.322797) (xy 375.004914 -378.322797) (xy 375.004917 -378.257358) (xy 375.013704 -378.192512)
			(xy 375.031117 -378.129432) (xy 375.056839 -378.069261) (xy 375.073164 -378.0409) (xy 375.076476 -378.034874)
			(xy 375.080084 -378.021611) (xy 375.080276 -378.014738) (xy 375.080276 -377.728734) (xy 375.080693 -377.71856)
			(xy 375.088474 -377.699759) (xy 375.102862 -377.685371) (xy 375.121664 -377.677592) (xy 375.131838 -377.677172)
			(xy 375.848118 -377.677172) (xy 375.858295 -377.67755) (xy 375.877097 -377.685347) (xy 375.891482 -377.699747)
			(xy 375.89926 -377.718557) (xy 375.89968 -377.728734) (xy 375.89968 -378.014738) (xy 375.899898 -378.021609)
			(xy 375.903489 -378.034872) (xy 375.906792 -378.0409) (xy 375.923091 -378.069274) (xy 375.948809 -378.129442)
			(xy 375.966219 -378.192518) (xy 375.975004 -378.25736) (xy 375.975007 -378.322795) (xy 375.966228 -378.387638)
			(xy 375.948824 -378.450715) (xy 375.923112 -378.510886) (xy 375.906792 -378.539248) (xy 375.90346 -378.545264)
			(xy 375.899865 -378.558534) (xy 375.89968 -378.56541) (xy 375.89968 -379.31471) (xy 375.899871 -379.321583)
			(xy 375.90348 -379.334846) (xy 375.906792 -379.340872) (xy 375.923152 -379.369212) (xy 375.948865 -379.429389)
			(xy 375.966267 -379.492472) (xy 375.975045 -379.55732) (xy 375.97504 -379.622759) (xy 375.966251 -379.687606)
			(xy 375.948838 -379.750686) (xy 375.923116 -379.810858) (xy 375.906792 -379.83922) (xy 375.90347 -379.845241)
			(xy 375.899869 -379.858508) (xy 375.89968 -379.865382) (xy 375.89968 -380.151386) (xy 375.899156 -380.161541)
			(xy 375.891389 -380.180306) (xy 375.877033 -380.194671) (xy 375.858272 -380.202449) (xy 375.848118 -380.202948)
			(xy 375.131838 -380.202948) (xy 375.121667 -380.202505) (xy 375.102871 -380.19473) (xy 375.088484 -380.18035)
			(xy 375.0807 -380.161557) (xy 375.080276 -380.151386) (xy 375.080276 -379.865382) (xy 375.080094 -379.858508)
			(xy 375.076479 -379.845245) (xy 375.073164 -379.83922) (xy 375.05688 -379.810838) (xy 375.031157 -379.750672)
			(xy 375.013744 -379.687597) (xy 375.004955 -379.622756) (xy 375.00495 -379.557323) (xy 375.013728 -379.49248)
			(xy 375.031131 -379.429403) (xy 375.056844 -379.369233) (xy 375.073164 -379.340872) (xy 375.076486 -379.334851)
			(xy 375.080087 -379.321584) (xy 375.080276 -379.31471) (xy 375.080276 -378.56541) (xy 375.080083 -378.558537)
			(xy 375.076476 -378.545274) (xy 375.073164 -378.539248) (xy 375.056819 -378.510899) (xy 375.031102 -378.450725)
			(xy 375.013695 -378.387644) (xy 375.004914 -378.322797) (xy 359.873568 -378.322797) (xy 359.857912 -379.088396)
			(xy 362.932978 -379.088396) (xy 362.937049 -379.032774) (xy 362.949175 -378.978337) (xy 362.969098 -378.926246)
			(xy 362.996394 -378.877611) (xy 363.03048 -378.833468) (xy 363.070629 -378.794759) (xy 363.115987 -378.762308)
			(xy 363.165587 -378.736807) (xy 363.218371 -378.7188) (xy 363.273214 -378.70867) (xy 363.328948 -378.706633)
			(xy 363.384385 -378.712733) (xy 363.438342 -378.726839) (xy 363.489671 -378.748651) (xy 363.537277 -378.777705)
			(xy 363.580145 -378.81338) (xy 363.617362 -378.854917) (xy 363.648135 -378.90143) (xy 363.671807 -378.951927)
			(xy 363.687875 -379.005334) (xy 363.695995 -379.06051) (xy 363.696504 -379.088396) (xy 363.695995 -379.116282)
			(xy 363.687875 -379.171458) (xy 363.671807 -379.224865) (xy 363.648135 -379.275362) (xy 363.617362 -379.321875)
			(xy 363.580145 -379.363412) (xy 363.537277 -379.399087) (xy 363.489671 -379.428141) (xy 363.438342 -379.449953)
			(xy 363.384385 -379.464059) (xy 363.328948 -379.470159) (xy 363.273214 -379.468122) (xy 363.218371 -379.457992)
			(xy 363.165587 -379.439985) (xy 363.115987 -379.414484) (xy 363.070629 -379.382033) (xy 363.03048 -379.343324)
			(xy 362.996394 -379.299181) (xy 362.969098 -379.250546) (xy 362.949175 -379.198455) (xy 362.937049 -379.144018)
			(xy 362.932978 -379.088396) (xy 359.857912 -379.088396) (xy 359.846319 -379.655324) (xy 360.52074 -379.655324)
			(xy 360.524811 -379.599702) (xy 360.536937 -379.545265) (xy 360.55686 -379.493174) (xy 360.584156 -379.444539)
			(xy 360.618242 -379.400396) (xy 360.658391 -379.361687) (xy 360.703749 -379.329236) (xy 360.753349 -379.303735)
			(xy 360.806133 -379.285728) (xy 360.860976 -379.275598) (xy 360.91671 -379.273561) (xy 360.972147 -379.279661)
			(xy 361.026104 -379.293767) (xy 361.077433 -379.315579) (xy 361.125039 -379.344633) (xy 361.167907 -379.380308)
			(xy 361.205124 -379.421845) (xy 361.235897 -379.468358) (xy 361.259569 -379.518855) (xy 361.275637 -379.572262)
			(xy 361.283757 -379.627438) (xy 361.284266 -379.655324) (xy 361.283757 -379.68321) (xy 361.275637 -379.738386)
			(xy 361.259569 -379.791793) (xy 361.235897 -379.84229) (xy 361.205124 -379.888803) (xy 361.167907 -379.93034)
			(xy 361.125039 -379.966015) (xy 361.077433 -379.995069) (xy 361.026104 -380.016881) (xy 360.972147 -380.030987)
			(xy 360.91671 -380.037087) (xy 360.860976 -380.03505) (xy 360.806133 -380.02492) (xy 360.753349 -380.006913)
			(xy 360.703749 -379.981412) (xy 360.658391 -379.948961) (xy 360.618242 -379.910252) (xy 360.584156 -379.866109)
			(xy 360.55686 -379.817474) (xy 360.536937 -379.765383) (xy 360.524811 -379.710946) (xy 360.52074 -379.655324)
			(xy 359.846319 -379.655324) (xy 359.825158 -380.69012) (xy 377.204224 -380.69012) (xy 377.204773 -380.65739)
			(xy 377.213633 -380.592531) (xy 377.231128 -380.529451) (xy 377.256941 -380.469293) (xy 377.273312 -380.440946)
			(xy 377.276611 -380.434914) (xy 377.280226 -380.421656) (xy 377.280424 -380.414784) (xy 377.280424 -379.665484)
			(xy 377.280235 -379.658611) (xy 377.276624 -379.645348) (xy 377.273312 -379.639322) (xy 377.256956 -379.610967)
			(xy 377.231152 -379.55081) (xy 377.213659 -379.487732) (xy 377.204796 -379.422877) (xy 377.204224 -379.390148)
			(xy 377.204786 -379.357418) (xy 377.213642 -379.29256) (xy 377.231134 -379.22948) (xy 377.256943 -379.169322)
			(xy 377.273312 -379.140974) (xy 377.276637 -379.134954) (xy 377.280236 -379.121687) (xy 377.280424 -379.114812)
			(xy 377.280424 -378.828554) (xy 377.280888 -378.818426) (xy 377.288628 -378.799707) (xy 377.302921 -378.785353)
			(xy 377.321607 -378.777533) (xy 377.331732 -378.776992) (xy 378.048012 -378.776992) (xy 378.058166 -378.777411)
			(xy 378.076917 -378.785209) (xy 378.09124 -378.799607) (xy 378.098941 -378.818398) (xy 378.09932 -378.828554)
			(xy 378.09932 -379.114812) (xy 378.099505 -379.121686) (xy 378.103118 -379.134949) (xy 378.106432 -379.140974)
			(xy 378.122781 -379.169333) (xy 378.148588 -379.229488) (xy 378.166083 -379.292565) (xy 378.174948 -379.35742)
			(xy 378.17552 -379.390148) (xy 378.17495 -379.422877) (xy 378.166095 -379.487735) (xy 378.148606 -379.550815)
			(xy 378.131777 -379.590046) (xy 379.404372 -379.590046) (xy 379.40494 -379.557317) (xy 379.413795 -379.492458)
			(xy 379.431285 -379.429378) (xy 379.457092 -379.36922) (xy 379.47346 -379.340872) (xy 379.476781 -379.334851)
			(xy 379.480383 -379.321584) (xy 379.480572 -379.31471) (xy 379.480572 -378.56541) (xy 379.48038 -378.558537)
			(xy 379.476772 -378.545274) (xy 379.47346 -378.539248) (xy 379.457079 -378.510907) (xy 379.43128 -378.450745)
			(xy 379.413794 -378.387663) (xy 379.404939 -378.322804) (xy 379.404372 -378.290074) (xy 379.404953 -378.257345)
			(xy 379.413805 -378.192487) (xy 379.431291 -378.129407) (xy 379.457094 -378.069249) (xy 379.47346 -378.0409)
			(xy 379.476771 -378.034874) (xy 379.48038 -378.021611) (xy 379.480572 -378.014738) (xy 379.480572 -377.728734)
			(xy 379.481056 -377.718606) (xy 379.488778 -377.699879) (xy 379.503066 -377.685521) (xy 379.521754 -377.677706)
			(xy 379.53188 -377.677172) (xy 380.24816 -377.677172) (xy 380.258308 -377.677654) (xy 380.277054 -377.685431)
			(xy 380.291378 -377.699809) (xy 380.299084 -377.718584) (xy 380.299468 -377.728734) (xy 380.299468 -378.014738)
			(xy 380.299687 -378.021609) (xy 380.303277 -378.034872) (xy 380.30658 -378.0409) (xy 380.322944 -378.06925)
			(xy 380.348746 -378.129409) (xy 380.366237 -378.192488) (xy 380.375097 -378.257345) (xy 380.375668 -378.290074)
			(xy 380.375104 -378.322797) (xy 383.805 -378.322797) (xy 383.805003 -378.257358) (xy 383.81379 -378.192512)
			(xy 383.831202 -378.129433) (xy 383.856924 -378.069261) (xy 383.873248 -378.0409) (xy 383.876559 -378.034873)
			(xy 383.880167 -378.021611) (xy 383.88036 -378.014738) (xy 383.88036 -377.728734) (xy 383.880792 -377.718562)
			(xy 383.88857 -377.699764) (xy 383.902954 -377.685377) (xy 383.92175 -377.677595) (xy 383.931922 -377.677172)
			(xy 384.648202 -377.677172) (xy 384.658378 -377.677563) (xy 384.677179 -377.685355) (xy 384.691565 -377.699751)
			(xy 384.699344 -377.718558) (xy 384.699764 -377.728734) (xy 384.699764 -378.014738) (xy 384.699984 -378.021609)
			(xy 384.703574 -378.034872) (xy 384.706876 -378.0409) (xy 384.723176 -378.069274) (xy 384.748895 -378.129442)
			(xy 384.766305 -378.192518) (xy 384.775091 -378.25736) (xy 384.775094 -378.322795) (xy 384.775094 -378.322797)
			(xy 388.20479 -378.322797) (xy 388.204793 -378.257358) (xy 388.21358 -378.192513) (xy 388.230991 -378.129433)
			(xy 388.256712 -378.069261) (xy 388.273036 -378.0409) (xy 388.276346 -378.034873) (xy 388.279955 -378.021611)
			(xy 388.280148 -378.014738) (xy 388.280148 -377.728734) (xy 388.280592 -377.718563) (xy 388.288368 -377.699768)
			(xy 388.302747 -377.685381) (xy 388.32154 -377.677597) (xy 388.33171 -377.677172) (xy 389.04799 -377.677172)
			(xy 389.058165 -377.677573) (xy 389.076966 -377.685361) (xy 389.091353 -377.699754) (xy 389.099132 -377.718559)
			(xy 389.099552 -377.728734) (xy 389.099552 -378.014738) (xy 389.099761 -378.02161) (xy 389.103357 -378.034873)
			(xy 389.106664 -378.0409) (xy 389.122964 -378.069273) (xy 389.148684 -378.129442) (xy 389.166094 -378.192518)
			(xy 389.17488 -378.25736) (xy 389.174881 -378.290074) (xy 392.603744 -378.290074) (xy 392.607735 -378.227907)
			(xy 392.619644 -378.16676) (xy 392.639273 -378.107639) (xy 392.666302 -378.051513) (xy 392.700286 -377.999304)
			(xy 392.740668 -377.951869) (xy 392.786784 -377.909988) (xy 392.837876 -377.874348) (xy 392.893107 -377.845534)
			(xy 392.951569 -377.82402) (xy 393.012303 -377.810158) (xy 393.07431 -377.804176) (xy 393.136573 -377.806172)
			(xy 393.19807 -377.816115) (xy 393.257791 -377.833839) (xy 393.314754 -377.859056) (xy 393.368025 -377.891349)
			(xy 393.41673 -377.930189) (xy 393.460067 -377.974939) (xy 393.497327 -378.024863) (xy 393.527896 -378.079142)
			(xy 393.551274 -378.136885) (xy 393.567075 -378.197143) (xy 393.575041 -378.258926) (xy 393.57554 -378.290074)
			(xy 393.575041 -378.321222) (xy 393.567075 -378.383005) (xy 393.551274 -378.443263) (xy 393.527896 -378.501006)
			(xy 393.497327 -378.555285) (xy 393.460067 -378.605209) (xy 393.41673 -378.649959) (xy 393.368025 -378.688799)
			(xy 393.314754 -378.721092) (xy 393.257791 -378.746309) (xy 393.19807 -378.764033) (xy 393.136573 -378.773976)
			(xy 393.07431 -378.775972) (xy 393.012303 -378.76999) (xy 392.951569 -378.756128) (xy 392.893107 -378.734614)
			(xy 392.837876 -378.7058) (xy 392.786784 -378.67016) (xy 392.740668 -378.628279) (xy 392.700286 -378.580844)
			(xy 392.666302 -378.528635) (xy 392.639273 -378.472509) (xy 392.619644 -378.413388) (xy 392.607735 -378.352241)
			(xy 392.603744 -378.290074) (xy 389.174881 -378.290074) (xy 389.174883 -378.322795) (xy 389.166103 -378.387638)
			(xy 389.148698 -378.450716) (xy 389.122984 -378.510887) (xy 389.106664 -378.539248) (xy 389.103337 -378.545267)
			(xy 389.099738 -378.558535) (xy 389.099552 -378.56541) (xy 389.099552 -379.31471) (xy 389.099734 -379.321584)
			(xy 389.103348 -379.334847) (xy 389.106664 -379.340872) (xy 389.123025 -379.369212) (xy 389.148739 -379.429388)
			(xy 389.166143 -379.492471) (xy 389.174921 -379.55732) (xy 389.174916 -379.622759) (xy 389.166127 -379.687606)
			(xy 389.148713 -379.750687) (xy 389.122989 -379.810859) (xy 389.106664 -379.83922) (xy 389.103347 -379.845244)
			(xy 389.099742 -379.858508) (xy 389.099552 -379.865382) (xy 389.099552 -380.151386) (xy 389.099125 -380.161558)
			(xy 389.091342 -380.180354) (xy 389.076958 -380.19474) (xy 389.058162 -380.202524) (xy 389.04799 -380.202948)
			(xy 388.33171 -380.202948) (xy 388.321537 -380.202528) (xy 388.30274 -380.194743) (xy 388.288354 -380.180357)
			(xy 388.280571 -380.161559) (xy 388.280148 -380.151386) (xy 388.280148 -379.865382) (xy 388.279969 -379.858508)
			(xy 388.276353 -379.845245) (xy 388.273036 -379.83922) (xy 388.256753 -379.810837) (xy 388.231032 -379.750671)
			(xy 388.213619 -379.687597) (xy 388.204831 -379.622756) (xy 388.204826 -379.557323) (xy 388.213604 -379.492481)
			(xy 388.231006 -379.429404) (xy 388.256717 -379.369233) (xy 388.273036 -379.340872) (xy 388.276356 -379.33485)
			(xy 388.279959 -379.321584) (xy 388.280148 -379.31471) (xy 388.280148 -378.56541) (xy 388.279959 -378.558536)
			(xy 388.276349 -378.545273) (xy 388.273036 -378.539248) (xy 388.256692 -378.510899) (xy 388.230976 -378.450725)
			(xy 388.213571 -378.387644) (xy 388.20479 -378.322797) (xy 384.775094 -378.322797) (xy 384.766314 -378.387638)
			(xy 384.748909 -378.450716) (xy 384.723196 -378.510887) (xy 384.706876 -378.539248) (xy 384.703543 -378.545263)
			(xy 384.699949 -378.558534) (xy 384.699764 -378.56541) (xy 384.699764 -379.31471) (xy 384.699957 -379.321583)
			(xy 384.703565 -379.334846) (xy 384.706876 -379.340872) (xy 384.723237 -379.369212) (xy 384.74895 -379.429388)
			(xy 384.766353 -379.492471) (xy 384.775132 -379.55732) (xy 384.775126 -379.622759) (xy 384.766337 -379.687606)
			(xy 384.748924 -379.750686) (xy 384.723201 -379.810859) (xy 384.706876 -379.83922) (xy 384.703552 -379.84524)
			(xy 384.699953 -379.858507) (xy 384.699764 -379.865382) (xy 384.699764 -380.151386) (xy 384.699325 -380.161556)
			(xy 384.691545 -380.180351) (xy 384.677164 -380.194736) (xy 384.658372 -380.202522) (xy 384.648202 -380.202948)
			(xy 383.931922 -380.202948) (xy 383.92175 -380.202518) (xy 383.902953 -380.194737) (xy 383.888567 -380.180353)
			(xy 383.880784 -380.161558) (xy 383.88036 -380.151386) (xy 383.88036 -379.865382) (xy 383.88018 -379.858508)
			(xy 383.876564 -379.845245) (xy 383.873248 -379.83922) (xy 383.856964 -379.810837) (xy 383.831243 -379.750671)
			(xy 383.81383 -379.687597) (xy 383.805041 -379.622756) (xy 383.805036 -379.557323) (xy 383.813814 -379.49248)
			(xy 383.831217 -379.429403) (xy 383.856929 -379.369233) (xy 383.873248 -379.340872) (xy 383.876569 -379.33485)
			(xy 383.880171 -379.321584) (xy 383.88036 -379.31471) (xy 383.88036 -378.56541) (xy 383.880169 -378.558537)
			(xy 383.876561 -378.545274) (xy 383.873248 -378.539248) (xy 383.856903 -378.510899) (xy 383.831187 -378.450725)
			(xy 383.813781 -378.387644) (xy 383.805 -378.322797) (xy 380.375104 -378.322797) (xy 380.375104 -378.322803)
			(xy 380.366246 -378.387661) (xy 380.348755 -378.450741) (xy 380.322948 -378.5109) (xy 380.30658 -378.539248)
			(xy 380.303247 -378.545264) (xy 380.299653 -378.558534) (xy 380.299468 -378.56541) (xy 380.299468 -379.31471)
			(xy 380.29966 -379.321583) (xy 380.303269 -379.334846) (xy 380.30658 -379.340872) (xy 380.322933 -379.369228)
			(xy 380.348738 -379.429385) (xy 380.366231 -379.492462) (xy 380.375096 -379.557318) (xy 380.375668 -379.590046)
			(xy 380.375091 -379.622775) (xy 380.366237 -379.687633) (xy 380.34875 -379.750713) (xy 380.322947 -379.810871)
			(xy 380.30658 -379.83922) (xy 380.303257 -379.84524) (xy 380.299657 -379.858507) (xy 380.299468 -379.865382)
			(xy 380.299468 -380.151386) (xy 380.298962 -380.161511) (xy 380.291241 -380.18023) (xy 380.27696 -380.194587)
			(xy 380.258282 -380.202408) (xy 380.24816 -380.202948) (xy 379.53188 -380.202948) (xy 379.521731 -380.202496)
			(xy 379.502987 -380.194703) (xy 379.488666 -380.180316) (xy 379.480958 -380.161537) (xy 379.480572 -380.151386)
			(xy 379.480572 -379.865382) (xy 379.48039 -379.858508) (xy 379.476775 -379.845245) (xy 379.47346 -379.83922)
			(xy 379.457108 -379.810863) (xy 379.431302 -379.750707) (xy 379.413808 -379.68763) (xy 379.404944 -379.622774)
			(xy 379.404372 -379.590046) (xy 378.131777 -379.590046) (xy 378.1228 -379.610974) (xy 378.106432 -379.639322)
			(xy 378.103112 -379.645344) (xy 378.099509 -379.65861) (xy 378.09932 -379.665484) (xy 378.09932 -380.414784)
			(xy 378.099516 -380.421657) (xy 378.103121 -380.43492) (xy 378.106432 -380.440946) (xy 378.122809 -380.469289)
			(xy 378.14861 -380.52945) (xy 378.166097 -380.592532) (xy 378.174952 -380.65739) (xy 378.174952 -380.6574)
			(xy 381.604883 -380.6574) (xy 381.613663 -380.592557) (xy 381.631067 -380.529479) (xy 381.65678 -380.469308)
			(xy 381.6731 -380.440946) (xy 381.676398 -380.434913) (xy 381.680014 -380.421656) (xy 381.680212 -380.414784)
			(xy 381.680212 -379.665484) (xy 381.680025 -379.65861) (xy 381.676413 -379.645348) (xy 381.6731 -379.639322)
			(xy 381.65682 -379.610938) (xy 381.6311 -379.550772) (xy 381.613689 -379.487698) (xy 381.604901 -379.422858)
			(xy 381.604896 -379.357425) (xy 381.613673 -379.292583) (xy 381.631073 -379.229506) (xy 381.656782 -379.169336)
			(xy 381.6731 -379.140974) (xy 381.676424 -379.134954) (xy 381.680024 -379.121687) (xy 381.680212 -379.114812)
			(xy 381.680212 -378.828554) (xy 381.680695 -378.818397) (xy 381.68848 -378.799631) (xy 381.702848 -378.785269)
			(xy 381.721616 -378.777491) (xy 381.731774 -378.776992) (xy 382.448054 -378.776992) (xy 382.458203 -378.77757)
			(xy 382.476962 -378.785321) (xy 382.491328 -378.79966) (xy 382.499112 -378.818406) (xy 382.499616 -378.828554)
			(xy 382.499616 -379.114812) (xy 382.499801 -379.121686) (xy 382.503414 -379.134949) (xy 382.506728 -379.140974)
			(xy 382.523092 -379.169312) (xy 382.548807 -379.229489) (xy 382.566212 -379.292572) (xy 382.574991 -379.357421)
			(xy 382.574986 -379.422861) (xy 382.566196 -379.487709) (xy 382.54878 -379.550789) (xy 382.523054 -379.610961)
			(xy 382.506728 -379.639322) (xy 382.503407 -379.645344) (xy 382.499805 -379.65861) (xy 382.499616 -379.665484)
			(xy 382.499616 -380.414784) (xy 382.499812 -380.421657) (xy 382.503417 -380.43492) (xy 382.506728 -380.440946)
			(xy 382.523068 -380.469298) (xy 382.548786 -380.529471) (xy 382.566193 -380.592551) (xy 382.574975 -380.657398)
			(xy 382.574974 -380.69012) (xy 386.004308 -380.69012) (xy 386.004859 -380.65739) (xy 386.013719 -380.592531)
			(xy 386.031214 -380.529451) (xy 386.057026 -380.469294) (xy 386.073396 -380.440946) (xy 386.076694 -380.434913)
			(xy 386.08031 -380.421656) (xy 386.080508 -380.414784) (xy 386.080508 -379.665484) (xy 386.080321 -379.65861)
			(xy 386.076709 -379.645348) (xy 386.073396 -379.639322) (xy 386.057039 -379.610968) (xy 386.031235 -379.55081)
			(xy 386.013743 -379.487732) (xy 386.00488 -379.422877) (xy 386.004308 -379.390148) (xy 386.004872 -379.357418)
			(xy 386.013728 -379.29256) (xy 386.031219 -379.22948) (xy 386.057027 -379.169322) (xy 386.073396 -379.140974)
			(xy 386.07672 -379.134954) (xy 386.08032 -379.121687) (xy 386.080508 -379.114812) (xy 386.080508 -378.828554)
			(xy 386.080988 -378.818428) (xy 386.088725 -378.799712) (xy 386.103012 -378.785359) (xy 386.121693 -378.777535)
			(xy 386.131816 -378.776992) (xy 386.848096 -378.776992) (xy 386.858249 -378.777425) (xy 386.877 -378.785218)
			(xy 386.891323 -378.799611) (xy 386.899024 -378.818399) (xy 386.899404 -378.828554) (xy 386.899404 -379.114812)
			(xy 386.899591 -379.121686) (xy 386.903202 -379.134948) (xy 386.906516 -379.140974) (xy 386.922873 -379.169328)
			(xy 386.948676 -379.229486) (xy 386.966168 -379.292564) (xy 386.975032 -379.357419) (xy 386.975604 -379.390148)
			(xy 386.975037 -379.422877) (xy 386.966181 -379.487736) (xy 386.948691 -379.550816) (xy 386.922884 -379.610974)
			(xy 386.906516 -379.639322) (xy 386.903195 -379.645343) (xy 386.899593 -379.65861) (xy 386.899404 -379.665484)
			(xy 386.899404 -380.414784) (xy 386.899602 -380.421657) (xy 386.903206 -380.43492) (xy 386.906516 -380.440946)
			(xy 386.922901 -380.469284) (xy 386.948698 -380.529448) (xy 386.966182 -380.592531) (xy 386.975037 -380.65739)
			(xy 386.975037 -380.657399) (xy 390.404955 -380.657399) (xy 390.413737 -380.592555) (xy 390.431144 -380.529477)
			(xy 390.456862 -380.469307) (xy 390.473184 -380.440946) (xy 390.476481 -380.434913) (xy 390.480098 -380.421656)
			(xy 390.480296 -380.414784) (xy 390.480296 -379.665484) (xy 390.480111 -379.65861) (xy 390.476498 -379.645347)
			(xy 390.473184 -379.639322) (xy 390.456901 -379.610939) (xy 390.431177 -379.550773) (xy 390.413763 -379.487699)
			(xy 390.404974 -379.422858) (xy 390.404968 -379.357424) (xy 390.413746 -379.292582) (xy 390.43115 -379.229505)
			(xy 390.456864 -379.169335) (xy 390.473184 -379.140974) (xy 390.476507 -379.134953) (xy 390.480108 -379.121687)
			(xy 390.480296 -379.114812) (xy 390.480296 -378.828554) (xy 390.480795 -378.818398) (xy 390.488576 -378.799636)
			(xy 390.50294 -378.785274) (xy 390.521702 -378.777494) (xy 390.531858 -378.776992) (xy 391.248138 -378.776992)
			(xy 391.258293 -378.777501) (xy 391.277054 -378.785279) (xy 391.291416 -378.79964) (xy 391.299197 -378.8184)
			(xy 391.2997 -378.828554) (xy 391.2997 -379.114812) (xy 391.299887 -379.121686) (xy 391.303499 -379.134948)
			(xy 391.306812 -379.140974) (xy 391.323173 -379.169313) (xy 391.348884 -379.22949) (xy 391.366286 -379.292573)
			(xy 391.375064 -379.357421) (xy 391.375058 -379.422861) (xy 391.36627 -379.487707) (xy 391.348857 -379.550788)
			(xy 391.332076 -379.590046) (xy 392.603744 -379.590046) (xy 392.607735 -379.527879) (xy 392.619644 -379.466732)
			(xy 392.639273 -379.407611) (xy 392.666302 -379.351485) (xy 392.700286 -379.299276) (xy 392.740668 -379.251841)
			(xy 392.786784 -379.20996) (xy 392.837876 -379.17432) (xy 392.893107 -379.145506) (xy 392.951569 -379.123992)
			(xy 393.012303 -379.11013) (xy 393.07431 -379.104148) (xy 393.136573 -379.106144) (xy 393.19807 -379.116087)
			(xy 393.257791 -379.133811) (xy 393.314754 -379.159028) (xy 393.368025 -379.191321) (xy 393.41673 -379.230161)
			(xy 393.460067 -379.274911) (xy 393.497327 -379.324835) (xy 393.527896 -379.379114) (xy 393.532363 -379.390148)
			(xy 394.803892 -379.390148) (xy 394.807883 -379.327981) (xy 394.819792 -379.266834) (xy 394.839421 -379.207713)
			(xy 394.86645 -379.151587) (xy 394.900434 -379.099378) (xy 394.940816 -379.051943) (xy 394.986932 -379.010062)
			(xy 395.038024 -378.974422) (xy 395.093255 -378.945608) (xy 395.151717 -378.924094) (xy 395.212451 -378.910232)
			(xy 395.274458 -378.90425) (xy 395.336721 -378.906246) (xy 395.398218 -378.916189) (xy 395.457939 -378.933913)
			(xy 395.514902 -378.95913) (xy 395.568173 -378.991423) (xy 395.616878 -379.030263) (xy 395.660215 -379.075013)
			(xy 395.697475 -379.124937) (xy 395.728044 -379.179216) (xy 395.751422 -379.236959) (xy 395.767223 -379.297217)
			(xy 395.775189 -379.359) (xy 395.775688 -379.390148) (xy 395.775189 -379.421296) (xy 395.767223 -379.483079)
			(xy 395.751422 -379.543337) (xy 395.728044 -379.60108) (xy 395.697475 -379.655359) (xy 395.660215 -379.705283)
			(xy 395.616878 -379.750033) (xy 395.568173 -379.788873) (xy 395.514902 -379.821166) (xy 395.457939 -379.846383)
			(xy 395.398218 -379.864107) (xy 395.336721 -379.87405) (xy 395.274458 -379.876046) (xy 395.212451 -379.870064)
			(xy 395.151717 -379.856202) (xy 395.093255 -379.834688) (xy 395.038024 -379.805874) (xy 394.986932 -379.770234)
			(xy 394.940816 -379.728353) (xy 394.900434 -379.680918) (xy 394.86645 -379.628709) (xy 394.839421 -379.572583)
			(xy 394.819792 -379.513462) (xy 394.807883 -379.452315) (xy 394.803892 -379.390148) (xy 393.532363 -379.390148)
			(xy 393.551274 -379.436857) (xy 393.567075 -379.497115) (xy 393.575041 -379.558898) (xy 393.57554 -379.590046)
			(xy 393.575041 -379.621194) (xy 393.567075 -379.682977) (xy 393.551274 -379.743235) (xy 393.527896 -379.800978)
			(xy 393.497327 -379.855257) (xy 393.460067 -379.905181) (xy 393.41673 -379.949931) (xy 393.368025 -379.988771)
			(xy 393.314754 -380.021064) (xy 393.257791 -380.046281) (xy 393.19807 -380.064005) (xy 393.136573 -380.073948)
			(xy 393.07431 -380.075944) (xy 393.012303 -380.069962) (xy 392.951569 -380.0561) (xy 392.893107 -380.034586)
			(xy 392.837876 -380.005772) (xy 392.786784 -379.970132) (xy 392.740668 -379.928251) (xy 392.700286 -379.880816)
			(xy 392.666302 -379.828607) (xy 392.639273 -379.772481) (xy 392.619644 -379.71336) (xy 392.607735 -379.652213)
			(xy 392.603744 -379.590046) (xy 391.332076 -379.590046) (xy 391.323136 -379.61096) (xy 391.306812 -379.639322)
			(xy 391.30349 -379.645343) (xy 391.299889 -379.65861) (xy 391.2997 -379.665484) (xy 391.2997 -380.414784)
			(xy 391.299898 -380.421657) (xy 391.303502 -380.43492) (xy 391.306812 -380.440946) (xy 391.32315 -380.469298)
			(xy 391.348863 -380.529472) (xy 391.366267 -380.592553) (xy 391.375048 -380.657398) (xy 391.375046 -380.69012)
			(xy 394.803892 -380.69012) (xy 394.807883 -380.627953) (xy 394.819792 -380.566806) (xy 394.839421 -380.507685)
			(xy 394.86645 -380.451559) (xy 394.900434 -380.39935) (xy 394.940816 -380.351915) (xy 394.986932 -380.310034)
			(xy 395.038024 -380.274394) (xy 395.093255 -380.24558) (xy 395.151717 -380.224066) (xy 395.212451 -380.210204)
			(xy 395.274458 -380.204222) (xy 395.336721 -380.206218) (xy 395.398218 -380.216161) (xy 395.457939 -380.233885)
			(xy 395.514902 -380.259102) (xy 395.568173 -380.291395) (xy 395.616878 -380.330235) (xy 395.660215 -380.374985)
			(xy 395.697475 -380.424909) (xy 395.728044 -380.479188) (xy 395.751422 -380.536931) (xy 395.767223 -380.597189)
			(xy 395.775189 -380.658972) (xy 395.775688 -380.69012) (xy 395.775189 -380.721268) (xy 395.767223 -380.783051)
			(xy 395.751422 -380.843309) (xy 395.728044 -380.901052) (xy 395.697475 -380.955331) (xy 395.660215 -381.005255)
			(xy 395.616878 -381.050005) (xy 395.568173 -381.088845) (xy 395.514902 -381.121138) (xy 395.457939 -381.146355)
			(xy 395.398218 -381.164079) (xy 395.336721 -381.174022) (xy 395.274458 -381.176018) (xy 395.212451 -381.170036)
			(xy 395.151717 -381.156174) (xy 395.093255 -381.13466) (xy 395.038024 -381.105846) (xy 394.986932 -381.070206)
			(xy 394.940816 -381.028325) (xy 394.900434 -380.98089) (xy 394.86645 -380.928681) (xy 394.839421 -380.872555)
			(xy 394.819792 -380.813434) (xy 394.807883 -380.752287) (xy 394.803892 -380.69012) (xy 391.375046 -380.69012)
			(xy 391.375045 -380.722836) (xy 391.36626 -380.787681) (xy 391.348852 -380.85076) (xy 391.323134 -380.910932)
			(xy 391.306812 -380.939294) (xy 391.3035 -380.94532) (xy 391.299892 -380.958583) (xy 391.2997 -380.965456)
			(xy 391.2997 -381.251206) (xy 391.299172 -381.261359) (xy 391.291403 -381.280121) (xy 391.277048 -381.294485)
			(xy 391.258291 -381.302266) (xy 391.248138 -381.302768) (xy 390.531858 -381.302768) (xy 390.521698 -381.302301)
			(xy 390.502929 -381.294514) (xy 390.488566 -381.28014) (xy 390.480792 -381.261366) (xy 390.480296 -381.251206)
			(xy 390.480296 -380.965456) (xy 390.480083 -380.958584) (xy 390.476489 -380.945322) (xy 390.473184 -380.939294)
			(xy 390.456877 -380.910924) (xy 390.431156 -380.850755) (xy 390.413744 -380.787678) (xy 390.404958 -380.722835)
			(xy 390.404955 -380.657399) (xy 386.975037 -380.657399) (xy 386.975604 -380.69012) (xy 386.975024 -380.722849)
			(xy 386.966172 -380.787707) (xy 386.948686 -380.850787) (xy 386.922883 -380.910945) (xy 386.906516 -380.939294)
			(xy 386.903205 -380.94532) (xy 386.899597 -380.958583) (xy 386.899404 -380.965456) (xy 386.899404 -381.251206)
			(xy 386.89888 -381.261328) (xy 386.891158 -381.280041) (xy 386.876884 -381.294395) (xy 386.858215 -381.302222)
			(xy 386.848096 -381.302768) (xy 386.131816 -381.302768) (xy 386.121659 -381.302365) (xy 386.102901 -381.294568)
			(xy 386.088576 -381.280166) (xy 386.080881 -381.261365) (xy 386.080508 -381.251206) (xy 386.080508 -380.965456)
			(xy 386.080293 -380.958584) (xy 386.0767 -380.945322) (xy 386.073396 -380.939294) (xy 386.057028 -380.910946)
			(xy 386.031227 -380.850786) (xy 386.013738 -380.787706) (xy 386.004878 -380.722849) (xy 386.004308 -380.69012)
			(xy 382.574974 -380.69012) (xy 382.574973 -380.722836) (xy 382.566187 -380.787682) (xy 382.548775 -380.850762)
			(xy 382.523053 -380.910933) (xy 382.506728 -380.939294) (xy 382.503417 -380.945321) (xy 382.499809 -380.958583)
			(xy 382.499616 -380.965456) (xy 382.499616 -381.251206) (xy 382.49924 -381.261384) (xy 382.491444 -381.280187)
			(xy 382.477044 -381.294574) (xy 382.458232 -381.30235) (xy 382.448054 -381.302768) (xy 381.731774 -381.302768)
			(xy 381.721615 -381.302288) (xy 381.702847 -381.294506) (xy 381.688482 -381.280137) (xy 381.680708 -381.261365)
			(xy 381.680212 -381.251206) (xy 381.680212 -380.965456) (xy 381.679997 -380.958584) (xy 381.676404 -380.945322)
			(xy 381.6731 -380.939294) (xy 381.656796 -380.910923) (xy 381.631079 -380.850754) (xy 381.61367 -380.787677)
			(xy 381.604885 -380.722835) (xy 381.604883 -380.6574) (xy 378.174952 -380.6574) (xy 378.17552 -380.69012)
			(xy 378.174938 -380.722849) (xy 378.166087 -380.787706) (xy 378.148601 -380.850787) (xy 378.122798 -380.910945)
			(xy 378.106432 -380.939294) (xy 378.103122 -380.945321) (xy 378.099513 -380.958583) (xy 378.09932 -380.965456)
			(xy 378.09932 -381.251206) (xy 378.098877 -381.261338) (xy 378.09114 -381.280067) (xy 378.07684 -381.294424)
			(xy 378.058142 -381.302236) (xy 378.048012 -381.302768) (xy 377.331732 -381.302768) (xy 377.321576 -381.302352)
			(xy 377.302818 -381.294561) (xy 377.288492 -381.280162) (xy 377.280797 -381.261364) (xy 377.280424 -381.251206)
			(xy 377.280424 -380.965456) (xy 377.280208 -380.958585) (xy 377.276616 -380.945322) (xy 377.273312 -380.939294)
			(xy 377.256945 -380.910945) (xy 377.231143 -380.850786) (xy 377.213654 -380.787706) (xy 377.204794 -380.722849)
			(xy 377.204224 -380.69012) (xy 359.825158 -380.69012) (xy 359.80421 -381.714502) (xy 360.796838 -381.714502)
			(xy 360.800909 -381.65888) (xy 360.813035 -381.604443) (xy 360.832958 -381.552352) (xy 360.860254 -381.503717)
			(xy 360.89434 -381.459574) (xy 360.934489 -381.420865) (xy 360.979847 -381.388414) (xy 361.029447 -381.362913)
			(xy 361.082231 -381.344906) (xy 361.137074 -381.334776) (xy 361.192808 -381.332739) (xy 361.248245 -381.338839)
			(xy 361.302202 -381.352945) (xy 361.353531 -381.374757) (xy 361.401137 -381.403811) (xy 361.444005 -381.439486)
			(xy 361.481222 -381.481023) (xy 361.511995 -381.527536) (xy 361.535667 -381.578033) (xy 361.551735 -381.63144)
			(xy 361.559855 -381.686616) (xy 361.560364 -381.714502) (xy 361.559855 -381.742388) (xy 361.551735 -381.797564)
			(xy 361.535667 -381.850971) (xy 361.511995 -381.901468) (xy 361.481222 -381.947981) (xy 361.444005 -381.989518)
			(xy 361.401137 -382.025193) (xy 361.353531 -382.054247) (xy 361.302202 -382.076059) (xy 361.248245 -382.090165)
			(xy 361.192808 -382.096265) (xy 361.137074 -382.094228) (xy 361.082231 -382.084098) (xy 361.029447 -382.066091)
			(xy 360.979847 -382.04059) (xy 360.934489 -382.008139) (xy 360.89434 -381.96943) (xy 360.860254 -381.925287)
			(xy 360.832958 -381.876652) (xy 360.813035 -381.824561) (xy 360.800909 -381.770124) (xy 360.796838 -381.714502)
			(xy 359.80421 -381.714502) (xy 359.793817 -382.22271) (xy 375.004923 -382.22271) (xy 375.004924 -382.157273)
			(xy 375.01371 -382.092427) (xy 375.03112 -382.029348) (xy 375.05684 -381.969177) (xy 375.073164 -381.940816)
			(xy 375.07647 -381.934787) (xy 375.080082 -381.921527) (xy 375.080276 -381.914654) (xy 375.080276 -381.628904)
			(xy 375.080724 -381.618753) (xy 375.088514 -381.600005) (xy 375.102902 -381.585683) (xy 375.121685 -381.577979)
			(xy 375.131838 -381.577596) (xy 375.848118 -381.577596) (xy 375.85824 -381.57811) (xy 375.876954 -381.585836)
			(xy 375.891308 -381.600113) (xy 375.899134 -381.618784) (xy 375.89968 -381.628904) (xy 375.89968 -381.914654)
			(xy 375.899892 -381.921526) (xy 375.903487 -381.934788) (xy 375.906792 -381.940816) (xy 375.923105 -381.969182)
			(xy 375.948822 -382.029353) (xy 375.966229 -382.09243) (xy 375.975013 -382.157274) (xy 375.975015 -382.222709)
			(xy 375.966233 -382.287553) (xy 375.948827 -382.350631) (xy 375.923113 -382.410802) (xy 375.906792 -382.439164)
			(xy 375.903489 -382.445195) (xy 375.899876 -382.458454) (xy 375.89968 -382.465326) (xy 375.89968 -383.21488)
			(xy 375.899882 -383.221752) (xy 375.903484 -383.235015) (xy 375.906792 -383.241042) (xy 375.923127 -383.269396)
			(xy 375.948842 -383.329569) (xy 375.966247 -383.392649) (xy 375.975028 -383.457495) (xy 375.975026 -383.522932)
			(xy 375.966241 -383.587777) (xy 375.948832 -383.650857) (xy 375.923114 -383.711028) (xy 375.906792 -383.73939)
			(xy 375.90348 -383.745416) (xy 375.899873 -383.758679) (xy 375.89968 -383.765552) (xy 375.89968 -384.051556)
			(xy 375.899242 -384.06171) (xy 375.891457 -384.080465) (xy 375.877065 -384.094791) (xy 375.858274 -384.102488)
			(xy 375.848118 -384.102864) (xy 375.131838 -384.102864) (xy 375.121714 -384.102342) (xy 375.102995 -384.094628)
			(xy 375.088637 -384.080352) (xy 375.080816 -384.061677) (xy 375.080276 -384.051556) (xy 375.080276 -383.765552)
			(xy 375.080067 -383.75868) (xy 375.076471 -383.745417) (xy 375.073164 -383.73939) (xy 375.056855 -383.711022)
			(xy 375.031134 -383.650852) (xy 375.013724 -383.587775) (xy 375.004938 -383.522932) (xy 375.004936 -383.457496)
			(xy 375.013718 -383.392652) (xy 375.031125 -383.329574) (xy 375.056842 -383.269403) (xy 375.073164 -383.241042)
			(xy 375.076461 -383.235009) (xy 375.080078 -383.221752) (xy 375.080276 -383.21488) (xy 375.080276 -382.465326)
			(xy 375.080077 -382.458453) (xy 375.076474 -382.44519) (xy 375.073164 -382.439164) (xy 375.056833 -382.410808)
			(xy 375.031114 -382.350636) (xy 375.013706 -382.287556) (xy 375.004923 -382.22271) (xy 359.793817 -382.22271)
			(xy 359.745407 -384.590036) (xy 377.204224 -384.590036) (xy 377.20478 -384.557306) (xy 377.213638 -384.492447)
			(xy 377.231131 -384.429367) (xy 377.256942 -384.36921) (xy 377.273312 -384.340862) (xy 377.276641 -384.334844)
			(xy 377.280237 -384.321575) (xy 377.280424 -384.3147) (xy 377.280424 -383.5654) (xy 377.280229 -383.558527)
			(xy 377.276623 -383.545264) (xy 377.273312 -383.539238) (xy 377.256963 -383.51088) (xy 377.231157 -383.450724)
			(xy 377.213662 -383.387647) (xy 377.204797 -383.322792) (xy 377.204224 -383.290064) (xy 377.204793 -383.257335)
			(xy 377.213647 -383.192476) (xy 377.231136 -383.129396) (xy 377.256944 -383.069238) (xy 377.273312 -383.04089)
			(xy 377.276631 -383.034868) (xy 377.280234 -383.021602) (xy 377.280424 -383.014728) (xy 377.280424 -382.728724)
			(xy 377.280836 -382.7186) (xy 377.288581 -382.699892) (xy 377.302899 -382.685576) (xy 377.321608 -382.677834)
			(xy 377.331732 -382.677416) (xy 378.048012 -382.677416) (xy 378.058137 -382.677806) (xy 378.076844 -382.685561)
			(xy 378.091159 -382.699886) (xy 378.098901 -382.718598) (xy 378.09932 -382.728724) (xy 378.09932 -383.014728)
			(xy 378.099499 -383.021602) (xy 378.103116 -383.034865) (xy 378.106432 -383.04089) (xy 378.122787 -383.069245)
			(xy 378.148593 -383.129402) (xy 378.166086 -383.19248) (xy 378.174949 -383.257335) (xy 378.17552 -383.290064)
			(xy 378.174958 -383.322794) (xy 378.166101 -383.387652) (xy 378.148609 -383.450732) (xy 378.13167 -383.490216)
			(xy 379.404372 -383.490216) (xy 379.404926 -383.457486) (xy 379.413786 -383.392628) (xy 379.43128 -383.329547)
			(xy 379.45709 -383.26939) (xy 379.47346 -383.241042) (xy 379.476757 -383.235008) (xy 379.480374 -383.221752)
			(xy 379.480572 -383.21488) (xy 379.480572 -382.465326) (xy 379.480374 -382.458453) (xy 379.47677 -382.44519)
			(xy 379.47346 -382.439164) (xy 379.457086 -382.410819) (xy 379.431285 -382.350659) (xy 379.413797 -382.287578)
			(xy 379.40494 -382.222719) (xy 379.404372 -382.18999) (xy 379.40496 -382.157261) (xy 379.41381 -382.092404)
			(xy 379.431294 -382.029324) (xy 379.457095 -381.969165) (xy 379.47346 -381.940816) (xy 379.476766 -381.934787)
			(xy 379.480377 -381.921527) (xy 379.480572 -381.914654) (xy 379.480572 -381.628904) (xy 379.481088 -381.618799)
			(xy 379.488819 -381.600126) (xy 379.503106 -381.585832) (xy 379.521775 -381.578092) (xy 379.53188 -381.577596)
			(xy 380.24816 -381.577596) (xy 380.258279 -381.578049) (xy 380.276981 -381.585783) (xy 380.291297 -381.600088)
			(xy 380.299044 -381.618785) (xy 380.299468 -381.628904) (xy 380.299468 -381.914654) (xy 380.299681 -381.921526)
			(xy 380.303275 -381.934788) (xy 380.30658 -381.940816) (xy 380.32295 -381.969163) (xy 380.348751 -382.029323)
			(xy 380.36624 -382.092403) (xy 380.375099 -382.157261) (xy 380.375668 -382.18999) (xy 380.375111 -382.22271)
			(xy 383.80501 -382.22271) (xy 383.805011 -382.157273) (xy 383.813796 -382.092428) (xy 383.831205 -382.029348)
			(xy 383.856925 -381.969177) (xy 383.873248 -381.940816) (xy 383.876553 -381.934786) (xy 383.880165 -381.921527)
			(xy 383.88036 -381.914654) (xy 383.88036 -381.628904) (xy 383.880824 -381.618755) (xy 383.888611 -381.600011)
			(xy 383.902994 -381.585689) (xy 383.921771 -381.577981) (xy 383.931922 -381.577596) (xy 384.648202 -381.577596)
			(xy 384.658323 -381.578124) (xy 384.677036 -381.585844) (xy 384.691391 -381.600117) (xy 384.699218 -381.618786)
			(xy 384.699764 -381.628904) (xy 384.699764 -381.914654) (xy 384.699978 -381.921526) (xy 384.703572 -381.934788)
			(xy 384.706876 -381.940816) (xy 384.723189 -381.969182) (xy 384.748907 -382.029352) (xy 384.766315 -382.09243)
			(xy 384.7751 -382.157274) (xy 384.775101 -382.222709) (xy 384.775101 -382.22271) (xy 388.204799 -382.22271)
			(xy 388.2048 -382.157273) (xy 388.213585 -382.092428) (xy 388.230994 -382.029349) (xy 388.256713 -381.969177)
			(xy 388.273036 -381.940816) (xy 388.27634 -381.934786) (xy 388.279953 -381.921527) (xy 388.280148 -381.914654)
			(xy 388.280148 -381.628904) (xy 388.280624 -381.618757) (xy 388.288408 -381.600014) (xy 388.302788 -381.585693)
			(xy 388.321561 -381.577984) (xy 388.33171 -381.577596) (xy 389.04799 -381.577596) (xy 389.058111 -381.578133)
			(xy 389.076823 -381.58585) (xy 389.091178 -381.60012) (xy 389.099006 -381.618786) (xy 389.099552 -381.628904)
			(xy 389.099552 -381.914654) (xy 389.099755 -381.921527) (xy 389.103355 -381.93479) (xy 389.106664 -381.940816)
			(xy 389.122978 -381.969182) (xy 389.148696 -382.029352) (xy 389.166105 -382.09243) (xy 389.174889 -382.157273)
			(xy 389.17489 -382.18999) (xy 392.603744 -382.18999) (xy 392.607735 -382.127823) (xy 392.619644 -382.066676)
			(xy 392.639273 -382.007555) (xy 392.666302 -381.951429) (xy 392.700286 -381.89922) (xy 392.740668 -381.851785)
			(xy 392.786784 -381.809904) (xy 392.837876 -381.774264) (xy 392.893107 -381.74545) (xy 392.951569 -381.723936)
			(xy 393.012303 -381.710074) (xy 393.07431 -381.704092) (xy 393.136573 -381.706088) (xy 393.19807 -381.716031)
			(xy 393.257791 -381.733755) (xy 393.314754 -381.758972) (xy 393.368025 -381.791265) (xy 393.41673 -381.830105)
			(xy 393.460067 -381.874855) (xy 393.497327 -381.924779) (xy 393.527896 -381.979058) (xy 393.551274 -382.036801)
			(xy 393.567075 -382.097059) (xy 393.575041 -382.158842) (xy 393.57554 -382.18999) (xy 393.575041 -382.221138)
			(xy 393.567075 -382.282921) (xy 393.551274 -382.343179) (xy 393.527896 -382.400922) (xy 393.497327 -382.455201)
			(xy 393.460067 -382.505125) (xy 393.41673 -382.549875) (xy 393.368025 -382.588715) (xy 393.314754 -382.621008)
			(xy 393.257791 -382.646225) (xy 393.19807 -382.663949) (xy 393.136573 -382.673892) (xy 393.07431 -382.675888)
			(xy 393.012303 -382.669906) (xy 392.951569 -382.656044) (xy 392.893107 -382.63453) (xy 392.837876 -382.605716)
			(xy 392.786784 -382.570076) (xy 392.740668 -382.528195) (xy 392.700286 -382.48076) (xy 392.666302 -382.428551)
			(xy 392.639273 -382.372425) (xy 392.619644 -382.313304) (xy 392.607735 -382.252157) (xy 392.603744 -382.18999)
			(xy 389.17489 -382.18999) (xy 389.174891 -382.222709) (xy 389.166108 -382.287553) (xy 389.148702 -382.350632)
			(xy 389.122985 -382.410803) (xy 389.106664 -382.439164) (xy 389.103367 -382.445197) (xy 389.099749 -382.458454)
			(xy 389.099552 -382.465326) (xy 389.099552 -383.21488) (xy 389.099745 -383.221753) (xy 389.103352 -383.235016)
			(xy 389.106664 -383.241042) (xy 389.123 -383.269396) (xy 389.145818 -383.322789) (xy 390.404926 -383.322789)
			(xy 390.40493 -383.257349) (xy 390.413719 -383.192502) (xy 390.431133 -383.129422) (xy 390.456858 -383.069251)
			(xy 390.473184 -383.04089) (xy 390.476501 -383.034867) (xy 390.480106 -383.021602) (xy 390.480296 -383.014728)
			(xy 390.480296 -382.728724) (xy 390.480741 -382.718572) (xy 390.488528 -382.699821) (xy 390.502918 -382.685497)
			(xy 390.521704 -382.677795) (xy 390.531858 -382.677416) (xy 391.248138 -382.677416) (xy 391.258264 -382.677895)
			(xy 391.276982 -382.685631) (xy 391.291336 -382.699919) (xy 391.299158 -382.7186) (xy 391.2997 -382.728724)
			(xy 391.2997 -383.014728) (xy 391.299881 -383.021602) (xy 391.303497 -383.034865) (xy 391.306812 -383.04089)
			(xy 391.323102 -383.069269) (xy 391.34882 -383.129436) (xy 391.36623 -383.192511) (xy 391.375016 -383.257352)
			(xy 391.37502 -383.322786) (xy 391.366242 -383.387628) (xy 391.34884 -383.450705) (xy 391.331958 -383.490216)
			(xy 392.603744 -383.490216) (xy 392.607735 -383.428049) (xy 392.619644 -383.366902) (xy 392.639273 -383.307781)
			(xy 392.666302 -383.251655) (xy 392.700286 -383.199446) (xy 392.740668 -383.152011) (xy 392.786784 -383.11013)
			(xy 392.837876 -383.07449) (xy 392.893107 -383.045676) (xy 392.951569 -383.024162) (xy 393.012303 -383.0103)
			(xy 393.07431 -383.004318) (xy 393.136573 -383.006314) (xy 393.19807 -383.016257) (xy 393.257791 -383.033981)
			(xy 393.314754 -383.059198) (xy 393.368025 -383.091491) (xy 393.41673 -383.130331) (xy 393.460067 -383.175081)
			(xy 393.497327 -383.225005) (xy 393.527896 -383.279284) (xy 393.53226 -383.290064) (xy 394.803892 -383.290064)
			(xy 394.807883 -383.227897) (xy 394.819792 -383.16675) (xy 394.839421 -383.107629) (xy 394.86645 -383.051503)
			(xy 394.900434 -382.999294) (xy 394.940816 -382.951859) (xy 394.986932 -382.909978) (xy 395.038024 -382.874338)
			(xy 395.093255 -382.845524) (xy 395.151717 -382.82401) (xy 395.212451 -382.810148) (xy 395.274458 -382.804166)
			(xy 395.336721 -382.806162) (xy 395.398218 -382.816105) (xy 395.457939 -382.833829) (xy 395.514902 -382.859046)
			(xy 395.568173 -382.891339) (xy 395.616878 -382.930179) (xy 395.660215 -382.974929) (xy 395.697475 -383.024853)
			(xy 395.728044 -383.079132) (xy 395.751422 -383.136875) (xy 395.767223 -383.197133) (xy 395.775189 -383.258916)
			(xy 395.775688 -383.290064) (xy 395.775189 -383.321212) (xy 395.767223 -383.382995) (xy 395.751422 -383.443253)
			(xy 395.728044 -383.500996) (xy 395.697475 -383.555275) (xy 395.660215 -383.605199) (xy 395.616878 -383.649949)
			(xy 395.568173 -383.688789) (xy 395.514902 -383.721082) (xy 395.457939 -383.746299) (xy 395.398218 -383.764023)
			(xy 395.336721 -383.773966) (xy 395.274458 -383.775962) (xy 395.212451 -383.76998) (xy 395.151717 -383.756118)
			(xy 395.093255 -383.734604) (xy 395.038024 -383.70579) (xy 394.986932 -383.67015) (xy 394.940816 -383.628269)
			(xy 394.900434 -383.580834) (xy 394.86645 -383.528625) (xy 394.839421 -383.472499) (xy 394.819792 -383.413378)
			(xy 394.807883 -383.352231) (xy 394.803892 -383.290064) (xy 393.53226 -383.290064) (xy 393.551274 -383.337027)
			(xy 393.567075 -383.397285) (xy 393.575041 -383.459068) (xy 393.57554 -383.490216) (xy 393.575041 -383.521364)
			(xy 393.567075 -383.583147) (xy 393.551274 -383.643405) (xy 393.527896 -383.701148) (xy 393.497327 -383.755427)
			(xy 393.460067 -383.805351) (xy 393.41673 -383.850101) (xy 393.368025 -383.888941) (xy 393.314754 -383.921234)
			(xy 393.257791 -383.946451) (xy 393.19807 -383.964175) (xy 393.136573 -383.974118) (xy 393.07431 -383.976114)
			(xy 393.012303 -383.970132) (xy 392.951569 -383.95627) (xy 392.893107 -383.934756) (xy 392.837876 -383.905942)
			(xy 392.786784 -383.870302) (xy 392.740668 -383.828421) (xy 392.700286 -383.780986) (xy 392.666302 -383.728777)
			(xy 392.639273 -383.672651) (xy 392.619644 -383.61353) (xy 392.607735 -383.552383) (xy 392.603744 -383.490216)
			(xy 391.331958 -383.490216) (xy 391.32313 -383.510876) (xy 391.306812 -383.539238) (xy 391.303485 -383.545256)
			(xy 391.299887 -383.558525) (xy 391.2997 -383.5654) (xy 391.2997 -384.3147) (xy 391.299892 -384.321573)
			(xy 391.3035 -384.334836) (xy 391.306812 -384.340862) (xy 391.323163 -384.369207) (xy 391.348875 -384.429383)
			(xy 391.366278 -384.492465) (xy 391.375057 -384.557312) (xy 391.375055 -384.590036) (xy 394.803892 -384.590036)
			(xy 394.807883 -384.527869) (xy 394.819792 -384.466722) (xy 394.839421 -384.407601) (xy 394.86645 -384.351475)
			(xy 394.900434 -384.299266) (xy 394.940816 -384.251831) (xy 394.986932 -384.20995) (xy 395.038024 -384.17431)
			(xy 395.093255 -384.145496) (xy 395.151717 -384.123982) (xy 395.212451 -384.11012) (xy 395.274458 -384.104138)
			(xy 395.336721 -384.106134) (xy 395.398218 -384.116077) (xy 395.457939 -384.133801) (xy 395.514902 -384.159018)
			(xy 395.568173 -384.191311) (xy 395.616878 -384.230151) (xy 395.660215 -384.274901) (xy 395.697475 -384.324825)
			(xy 395.728044 -384.379104) (xy 395.751422 -384.436847) (xy 395.767223 -384.497105) (xy 395.775189 -384.558888)
			(xy 395.775688 -384.590036) (xy 395.775189 -384.621184) (xy 395.767223 -384.682967) (xy 395.751422 -384.743225)
			(xy 395.728044 -384.800968) (xy 395.697475 -384.855247) (xy 395.660215 -384.905171) (xy 395.616878 -384.949921)
			(xy 395.568173 -384.988761) (xy 395.514902 -385.021054) (xy 395.457939 -385.046271) (xy 395.398218 -385.063995)
			(xy 395.336721 -385.073938) (xy 395.274458 -385.075934) (xy 395.212451 -385.069952) (xy 395.151717 -385.05609)
			(xy 395.093255 -385.034576) (xy 395.038024 -385.005762) (xy 394.986932 -384.970122) (xy 394.940816 -384.928241)
			(xy 394.900434 -384.880806) (xy 394.86645 -384.828597) (xy 394.839421 -384.772471) (xy 394.819792 -384.71335)
			(xy 394.807883 -384.652203) (xy 394.803892 -384.590036) (xy 391.375055 -384.590036) (xy 391.375053 -384.62275)
			(xy 391.366266 -384.687596) (xy 391.348855 -384.750676) (xy 391.323135 -384.810848) (xy 391.306812 -384.83921)
			(xy 391.303495 -384.845233) (xy 391.29989 -384.858498) (xy 391.2997 -384.865372) (xy 391.2997 -385.151376)
			(xy 391.299259 -385.161529) (xy 391.291471 -385.180281) (xy 391.27708 -385.194605) (xy 391.258292 -385.202305)
			(xy 391.248138 -385.202684) (xy 390.531858 -385.202684) (xy 390.521732 -385.202209) (xy 390.503014 -385.194471)
			(xy 390.48866 -385.180182) (xy 390.480838 -385.1615) (xy 390.480296 -385.151376) (xy 390.480296 -384.865372)
			(xy 390.480115 -384.858498) (xy 390.4765 -384.845235) (xy 390.473184 -384.83921) (xy 390.456891 -384.810832)
			(xy 390.431168 -384.750666) (xy 390.413755 -384.68759) (xy 390.404967 -384.622748) (xy 390.404963 -384.557313)
			(xy 390.413743 -384.49247) (xy 390.431148 -384.429393) (xy 390.456863 -384.369223) (xy 390.473184 -384.340862)
			(xy 390.476511 -384.334843) (xy 390.480109 -384.321575) (xy 390.480296 -384.3147) (xy 390.480296 -383.5654)
			(xy 390.480105 -383.558527) (xy 390.476496 -383.545264) (xy 390.473184 -383.539238) (xy 390.45683 -383.510894)
			(xy 390.431113 -383.450719) (xy 390.413706 -383.387637) (xy 390.404926 -383.322789) (xy 389.145818 -383.322789)
			(xy 389.148716 -383.329569) (xy 389.166122 -383.392649) (xy 389.174904 -383.457495) (xy 389.174902 -383.522933)
			(xy 389.166117 -383.587778) (xy 389.148707 -383.650857) (xy 389.122987 -383.711029) (xy 389.106664 -383.73939)
			(xy 389.103358 -383.745419) (xy 389.099746 -383.758679) (xy 389.099552 -383.765552) (xy 389.099552 -384.051556)
			(xy 389.099043 -384.061701) (xy 389.091272 -384.080442) (xy 389.076902 -384.094765) (xy 389.058136 -384.102476)
			(xy 389.04799 -384.102864) (xy 388.33171 -384.102864) (xy 388.321584 -384.102365) (xy 388.302864 -384.094642)
			(xy 388.288508 -384.080359) (xy 388.280687 -384.061679) (xy 388.280148 -384.051556) (xy 388.280148 -383.765552)
			(xy 388.279943 -383.75868) (xy 388.276344 -383.745417) (xy 388.273036 -383.73939) (xy 388.256727 -383.711021)
			(xy 388.231009 -383.650852) (xy 388.213599 -383.587775) (xy 388.204814 -383.522932) (xy 388.204812 -383.457496)
			(xy 388.213594 -383.392652) (xy 388.231 -383.329574) (xy 388.256715 -383.269403) (xy 388.273036 -383.241042)
			(xy 388.276331 -383.235007) (xy 388.27995 -383.221751) (xy 388.280148 -383.21488) (xy 388.280148 -382.465326)
			(xy 388.279953 -382.458453) (xy 388.276347 -382.44519) (xy 388.273036 -382.439164) (xy 388.256705 -382.410807)
			(xy 388.230989 -382.350635) (xy 388.213582 -382.287555) (xy 388.204799 -382.22271) (xy 384.775101 -382.22271)
			(xy 384.766319 -382.287553) (xy 384.748913 -382.350631) (xy 384.723197 -382.410803) (xy 384.706876 -382.439164)
			(xy 384.703572 -382.445194) (xy 384.69996 -382.458454) (xy 384.699764 -382.465326) (xy 384.699764 -383.21488)
			(xy 384.699968 -383.221752) (xy 384.703569 -383.235015) (xy 384.706876 -383.241042) (xy 384.723211 -383.269396)
			(xy 384.748927 -383.329569) (xy 384.766333 -383.392649) (xy 384.775115 -383.457495) (xy 384.775113 -383.522933)
			(xy 384.766327 -383.587778) (xy 384.748918 -383.650857) (xy 384.723199 -383.711029) (xy 384.706876 -383.73939)
			(xy 384.703563 -383.745415) (xy 384.699957 -383.758679) (xy 384.699764 -383.765552) (xy 384.699764 -384.051556)
			(xy 384.699342 -384.061712) (xy 384.691554 -384.08047) (xy 384.677156 -384.094796) (xy 384.65836 -384.102491)
			(xy 384.648202 -384.102864) (xy 383.931922 -384.102864) (xy 383.921797 -384.102356) (xy 383.903077 -384.094636)
			(xy 383.88872 -384.080356) (xy 383.8809 -384.061678) (xy 383.88036 -384.051556) (xy 383.88036 -383.765552)
			(xy 383.880153 -383.75868) (xy 383.876556 -383.745417) (xy 383.873248 -383.73939) (xy 383.856939 -383.711021)
			(xy 383.83122 -383.650852) (xy 383.81381 -383.587775) (xy 383.805024 -383.522932) (xy 383.805023 -383.457496)
			(xy 383.813804 -383.392652) (xy 383.831211 -383.329574) (xy 383.856927 -383.269403) (xy 383.873248 -383.241042)
			(xy 383.876544 -383.235008) (xy 383.880162 -383.221752) (xy 383.88036 -383.21488) (xy 383.88036 -382.465326)
			(xy 383.880163 -382.458453) (xy 383.876559 -382.44519) (xy 383.873248 -382.439164) (xy 383.856917 -382.410808)
			(xy 383.8312 -382.350635) (xy 383.813792 -382.287556) (xy 383.80501 -382.22271) (xy 380.375111 -382.22271)
			(xy 380.375111 -382.22272) (xy 380.366251 -382.287578) (xy 380.348758 -382.350658) (xy 380.322949 -382.410816)
			(xy 380.30658 -382.439164) (xy 380.303277 -382.445194) (xy 380.299664 -382.458454) (xy 380.299468 -382.465326)
			(xy 380.299468 -383.21488) (xy 380.299672 -383.221752) (xy 380.303272 -383.235015) (xy 380.30658 -383.241042)
			(xy 380.32296 -383.269383) (xy 380.345861 -383.322788) (xy 381.604853 -383.322788) (xy 381.604858 -383.25735)
			(xy 381.613645 -383.192504) (xy 381.631056 -383.129424) (xy 381.656777 -383.069252) (xy 381.6731 -383.04089)
			(xy 381.676418 -383.034867) (xy 381.680022 -383.021602) (xy 381.680212 -383.014728) (xy 381.680212 -382.728724)
			(xy 381.680641 -382.71857) (xy 381.688431 -382.699816) (xy 381.702826 -382.685491) (xy 381.721618 -382.677793)
			(xy 381.731774 -382.677416) (xy 382.448054 -382.677416) (xy 382.458175 -382.677964) (xy 382.47689 -382.685672)
			(xy 382.491247 -382.699939) (xy 382.499072 -382.718606) (xy 382.499616 -382.728724) (xy 382.499616 -383.014728)
			(xy 382.499795 -383.021602) (xy 382.503412 -383.034865) (xy 382.506728 -383.04089) (xy 382.523021 -383.069268)
			(xy 382.548743 -383.129435) (xy 382.566156 -383.19251) (xy 382.574944 -383.257352) (xy 382.574948 -383.322786)
			(xy 382.566168 -383.387629) (xy 382.548763 -383.450707) (xy 382.523049 -383.510877) (xy 382.506728 -383.539238)
			(xy 382.503402 -383.545257) (xy 382.499803 -383.558525) (xy 382.499616 -383.5654) (xy 382.499616 -384.3147)
			(xy 382.499806 -384.321573) (xy 382.503416 -384.334836) (xy 382.506728 -384.340862) (xy 382.523082 -384.369206)
			(xy 382.548798 -384.429381) (xy 382.566204 -384.492463) (xy 382.574985 -384.557311) (xy 382.574982 -384.590036)
			(xy 386.004308 -384.590036) (xy 386.004867 -384.557306) (xy 386.013724 -384.492448) (xy 386.031217 -384.429368)
			(xy 386.057026 -384.36921) (xy 386.073396 -384.340862) (xy 386.076724 -384.334844) (xy 386.080321 -384.321575)
			(xy 386.080508 -384.3147) (xy 386.080508 -383.5654) (xy 386.080315 -383.558527) (xy 386.076708 -383.545264)
			(xy 386.073396 -383.539238) (xy 386.057045 -383.510881) (xy 386.03124 -383.450724) (xy 386.013746 -383.387647)
			(xy 386.004881 -383.322792) (xy 386.004308 -383.290064) (xy 386.004879 -383.257335) (xy 386.013733 -383.192477)
			(xy 386.031222 -383.129396) (xy 386.057028 -383.069238) (xy 386.073396 -383.04089) (xy 386.076714 -383.034867)
			(xy 386.080318 -383.021602) (xy 386.080508 -383.014728) (xy 386.080508 -382.728724) (xy 386.080936 -382.718602)
			(xy 386.088677 -382.699897) (xy 386.102991 -382.685582) (xy 386.121694 -382.677837) (xy 386.131816 -382.677416)
			(xy 386.848096 -382.677416) (xy 386.85822 -382.67782) (xy 386.876927 -382.685569) (xy 386.891242 -382.69989)
			(xy 386.898984 -382.7186) (xy 386.899404 -382.728724) (xy 386.899404 -383.014728) (xy 386.899585 -383.021602)
			(xy 386.9032 -383.034865) (xy 386.906516 -383.04089) (xy 386.922879 -383.069241) (xy 386.948681 -383.1294)
			(xy 386.966171 -383.192479) (xy 386.975033 -383.257335) (xy 386.975604 -383.290064) (xy 386.975044 -383.322794)
			(xy 386.966186 -383.387652) (xy 386.948694 -383.450732) (xy 386.922885 -383.51089) (xy 386.906516 -383.539238)
			(xy 386.903189 -383.545257) (xy 386.899591 -383.558525) (xy 386.899404 -383.5654) (xy 386.899404 -384.3147)
			(xy 386.899595 -384.321573) (xy 386.903204 -384.334836) (xy 386.906516 -384.340862) (xy 386.922868 -384.369219)
			(xy 386.948673 -384.429376) (xy 386.966166 -384.492453) (xy 386.975031 -384.557308) (xy 386.975604 -384.590036)
			(xy 386.975031 -384.622765) (xy 386.966177 -384.687623) (xy 386.948689 -384.750703) (xy 386.922884 -384.810862)
			(xy 386.906516 -384.83921) (xy 386.903199 -384.845233) (xy 386.899594 -384.858498) (xy 386.899404 -384.865372)
			(xy 386.899404 -385.151376) (xy 386.898965 -385.161496) (xy 386.891225 -385.180199) (xy 386.876916 -385.194514)
			(xy 386.858216 -385.202261) (xy 386.848096 -385.202684) (xy 386.131816 -385.202684) (xy 386.121693 -385.202271)
			(xy 386.102986 -385.194525) (xy 386.088671 -385.180207) (xy 386.080928 -385.1615) (xy 386.080508 -385.151376)
			(xy 386.080508 -384.865372) (xy 386.080326 -384.858498) (xy 386.076711 -384.845235) (xy 386.073396 -384.83921)
			(xy 386.057034 -384.810859) (xy 386.031231 -384.7507) (xy 386.013741 -384.687621) (xy 386.004879 -384.622765)
			(xy 386.004308 -384.590036) (xy 382.574982 -384.590036) (xy 382.57498 -384.622751) (xy 382.566192 -384.687597)
			(xy 382.548778 -384.750678) (xy 382.523054 -384.810849) (xy 382.506728 -384.83921) (xy 382.503412 -384.845234)
			(xy 382.499807 -384.858498) (xy 382.499616 -384.865372) (xy 382.499616 -385.151376) (xy 382.499159 -385.161527)
			(xy 382.491375 -385.180275) (xy 382.476989 -385.194599) (xy 382.458206 -385.202303) (xy 382.448054 -385.202684)
			(xy 381.731774 -385.202684) (xy 381.721649 -385.202196) (xy 381.702931 -385.194464) (xy 381.688577 -385.180179)
			(xy 381.680754 -385.161499) (xy 381.680212 -385.151376) (xy 381.680212 -384.865372) (xy 381.680029 -384.858498)
			(xy 381.676415 -384.845235) (xy 381.6731 -384.83921) (xy 381.656809 -384.810832) (xy 381.631091 -384.750664)
			(xy 381.613681 -384.687589) (xy 381.604894 -384.622748) (xy 381.60489 -384.557314) (xy 381.613669 -384.492472)
			(xy 381.631071 -384.429394) (xy 381.656781 -384.369224) (xy 381.6731 -384.340862) (xy 381.676428 -384.334844)
			(xy 381.680025 -384.321575) (xy 381.680212 -384.3147) (xy 381.680212 -383.5654) (xy 381.680019 -383.558527)
			(xy 381.676411 -383.545264) (xy 381.6731 -383.539238) (xy 381.656748 -383.510893) (xy 381.631036 -383.450718)
			(xy 381.613632 -383.387636) (xy 381.604853 -383.322788) (xy 380.345861 -383.322788) (xy 380.348759 -383.329545)
			(xy 380.366245 -383.392627) (xy 380.3751 -383.457486) (xy 380.375668 -383.490216) (xy 380.375078 -383.522945)
			(xy 380.366228 -383.587802) (xy 380.348745 -383.650882) (xy 380.322945 -383.711041) (xy 380.30658 -383.73939)
			(xy 380.303267 -383.745416) (xy 380.299661 -383.758679) (xy 380.299468 -383.765552) (xy 380.299468 -384.051556)
			(xy 380.299047 -384.06168) (xy 380.291308 -384.080388) (xy 380.276992 -384.094705) (xy 380.258284 -384.102446)
			(xy 380.24816 -384.102864) (xy 379.53188 -384.102864) (xy 379.521752 -384.1025) (xy 379.503041 -384.094738)
			(xy 379.488726 -384.080405) (xy 379.480988 -384.061685) (xy 379.480572 -384.051556) (xy 379.480572 -383.765552)
			(xy 379.480364 -383.75868) (xy 379.476767 -383.745417) (xy 379.47346 -383.73939) (xy 379.457096 -383.71104)
			(xy 379.431293 -383.650881) (xy 379.413802 -383.587802) (xy 379.404942 -383.522945) (xy 379.404372 -383.490216)
			(xy 378.13167 -383.490216) (xy 378.122801 -383.51089) (xy 378.106432 -383.539238) (xy 378.103106 -383.545257)
			(xy 378.099507 -383.558525) (xy 378.09932 -383.5654) (xy 378.09932 -384.3147) (xy 378.09951 -384.321573)
			(xy 378.103119 -384.334836) (xy 378.106432 -384.340862) (xy 378.122776 -384.369223) (xy 378.148585 -384.429378)
			(xy 378.166081 -384.492454) (xy 378.174947 -384.557308) (xy 378.17552 -384.590036) (xy 378.174945 -384.622765)
			(xy 378.166092 -384.687623) (xy 378.148604 -384.750703) (xy 378.122799 -384.810861) (xy 378.106432 -384.83921)
			(xy 378.103116 -384.845234) (xy 378.099511 -384.858498) (xy 378.09932 -384.865372) (xy 378.09932 -385.151376)
			(xy 378.098865 -385.161494) (xy 378.091128 -385.180194) (xy 378.076824 -385.194508) (xy 378.05813 -385.202258)
			(xy 378.048012 -385.202684) (xy 377.331732 -385.202684) (xy 377.32161 -385.202258) (xy 377.302903 -385.194517)
			(xy 377.288587 -385.180203) (xy 377.280844 -385.161498) (xy 377.280424 -385.151376) (xy 377.280424 -384.865372)
			(xy 377.28024 -384.858498) (xy 377.276626 -384.845236) (xy 377.273312 -384.83921) (xy 377.256952 -384.810858)
			(xy 377.231148 -384.7507) (xy 377.213657 -384.687621) (xy 377.204795 -384.622765) (xy 377.204224 -384.590036)
			(xy 359.745407 -384.590036) (xy 359.713047 -386.172456) (xy 361.296202 -386.172456) (xy 361.300273 -386.116834)
			(xy 361.312399 -386.062397) (xy 361.332322 -386.010306) (xy 361.359618 -385.961671) (xy 361.393704 -385.917528)
			(xy 361.433853 -385.878819) (xy 361.479211 -385.846368) (xy 361.528811 -385.820867) (xy 361.581595 -385.80286)
			(xy 361.636438 -385.79273) (xy 361.692172 -385.790693) (xy 361.747609 -385.796793) (xy 361.801566 -385.810899)
			(xy 361.852895 -385.832711) (xy 361.900501 -385.861765) (xy 361.943369 -385.89744) (xy 361.980586 -385.938977)
			(xy 362.011359 -385.98549) (xy 362.035031 -386.035987) (xy 362.051099 -386.089394) (xy 362.059219 -386.14457)
			(xy 362.059728 -386.172456) (xy 362.059219 -386.200342) (xy 362.051099 -386.255518) (xy 362.035031 -386.308925)
			(xy 362.011359 -386.359422) (xy 361.980586 -386.405935) (xy 361.943369 -386.447472) (xy 361.900501 -386.483147)
			(xy 361.852895 -386.512201) (xy 361.801566 -386.534013) (xy 361.747609 -386.548119) (xy 361.692172 -386.554219)
			(xy 361.636438 -386.552182) (xy 361.581595 -386.542052) (xy 361.528811 -386.524045) (xy 361.479211 -386.498544)
			(xy 361.433853 -386.466093) (xy 361.393704 -386.427384) (xy 361.359618 -386.383241) (xy 361.332322 -386.334606)
			(xy 361.312399 -386.282515) (xy 361.300273 -386.228078) (xy 361.296202 -386.172456) (xy 359.713047 -386.172456)
			(xy 359.708196 -386.409692) (xy 359.706892 -386.451339) (xy 359.698203 -386.534214) (xy 359.682631 -386.616075)
			(xy 359.660285 -386.696352) (xy 359.64622 -386.735574) (xy 359.188435 -387.9723) (xy 362.73308 -387.9723)
			(xy 362.737151 -387.916678) (xy 362.749277 -387.862241) (xy 362.7692 -387.81015) (xy 362.796496 -387.761515)
			(xy 362.830582 -387.717372) (xy 362.870731 -387.678663) (xy 362.916089 -387.646212) (xy 362.965689 -387.620711)
			(xy 363.018473 -387.602704) (xy 363.073316 -387.592574) (xy 363.12905 -387.590537) (xy 363.184487 -387.596637)
			(xy 363.238444 -387.610743) (xy 363.289773 -387.632555) (xy 363.337379 -387.661609) (xy 363.380247 -387.697284)
			(xy 363.417464 -387.738821) (xy 363.448237 -387.785334) (xy 363.471909 -387.835831) (xy 363.487977 -387.889238)
			(xy 363.490893 -387.909054) (xy 366.166144 -387.909054) (xy 366.170215 -387.853432) (xy 366.182341 -387.798995)
			(xy 366.202264 -387.746904) (xy 366.22956 -387.698269) (xy 366.263646 -387.654126) (xy 366.303795 -387.615417)
			(xy 366.349153 -387.582966) (xy 366.398753 -387.557465) (xy 366.451537 -387.539458) (xy 366.50638 -387.529328)
			(xy 366.562114 -387.527291) (xy 366.617551 -387.533391) (xy 366.671508 -387.547497) (xy 366.722837 -387.569309)
			(xy 366.770443 -387.598363) (xy 366.813311 -387.634038) (xy 366.850528 -387.675575) (xy 366.881301 -387.722088)
			(xy 366.904973 -387.772585) (xy 366.921041 -387.825992) (xy 366.929161 -387.881168) (xy 366.92967 -387.909054)
			(xy 366.929161 -387.93694) (xy 366.921041 -387.992116) (xy 366.904973 -388.045523) (xy 366.881301 -388.09602)
			(xy 366.850528 -388.142533) (xy 366.813311 -388.18407) (xy 366.770443 -388.219745) (xy 366.722837 -388.248799)
			(xy 366.671508 -388.270611) (xy 366.617551 -388.284717) (xy 366.562114 -388.290817) (xy 366.50638 -388.28878)
			(xy 366.451537 -388.27865) (xy 366.398753 -388.260643) (xy 366.349153 -388.235142) (xy 366.303795 -388.202691)
			(xy 366.263646 -388.163982) (xy 366.22956 -388.119839) (xy 366.202264 -388.071204) (xy 366.182341 -388.019113)
			(xy 366.170215 -387.964676) (xy 366.166144 -387.909054) (xy 363.490893 -387.909054) (xy 363.496097 -387.944414)
			(xy 363.496606 -387.9723) (xy 363.496097 -388.000186) (xy 363.487977 -388.055362) (xy 363.471909 -388.108769)
			(xy 363.448237 -388.159266) (xy 363.417464 -388.205779) (xy 363.380247 -388.247316) (xy 363.337379 -388.282991)
			(xy 363.289773 -388.312045) (xy 363.238444 -388.333857) (xy 363.184487 -388.347963) (xy 363.12905 -388.354063)
			(xy 363.073316 -388.352026) (xy 363.018473 -388.341896) (xy 362.965689 -388.323889) (xy 362.916089 -388.298388)
			(xy 362.870731 -388.265937) (xy 362.830582 -388.227228) (xy 362.796496 -388.183085) (xy 362.7692 -388.13445)
			(xy 362.749277 -388.082359) (xy 362.737151 -388.027922) (xy 362.73308 -387.9723) (xy 359.188435 -387.9723)
			(xy 358.866321 -388.842504) (xy 366.936272 -388.842504) (xy 366.940343 -388.786882) (xy 366.952469 -388.732445)
			(xy 366.972392 -388.680354) (xy 366.999688 -388.631719) (xy 367.033774 -388.587576) (xy 367.073923 -388.548867)
			(xy 367.119281 -388.516416) (xy 367.168881 -388.490915) (xy 367.221665 -388.472908) (xy 367.276508 -388.462778)
			(xy 367.332242 -388.460741) (xy 367.387679 -388.466841) (xy 367.441636 -388.480947) (xy 367.492965 -388.502759)
			(xy 367.540571 -388.531813) (xy 367.583439 -388.567488) (xy 367.620656 -388.609025) (xy 367.651429 -388.655538)
			(xy 367.675101 -388.706035) (xy 367.691169 -388.759442) (xy 367.699289 -388.814618) (xy 367.699798 -388.842504)
			(xy 367.699289 -388.87039) (xy 367.691169 -388.925566) (xy 367.675101 -388.978973) (xy 367.651429 -389.02947)
			(xy 367.620656 -389.075983) (xy 367.583439 -389.11752) (xy 367.540571 -389.153195) (xy 367.492965 -389.182249)
			(xy 367.441636 -389.204061) (xy 367.387679 -389.218167) (xy 367.332242 -389.224267) (xy 367.276508 -389.22223)
			(xy 367.221665 -389.2121) (xy 367.168881 -389.194093) (xy 367.119281 -389.168592) (xy 367.073923 -389.136141)
			(xy 367.033774 -389.097432) (xy 366.999688 -389.053289) (xy 366.972392 -389.004654) (xy 366.952469 -388.952563)
			(xy 366.940343 -388.898126) (xy 366.936272 -388.842504) (xy 358.866321 -388.842504) (xy 358.757728 -389.135874)
			(xy 358.742772 -389.175084) (xy 358.707166 -389.251084) (xy 358.665304 -389.323825) (xy 358.617483 -389.392796)
			(xy 358.591104 -389.425434) (xy 358.08412 -390.038082) (xy 358.082088 -390.070848) (xy 358.090978 -390.084818)
			(xy 358.104919 -390.107794) (xy 358.126929 -390.156823) (xy 358.141865 -390.208448) (xy 358.149433 -390.261655)
			(xy 358.149906 -390.288526) (xy 358.149906 -390.28878) (xy 358.149421 -390.316051) (xy 358.141662 -390.37004)
			(xy 358.126299 -390.422374) (xy 358.103644 -390.471989) (xy 358.07416 -390.517876) (xy 358.038445 -390.5591)
			(xy 357.997227 -390.594821) (xy 357.951346 -390.624314) (xy 357.901734 -390.646976) (xy 357.849402 -390.662348)
			(xy 357.795415 -390.670116) (xy 357.768144 -390.670542) (xy 357.76789 -390.670542) (xy 357.744089 -390.67018)
			(xy 357.696856 -390.664257) (xy 357.65073 -390.652492) (xy 357.628444 -390.644126) (xy 357.609902 -390.64057)
			(xy 357.598663 -390.641154) (xy 357.578351 -390.65078) (xy 357.570786 -390.659112) (xy 357.06928 -391.26541)
			(xy 365.668812 -391.26541) (xy 365.672883 -391.209788) (xy 365.685009 -391.155351) (xy 365.704932 -391.10326)
			(xy 365.732228 -391.054625) (xy 365.766314 -391.010482) (xy 365.806463 -390.971773) (xy 365.851821 -390.939322)
			(xy 365.901421 -390.913821) (xy 365.954205 -390.895814) (xy 366.009048 -390.885684) (xy 366.064782 -390.883647)
			(xy 366.120219 -390.889747) (xy 366.174176 -390.903853) (xy 366.225505 -390.925665) (xy 366.273111 -390.954719)
			(xy 366.315979 -390.990394) (xy 366.353196 -391.031931) (xy 366.383969 -391.078444) (xy 366.407641 -391.128941)
			(xy 366.423709 -391.182348) (xy 366.431829 -391.237524) (xy 366.432338 -391.26541) (xy 366.431829 -391.293296)
			(xy 366.423709 -391.348472) (xy 366.407641 -391.401879) (xy 366.383969 -391.452376) (xy 366.353196 -391.498889)
			(xy 366.315979 -391.540426) (xy 366.273111 -391.576101) (xy 366.225505 -391.605155) (xy 366.174176 -391.626967)
			(xy 366.120219 -391.641073) (xy 366.064782 -391.647173) (xy 366.009048 -391.645136) (xy 365.954205 -391.635006)
			(xy 365.901421 -391.616999) (xy 365.851821 -391.591498) (xy 365.806463 -391.559047) (xy 365.766314 -391.520338)
			(xy 365.732228 -391.476195) (xy 365.704932 -391.42756) (xy 365.685009 -391.375469) (xy 365.672883 -391.321032)
			(xy 365.668812 -391.26541) (xy 357.06928 -391.26541) (xy 356.839012 -391.543794) (xy 356.811302 -391.576544)
			(xy 356.751119 -391.637689) (xy 356.68591 -391.693444) (xy 356.651306 -391.7188) (xy 356.33914 -391.942574)
			(xy 356.329488 -391.951464) (xy 355.72348 -392.684254) (xy 363.702852 -392.684254) (xy 363.706923 -392.628632)
			(xy 363.719049 -392.574195) (xy 363.738972 -392.522104) (xy 363.766268 -392.473469) (xy 363.800354 -392.429326)
			(xy 363.840503 -392.390617) (xy 363.885861 -392.358166) (xy 363.935461 -392.332665) (xy 363.988245 -392.314658)
			(xy 364.043088 -392.304528) (xy 364.098822 -392.302491) (xy 364.154259 -392.308591) (xy 364.208216 -392.322697)
			(xy 364.259545 -392.344509) (xy 364.307151 -392.373563) (xy 364.350019 -392.409238) (xy 364.387236 -392.450775)
			(xy 364.418009 -392.497288) (xy 364.441681 -392.547785) (xy 364.457749 -392.601192) (xy 364.465869 -392.656368)
			(xy 364.466378 -392.684254) (xy 364.465869 -392.71214) (xy 364.457749 -392.767316) (xy 364.441681 -392.820723)
			(xy 364.418009 -392.87122) (xy 364.387236 -392.917733) (xy 364.350019 -392.95927) (xy 364.307151 -392.994945)
			(xy 364.259545 -393.023999) (xy 364.208216 -393.045811) (xy 364.154259 -393.059917) (xy 364.098822 -393.066017)
			(xy 364.043088 -393.06398) (xy 363.988245 -393.05385) (xy 363.935461 -393.035843) (xy 363.885861 -393.010342)
			(xy 363.840503 -392.977891) (xy 363.800354 -392.939182) (xy 363.766268 -392.895039) (xy 363.738972 -392.846404)
			(xy 363.719049 -392.794313) (xy 363.706923 -392.739876) (xy 363.702852 -392.684254) (xy 355.72348 -392.684254)
			(xy 355.639878 -392.785346) (xy 355.620574 -392.808206) (xy 355.618796 -392.810238) (xy 355.614732 -392.81481)
			(xy 355.583465 -392.848931) (xy 355.515557 -392.91182) (xy 355.442066 -392.968083) (xy 355.363636 -393.017228)
			(xy 355.280955 -393.058825) (xy 355.23805 -393.076176) (xy 354.258207 -393.459716) (xy 357.18572 -393.459716)
			(xy 357.189791 -393.404094) (xy 357.201917 -393.349657) (xy 357.22184 -393.297566) (xy 357.249136 -393.248931)
			(xy 357.283222 -393.204788) (xy 357.323371 -393.166079) (xy 357.368729 -393.133628) (xy 357.418329 -393.108127)
			(xy 357.471113 -393.09012) (xy 357.525956 -393.07999) (xy 357.58169 -393.077953) (xy 357.637127 -393.084053)
			(xy 357.691084 -393.098159) (xy 357.742413 -393.119971) (xy 357.790019 -393.149025) (xy 357.832887 -393.1847)
			(xy 357.870104 -393.226237) (xy 357.900877 -393.27275) (xy 357.924549 -393.323247) (xy 357.940617 -393.376654)
			(xy 357.948737 -393.43183) (xy 357.949246 -393.459716) (xy 357.948737 -393.487602) (xy 357.940617 -393.542778)
			(xy 357.924549 -393.596185) (xy 357.900877 -393.646682) (xy 357.870104 -393.693195) (xy 357.832887 -393.734732)
			(xy 357.790019 -393.770407) (xy 357.742413 -393.799461) (xy 357.691084 -393.821273) (xy 357.637127 -393.835379)
			(xy 357.58169 -393.841479) (xy 357.525956 -393.839442) (xy 357.471113 -393.829312) (xy 357.418329 -393.811305)
			(xy 357.368729 -393.785804) (xy 357.323371 -393.753353) (xy 357.283222 -393.714644) (xy 357.249136 -393.670501)
			(xy 357.22184 -393.621866) (xy 357.201917 -393.569775) (xy 357.189791 -393.515338) (xy 357.18572 -393.459716)
			(xy 354.258207 -393.459716) (xy 354.182934 -393.48918) (xy 354.172012 -393.495276) (xy 354.082858 -393.55903)
			(xy 354.049072 -393.58271) (xy 353.978259 -393.625061) (xy 353.904193 -393.661425) (xy 353.865942 -393.676886)
			(xy 349.66656 -395.32306) (xy 349.651066 -395.340332) (xy 349.649542 -395.345412) (xy 349.639884 -395.378359)
			(xy 349.613863 -395.441896) (xy 349.58053 -395.50192) (xy 349.540349 -395.557593) (xy 349.493881 -395.608138)
			(xy 349.441776 -395.652849) (xy 349.384761 -395.691102) (xy 349.323632 -395.722363) (xy 349.259242 -395.746195)
			(xy 349.192491 -395.762265) (xy 349.124309 -395.77035) (xy 349.08998 -395.770862) (xy 349.08744 -395.770862)
			(xy 349.08236 -395.771116) (xy 349.073007 -395.772352) (xy 349.056124 -395.78074) (xy 349.043411 -395.794662)
			(xy 349.036587 -395.812236) (xy 349.036132 -395.821662) (xy 349.036132 -395.935454) (xy 349.036536 -395.940734)
			(xy 349.03923 -395.950973) (xy 349.041466 -395.955774) (xy 349.048832 -395.966442) (xy 349.055944 -395.973554)
			(xy 349.073978 -395.99108) (xy 349.080617 -395.996849) (xy 349.096728 -396.003869) (xy 349.105474 -396.004796)
			(xy 349.106744 -396.004796) (xy 349.13781 -396.006364) (xy 349.199193 -396.016428) (xy 349.258789 -396.034247)
			(xy 349.315623 -396.059529) (xy 349.322518 -396.063724) (xy 357.261158 -396.063724) (xy 357.265229 -396.008102)
			(xy 357.277355 -395.953665) (xy 357.297278 -395.901574) (xy 357.324574 -395.852939) (xy 357.35866 -395.808796)
			(xy 357.398809 -395.770087) (xy 357.444167 -395.737636) (xy 357.493767 -395.712135) (xy 357.546551 -395.694128)
			(xy 357.601394 -395.683998) (xy 357.657128 -395.681961) (xy 357.712565 -395.688061) (xy 357.766522 -395.702167)
			(xy 357.817851 -395.723979) (xy 357.865457 -395.753033) (xy 357.908325 -395.788708) (xy 357.945542 -395.830245)
			(xy 357.976315 -395.876758) (xy 357.999987 -395.927255) (xy 358.016055 -395.980662) (xy 358.024175 -396.035838)
			(xy 358.024684 -396.063724) (xy 358.024175 -396.09161) (xy 358.016055 -396.146786) (xy 357.999987 -396.200193)
			(xy 357.976315 -396.25069) (xy 357.945542 -396.297203) (xy 357.908325 -396.33874) (xy 357.865457 -396.374415)
			(xy 357.817851 -396.403469) (xy 357.766522 -396.425281) (xy 357.712565 -396.439387) (xy 357.657128 -396.445487)
			(xy 357.601394 -396.44345) (xy 357.546551 -396.43332) (xy 357.493767 -396.415313) (xy 357.444167 -396.389812)
			(xy 357.398809 -396.357361) (xy 357.35866 -396.318652) (xy 357.324574 -396.274509) (xy 357.297278 -396.225874)
			(xy 357.277355 -396.173783) (xy 357.265229 -396.119346) (xy 357.261158 -396.063724) (xy 349.322518 -396.063724)
			(xy 349.368763 -396.09186) (xy 349.41734 -396.130712) (xy 349.460559 -396.175447) (xy 349.497713 -396.225335)
			(xy 349.528193 -396.279558) (xy 349.551501 -396.337229) (xy 349.567255 -396.397404) (xy 349.575197 -396.459098)
			(xy 349.575197 -396.521301) (xy 349.567255 -396.582995) (xy 349.551501 -396.64317) (xy 349.528194 -396.700841)
			(xy 349.497714 -396.755064) (xy 349.46056 -396.804952) (xy 349.417341 -396.849688) (xy 349.368763 -396.88854)
			(xy 349.315623 -396.920871) (xy 349.25879 -396.946153) (xy 349.199194 -396.963972) (xy 349.137811 -396.974036)
			(xy 349.106744 -396.975584) (xy 349.105474 -396.975584) (xy 349.096731 -396.976525) (xy 349.080617 -396.983534)
			(xy 349.073978 -396.9893) (xy 349.055944 -397.006826) (xy 349.048832 -397.013938) (xy 349.041466 -397.024606)
			(xy 349.040984 -397.025622) (xy 365.416844 -397.025622) (xy 365.420915 -396.97) (xy 365.433041 -396.915563)
			(xy 365.452964 -396.863472) (xy 365.48026 -396.814837) (xy 365.514346 -396.770694) (xy 365.554495 -396.731985)
			(xy 365.599853 -396.699534) (xy 365.649453 -396.674033) (xy 365.702237 -396.656026) (xy 365.75708 -396.645896)
			(xy 365.812814 -396.643859) (xy 365.868251 -396.649959) (xy 365.922208 -396.664065) (xy 365.973537 -396.685877)
			(xy 366.021143 -396.714931) (xy 366.064011 -396.750606) (xy 366.101048 -396.791942) (xy 366.335308 -396.791942)
			(xy 366.339379 -396.73632) (xy 366.351505 -396.681883) (xy 366.371428 -396.629792) (xy 366.398724 -396.581157)
			(xy 366.43281 -396.537014) (xy 366.472959 -396.498305) (xy 366.518317 -396.465854) (xy 366.567917 -396.440353)
			(xy 366.620701 -396.422346) (xy 366.675544 -396.412216) (xy 366.731278 -396.410179) (xy 366.786715 -396.416279)
			(xy 366.840672 -396.430385) (xy 366.892001 -396.452197) (xy 366.939607 -396.481251) (xy 366.982475 -396.516926)
			(xy 367.019692 -396.558463) (xy 367.050465 -396.604976) (xy 367.074137 -396.655473) (xy 367.090205 -396.70888)
			(xy 367.098325 -396.764056) (xy 367.098834 -396.791942) (xy 367.098325 -396.819828) (xy 367.090205 -396.875004)
			(xy 367.074137 -396.928411) (xy 367.050465 -396.978908) (xy 367.019692 -397.025421) (xy 366.982475 -397.066958)
			(xy 366.939607 -397.102633) (xy 366.892001 -397.131687) (xy 366.840672 -397.153499) (xy 366.786715 -397.167605)
			(xy 366.731278 -397.173705) (xy 366.675544 -397.171668) (xy 366.620701 -397.161538) (xy 366.567917 -397.143531)
			(xy 366.518317 -397.11803) (xy 366.472959 -397.085579) (xy 366.43281 -397.04687) (xy 366.398724 -397.002727)
			(xy 366.371428 -396.954092) (xy 366.351505 -396.902001) (xy 366.339379 -396.847564) (xy 366.335308 -396.791942)
			(xy 366.101048 -396.791942) (xy 366.101228 -396.792143) (xy 366.132001 -396.838656) (xy 366.155673 -396.889153)
			(xy 366.171741 -396.94256) (xy 366.179861 -396.997736) (xy 366.18037 -397.025622) (xy 366.179861 -397.053508)
			(xy 366.171741 -397.108684) (xy 366.155673 -397.162091) (xy 366.132001 -397.212588) (xy 366.101228 -397.259101)
			(xy 366.064011 -397.300638) (xy 366.021143 -397.336313) (xy 365.973537 -397.365367) (xy 365.922208 -397.387179)
			(xy 365.868251 -397.401285) (xy 365.812814 -397.407385) (xy 365.75708 -397.405348) (xy 365.702237 -397.395218)
			(xy 365.649453 -397.377211) (xy 365.599853 -397.35171) (xy 365.554495 -397.319259) (xy 365.514346 -397.28055)
			(xy 365.48026 -397.236407) (xy 365.452964 -397.187772) (xy 365.433041 -397.135681) (xy 365.420915 -397.081244)
			(xy 365.416844 -397.025622) (xy 349.040984 -397.025622) (xy 349.039194 -397.029393) (xy 349.036496 -397.03964)
			(xy 349.036132 -397.044926) (xy 349.036132 -397.235426) (xy 349.036533 -397.240707) (xy 349.039222 -397.250949)
			(xy 349.041466 -397.255746) (xy 349.048832 -397.266414) (xy 349.051118 -397.2687) (xy 349.07982 -397.297148)
			(xy 349.086932 -397.304006) (xy 349.106744 -397.304768) (xy 349.137808 -397.306336) (xy 349.199187 -397.3164)
			(xy 349.258778 -397.334219) (xy 349.315607 -397.359502) (xy 349.368742 -397.391833) (xy 349.417314 -397.430685)
			(xy 349.460527 -397.475421) (xy 349.497675 -397.525308) (xy 349.528148 -397.57953) (xy 349.532382 -397.59001)
			(xy 350.80398 -397.59001) (xy 350.807971 -397.527843) (xy 350.81988 -397.466696) (xy 350.839509 -397.407575)
			(xy 350.866538 -397.351449) (xy 350.900522 -397.29924) (xy 350.940904 -397.251805) (xy 350.98702 -397.209924)
			(xy 351.038112 -397.174284) (xy 351.093343 -397.14547) (xy 351.151805 -397.123956) (xy 351.212539 -397.110094)
			(xy 351.274546 -397.104112) (xy 351.336809 -397.106108) (xy 351.398306 -397.116051) (xy 351.458027 -397.133775)
			(xy 351.51499 -397.158992) (xy 351.568261 -397.191285) (xy 351.616966 -397.230125) (xy 351.660303 -397.274875)
			(xy 351.697563 -397.324799) (xy 351.728132 -397.379078) (xy 351.75151 -397.436821) (xy 351.767311 -397.497079)
			(xy 351.775277 -397.558862) (xy 351.775776 -397.59001) (xy 351.775277 -397.621158) (xy 351.767311 -397.682941)
			(xy 351.75151 -397.743199) (xy 351.728132 -397.800942) (xy 351.715773 -397.822887) (xy 375.004907 -397.822887)
			(xy 375.004912 -397.757448) (xy 375.0137 -397.692601) (xy 375.031114 -397.629521) (xy 375.056838 -397.569349)
			(xy 375.073164 -397.540988) (xy 375.07648 -397.534964) (xy 375.080085 -397.5217) (xy 375.080276 -397.514826)
			(xy 375.080276 -396.765526) (xy 375.080077 -396.758653) (xy 375.076474 -396.74539) (xy 375.073164 -396.739364)
			(xy 375.056833 -396.711008) (xy 375.031114 -396.650836) (xy 375.013706 -396.587756) (xy 375.004923 -396.52291)
			(xy 375.004924 -396.457473) (xy 375.01371 -396.392627) (xy 375.03112 -396.329548) (xy 375.05684 -396.269377)
			(xy 375.073164 -396.241016) (xy 375.07647 -396.234987) (xy 375.080082 -396.221727) (xy 375.080276 -396.214854)
			(xy 375.080276 -395.92885) (xy 375.080706 -395.918677) (xy 375.088481 -395.899876) (xy 375.102866 -395.885488)
			(xy 375.121665 -395.877708) (xy 375.131838 -395.877288) (xy 375.848118 -395.877288) (xy 375.858297 -395.87765)
			(xy 375.877102 -395.885451) (xy 375.891487 -395.899856) (xy 375.899263 -395.91867) (xy 375.89968 -395.92885)
			(xy 375.89968 -396.214854) (xy 375.899892 -396.221726) (xy 375.903487 -396.234988) (xy 375.906792 -396.241016)
			(xy 375.923105 -396.269382) (xy 375.948822 -396.329553) (xy 375.966229 -396.39263) (xy 375.975013 -396.457474)
			(xy 375.975015 -396.522909) (xy 375.966233 -396.587753) (xy 375.948827 -396.650831) (xy 375.923113 -396.711002)
			(xy 375.906792 -396.739364) (xy 375.903489 -396.745395) (xy 375.899876 -396.758654) (xy 375.89968 -396.765526)
			(xy 375.89968 -397.514826) (xy 375.899865 -397.5217) (xy 375.903478 -397.534962) (xy 375.906792 -397.540988)
			(xy 375.923081 -397.569367) (xy 375.9488 -397.629535) (xy 375.966211 -397.69261) (xy 375.974998 -397.757451)
			(xy 375.975002 -397.822884) (xy 375.966224 -397.887726) (xy 375.948822 -397.950804) (xy 375.923111 -398.010974)
			(xy 375.906792 -398.039336) (xy 375.903464 -398.045354) (xy 375.899867 -398.058623) (xy 375.89968 -398.065498)
			(xy 375.89968 -398.351502) (xy 375.899169 -398.361658) (xy 375.891397 -398.380423) (xy 375.877037 -398.394788)
			(xy 375.858274 -398.402565) (xy 375.848118 -398.403064) (xy 375.131838 -398.403064) (xy 375.121669 -398.402605)
			(xy 375.102876 -398.394833) (xy 375.08849 -398.380458) (xy 375.080703 -398.361671) (xy 375.080276 -398.351502)
			(xy 375.080276 -398.065498) (xy 375.080088 -398.058624) (xy 375.076477 -398.045362) (xy 375.073164 -398.039336)
			(xy 375.056809 -398.010993) (xy 375.031093 -397.950818) (xy 375.013687 -397.887735) (xy 375.004907 -397.822887)
			(xy 351.715773 -397.822887) (xy 351.697563 -397.855221) (xy 351.660303 -397.905145) (xy 351.616966 -397.949895)
			(xy 351.568261 -397.988735) (xy 351.51499 -398.021028) (xy 351.458027 -398.046245) (xy 351.398306 -398.063969)
			(xy 351.336809 -398.073912) (xy 351.274546 -398.075908) (xy 351.212539 -398.069926) (xy 351.151805 -398.056064)
			(xy 351.093343 -398.03455) (xy 351.038112 -398.005736) (xy 350.98702 -397.970096) (xy 350.940904 -397.928215)
			(xy 350.900522 -397.88078) (xy 350.866538 -397.828571) (xy 350.839509 -397.772445) (xy 350.81988 -397.713324)
			(xy 350.807971 -397.652177) (xy 350.80398 -397.59001) (xy 349.532382 -397.59001) (xy 349.551449 -397.6372)
			(xy 349.567195 -397.697372) (xy 349.575129 -397.759063) (xy 349.575628 -397.790162) (xy 349.575133 -397.821962)
			(xy 349.566836 -397.885017) (xy 349.550379 -397.94645) (xy 349.526043 -398.005209) (xy 349.494246 -398.060289)
			(xy 349.455531 -398.110747) (xy 349.41056 -398.155719) (xy 349.360104 -398.194436) (xy 349.305025 -398.226235)
			(xy 349.246267 -398.250573) (xy 349.184835 -398.267032) (xy 349.12178 -398.275332) (xy 349.08998 -398.27581)
			(xy 349.089472 -398.27581) (xy 349.08871 -398.27581) (xy 349.087948 -398.27581) (xy 349.058115 -398.275371)
			(xy 348.998893 -398.268113) (xy 348.969838 -398.261332) (xy 348.958408 -398.259808) (xy 348.957138 -398.259808)
			(xy 348.947228 -398.287358) (xy 348.924607 -398.341368) (xy 348.911926 -398.367758) (xy 348.9071 -398.384522)
			(xy 348.90367 -398.410727) (xy 348.890518 -398.461913) (xy 348.870432 -398.510796) (xy 348.843796 -398.556442)
			(xy 348.811121 -398.597979) (xy 348.773029 -398.634613) (xy 348.730249 -398.665643) (xy 348.683599 -398.690478)
			(xy 348.658942 -398.69999) (xy 348.653608 -398.702276) (xy 348.465524 -398.890236) (xy 350.80398 -398.890236)
			(xy 350.807971 -398.828069) (xy 350.81988 -398.766922) (xy 350.839509 -398.707801) (xy 350.866538 -398.651675)
			(xy 350.900522 -398.599466) (xy 350.940904 -398.552031) (xy 350.98702 -398.51015) (xy 351.038112 -398.47451)
			(xy 351.093343 -398.445696) (xy 351.151805 -398.424182) (xy 351.212539 -398.41032) (xy 351.274546 -398.404338)
			(xy 351.336809 -398.406334) (xy 351.398306 -398.416277) (xy 351.458027 -398.434001) (xy 351.481667 -398.444466)
			(xy 363.577884 -398.444466) (xy 363.581955 -398.388844) (xy 363.594081 -398.334407) (xy 363.614004 -398.282316)
			(xy 363.6413 -398.233681) (xy 363.675386 -398.189538) (xy 363.715535 -398.150829) (xy 363.760893 -398.118378)
			(xy 363.810493 -398.092877) (xy 363.863277 -398.07487) (xy 363.91812 -398.06474) (xy 363.973854 -398.062703)
			(xy 364.029291 -398.068803) (xy 364.083248 -398.082909) (xy 364.134577 -398.104721) (xy 364.182183 -398.133775)
			(xy 364.225051 -398.16945) (xy 364.262268 -398.210987) (xy 364.293041 -398.2575) (xy 364.316713 -398.307997)
			(xy 364.332781 -398.361404) (xy 364.340901 -398.41658) (xy 364.34141 -398.444466) (xy 364.340901 -398.472352)
			(xy 364.332781 -398.527528) (xy 364.316713 -398.580935) (xy 364.293041 -398.631432) (xy 364.262268 -398.677945)
			(xy 364.225051 -398.719482) (xy 364.182183 -398.755157) (xy 364.134577 -398.784211) (xy 364.083248 -398.806023)
			(xy 364.029291 -398.820129) (xy 363.973854 -398.826229) (xy 363.91812 -398.824192) (xy 363.863277 -398.814062)
			(xy 363.810493 -398.796055) (xy 363.760893 -398.770554) (xy 363.715535 -398.738103) (xy 363.675386 -398.699394)
			(xy 363.6413 -398.655251) (xy 363.614004 -398.606616) (xy 363.594081 -398.554525) (xy 363.581955 -398.500088)
			(xy 363.577884 -398.444466) (xy 351.481667 -398.444466) (xy 351.51499 -398.459218) (xy 351.568261 -398.491511)
			(xy 351.616966 -398.530351) (xy 351.660303 -398.575101) (xy 351.697563 -398.625025) (xy 351.728132 -398.679304)
			(xy 351.75151 -398.737047) (xy 351.767311 -398.797305) (xy 351.775277 -398.859088) (xy 351.775776 -398.890236)
			(xy 351.775277 -398.921384) (xy 351.767311 -398.983167) (xy 351.75151 -399.043425) (xy 351.728132 -399.101168)
			(xy 351.697563 -399.155447) (xy 351.660303 -399.205371) (xy 351.646206 -399.219928) (xy 357.060752 -399.219928)
			(xy 357.064823 -399.164306) (xy 357.076949 -399.109869) (xy 357.096872 -399.057778) (xy 357.124168 -399.009143)
			(xy 357.158254 -398.965) (xy 357.198403 -398.926291) (xy 357.243761 -398.89384) (xy 357.293361 -398.868339)
			(xy 357.346145 -398.850332) (xy 357.400988 -398.840202) (xy 357.456722 -398.838165) (xy 357.512159 -398.844265)
			(xy 357.566116 -398.858371) (xy 357.617445 -398.880183) (xy 357.633917 -398.890236) (xy 377.204224 -398.890236)
			(xy 377.20478 -398.857506) (xy 377.213638 -398.792647) (xy 377.231131 -398.729567) (xy 377.256942 -398.66941)
			(xy 377.273312 -398.641062) (xy 377.276641 -398.635044) (xy 377.280237 -398.621775) (xy 377.280424 -398.6149)
			(xy 377.280424 -397.865346) (xy 377.280212 -397.858474) (xy 377.276617 -397.845212) (xy 377.273312 -397.839184)
			(xy 377.256941 -397.810838) (xy 377.23114 -397.750677) (xy 377.213652 -397.687597) (xy 377.204793 -397.622739)
			(xy 377.204224 -397.59001) (xy 377.204769 -397.55728) (xy 377.21363 -397.492421) (xy 377.231127 -397.42934)
			(xy 377.25694 -397.369183) (xy 377.273312 -397.340836) (xy 377.276615 -397.334806) (xy 377.280228 -397.321546)
			(xy 377.280424 -397.314674) (xy 377.280424 -397.028924) (xy 377.280836 -397.0188) (xy 377.288581 -397.000092)
			(xy 377.302899 -396.985776) (xy 377.321608 -396.978034) (xy 377.331732 -396.977616) (xy 378.048012 -396.977616)
			(xy 378.058137 -396.978006) (xy 378.076844 -396.985761) (xy 378.091159 -397.000086) (xy 378.098901 -397.018798)
			(xy 378.09932 -397.028924) (xy 378.09932 -397.314674) (xy 378.09952 -397.321547) (xy 378.103122 -397.33481)
			(xy 378.106432 -397.340836) (xy 378.122805 -397.369181) (xy 378.148607 -397.429342) (xy 378.166095 -397.492422)
			(xy 378.174952 -397.557281) (xy 378.17552 -397.59001) (xy 378.174933 -397.622739) (xy 378.166083 -397.687596)
			(xy 378.148599 -397.750676) (xy 378.131664 -397.790162) (xy 379.404372 -397.790162) (xy 379.404947 -397.757433)
			(xy 379.413801 -397.692575) (xy 379.431288 -397.629495) (xy 379.457093 -397.569337) (xy 379.47346 -397.540988)
			(xy 379.476776 -397.534964) (xy 379.480381 -397.5217) (xy 379.480572 -397.514826) (xy 379.480572 -396.765526)
			(xy 379.480374 -396.758653) (xy 379.47677 -396.74539) (xy 379.47346 -396.739364) (xy 379.457086 -396.711019)
			(xy 379.431285 -396.650859) (xy 379.413797 -396.587778) (xy 379.40494 -396.522919) (xy 379.404372 -396.49019)
			(xy 379.40496 -396.457461) (xy 379.41381 -396.392604) (xy 379.431294 -396.329524) (xy 379.457095 -396.269365)
			(xy 379.47346 -396.241016) (xy 379.476766 -396.234987) (xy 379.480377 -396.221727) (xy 379.480572 -396.214854)
			(xy 379.480572 -395.92885) (xy 379.481069 -395.918723) (xy 379.488786 -395.899996) (xy 379.50307 -395.885637)
			(xy 379.521755 -395.877822) (xy 379.53188 -395.877288) (xy 380.24816 -395.877288) (xy 380.25831 -395.877754)
			(xy 380.277059 -395.885534) (xy 380.291384 -395.899917) (xy 380.299087 -395.918698) (xy 380.299468 -395.92885)
			(xy 380.299468 -396.214854) (xy 380.299681 -396.221726) (xy 380.303275 -396.234988) (xy 380.30658 -396.241016)
			(xy 380.32295 -396.269363) (xy 380.348751 -396.329523) (xy 380.36624 -396.392603) (xy 380.375099 -396.457461)
			(xy 380.375668 -396.49019) (xy 380.375111 -396.52292) (xy 380.366251 -396.587778) (xy 380.348758 -396.650858)
			(xy 380.322949 -396.711016) (xy 380.30658 -396.739364) (xy 380.303277 -396.745394) (xy 380.299664 -396.758654)
			(xy 380.299468 -396.765526) (xy 380.299468 -397.514826) (xy 380.299654 -397.5217) (xy 380.303267 -397.534962)
			(xy 380.30658 -397.540988) (xy 380.315986 -397.557291) (xy 381.604878 -397.557291) (xy 381.61366 -397.492447)
			(xy 381.631065 -397.429369) (xy 381.65678 -397.369198) (xy 381.6731 -397.340836) (xy 381.676402 -397.334805)
			(xy 381.680016 -397.321546) (xy 381.680212 -397.314674) (xy 381.680212 -397.028924) (xy 381.680641 -397.01877)
			(xy 381.688431 -397.000016) (xy 381.702826 -396.985691) (xy 381.721618 -396.977993) (xy 381.731774 -396.977616)
			(xy 382.448054 -396.977616) (xy 382.458175 -396.978164) (xy 382.47689 -396.985872) (xy 382.491247 -397.000139)
			(xy 382.499072 -397.018806) (xy 382.499616 -397.028924) (xy 382.499616 -397.314674) (xy 382.499816 -397.321547)
			(xy 382.503419 -397.334809) (xy 382.506728 -397.340836) (xy 382.52306 -397.369192) (xy 382.548778 -397.429364)
			(xy 382.566187 -397.492444) (xy 382.57497 -397.55729) (xy 382.574969 -397.622727) (xy 382.566183 -397.687573)
			(xy 382.548773 -397.750652) (xy 382.523052 -397.810823) (xy 382.516108 -397.822887) (xy 383.804994 -397.822887)
			(xy 383.804998 -397.757448) (xy 383.813786 -397.692601) (xy 383.8312 -397.629521) (xy 383.856923 -397.569349)
			(xy 383.873248 -397.540988) (xy 383.876563 -397.534963) (xy 383.880169 -397.5217) (xy 383.88036 -397.514826)
			(xy 383.88036 -396.765526) (xy 383.880163 -396.758653) (xy 383.876559 -396.74539) (xy 383.873248 -396.739364)
			(xy 383.856917 -396.711008) (xy 383.8312 -396.650835) (xy 383.813792 -396.587756) (xy 383.80501 -396.52291)
			(xy 383.805011 -396.457473) (xy 383.813796 -396.392628) (xy 383.831205 -396.329548) (xy 383.856925 -396.269377)
			(xy 383.873248 -396.241016) (xy 383.876553 -396.234986) (xy 383.880165 -396.221727) (xy 383.88036 -396.214854)
			(xy 383.88036 -395.92885) (xy 383.880805 -395.918679) (xy 383.888578 -395.899881) (xy 383.902958 -395.885494)
			(xy 383.921751 -395.877711) (xy 383.931922 -395.877288) (xy 384.648202 -395.877288) (xy 384.65838 -395.877663)
			(xy 384.677184 -395.885458) (xy 384.691571 -395.899859) (xy 384.699347 -395.918672) (xy 384.699764 -395.92885)
			(xy 384.699764 -396.214854) (xy 384.699978 -396.221726) (xy 384.703572 -396.234988) (xy 384.706876 -396.241016)
			(xy 384.723189 -396.269382) (xy 384.748907 -396.329552) (xy 384.766315 -396.39263) (xy 384.7751 -396.457474)
			(xy 384.775101 -396.522909) (xy 384.766319 -396.587753) (xy 384.748913 -396.650831) (xy 384.723197 -396.711003)
			(xy 384.706876 -396.739364) (xy 384.703572 -396.745394) (xy 384.69996 -396.758654) (xy 384.699764 -396.765526)
			(xy 384.699764 -397.514826) (xy 384.699951 -397.5217) (xy 384.703563 -397.534962) (xy 384.706876 -397.540988)
			(xy 384.723166 -397.569367) (xy 384.748885 -397.629534) (xy 384.766296 -397.692609) (xy 384.775084 -397.75745)
			(xy 384.775088 -397.822884) (xy 384.76631 -397.887727) (xy 384.748907 -397.950804) (xy 384.723195 -398.010975)
			(xy 384.706876 -398.039336) (xy 384.703547 -398.045353) (xy 384.699951 -398.058623) (xy 384.699764 -398.065498)
			(xy 384.699764 -398.351502) (xy 384.699268 -398.36166) (xy 384.691494 -398.380428) (xy 384.677128 -398.394794)
			(xy 384.65836 -398.402568) (xy 384.648202 -398.403064) (xy 383.931922 -398.403064) (xy 383.921752 -398.402618)
			(xy 383.902958 -398.394841) (xy 383.888573 -398.380462) (xy 383.880787 -398.361672) (xy 383.88036 -398.351502)
			(xy 383.88036 -398.065498) (xy 383.880174 -398.058624) (xy 383.876562 -398.045361) (xy 383.873248 -398.039336)
			(xy 383.856893 -398.010993) (xy 383.831178 -397.950817) (xy 383.813773 -397.887735) (xy 383.804994 -397.822887)
			(xy 382.516108 -397.822887) (xy 382.506728 -397.839184) (xy 382.503421 -397.845212) (xy 382.49981 -397.858473)
			(xy 382.499616 -397.865346) (xy 382.499616 -398.6149) (xy 382.499806 -398.621773) (xy 382.503416 -398.635036)
			(xy 382.506728 -398.641062) (xy 382.523082 -398.669406) (xy 382.548798 -398.729581) (xy 382.566204 -398.792663)
			(xy 382.574985 -398.857511) (xy 382.574982 -398.890236) (xy 386.004308 -398.890236) (xy 386.004867 -398.857506)
			(xy 386.013724 -398.792648) (xy 386.031217 -398.729568) (xy 386.057026 -398.66941) (xy 386.073396 -398.641062)
			(xy 386.076724 -398.635044) (xy 386.080321 -398.621775) (xy 386.080508 -398.6149) (xy 386.080508 -397.865346)
			(xy 386.080297 -397.858474) (xy 386.076702 -397.845211) (xy 386.073396 -397.839184) (xy 386.057024 -397.810838)
			(xy 386.031224 -397.750678) (xy 386.013736 -397.687597) (xy 386.004877 -397.622739) (xy 386.004308 -397.59001)
			(xy 386.004855 -397.55728) (xy 386.013716 -397.492421) (xy 386.031212 -397.429341) (xy 386.057025 -397.369183)
			(xy 386.073396 -397.340836) (xy 386.076698 -397.334805) (xy 386.080312 -397.321546) (xy 386.080508 -397.314674)
			(xy 386.080508 -397.028924) (xy 386.080936 -397.018802) (xy 386.088677 -397.000097) (xy 386.102991 -396.985782)
			(xy 386.121694 -396.978037) (xy 386.131816 -396.977616) (xy 386.848096 -396.977616) (xy 386.85822 -396.97802)
			(xy 386.876927 -396.985769) (xy 386.891242 -397.00009) (xy 386.898984 -397.0188) (xy 386.899404 -397.028924)
			(xy 386.899404 -397.314674) (xy 386.899606 -397.321547) (xy 386.903207 -397.334809) (xy 386.906516 -397.340836)
			(xy 386.922897 -397.369176) (xy 386.948695 -397.429339) (xy 386.96618 -397.492421) (xy 386.975036 -397.55728)
			(xy 386.975604 -397.59001) (xy 386.97502 -397.622739) (xy 386.966169 -397.687596) (xy 386.948684 -397.750677)
			(xy 386.922882 -397.810835) (xy 386.915924 -397.822887) (xy 388.204783 -397.822887) (xy 388.204788 -397.757448)
			(xy 388.213576 -397.692601) (xy 388.230989 -397.629521) (xy 388.256711 -397.569349) (xy 388.273036 -397.540988)
			(xy 388.27635 -397.534963) (xy 388.279957 -397.5217) (xy 388.280148 -397.514826) (xy 388.280148 -396.765526)
			(xy 388.279953 -396.758653) (xy 388.276347 -396.74539) (xy 388.273036 -396.739364) (xy 388.256705 -396.711007)
			(xy 388.230989 -396.650835) (xy 388.213582 -396.587755) (xy 388.204799 -396.52291) (xy 388.2048 -396.457473)
			(xy 388.213585 -396.392628) (xy 388.230994 -396.329549) (xy 388.256713 -396.269377) (xy 388.273036 -396.241016)
			(xy 388.27634 -396.234986) (xy 388.279953 -396.221727) (xy 388.280148 -396.214854) (xy 388.280148 -395.92885)
			(xy 388.280605 -395.91868) (xy 388.288375 -395.899885) (xy 388.302751 -395.885498) (xy 388.321541 -395.877713)
			(xy 388.33171 -395.877288) (xy 389.04799 -395.877288) (xy 389.058167 -395.877673) (xy 389.076971 -395.885464)
			(xy 389.091358 -395.899862) (xy 389.099135 -395.918672) (xy 389.099552 -395.92885) (xy 389.099552 -396.214854)
			(xy 389.099755 -396.221727) (xy 389.103355 -396.23499) (xy 389.106664 -396.241016) (xy 389.122978 -396.269382)
			(xy 389.148696 -396.329552) (xy 389.166105 -396.39263) (xy 389.174889 -396.457473) (xy 389.174891 -396.522909)
			(xy 389.166108 -396.587753) (xy 389.148702 -396.650832) (xy 389.122985 -396.711003) (xy 389.106664 -396.739364)
			(xy 389.103367 -396.745397) (xy 389.099749 -396.758654) (xy 389.099552 -396.765526) (xy 389.099552 -397.514826)
			(xy 389.099728 -397.521701) (xy 389.103346 -397.534964) (xy 389.106664 -397.540988) (xy 389.116022 -397.55729)
			(xy 390.404951 -397.55729) (xy 390.413734 -397.492446) (xy 390.431142 -397.429367) (xy 390.456861 -397.369197)
			(xy 390.473184 -397.340836) (xy 390.476485 -397.334805) (xy 390.4801 -397.321546) (xy 390.480296 -397.314674)
			(xy 390.480296 -397.028924) (xy 390.480741 -397.018772) (xy 390.488528 -397.000021) (xy 390.502918 -396.985697)
			(xy 390.521704 -396.977995) (xy 390.531858 -396.977616) (xy 391.248138 -396.977616) (xy 391.258264 -396.978095)
			(xy 391.276982 -396.985831) (xy 391.291336 -397.000119) (xy 391.299158 -397.0188) (xy 391.2997 -397.028924)
			(xy 391.2997 -397.314674) (xy 391.299902 -397.321546) (xy 391.303504 -397.334809) (xy 391.306812 -397.340836)
			(xy 391.323141 -397.369193) (xy 391.348855 -397.429366) (xy 391.366261 -397.492445) (xy 391.375042 -397.55729)
			(xy 391.375041 -397.622727) (xy 391.366257 -397.687571) (xy 391.34885 -397.75065) (xy 391.323133 -397.810822)
			(xy 391.306812 -397.839184) (xy 391.303504 -397.845212) (xy 391.299894 -397.858473) (xy 391.2997 -397.865346)
			(xy 391.2997 -398.6149) (xy 391.299892 -398.621773) (xy 391.3035 -398.635036) (xy 391.306812 -398.641062)
			(xy 391.323163 -398.669407) (xy 391.348875 -398.729583) (xy 391.366278 -398.792665) (xy 391.375057 -398.857512)
			(xy 391.375053 -398.92295) (xy 391.366266 -398.987796) (xy 391.348855 -399.050876) (xy 391.323135 -399.111048)
			(xy 391.306812 -399.13941) (xy 391.303495 -399.145433) (xy 391.29989 -399.158698) (xy 391.2997 -399.165572)
			(xy 391.2997 -399.451576) (xy 391.299259 -399.461729) (xy 391.291471 -399.480481) (xy 391.27708 -399.494805)
			(xy 391.258292 -399.502505) (xy 391.248138 -399.502884) (xy 390.531858 -399.502884) (xy 390.521732 -399.502409)
			(xy 390.503014 -399.494671) (xy 390.48866 -399.480382) (xy 390.480838 -399.4617) (xy 390.480296 -399.451576)
			(xy 390.480296 -399.165572) (xy 390.480115 -399.158698) (xy 390.4765 -399.145435) (xy 390.473184 -399.13941)
			(xy 390.456891 -399.111032) (xy 390.431168 -399.050866) (xy 390.413755 -398.98779) (xy 390.404967 -398.922948)
			(xy 390.404963 -398.857513) (xy 390.413743 -398.79267) (xy 390.431148 -398.729593) (xy 390.456863 -398.669423)
			(xy 390.473184 -398.641062) (xy 390.476511 -398.635043) (xy 390.480109 -398.621775) (xy 390.480296 -398.6149)
			(xy 390.480296 -397.865346) (xy 390.480087 -397.858474) (xy 390.47649 -397.845211) (xy 390.473184 -397.839184)
			(xy 390.456869 -397.810819) (xy 390.431148 -397.750649) (xy 390.413737 -397.687571) (xy 390.404952 -397.622727)
			(xy 390.404951 -397.55729) (xy 389.116022 -397.55729) (xy 389.122954 -397.569367) (xy 389.148674 -397.629534)
			(xy 389.166086 -397.692609) (xy 389.174873 -397.75745) (xy 389.174878 -397.822884) (xy 389.166099 -397.887727)
			(xy 389.148696 -397.950804) (xy 389.122984 -398.010975) (xy 389.106664 -398.039336) (xy 389.103341 -398.045357)
			(xy 389.09974 -398.058623) (xy 389.099552 -398.065498) (xy 389.099552 -398.351502) (xy 389.099138 -398.361675)
			(xy 389.09135 -398.380472) (xy 389.076962 -398.394857) (xy 389.058163 -398.40264) (xy 389.04799 -398.403064)
			(xy 388.33171 -398.403064) (xy 388.321539 -398.402628) (xy 388.302745 -398.394847) (xy 388.28836 -398.380465)
			(xy 388.280574 -398.361673) (xy 388.280148 -398.351502) (xy 388.280148 -398.065498) (xy 388.279963 -398.058624)
			(xy 388.276351 -398.045361) (xy 388.273036 -398.039336) (xy 388.256682 -398.010992) (xy 388.230967 -397.950817)
			(xy 388.213563 -397.887735) (xy 388.204783 -397.822887) (xy 386.915924 -397.822887) (xy 386.906516 -397.839184)
			(xy 386.903208 -397.845212) (xy 386.899598 -397.858473) (xy 386.899404 -397.865346) (xy 386.899404 -398.6149)
			(xy 386.899595 -398.621773) (xy 386.903204 -398.635036) (xy 386.906516 -398.641062) (xy 386.922868 -398.669419)
			(xy 386.948673 -398.729576) (xy 386.966166 -398.792653) (xy 386.975031 -398.857508) (xy 386.975604 -398.890236)
			(xy 386.975031 -398.922965) (xy 386.966177 -398.987823) (xy 386.948689 -399.050903) (xy 386.922884 -399.111062)
			(xy 386.906516 -399.13941) (xy 386.903199 -399.145433) (xy 386.899594 -399.158698) (xy 386.899404 -399.165572)
			(xy 386.899404 -399.451576) (xy 386.898965 -399.461696) (xy 386.891225 -399.480399) (xy 386.876916 -399.494714)
			(xy 386.858216 -399.502461) (xy 386.848096 -399.502884) (xy 386.131816 -399.502884) (xy 386.121693 -399.502471)
			(xy 386.102986 -399.494725) (xy 386.088671 -399.480407) (xy 386.080928 -399.4617) (xy 386.080508 -399.451576)
			(xy 386.080508 -399.165572) (xy 386.080326 -399.158698) (xy 386.076711 -399.145435) (xy 386.073396 -399.13941)
			(xy 386.057034 -399.111059) (xy 386.031231 -399.0509) (xy 386.013741 -398.987821) (xy 386.004879 -398.922965)
			(xy 386.004308 -398.890236) (xy 382.574982 -398.890236) (xy 382.57498 -398.922951) (xy 382.566192 -398.987797)
			(xy 382.548778 -399.050878) (xy 382.523054 -399.111049) (xy 382.506728 -399.13941) (xy 382.503412 -399.145434)
			(xy 382.499807 -399.158698) (xy 382.499616 -399.165572) (xy 382.499616 -399.451576) (xy 382.499159 -399.461727)
			(xy 382.491375 -399.480475) (xy 382.476989 -399.494799) (xy 382.458206 -399.502503) (xy 382.448054 -399.502884)
			(xy 381.731774 -399.502884) (xy 381.721649 -399.502396) (xy 381.702931 -399.494664) (xy 381.688577 -399.480379)
			(xy 381.680754 -399.461699) (xy 381.680212 -399.451576) (xy 381.680212 -399.165572) (xy 381.680029 -399.158698)
			(xy 381.676415 -399.145435) (xy 381.6731 -399.13941) (xy 381.656809 -399.111032) (xy 381.631091 -399.050864)
			(xy 381.613681 -398.987789) (xy 381.604894 -398.922948) (xy 381.60489 -398.857514) (xy 381.613669 -398.792672)
			(xy 381.631071 -398.729594) (xy 381.656781 -398.669424) (xy 381.6731 -398.641062) (xy 381.676428 -398.635044)
			(xy 381.680025 -398.621775) (xy 381.680212 -398.6149) (xy 381.680212 -397.865346) (xy 381.680001 -397.858474)
			(xy 381.676405 -397.845212) (xy 381.6731 -397.839184) (xy 381.656787 -397.810818) (xy 381.631071 -397.750647)
			(xy 381.613663 -397.68757) (xy 381.60488 -397.622726) (xy 381.604878 -397.557291) (xy 380.315986 -397.557291)
			(xy 380.322939 -397.569341) (xy 380.348743 -397.629499) (xy 380.366234 -397.692577) (xy 380.375097 -397.757433)
			(xy 380.375668 -397.790162) (xy 380.375098 -397.822891) (xy 380.366242 -397.887749) (xy 380.348753 -397.950829)
			(xy 380.322948 -398.010988) (xy 380.30658 -398.039336) (xy 380.303251 -398.045354) (xy 380.299655 -398.058623)
			(xy 380.299468 -398.065498) (xy 380.299468 -398.351502) (xy 380.298975 -398.361628) (xy 380.291248 -398.380347)
			(xy 380.276964 -398.394703) (xy 380.258283 -398.402524) (xy 380.24816 -398.403064) (xy 379.53188 -398.403064)
			(xy 379.52172 -398.402694) (xy 379.50296 -398.394885) (xy 379.488636 -398.380472) (xy 379.480944 -398.361664)
			(xy 379.480572 -398.351502) (xy 379.480572 -398.065498) (xy 379.480384 -398.058624) (xy 379.476773 -398.045362)
			(xy 379.47346 -398.039336) (xy 379.457114 -398.010976) (xy 379.431306 -397.950821) (xy 379.413811 -397.887744)
			(xy 379.404945 -397.82289) (xy 379.404372 -397.790162) (xy 378.131664 -397.790162) (xy 378.122798 -397.810835)
			(xy 378.106432 -397.839184) (xy 378.103126 -397.845213) (xy 378.099514 -397.858473) (xy 378.09932 -397.865346)
			(xy 378.09932 -398.6149) (xy 378.09951 -398.621773) (xy 378.103119 -398.635036) (xy 378.106432 -398.641062)
			(xy 378.122776 -398.669423) (xy 378.148585 -398.729578) (xy 378.166081 -398.792654) (xy 378.174947 -398.857508)
			(xy 378.17552 -398.890236) (xy 378.174945 -398.922965) (xy 378.166092 -398.987823) (xy 378.148604 -399.050903)
			(xy 378.122799 -399.111061) (xy 378.106432 -399.13941) (xy 378.103116 -399.145434) (xy 378.099511 -399.158698)
			(xy 378.09932 -399.165572) (xy 378.09932 -399.451576) (xy 378.098865 -399.461694) (xy 378.091128 -399.480394)
			(xy 378.076824 -399.494708) (xy 378.05813 -399.502458) (xy 378.048012 -399.502884) (xy 377.331732 -399.502884)
			(xy 377.32161 -399.502458) (xy 377.302903 -399.494717) (xy 377.288587 -399.480403) (xy 377.280844 -399.461698)
			(xy 377.280424 -399.451576) (xy 377.280424 -399.165572) (xy 377.28024 -399.158698) (xy 377.276626 -399.145436)
			(xy 377.273312 -399.13941) (xy 377.256952 -399.111058) (xy 377.231148 -399.0509) (xy 377.213657 -398.987821)
			(xy 377.204795 -398.922965) (xy 377.204224 -398.890236) (xy 357.633917 -398.890236) (xy 357.665051 -398.909237)
			(xy 357.707919 -398.944912) (xy 357.745136 -398.986449) (xy 357.775909 -399.032962) (xy 357.799581 -399.083459)
			(xy 357.815649 -399.136866) (xy 357.823769 -399.192042) (xy 357.824278 -399.219928) (xy 357.823769 -399.247814)
			(xy 357.815649 -399.30299) (xy 357.799581 -399.356397) (xy 357.775909 -399.406894) (xy 357.745136 -399.453407)
			(xy 357.707919 -399.494944) (xy 357.665051 -399.530619) (xy 357.617445 -399.559673) (xy 357.566116 -399.581485)
			(xy 357.512159 -399.595591) (xy 357.456722 -399.601691) (xy 357.400988 -399.599654) (xy 357.346145 -399.589524)
			(xy 357.293361 -399.571517) (xy 357.243761 -399.546016) (xy 357.198403 -399.513565) (xy 357.158254 -399.474856)
			(xy 357.124168 -399.430713) (xy 357.096872 -399.382078) (xy 357.076949 -399.329987) (xy 357.064823 -399.27555)
			(xy 357.060752 -399.219928) (xy 351.646206 -399.219928) (xy 351.616966 -399.250121) (xy 351.568261 -399.288961)
			(xy 351.51499 -399.321254) (xy 351.458027 -399.346471) (xy 351.398306 -399.364195) (xy 351.336809 -399.374138)
			(xy 351.274546 -399.376134) (xy 351.212539 -399.370152) (xy 351.151805 -399.35629) (xy 351.093343 -399.334776)
			(xy 351.038112 -399.305962) (xy 350.98702 -399.270322) (xy 350.940904 -399.228441) (xy 350.900522 -399.181006)
			(xy 350.866538 -399.128797) (xy 350.839509 -399.072671) (xy 350.81988 -399.01355) (xy 350.807971 -398.952403)
			(xy 350.80398 -398.890236) (xy 348.465524 -398.890236) (xy 348.269306 -399.086324) (xy 348.236408 -399.118509)
			(xy 348.165636 -399.177356) (xy 348.089742 -399.229429) (xy 348.009371 -399.274286) (xy 347.925209 -399.311545)
			(xy 347.83797 -399.340887) (xy 347.79331 -399.352008) (xy 347.760798 -399.376646) (xy 347.738854 -399.414913)
			(xy 347.689183 -399.487819) (xy 347.633267 -399.556054) (xy 347.571542 -399.619083) (xy 347.504491 -399.676413)
			(xy 347.432639 -399.727598) (xy 347.356547 -399.772236) (xy 347.276809 -399.809978) (xy 347.19405 -399.84053)
			(xy 347.108915 -399.863653) (xy 347.022071 -399.879167) (xy 346.934196 -399.886948) (xy 346.890086 -399.88744)
			(xy 346.889832 -399.88744) (xy 346.846763 -399.886976) (xy 346.760948 -399.879524) (xy 346.676097 -399.864689)
			(xy 346.592844 -399.842583) (xy 346.511811 -399.81337) (xy 346.47251 -399.795746) (xy 346.467176 -399.797016)
			(xy 346.444931 -399.80537) (xy 346.398889 -399.817124) (xy 346.351743 -399.823064) (xy 346.327984 -399.823432)
			(xy 346.300733 -399.822945) (xy 346.246786 -399.815187) (xy 346.194491 -399.799831) (xy 346.144915 -399.777189)
			(xy 346.099065 -399.747723) (xy 346.057874 -399.712031) (xy 346.022182 -399.670842) (xy 345.992715 -399.624992)
			(xy 345.970072 -399.575416) (xy 345.954715 -399.523122) (xy 345.946955 -399.469175) (xy 345.946476 -399.441924)
			(xy 345.946476 -399.441416) (xy 345.946806 -399.41703) (xy 345.95292 -399.368644) (xy 345.965164 -399.321435)
			(xy 345.973908 -399.298668) (xy 345.975686 -399.289778) (xy 345.97594 -399.289016) (xy 345.959899 -399.251245)
			(xy 345.933348 -399.173591) (xy 345.913274 -399.094016) (xy 345.899815 -399.013059) (xy 345.893061 -398.93127)
			(xy 345.892628 -398.890236) (xy 345.892628 -398.50822) (xy 345.893103 -398.465231) (xy 345.900549 -398.379575)
			(xy 345.915336 -398.294877) (xy 345.925902 -398.253204) (xy 345.92768 -398.24025) (xy 345.925902 -398.227296)
			(xy 345.91988 -398.203834) (xy 345.909842 -398.156443) (xy 345.905836 -398.132554) (xy 345.90355 -398.119854)
			(xy 345.889834 -398.102074) (xy 345.881706 -398.094962) (xy 345.881198 -398.094454) (xy 345.872816 -398.089628)
			(xy 345.87053 -398.088612) (xy 345.799918 -398.060418) (xy 345.79591 -398.059136) (xy 345.787614 -398.057734)
			(xy 345.783408 -398.057624) (xy 345.781376 -398.058386) (xy 345.763088 -398.072102) (xy 345.76258 -398.07261)
			(xy 345.730734 -398.096518) (xy 345.663852 -398.139751) (xy 345.628976 -398.15897) (xy 345.621623 -398.163322)
			(xy 345.610089 -398.175914) (xy 345.60637 -398.183608) (xy 345.588281 -398.224497) (xy 345.545806 -398.303182)
			(xy 345.496456 -398.377747) (xy 345.440629 -398.447595) (xy 345.378771 -398.512164) (xy 345.311381 -398.570934)
			(xy 345.239 -398.623435) (xy 345.162208 -398.669245) (xy 345.081624 -398.707995) (xy 344.997893 -398.739373)
			(xy 344.91169 -398.763129) (xy 344.823705 -398.779072) (xy 344.734647 -398.787072) (xy 344.689938 -398.78762)
			(xy 344.646845 -398.78715) (xy 344.560982 -398.779688) (xy 344.476083 -398.764851) (xy 344.392779 -398.742749)
			(xy 344.311691 -398.713547) (xy 344.272362 -398.695926) (xy 344.266266 -398.69745) (xy 344.244126 -398.705676)
			(xy 344.198327 -398.717224) (xy 344.151452 -398.723032) (xy 344.127836 -398.723358) (xy 344.127328 -398.723358)
			(xy 344.109187 -398.723224) (xy 344.073056 -398.719917) (xy 344.055192 -398.716754) (xy 344.048842 -398.715484)
			(xy 344.042492 -398.714976) (xy 344.040968 -398.714722) (xy 344.028776 -398.716246) (xy 343.658444 -399.086324)
			(xy 343.624221 -399.11976) (xy 343.550405 -399.180641) (xy 343.471099 -399.234175) (xy 343.429336 -399.25752)
			(xy 343.422024 -399.261867) (xy 343.410603 -399.274459) (xy 343.406984 -399.282158) (xy 343.388929 -399.32312)
			(xy 343.346506 -399.401952) (xy 343.297188 -399.476665) (xy 343.241371 -399.546656) (xy 343.179506 -399.611362)
			(xy 343.112089 -399.670263) (xy 343.039665 -399.722884) (xy 342.962815 -399.768801) (xy 342.882159 -399.807645)
			(xy 342.798346 -399.839103) (xy 342.71205 -399.862921) (xy 342.623967 -399.878909) (xy 342.534805 -399.886938)
			(xy 342.490044 -399.88744) (xy 342.489282 -399.88744) (xy 342.447941 -399.887015) (xy 342.365545 -399.880153)
			(xy 342.284 -399.866485) (xy 342.203869 -399.846107) (xy 342.125702 -399.819157) (xy 342.087708 -399.802858)
			(xy 342.078056 -399.79854) (xy 342.063578 -399.79854) (xy 342.062562 -399.799048) (xy 342.062308 -399.799048)
			(xy 342.031528 -399.809917) (xy 341.967418 -399.822177) (xy 341.9348 -399.823432) (xy 341.92591 -399.823432)
			(xy 341.898751 -399.822811) (xy 341.845017 -399.814825) (xy 341.79296 -399.799299) (xy 341.743631 -399.776546)
			(xy 341.698028 -399.747025) (xy 341.657073 -399.711335) (xy 341.621594 -399.670197) (xy 341.592309 -399.624443)
			(xy 341.569811 -399.574997) (xy 341.554553 -399.52286) (xy 341.546844 -399.469086) (xy 341.546434 -399.441924)
			(xy 341.546434 -399.440146) (xy 341.546863 -399.416786) (xy 341.552721 -399.370431) (xy 341.564195 -399.325138)
			(xy 341.572342 -399.30324) (xy 341.57285 -399.30197) (xy 341.574882 -399.294858) (xy 341.57539 -399.291302)
			(xy 341.575898 -399.288508) (xy 341.559899 -399.25078) (xy 341.533418 -399.173219) (xy 341.513398 -399.093744)
			(xy 341.499976 -399.012894) (xy 341.49324 -398.931214) (xy 341.49284 -398.890236) (xy 341.49284 -398.507458)
			(xy 341.493309 -398.464601) (xy 341.500685 -398.379205) (xy 341.515362 -398.294758) (xy 341.52586 -398.253204)
			(xy 341.527638 -398.24025) (xy 341.52586 -398.227296) (xy 341.519573 -398.203027) (xy 341.509152 -398.153982)
			(xy 341.505032 -398.129252) (xy 341.501476 -398.106646) (xy 341.499444 -398.104106) (xy 341.494618 -398.100296)
			(xy 341.483188 -398.093946) (xy 341.422228 -398.069054) (xy 341.42172 -398.069054) (xy 341.400892 -398.060672)
			(xy 341.395505 -398.058824) (xy 341.384224 -398.057279) (xy 341.37854 -398.057624) (xy 341.361014 -398.070578)
			(xy 341.330326 -398.092827) (xy 341.266122 -398.133132) (xy 341.232744 -398.151096) (xy 341.20963 -398.176496)
			(xy 341.191746 -398.217802) (xy 341.149559 -398.29732) (xy 341.100375 -398.372711) (xy 341.044596 -398.443362)
			(xy 340.982675 -398.508698) (xy 340.915117 -398.568186) (xy 340.842472 -398.621342) (xy 340.76533 -398.667733)
			(xy 340.684322 -398.706982) (xy 340.600104 -398.738768) (xy 340.513365 -398.762834) (xy 340.424809 -398.778983)
			(xy 340.335158 -398.787084) (xy 340.29015 -398.78762) (xy 340.249555 -398.787178) (xy 340.168638 -398.780513)
			(xy 340.088532 -398.767288) (xy 340.009766 -398.747592) (xy 339.932864 -398.721553) (xy 339.895434 -398.705832)
			(xy 339.894926 -398.705832) (xy 339.871812 -398.695926) (xy 339.867494 -398.696942) (xy 339.863684 -398.698466)
			(xy 339.845904 -398.709896) (xy 339.469222 -399.086324) (xy 339.436324 -399.11851) (xy 339.365553 -399.177357)
			(xy 339.289659 -399.229432) (xy 339.209289 -399.27429) (xy 339.125126 -399.31155) (xy 339.037888 -399.340894)
			(xy 338.993226 -399.352008) (xy 338.960714 -399.376646) (xy 338.93877 -399.414913) (xy 338.8891 -399.487821)
			(xy 338.833183 -399.556056) (xy 338.771459 -399.619086) (xy 338.704408 -399.676418) (xy 338.632556 -399.727603)
			(xy 338.556464 -399.772242) (xy 338.476726 -399.809986) (xy 338.393967 -399.84054) (xy 338.308832 -399.863664)
			(xy 338.221987 -399.879178) (xy 338.134112 -399.886962) (xy 338.090002 -399.88744) (xy 338.089748 -399.88744)
			(xy 338.046679 -399.886977) (xy 337.960863 -399.879526) (xy 337.876012 -399.864692) (xy 337.792758 -399.842587)
			(xy 337.711724 -399.813376) (xy 337.672426 -399.795746) (xy 337.667092 -399.797016) (xy 337.644846 -399.805365)
			(xy 337.598803 -399.817109) (xy 337.551658 -399.823039) (xy 337.5279 -399.823432) (xy 337.500648 -399.822946)
			(xy 337.446699 -399.81519) (xy 337.394403 -399.799835) (xy 337.344824 -399.777194) (xy 337.298972 -399.747728)
			(xy 337.25778 -399.712037) (xy 337.222086 -399.670847) (xy 337.192617 -399.624997) (xy 337.169973 -399.57542)
			(xy 337.154615 -399.523124) (xy 337.146855 -399.469176) (xy 337.146392 -399.441924) (xy 337.146392 -399.441416)
			(xy 337.146722 -399.41703) (xy 337.152836 -399.368644) (xy 337.165081 -399.321435) (xy 337.173824 -399.298668)
			(xy 337.175602 -399.289778) (xy 337.175856 -399.289016) (xy 337.159815 -399.251245) (xy 337.133263 -399.173591)
			(xy 337.113189 -399.094016) (xy 337.09973 -399.013059) (xy 337.092975 -398.93127) (xy 337.092544 -398.890236)
			(xy 337.092544 -398.50822) (xy 337.093019 -398.465231) (xy 337.100465 -398.379575) (xy 337.115253 -398.294877)
			(xy 337.125818 -398.253204) (xy 337.127596 -398.24025) (xy 337.125818 -398.227296) (xy 337.122262 -398.213326)
			(xy 337.118879 -398.202338) (xy 337.104234 -398.184658) (xy 337.094068 -398.17929) (xy 337.06562 -398.16659)
			(xy 337.060612 -398.16446) (xy 337.049979 -398.162153) (xy 337.044538 -398.162018) (xy 337.02117 -398.167606)
			(xy 336.984907 -398.185862) (xy 336.909971 -398.217119) (xy 336.832743 -398.242187) (xy 336.793332 -398.251934)
			(xy 336.76082 -398.276572) (xy 336.738888 -398.314854) (xy 336.689238 -398.387793) (xy 336.633336 -398.456059)
			(xy 336.571622 -398.519118) (xy 336.504576 -398.576478) (xy 336.432725 -398.627689) (xy 336.35663 -398.672352)
			(xy 336.276886 -398.710116) (xy 336.194118 -398.740686) (xy 336.108972 -398.763823) (xy 336.022114 -398.779347)
			(xy 335.934225 -398.787135) (xy 335.890108 -398.78762) (xy 335.849512 -398.78718) (xy 335.768594 -398.78052)
			(xy 335.688486 -398.7673) (xy 335.609719 -398.747607) (xy 335.532814 -398.721573) (xy 335.495392 -398.705832)
			(xy 335.494884 -398.705832) (xy 335.47177 -398.695926) (xy 335.467452 -398.696942) (xy 335.463642 -398.698466)
			(xy 335.445862 -398.709896) (xy 335.06918 -399.086324) (xy 335.036283 -399.118512) (xy 334.965513 -399.177363)
			(xy 334.889621 -399.229442) (xy 334.809252 -399.274304) (xy 334.72509 -399.311569) (xy 334.637852 -399.340918)
			(xy 334.593184 -399.352008) (xy 334.560672 -399.376646) (xy 334.538729 -399.414915) (xy 334.489059 -399.487825)
			(xy 334.433144 -399.556064) (xy 334.37142 -399.619098) (xy 334.304371 -399.676433) (xy 334.232519 -399.727623)
			(xy 334.156427 -399.772266) (xy 334.076689 -399.810015) (xy 333.993929 -399.840573) (xy 333.908794 -399.863702)
			(xy 333.821948 -399.879221) (xy 333.734071 -399.88701) (xy 333.68996 -399.88744) (xy 333.689198 -399.88744)
			(xy 333.647858 -399.887011) (xy 333.565463 -399.880143) (xy 333.483921 -399.866469) (xy 333.403793 -399.846084)
			(xy 333.32563 -399.819129) (xy 333.287624 -399.802858) (xy 333.277972 -399.79854) (xy 333.263494 -399.79854)
			(xy 333.262478 -399.799048) (xy 333.262224 -399.799048) (xy 333.231444 -399.809918) (xy 333.167335 -399.822181)
			(xy 333.134716 -399.823432) (xy 333.125826 -399.823432) (xy 333.098671 -399.822805) (xy 333.044946 -399.81481)
			(xy 332.992899 -399.799276) (xy 332.94358 -399.776518) (xy 332.897988 -399.746996) (xy 332.857043 -399.711306)
			(xy 332.821573 -399.67017) (xy 332.792296 -399.624419) (xy 332.769803 -399.574979) (xy 332.75455 -399.522849)
			(xy 332.746843 -399.469082) (xy 332.74635 -399.441924) (xy 332.74635 -399.440146) (xy 332.746779 -399.416786)
			(xy 332.752637 -399.370431) (xy 332.764112 -399.325138) (xy 332.772258 -399.30324) (xy 332.772766 -399.30197)
			(xy 332.774798 -399.294858) (xy 332.775306 -399.291302) (xy 332.775814 -399.288508) (xy 332.759816 -399.250779)
			(xy 332.733337 -399.173218) (xy 332.71332 -399.093744) (xy 332.699898 -399.012894) (xy 332.693163 -398.931214)
			(xy 332.692756 -398.890236) (xy 332.692756 -398.507458) (xy 332.693225 -398.464601) (xy 332.7006 -398.379205)
			(xy 332.715276 -398.294757) (xy 332.725776 -398.253204) (xy 332.727554 -398.24025) (xy 332.725776 -398.227296)
			(xy 332.719489 -398.203027) (xy 332.709067 -398.153982) (xy 332.704948 -398.129252) (xy 332.701392 -398.106646)
			(xy 332.69936 -398.104106) (xy 332.694534 -398.100296) (xy 332.683104 -398.093946) (xy 332.622144 -398.069054)
			(xy 332.621636 -398.069054) (xy 332.599538 -398.060164) (xy 332.595408 -398.058846) (xy 332.586854 -398.057441)
			(xy 332.58252 -398.05737) (xy 332.562962 -398.072356) (xy 332.531061 -398.096337) (xy 332.464051 -398.139697)
			(xy 332.429104 -398.15897) (xy 332.421748 -398.163319) (xy 332.410208 -398.175909) (xy 332.406498 -398.183608)
			(xy 332.388409 -398.224497) (xy 332.345935 -398.303184) (xy 332.296586 -398.377751) (xy 332.240758 -398.4476)
			(xy 332.178901 -398.512171) (xy 332.111512 -398.570943) (xy 332.03913 -398.623446) (xy 331.962339 -398.669258)
			(xy 331.881754 -398.708009) (xy 331.798024 -398.739391) (xy 331.711819 -398.763149) (xy 331.623834 -398.779094)
			(xy 331.534775 -398.787097) (xy 331.490066 -398.78762) (xy 331.446973 -398.787151) (xy 331.361109 -398.779691)
			(xy 331.276209 -398.764856) (xy 331.192904 -398.742757) (xy 331.111814 -398.713557) (xy 331.07249 -398.695926)
			(xy 331.066394 -398.69745) (xy 331.044334 -398.705646) (xy 330.998703 -398.717164) (xy 330.952003 -398.722984)
			(xy 330.928472 -398.723358) (xy 330.927964 -398.723358) (xy 330.900828 -398.722878) (xy 330.847106 -398.715183)
			(xy 330.795015 -398.699953) (xy 330.745608 -398.677496) (xy 330.699882 -398.648265) (xy 330.658759 -398.61285)
			(xy 330.623069 -398.571965) (xy 330.593532 -398.526435) (xy 330.570745 -398.477179) (xy 330.555167 -398.425192)
			(xy 330.547112 -398.371522) (xy 330.546456 -398.34439) (xy 330.546456 -398.341596) (xy 330.546829 -398.31793)
			(xy 330.552706 -398.270964) (xy 330.564332 -398.225082) (xy 330.572618 -398.202912) (xy 330.574142 -398.199102)
			(xy 330.57465 -398.19707) (xy 330.57592 -398.189196) (xy 330.559877 -398.151399) (xy 330.533321 -398.073693)
			(xy 330.513241 -397.994067) (xy 330.499775 -397.91306) (xy 330.493012 -397.831221) (xy 330.492608 -397.790162)
			(xy 330.492608 -397.408146) (xy 330.493082 -397.365157) (xy 330.500526 -397.2795) (xy 330.51531 -397.194802)
			(xy 330.525882 -397.15313) (xy 330.52766 -397.140176) (xy 330.525882 -397.127222) (xy 330.515304 -397.085551)
			(xy 330.500514 -397.000853) (xy 330.493074 -396.915196) (xy 330.492608 -396.872206) (xy 330.492608 -396.49019)
			(xy 330.493034 -396.4491) (xy 330.499812 -396.367199) (xy 330.513314 -396.286134) (xy 330.533448 -396.206458)
			(xy 330.560076 -396.12871) (xy 330.576174 -396.090902) (xy 330.57592 -396.089632) (xy 330.574142 -396.081504)
			(xy 330.572618 -396.07744) (xy 330.572364 -396.076932) (xy 330.56422 -396.054988) (xy 330.552733 -396.009613)
			(xy 330.54688 -395.963174) (xy 330.546456 -395.939772) (xy 330.546456 -395.935962) (xy 330.547108 -395.908909)
			(xy 330.55511 -395.85539) (xy 330.570593 -395.803539) (xy 330.593246 -395.754395) (xy 330.622616 -395.708945)
			(xy 330.658113 -395.668101) (xy 330.699025 -395.632682) (xy 330.74453 -395.603398) (xy 330.793717 -395.580837)
			(xy 330.845598 -395.565453) (xy 330.899132 -395.557552) (xy 330.926186 -395.556994) (xy 330.929234 -395.556994)
			(xy 330.94168 -395.557248) (xy 330.943458 -395.557248) (xy 330.950062 -395.55674) (xy 330.96327 -395.553184)
			(xy 330.972226 -395.548868) (xy 330.98619 -395.534745) (xy 330.993748 -395.516378) (xy 330.994258 -395.506448)
			(xy 330.989178 -395.487398) (xy 330.985114 -395.477238) (xy 330.984098 -395.47546) (xy 330.981304 -395.47038)
			(xy 330.980796 -395.469364) (xy 330.97978 -395.467586) (xy 330.976732 -395.461744) (xy 330.976224 -395.460728)
			(xy 330.9747 -395.457934) (xy 330.974446 -395.457426) (xy 330.95887 -395.426225) (xy 330.934462 -395.360898)
			(xy 330.918073 -395.293114) (xy 330.913486 -395.258544) (xy 330.91169 -395.242473) (xy 330.909658 -395.210197)
			(xy 330.909422 -395.194028) (xy 330.909422 -395.186408) (xy 330.910171 -395.151468) (xy 330.919014 -395.082142)
			(xy 330.936115 -395.014378) (xy 330.961228 -394.949158) (xy 330.993988 -394.887424) (xy 331.033922 -394.830069)
			(xy 331.080453 -394.777922) (xy 331.132907 -394.731739) (xy 331.190526 -394.692187) (xy 331.252477 -394.659838)
			(xy 331.317863 -394.635159) (xy 331.385738 -394.618509) (xy 331.455122 -394.610127) (xy 331.490066 -394.609574)
			(xy 331.505814 -394.609574) (xy 331.536735 -394.610797) (xy 331.598072 -394.619023) (xy 331.658183 -394.633735)
			(xy 331.687424 -394.643864) (xy 331.688694 -394.644372) (xy 331.691742 -394.645388) (xy 331.705966 -394.648182)
			(xy 331.707998 -394.648436) (xy 331.708506 -394.648436) (xy 331.718385 -394.647979) (xy 331.73669 -394.640543)
			(xy 331.744066 -394.633958) (xy 333.170784 -393.206986) (xy 333.210916 -393.166854) (xy 333.213456 -393.163298)
			(xy 333.214218 -393.162282) (xy 333.22651 -393.144523) (xy 333.252428 -393.109967) (xy 333.266034 -393.093194)
			(xy 333.540354 -392.759184) (xy 333.568287 -392.725867) (xy 333.629119 -392.663739) (xy 333.695178 -392.607201)
			(xy 333.765952 -392.556689) (xy 333.840892 -392.512595) (xy 333.879952 -392.4935) (xy 333.887826 -392.489944)
			(xy 333.946246 -392.431524) (xy 333.948278 -392.428984) (xy 333.968223 -392.403537) (xy 334.010929 -392.354985)
			(xy 334.033622 -392.331956) (xy 335.118964 -391.246614) (xy 335.149222 -391.216948) (xy 335.213992 -391.162299)
			(xy 335.283167 -391.113347) (xy 335.35625 -391.070444) (xy 335.3943 -391.051796) (xy 335.488788 -391.006584)
			(xy 335.498186 -390.999218) (xy 335.501742 -390.994392) (xy 335.52835 -390.960923) (xy 335.586488 -390.89822)
			(xy 335.649834 -390.840782) (xy 335.683606 -390.81456) (xy 335.68894 -390.810496) (xy 335.695544 -390.805416)
			(xy 335.699608 -390.802368) (xy 335.709006 -390.796018) (xy 335.709514 -390.79551) (xy 335.745871 -390.770261)
			(xy 335.822314 -390.725619) (xy 335.862168 -390.706356) (xy 336.262472 -390.518396) (xy 336.302487 -390.500149)
			(xy 336.385116 -390.470016) (xy 336.470098 -390.447353) (xy 336.55676 -390.432343) (xy 336.600546 -390.428226)
			(xy 336.6008 -390.428226) (xy 336.612484 -390.423146) (xy 336.630518 -390.415272) (xy 336.631788 -390.414002)
			(xy 336.635344 -390.410954) (xy 336.638138 -390.40816) (xy 336.6389 -390.407398) (xy 336.640424 -390.406128)
			(xy 336.640932 -390.40562) (xy 336.676033 -390.375597) (xy 336.750904 -390.321494) (xy 336.830496 -390.274613)
			(xy 336.872072 -390.25449) (xy 337.272122 -390.066022) (xy 337.316064 -390.045988) (xy 337.407043 -390.013577)
			(xy 337.500747 -389.990185) (xy 337.596284 -389.976035) (xy 337.644486 -389.973058) (xy 337.664044 -389.967978)
			(xy 346.298012 -385.845812) (xy 346.312998 -385.825238) (xy 346.314268 -385.81584) (xy 346.319247 -385.781283)
			(xy 346.336414 -385.713606) (xy 346.361573 -385.648476) (xy 346.39436 -385.586833) (xy 346.434302 -385.529565)
			(xy 346.480822 -385.477501) (xy 346.53325 -385.43139) (xy 346.590828 -385.391898) (xy 346.652727 -385.359596)
			(xy 346.718052 -385.334948) (xy 346.785861 -385.318312) (xy 346.855176 -385.309926) (xy 346.890086 -385.309364)
			(xy 346.898976 -385.309364) (xy 346.924026 -385.310009) (xy 346.973881 -385.315093) (xy 346.998544 -385.319524)
			(xy 346.999052 -385.318) (xy 347.032072 -385.32689) (xy 347.033088 -385.327144) (xy 347.061876 -385.334817)
			(xy 347.117838 -385.355269) (xy 347.171411 -385.381344) (xy 347.196918 -385.39674) (xy 347.197426 -385.397248)
			(xy 347.20276 -385.400296) (xy 347.22816 -385.401566) (xy 348.493842 -384.797554) (xy 348.509336 -384.774186)
			(xy 348.50959 -384.769614) (xy 348.511309 -384.734995) (xy 348.521967 -384.666502) (xy 348.540699 -384.599764)
			(xy 348.56724 -384.53573) (xy 348.601211 -384.475308) (xy 348.642131 -384.419358) (xy 348.689418 -384.368675)
			(xy 348.715584 -384.345942) (xy 348.74613 -384.321072) (xy 348.81268 -384.278937) (xy 348.884316 -384.246184)
			(xy 348.921832 -384.234182) (xy 348.937072 -384.22961) (xy 348.94305 -384.226726) (xy 348.95335 -384.218364)
			(xy 348.957392 -384.2131) (xy 348.96171 -383.97053) (xy 348.960694 -383.969006) (xy 348.956122 -383.962656)
			(xy 348.950534 -383.958592) (xy 348.947583 -383.95649) (xy 348.94121 -383.953046) (xy 348.937834 -383.951734)
			(xy 348.927674 -383.948178) (xy 348.899657 -383.937753) (xy 348.846194 -383.911005) (xy 348.796417 -383.8779)
			(xy 348.751079 -383.838937) (xy 348.710863 -383.794705) (xy 348.676379 -383.745873) (xy 348.648146 -383.693179)
			(xy 348.626593 -383.63742) (xy 348.612044 -383.579436) (xy 348.604719 -383.520106) (xy 348.604332 -383.490216)
			(xy 348.604838 -383.45862) (xy 348.61303 -383.39596) (xy 348.629279 -383.334892) (xy 348.653309 -383.276446)
			(xy 348.684715 -383.221611) (xy 348.722967 -383.17131) (xy 348.767419 -383.126395) (xy 348.81732 -383.087623)
			(xy 348.871827 -383.05565) (xy 348.90075 -383.042922) (xy 348.911559 -383.038395) (xy 348.933539 -383.030263)
			(xy 348.944692 -383.026666) (xy 348.958154 -383.022348) (xy 348.964207 -383.019588) (xy 348.974744 -383.011475)
			(xy 348.978982 -383.006346) (xy 348.97949 -383.005838) (xy 348.985586 -382.67767) (xy 348.984062 -382.675384)
			(xy 348.978982 -382.66878) (xy 348.972124 -382.664208) (xy 348.968988 -382.662125) (xy 348.962227 -382.658813)
			(xy 348.958662 -382.657604) (xy 348.949264 -382.65481) (xy 348.919722 -382.645353) (xy 348.863126 -382.619964)
			(xy 348.810224 -382.587575) (xy 348.761876 -382.548714) (xy 348.71887 -382.504012) (xy 348.681907 -382.454199)
			(xy 348.651587 -382.400084) (xy 348.628405 -382.342549) (xy 348.612738 -382.28253) (xy 348.604841 -382.221005)
			(xy 348.604332 -382.18999) (xy 348.604843 -382.1579) (xy 348.613284 -382.094277) (xy 348.630032 -382.03232)
			(xy 348.654795 -381.973109) (xy 348.687141 -381.917676) (xy 348.726506 -381.866985) (xy 348.772205 -381.821922)
			(xy 348.823441 -381.78327) (xy 348.879322 -381.751703) (xy 348.938874 -381.727772) (xy 348.969838 -381.719328)
			(xy 348.978982 -381.717042) (xy 348.985684 -381.714477) (xy 348.997416 -381.706226) (xy 349.002096 -381.700786)
			(xy 349.00362 -381.699008) (xy 349.007684 -381.481076) (xy 349.002413 -381.473728) (xy 348.987834 -381.46305)
			(xy 348.979236 -381.460248) (xy 348.97314 -381.458978) (xy 348.940471 -381.451803) (xy 348.876919 -381.430937)
			(xy 348.816186 -381.402906) (xy 348.759076 -381.368083) (xy 348.706346 -381.326929) (xy 348.658693 -381.279989)
			(xy 348.61675 -381.227884) (xy 348.581071 -381.171305) (xy 348.552129 -381.111001) (xy 348.530308 -381.047771)
			(xy 348.515896 -380.982453) (xy 348.509085 -380.915911) (xy 348.509965 -380.849028) (xy 348.518523 -380.782688)
			(xy 348.534648 -380.717771) (xy 348.558124 -380.655137) (xy 348.588642 -380.595615) (xy 348.625797 -380.539994)
			(xy 348.669096 -380.489011) (xy 348.717967 -380.44334) (xy 348.771762 -380.403586) (xy 348.829768 -380.370278)
			(xy 348.891217 -380.343854) (xy 348.955295 -380.324666) (xy 348.988126 -380.318264) (xy 349.002604 -380.315724)
			(xy 349.010527 -380.312916) (xy 349.024142 -380.303076) (xy 349.029274 -380.29642) (xy 349.033338 -380.08941)
			(xy 349.030036 -380.084838) (xy 349.024448 -380.078234) (xy 349.010224 -380.069598) (xy 348.998286 -380.067058)
			(xy 348.967395 -380.060606) (xy 348.907486 -380.040767) (xy 348.850651 -380.013337) (xy 348.797847 -379.978779)
			(xy 348.749962 -379.937673) (xy 348.707804 -379.890713) (xy 348.672081 -379.838689) (xy 348.643396 -379.782477)
			(xy 348.622232 -379.723024) (xy 348.608945 -379.66133) (xy 348.605856 -379.629924) (xy 348.605348 -379.624082)
			(xy 348.604078 -379.590046) (xy 348.60458 -379.558482) (xy 348.612754 -379.495886) (xy 348.628971 -379.434876)
			(xy 348.652956 -379.376482) (xy 348.684306 -379.321689) (xy 348.722492 -379.27142) (xy 348.76687 -379.226523)
			(xy 348.816691 -379.187755) (xy 348.871116 -379.15577) (xy 348.899988 -379.143006) (xy 348.928312 -379.131455)
			(xy 348.987165 -379.114771) (xy 349.017336 -379.109732) (xy 349.021654 -379.10897) (xy 349.029319 -379.106928)
			(xy 349.04291 -379.098765) (xy 349.048324 -379.092968) (xy 349.051626 -379.089412) (xy 349.057214 -378.793502)
			(xy 349.05146 -378.785479) (xy 349.035246 -378.774249) (xy 349.025718 -378.771658) (xy 349.019114 -378.770642)
			(xy 348.98684 -378.765351) (xy 348.924001 -378.747226) (xy 348.864164 -378.720828) (xy 348.808414 -378.686634)
			(xy 348.75776 -378.645265) (xy 348.713119 -378.597469) (xy 348.6753 -378.544112) (xy 348.644988 -378.48616)
			(xy 348.622731 -378.424662) (xy 348.608933 -378.360734) (xy 348.605856 -378.328174) (xy 348.605602 -378.325888)
			(xy 348.605348 -378.324364) (xy 348.604332 -378.290328) (xy 348.604332 -378.28982) (xy 348.604862 -378.257801)
			(xy 348.613311 -378.194323) (xy 348.630026 -378.132504) (xy 348.654718 -378.073418) (xy 348.686957 -378.018087)
			(xy 348.726186 -377.96747) (xy 348.771724 -377.922446) (xy 348.822782 -377.883795) (xy 348.878476 -377.852186)
			(xy 348.937839 -377.828167) (xy 348.999843 -377.812155) (xy 349.03156 -377.807728) (xy 349.042482 -377.806458)
			(xy 349.044006 -377.806204) (xy 349.05189 -377.804374) (xy 349.066004 -377.796468) (xy 349.071692 -377.79071)
			(xy 349.075502 -377.786646) (xy 349.100394 -376.434858) (xy 349.100145 -376.424712) (xy 349.092666 -376.405863)
			(xy 349.085916 -376.398282) (xy 349.073724 -376.385836) (xy 349.070067 -376.384783) (xy 349.062543 -376.383636)
			(xy 349.058738 -376.38355) (xy 348.914974 -376.38355) (xy 348.907936 -376.383775) (xy 348.894402 -376.387648)
			(xy 348.888304 -376.39117) (xy 348.882208 -376.39498) (xy 348.87281 -376.40514) (xy 348.869508 -376.411744)
			(xy 348.856361 -376.437021) (xy 348.823714 -376.483712) (xy 348.784497 -376.525039) (xy 348.739578 -376.560085)
			(xy 348.689954 -376.588074) (xy 348.663514 -376.598688) (xy 348.653354 -376.602498) (xy 348.269306 -376.986292)
			(xy 348.236408 -377.018478) (xy 348.165638 -377.077326) (xy 348.089744 -377.129401) (xy 348.009374 -377.17426)
			(xy 347.925211 -377.211519) (xy 347.837972 -377.240863) (xy 347.79331 -377.251976) (xy 347.760798 -377.276614)
			(xy 347.738852 -377.314879) (xy 347.689179 -377.387781) (xy 347.63326 -377.456011) (xy 347.571534 -377.519036)
			(xy 347.504482 -377.576362) (xy 347.43263 -377.627543) (xy 347.356538 -377.672178) (xy 347.276801 -377.709917)
			(xy 347.194043 -377.740467) (xy 347.10891 -377.763589) (xy 347.022068 -377.7791) (xy 346.934195 -377.786882)
			(xy 346.890086 -377.787408) (xy 346.889832 -377.787408) (xy 346.846763 -377.786944) (xy 346.760948 -377.779491)
			(xy 346.676097 -377.764656) (xy 346.592845 -377.742549) (xy 346.511812 -377.713336) (xy 346.47251 -377.695714)
			(xy 346.467176 -377.696984) (xy 346.444931 -377.705339) (xy 346.398889 -377.717093) (xy 346.351743 -377.723034)
			(xy 346.327984 -377.7234) (xy 346.299245 -377.722878) (xy 346.242419 -377.714253) (xy 346.187529 -377.697201)
			(xy 346.135819 -377.672108) (xy 346.088458 -377.639541) (xy 346.067126 -377.620276) (xy 346.062747 -377.616376)
			(xy 346.052611 -377.610483) (xy 346.04706 -377.608592) (xy 346.041726 -377.607068) (xy 346.018612 -377.600718)
			(xy 346.004896 -377.599448) (xy 346.002356 -377.599702) (xy 345.991709 -377.600216) (xy 345.971488 -377.593558)
			(xy 345.955708 -377.579267) (xy 345.947085 -377.559801) (xy 345.946476 -377.549156) (xy 345.946476 -377.341638)
			(xy 345.94682 -377.318427) (xy 345.952459 -377.272349) (xy 345.96366 -377.227299) (xy 345.971622 -377.205494)
			(xy 345.97213 -377.204224) (xy 345.972638 -377.202954) (xy 345.9734 -377.200668) (xy 345.974924 -377.19254)
			(xy 345.975686 -377.188222) (xy 345.959894 -377.150936) (xy 345.9337 -377.074308) (xy 345.913814 -376.995807)
			(xy 345.90037 -376.91595) (xy 345.893455 -376.835264) (xy 345.892882 -376.794776) (xy 345.892628 -376.766074)
			(xy 345.88501 -376.756416) (xy 345.863249 -376.745028) (xy 345.850972 -376.74423) (xy 344.132662 -376.74423)
			(xy 344.122595 -376.744661) (xy 344.104004 -376.752388) (xy 344.096594 -376.759216) (xy 343.869264 -376.986292)
			(xy 343.836367 -377.01848) (xy 343.765598 -377.077332) (xy 343.689706 -377.129411) (xy 343.609337 -377.174274)
			(xy 343.525175 -377.211539) (xy 343.437936 -377.240888) (xy 343.393268 -377.251976) (xy 343.360756 -377.276614)
			(xy 343.338811 -377.31488) (xy 343.289138 -377.387786) (xy 343.233221 -377.456019) (xy 343.171495 -377.519047)
			(xy 343.104445 -377.576378) (xy 343.032593 -377.627563) (xy 342.956501 -377.672202) (xy 342.876764 -377.709946)
			(xy 342.794006 -377.7405) (xy 342.708872 -377.763627) (xy 342.622028 -377.779143) (xy 342.534154 -377.78693)
			(xy 342.490044 -377.787408) (xy 342.489282 -377.787408) (xy 342.447941 -377.786983) (xy 342.365545 -377.78012)
			(xy 342.284 -377.766453) (xy 342.20387 -377.746073) (xy 342.125703 -377.719123) (xy 342.087708 -377.702826)
			(xy 342.078056 -377.698508) (xy 342.063578 -377.698508) (xy 342.062562 -377.699016) (xy 342.062308 -377.699016)
			(xy 342.029034 -377.709938) (xy 342.02878 -377.709938) (xy 342.005721 -377.715859) (xy 341.958594 -377.722608)
			(xy 341.9348 -377.7234) (xy 341.92591 -377.7234) (xy 341.89889 -377.72279) (xy 341.845426 -377.714883)
			(xy 341.793613 -377.699511) (xy 341.744488 -377.67698) (xy 341.699035 -377.647742) (xy 341.658162 -377.612381)
			(xy 341.62269 -377.571606) (xy 341.593326 -377.526234) (xy 341.57066 -377.477171) (xy 341.555145 -377.4254)
			(xy 341.547092 -377.371958) (xy 341.546434 -377.34494) (xy 341.546434 -377.333764) (xy 341.547837 -377.300378)
			(xy 341.560866 -377.234845) (xy 341.572342 -377.203462) (xy 341.572342 -377.202954) (xy 341.573543 -377.19559)
			(xy 341.572129 -377.180744) (xy 341.569548 -377.173744) (xy 341.55189 -377.129944) (xy 341.523953 -377.039727)
			(xy 341.504661 -376.947274) (xy 341.494188 -376.853412) (xy 341.49284 -376.806206) (xy 341.492332 -376.778012)
			(xy 341.485147 -376.76873) (xy 341.46464 -376.75736) (xy 341.452962 -376.756168) (xy 339.720682 -376.756168)
			(xy 339.710613 -376.756594) (xy 339.69201 -376.764309) (xy 339.684614 -376.771154) (xy 339.469222 -376.986292)
			(xy 339.436325 -377.018479) (xy 339.365554 -377.077328) (xy 339.289661 -377.129404) (xy 339.209291 -377.174264)
			(xy 339.125128 -377.211525) (xy 339.03789 -377.24087) (xy 338.993226 -377.251976) (xy 338.960714 -377.276614)
			(xy 338.938769 -377.314879) (xy 338.889095 -377.387782) (xy 338.833177 -377.456013) (xy 338.771451 -377.519039)
			(xy 338.7044 -377.576367) (xy 338.632547 -377.627548) (xy 338.556456 -377.672184) (xy 338.476719 -377.709925)
			(xy 338.39396 -377.740476) (xy 338.308827 -377.763599) (xy 338.221984 -377.779112) (xy 338.134111 -377.786895)
			(xy 338.090002 -377.787408) (xy 338.089748 -377.787408) (xy 338.046679 -377.786945) (xy 337.960864 -377.779493)
			(xy 337.876012 -377.76466) (xy 337.792759 -377.742554) (xy 337.711725 -377.713342) (xy 337.672426 -377.695714)
			(xy 337.667092 -377.696984) (xy 337.644846 -377.705334) (xy 337.598804 -377.717078) (xy 337.551658 -377.723009)
			(xy 337.5279 -377.7234) (xy 337.499161 -377.722879) (xy 337.442333 -377.714256) (xy 337.387442 -377.697206)
			(xy 337.33573 -377.672114) (xy 337.288367 -377.639549) (xy 337.267042 -377.620276) (xy 337.262664 -377.616374)
			(xy 337.252529 -377.610479) (xy 337.246976 -377.608592) (xy 337.241642 -377.607068) (xy 337.218528 -377.600718)
			(xy 337.204812 -377.599448) (xy 337.202272 -377.599702) (xy 337.191623 -377.600219) (xy 337.171396 -377.593564)
			(xy 337.15561 -377.579272) (xy 337.146984 -377.559804) (xy 337.146392 -377.549156) (xy 337.146392 -377.341638)
			(xy 337.146736 -377.318427) (xy 337.152376 -377.27235) (xy 337.163576 -377.2273) (xy 337.171538 -377.205494)
			(xy 337.172046 -377.204224) (xy 337.172554 -377.202954) (xy 337.173316 -377.200668) (xy 337.17484 -377.19254)
			(xy 337.175602 -377.188222) (xy 337.159619 -377.150515) (xy 337.133163 -377.073001) (xy 337.113155 -376.993578)
			(xy 337.09973 -376.912782) (xy 337.092978 -376.831156) (xy 337.092544 -376.790204) (xy 337.092544 -376.757946)
			(xy 337.085054 -376.748133) (xy 337.063219 -376.736677) (xy 337.050888 -376.736102) (xy 335.340706 -376.736102)
			(xy 335.330635 -376.736524) (xy 335.31203 -376.744237) (xy 335.304638 -376.751088) (xy 335.06918 -376.986292)
			(xy 335.036284 -377.01848) (xy 334.965515 -377.077334) (xy 334.889623 -377.129414) (xy 334.809254 -377.174278)
			(xy 334.725092 -377.211544) (xy 334.637854 -377.240894) (xy 334.593184 -377.251976) (xy 334.560672 -377.276614)
			(xy 334.538727 -377.314881) (xy 334.489055 -377.387787) (xy 334.433137 -377.456021) (xy 334.371412 -377.519051)
			(xy 334.304362 -377.576382) (xy 334.23251 -377.627568) (xy 334.156418 -377.672208) (xy 334.076682 -377.709954)
			(xy 333.993923 -377.74051) (xy 333.908789 -377.763637) (xy 333.821945 -377.779155) (xy 333.73407 -377.786943)
			(xy 333.68996 -377.787408) (xy 333.689198 -377.787408) (xy 333.647858 -377.786979) (xy 333.565463 -377.78011)
			(xy 333.483922 -377.766436) (xy 333.403794 -377.746051) (xy 333.325631 -377.719095) (xy 333.287624 -377.702826)
			(xy 333.277972 -377.698508) (xy 333.263494 -377.698508) (xy 333.262478 -377.699016) (xy 333.262224 -377.699016)
			(xy 333.22895 -377.709938) (xy 333.228696 -377.709938) (xy 333.205637 -377.715859) (xy 333.15851 -377.722611)
			(xy 333.134716 -377.7234) (xy 333.125826 -377.7234) (xy 333.09881 -377.722784) (xy 333.045355 -377.714868)
			(xy 332.993552 -377.699488) (xy 332.944438 -377.676953) (xy 332.898994 -377.647712) (xy 332.858132 -377.612352)
			(xy 332.822668 -377.571579) (xy 332.793313 -377.52621) (xy 332.770653 -377.477153) (xy 332.755142 -377.425389)
			(xy 332.747091 -377.371954) (xy 332.74635 -377.34494) (xy 332.74635 -377.333764) (xy 332.747753 -377.300378)
			(xy 332.760782 -377.234845) (xy 332.772258 -377.203462) (xy 332.772258 -377.202954) (xy 332.773274 -377.193302)
			(xy 332.76921 -377.173744) (xy 332.750147 -377.126297) (xy 332.720689 -377.028374) (xy 332.701405 -376.927951)
			(xy 332.696312 -376.877072) (xy 332.693772 -376.84837) (xy 332.688946 -376.844052) (xy 332.681739 -376.837909)
			(xy 332.664118 -376.831008) (xy 332.654656 -376.83059) (xy 330.668376 -376.83059) (xy 330.658308 -376.830162)
			(xy 330.639711 -376.822441) (xy 330.632308 -376.815604) (xy 330.369164 -376.55246) (xy 330.362317 -376.545062)
			(xy 330.354587 -376.526464) (xy 330.354178 -376.516392) (xy 330.354178 -369.21059) (xy 330.354015 -369.204579)
			(xy 330.351199 -369.192893) (xy 330.34859 -369.187476) (xy 330.34675 -369.184002) (xy 330.342155 -369.177625)
			(xy 330.339446 -369.174776) (xy 329.699366 -368.534696) (xy 329.695491 -368.531035) (xy 329.686522 -368.52528)
			(xy 329.681586 -368.523266) (xy 328.397616 -368.031776) (xy 328.386948 -368.032284) (xy 328.337672 -368.0333)
			(xy 328.29208 -368.032815) (xy 328.201274 -368.024535) (xy 328.111604 -368.007992) (xy 328.023821 -367.983325)
			(xy 327.981056 -367.967514) (xy 327.518014 -367.790222) (xy 327.480144 -367.775275) (xy 327.406733 -367.740057)
			(xy 327.336436 -367.698974) (xy 327.269721 -367.652299) (xy 327.238106 -367.626646) (xy 327.207626 -367.614962)
			(xy 327.166873 -367.612977) (xy 327.085867 -367.603169) (xy 327.005933 -367.586776) (xy 326.927606 -367.563907)
			(xy 326.889364 -367.549684) (xy 326.426576 -367.372392) (xy 326.38874 -367.357434) (xy 326.315397 -367.322203)
			(xy 326.245164 -367.281121) (xy 326.178507 -367.234461) (xy 326.146922 -367.208816) (xy 326.116442 -367.197132)
			(xy 326.075658 -367.19515) (xy 325.99459 -367.185344) (xy 325.914594 -367.168946) (xy 325.836206 -367.146064)
			(xy 325.797926 -367.131854) (xy 325.335138 -366.954562) (xy 325.297303 -366.939602) (xy 325.223963 -366.904369)
			(xy 325.153732 -366.863284) (xy 325.087078 -366.81662) (xy 325.055484 -366.790986) (xy 325.025004 -366.779302)
			(xy 324.98422 -366.777322) (xy 324.90315 -366.767521) (xy 324.823152 -366.751127) (xy 324.744762 -366.728249)
			(xy 324.706488 -366.714024) (xy 324.2437 -366.536732) (xy 324.205864 -366.521775) (xy 324.132519 -366.486547)
			(xy 324.062284 -366.445468) (xy 323.995624 -366.39881) (xy 323.964046 -366.373156) (xy 323.933566 -366.361472)
			(xy 323.892782 -366.359491) (xy 323.811713 -366.349688) (xy 323.731716 -366.333291) (xy 323.653327 -366.310412)
			(xy 323.61505 -366.296194) (xy 323.152262 -366.118902) (xy 323.113891 -366.103744) (xy 323.039554 -366.06794)
			(xy 322.968428 -366.026119) (xy 322.901 -365.978567) (xy 322.837729 -365.925608) (xy 322.808092 -365.896906)
			(xy 322.804282 -365.893096) (xy 322.795392 -365.887254) (xy 314.560458 -362.735114) (xy 314.520689 -362.719383)
			(xy 314.443741 -362.682044) (xy 314.370274 -362.638251) (xy 314.300827 -362.588328) (xy 314.235912 -362.53264)
			(xy 314.20562 -362.50245) (xy 313.37758 -361.659424) (xy 313.372754 -361.655106) (xy 313.234324 -361.545378)
			(xy 313.199826 -361.517424) (xy 313.135465 -361.456243) (xy 313.1058 -361.423204) (xy 312.771282 -361.042204)
			(xy 312.76925 -361.040172) (xy 312.584592 -360.851958) (xy 312.554759 -360.820991) (xy 312.499946 -360.754731)
			(xy 312.475118 -360.719624) (xy 312.430668 -360.655108) (xy 312.426858 -360.650282) (xy 311.921398 -360.074718)
			(xy 311.892538 -360.041133) (xy 311.840263 -359.969651) (xy 311.817004 -359.93197) (xy 311.035446 -358.632506)
			(xy 311.033668 -358.629966) (xy 300.087284 -342.762586) (xy 300.083728 -342.760046) (xy 300.067218 -342.755474)
			(xy 300.037754 -342.771984) (xy 300.016231 -342.783709) (xy 299.970819 -342.802149) (xy 299.923417 -342.814613)
			(xy 299.874809 -342.820898) (xy 299.850302 -342.82126) (xy 298.732448 -342.82126) (xy 298.706546 -342.820829)
			(xy 298.655218 -342.813821) (xy 298.605312 -342.799927) (xy 298.557747 -342.779404) (xy 298.535344 -342.766396)
			(xy 298.508928 -342.75903) (xy 298.496736 -342.760554) (xy 298.477296 -342.765042) (xy 298.437691 -342.769879)
			(xy 298.417742 -342.770206) (xy 298.391751 -342.769726) (xy 298.340407 -342.7616) (xy 298.290968 -342.745542)
			(xy 298.244649 -342.721946) (xy 298.202592 -342.691395) (xy 298.165832 -342.65464) (xy 298.135276 -342.612587)
			(xy 298.111674 -342.566271) (xy 298.09561 -342.516834) (xy 298.087477 -342.465491) (xy 298.087477 -342.413509)
			(xy 298.09561 -342.362166) (xy 298.111674 -342.312729) (xy 298.135276 -342.266413) (xy 298.165832 -342.22436)
			(xy 298.202592 -342.187605) (xy 298.244649 -342.157054) (xy 298.290968 -342.133458) (xy 298.340407 -342.1174)
			(xy 298.391751 -342.109274) (xy 298.417742 -342.10879) (xy 298.437693 -342.109089) (xy 298.477301 -342.113924)
			(xy 298.496736 -342.118442) (xy 298.508928 -342.119966) (xy 298.535344 -342.1126) (xy 298.557749 -342.099597)
			(xy 298.60532 -342.07909) (xy 298.655224 -342.065195) (xy 298.706547 -342.058165) (xy 298.732448 -342.057736)
			(xy 299.310044 -342.057736) (xy 299.319141 -342.057319) (xy 299.336162 -342.050882) (xy 299.349862 -342.038905)
			(xy 299.354494 -342.031066) (xy 299.356526 -342.025986) (xy 299.359251 -342.018954) (xy 299.360809 -342.003961)
			(xy 299.359574 -341.996522) (xy 299.358304 -341.989918) (xy 299.351192 -341.97671) (xy 299.210984 -341.836502)
			(xy 299.206666 -341.832692) (xy 285.570676 -331.056996) (xy 285.548891 -331.039552) (xy 285.507081 -331.002576)
			(xy 285.48711 -330.983082) (xy 283.369004 -328.885042) (xy 283.333861 -328.849368) (xy 283.270116 -328.772131)
			(xy 283.24175 -328.730864) (xy 282.552648 -327.700386) (xy 282.525843 -327.659284) (xy 282.479531 -327.572765)
			(xy 282.460192 -327.527666) (xy 281.762454 -325.843138) (xy 281.744245 -325.797664) (xy 281.715805 -325.703923)
			(xy 281.696693 -325.607845) (xy 281.687091 -325.510356) (xy 281.686508 -325.461376) (xy 281.686508 -319.915286)
			(xy 281.687033 -319.869176) (xy 281.69557 -319.777352) (xy 281.712561 -319.686711) (xy 281.737859 -319.598029)
			(xy 281.754072 -319.55486) (xy 281.757628 -319.536572) (xy 281.757628 -317.14313) (xy 281.75715 -317.133791)
			(xy 281.750366 -317.11638) (xy 281.737824 -317.10253) (xy 281.729688 -317.097918) (xy 281.648408 -317.057024)
			(xy 281.639819 -317.053236) (xy 281.621145 -317.051496) (xy 281.603092 -317.056582) (xy 281.595322 -317.06185)
			(xy 281.574045 -317.077062) (xy 281.527665 -317.101235) (xy 281.478028 -317.117714) (xy 281.4264 -317.126081)
			(xy 281.40025 -317.12662) (xy 281.399742 -317.12662) (xy 281.374048 -317.126146) (xy 281.323293 -317.118113)
			(xy 281.274419 -317.102238) (xy 281.22863 -317.078913) (xy 281.187055 -317.048711) (xy 281.150716 -317.012377)
			(xy 281.120509 -316.970806) (xy 281.097178 -316.92502) (xy 281.081297 -316.876148) (xy 281.073258 -316.825394)
			(xy 281.073258 -316.774006) (xy 281.081297 -316.723252) (xy 281.097178 -316.67438) (xy 281.120509 -316.628594)
			(xy 281.150716 -316.587023) (xy 281.187055 -316.550689) (xy 281.22863 -316.520487) (xy 281.274419 -316.497162)
			(xy 281.323293 -316.481287) (xy 281.374048 -316.473254) (xy 281.399742 -316.472824) (xy 281.40025 -316.472824)
			(xy 281.4264 -316.473359) (xy 281.478028 -316.481726) (xy 281.527665 -316.498208) (xy 281.574044 -316.522383)
			(xy 281.595322 -316.537594) (xy 281.603083 -316.542886) (xy 281.621143 -316.547989) (xy 281.639829 -316.546242)
			(xy 281.648408 -316.54242) (xy 281.729688 -316.501526) (xy 281.737855 -316.496953) (xy 281.750428 -316.483108)
			(xy 281.757169 -316.465664) (xy 281.757628 -316.456314) (xy 281.757628 -316.455044) (xy 281.758149 -316.4097)
			(xy 281.766593 -316.319405) (xy 281.783411 -316.23029) (xy 281.808457 -316.143128) (xy 281.841513 -316.058679)
			(xy 281.882292 -315.977676) (xy 281.930439 -315.900824) (xy 281.985536 -315.828791) (xy 282.015946 -315.795152)
			(xy 282.028138 -315.772546) (xy 282.034923 -315.746531) (xy 282.055762 -315.696976) (xy 282.084345 -315.651444)
			(xy 282.119918 -315.611138) (xy 282.140406 -315.59373) (xy 282.159202 -315.55436) (xy 282.159202 -315.195204)
			(xy 282.140406 -315.155834) (xy 282.121785 -315.14004) (xy 282.088945 -315.10391) (xy 282.061773 -315.063344)
			(xy 282.04086 -315.019224) (xy 282.02666 -314.972509) (xy 282.019482 -314.924215) (xy 282.018994 -314.899802)
			(xy 282.019637 -314.870517) (xy 282.029997 -314.81287) (xy 282.050374 -314.757958) (xy 282.064714 -314.732416)
			(xy 282.03906 -314.706762) (xy 282.02152 -314.688373) (xy 281.991784 -314.647165) (xy 281.968802 -314.601842)
			(xy 281.953132 -314.553502) (xy 281.945153 -314.503315) (xy 281.944572 -314.477908) (xy 281.944572 -314.35548)
			(xy 281.945159 -314.328758) (xy 281.953974 -314.276043) (xy 281.962098 -314.250578) (xy 281.964892 -314.234068)
			(xy 281.964892 -313.665616) (xy 281.962098 -313.649106) (xy 281.953951 -313.623647) (xy 281.945146 -313.570928)
			(xy 281.944572 -313.544204) (xy 281.944572 -313.40552) (xy 281.945155 -313.378797) (xy 281.953964 -313.32608)
			(xy 281.962098 -313.300618) (xy 281.964892 -313.284108) (xy 281.964892 -312.876692) (xy 281.963876 -312.875676)
			(xy 281.963876 -312.712608) (xy 281.963843 -312.708472) (xy 281.962566 -312.700301) (xy 281.961336 -312.696352)
			(xy 281.953572 -312.671539) (xy 281.945146 -312.620237) (xy 281.944572 -312.594244) (xy 281.944572 -312.45556)
			(xy 281.945161 -312.429568) (xy 281.953578 -312.378266) (xy 281.961336 -312.353452) (xy 281.962533 -312.349496)
			(xy 281.963804 -312.341329) (xy 281.963876 -312.337196) (xy 281.963876 -311.762648) (xy 281.963847 -311.758512)
			(xy 281.962576 -311.750338) (xy 281.961336 -311.746392) (xy 281.953577 -311.721578) (xy 281.94516 -311.670276)
			(xy 281.944572 -311.644284) (xy 281.944572 -311.5056) (xy 281.945166 -311.479609) (xy 281.953591 -311.42831)
			(xy 281.961336 -311.403492) (xy 281.962536 -311.399536) (xy 281.963813 -311.391369) (xy 281.963876 -311.387236)
			(xy 281.963876 -310.812688) (xy 281.963842 -310.808552) (xy 281.962561 -310.800382) (xy 281.961336 -310.796432)
			(xy 281.953574 -310.771618) (xy 281.94515 -310.720317) (xy 281.944572 -310.694324) (xy 281.944572 -310.555386)
			(xy 281.945167 -310.529395) (xy 281.953595 -310.478097) (xy 281.961336 -310.453278) (xy 281.962535 -310.449322)
			(xy 281.96381 -310.441155) (xy 281.963876 -310.437022) (xy 281.963876 -310.071516) (xy 281.962155 -310.06442)
			(xy 281.955319 -310.051526) (xy 281.950414 -310.046116) (xy 281.900884 -309.995316) (xy 281.897389 -309.991859)
			(xy 281.889332 -309.98623) (xy 281.884882 -309.98414) (xy 281.875992 -309.98033) (xy 281.866086 -309.980076)
			(xy 281.841299 -309.978892) (xy 281.792578 -309.969492) (xy 281.746016 -309.95234) (xy 281.702841 -309.927885)
			(xy 281.664186 -309.896772) (xy 281.63107 -309.85982) (xy 281.604364 -309.817999) (xy 281.58477 -309.772412)
			(xy 281.572803 -309.724256) (xy 281.568779 -309.674799) (xy 281.572803 -309.625342) (xy 281.58477 -309.577187)
			(xy 281.604365 -309.531599) (xy 281.631071 -309.489779) (xy 281.664188 -309.452827) (xy 281.702842 -309.421714)
			(xy 281.746018 -309.39726) (xy 281.792579 -309.380107) (xy 281.841301 -309.370708) (xy 281.866086 -309.36946)
			(xy 281.875992 -309.369206) (xy 281.884882 -309.365396) (xy 281.889332 -309.363306) (xy 281.897396 -309.357684)
			(xy 281.900884 -309.35422) (xy 281.950414 -309.30342) (xy 281.955356 -309.298037) (xy 281.962198 -309.285132)
			(xy 281.963876 -309.27802) (xy 281.963876 -309.121556) (xy 281.96216 -309.114457) (xy 281.955331 -309.101556)
			(xy 281.950414 -309.096156) (xy 281.900884 -309.045356) (xy 281.897387 -309.041902) (xy 281.889327 -309.036279)
			(xy 281.884882 -309.03418) (xy 281.875992 -309.03037) (xy 281.866086 -309.030116) (xy 281.841296 -309.028932)
			(xy 281.792568 -309.019531) (xy 281.746001 -309.002376) (xy 281.702819 -308.977919) (xy 281.66416 -308.946802)
			(xy 281.631039 -308.909845) (xy 281.604329 -308.868019) (xy 281.584732 -308.822425) (xy 281.572764 -308.774263)
			(xy 281.568739 -308.7248) (xy 281.572764 -308.675337) (xy 281.584732 -308.627175) (xy 281.604329 -308.581581)
			(xy 281.631039 -308.539756) (xy 281.664159 -308.502798) (xy 281.702819 -308.471682) (xy 281.746 -308.447224)
			(xy 281.792568 -308.430069) (xy 281.841296 -308.420668) (xy 281.866086 -308.4195) (xy 281.875992 -308.419246)
			(xy 281.884882 -308.415436) (xy 281.889004 -308.413498) (xy 281.896538 -308.408383) (xy 281.899868 -308.405276)
			(xy 281.900884 -308.40426) (xy 281.914854 -308.389782) (xy 281.930094 -308.374034) (xy 281.936635 -308.366704)
			(xy 281.944072 -308.34854) (xy 281.944572 -308.338728) (xy 281.944572 -304.983642) (xy 281.944709 -304.978751)
			(xy 281.946627 -304.969159) (xy 281.948382 -304.964592) (xy 281.990292 -304.861468) (xy 281.992416 -304.856661)
			(xy 281.99831 -304.847962) (xy 282.001976 -304.844196) (xy 282.0416 -304.805842) (xy 282.042108 -304.805334)
			(xy 282.144216 -304.703226) (xy 282.15106 -304.695828) (xy 282.158781 -304.677228) (xy 282.159202 -304.667158)
			(xy 282.159202 -304.631598) (xy 282.159626 -304.621528) (xy 282.167341 -304.602924) (xy 282.174188 -304.59553)
			(xy 282.547568 -304.22215) (xy 282.554968 -304.215309) (xy 282.573567 -304.207591) (xy 282.583636 -304.207164)
			(xy 282.619196 -304.207164) (xy 282.629266 -304.206741) (xy 282.647868 -304.199023) (xy 282.655264 -304.192178)
			(xy 282.68168 -304.165762) (xy 282.700106 -304.147998) (xy 282.741469 -304.117855) (xy 282.787033 -304.094546)
			(xy 282.83568 -304.078644) (xy 282.886215 -304.070538) (xy 282.911804 -304.070004) (xy 290.827714 -304.070004)
			(xy 290.837783 -304.069578) (xy 290.856384 -304.061861) (xy 290.863782 -304.055018) (xy 290.916614 -304.002186)
			(xy 290.923468 -303.994791) (xy 290.93121 -303.976192) (xy 290.9316 -303.966118) (xy 290.9316 -303.456848)
			(xy 290.931189 -303.44682) (xy 290.923527 -303.428287) (xy 290.909353 -303.4141) (xy 290.890827 -303.406421)
			(xy 290.8808 -303.406048) (xy 290.42487 -303.406048) (xy 290.397639 -303.40556) (xy 290.343731 -303.397806)
			(xy 290.291476 -303.382458) (xy 290.241936 -303.359831) (xy 290.196121 -303.330384) (xy 290.154962 -303.294717)
			(xy 290.119298 -303.253555) (xy 290.089855 -303.207738) (xy 290.067231 -303.158196) (xy 290.051888 -303.10594)
			(xy 290.044138 -303.052031) (xy 290.044138 -302.997569) (xy 290.051888 -302.94366) (xy 290.067231 -302.891404)
			(xy 290.089855 -302.841862) (xy 290.119298 -302.796045) (xy 290.154962 -302.754883) (xy 290.196121 -302.719216)
			(xy 290.241936 -302.689769) (xy 290.291476 -302.667142) (xy 290.343731 -302.651794) (xy 290.397639 -302.64404)
			(xy 290.42487 -302.64354) (xy 290.710112 -302.64354) (xy 290.72018 -302.643113) (xy 290.738776 -302.635389)
			(xy 290.74618 -302.628554) (xy 290.81603 -302.558704) (xy 290.822885 -302.551309) (xy 290.830632 -302.53271)
			(xy 290.831016 -302.522636) (xy 290.831016 -301.394876) (xy 290.830542 -301.384606) (xy 290.822488 -301.365711)
			(xy 290.807677 -301.35148) (xy 290.79825 -301.347378) (xy 290.70935 -301.313596) (xy 290.699547 -301.310372)
			(xy 290.678949 -301.311216) (xy 290.660354 -301.320115) (xy 290.653216 -301.327566) (xy 290.635681 -301.346517)
			(xy 290.595411 -301.37882) (xy 290.550279 -301.403888) (xy 290.501574 -301.421006) (xy 290.450683 -301.429686)
			(xy 290.42487 -301.430182) (xy 290.399618 -301.429658) (xy 290.349805 -301.421341) (xy 290.302039 -301.404939)
			(xy 290.257625 -301.380899) (xy 290.217772 -301.349877) (xy 290.183569 -301.312719) (xy 290.155948 -301.270439)
			(xy 290.135662 -301.224189) (xy 290.123265 -301.175231) (xy 290.119095 -301.1249) (xy 290.123265 -301.074569)
			(xy 290.135662 -301.025611) (xy 290.155948 -300.979361) (xy 290.183569 -300.937081) (xy 290.217772 -300.899923)
			(xy 290.257625 -300.868901) (xy 290.302039 -300.844861) (xy 290.349805 -300.828459) (xy 290.399618 -300.820142)
			(xy 290.42487 -300.819566) (xy 290.450678 -300.82011) (xy 290.501559 -300.828798) (xy 290.550256 -300.845915)
			(xy 290.595382 -300.870974) (xy 290.635654 -300.903261) (xy 290.653216 -300.922182) (xy 290.660382 -300.929592)
			(xy 290.678969 -300.938462) (xy 290.699546 -300.939337) (xy 290.70935 -300.936152) (xy 290.79825 -300.90237)
			(xy 290.807682 -300.898281) (xy 290.822484 -300.884042) (xy 290.830522 -300.865142) (xy 290.831016 -300.854872)
			(xy 290.831016 -299.494956) (xy 290.830538 -299.484689) (xy 290.82248 -299.4658) (xy 290.80767 -299.451575)
			(xy 290.79825 -299.447458) (xy 290.70935 -299.413676) (xy 290.699547 -299.410453) (xy 290.678949 -299.411296)
			(xy 290.660351 -299.420193) (xy 290.653216 -299.427646) (xy 290.635679 -299.446592) (xy 290.595405 -299.478888)
			(xy 290.550274 -299.503949) (xy 290.50157 -299.521062) (xy 290.450682 -299.52974) (xy 290.42487 -299.530262)
			(xy 290.39962 -299.529738) (xy 290.34981 -299.521422) (xy 290.302047 -299.505021) (xy 290.257636 -299.480983)
			(xy 290.217786 -299.449963) (xy 290.183585 -299.412807) (xy 290.155966 -299.370529) (xy 290.135681 -299.324282)
			(xy 290.123285 -299.275327) (xy 290.119115 -299.225) (xy 290.123285 -299.174673) (xy 290.135681 -299.125718)
			(xy 290.155966 -299.079471) (xy 290.183585 -299.037193) (xy 290.217786 -299.000037) (xy 290.257636 -298.969017)
			(xy 290.302047 -298.944979) (xy 290.34981 -298.928578) (xy 290.39962 -298.920262) (xy 290.42487 -298.919646)
			(xy 290.450679 -298.92019) (xy 290.50156 -298.928878) (xy 290.550257 -298.945994) (xy 290.595384 -298.971051)
			(xy 290.635658 -299.003338) (xy 290.653216 -299.022262) (xy 290.660381 -299.029675) (xy 290.678968 -299.038548)
			(xy 290.699547 -299.039423) (xy 290.70935 -299.036232) (xy 290.79825 -299.00245) (xy 290.80768 -298.99836)
			(xy 290.822476 -298.98412) (xy 290.830507 -298.96522) (xy 290.831016 -298.954952) (xy 290.831016 -297.594782)
			(xy 290.830543 -297.584512) (xy 290.822491 -297.565615) (xy 290.80768 -297.551382) (xy 290.79825 -297.547284)
			(xy 290.70935 -297.513502) (xy 290.699548 -297.510278) (xy 290.67895 -297.511122) (xy 290.660355 -297.520022)
			(xy 290.653216 -297.527472) (xy 290.635681 -297.546422) (xy 290.59541 -297.578725) (xy 290.550279 -297.603793)
			(xy 290.501574 -297.62091) (xy 290.450683 -297.62959) (xy 290.42487 -297.630088) (xy 290.399618 -297.629564)
			(xy 290.349803 -297.621247) (xy 290.302037 -297.604845) (xy 290.257621 -297.580804) (xy 290.217768 -297.549782)
			(xy 290.183564 -297.512623) (xy 290.155943 -297.470342) (xy 290.135657 -297.424091) (xy 290.123259 -297.375132)
			(xy 290.119089 -297.3248) (xy 290.123259 -297.274468) (xy 290.135657 -297.225509) (xy 290.155943 -297.179258)
			(xy 290.183564 -297.136977) (xy 290.217768 -297.099818) (xy 290.257621 -297.068796) (xy 290.302037 -297.044755)
			(xy 290.349803 -297.028353) (xy 290.399618 -297.020036) (xy 290.42487 -297.019472) (xy 290.450678 -297.020016)
			(xy 290.501559 -297.028704) (xy 290.550255 -297.045822) (xy 290.595381 -297.070881) (xy 290.635653 -297.103169)
			(xy 290.653216 -297.122088) (xy 290.660382 -297.129498) (xy 290.678969 -297.138366) (xy 290.699545 -297.139241)
			(xy 290.70935 -297.136058) (xy 290.79825 -297.102276) (xy 290.807683 -297.098187) (xy 290.822486 -297.083949)
			(xy 290.830526 -297.065048) (xy 290.831016 -297.054778) (xy 290.831016 -296.678858) (xy 290.830586 -296.668791)
			(xy 290.822862 -296.650196) (xy 290.81603 -296.64279) (xy 290.40963 -296.23639) (xy 290.402232 -296.229545)
			(xy 290.383633 -296.221822) (xy 290.373562 -296.221404) (xy 289.87877 -296.221404) (xy 289.86787 -296.221871)
			(xy 289.848007 -296.230838) (xy 289.840416 -296.238676) (xy 289.782504 -296.304462) (xy 289.776408 -296.325036)
			(xy 289.777678 -296.335958) (xy 289.77886 -296.34563) (xy 289.78013 -296.365076) (xy 289.780218 -296.37482)
			(xy 289.779696 -296.400075) (xy 289.771383 -296.449897) (xy 289.754982 -296.497671) (xy 289.730941 -296.542094)
			(xy 289.699917 -296.581954) (xy 289.662755 -296.616164) (xy 289.620469 -296.64379) (xy 289.574213 -296.66408)
			(xy 289.525248 -296.67648) (xy 289.47491 -296.680651) (xy 289.424572 -296.67648) (xy 289.375607 -296.66408)
			(xy 289.329351 -296.64379) (xy 289.287065 -296.616164) (xy 289.249903 -296.581954) (xy 289.218879 -296.542094)
			(xy 289.194838 -296.497671) (xy 289.178437 -296.449897) (xy 289.170124 -296.400075) (xy 289.169602 -296.37482)
			(xy 289.169705 -296.36514) (xy 289.170978 -296.345822) (xy 289.172142 -296.336212) (xy 289.172142 -296.335704)
			(xy 289.173412 -296.325036) (xy 289.167316 -296.304462) (xy 289.109404 -296.238676) (xy 289.101821 -296.230829)
			(xy 289.081951 -296.221861) (xy 289.07105 -296.221404) (xy 287.978596 -296.221404) (xy 287.967694 -296.221865)
			(xy 287.947823 -296.230826) (xy 287.940242 -296.238676) (xy 287.88233 -296.304462) (xy 287.876234 -296.325036)
			(xy 287.877504 -296.335958) (xy 287.878686 -296.34563) (xy 287.879956 -296.365076) (xy 287.880044 -296.37482)
			(xy 287.879522 -296.400075) (xy 287.871209 -296.449897) (xy 287.854808 -296.497671) (xy 287.830767 -296.542094)
			(xy 287.799743 -296.581954) (xy 287.762581 -296.616164) (xy 287.720295 -296.64379) (xy 287.674039 -296.66408)
			(xy 287.625074 -296.67648) (xy 287.574736 -296.680651) (xy 287.524398 -296.67648) (xy 287.475433 -296.66408)
			(xy 287.429177 -296.64379) (xy 287.386891 -296.616164) (xy 287.349729 -296.581954) (xy 287.318705 -296.542094)
			(xy 287.294664 -296.497671) (xy 287.278263 -296.449897) (xy 287.26995 -296.400075) (xy 287.269428 -296.37482)
			(xy 287.269531 -296.36514) (xy 287.270804 -296.345822) (xy 287.271968 -296.336212) (xy 287.271968 -296.335704)
			(xy 287.273238 -296.325036) (xy 287.267142 -296.304462) (xy 287.20923 -296.238676) (xy 287.201643 -296.230841)
			(xy 287.181772 -296.221902) (xy 287.170876 -296.221404) (xy 286.078676 -296.221404) (xy 286.067776 -296.221869)
			(xy 286.047911 -296.230835) (xy 286.040322 -296.238676) (xy 285.98241 -296.304462) (xy 285.976314 -296.325036)
			(xy 285.977584 -296.335958) (xy 285.978766 -296.34563) (xy 285.980036 -296.365076) (xy 285.980124 -296.37482)
			(xy 285.979602 -296.400075) (xy 285.971289 -296.449897) (xy 285.954888 -296.497671) (xy 285.930847 -296.542094)
			(xy 285.899823 -296.581954) (xy 285.862661 -296.616164) (xy 285.820375 -296.64379) (xy 285.774119 -296.66408)
			(xy 285.725154 -296.67648) (xy 285.674816 -296.680651) (xy 285.624478 -296.67648) (xy 285.575513 -296.66408)
			(xy 285.529257 -296.64379) (xy 285.486971 -296.616164) (xy 285.449809 -296.581954) (xy 285.418785 -296.542094)
			(xy 285.394744 -296.497671) (xy 285.378343 -296.449897) (xy 285.37003 -296.400075) (xy 285.369508 -296.37482)
			(xy 285.369611 -296.36514) (xy 285.370884 -296.345822) (xy 285.372048 -296.336212) (xy 285.372048 -296.335704)
			(xy 285.373318 -296.325036) (xy 285.367222 -296.304462) (xy 285.30931 -296.238676) (xy 285.301728 -296.230828)
			(xy 285.281857 -296.221858) (xy 285.270956 -296.221404) (xy 284.178756 -296.221404) (xy 284.167848 -296.221853)
			(xy 284.147959 -296.230799) (xy 284.140402 -296.238676) (xy 284.08249 -296.304462) (xy 284.076394 -296.325036)
			(xy 284.077664 -296.335958) (xy 284.078846 -296.34563) (xy 284.080117 -296.365076) (xy 284.080204 -296.37482)
			(xy 284.079682 -296.400075) (xy 284.071369 -296.449897) (xy 284.054968 -296.497671) (xy 284.030927 -296.542094)
			(xy 283.999903 -296.581954) (xy 283.962741 -296.616164) (xy 283.920455 -296.64379) (xy 283.874199 -296.66408)
			(xy 283.825234 -296.67648) (xy 283.774896 -296.680651) (xy 283.724558 -296.67648) (xy 283.675593 -296.66408)
			(xy 283.629337 -296.64379) (xy 283.587051 -296.616164) (xy 283.549889 -296.581954) (xy 283.518865 -296.542094)
			(xy 283.494824 -296.497671) (xy 283.478423 -296.449897) (xy 283.47011 -296.400075) (xy 283.469588 -296.37482)
			(xy 283.469691 -296.36514) (xy 283.470964 -296.345822) (xy 283.472128 -296.336212) (xy 283.472128 -296.335704)
			(xy 283.473398 -296.325036) (xy 283.467302 -296.304462) (xy 283.40939 -296.238676) (xy 283.401806 -296.230832)
			(xy 283.381936 -296.221869) (xy 283.371036 -296.221404) (xy 282.278582 -296.221404) (xy 282.267681 -296.221868)
			(xy 282.247814 -296.230832) (xy 282.240228 -296.238676) (xy 282.182316 -296.304462) (xy 282.17622 -296.325036)
			(xy 282.17749 -296.335958) (xy 282.178672 -296.34563) (xy 282.179942 -296.365076) (xy 282.18003 -296.37482)
			(xy 282.179508 -296.400075) (xy 282.171195 -296.449897) (xy 282.154794 -296.497671) (xy 282.130753 -296.542094)
			(xy 282.099729 -296.581954) (xy 282.062567 -296.616164) (xy 282.020281 -296.64379) (xy 281.974025 -296.66408)
			(xy 281.92506 -296.67648) (xy 281.874722 -296.680651) (xy 281.824384 -296.67648) (xy 281.775419 -296.66408)
			(xy 281.729163 -296.64379) (xy 281.686877 -296.616164) (xy 281.649715 -296.581954) (xy 281.618691 -296.542094)
			(xy 281.59465 -296.497671) (xy 281.578249 -296.449897) (xy 281.569936 -296.400075) (xy 281.569414 -296.37482)
			(xy 281.569517 -296.36514) (xy 281.57079 -296.345822) (xy 281.571954 -296.336212) (xy 281.571954 -296.335704)
			(xy 281.573224 -296.325036) (xy 281.567128 -296.304462) (xy 281.509216 -296.238676) (xy 281.501634 -296.230827)
			(xy 281.481764 -296.221854) (xy 281.470862 -296.221404) (xy 280.378662 -296.221404) (xy 280.367754 -296.221852)
			(xy 280.347862 -296.230796) (xy 280.340308 -296.238676) (xy 280.282396 -296.304462) (xy 280.2763 -296.325036)
			(xy 280.27757 -296.335958) (xy 280.278752 -296.34563) (xy 280.280022 -296.365076) (xy 280.28011 -296.37482)
			(xy 280.279588 -296.400075) (xy 280.271275 -296.449897) (xy 280.254874 -296.497671) (xy 280.230833 -296.542094)
			(xy 280.199809 -296.581954) (xy 280.162647 -296.616164) (xy 280.120361 -296.64379) (xy 280.074105 -296.66408)
			(xy 280.02514 -296.67648) (xy 279.974802 -296.680651) (xy 279.924464 -296.67648) (xy 279.875499 -296.66408)
			(xy 279.829243 -296.64379) (xy 279.786957 -296.616164) (xy 279.749795 -296.581954) (xy 279.718771 -296.542094)
			(xy 279.69473 -296.497671) (xy 279.678329 -296.449897) (xy 279.670016 -296.400075) (xy 279.669494 -296.37482)
			(xy 279.669597 -296.36514) (xy 279.67087 -296.345822) (xy 279.672034 -296.336212) (xy 279.672034 -296.335704)
			(xy 279.673304 -296.325036) (xy 279.667208 -296.304462) (xy 279.609296 -296.238676) (xy 279.601713 -296.230831)
			(xy 279.581842 -296.221866) (xy 279.570942 -296.221404) (xy 277.528782 -296.221404) (xy 277.517881 -296.221868)
			(xy 277.498014 -296.230832) (xy 277.490428 -296.238676) (xy 277.432516 -296.304462) (xy 277.42642 -296.325036)
			(xy 277.42769 -296.335958) (xy 277.428872 -296.34563) (xy 277.430142 -296.365076) (xy 277.43023 -296.37482)
			(xy 277.429708 -296.400075) (xy 277.421395 -296.449897) (xy 277.404994 -296.497671) (xy 277.380953 -296.542094)
			(xy 277.349929 -296.581954) (xy 277.312767 -296.616164) (xy 277.270481 -296.64379) (xy 277.224225 -296.66408)
			(xy 277.17526 -296.67648) (xy 277.124922 -296.680651) (xy 277.074584 -296.67648) (xy 277.025619 -296.66408)
			(xy 276.979363 -296.64379) (xy 276.937077 -296.616164) (xy 276.899915 -296.581954) (xy 276.868891 -296.542094)
			(xy 276.84485 -296.497671) (xy 276.828449 -296.449897) (xy 276.820136 -296.400075) (xy 276.819614 -296.37482)
			(xy 276.819717 -296.36514) (xy 276.82099 -296.345822) (xy 276.822154 -296.336212) (xy 276.822154 -296.335704)
			(xy 276.823424 -296.325036) (xy 276.817328 -296.304462) (xy 276.759416 -296.238676) (xy 276.751834 -296.230827)
			(xy 276.731964 -296.221854) (xy 276.721062 -296.221404) (xy 267.581888 -296.221404) (xy 267.551972 -296.220797)
			(xy 267.492879 -296.21141) (xy 267.435975 -296.192916) (xy 267.382655 -296.165766) (xy 267.334226 -296.130628)
			(xy 267.312648 -296.109898) (xy 266.878054 -295.67505) (xy 266.870655 -295.668205) (xy 266.852057 -295.66048)
			(xy 266.841986 -295.660064) (xy 264.382504 -295.660064) (xy 264.370088 -295.660683) (xy 264.348128 -295.672273)
			(xy 264.340594 -295.682162) (xy 264.293096 -295.750996) (xy 264.286747 -295.761553) (xy 264.283831 -295.785974)
			(xy 264.287508 -295.797732) (xy 264.2954 -295.81942) (xy 264.306478 -295.864223) (xy 264.312058 -295.910038)
			(xy 264.3124 -295.933114) (xy 264.311836 -295.962493) (xy 264.302786 -296.020552) (xy 264.284947 -296.076539)
			(xy 264.258741 -296.129131) (xy 264.224787 -296.177088) (xy 264.183887 -296.219276) (xy 264.160762 -296.237406)
			(xy 264.151364 -296.244518) (xy 264.140696 -296.265346) (xy 264.139426 -296.369232) (xy 264.149332 -296.390314)
			(xy 264.158476 -296.39768) (xy 264.1803 -296.415911) (xy 264.218829 -296.457733) (xy 264.25073 -296.504806)
			(xy 264.275297 -296.556089) (xy 264.291988 -296.610448) (xy 264.300433 -296.666682) (xy 264.30097 -296.695114)
			(xy 264.934444 -296.695114) (xy 264.938515 -296.639492) (xy 264.950641 -296.585055) (xy 264.970564 -296.532964)
			(xy 264.99786 -296.484329) (xy 265.031946 -296.440186) (xy 265.072095 -296.401477) (xy 265.117453 -296.369026)
			(xy 265.167053 -296.343525) (xy 265.219837 -296.325518) (xy 265.27468 -296.315388) (xy 265.330414 -296.313351)
			(xy 265.385851 -296.319451) (xy 265.439808 -296.333557) (xy 265.491137 -296.355369) (xy 265.538743 -296.384423)
			(xy 265.581611 -296.420098) (xy 265.618828 -296.461635) (xy 265.649601 -296.508148) (xy 265.673273 -296.558645)
			(xy 265.689341 -296.612052) (xy 265.697461 -296.667228) (xy 265.69797 -296.695114) (xy 265.697461 -296.723)
			(xy 265.689341 -296.778176) (xy 265.673273 -296.831583) (xy 265.649601 -296.88208) (xy 265.618828 -296.928593)
			(xy 265.581611 -296.97013) (xy 265.538743 -297.005805) (xy 265.491137 -297.034859) (xy 265.439808 -297.056671)
			(xy 265.385851 -297.070777) (xy 265.330414 -297.076877) (xy 265.27468 -297.07484) (xy 265.219837 -297.06471)
			(xy 265.167053 -297.046703) (xy 265.117453 -297.021202) (xy 265.072095 -296.988751) (xy 265.031946 -296.950042)
			(xy 264.99786 -296.905899) (xy 264.970564 -296.857264) (xy 264.950641 -296.805173) (xy 264.938515 -296.750736)
			(xy 264.934444 -296.695114) (xy 264.30097 -296.695114) (xy 264.300484 -296.722365) (xy 264.292728 -296.776313)
			(xy 264.277373 -296.828608) (xy 264.254731 -296.878185) (xy 264.225265 -296.924035) (xy 264.189574 -296.965226)
			(xy 264.148383 -297.000917) (xy 264.102533 -297.030383) (xy 264.052956 -297.053025) (xy 264.000661 -297.06838)
			(xy 263.946713 -297.076136) (xy 263.892211 -297.076136) (xy 263.838263 -297.06838) (xy 263.785968 -297.053025)
			(xy 263.736391 -297.030383) (xy 263.690541 -297.000917) (xy 263.64935 -296.965226) (xy 263.613659 -296.924035)
			(xy 263.584193 -296.878185) (xy 263.561551 -296.828608) (xy 263.546196 -296.776313) (xy 263.53844 -296.722365)
			(xy 263.537954 -296.695114) (xy 263.538517 -296.665734) (xy 263.547564 -296.607675) (xy 263.565401 -296.551687)
			(xy 263.591607 -296.499094) (xy 263.625563 -296.451137) (xy 263.666466 -296.408951) (xy 263.689592 -296.390822)
			(xy 263.69899 -296.38371) (xy 263.709658 -296.362882) (xy 263.710928 -296.258996) (xy 263.701022 -296.237914)
			(xy 263.691878 -296.230548) (xy 263.670054 -296.212317) (xy 263.631527 -296.170494) (xy 263.599627 -296.12342)
			(xy 263.575059 -296.072138) (xy 263.558366 -296.017779) (xy 263.549918 -295.961546) (xy 263.549384 -295.933114)
			(xy 263.549754 -295.91004) (xy 263.555354 -295.864233) (xy 263.566426 -295.819433) (xy 263.574276 -295.797732)
			(xy 263.578848 -295.785794) (xy 263.5758 -295.76141) (xy 263.52119 -295.682162) (xy 263.51366 -295.672275)
			(xy 263.491693 -295.660711) (xy 263.47928 -295.660064) (xy 263.420352 -295.660064) (xy 263.410287 -295.660498)
			(xy 263.391701 -295.668231) (xy 263.384284 -295.67505) (xy 263.030462 -296.028872) (xy 263.02362 -296.036271)
			(xy 263.015902 -296.05487) (xy 263.015476 -296.06494) (xy 263.015476 -297.350792) (xy 268.244255 -297.350792)
			(xy 268.244255 -297.298808) (xy 268.252388 -297.247465) (xy 268.268452 -297.198025) (xy 268.292053 -297.151708)
			(xy 268.322609 -297.109653) (xy 268.359368 -297.072896) (xy 268.401425 -297.042342) (xy 268.447744 -297.018744)
			(xy 268.497184 -297.002683) (xy 268.548528 -296.994554) (xy 268.57452 -296.994072) (xy 269.52448 -296.994072)
			(xy 269.550469 -296.994594) (xy 269.601807 -297.002722) (xy 269.651241 -297.018781) (xy 269.697554 -297.042377)
			(xy 269.739606 -297.072927) (xy 269.77636 -297.109679) (xy 269.806913 -297.151729) (xy 269.830511 -297.198041)
			(xy 269.846573 -297.247474) (xy 269.854705 -297.298811) (xy 269.854705 -297.32478) (xy 278.719038 -297.32478)
			(xy 278.722998 -297.275726) (xy 278.734775 -297.227942) (xy 278.754066 -297.182666) (xy 278.780369 -297.14107)
			(xy 278.813004 -297.104233) (xy 278.851125 -297.073108) (xy 278.893746 -297.048501) (xy 278.939762 -297.031049)
			(xy 278.987981 -297.021205) (xy 279.037156 -297.019224) (xy 279.086011 -297.025156) (xy 279.133282 -297.038848)
			(xy 279.177744 -297.059946) (xy 279.218247 -297.087902) (xy 279.25374 -297.121994) (xy 279.283305 -297.161338)
			(xy 279.306176 -297.204915) (xy 279.32176 -297.251596) (xy 279.329655 -297.300173) (xy 279.33015 -297.32478)
			(xy 280.618958 -297.32478) (xy 280.622918 -297.275726) (xy 280.634695 -297.227942) (xy 280.653986 -297.182666)
			(xy 280.680289 -297.14107) (xy 280.712924 -297.104233) (xy 280.751045 -297.073108) (xy 280.793666 -297.048501)
			(xy 280.839682 -297.031049) (xy 280.887901 -297.021205) (xy 280.937076 -297.019224) (xy 280.985931 -297.025156)
			(xy 281.033202 -297.038848) (xy 281.077664 -297.059946) (xy 281.118167 -297.087902) (xy 281.15366 -297.121994)
			(xy 281.183225 -297.161338) (xy 281.206096 -297.204915) (xy 281.22168 -297.251596) (xy 281.229575 -297.300173)
			(xy 281.23007 -297.32478) (xy 282.519132 -297.32478) (xy 282.523092 -297.275726) (xy 282.534869 -297.227942)
			(xy 282.55416 -297.182666) (xy 282.580463 -297.14107) (xy 282.613098 -297.104233) (xy 282.651219 -297.073108)
			(xy 282.69384 -297.048501) (xy 282.739856 -297.031049) (xy 282.788075 -297.021205) (xy 282.83725 -297.019224)
			(xy 282.886105 -297.025156) (xy 282.933376 -297.038848) (xy 282.977838 -297.059946) (xy 283.018341 -297.087902)
			(xy 283.053834 -297.121994) (xy 283.083399 -297.161338) (xy 283.10627 -297.204915) (xy 283.121854 -297.251596)
			(xy 283.129749 -297.300173) (xy 283.130244 -297.32478) (xy 284.419052 -297.32478) (xy 284.423012 -297.275726)
			(xy 284.434789 -297.227942) (xy 284.45408 -297.182666) (xy 284.480383 -297.14107) (xy 284.513018 -297.104233)
			(xy 284.551139 -297.073108) (xy 284.59376 -297.048501) (xy 284.639776 -297.031049) (xy 284.687995 -297.021205)
			(xy 284.73717 -297.019224) (xy 284.786025 -297.025156) (xy 284.833296 -297.038848) (xy 284.877758 -297.059946)
			(xy 284.918261 -297.087902) (xy 284.953754 -297.121994) (xy 284.983319 -297.161338) (xy 285.00619 -297.204915)
			(xy 285.021774 -297.251596) (xy 285.029669 -297.300173) (xy 285.030164 -297.32478) (xy 286.318972 -297.32478)
			(xy 286.322932 -297.275726) (xy 286.334709 -297.227942) (xy 286.354 -297.182666) (xy 286.380303 -297.14107)
			(xy 286.412938 -297.104233) (xy 286.451059 -297.073108) (xy 286.49368 -297.048501) (xy 286.539696 -297.031049)
			(xy 286.587915 -297.021205) (xy 286.63709 -297.019224) (xy 286.685945 -297.025156) (xy 286.733216 -297.038848)
			(xy 286.777678 -297.059946) (xy 286.818181 -297.087902) (xy 286.853674 -297.121994) (xy 286.883239 -297.161338)
			(xy 286.90611 -297.204915) (xy 286.921694 -297.251596) (xy 286.929589 -297.300173) (xy 286.930084 -297.32478)
			(xy 288.218892 -297.32478) (xy 288.222852 -297.275726) (xy 288.234629 -297.227942) (xy 288.25392 -297.182666)
			(xy 288.280223 -297.14107) (xy 288.312858 -297.104233) (xy 288.350979 -297.073108) (xy 288.3936 -297.048501)
			(xy 288.439616 -297.031049) (xy 288.487835 -297.021205) (xy 288.53701 -297.019224) (xy 288.585865 -297.025156)
			(xy 288.633136 -297.038848) (xy 288.677598 -297.059946) (xy 288.718101 -297.087902) (xy 288.753594 -297.121994)
			(xy 288.783159 -297.161338) (xy 288.80603 -297.204915) (xy 288.821614 -297.251596) (xy 288.829509 -297.300173)
			(xy 288.830004 -297.32478) (xy 288.829509 -297.349387) (xy 288.821614 -297.397964) (xy 288.80603 -297.444645)
			(xy 288.783159 -297.488222) (xy 288.753594 -297.527566) (xy 288.718101 -297.561658) (xy 288.677598 -297.589614)
			(xy 288.633136 -297.610712) (xy 288.585865 -297.624404) (xy 288.53701 -297.630336) (xy 288.487835 -297.628355)
			(xy 288.439616 -297.618511) (xy 288.3936 -297.601059) (xy 288.350979 -297.576452) (xy 288.312858 -297.545327)
			(xy 288.280223 -297.50849) (xy 288.25392 -297.466894) (xy 288.234629 -297.421618) (xy 288.222852 -297.373834)
			(xy 288.218892 -297.32478) (xy 286.930084 -297.32478) (xy 286.929589 -297.349387) (xy 286.921694 -297.397964)
			(xy 286.90611 -297.444645) (xy 286.883239 -297.488222) (xy 286.853674 -297.527566) (xy 286.818181 -297.561658)
			(xy 286.777678 -297.589614) (xy 286.733216 -297.610712) (xy 286.685945 -297.624404) (xy 286.63709 -297.630336)
			(xy 286.587915 -297.628355) (xy 286.539696 -297.618511) (xy 286.49368 -297.601059) (xy 286.451059 -297.576452)
			(xy 286.412938 -297.545327) (xy 286.380303 -297.50849) (xy 286.354 -297.466894) (xy 286.334709 -297.421618)
			(xy 286.322932 -297.373834) (xy 286.318972 -297.32478) (xy 285.030164 -297.32478) (xy 285.029669 -297.349387)
			(xy 285.021774 -297.397964) (xy 285.00619 -297.444645) (xy 284.983319 -297.488222) (xy 284.953754 -297.527566)
			(xy 284.918261 -297.561658) (xy 284.877758 -297.589614) (xy 284.833296 -297.610712) (xy 284.786025 -297.624404)
			(xy 284.73717 -297.630336) (xy 284.687995 -297.628355) (xy 284.639776 -297.618511) (xy 284.59376 -297.601059)
			(xy 284.551139 -297.576452) (xy 284.513018 -297.545327) (xy 284.480383 -297.50849) (xy 284.45408 -297.466894)
			(xy 284.434789 -297.421618) (xy 284.423012 -297.373834) (xy 284.419052 -297.32478) (xy 283.130244 -297.32478)
			(xy 283.129749 -297.349387) (xy 283.121854 -297.397964) (xy 283.10627 -297.444645) (xy 283.083399 -297.488222)
			(xy 283.053834 -297.527566) (xy 283.018341 -297.561658) (xy 282.977838 -297.589614) (xy 282.933376 -297.610712)
			(xy 282.886105 -297.624404) (xy 282.83725 -297.630336) (xy 282.788075 -297.628355) (xy 282.739856 -297.618511)
			(xy 282.69384 -297.601059) (xy 282.651219 -297.576452) (xy 282.613098 -297.545327) (xy 282.580463 -297.50849)
			(xy 282.55416 -297.466894) (xy 282.534869 -297.421618) (xy 282.523092 -297.373834) (xy 282.519132 -297.32478)
			(xy 281.23007 -297.32478) (xy 281.229575 -297.349387) (xy 281.22168 -297.397964) (xy 281.206096 -297.444645)
			(xy 281.183225 -297.488222) (xy 281.15366 -297.527566) (xy 281.118167 -297.561658) (xy 281.077664 -297.589614)
			(xy 281.033202 -297.610712) (xy 280.985931 -297.624404) (xy 280.937076 -297.630336) (xy 280.887901 -297.628355)
			(xy 280.839682 -297.618511) (xy 280.793666 -297.601059) (xy 280.751045 -297.576452) (xy 280.712924 -297.545327)
			(xy 280.680289 -297.50849) (xy 280.653986 -297.466894) (xy 280.634695 -297.421618) (xy 280.622918 -297.373834)
			(xy 280.618958 -297.32478) (xy 279.33015 -297.32478) (xy 279.329655 -297.349387) (xy 279.32176 -297.397964)
			(xy 279.306176 -297.444645) (xy 279.283305 -297.488222) (xy 279.25374 -297.527566) (xy 279.218247 -297.561658)
			(xy 279.177744 -297.589614) (xy 279.133282 -297.610712) (xy 279.086011 -297.624404) (xy 279.037156 -297.630336)
			(xy 278.987981 -297.628355) (xy 278.939762 -297.618511) (xy 278.893746 -297.601059) (xy 278.851125 -297.576452)
			(xy 278.813004 -297.545327) (xy 278.780369 -297.50849) (xy 278.754066 -297.466894) (xy 278.734775 -297.421618)
			(xy 278.722998 -297.373834) (xy 278.719038 -297.32478) (xy 269.854705 -297.32478) (xy 269.854705 -297.350789)
			(xy 269.846573 -297.402126) (xy 269.830511 -297.451559) (xy 269.806913 -297.497871) (xy 269.77636 -297.539921)
			(xy 269.739606 -297.576673) (xy 269.697554 -297.607223) (xy 269.651241 -297.630819) (xy 269.601807 -297.646878)
			(xy 269.550469 -297.655006) (xy 269.52448 -297.655488) (xy 268.57452 -297.655488) (xy 268.548528 -297.655046)
			(xy 268.497184 -297.646917) (xy 268.447744 -297.630856) (xy 268.401425 -297.607258) (xy 268.359368 -297.576704)
			(xy 268.322609 -297.539947) (xy 268.292053 -297.497892) (xy 268.268452 -297.451575) (xy 268.252388 -297.402135)
			(xy 268.244255 -297.350792) (xy 263.015476 -297.350792) (xy 263.015476 -298.27474) (xy 276.819118 -298.27474)
			(xy 276.823078 -298.225686) (xy 276.834855 -298.177902) (xy 276.854146 -298.132626) (xy 276.880449 -298.09103)
			(xy 276.913084 -298.054193) (xy 276.951205 -298.023068) (xy 276.993826 -297.998461) (xy 277.039842 -297.981009)
			(xy 277.088061 -297.971165) (xy 277.137236 -297.969184) (xy 277.186091 -297.975116) (xy 277.233362 -297.988808)
			(xy 277.277824 -298.009906) (xy 277.318327 -298.037862) (xy 277.35382 -298.071954) (xy 277.383385 -298.111298)
			(xy 277.406256 -298.154875) (xy 277.42184 -298.201556) (xy 277.429735 -298.250133) (xy 277.43023 -298.27474)
			(xy 279.668998 -298.27474) (xy 279.672958 -298.225686) (xy 279.684735 -298.177902) (xy 279.704026 -298.132626)
			(xy 279.730329 -298.09103) (xy 279.762964 -298.054193) (xy 279.801085 -298.023068) (xy 279.843706 -297.998461)
			(xy 279.889722 -297.981009) (xy 279.937941 -297.971165) (xy 279.987116 -297.969184) (xy 280.035971 -297.975116)
			(xy 280.083242 -297.988808) (xy 280.127704 -298.009906) (xy 280.168207 -298.037862) (xy 280.2037 -298.071954)
			(xy 280.233265 -298.111298) (xy 280.256136 -298.154875) (xy 280.27172 -298.201556) (xy 280.279615 -298.250133)
			(xy 280.28011 -298.27474) (xy 281.568918 -298.27474) (xy 281.572878 -298.225686) (xy 281.584655 -298.177902)
			(xy 281.603946 -298.132626) (xy 281.630249 -298.09103) (xy 281.662884 -298.054193) (xy 281.701005 -298.023068)
			(xy 281.743626 -297.998461) (xy 281.789642 -297.981009) (xy 281.837861 -297.971165) (xy 281.887036 -297.969184)
			(xy 281.935891 -297.975116) (xy 281.983162 -297.988808) (xy 282.027624 -298.009906) (xy 282.068127 -298.037862)
			(xy 282.10362 -298.071954) (xy 282.133185 -298.111298) (xy 282.156056 -298.154875) (xy 282.17164 -298.201556)
			(xy 282.179535 -298.250133) (xy 282.18003 -298.27474) (xy 283.469092 -298.27474) (xy 283.473052 -298.225686)
			(xy 283.484829 -298.177902) (xy 283.50412 -298.132626) (xy 283.530423 -298.09103) (xy 283.563058 -298.054193)
			(xy 283.601179 -298.023068) (xy 283.6438 -297.998461) (xy 283.689816 -297.981009) (xy 283.738035 -297.971165)
			(xy 283.78721 -297.969184) (xy 283.836065 -297.975116) (xy 283.883336 -297.988808) (xy 283.927798 -298.009906)
			(xy 283.968301 -298.037862) (xy 284.003794 -298.071954) (xy 284.033359 -298.111298) (xy 284.05623 -298.154875)
			(xy 284.071814 -298.201556) (xy 284.079709 -298.250133) (xy 284.080204 -298.27474) (xy 285.369012 -298.27474)
			(xy 285.372972 -298.225686) (xy 285.384749 -298.177902) (xy 285.40404 -298.132626) (xy 285.430343 -298.09103)
			(xy 285.462978 -298.054193) (xy 285.501099 -298.023068) (xy 285.54372 -297.998461) (xy 285.589736 -297.981009)
			(xy 285.637955 -297.971165) (xy 285.68713 -297.969184) (xy 285.735985 -297.975116) (xy 285.783256 -297.988808)
			(xy 285.827718 -298.009906) (xy 285.868221 -298.037862) (xy 285.903714 -298.071954) (xy 285.933279 -298.111298)
			(xy 285.95615 -298.154875) (xy 285.971734 -298.201556) (xy 285.979629 -298.250133) (xy 285.980124 -298.27474)
			(xy 287.268932 -298.27474) (xy 287.272892 -298.225686) (xy 287.284669 -298.177902) (xy 287.30396 -298.132626)
			(xy 287.330263 -298.09103) (xy 287.362898 -298.054193) (xy 287.401019 -298.023068) (xy 287.44364 -297.998461)
			(xy 287.489656 -297.981009) (xy 287.537875 -297.971165) (xy 287.58705 -297.969184) (xy 287.635905 -297.975116)
			(xy 287.683176 -297.988808) (xy 287.727638 -298.009906) (xy 287.768141 -298.037862) (xy 287.803634 -298.071954)
			(xy 287.833199 -298.111298) (xy 287.85607 -298.154875) (xy 287.871654 -298.201556) (xy 287.879549 -298.250133)
			(xy 287.880044 -298.27474) (xy 289.169106 -298.27474) (xy 289.173066 -298.225686) (xy 289.184843 -298.177902)
			(xy 289.204134 -298.132626) (xy 289.230437 -298.09103) (xy 289.263072 -298.054193) (xy 289.301193 -298.023068)
			(xy 289.343814 -297.998461) (xy 289.38983 -297.981009) (xy 289.438049 -297.971165) (xy 289.487224 -297.969184)
			(xy 289.536079 -297.975116) (xy 289.58335 -297.988808) (xy 289.627812 -298.009906) (xy 289.668315 -298.037862)
			(xy 289.703808 -298.071954) (xy 289.733373 -298.111298) (xy 289.756244 -298.154875) (xy 289.771828 -298.201556)
			(xy 289.779723 -298.250133) (xy 289.780218 -298.27474) (xy 289.779723 -298.299347) (xy 289.771828 -298.347924)
			(xy 289.756244 -298.394605) (xy 289.733373 -298.438182) (xy 289.703808 -298.477526) (xy 289.668315 -298.511618)
			(xy 289.627812 -298.539574) (xy 289.58335 -298.560672) (xy 289.536079 -298.574364) (xy 289.487224 -298.580296)
			(xy 289.438049 -298.578315) (xy 289.38983 -298.568471) (xy 289.343814 -298.551019) (xy 289.301193 -298.526412)
			(xy 289.263072 -298.495287) (xy 289.230437 -298.45845) (xy 289.204134 -298.416854) (xy 289.184843 -298.371578)
			(xy 289.173066 -298.323794) (xy 289.169106 -298.27474) (xy 287.880044 -298.27474) (xy 287.879549 -298.299347)
			(xy 287.871654 -298.347924) (xy 287.85607 -298.394605) (xy 287.833199 -298.438182) (xy 287.803634 -298.477526)
			(xy 287.768141 -298.511618) (xy 287.727638 -298.539574) (xy 287.683176 -298.560672) (xy 287.635905 -298.574364)
			(xy 287.58705 -298.580296) (xy 287.537875 -298.578315) (xy 287.489656 -298.568471) (xy 287.44364 -298.551019)
			(xy 287.401019 -298.526412) (xy 287.362898 -298.495287) (xy 287.330263 -298.45845) (xy 287.30396 -298.416854)
			(xy 287.284669 -298.371578) (xy 287.272892 -298.323794) (xy 287.268932 -298.27474) (xy 285.980124 -298.27474)
			(xy 285.979629 -298.299347) (xy 285.971734 -298.347924) (xy 285.95615 -298.394605) (xy 285.933279 -298.438182)
			(xy 285.903714 -298.477526) (xy 285.868221 -298.511618) (xy 285.827718 -298.539574) (xy 285.783256 -298.560672)
			(xy 285.735985 -298.574364) (xy 285.68713 -298.580296) (xy 285.637955 -298.578315) (xy 285.589736 -298.568471)
			(xy 285.54372 -298.551019) (xy 285.501099 -298.526412) (xy 285.462978 -298.495287) (xy 285.430343 -298.45845)
			(xy 285.40404 -298.416854) (xy 285.384749 -298.371578) (xy 285.372972 -298.323794) (xy 285.369012 -298.27474)
			(xy 284.080204 -298.27474) (xy 284.079709 -298.299347) (xy 284.071814 -298.347924) (xy 284.05623 -298.394605)
			(xy 284.033359 -298.438182) (xy 284.003794 -298.477526) (xy 283.968301 -298.511618) (xy 283.927798 -298.539574)
			(xy 283.883336 -298.560672) (xy 283.836065 -298.574364) (xy 283.78721 -298.580296) (xy 283.738035 -298.578315)
			(xy 283.689816 -298.568471) (xy 283.6438 -298.551019) (xy 283.601179 -298.526412) (xy 283.563058 -298.495287)
			(xy 283.530423 -298.45845) (xy 283.50412 -298.416854) (xy 283.484829 -298.371578) (xy 283.473052 -298.323794)
			(xy 283.469092 -298.27474) (xy 282.18003 -298.27474) (xy 282.179535 -298.299347) (xy 282.17164 -298.347924)
			(xy 282.156056 -298.394605) (xy 282.133185 -298.438182) (xy 282.10362 -298.477526) (xy 282.068127 -298.511618)
			(xy 282.027624 -298.539574) (xy 281.983162 -298.560672) (xy 281.935891 -298.574364) (xy 281.887036 -298.580296)
			(xy 281.837861 -298.578315) (xy 281.789642 -298.568471) (xy 281.743626 -298.551019) (xy 281.701005 -298.526412)
			(xy 281.662884 -298.495287) (xy 281.630249 -298.45845) (xy 281.603946 -298.416854) (xy 281.584655 -298.371578)
			(xy 281.572878 -298.323794) (xy 281.568918 -298.27474) (xy 280.28011 -298.27474) (xy 280.279615 -298.299347)
			(xy 280.27172 -298.347924) (xy 280.256136 -298.394605) (xy 280.233265 -298.438182) (xy 280.2037 -298.477526)
			(xy 280.168207 -298.511618) (xy 280.127704 -298.539574) (xy 280.083242 -298.560672) (xy 280.035971 -298.574364)
			(xy 279.987116 -298.580296) (xy 279.937941 -298.578315) (xy 279.889722 -298.568471) (xy 279.843706 -298.551019)
			(xy 279.801085 -298.526412) (xy 279.762964 -298.495287) (xy 279.730329 -298.45845) (xy 279.704026 -298.416854)
			(xy 279.684735 -298.371578) (xy 279.672958 -298.323794) (xy 279.668998 -298.27474) (xy 277.43023 -298.27474)
			(xy 277.429735 -298.299347) (xy 277.42184 -298.347924) (xy 277.406256 -298.394605) (xy 277.383385 -298.438182)
			(xy 277.35382 -298.477526) (xy 277.318327 -298.511618) (xy 277.277824 -298.539574) (xy 277.233362 -298.560672)
			(xy 277.186091 -298.574364) (xy 277.137236 -298.580296) (xy 277.088061 -298.578315) (xy 277.039842 -298.568471)
			(xy 276.993826 -298.551019) (xy 276.951205 -298.526412) (xy 276.913084 -298.495287) (xy 276.880449 -298.45845)
			(xy 276.854146 -298.416854) (xy 276.834855 -298.371578) (xy 276.823078 -298.323794) (xy 276.819118 -298.27474)
			(xy 263.015476 -298.27474) (xy 263.015476 -299.895514) (xy 263.537954 -299.895514) (xy 263.53852 -299.866133)
			(xy 263.547548 -299.808068) (xy 263.565376 -299.752075) (xy 263.591583 -299.69948) (xy 263.625547 -299.651528)
			(xy 263.666466 -299.609354) (xy 263.689592 -299.591222) (xy 263.698524 -299.58375) (xy 263.708977 -299.562969)
			(xy 263.709658 -299.551344) (xy 263.710928 -299.459396) (xy 263.701022 -299.438314) (xy 263.691878 -299.430948)
			(xy 263.670018 -299.412756) (xy 263.63148 -299.370933) (xy 263.599575 -299.323855) (xy 263.57501 -299.272563)
			(xy 263.558329 -299.218193) (xy 263.549902 -299.16195) (xy 263.549384 -299.133514) (xy 263.54987 -299.106263)
			(xy 263.557626 -299.052315) (xy 263.572981 -299.00002) (xy 263.595623 -298.950443) (xy 263.625089 -298.904593)
			(xy 263.66078 -298.863402) (xy 263.701971 -298.827711) (xy 263.747821 -298.798245) (xy 263.797398 -298.775603)
			(xy 263.849693 -298.760248) (xy 263.903641 -298.752492) (xy 263.958143 -298.752492) (xy 264.012091 -298.760248)
			(xy 264.064386 -298.775603) (xy 264.113963 -298.798245) (xy 264.159813 -298.827711) (xy 264.201004 -298.863402)
			(xy 264.236695 -298.904593) (xy 264.266161 -298.950443) (xy 264.288803 -299.00002) (xy 264.304158 -299.052315)
			(xy 264.311914 -299.106263) (xy 264.3124 -299.133514) (xy 264.311872 -299.162897) (xy 264.302839 -299.220964)
			(xy 264.285005 -299.276959) (xy 264.258791 -299.329554) (xy 264.224818 -299.377505) (xy 264.183891 -299.419676)
			(xy 264.160762 -299.437806) (xy 264.151826 -299.445275) (xy 264.141373 -299.466057) (xy 264.140696 -299.477684)
			(xy 264.139426 -299.569632) (xy 264.149332 -299.590714) (xy 264.158476 -299.59808) (xy 264.180292 -299.616323)
			(xy 264.218835 -299.658133) (xy 264.250747 -299.705201) (xy 264.275319 -299.756484) (xy 264.292009 -299.810845)
			(xy 264.300447 -299.867081) (xy 264.30097 -299.895514) (xy 264.934444 -299.895514) (xy 264.938515 -299.839892)
			(xy 264.950641 -299.785455) (xy 264.970564 -299.733364) (xy 264.99786 -299.684729) (xy 265.031946 -299.640586)
			(xy 265.072095 -299.601877) (xy 265.117453 -299.569426) (xy 265.167053 -299.543925) (xy 265.219837 -299.525918)
			(xy 265.27468 -299.515788) (xy 265.330414 -299.513751) (xy 265.385851 -299.519851) (xy 265.439808 -299.533957)
			(xy 265.491137 -299.555769) (xy 265.538743 -299.584823) (xy 265.581611 -299.620498) (xy 265.618828 -299.662035)
			(xy 265.649601 -299.708548) (xy 265.673273 -299.759045) (xy 265.689341 -299.812452) (xy 265.697461 -299.867628)
			(xy 265.69797 -299.895514) (xy 265.697461 -299.9234) (xy 265.689341 -299.978576) (xy 265.673273 -300.031983)
			(xy 265.649601 -300.08248) (xy 265.618828 -300.128993) (xy 265.581611 -300.17053) (xy 265.538743 -300.206205)
			(xy 265.491137 -300.235259) (xy 265.439808 -300.257071) (xy 265.385851 -300.271177) (xy 265.330414 -300.277277)
			(xy 265.27468 -300.27524) (xy 265.219837 -300.26511) (xy 265.167053 -300.247103) (xy 265.117453 -300.221602)
			(xy 265.072095 -300.189151) (xy 265.031946 -300.150442) (xy 264.99786 -300.106299) (xy 264.970564 -300.057664)
			(xy 264.950641 -300.005573) (xy 264.938515 -299.951136) (xy 264.934444 -299.895514) (xy 264.30097 -299.895514)
			(xy 264.300484 -299.922765) (xy 264.292728 -299.976713) (xy 264.277373 -300.029008) (xy 264.254731 -300.078585)
			(xy 264.225265 -300.124435) (xy 264.189574 -300.165626) (xy 264.148383 -300.201317) (xy 264.102533 -300.230783)
			(xy 264.052956 -300.253425) (xy 264.000661 -300.26878) (xy 263.946713 -300.276536) (xy 263.892211 -300.276536)
			(xy 263.838263 -300.26878) (xy 263.785968 -300.253425) (xy 263.736391 -300.230783) (xy 263.690541 -300.201317)
			(xy 263.64935 -300.165626) (xy 263.613659 -300.124435) (xy 263.584193 -300.078585) (xy 263.561551 -300.029008)
			(xy 263.546196 -299.976713) (xy 263.53844 -299.922765) (xy 263.537954 -299.895514) (xy 263.015476 -299.895514)
			(xy 263.015476 -300.337728) (xy 263.014868 -300.367644) (xy 263.005478 -300.426735) (xy 262.986981 -300.483636)
			(xy 262.959829 -300.536953) (xy 262.924688 -300.585379) (xy 262.90397 -300.606968) (xy 254.974344 -308.536594)
			(xy 254.952768 -308.55733) (xy 254.904351 -308.592494) (xy 254.851033 -308.619657) (xy 254.794124 -308.638152)
			(xy 254.735023 -308.647522) (xy 254.705104 -308.6481) (xy 249.049032 -308.6481) (xy 249.038967 -308.648536)
			(xy 249.020381 -308.656267) (xy 249.012964 -308.663086) (xy 248.847864 -308.828186) (xy 248.846848 -308.829202)
			(xy 248.828744 -308.847972) (xy 248.788297 -308.880891) (xy 248.743742 -308.907992) (xy 248.695911 -308.928771)
			(xy 248.645695 -308.942841) (xy 248.594031 -308.949939) (xy 248.567956 -308.95036) (xy 248.540706 -308.949894)
			(xy 248.486763 -308.942131) (xy 248.434473 -308.926771) (xy 248.384901 -308.904125) (xy 248.339057 -308.874655)
			(xy 248.297874 -308.838961) (xy 248.262189 -308.797769) (xy 248.232731 -308.751918) (xy 248.210097 -308.702341)
			(xy 248.194749 -308.650047) (xy 248.187 -308.596102) (xy 248.186448 -308.568852) (xy 248.186896 -308.54278)
			(xy 248.194002 -308.491121) (xy 248.208075 -308.440912) (xy 248.228854 -308.393086) (xy 248.25595 -308.348534)
			(xy 248.28886 -308.308086) (xy 248.307606 -308.28996) (xy 248.308114 -308.289198) (xy 248.534936 -308.062376)
			(xy 248.541616 -308.054966) (xy 248.549204 -308.036538) (xy 248.549194 -308.016609) (xy 248.541586 -307.998188)
			(xy 248.534936 -307.990748) (xy 248.305828 -307.761386) (xy 248.304812 -307.76037) (xy 248.286463 -307.742312)
			(xy 248.254296 -307.702117) (xy 248.227829 -307.657959) (xy 248.207543 -307.610642) (xy 248.193808 -307.561026)
			(xy 248.186872 -307.510013) (xy 248.186448 -307.484272) (xy 248.186936 -307.457021) (xy 248.194695 -307.403074)
			(xy 248.210052 -307.35078) (xy 248.232694 -307.301203) (xy 248.262161 -307.255353) (xy 248.297852 -307.214163)
			(xy 248.339041 -307.17847) (xy 248.384889 -307.149002) (xy 248.434465 -307.126358) (xy 248.486758 -307.110999)
			(xy 248.540705 -307.103237) (xy 248.567956 -307.102764) (xy 248.590816 -307.103526) (xy 248.715022 -307.103526)
			(xy 248.72509 -307.103954) (xy 248.743686 -307.111677) (xy 248.75109 -307.118512) (xy 249.036586 -307.403754)
			(xy 249.043987 -307.410592) (xy 249.062586 -307.418302) (xy 249.072654 -307.41874) (xy 254.331216 -307.41874)
			(xy 254.341284 -307.418312) (xy 254.359878 -307.410587) (xy 254.367284 -307.403754) (xy 260.325616 -301.445422)
			(xy 260.325616 -301.444406) (xy 261.765288 -300.004734) (xy 261.772125 -299.997332) (xy 261.779837 -299.978734)
			(xy 261.780274 -299.968666) (xy 261.780274 -299.944536) (xy 261.780708 -299.93447) (xy 261.788436 -299.91588)
			(xy 261.79526 -299.908468) (xy 261.795768 -299.90796) (xy 261.795768 -295.6306) (xy 261.795344 -295.62053)
			(xy 261.787626 -295.601929) (xy 261.780782 -295.594532) (xy 261.62889 -295.44264) (xy 261.621493 -295.435791)
			(xy 261.602894 -295.428054) (xy 261.592822 -295.427654) (xy 248.604024 -295.427654) (xy 248.594003 -295.427238)
			(xy 248.575486 -295.419571) (xy 248.561317 -295.405396) (xy 248.553658 -295.386875) (xy 248.553224 -295.376854)
			(xy 248.553224 -281.848306) (xy 248.553052 -281.842298) (xy 248.55022 -281.830619) (xy 248.547636 -281.825192)
			(xy 248.545798 -281.821717) (xy 248.541208 -281.815334) (xy 248.538492 -281.812492) (xy 248.299732 -281.573732)
			(xy 248.296882 -281.571025) (xy 248.290505 -281.566428) (xy 248.287032 -281.564588) (xy 248.281604 -281.562008)
			(xy 248.269925 -281.559191) (xy 248.263918 -281.559) (xy 234.717082 -281.559) (xy 234.707013 -281.559427)
			(xy 234.688414 -281.567146) (xy 234.681014 -281.573986) (xy 234.10291 -282.15209) (xy 234.096061 -282.159487)
			(xy 234.088321 -282.178085) (xy 234.087924 -282.188158) (xy 234.087924 -283.009456) (xy 241.001717 -283.009456)
			(xy 241.001717 -282.954944) (xy 241.009475 -282.900988) (xy 241.024833 -282.848684) (xy 241.047478 -282.799099)
			(xy 241.076949 -282.753241) (xy 241.112647 -282.712044) (xy 241.153844 -282.676347) (xy 241.199702 -282.646876)
			(xy 241.249288 -282.624231) (xy 241.301591 -282.608874) (xy 241.355548 -282.601117) (xy 241.382804 -282.600654)
			(xy 241.411542 -282.601188) (xy 241.468369 -282.60981) (xy 241.523259 -282.626858) (xy 241.574971 -282.651947)
			(xy 241.622334 -282.684509) (xy 241.643662 -282.703778) (xy 241.65052 -282.710382) (xy 241.668554 -282.717494)
			(xy 241.757454 -282.717494) (xy 241.775488 -282.710382) (xy 241.782346 -282.703778) (xy 241.803673 -282.684508)
			(xy 241.851036 -282.651943) (xy 241.902747 -282.626852) (xy 241.957638 -282.609802) (xy 242.014465 -282.60118)
			(xy 242.071943 -282.60118) (xy 242.12877 -282.609802) (xy 242.183661 -282.626852) (xy 242.235372 -282.651943)
			(xy 242.282735 -282.684508) (xy 242.304062 -282.703778) (xy 242.31092 -282.710382) (xy 242.328954 -282.717494)
			(xy 242.417854 -282.717494) (xy 242.435888 -282.710382) (xy 242.442746 -282.703778) (xy 242.464077 -282.684512)
			(xy 242.511437 -282.651944) (xy 242.563148 -282.626849) (xy 242.618038 -282.609798) (xy 242.674865 -282.601175)
			(xy 242.703604 -282.600654) (xy 242.733728 -282.601221) (xy 242.793224 -282.610703) (xy 242.850492 -282.629414)
			(xy 242.904109 -282.656891) (xy 242.952743 -282.692451) (xy 242.974368 -282.71343) (xy 242.981781 -282.720253)
			(xy 243.000371 -282.727982) (xy 243.010436 -282.728416) (xy 243.082572 -282.728416) (xy 243.092643 -282.727998)
			(xy 243.111242 -282.720275) (xy 243.11864 -282.71343) (xy 243.140273 -282.692459) (xy 243.188899 -282.656888)
			(xy 243.242513 -282.629406) (xy 243.299782 -282.610696) (xy 243.35928 -282.601223) (xy 243.389404 -282.600654)
			(xy 243.416652 -282.601216) (xy 243.470594 -282.608973) (xy 243.522883 -282.624327) (xy 243.572455 -282.646966)
			(xy 243.6183 -282.676429) (xy 243.659486 -282.712117) (xy 243.695173 -282.753303) (xy 243.724636 -282.799149)
			(xy 243.747275 -282.848721) (xy 243.762628 -282.90101) (xy 243.770384 -282.954952) (xy 243.770384 -283.009448)
			(xy 243.762628 -283.06339) (xy 243.747275 -283.115679) (xy 243.724636 -283.165251) (xy 243.695173 -283.211097)
			(xy 243.659486 -283.252283) (xy 243.6183 -283.287971) (xy 243.572455 -283.317434) (xy 243.522883 -283.340073)
			(xy 243.470594 -283.355427) (xy 243.416652 -283.363184) (xy 243.389404 -283.36367) (xy 243.359281 -283.363091)
			(xy 243.299785 -283.353611) (xy 243.242518 -283.334902) (xy 243.1889 -283.307428) (xy 243.140265 -283.271872)
			(xy 243.11864 -283.250894) (xy 243.111221 -283.244078) (xy 243.092636 -283.236345) (xy 243.082572 -283.235908)
			(xy 243.010436 -283.235908) (xy 243.000369 -283.23635) (xy 242.98177 -283.244059) (xy 242.974368 -283.250894)
			(xy 242.952735 -283.271866) (xy 242.904109 -283.307435) (xy 242.850494 -283.334917) (xy 242.793226 -283.353627)
			(xy 242.733728 -283.363101) (xy 242.703604 -283.36367) (xy 242.674866 -283.363125) (xy 242.618041 -283.354505)
			(xy 242.563151 -283.337459) (xy 242.511439 -283.312372) (xy 242.464074 -283.279813) (xy 242.442746 -283.260546)
			(xy 242.435888 -283.253942) (xy 242.417854 -283.24683) (xy 242.328954 -283.24683) (xy 242.31092 -283.253942)
			(xy 242.304062 -283.260546) (xy 242.282735 -283.279816) (xy 242.235372 -283.312381) (xy 242.183661 -283.337472)
			(xy 242.12877 -283.354522) (xy 242.071943 -283.363144) (xy 242.014465 -283.363144) (xy 241.957638 -283.354522)
			(xy 241.902747 -283.337472) (xy 241.851036 -283.312381) (xy 241.803673 -283.279816) (xy 241.782346 -283.260546)
			(xy 241.775488 -283.253942) (xy 241.757454 -283.24683) (xy 241.668554 -283.24683) (xy 241.65052 -283.253942)
			(xy 241.643662 -283.260546) (xy 241.622331 -283.279812) (xy 241.57497 -283.31238) (xy 241.52326 -283.337473)
			(xy 241.46837 -283.354525) (xy 241.411543 -283.363149) (xy 241.382804 -283.36367) (xy 241.355548 -283.363283)
			(xy 241.301591 -283.355526) (xy 241.249288 -283.340169) (xy 241.199702 -283.317524) (xy 241.153844 -283.288053)
			(xy 241.112647 -283.252356) (xy 241.076949 -283.211159) (xy 241.047478 -283.165301) (xy 241.024833 -283.115716)
			(xy 241.009475 -283.063412) (xy 241.001717 -283.009456) (xy 234.087924 -283.009456) (xy 234.087924 -284.66875)
			(xy 237.195599 -284.66875) (xy 237.195599 -284.61425) (xy 237.203356 -284.560304) (xy 237.218711 -284.508011)
			(xy 237.241352 -284.458435) (xy 237.270817 -284.412587) (xy 237.306509 -284.371399) (xy 237.347698 -284.335709)
			(xy 237.393548 -284.306245) (xy 237.443124 -284.283606) (xy 237.495417 -284.268253) (xy 237.549364 -284.260498)
			(xy 237.576614 -284.260036) (xy 237.605352 -284.260568) (xy 237.662179 -284.269191) (xy 237.717069 -284.28624)
			(xy 237.76878 -284.31133) (xy 237.816144 -284.343891) (xy 237.837472 -284.36316) (xy 237.84433 -284.369764)
			(xy 237.862364 -284.376876) (xy 237.951264 -284.376876) (xy 237.969298 -284.369764) (xy 237.976156 -284.36316)
			(xy 237.997483 -284.34389) (xy 238.044846 -284.311325) (xy 238.096557 -284.286234) (xy 238.151448 -284.269184)
			(xy 238.208275 -284.260562) (xy 238.265753 -284.260562) (xy 238.32258 -284.269184) (xy 238.377471 -284.286234)
			(xy 238.429182 -284.311325) (xy 238.476545 -284.34389) (xy 238.497872 -284.36316) (xy 238.50473 -284.369764)
			(xy 238.522764 -284.376876) (xy 238.611664 -284.376876) (xy 238.629698 -284.369764) (xy 238.636556 -284.36316)
			(xy 238.657881 -284.343886) (xy 238.705243 -284.31132) (xy 238.756955 -284.286227) (xy 238.811847 -284.269177)
			(xy 238.868675 -284.260556) (xy 238.897414 -284.260036) (xy 238.927538 -284.260602) (xy 238.987034 -284.270085)
			(xy 239.044302 -284.288797) (xy 239.097919 -284.316274) (xy 239.146553 -284.351833) (xy 239.168178 -284.372812)
			(xy 239.17559 -284.379636) (xy 239.19418 -284.387365) (xy 239.204246 -284.387798) (xy 239.276382 -284.387798)
			(xy 239.286454 -284.38739) (xy 239.305053 -284.37966) (xy 239.31245 -284.372812) (xy 239.334076 -284.351833)
			(xy 239.382704 -284.316264) (xy 239.43632 -284.288783) (xy 239.49359 -284.270075) (xy 239.55309 -284.260604)
			(xy 239.583214 -284.260036) (xy 239.610468 -284.260435) (xy 239.66442 -284.268194) (xy 239.716719 -284.283552)
			(xy 239.7663 -284.306197) (xy 239.812154 -284.335667) (xy 239.853348 -284.371362) (xy 239.889042 -284.412557)
			(xy 239.91851 -284.458412) (xy 239.941153 -284.507994) (xy 239.956509 -284.560294) (xy 239.964266 -284.614246)
			(xy 239.964266 -284.668754) (xy 239.956509 -284.722706) (xy 239.941153 -284.775006) (xy 239.91851 -284.824588)
			(xy 239.889042 -284.870443) (xy 239.853348 -284.911638) (xy 239.812154 -284.947333) (xy 239.7663 -284.976803)
			(xy 239.716719 -284.999448) (xy 239.66442 -285.014806) (xy 239.610468 -285.022565) (xy 239.583214 -285.023052)
			(xy 239.553091 -285.022472) (xy 239.493595 -285.012993) (xy 239.436327 -284.994284) (xy 239.38271 -284.966811)
			(xy 239.334075 -284.931254) (xy 239.31245 -284.910276) (xy 239.30503 -284.903462) (xy 239.286446 -284.895728)
			(xy 239.276382 -284.89529) (xy 239.204246 -284.89529) (xy 239.194176 -284.895716) (xy 239.175577 -284.903434)
			(xy 239.168178 -284.910276) (xy 239.146538 -284.93124) (xy 239.097914 -284.966811) (xy 239.044301 -284.994295)
			(xy 238.987034 -285.013007) (xy 238.927537 -285.022482) (xy 238.897414 -285.023052) (xy 238.868676 -285.022506)
			(xy 238.81185 -285.013887) (xy 238.75696 -284.996841) (xy 238.705248 -284.971755) (xy 238.657884 -284.939196)
			(xy 238.636556 -284.919928) (xy 238.629698 -284.913324) (xy 238.611664 -284.906212) (xy 238.522764 -284.906212)
			(xy 238.50473 -284.913324) (xy 238.497872 -284.919928) (xy 238.476545 -284.939198) (xy 238.429182 -284.971763)
			(xy 238.377471 -284.996854) (xy 238.32258 -285.013904) (xy 238.265753 -285.022526) (xy 238.208275 -285.022526)
			(xy 238.151448 -285.013904) (xy 238.096557 -284.996854) (xy 238.044846 -284.971763) (xy 237.997483 -284.939198)
			(xy 237.976156 -284.919928) (xy 237.969298 -284.913324) (xy 237.951264 -284.906212) (xy 237.862364 -284.906212)
			(xy 237.84433 -284.913324) (xy 237.837472 -284.919928) (xy 237.816134 -284.939186) (xy 237.768776 -284.971756)
			(xy 237.717067 -284.996851) (xy 237.662178 -285.013905) (xy 237.605352 -285.02253) (xy 237.576614 -285.023052)
			(xy 237.549364 -285.022502) (xy 237.495417 -285.014747) (xy 237.443124 -284.999394) (xy 237.393548 -284.976755)
			(xy 237.347698 -284.947291) (xy 237.306509 -284.911601) (xy 237.270817 -284.870413) (xy 237.241352 -284.824565)
			(xy 237.218711 -284.774989) (xy 237.203356 -284.722696) (xy 237.195599 -284.66875) (xy 234.087924 -284.66875)
			(xy 234.087924 -285.473256) (xy 241.001717 -285.473256) (xy 241.001717 -285.418744) (xy 241.009475 -285.364788)
			(xy 241.024833 -285.312484) (xy 241.047478 -285.262899) (xy 241.076949 -285.217041) (xy 241.112647 -285.175844)
			(xy 241.153844 -285.140147) (xy 241.199702 -285.110676) (xy 241.249288 -285.088031) (xy 241.301591 -285.072674)
			(xy 241.355548 -285.064917) (xy 241.382804 -285.064454) (xy 241.411542 -285.064988) (xy 241.468369 -285.07361)
			(xy 241.523259 -285.090658) (xy 241.574971 -285.115747) (xy 241.622334 -285.148309) (xy 241.643662 -285.167578)
			(xy 241.65052 -285.174182) (xy 241.668554 -285.181294) (xy 241.757454 -285.181294) (xy 241.775488 -285.174182)
			(xy 241.782346 -285.167578) (xy 241.803673 -285.148308) (xy 241.851036 -285.115743) (xy 241.902747 -285.090652)
			(xy 241.957638 -285.073602) (xy 242.014465 -285.06498) (xy 242.071943 -285.06498) (xy 242.12877 -285.073602)
			(xy 242.183661 -285.090652) (xy 242.235372 -285.115743) (xy 242.282735 -285.148308) (xy 242.304062 -285.167578)
			(xy 242.31092 -285.174182) (xy 242.328954 -285.181294) (xy 242.417854 -285.181294) (xy 242.435888 -285.174182)
			(xy 242.442746 -285.167578) (xy 242.464077 -285.148312) (xy 242.511437 -285.115744) (xy 242.563148 -285.090649)
			(xy 242.618038 -285.073598) (xy 242.674865 -285.064975) (xy 242.703604 -285.064454) (xy 242.733728 -285.065021)
			(xy 242.793224 -285.074503) (xy 242.850492 -285.093214) (xy 242.904109 -285.120691) (xy 242.952743 -285.156251)
			(xy 242.974368 -285.17723) (xy 242.981781 -285.184053) (xy 243.000371 -285.191782) (xy 243.010436 -285.192216)
			(xy 243.082572 -285.192216) (xy 243.092643 -285.191798) (xy 243.111242 -285.184075) (xy 243.11864 -285.17723)
			(xy 243.140273 -285.156259) (xy 243.188899 -285.120688) (xy 243.242513 -285.093206) (xy 243.299782 -285.074496)
			(xy 243.35928 -285.065023) (xy 243.389404 -285.064454) (xy 243.416652 -285.065016) (xy 243.470594 -285.072773)
			(xy 243.522883 -285.088127) (xy 243.572455 -285.110766) (xy 243.6183 -285.140229) (xy 243.659486 -285.175917)
			(xy 243.695173 -285.217103) (xy 243.724636 -285.262949) (xy 243.747275 -285.312521) (xy 243.762628 -285.36481)
			(xy 243.770384 -285.418752) (xy 243.770384 -285.473248) (xy 243.762628 -285.52719) (xy 243.747275 -285.579479)
			(xy 243.724636 -285.629051) (xy 243.695173 -285.674897) (xy 243.659486 -285.716083) (xy 243.6183 -285.751771)
			(xy 243.572455 -285.781234) (xy 243.522883 -285.803873) (xy 243.470594 -285.819227) (xy 243.416652 -285.826984)
			(xy 243.389404 -285.82747) (xy 243.359281 -285.826891) (xy 243.299785 -285.817411) (xy 243.242518 -285.798702)
			(xy 243.1889 -285.771228) (xy 243.140265 -285.735672) (xy 243.11864 -285.714694) (xy 243.111221 -285.707878)
			(xy 243.092636 -285.700145) (xy 243.082572 -285.699708) (xy 243.010436 -285.699708) (xy 243.000369 -285.70015)
			(xy 242.98177 -285.707859) (xy 242.974368 -285.714694) (xy 242.952735 -285.735666) (xy 242.904109 -285.771235)
			(xy 242.850494 -285.798717) (xy 242.793226 -285.817427) (xy 242.733728 -285.826901) (xy 242.703604 -285.82747)
			(xy 242.674866 -285.826925) (xy 242.618041 -285.818305) (xy 242.563151 -285.801259) (xy 242.511439 -285.776172)
			(xy 242.464074 -285.743613) (xy 242.442746 -285.724346) (xy 242.435888 -285.717742) (xy 242.417854 -285.71063)
			(xy 242.328954 -285.71063) (xy 242.31092 -285.717742) (xy 242.304062 -285.724346) (xy 242.282735 -285.743616)
			(xy 242.235372 -285.776181) (xy 242.183661 -285.801272) (xy 242.12877 -285.818322) (xy 242.071943 -285.826944)
			(xy 242.014465 -285.826944) (xy 241.957638 -285.818322) (xy 241.902747 -285.801272) (xy 241.851036 -285.776181)
			(xy 241.803673 -285.743616) (xy 241.782346 -285.724346) (xy 241.775488 -285.717742) (xy 241.757454 -285.71063)
			(xy 241.668554 -285.71063) (xy 241.65052 -285.717742) (xy 241.643662 -285.724346) (xy 241.622331 -285.743612)
			(xy 241.57497 -285.77618) (xy 241.52326 -285.801273) (xy 241.46837 -285.818325) (xy 241.411543 -285.826949)
			(xy 241.382804 -285.82747) (xy 241.355548 -285.827083) (xy 241.301591 -285.819326) (xy 241.249288 -285.803969)
			(xy 241.199702 -285.781324) (xy 241.153844 -285.751853) (xy 241.112647 -285.716156) (xy 241.076949 -285.674959)
			(xy 241.047478 -285.629101) (xy 241.024833 -285.579516) (xy 241.009475 -285.527212) (xy 241.001717 -285.473256)
			(xy 234.087924 -285.473256) (xy 234.087924 -287.13255) (xy 237.195599 -287.13255) (xy 237.195599 -287.07805)
			(xy 237.203356 -287.024104) (xy 237.218711 -286.971811) (xy 237.241352 -286.922235) (xy 237.270817 -286.876387)
			(xy 237.306509 -286.835199) (xy 237.347698 -286.799509) (xy 237.393548 -286.770045) (xy 237.443124 -286.747406)
			(xy 237.495417 -286.732053) (xy 237.549364 -286.724298) (xy 237.576614 -286.723836) (xy 237.605352 -286.724368)
			(xy 237.662179 -286.732991) (xy 237.717069 -286.75004) (xy 237.76878 -286.77513) (xy 237.816144 -286.807691)
			(xy 237.837472 -286.82696) (xy 237.84433 -286.833564) (xy 237.862364 -286.840676) (xy 237.951264 -286.840676)
			(xy 237.969298 -286.833564) (xy 237.976156 -286.82696) (xy 237.997483 -286.80769) (xy 238.044846 -286.775125)
			(xy 238.096557 -286.750034) (xy 238.151448 -286.732984) (xy 238.208275 -286.724362) (xy 238.265753 -286.724362)
			(xy 238.32258 -286.732984) (xy 238.377471 -286.750034) (xy 238.429182 -286.775125) (xy 238.476545 -286.80769)
			(xy 238.497872 -286.82696) (xy 238.50473 -286.833564) (xy 238.522764 -286.840676) (xy 238.611664 -286.840676)
			(xy 238.629698 -286.833564) (xy 238.636556 -286.82696) (xy 238.657881 -286.807686) (xy 238.705243 -286.77512)
			(xy 238.756955 -286.750027) (xy 238.811847 -286.732977) (xy 238.868675 -286.724356) (xy 238.897414 -286.723836)
			(xy 238.927538 -286.724402) (xy 238.987034 -286.733885) (xy 239.044302 -286.752597) (xy 239.097919 -286.780074)
			(xy 239.146553 -286.815633) (xy 239.168178 -286.836612) (xy 239.17559 -286.843436) (xy 239.19418 -286.851165)
			(xy 239.204246 -286.851598) (xy 239.276382 -286.851598) (xy 239.286454 -286.85119) (xy 239.305053 -286.84346)
			(xy 239.31245 -286.836612) (xy 239.334076 -286.815633) (xy 239.382704 -286.780064) (xy 239.43632 -286.752583)
			(xy 239.49359 -286.733875) (xy 239.55309 -286.724404) (xy 239.583214 -286.723836) (xy 239.610468 -286.724235)
			(xy 239.66442 -286.731994) (xy 239.716719 -286.747352) (xy 239.7663 -286.769997) (xy 239.812154 -286.799467)
			(xy 239.853348 -286.835162) (xy 239.889042 -286.876357) (xy 239.91851 -286.922212) (xy 239.941153 -286.971794)
			(xy 239.956509 -287.024094) (xy 239.964266 -287.078046) (xy 239.964266 -287.132554) (xy 239.956509 -287.186506)
			(xy 239.941153 -287.238806) (xy 239.91851 -287.288388) (xy 239.889042 -287.334243) (xy 239.853348 -287.375438)
			(xy 239.812154 -287.411133) (xy 239.7663 -287.440603) (xy 239.716719 -287.463248) (xy 239.66442 -287.478606)
			(xy 239.610468 -287.486365) (xy 239.583214 -287.486852) (xy 239.553091 -287.486272) (xy 239.493595 -287.476793)
			(xy 239.436327 -287.458084) (xy 239.38271 -287.430611) (xy 239.334075 -287.395054) (xy 239.31245 -287.374076)
			(xy 239.30503 -287.367262) (xy 239.286446 -287.359528) (xy 239.276382 -287.35909) (xy 239.204246 -287.35909)
			(xy 239.194176 -287.359516) (xy 239.175577 -287.367234) (xy 239.168178 -287.374076) (xy 239.146538 -287.39504)
			(xy 239.097914 -287.430611) (xy 239.044301 -287.458095) (xy 238.987034 -287.476807) (xy 238.927537 -287.486282)
			(xy 238.897414 -287.486852) (xy 238.868676 -287.486306) (xy 238.81185 -287.477687) (xy 238.75696 -287.460641)
			(xy 238.705248 -287.435555) (xy 238.657884 -287.402996) (xy 238.636556 -287.383728) (xy 238.629698 -287.377124)
			(xy 238.611664 -287.370012) (xy 238.522764 -287.370012) (xy 238.50473 -287.377124) (xy 238.497872 -287.383728)
			(xy 238.476545 -287.402998) (xy 238.429182 -287.435563) (xy 238.377471 -287.460654) (xy 238.32258 -287.477704)
			(xy 238.265753 -287.486326) (xy 238.208275 -287.486326) (xy 238.151448 -287.477704) (xy 238.096557 -287.460654)
			(xy 238.044846 -287.435563) (xy 237.997483 -287.402998) (xy 237.976156 -287.383728) (xy 237.969298 -287.377124)
			(xy 237.951264 -287.370012) (xy 237.862364 -287.370012) (xy 237.84433 -287.377124) (xy 237.837472 -287.383728)
			(xy 237.816134 -287.402986) (xy 237.768776 -287.435556) (xy 237.717067 -287.460651) (xy 237.662178 -287.477705)
			(xy 237.605352 -287.48633) (xy 237.576614 -287.486852) (xy 237.549364 -287.486302) (xy 237.495417 -287.478547)
			(xy 237.443124 -287.463194) (xy 237.393548 -287.440555) (xy 237.347698 -287.411091) (xy 237.306509 -287.375401)
			(xy 237.270817 -287.334213) (xy 237.241352 -287.288365) (xy 237.218711 -287.238789) (xy 237.203356 -287.186496)
			(xy 237.195599 -287.13255) (xy 234.087924 -287.13255) (xy 234.087924 -287.776255) (xy 242.583135 -287.776255)
			(xy 242.583135 -287.721745) (xy 242.590893 -287.667791) (xy 242.60625 -287.61549) (xy 242.628894 -287.565906)
			(xy 242.658364 -287.52005) (xy 242.694061 -287.478855) (xy 242.735257 -287.44316) (xy 242.781113 -287.41369)
			(xy 242.830697 -287.391047) (xy 242.882999 -287.375691) (xy 242.936953 -287.367934) (xy 242.964208 -287.367472)
			(xy 242.994332 -287.368031) (xy 243.053829 -287.377514) (xy 243.111097 -287.396227) (xy 243.164714 -287.423706)
			(xy 243.213348 -287.459267) (xy 243.234972 -287.480248) (xy 243.242394 -287.487061) (xy 243.260976 -287.494798)
			(xy 243.27104 -287.495234) (xy 243.343176 -287.495234) (xy 243.353246 -287.494814) (xy 243.371845 -287.487091)
			(xy 243.379244 -287.480248) (xy 243.400878 -287.459278) (xy 243.449504 -287.423706) (xy 243.503118 -287.396223)
			(xy 243.560386 -287.377513) (xy 243.619884 -287.368041) (xy 243.650008 -287.367472) (xy 243.677257 -287.367999)
			(xy 243.731201 -287.375756) (xy 243.783492 -287.391111) (xy 243.833066 -287.413751) (xy 243.878913 -287.443216)
			(xy 243.9201 -287.478906) (xy 243.955789 -287.520094) (xy 243.985253 -287.565941) (xy 244.007892 -287.615515)
			(xy 244.023246 -287.667806) (xy 244.031002 -287.721751) (xy 244.031002 -287.776249) (xy 244.023246 -287.830194)
			(xy 244.007892 -287.882485) (xy 243.985253 -287.932059) (xy 243.955789 -287.977906) (xy 243.9201 -288.019094)
			(xy 243.878913 -288.054784) (xy 243.833066 -288.084249) (xy 243.783492 -288.106889) (xy 243.731201 -288.122244)
			(xy 243.677257 -288.130001) (xy 243.650008 -288.130488) (xy 243.619884 -288.12993) (xy 243.560386 -288.120448)
			(xy 243.503117 -288.101736) (xy 243.449501 -288.074256) (xy 243.400868 -288.038693) (xy 243.379244 -288.017712)
			(xy 243.371821 -288.0109) (xy 243.353239 -288.003164) (xy 243.343176 -288.002726) (xy 243.27104 -288.002726)
			(xy 243.260972 -288.003166) (xy 243.242374 -288.010876) (xy 243.234972 -288.017712) (xy 243.213341 -288.038685)
			(xy 243.164713 -288.074254) (xy 243.111098 -288.101735) (xy 243.05383 -288.120445) (xy 242.994332 -288.129918)
			(xy 242.964208 -288.130488) (xy 242.936953 -288.130066) (xy 242.882999 -288.122309) (xy 242.830697 -288.106953)
			(xy 242.781113 -288.08431) (xy 242.735257 -288.05484) (xy 242.694061 -288.019145) (xy 242.658364 -287.97795)
			(xy 242.628894 -287.932094) (xy 242.60625 -287.88251) (xy 242.590893 -287.830209) (xy 242.583135 -287.776255)
			(xy 234.087924 -287.776255) (xy 234.087924 -288.652204) (xy 244.030752 -288.652204) (xy 244.034823 -288.596582)
			(xy 244.046949 -288.542145) (xy 244.066872 -288.490054) (xy 244.094168 -288.441419) (xy 244.128254 -288.397276)
			(xy 244.168403 -288.358567) (xy 244.213761 -288.326116) (xy 244.263361 -288.300615) (xy 244.316145 -288.282608)
			(xy 244.370988 -288.272478) (xy 244.426722 -288.270441) (xy 244.482159 -288.276541) (xy 244.536116 -288.290647)
			(xy 244.587445 -288.312459) (xy 244.635051 -288.341513) (xy 244.677919 -288.377188) (xy 244.715136 -288.418725)
			(xy 244.745909 -288.465238) (xy 244.769581 -288.515735) (xy 244.785649 -288.569142) (xy 244.793769 -288.624318)
			(xy 244.794278 -288.652204) (xy 244.793769 -288.68009) (xy 244.785649 -288.735266) (xy 244.769581 -288.788673)
			(xy 244.745909 -288.83917) (xy 244.715136 -288.885683) (xy 244.677919 -288.92722) (xy 244.635051 -288.962895)
			(xy 244.587445 -288.991949) (xy 244.536116 -289.013761) (xy 244.482159 -289.027867) (xy 244.426722 -289.033967)
			(xy 244.370988 -289.03193) (xy 244.316145 -289.0218) (xy 244.263361 -289.003793) (xy 244.213761 -288.978292)
			(xy 244.168403 -288.945841) (xy 244.128254 -288.907132) (xy 244.094168 -288.862989) (xy 244.066872 -288.814354)
			(xy 244.046949 -288.762263) (xy 244.034823 -288.707826) (xy 244.030752 -288.652204) (xy 234.087924 -288.652204)
			(xy 234.087924 -289.41855) (xy 236.509799 -289.41855) (xy 236.509799 -289.36405) (xy 236.517556 -289.310104)
			(xy 236.532911 -289.257811) (xy 236.555552 -289.208235) (xy 236.585017 -289.162387) (xy 236.620709 -289.121199)
			(xy 236.661898 -289.085509) (xy 236.707748 -289.056045) (xy 236.757324 -289.033406) (xy 236.809617 -289.018053)
			(xy 236.863564 -289.010298) (xy 236.890814 -289.009836) (xy 236.920938 -289.010402) (xy 236.980434 -289.019885)
			(xy 237.037702 -289.038597) (xy 237.091319 -289.066074) (xy 237.139953 -289.101633) (xy 237.161578 -289.122612)
			(xy 237.16899 -289.129436) (xy 237.18758 -289.137165) (xy 237.197646 -289.137598) (xy 237.269782 -289.137598)
			(xy 237.279854 -289.13719) (xy 237.298453 -289.12946) (xy 237.30585 -289.122612) (xy 237.327476 -289.101633)
			(xy 237.376104 -289.066064) (xy 237.42972 -289.038583) (xy 237.48699 -289.019875) (xy 237.54649 -289.010404)
			(xy 237.576614 -289.009836) (xy 237.603868 -289.010235) (xy 237.65782 -289.017994) (xy 237.710119 -289.033352)
			(xy 237.7597 -289.055997) (xy 237.805554 -289.085467) (xy 237.846748 -289.121162) (xy 237.882442 -289.162357)
			(xy 237.91191 -289.208212) (xy 237.934553 -289.257794) (xy 237.949909 -289.310094) (xy 237.957666 -289.364046)
			(xy 237.957666 -289.418554) (xy 237.949909 -289.472506) (xy 237.934553 -289.524806) (xy 237.91191 -289.574388)
			(xy 237.882442 -289.620243) (xy 237.846748 -289.661438) (xy 237.805554 -289.697133) (xy 237.7597 -289.726603)
			(xy 237.710119 -289.749248) (xy 237.65782 -289.764606) (xy 237.603868 -289.772365) (xy 237.576614 -289.772852)
			(xy 237.546491 -289.772272) (xy 237.486995 -289.762793) (xy 237.429727 -289.744084) (xy 237.37611 -289.716611)
			(xy 237.327475 -289.681054) (xy 237.30585 -289.660076) (xy 237.29843 -289.653262) (xy 237.279846 -289.645528)
			(xy 237.269782 -289.64509) (xy 237.197646 -289.64509) (xy 237.187576 -289.645516) (xy 237.168977 -289.653234)
			(xy 237.161578 -289.660076) (xy 237.139938 -289.68104) (xy 237.091314 -289.716611) (xy 237.037701 -289.744095)
			(xy 236.980434 -289.762807) (xy 236.920937 -289.772282) (xy 236.890814 -289.772852) (xy 236.863564 -289.772302)
			(xy 236.809617 -289.764547) (xy 236.757324 -289.749194) (xy 236.707748 -289.726555) (xy 236.661898 -289.697091)
			(xy 236.620709 -289.661401) (xy 236.585017 -289.620213) (xy 236.555552 -289.574365) (xy 236.532911 -289.524789)
			(xy 236.517556 -289.472496) (xy 236.509799 -289.41855) (xy 234.087924 -289.41855) (xy 234.087924 -290.900149)
			(xy 243.338104 -290.900149) (xy 243.338104 -290.845651) (xy 243.34586 -290.791707) (xy 243.361214 -290.739416)
			(xy 243.383853 -290.689843) (xy 243.413317 -290.643996) (xy 243.449006 -290.602809) (xy 243.490193 -290.567119)
			(xy 243.536039 -290.537655) (xy 243.585613 -290.515015) (xy 243.637903 -290.499661) (xy 243.691847 -290.491904)
			(xy 243.719096 -290.491418) (xy 243.746466 -290.491882) (xy 243.800646 -290.4997) (xy 243.853149 -290.515189)
			(xy 243.902896 -290.538031) (xy 243.948862 -290.567756) (xy 243.969794 -290.585398) (xy 243.970048 -290.585652)
			(xy 243.977141 -290.591229) (xy 243.994053 -290.59748) (xy 244.003068 -290.597844) (xy 244.070124 -290.597844)
			(xy 244.079144 -290.597511) (xy 244.096061 -290.591248) (xy 244.103144 -290.585652) (xy 244.103144 -290.585398)
			(xy 244.103398 -290.585398) (xy 244.12432 -290.567746) (xy 244.170295 -290.538036) (xy 244.220046 -290.515203)
			(xy 244.272549 -290.499715) (xy 244.326726 -290.49189) (xy 244.354096 -290.491418) (xy 244.381351 -290.491829)
			(xy 244.435306 -290.499586) (xy 244.487608 -290.514942) (xy 244.537192 -290.537586) (xy 244.583049 -290.567056)
			(xy 244.624245 -290.602752) (xy 244.659941 -290.643948) (xy 244.689412 -290.689804) (xy 244.712056 -290.739388)
			(xy 244.727413 -290.79169) (xy 244.735171 -290.845645) (xy 244.735171 -290.900155) (xy 244.727413 -290.95411)
			(xy 244.712056 -291.006412) (xy 244.689412 -291.055996) (xy 244.659941 -291.101852) (xy 244.624245 -291.143048)
			(xy 244.583049 -291.178744) (xy 244.537192 -291.208214) (xy 244.487608 -291.230858) (xy 244.435306 -291.246214)
			(xy 244.381351 -291.253971) (xy 244.354096 -291.254434) (xy 244.326725 -291.253986) (xy 244.272544 -291.246167)
			(xy 244.22004 -291.230674) (xy 244.170294 -291.207828) (xy 244.124328 -291.178098) (xy 244.103398 -291.160454)
			(xy 244.103144 -291.1602) (xy 244.096049 -291.154626) (xy 244.079139 -291.148372) (xy 244.070124 -291.148008)
			(xy 244.003068 -291.148008) (xy 243.994049 -291.148348) (xy 243.977133 -291.154607) (xy 243.970048 -291.1602)
			(xy 243.970048 -291.160454) (xy 243.969794 -291.160454) (xy 243.948869 -291.178102) (xy 243.902895 -291.207814)
			(xy 243.853146 -291.230649) (xy 243.800643 -291.246138) (xy 243.746466 -291.253962) (xy 243.719096 -291.254434)
			(xy 243.691847 -291.253896) (xy 243.637903 -291.246139) (xy 243.585613 -291.230785) (xy 243.536039 -291.208145)
			(xy 243.490193 -291.178681) (xy 243.449006 -291.142991) (xy 243.413317 -291.101804) (xy 243.383853 -291.055957)
			(xy 243.361214 -291.006384) (xy 243.34586 -290.954093) (xy 243.338104 -290.900149) (xy 234.087924 -290.900149)
			(xy 234.087924 -291.545049) (xy 236.34701 -291.545049) (xy 236.34701 -291.490551) (xy 236.354766 -291.436608)
			(xy 236.37012 -291.384318) (xy 236.392759 -291.334745) (xy 236.422223 -291.288898) (xy 236.457911 -291.247711)
			(xy 236.499098 -291.212023) (xy 236.544945 -291.182559) (xy 236.594518 -291.15992) (xy 236.646808 -291.144566)
			(xy 236.700751 -291.13681) (xy 236.728 -291.136324) (xy 236.755371 -291.136784) (xy 236.80955 -291.144603)
			(xy 236.862053 -291.160093) (xy 236.9118 -291.182936) (xy 236.957767 -291.212662) (xy 236.978698 -291.230304)
			(xy 236.978952 -291.230558) (xy 236.986043 -291.236138) (xy 237.002957 -291.242387) (xy 237.011972 -291.24275)
			(xy 237.079028 -291.24275) (xy 237.088048 -291.242417) (xy 237.104965 -291.236154) (xy 237.112048 -291.230558)
			(xy 237.112048 -291.230304) (xy 237.112302 -291.230304) (xy 237.133223 -291.212651) (xy 237.179199 -291.182941)
			(xy 237.228949 -291.160108) (xy 237.281452 -291.14462) (xy 237.33563 -291.136796) (xy 237.363 -291.136324)
			(xy 237.390254 -291.136746) (xy 237.444206 -291.144503) (xy 237.496505 -291.159859) (xy 237.546086 -291.182502)
			(xy 237.591941 -291.211971) (xy 237.633134 -291.247666) (xy 237.668829 -291.288859) (xy 237.698298 -291.334714)
			(xy 237.720941 -291.384295) (xy 237.736297 -291.436594) (xy 237.744054 -291.490546) (xy 237.744054 -291.545054)
			(xy 237.736297 -291.599006) (xy 237.720941 -291.651305) (xy 237.698298 -291.700886) (xy 237.668829 -291.746741)
			(xy 237.633134 -291.787934) (xy 237.591941 -291.823629) (xy 237.546086 -291.853098) (xy 237.496505 -291.875741)
			(xy 237.444206 -291.891097) (xy 237.390254 -291.898854) (xy 237.363 -291.89934) (xy 237.335629 -291.898889)
			(xy 237.281449 -291.891069) (xy 237.228945 -291.875578) (xy 237.179198 -291.852732) (xy 237.133233 -291.823004)
			(xy 237.112302 -291.80536) (xy 237.112048 -291.805106) (xy 237.104951 -291.799534) (xy 237.088042 -291.793278)
			(xy 237.079028 -291.792914) (xy 237.011972 -291.792914) (xy 237.002953 -291.793255) (xy 236.986036 -291.799513)
			(xy 236.978952 -291.805106) (xy 236.978952 -291.80536) (xy 236.978698 -291.80536) (xy 236.957772 -291.823007)
			(xy 236.911798 -291.852719) (xy 236.862049 -291.875554) (xy 236.809547 -291.891043) (xy 236.75537 -291.898868)
			(xy 236.728 -291.89934) (xy 236.700751 -291.89879) (xy 236.646808 -291.891034) (xy 236.594518 -291.87568)
			(xy 236.544945 -291.853041) (xy 236.499098 -291.823577) (xy 236.457911 -291.787889) (xy 236.422223 -291.746702)
			(xy 236.392759 -291.700855) (xy 236.37012 -291.651282) (xy 236.354766 -291.598992) (xy 236.34701 -291.545049)
			(xy 234.087924 -291.545049) (xy 234.087924 -297.831256) (xy 258.01142 -297.831256) (xy 258.015491 -297.775634)
			(xy 258.027617 -297.721197) (xy 258.04754 -297.669106) (xy 258.074836 -297.620471) (xy 258.108922 -297.576328)
			(xy 258.149071 -297.537619) (xy 258.194429 -297.505168) (xy 258.244029 -297.479667) (xy 258.296813 -297.46166)
			(xy 258.351656 -297.45153) (xy 258.40739 -297.449493) (xy 258.462827 -297.455593) (xy 258.516784 -297.469699)
			(xy 258.568113 -297.491511) (xy 258.615719 -297.520565) (xy 258.658587 -297.55624) (xy 258.695804 -297.597777)
			(xy 258.726577 -297.64429) (xy 258.750249 -297.694787) (xy 258.766317 -297.748194) (xy 258.774437 -297.80337)
			(xy 258.774946 -297.831256) (xy 258.774437 -297.859142) (xy 258.766317 -297.914318) (xy 258.750249 -297.967725)
			(xy 258.726577 -298.018222) (xy 258.695804 -298.064735) (xy 258.658587 -298.106272) (xy 258.615719 -298.141947)
			(xy 258.568113 -298.171001) (xy 258.516784 -298.192813) (xy 258.462827 -298.206919) (xy 258.40739 -298.213019)
			(xy 258.351656 -298.210982) (xy 258.296813 -298.200852) (xy 258.244029 -298.182845) (xy 258.194429 -298.157344)
			(xy 258.149071 -298.124893) (xy 258.108922 -298.086184) (xy 258.074836 -298.042041) (xy 258.04754 -297.993406)
			(xy 258.027617 -297.941315) (xy 258.015491 -297.886878) (xy 258.01142 -297.831256) (xy 234.087924 -297.831256)
			(xy 234.087924 -298.30903) (xy 259.50113 -298.30903) (xy 259.505201 -298.253408) (xy 259.517327 -298.198971)
			(xy 259.53725 -298.14688) (xy 259.564546 -298.098245) (xy 259.598632 -298.054102) (xy 259.638781 -298.015393)
			(xy 259.684139 -297.982942) (xy 259.733739 -297.957441) (xy 259.786523 -297.939434) (xy 259.841366 -297.929304)
			(xy 259.8971 -297.927267) (xy 259.952537 -297.933367) (xy 260.006494 -297.947473) (xy 260.057823 -297.969285)
			(xy 260.105429 -297.998339) (xy 260.148297 -298.034014) (xy 260.185514 -298.075551) (xy 260.216287 -298.122064)
			(xy 260.239959 -298.172561) (xy 260.256027 -298.225968) (xy 260.264147 -298.281144) (xy 260.264656 -298.30903)
			(xy 260.264147 -298.336916) (xy 260.256027 -298.392092) (xy 260.239959 -298.445499) (xy 260.216287 -298.495996)
			(xy 260.185514 -298.542509) (xy 260.148297 -298.584046) (xy 260.105429 -298.619721) (xy 260.057823 -298.648775)
			(xy 260.006494 -298.670587) (xy 259.952537 -298.684693) (xy 259.8971 -298.690793) (xy 259.841366 -298.688756)
			(xy 259.786523 -298.678626) (xy 259.733739 -298.660619) (xy 259.684139 -298.635118) (xy 259.638781 -298.602667)
			(xy 259.598632 -298.563958) (xy 259.564546 -298.519815) (xy 259.53725 -298.47118) (xy 259.517327 -298.419089)
			(xy 259.505201 -298.364652) (xy 259.50113 -298.30903) (xy 234.087924 -298.30903) (xy 234.087924 -301.031656)
			(xy 258.01142 -301.031656) (xy 258.015491 -300.976034) (xy 258.027617 -300.921597) (xy 258.04754 -300.869506)
			(xy 258.074836 -300.820871) (xy 258.108922 -300.776728) (xy 258.149071 -300.738019) (xy 258.194429 -300.705568)
			(xy 258.244029 -300.680067) (xy 258.296813 -300.66206) (xy 258.351656 -300.65193) (xy 258.40739 -300.649893)
			(xy 258.462827 -300.655993) (xy 258.516784 -300.670099) (xy 258.568113 -300.691911) (xy 258.615719 -300.720965)
			(xy 258.658587 -300.75664) (xy 258.695804 -300.798177) (xy 258.726577 -300.84469) (xy 258.750249 -300.895187)
			(xy 258.766317 -300.948594) (xy 258.767028 -300.953424) (xy 259.495288 -300.953424) (xy 259.499359 -300.897802)
			(xy 259.511485 -300.843365) (xy 259.531408 -300.791274) (xy 259.558704 -300.742639) (xy 259.59279 -300.698496)
			(xy 259.632939 -300.659787) (xy 259.678297 -300.627336) (xy 259.727897 -300.601835) (xy 259.780681 -300.583828)
			(xy 259.835524 -300.573698) (xy 259.891258 -300.571661) (xy 259.946695 -300.577761) (xy 260.000652 -300.591867)
			(xy 260.051981 -300.613679) (xy 260.099587 -300.642733) (xy 260.142455 -300.678408) (xy 260.179672 -300.719945)
			(xy 260.210445 -300.766458) (xy 260.234117 -300.816955) (xy 260.250185 -300.870362) (xy 260.258305 -300.925538)
			(xy 260.258814 -300.953424) (xy 260.258305 -300.98131) (xy 260.250185 -301.036486) (xy 260.234117 -301.089893)
			(xy 260.210445 -301.14039) (xy 260.179672 -301.186903) (xy 260.142455 -301.22844) (xy 260.099587 -301.264115)
			(xy 260.051981 -301.293169) (xy 260.000652 -301.314981) (xy 259.946695 -301.329087) (xy 259.891258 -301.335187)
			(xy 259.835524 -301.33315) (xy 259.780681 -301.32302) (xy 259.727897 -301.305013) (xy 259.678297 -301.279512)
			(xy 259.632939 -301.247061) (xy 259.59279 -301.208352) (xy 259.558704 -301.164209) (xy 259.531408 -301.115574)
			(xy 259.511485 -301.063483) (xy 259.499359 -301.009046) (xy 259.495288 -300.953424) (xy 258.767028 -300.953424)
			(xy 258.774437 -301.00377) (xy 258.774946 -301.031656) (xy 258.774437 -301.059542) (xy 258.766317 -301.114718)
			(xy 258.750249 -301.168125) (xy 258.726577 -301.218622) (xy 258.695804 -301.265135) (xy 258.658587 -301.306672)
			(xy 258.615719 -301.342347) (xy 258.568113 -301.371401) (xy 258.516784 -301.393213) (xy 258.462827 -301.407319)
			(xy 258.40739 -301.413419) (xy 258.351656 -301.411382) (xy 258.296813 -301.401252) (xy 258.244029 -301.383245)
			(xy 258.194429 -301.357744) (xy 258.149071 -301.325293) (xy 258.108922 -301.286584) (xy 258.074836 -301.242441)
			(xy 258.04754 -301.193806) (xy 258.027617 -301.141715) (xy 258.015491 -301.087278) (xy 258.01142 -301.031656)
			(xy 234.087924 -301.031656) (xy 234.087924 -306.744116) (xy 238.199674 -306.744116) (xy 238.203745 -306.688494)
			(xy 238.215871 -306.634057) (xy 238.235794 -306.581966) (xy 238.26309 -306.533331) (xy 238.297176 -306.489188)
			(xy 238.337325 -306.450479) (xy 238.382683 -306.418028) (xy 238.432283 -306.392527) (xy 238.485067 -306.37452)
			(xy 238.53991 -306.36439) (xy 238.595644 -306.362353) (xy 238.651081 -306.368453) (xy 238.705038 -306.382559)
			(xy 238.756367 -306.404371) (xy 238.803973 -306.433425) (xy 238.846841 -306.4691) (xy 238.884058 -306.510637)
			(xy 238.914831 -306.55715) (xy 238.938503 -306.607647) (xy 238.954571 -306.661054) (xy 238.962691 -306.71623)
			(xy 238.9632 -306.744116) (xy 238.962691 -306.772002) (xy 238.960478 -306.787042) (xy 245.473726 -306.787042)
			(xy 245.477797 -306.73142) (xy 245.489923 -306.676983) (xy 245.509846 -306.624892) (xy 245.537142 -306.576257)
			(xy 245.571228 -306.532114) (xy 245.611377 -306.493405) (xy 245.656735 -306.460954) (xy 245.706335 -306.435453)
			(xy 245.759119 -306.417446) (xy 245.813962 -306.407316) (xy 245.869696 -306.405279) (xy 245.925133 -306.411379)
			(xy 245.97909 -306.425485) (xy 246.030419 -306.447297) (xy 246.078025 -306.476351) (xy 246.120893 -306.512026)
			(xy 246.15811 -306.553563) (xy 246.188883 -306.600076) (xy 246.212555 -306.650573) (xy 246.228623 -306.70398)
			(xy 246.236743 -306.759156) (xy 246.237252 -306.787042) (xy 246.236743 -306.814928) (xy 246.228623 -306.870104)
			(xy 246.212555 -306.923511) (xy 246.188883 -306.974008) (xy 246.15811 -307.020521) (xy 246.120893 -307.062058)
			(xy 246.078025 -307.097733) (xy 246.030419 -307.126787) (xy 245.97909 -307.148599) (xy 245.925133 -307.162705)
			(xy 245.869696 -307.168805) (xy 245.813962 -307.166768) (xy 245.759119 -307.156638) (xy 245.706335 -307.138631)
			(xy 245.656735 -307.11313) (xy 245.611377 -307.080679) (xy 245.571228 -307.04197) (xy 245.537142 -306.997827)
			(xy 245.509846 -306.949192) (xy 245.489923 -306.897101) (xy 245.477797 -306.842664) (xy 245.473726 -306.787042)
			(xy 238.960478 -306.787042) (xy 238.954571 -306.827178) (xy 238.938503 -306.880585) (xy 238.914831 -306.931082)
			(xy 238.884058 -306.977595) (xy 238.846841 -307.019132) (xy 238.803973 -307.054807) (xy 238.756367 -307.083861)
			(xy 238.705038 -307.105673) (xy 238.651081 -307.119779) (xy 238.595644 -307.125879) (xy 238.53991 -307.123842)
			(xy 238.485067 -307.113712) (xy 238.432283 -307.095705) (xy 238.382683 -307.070204) (xy 238.337325 -307.037753)
			(xy 238.297176 -306.999044) (xy 238.26309 -306.954901) (xy 238.235794 -306.906266) (xy 238.215871 -306.854175)
			(xy 238.203745 -306.799738) (xy 238.199674 -306.744116) (xy 234.087924 -306.744116) (xy 234.087924 -307.446426)
			(xy 243.125242 -307.446426) (xy 243.129313 -307.390804) (xy 243.141439 -307.336367) (xy 243.161362 -307.284276)
			(xy 243.188658 -307.235641) (xy 243.222744 -307.191498) (xy 243.262893 -307.152789) (xy 243.308251 -307.120338)
			(xy 243.357851 -307.094837) (xy 243.410635 -307.07683) (xy 243.465478 -307.0667) (xy 243.521212 -307.064663)
			(xy 243.576649 -307.070763) (xy 243.630606 -307.084869) (xy 243.681935 -307.106681) (xy 243.729541 -307.135735)
			(xy 243.772409 -307.17141) (xy 243.809626 -307.212947) (xy 243.840399 -307.25946) (xy 243.864071 -307.309957)
			(xy 243.880139 -307.363364) (xy 243.888259 -307.41854) (xy 243.888768 -307.446426) (xy 243.888259 -307.474312)
			(xy 243.880139 -307.529488) (xy 243.864071 -307.582895) (xy 243.840399 -307.633392) (xy 243.809626 -307.679905)
			(xy 243.772409 -307.721442) (xy 243.729541 -307.757117) (xy 243.681935 -307.786171) (xy 243.630606 -307.807983)
			(xy 243.576649 -307.822089) (xy 243.521212 -307.828189) (xy 243.465478 -307.826152) (xy 243.410635 -307.816022)
			(xy 243.357851 -307.798015) (xy 243.308251 -307.772514) (xy 243.262893 -307.740063) (xy 243.222744 -307.701354)
			(xy 243.188658 -307.657211) (xy 243.161362 -307.608576) (xy 243.141439 -307.556485) (xy 243.129313 -307.502048)
			(xy 243.125242 -307.446426) (xy 234.087924 -307.446426) (xy 234.087924 -308.402228) (xy 244.183152 -308.402228)
			(xy 244.187223 -308.346606) (xy 244.199349 -308.292169) (xy 244.219272 -308.240078) (xy 244.246568 -308.191443)
			(xy 244.280654 -308.1473) (xy 244.320803 -308.108591) (xy 244.366161 -308.07614) (xy 244.415761 -308.050639)
			(xy 244.468545 -308.032632) (xy 244.523388 -308.022502) (xy 244.579122 -308.020465) (xy 244.634559 -308.026565)
			(xy 244.688516 -308.040671) (xy 244.739845 -308.062483) (xy 244.787451 -308.091537) (xy 244.830319 -308.127212)
			(xy 244.867536 -308.168749) (xy 244.898309 -308.215262) (xy 244.921981 -308.265759) (xy 244.938049 -308.319166)
			(xy 244.946169 -308.374342) (xy 244.946678 -308.402228) (xy 244.946169 -308.430114) (xy 244.938049 -308.48529)
			(xy 244.921981 -308.538697) (xy 244.898309 -308.589194) (xy 244.867536 -308.635707) (xy 244.830319 -308.677244)
			(xy 244.787451 -308.712919) (xy 244.739845 -308.741973) (xy 244.688516 -308.763785) (xy 244.634559 -308.777891)
			(xy 244.579122 -308.783991) (xy 244.523388 -308.781954) (xy 244.468545 -308.771824) (xy 244.415761 -308.753817)
			(xy 244.366161 -308.728316) (xy 244.320803 -308.695865) (xy 244.280654 -308.657156) (xy 244.246568 -308.613013)
			(xy 244.219272 -308.564378) (xy 244.199349 -308.512287) (xy 244.187223 -308.45785) (xy 244.183152 -308.402228)
			(xy 234.087924 -308.402228) (xy 234.087924 -309.018178) (xy 246.191276 -309.018178) (xy 246.195347 -308.962556)
			(xy 246.207473 -308.908119) (xy 246.227396 -308.856028) (xy 246.254692 -308.807393) (xy 246.288778 -308.76325)
			(xy 246.328927 -308.724541) (xy 246.374285 -308.69209) (xy 246.423885 -308.666589) (xy 246.476669 -308.648582)
			(xy 246.531512 -308.638452) (xy 246.587246 -308.636415) (xy 246.642683 -308.642515) (xy 246.69664 -308.656621)
			(xy 246.747969 -308.678433) (xy 246.795575 -308.707487) (xy 246.838443 -308.743162) (xy 246.87566 -308.784699)
			(xy 246.906433 -308.831212) (xy 246.930105 -308.881709) (xy 246.946173 -308.935116) (xy 246.954293 -308.990292)
			(xy 246.954802 -309.018178) (xy 246.954293 -309.046064) (xy 246.946173 -309.10124) (xy 246.930105 -309.154647)
			(xy 246.906433 -309.205144) (xy 246.87566 -309.251657) (xy 246.838443 -309.293194) (xy 246.795575 -309.328869)
			(xy 246.747969 -309.357923) (xy 246.69664 -309.379735) (xy 246.642683 -309.393841) (xy 246.587246 -309.399941)
			(xy 246.531512 -309.397904) (xy 246.476669 -309.387774) (xy 246.423885 -309.369767) (xy 246.374285 -309.344266)
			(xy 246.328927 -309.311815) (xy 246.288778 -309.273106) (xy 246.254692 -309.228963) (xy 246.227396 -309.180328)
			(xy 246.207473 -309.128237) (xy 246.195347 -309.0738) (xy 246.191276 -309.018178) (xy 234.087924 -309.018178)
			(xy 234.087924 -309.908448) (xy 242.571268 -309.908448) (xy 242.575339 -309.852826) (xy 242.587465 -309.798389)
			(xy 242.607388 -309.746298) (xy 242.634684 -309.697663) (xy 242.66877 -309.65352) (xy 242.708919 -309.614811)
			(xy 242.754277 -309.58236) (xy 242.803877 -309.556859) (xy 242.856661 -309.538852) (xy 242.911504 -309.528722)
			(xy 242.967238 -309.526685) (xy 243.022675 -309.532785) (xy 243.076632 -309.546891) (xy 243.127961 -309.568703)
			(xy 243.175567 -309.597757) (xy 243.218435 -309.633432) (xy 243.255652 -309.674969) (xy 243.286425 -309.721482)
			(xy 243.297509 -309.745126) (xy 244.286784 -309.745126) (xy 244.290855 -309.689504) (xy 244.302981 -309.635067)
			(xy 244.322904 -309.582976) (xy 244.3502 -309.534341) (xy 244.384286 -309.490198) (xy 244.424435 -309.451489)
			(xy 244.469793 -309.419038) (xy 244.519393 -309.393537) (xy 244.572177 -309.37553) (xy 244.62702 -309.3654)
			(xy 244.682754 -309.363363) (xy 244.738191 -309.369463) (xy 244.792148 -309.383569) (xy 244.843477 -309.405381)
			(xy 244.891083 -309.434435) (xy 244.933951 -309.47011) (xy 244.971168 -309.511647) (xy 245.001941 -309.55816)
			(xy 245.025613 -309.608657) (xy 245.041681 -309.662064) (xy 245.049801 -309.71724) (xy 245.05031 -309.745126)
			(xy 245.049801 -309.773012) (xy 245.041681 -309.828188) (xy 245.025613 -309.881595) (xy 245.001941 -309.932092)
			(xy 244.971168 -309.978605) (xy 244.933951 -310.020142) (xy 244.891083 -310.055817) (xy 244.843477 -310.084871)
			(xy 244.792148 -310.106683) (xy 244.738191 -310.120789) (xy 244.682754 -310.126889) (xy 244.62702 -310.124852)
			(xy 244.572177 -310.114722) (xy 244.519393 -310.096715) (xy 244.469793 -310.071214) (xy 244.424435 -310.038763)
			(xy 244.384286 -310.000054) (xy 244.3502 -309.955911) (xy 244.322904 -309.907276) (xy 244.302981 -309.855185)
			(xy 244.290855 -309.800748) (xy 244.286784 -309.745126) (xy 243.297509 -309.745126) (xy 243.310097 -309.771979)
			(xy 243.326165 -309.825386) (xy 243.334285 -309.880562) (xy 243.334794 -309.908448) (xy 243.334285 -309.936334)
			(xy 243.326165 -309.99151) (xy 243.310097 -310.044917) (xy 243.286425 -310.095414) (xy 243.255652 -310.141927)
			(xy 243.218435 -310.183464) (xy 243.196075 -310.202072) (xy 248.072908 -310.202072) (xy 248.076979 -310.14645)
			(xy 248.089105 -310.092013) (xy 248.109028 -310.039922) (xy 248.136324 -309.991287) (xy 248.17041 -309.947144)
			(xy 248.210559 -309.908435) (xy 248.255917 -309.875984) (xy 248.305517 -309.850483) (xy 248.358301 -309.832476)
			(xy 248.413144 -309.822346) (xy 248.468878 -309.820309) (xy 248.524315 -309.826409) (xy 248.578272 -309.840515)
			(xy 248.629601 -309.862327) (xy 248.677207 -309.891381) (xy 248.720075 -309.927056) (xy 248.757292 -309.968593)
			(xy 248.788065 -310.015106) (xy 248.811737 -310.065603) (xy 248.827805 -310.11901) (xy 248.835925 -310.174186)
			(xy 248.836434 -310.202072) (xy 248.835925 -310.229958) (xy 248.827805 -310.285134) (xy 248.811737 -310.338541)
			(xy 248.788065 -310.389038) (xy 248.757292 -310.435551) (xy 248.720075 -310.477088) (xy 248.677207 -310.512763)
			(xy 248.629601 -310.541817) (xy 248.578272 -310.563629) (xy 248.524315 -310.577735) (xy 248.468878 -310.583835)
			(xy 248.413144 -310.581798) (xy 248.358301 -310.571668) (xy 248.305517 -310.553661) (xy 248.255917 -310.52816)
			(xy 248.210559 -310.495709) (xy 248.17041 -310.457) (xy 248.136324 -310.412857) (xy 248.109028 -310.364222)
			(xy 248.089105 -310.312131) (xy 248.076979 -310.257694) (xy 248.072908 -310.202072) (xy 243.196075 -310.202072)
			(xy 243.175567 -310.219139) (xy 243.127961 -310.248193) (xy 243.076632 -310.270005) (xy 243.022675 -310.284111)
			(xy 242.967238 -310.290211) (xy 242.911504 -310.288174) (xy 242.856661 -310.278044) (xy 242.803877 -310.260037)
			(xy 242.754277 -310.234536) (xy 242.708919 -310.202085) (xy 242.66877 -310.163376) (xy 242.634684 -310.119233)
			(xy 242.607388 -310.070598) (xy 242.587465 -310.018507) (xy 242.575339 -309.96407) (xy 242.571268 -309.908448)
			(xy 234.087924 -309.908448) (xy 234.087924 -311.215786) (xy 243.749066 -311.215786) (xy 243.753137 -311.160164)
			(xy 243.765263 -311.105727) (xy 243.785186 -311.053636) (xy 243.812482 -311.005001) (xy 243.846568 -310.960858)
			(xy 243.886717 -310.922149) (xy 243.932075 -310.889698) (xy 243.981675 -310.864197) (xy 244.034459 -310.84619)
			(xy 244.089302 -310.83606) (xy 244.145036 -310.834023) (xy 244.200473 -310.840123) (xy 244.25443 -310.854229)
			(xy 244.305759 -310.876041) (xy 244.353365 -310.905095) (xy 244.396233 -310.94077) (xy 244.43345 -310.982307)
			(xy 244.464223 -311.02882) (xy 244.487895 -311.079317) (xy 244.503963 -311.132724) (xy 244.512083 -311.1879)
			(xy 244.512592 -311.215786) (xy 244.512083 -311.243672) (xy 244.503963 -311.298848) (xy 244.487895 -311.352255)
			(xy 244.464223 -311.402752) (xy 244.43345 -311.449265) (xy 244.396233 -311.490802) (xy 244.353365 -311.526477)
			(xy 244.305759 -311.555531) (xy 244.25443 -311.577343) (xy 244.200473 -311.591449) (xy 244.145036 -311.597549)
			(xy 244.089302 -311.595512) (xy 244.034459 -311.585382) (xy 243.981675 -311.567375) (xy 243.932075 -311.541874)
			(xy 243.886717 -311.509423) (xy 243.846568 -311.470714) (xy 243.812482 -311.426571) (xy 243.785186 -311.377936)
			(xy 243.765263 -311.325845) (xy 243.753137 -311.271408) (xy 243.749066 -311.215786) (xy 234.087924 -311.215786)
			(xy 234.087924 -320.816732) (xy 241.138202 -320.816732) (xy 241.138686 -320.789362) (xy 241.1465 -320.735184)
			(xy 241.161984 -320.682681) (xy 241.184822 -320.632934) (xy 241.214543 -320.586966) (xy 241.232182 -320.566034)
			(xy 241.232436 -320.56578) (xy 241.238041 -320.558706) (xy 241.244276 -320.541779) (xy 241.244628 -320.53276)
			(xy 241.244628 -320.465704) (xy 241.244263 -320.456688) (xy 241.23802 -320.439771) (xy 241.232436 -320.432684)
			(xy 241.232182 -320.432684) (xy 241.232182 -320.43243) (xy 241.214541 -320.4115) (xy 241.18483 -320.365526)
			(xy 241.161995 -320.315778) (xy 241.146504 -320.263277) (xy 241.138676 -320.209101) (xy 241.138202 -320.181732)
			(xy 241.138685 -320.154479) (xy 241.146438 -320.100529) (xy 241.16179 -320.048231) (xy 241.18443 -319.99865)
			(xy 241.213896 -319.952796) (xy 241.249587 -319.911603) (xy 241.290779 -319.875909) (xy 241.336631 -319.846441)
			(xy 241.38621 -319.823798) (xy 241.438507 -319.808443) (xy 241.492458 -319.800687) (xy 241.51971 -319.800224)
			(xy 241.547081 -319.800678) (xy 241.601261 -319.808498) (xy 241.653764 -319.82399) (xy 241.703511 -319.846834)
			(xy 241.749477 -319.876561) (xy 241.770408 -319.894204) (xy 241.770662 -319.894458) (xy 241.77775 -319.900042)
			(xy 241.794666 -319.906289) (xy 241.803682 -319.90665) (xy 241.870738 -319.90665) (xy 241.879758 -319.906322)
			(xy 241.896675 -319.900056) (xy 241.903758 -319.894458) (xy 241.903758 -319.894204) (xy 241.904012 -319.894204)
			(xy 241.924945 -319.876563) (xy 241.970913 -319.846839) (xy 242.020659 -319.823993) (xy 242.073161 -319.808497)
			(xy 242.127339 -319.800668) (xy 242.182081 -319.800668) (xy 242.236259 -319.808497) (xy 242.288761 -319.823993)
			(xy 242.338507 -319.846839) (xy 242.384475 -319.876563) (xy 242.405408 -319.894204) (xy 242.405662 -319.894458)
			(xy 242.41275 -319.900042) (xy 242.429666 -319.906289) (xy 242.438682 -319.90665) (xy 242.505738 -319.90665)
			(xy 242.514758 -319.906322) (xy 242.531675 -319.900056) (xy 242.538758 -319.894458) (xy 242.538758 -319.894204)
			(xy 242.539012 -319.894204) (xy 242.559967 -319.876593) (xy 242.605933 -319.846877) (xy 242.655675 -319.824036)
			(xy 242.708171 -319.808538) (xy 242.762342 -319.800702) (xy 242.78971 -319.800224) (xy 242.816965 -319.800646)
			(xy 242.870919 -319.808405) (xy 242.923219 -319.823764) (xy 242.972802 -319.84641) (xy 243.018656 -319.875882)
			(xy 243.05985 -319.91158) (xy 243.095543 -319.952777) (xy 243.12501 -319.998635) (xy 243.147651 -320.04822)
			(xy 243.163004 -320.100522) (xy 243.170757 -320.154477) (xy 243.171218 -320.181732) (xy 243.170791 -320.209104)
			(xy 243.162967 -320.263285) (xy 243.14747 -320.31579) (xy 243.124619 -320.365536) (xy 243.094884 -320.4115)
			(xy 243.077238 -320.43243) (xy 243.076984 -320.432684) (xy 243.071396 -320.43977) (xy 243.065151 -320.456687)
			(xy 243.064792 -320.465704) (xy 243.064792 -320.53276) (xy 243.06517 -320.541775) (xy 243.071403 -320.558692)
			(xy 243.076984 -320.56578) (xy 243.077238 -320.56578) (xy 243.077238 -320.566034) (xy 243.094866 -320.586975)
			(xy 243.124578 -320.632946) (xy 243.147416 -320.682691) (xy 243.16291 -320.73519) (xy 243.170742 -320.789364)
			(xy 243.171218 -320.816732) (xy 243.170752 -320.843984) (xy 243.162991 -320.897931) (xy 243.147633 -320.950226)
			(xy 243.124989 -320.999803) (xy 243.09552 -321.045652) (xy 243.059826 -321.086842) (xy 243.018635 -321.122533)
			(xy 242.972783 -321.151999) (xy 242.923205 -321.17464) (xy 242.87091 -321.189996) (xy 242.816962 -321.197754)
			(xy 242.78971 -321.19824) (xy 242.762339 -321.197783) (xy 242.708159 -321.189965) (xy 242.655655 -321.174475)
			(xy 242.605909 -321.151631) (xy 242.559943 -321.121903) (xy 242.539012 -321.10426) (xy 242.538758 -321.104006)
			(xy 242.531658 -321.098438) (xy 242.514752 -321.09218) (xy 242.505738 -321.091814) (xy 242.438682 -321.091814)
			(xy 242.429664 -321.092159) (xy 242.412747 -321.098415) (xy 242.405662 -321.104006) (xy 242.405408 -321.10426)
			(xy 242.384475 -321.121901) (xy 242.338507 -321.151625) (xy 242.288761 -321.174471) (xy 242.236259 -321.189967)
			(xy 242.182081 -321.197796) (xy 242.127339 -321.197796) (xy 242.073161 -321.189967) (xy 242.020659 -321.174471)
			(xy 241.970913 -321.151625) (xy 241.924945 -321.121901) (xy 241.904012 -321.10426) (xy 241.903758 -321.104006)
			(xy 241.896658 -321.098438) (xy 241.879752 -321.09218) (xy 241.870738 -321.091814) (xy 241.803682 -321.091814)
			(xy 241.794664 -321.092159) (xy 241.777747 -321.098415) (xy 241.770662 -321.104006) (xy 241.770662 -321.10426)
			(xy 241.770408 -321.10426) (xy 241.749479 -321.121903) (xy 241.703506 -321.151615) (xy 241.653758 -321.174451)
			(xy 241.601256 -321.189941) (xy 241.547079 -321.197767) (xy 241.51971 -321.19824) (xy 241.49246 -321.197713)
			(xy 241.438516 -321.189958) (xy 241.386224 -321.174606) (xy 241.336649 -321.151968) (xy 241.2908 -321.122506)
			(xy 241.249611 -321.086819) (xy 241.213919 -321.045634) (xy 241.184452 -320.999788) (xy 241.161809 -320.950215)
			(xy 241.146451 -320.897925) (xy 241.13869 -320.843981) (xy 241.138202 -320.816732) (xy 234.087924 -320.816732)
			(xy 234.087924 -321.555872) (xy 234.088361 -321.565936) (xy 234.096096 -321.584519) (xy 234.10291 -321.59194)
			(xy 234.399328 -321.888358) (xy 234.406726 -321.895205) (xy 234.425325 -321.902936) (xy 234.435396 -321.903344)
			(xy 239.274096 -321.903344) (xy 239.30695 -321.903804) (xy 239.372245 -321.91116) (xy 239.436306 -321.925779)
			(xy 239.498328 -321.947477) (xy 239.557531 -321.975983) (xy 239.61317 -322.010938) (xy 239.664546 -322.051901)
			(xy 239.688116 -322.074794) (xy 241.27206 -323.658738) (xy 241.295008 -323.682292) (xy 241.336031 -323.73369)
			(xy 241.371038 -323.789361) (xy 241.399587 -323.848603) (xy 241.421319 -323.910671) (xy 241.43596 -323.974782)
			(xy 241.443327 -324.040131) (xy 241.443764 -324.073012) (xy 241.443764 -328.639678) (xy 241.444305 -328.649628)
			(xy 241.451972 -328.668001) (xy 241.46602 -328.682107) (xy 241.475006 -328.686414) (xy 241.48923 -328.692256)
			(xy 241.519202 -328.686414) (xy 251.558298 -318.647318) (xy 251.565132 -318.639915) (xy 251.572836 -318.621317)
			(xy 251.573284 -318.61125) (xy 251.573284 -315.47181) (xy 251.573722 -315.439356) (xy 251.580991 -315.374856)
			(xy 251.595439 -315.311576) (xy 251.616884 -315.250313) (xy 251.645056 -315.191837) (xy 251.6796 -315.136884)
			(xy 251.720082 -315.086147) (xy 251.742702 -315.06287) (xy 260.207252 -306.598574) (xy 260.215126 -306.580286)
			(xy 260.215126 -306.57038) (xy 260.216011 -306.53854) (xy 260.223903 -306.475333) (xy 260.238697 -306.413377)
			(xy 260.260213 -306.353423) (xy 260.28819 -306.296199) (xy 260.322289 -306.242397) (xy 260.362097 -306.19267)
			(xy 260.38429 -306.169822) (xy 260.654038 -305.900074) (xy 260.678275 -305.87653) (xy 260.731315 -305.834666)
			(xy 260.788877 -305.799274) (xy 260.850174 -305.770838) (xy 260.914369 -305.749744) (xy 260.980586 -305.736283)
			(xy 261.01421 -305.732942) (xy 261.02306 -305.731843) (xy 261.039223 -305.724329) (xy 261.051826 -305.711726)
			(xy 261.059342 -305.695565) (xy 261.060438 -305.686714) (xy 261.063752 -305.653088) (xy 261.077235 -305.586875)
			(xy 261.098341 -305.522685) (xy 261.126784 -305.461391) (xy 261.162174 -305.403829) (xy 261.204031 -305.350783)
			(xy 261.22757 -305.326542) (xy 261.497318 -305.056794) (xy 261.520155 -305.034588) (xy 261.569886 -304.994783)
			(xy 261.62369 -304.960684) (xy 261.680916 -304.932706) (xy 261.740871 -304.911186) (xy 261.802827 -304.896386)
			(xy 261.866035 -304.888486) (xy 261.897876 -304.88763) (xy 261.907782 -304.88763) (xy 261.92607 -304.879756)
			(xy 262.159496 -304.64633) (xy 262.16737 -304.628042) (xy 262.16737 -304.618136) (xy 262.168252 -304.586295)
			(xy 262.176138 -304.523084) (xy 262.190926 -304.461124) (xy 262.212436 -304.401165) (xy 262.240407 -304.343934)
			(xy 262.274501 -304.290125) (xy 262.314304 -304.240391) (xy 262.336534 -304.217578) (xy 262.606282 -303.94783)
			(xy 262.629119 -303.925626) (xy 262.67885 -303.885824) (xy 262.732656 -303.851729) (xy 262.789882 -303.823755)
			(xy 262.849837 -303.80224) (xy 262.911793 -303.787446) (xy 262.975 -303.779552) (xy 263.00684 -303.778666)
			(xy 263.016746 -303.778666) (xy 263.035034 -303.770792) (xy 266.930124 -299.875448) (xy 266.953169 -299.853018)
			(xy 267.003407 -299.812867) (xy 267.057793 -299.778544) (xy 267.115655 -299.750473) (xy 267.176277 -299.729002)
			(xy 267.207492 -299.72127) (xy 267.214328 -299.719459) (xy 267.226703 -299.71263) (xy 267.231876 -299.707808)
			(xy 267.601954 -299.33773) (xy 267.610469 -299.328318) (xy 267.617801 -299.304054) (xy 267.615924 -299.291502)
			(xy 267.612725 -299.275051) (xy 267.609287 -299.241712) (xy 267.609066 -299.224954) (xy 267.609066 -299.2247)
			(xy 267.609576 -299.198712) (xy 267.617706 -299.147376) (xy 267.633767 -299.097944) (xy 267.657362 -299.051632)
			(xy 267.687911 -299.009582) (xy 267.724662 -298.972828) (xy 267.76671 -298.942276) (xy 267.81302 -298.918677)
			(xy 267.862451 -298.902612) (xy 267.913786 -298.894478) (xy 267.939774 -298.893992) (xy 267.966263 -298.894513)
			(xy 268.018563 -298.902957) (xy 268.068847 -298.919634) (xy 268.115828 -298.944115) (xy 268.158304 -298.975776)
			(xy 268.195188 -299.013805) (xy 268.210792 -299.035216) (xy 268.252448 -299.05706) (xy 268.2621 -299.05706)
			(xy 268.274289 -299.056302) (xy 268.295921 -299.045042) (xy 268.303502 -299.03547) (xy 268.31909 -299.014033)
			(xy 268.355953 -298.975953) (xy 268.398421 -298.944245) (xy 268.445406 -298.91972) (xy 268.495702 -298.903008)
			(xy 268.54802 -298.894537) (xy 268.57452 -298.893992) (xy 269.52448 -298.893992) (xy 269.549603 -298.894465)
			(xy 269.59927 -298.902073) (xy 269.647216 -298.917103) (xy 269.692338 -298.939209) (xy 269.7336 -298.967882)
			(xy 269.770052 -299.002464) (xy 269.785846 -299.022008) (xy 269.789402 -299.02658) (xy 269.797784 -299.033438)
			(xy 269.822676 -299.046392) (xy 269.828163 -299.048994) (xy 269.839973 -299.051811) (xy 269.846044 -299.05198)
			(xy 270.153384 -299.05198) (xy 270.159392 -299.051809) (xy 270.171071 -299.048977) (xy 270.176498 -299.046392)
			(xy 270.185388 -299.04182) (xy 270.197072 -299.035724) (xy 270.201634 -299.033089) (xy 270.209686 -299.026298)
			(xy 270.213074 -299.022262) (xy 270.213328 -299.022008) (xy 270.213328 -299.021754) (xy 270.22912 -299.002223)
			(xy 270.265601 -298.967703) (xy 270.306876 -298.939086) (xy 270.351998 -298.917028) (xy 270.399933 -298.902036)
			(xy 270.449582 -298.894454) (xy 270.499806 -298.894454) (xy 270.549455 -298.902036) (xy 270.59739 -298.917028)
			(xy 270.642512 -298.939086) (xy 270.683787 -298.967703) (xy 270.720268 -299.002223) (xy 270.73606 -299.021754)
			(xy 270.73606 -299.022008) (xy 270.736314 -299.022262) (xy 270.73965 -299.026348) (xy 270.747721 -299.033134)
			(xy 270.752316 -299.035724) (xy 270.763746 -299.041566) (xy 270.764254 -299.042074) (xy 270.77289 -299.046392)
			(xy 270.778318 -299.048971) (xy 270.789997 -299.051784) (xy 270.796004 -299.05198) (xy 270.864584 -299.05198)
			(xy 270.874667 -299.051562) (xy 270.893276 -299.043796) (xy 270.907425 -299.029429) (xy 270.911574 -299.02023)
			(xy 270.911574 -299.019976) (xy 270.923743 -298.990733) (xy 270.953786 -298.934969) (xy 270.971518 -298.908724)
			(xy 270.992854 -298.880022) (xy 270.999458 -298.87164) (xy 271.007332 -298.862496) (xy 271.029883 -298.837289)
			(xy 271.080116 -298.791996) (xy 271.135498 -298.753168) (xy 271.195202 -298.721383) (xy 271.258336 -298.697117)
			(xy 271.323959 -298.680732) (xy 271.391089 -298.672472) (xy 271.424908 -298.671996) (xy 271.716754 -298.671996)
			(xy 271.746489 -298.672416) (xy 271.805611 -298.678856) (xy 271.863697 -298.691614) (xy 271.892014 -298.700698)
			(xy 271.911572 -298.707302) (xy 271.948402 -298.689776) (xy 271.94891 -298.68876) (xy 271.981893 -298.680978)
			(xy 272.049139 -298.672576) (xy 272.083022 -298.671996) (xy 272.374868 -298.671996) (xy 272.40705 -298.672445)
			(xy 272.470979 -298.679917) (xy 272.533607 -298.694765) (xy 272.594086 -298.716786) (xy 272.651599 -298.745683)
			(xy 272.705365 -298.781065) (xy 272.754658 -298.822453) (xy 272.79881 -298.869285) (xy 272.837223 -298.92093)
			(xy 272.853658 -298.948602) (xy 272.871193 -298.980185) (xy 272.898823 -299.046932) (xy 272.917524 -299.116709)
			(xy 272.926979 -299.188327) (xy 272.927572 -299.224446) (xy 272.927572 -299.224954) (xy 276.819118 -299.224954)
			(xy 276.823078 -299.1759) (xy 276.834855 -299.128116) (xy 276.854146 -299.08284) (xy 276.880449 -299.041244)
			(xy 276.913084 -299.004407) (xy 276.951205 -298.973282) (xy 276.993826 -298.948675) (xy 277.039842 -298.931223)
			(xy 277.088061 -298.921379) (xy 277.137236 -298.919398) (xy 277.186091 -298.92533) (xy 277.233362 -298.939022)
			(xy 277.277824 -298.96012) (xy 277.318327 -298.988076) (xy 277.35382 -299.022168) (xy 277.383385 -299.061512)
			(xy 277.406256 -299.105089) (xy 277.42184 -299.15177) (xy 277.429735 -299.200347) (xy 277.43023 -299.224954)
			(xy 278.719038 -299.224954) (xy 278.722998 -299.1759) (xy 278.734775 -299.128116) (xy 278.754066 -299.08284)
			(xy 278.780369 -299.041244) (xy 278.813004 -299.004407) (xy 278.851125 -298.973282) (xy 278.893746 -298.948675)
			(xy 278.939762 -298.931223) (xy 278.987981 -298.921379) (xy 279.037156 -298.919398) (xy 279.086011 -298.92533)
			(xy 279.133282 -298.939022) (xy 279.177744 -298.96012) (xy 279.218247 -298.988076) (xy 279.25374 -299.022168)
			(xy 279.283305 -299.061512) (xy 279.306176 -299.105089) (xy 279.32176 -299.15177) (xy 279.329655 -299.200347)
			(xy 279.33015 -299.224954) (xy 280.618958 -299.224954) (xy 280.622918 -299.1759) (xy 280.634695 -299.128116)
			(xy 280.653986 -299.08284) (xy 280.680289 -299.041244) (xy 280.712924 -299.004407) (xy 280.751045 -298.973282)
			(xy 280.793666 -298.948675) (xy 280.839682 -298.931223) (xy 280.887901 -298.921379) (xy 280.937076 -298.919398)
			(xy 280.985931 -298.92533) (xy 281.033202 -298.939022) (xy 281.077664 -298.96012) (xy 281.118167 -298.988076)
			(xy 281.15366 -299.022168) (xy 281.183225 -299.061512) (xy 281.206096 -299.105089) (xy 281.22168 -299.15177)
			(xy 281.229575 -299.200347) (xy 281.23007 -299.224954) (xy 282.519132 -299.224954) (xy 282.523092 -299.1759)
			(xy 282.534869 -299.128116) (xy 282.55416 -299.08284) (xy 282.580463 -299.041244) (xy 282.613098 -299.004407)
			(xy 282.651219 -298.973282) (xy 282.69384 -298.948675) (xy 282.739856 -298.931223) (xy 282.788075 -298.921379)
			(xy 282.83725 -298.919398) (xy 282.886105 -298.92533) (xy 282.933376 -298.939022) (xy 282.977838 -298.96012)
			(xy 283.018341 -298.988076) (xy 283.053834 -299.022168) (xy 283.083399 -299.061512) (xy 283.10627 -299.105089)
			(xy 283.121854 -299.15177) (xy 283.129749 -299.200347) (xy 283.130244 -299.224954) (xy 283.469092 -299.224954)
			(xy 283.473052 -299.1759) (xy 283.484829 -299.128116) (xy 283.50412 -299.08284) (xy 283.530423 -299.041244)
			(xy 283.563058 -299.004407) (xy 283.601179 -298.973282) (xy 283.6438 -298.948675) (xy 283.689816 -298.931223)
			(xy 283.738035 -298.921379) (xy 283.78721 -298.919398) (xy 283.836065 -298.92533) (xy 283.883336 -298.939022)
			(xy 283.927798 -298.96012) (xy 283.968301 -298.988076) (xy 284.003794 -299.022168) (xy 284.033359 -299.061512)
			(xy 284.05623 -299.105089) (xy 284.071814 -299.15177) (xy 284.079709 -299.200347) (xy 284.080204 -299.224954)
			(xy 284.419052 -299.224954) (xy 284.423012 -299.1759) (xy 284.434789 -299.128116) (xy 284.45408 -299.08284)
			(xy 284.480383 -299.041244) (xy 284.513018 -299.004407) (xy 284.551139 -298.973282) (xy 284.59376 -298.948675)
			(xy 284.639776 -298.931223) (xy 284.687995 -298.921379) (xy 284.73717 -298.919398) (xy 284.786025 -298.92533)
			(xy 284.833296 -298.939022) (xy 284.877758 -298.96012) (xy 284.918261 -298.988076) (xy 284.953754 -299.022168)
			(xy 284.983319 -299.061512) (xy 285.00619 -299.105089) (xy 285.021774 -299.15177) (xy 285.029669 -299.200347)
			(xy 285.030164 -299.224954) (xy 285.369012 -299.224954) (xy 285.372972 -299.1759) (xy 285.384749 -299.128116)
			(xy 285.40404 -299.08284) (xy 285.430343 -299.041244) (xy 285.462978 -299.004407) (xy 285.501099 -298.973282)
			(xy 285.54372 -298.948675) (xy 285.589736 -298.931223) (xy 285.637955 -298.921379) (xy 285.68713 -298.919398)
			(xy 285.735985 -298.92533) (xy 285.783256 -298.939022) (xy 285.827718 -298.96012) (xy 285.868221 -298.988076)
			(xy 285.903714 -299.022168) (xy 285.933279 -299.061512) (xy 285.95615 -299.105089) (xy 285.971734 -299.15177)
			(xy 285.979629 -299.200347) (xy 285.980124 -299.224954) (xy 286.318972 -299.224954) (xy 286.322932 -299.1759)
			(xy 286.334709 -299.128116) (xy 286.354 -299.08284) (xy 286.380303 -299.041244) (xy 286.412938 -299.004407)
			(xy 286.451059 -298.973282) (xy 286.49368 -298.948675) (xy 286.539696 -298.931223) (xy 286.587915 -298.921379)
			(xy 286.63709 -298.919398) (xy 286.685945 -298.92533) (xy 286.733216 -298.939022) (xy 286.777678 -298.96012)
			(xy 286.818181 -298.988076) (xy 286.853674 -299.022168) (xy 286.883239 -299.061512) (xy 286.90611 -299.105089)
			(xy 286.921694 -299.15177) (xy 286.929589 -299.200347) (xy 286.930084 -299.224954) (xy 287.268932 -299.224954)
			(xy 287.272892 -299.1759) (xy 287.284669 -299.128116) (xy 287.30396 -299.08284) (xy 287.330263 -299.041244)
			(xy 287.362898 -299.004407) (xy 287.401019 -298.973282) (xy 287.44364 -298.948675) (xy 287.489656 -298.931223)
			(xy 287.537875 -298.921379) (xy 287.58705 -298.919398) (xy 287.635905 -298.92533) (xy 287.683176 -298.939022)
			(xy 287.727638 -298.96012) (xy 287.768141 -298.988076) (xy 287.803634 -299.022168) (xy 287.833199 -299.061512)
			(xy 287.85607 -299.105089) (xy 287.871654 -299.15177) (xy 287.879549 -299.200347) (xy 287.880044 -299.224954)
			(xy 288.218892 -299.224954) (xy 288.222852 -299.1759) (xy 288.234629 -299.128116) (xy 288.25392 -299.08284)
			(xy 288.280223 -299.041244) (xy 288.312858 -299.004407) (xy 288.350979 -298.973282) (xy 288.3936 -298.948675)
			(xy 288.439616 -298.931223) (xy 288.487835 -298.921379) (xy 288.53701 -298.919398) (xy 288.585865 -298.92533)
			(xy 288.633136 -298.939022) (xy 288.677598 -298.96012) (xy 288.718101 -298.988076) (xy 288.753594 -299.022168)
			(xy 288.783159 -299.061512) (xy 288.80603 -299.105089) (xy 288.821614 -299.15177) (xy 288.829509 -299.200347)
			(xy 288.830004 -299.224954) (xy 289.169106 -299.224954) (xy 289.173066 -299.1759) (xy 289.184843 -299.128116)
			(xy 289.204134 -299.08284) (xy 289.230437 -299.041244) (xy 289.263072 -299.004407) (xy 289.301193 -298.973282)
			(xy 289.343814 -298.948675) (xy 289.38983 -298.931223) (xy 289.438049 -298.921379) (xy 289.487224 -298.919398)
			(xy 289.536079 -298.92533) (xy 289.58335 -298.939022) (xy 289.627812 -298.96012) (xy 289.668315 -298.988076)
			(xy 289.703808 -299.022168) (xy 289.733373 -299.061512) (xy 289.756244 -299.105089) (xy 289.771828 -299.15177)
			(xy 289.779723 -299.200347) (xy 289.780218 -299.224954) (xy 289.779723 -299.249561) (xy 289.771828 -299.298138)
			(xy 289.756244 -299.344819) (xy 289.733373 -299.388396) (xy 289.703808 -299.42774) (xy 289.668315 -299.461832)
			(xy 289.627812 -299.489788) (xy 289.58335 -299.510886) (xy 289.536079 -299.524578) (xy 289.487224 -299.53051)
			(xy 289.438049 -299.528529) (xy 289.38983 -299.518685) (xy 289.343814 -299.501233) (xy 289.301193 -299.476626)
			(xy 289.263072 -299.445501) (xy 289.230437 -299.408664) (xy 289.204134 -299.367068) (xy 289.184843 -299.321792)
			(xy 289.173066 -299.274008) (xy 289.169106 -299.224954) (xy 288.830004 -299.224954) (xy 288.829509 -299.249561)
			(xy 288.821614 -299.298138) (xy 288.80603 -299.344819) (xy 288.783159 -299.388396) (xy 288.753594 -299.42774)
			(xy 288.718101 -299.461832) (xy 288.677598 -299.489788) (xy 288.633136 -299.510886) (xy 288.585865 -299.524578)
			(xy 288.53701 -299.53051) (xy 288.487835 -299.528529) (xy 288.439616 -299.518685) (xy 288.3936 -299.501233)
			(xy 288.350979 -299.476626) (xy 288.312858 -299.445501) (xy 288.280223 -299.408664) (xy 288.25392 -299.367068)
			(xy 288.234629 -299.321792) (xy 288.222852 -299.274008) (xy 288.218892 -299.224954) (xy 287.880044 -299.224954)
			(xy 287.879549 -299.249561) (xy 287.871654 -299.298138) (xy 287.85607 -299.344819) (xy 287.833199 -299.388396)
			(xy 287.803634 -299.42774) (xy 287.768141 -299.461832) (xy 287.727638 -299.489788) (xy 287.683176 -299.510886)
			(xy 287.635905 -299.524578) (xy 287.58705 -299.53051) (xy 287.537875 -299.528529) (xy 287.489656 -299.518685)
			(xy 287.44364 -299.501233) (xy 287.401019 -299.476626) (xy 287.362898 -299.445501) (xy 287.330263 -299.408664)
			(xy 287.30396 -299.367068) (xy 287.284669 -299.321792) (xy 287.272892 -299.274008) (xy 287.268932 -299.224954)
			(xy 286.930084 -299.224954) (xy 286.929589 -299.249561) (xy 286.921694 -299.298138) (xy 286.90611 -299.344819)
			(xy 286.883239 -299.388396) (xy 286.853674 -299.42774) (xy 286.818181 -299.461832) (xy 286.777678 -299.489788)
			(xy 286.733216 -299.510886) (xy 286.685945 -299.524578) (xy 286.63709 -299.53051) (xy 286.587915 -299.528529)
			(xy 286.539696 -299.518685) (xy 286.49368 -299.501233) (xy 286.451059 -299.476626) (xy 286.412938 -299.445501)
			(xy 286.380303 -299.408664) (xy 286.354 -299.367068) (xy 286.334709 -299.321792) (xy 286.322932 -299.274008)
			(xy 286.318972 -299.224954) (xy 285.980124 -299.224954) (xy 285.979629 -299.249561) (xy 285.971734 -299.298138)
			(xy 285.95615 -299.344819) (xy 285.933279 -299.388396) (xy 285.903714 -299.42774) (xy 285.868221 -299.461832)
			(xy 285.827718 -299.489788) (xy 285.783256 -299.510886) (xy 285.735985 -299.524578) (xy 285.68713 -299.53051)
			(xy 285.637955 -299.528529) (xy 285.589736 -299.518685) (xy 285.54372 -299.501233) (xy 285.501099 -299.476626)
			(xy 285.462978 -299.445501) (xy 285.430343 -299.408664) (xy 285.40404 -299.367068) (xy 285.384749 -299.321792)
			(xy 285.372972 -299.274008) (xy 285.369012 -299.224954) (xy 285.030164 -299.224954) (xy 285.029669 -299.249561)
			(xy 285.021774 -299.298138) (xy 285.00619 -299.344819) (xy 284.983319 -299.388396) (xy 284.953754 -299.42774)
			(xy 284.918261 -299.461832) (xy 284.877758 -299.489788) (xy 284.833296 -299.510886) (xy 284.786025 -299.524578)
			(xy 284.73717 -299.53051) (xy 284.687995 -299.528529) (xy 284.639776 -299.518685) (xy 284.59376 -299.501233)
			(xy 284.551139 -299.476626) (xy 284.513018 -299.445501) (xy 284.480383 -299.408664) (xy 284.45408 -299.367068)
			(xy 284.434789 -299.321792) (xy 284.423012 -299.274008) (xy 284.419052 -299.224954) (xy 284.080204 -299.224954)
			(xy 284.079709 -299.249561) (xy 284.071814 -299.298138) (xy 284.05623 -299.344819) (xy 284.033359 -299.388396)
			(xy 284.003794 -299.42774) (xy 283.968301 -299.461832) (xy 283.927798 -299.489788) (xy 283.883336 -299.510886)
			(xy 283.836065 -299.524578) (xy 283.78721 -299.53051) (xy 283.738035 -299.528529) (xy 283.689816 -299.518685)
			(xy 283.6438 -299.501233) (xy 283.601179 -299.476626) (xy 283.563058 -299.445501) (xy 283.530423 -299.408664)
			(xy 283.50412 -299.367068) (xy 283.484829 -299.321792) (xy 283.473052 -299.274008) (xy 283.469092 -299.224954)
			(xy 283.130244 -299.224954) (xy 283.129749 -299.249561) (xy 283.121854 -299.298138) (xy 283.10627 -299.344819)
			(xy 283.083399 -299.388396) (xy 283.053834 -299.42774) (xy 283.018341 -299.461832) (xy 282.977838 -299.489788)
			(xy 282.933376 -299.510886) (xy 282.886105 -299.524578) (xy 282.83725 -299.53051) (xy 282.788075 -299.528529)
			(xy 282.739856 -299.518685) (xy 282.69384 -299.501233) (xy 282.651219 -299.476626) (xy 282.613098 -299.445501)
			(xy 282.580463 -299.408664) (xy 282.55416 -299.367068) (xy 282.534869 -299.321792) (xy 282.523092 -299.274008)
			(xy 282.519132 -299.224954) (xy 281.23007 -299.224954) (xy 281.229575 -299.249561) (xy 281.22168 -299.298138)
			(xy 281.206096 -299.344819) (xy 281.183225 -299.388396) (xy 281.15366 -299.42774) (xy 281.118167 -299.461832)
			(xy 281.077664 -299.489788) (xy 281.033202 -299.510886) (xy 280.985931 -299.524578) (xy 280.937076 -299.53051)
			(xy 280.887901 -299.528529) (xy 280.839682 -299.518685) (xy 280.793666 -299.501233) (xy 280.751045 -299.476626)
			(xy 280.712924 -299.445501) (xy 280.680289 -299.408664) (xy 280.653986 -299.367068) (xy 280.634695 -299.321792)
			(xy 280.622918 -299.274008) (xy 280.618958 -299.224954) (xy 279.33015 -299.224954) (xy 279.329655 -299.249561)
			(xy 279.32176 -299.298138) (xy 279.306176 -299.344819) (xy 279.283305 -299.388396) (xy 279.25374 -299.42774)
			(xy 279.218247 -299.461832) (xy 279.177744 -299.489788) (xy 279.133282 -299.510886) (xy 279.086011 -299.524578)
			(xy 279.037156 -299.53051) (xy 278.987981 -299.528529) (xy 278.939762 -299.518685) (xy 278.893746 -299.501233)
			(xy 278.851125 -299.476626) (xy 278.813004 -299.445501) (xy 278.780369 -299.408664) (xy 278.754066 -299.367068)
			(xy 278.734775 -299.321792) (xy 278.722998 -299.274008) (xy 278.719038 -299.224954) (xy 277.43023 -299.224954)
			(xy 277.429735 -299.249561) (xy 277.42184 -299.298138) (xy 277.406256 -299.344819) (xy 277.383385 -299.388396)
			(xy 277.35382 -299.42774) (xy 277.318327 -299.461832) (xy 277.277824 -299.489788) (xy 277.233362 -299.510886)
			(xy 277.186091 -299.524578) (xy 277.137236 -299.53051) (xy 277.088061 -299.528529) (xy 277.039842 -299.518685)
			(xy 276.993826 -299.501233) (xy 276.951205 -299.476626) (xy 276.913084 -299.445501) (xy 276.880449 -299.408664)
			(xy 276.854146 -299.367068) (xy 276.834855 -299.321792) (xy 276.823078 -299.274008) (xy 276.819118 -299.224954)
			(xy 272.927572 -299.224954) (xy 272.927095 -299.257966) (xy 272.919237 -299.323522) (xy 272.903627 -299.387675)
			(xy 272.880487 -299.449512) (xy 272.850148 -299.508154) (xy 272.81304 -299.562764) (xy 272.769692 -299.612566)
			(xy 272.720722 -299.656851) (xy 272.666825 -299.694989) (xy 272.60877 -299.726436) (xy 272.547383 -299.750744)
			(xy 272.515584 -299.759624) (xy 272.500598 -299.763434) (xy 272.48358 -299.77715) (xy 272.478754 -299.786548)
			(xy 272.461256 -299.816962) (xy 272.419731 -299.873524) (xy 272.39595 -299.899324) (xy 272.386044 -299.909484)
			(xy 272.120614 -300.174914) (xy 276.819118 -300.174914) (xy 276.823078 -300.12586) (xy 276.834855 -300.078076)
			(xy 276.854146 -300.0328) (xy 276.880449 -299.991204) (xy 276.913084 -299.954367) (xy 276.951205 -299.923242)
			(xy 276.993826 -299.898635) (xy 277.039842 -299.881183) (xy 277.088061 -299.871339) (xy 277.137236 -299.869358)
			(xy 277.186091 -299.87529) (xy 277.233362 -299.888982) (xy 277.277824 -299.91008) (xy 277.318327 -299.938036)
			(xy 277.35382 -299.972128) (xy 277.383385 -300.011472) (xy 277.406256 -300.055049) (xy 277.42184 -300.10173)
			(xy 277.429735 -300.150307) (xy 277.43023 -300.174914) (xy 279.668998 -300.174914) (xy 279.672958 -300.12586)
			(xy 279.684735 -300.078076) (xy 279.704026 -300.0328) (xy 279.730329 -299.991204) (xy 279.762964 -299.954367)
			(xy 279.801085 -299.923242) (xy 279.843706 -299.898635) (xy 279.889722 -299.881183) (xy 279.937941 -299.871339)
			(xy 279.987116 -299.869358) (xy 280.035971 -299.87529) (xy 280.083242 -299.888982) (xy 280.127704 -299.91008)
			(xy 280.168207 -299.938036) (xy 280.2037 -299.972128) (xy 280.233265 -300.011472) (xy 280.256136 -300.055049)
			(xy 280.27172 -300.10173) (xy 280.279615 -300.150307) (xy 280.28011 -300.174914) (xy 281.568918 -300.174914)
			(xy 281.572878 -300.12586) (xy 281.584655 -300.078076) (xy 281.603946 -300.0328) (xy 281.630249 -299.991204)
			(xy 281.662884 -299.954367) (xy 281.701005 -299.923242) (xy 281.743626 -299.898635) (xy 281.789642 -299.881183)
			(xy 281.837861 -299.871339) (xy 281.887036 -299.869358) (xy 281.935891 -299.87529) (xy 281.983162 -299.888982)
			(xy 282.027624 -299.91008) (xy 282.068127 -299.938036) (xy 282.10362 -299.972128) (xy 282.133185 -300.011472)
			(xy 282.156056 -300.055049) (xy 282.17164 -300.10173) (xy 282.179535 -300.150307) (xy 282.18003 -300.174914)
			(xy 282.179535 -300.199521) (xy 282.17164 -300.248098) (xy 282.156056 -300.294779) (xy 282.133185 -300.338356)
			(xy 282.10362 -300.3777) (xy 282.068127 -300.411792) (xy 282.027624 -300.439748) (xy 281.983162 -300.460846)
			(xy 281.935891 -300.474538) (xy 281.887036 -300.48047) (xy 281.837861 -300.478489) (xy 281.789642 -300.468645)
			(xy 281.743626 -300.451193) (xy 281.701005 -300.426586) (xy 281.662884 -300.395461) (xy 281.630249 -300.358624)
			(xy 281.603946 -300.317028) (xy 281.584655 -300.271752) (xy 281.572878 -300.223968) (xy 281.568918 -300.174914)
			(xy 280.28011 -300.174914) (xy 280.279615 -300.199521) (xy 280.27172 -300.248098) (xy 280.256136 -300.294779)
			(xy 280.233265 -300.338356) (xy 280.2037 -300.3777) (xy 280.168207 -300.411792) (xy 280.127704 -300.439748)
			(xy 280.083242 -300.460846) (xy 280.035971 -300.474538) (xy 279.987116 -300.48047) (xy 279.937941 -300.478489)
			(xy 279.889722 -300.468645) (xy 279.843706 -300.451193) (xy 279.801085 -300.426586) (xy 279.762964 -300.395461)
			(xy 279.730329 -300.358624) (xy 279.704026 -300.317028) (xy 279.684735 -300.271752) (xy 279.672958 -300.223968)
			(xy 279.668998 -300.174914) (xy 277.43023 -300.174914) (xy 277.429735 -300.199521) (xy 277.42184 -300.248098)
			(xy 277.406256 -300.294779) (xy 277.383385 -300.338356) (xy 277.35382 -300.3777) (xy 277.318327 -300.411792)
			(xy 277.277824 -300.439748) (xy 277.233362 -300.460846) (xy 277.186091 -300.474538) (xy 277.137236 -300.48047)
			(xy 277.088061 -300.478489) (xy 277.039842 -300.468645) (xy 276.993826 -300.451193) (xy 276.951205 -300.426586)
			(xy 276.913084 -300.395461) (xy 276.880449 -300.358624) (xy 276.854146 -300.317028) (xy 276.834855 -300.271752)
			(xy 276.823078 -300.223968) (xy 276.819118 -300.174914) (xy 272.120614 -300.174914) (xy 272.104358 -300.19117)
			(xy 272.082107 -300.212783) (xy 272.03359 -300.251438) (xy 271.981051 -300.284421) (xy 271.925152 -300.311317)
			(xy 271.866594 -300.331789) (xy 271.806113 -300.34558) (xy 271.744469 -300.352517) (xy 271.713452 -300.352968)
			(xy 271.703546 -300.352968) (xy 271.688919 -300.374919) (xy 271.653837 -300.414307) (xy 271.61295 -300.44763)
			(xy 271.567293 -300.474043) (xy 271.518025 -300.492878) (xy 271.466391 -300.503657) (xy 271.413702 -300.506108)
			(xy 271.361291 -300.500168) (xy 271.310487 -300.485987) (xy 271.262576 -300.463925) (xy 271.218773 -300.434541)
			(xy 271.180186 -300.39858) (xy 271.163542 -300.378114) (xy 271.163542 -300.37786) (xy 271.163288 -300.377606)
			(xy 271.159956 -300.373516) (xy 271.151889 -300.366721) (xy 271.147286 -300.364144) (xy 271.13738 -300.359064)
			(xy 271.131809 -300.35627) (xy 271.119733 -300.3532) (xy 271.113504 -300.352968) (xy 270.786098 -300.352968)
			(xy 270.779865 -300.353173) (xy 270.767783 -300.356243) (xy 270.762222 -300.359064) (xy 270.752316 -300.364144)
			(xy 270.747748 -300.366772) (xy 270.739682 -300.373552) (xy 270.736314 -300.377606) (xy 270.73606 -300.37786)
			(xy 270.73606 -300.378114) (xy 270.720268 -300.397645) (xy 270.683787 -300.432165) (xy 270.642512 -300.460782)
			(xy 270.59739 -300.48284) (xy 270.549455 -300.497832) (xy 270.499806 -300.505414) (xy 270.449582 -300.505414)
			(xy 270.399933 -300.497832) (xy 270.351998 -300.48284) (xy 270.306876 -300.460782) (xy 270.265601 -300.432165)
			(xy 270.22912 -300.397645) (xy 270.213328 -300.378114) (xy 270.213328 -300.37786) (xy 270.213074 -300.377606)
			(xy 270.209741 -300.373517) (xy 270.201673 -300.366724) (xy 270.197072 -300.364144) (xy 270.187166 -300.359064)
			(xy 270.181597 -300.35626) (xy 270.169521 -300.35317) (xy 270.16329 -300.352968) (xy 269.835884 -300.352968)
			(xy 269.829652 -300.353175) (xy 269.817571 -300.356248) (xy 269.812008 -300.359064) (xy 269.802102 -300.364144)
			(xy 269.797535 -300.366773) (xy 269.78947 -300.373555) (xy 269.7861 -300.377606) (xy 269.785846 -300.37786)
			(xy 269.785846 -300.378114) (xy 269.768575 -300.399404) (xy 269.728217 -300.436502) (xy 269.682303 -300.46645)
			(xy 269.632085 -300.488431) (xy 269.578932 -300.501843) (xy 269.551658 -300.504606) (xy 269.52448 -300.505622)
			(xy 269.498901 -300.505143) (xy 269.448352 -300.497267) (xy 269.399617 -300.481706) (xy 269.353858 -300.458829)
			(xy 269.312164 -300.429183) (xy 269.27553 -300.393474) (xy 269.259812 -300.373288) (xy 269.219172 -300.352968)
			(xy 268.440916 -300.352968) (xy 268.430866 -300.353474) (xy 268.412306 -300.361196) (xy 268.404848 -300.367954)
			(xy 268.281912 -300.49089) (xy 268.280896 -300.491906) (xy 268.267688 -300.505622) (xy 268.149578 -300.623732)
			(xy 268.144761 -300.628908) (xy 268.137925 -300.641281) (xy 268.136116 -300.648116) (xy 268.128421 -300.679472)
			(xy 268.106977 -300.740374) (xy 268.078876 -300.798505) (xy 268.044468 -300.85314) (xy 268.004184 -300.903598)
			(xy 267.981684 -300.926754) (xy 267.783555 -301.124874) (xy 278.719038 -301.124874) (xy 278.722998 -301.07582)
			(xy 278.734775 -301.028036) (xy 278.754066 -300.98276) (xy 278.780369 -300.941164) (xy 278.813004 -300.904327)
			(xy 278.851125 -300.873202) (xy 278.893746 -300.848595) (xy 278.939762 -300.831143) (xy 278.987981 -300.821299)
			(xy 279.037156 -300.819318) (xy 279.086011 -300.82525) (xy 279.133282 -300.838942) (xy 279.177744 -300.86004)
			(xy 279.218247 -300.887996) (xy 279.25374 -300.922088) (xy 279.283305 -300.961432) (xy 279.306176 -301.005009)
			(xy 279.32176 -301.05169) (xy 279.329655 -301.100267) (xy 279.33015 -301.124874) (xy 280.618958 -301.124874)
			(xy 280.622918 -301.07582) (xy 280.634695 -301.028036) (xy 280.653986 -300.98276) (xy 280.680289 -300.941164)
			(xy 280.712924 -300.904327) (xy 280.751045 -300.873202) (xy 280.793666 -300.848595) (xy 280.839682 -300.831143)
			(xy 280.887901 -300.821299) (xy 280.937076 -300.819318) (xy 280.985931 -300.82525) (xy 281.033202 -300.838942)
			(xy 281.077664 -300.86004) (xy 281.118167 -300.887996) (xy 281.15366 -300.922088) (xy 281.183225 -300.961432)
			(xy 281.206096 -301.005009) (xy 281.22168 -301.05169) (xy 281.229575 -301.100267) (xy 281.23007 -301.124874)
			(xy 282.519132 -301.124874) (xy 282.523092 -301.07582) (xy 282.534869 -301.028036) (xy 282.55416 -300.98276)
			(xy 282.580463 -300.941164) (xy 282.613098 -300.904327) (xy 282.651219 -300.873202) (xy 282.69384 -300.848595)
			(xy 282.739856 -300.831143) (xy 282.788075 -300.821299) (xy 282.83725 -300.819318) (xy 282.886105 -300.82525)
			(xy 282.933376 -300.838942) (xy 282.977838 -300.86004) (xy 283.018341 -300.887996) (xy 283.053834 -300.922088)
			(xy 283.083399 -300.961432) (xy 283.10627 -301.005009) (xy 283.121854 -301.05169) (xy 283.129749 -301.100267)
			(xy 283.130244 -301.124874) (xy 283.469092 -301.124874) (xy 283.473052 -301.07582) (xy 283.484829 -301.028036)
			(xy 283.50412 -300.98276) (xy 283.530423 -300.941164) (xy 283.563058 -300.904327) (xy 283.601179 -300.873202)
			(xy 283.6438 -300.848595) (xy 283.689816 -300.831143) (xy 283.738035 -300.821299) (xy 283.78721 -300.819318)
			(xy 283.836065 -300.82525) (xy 283.883336 -300.838942) (xy 283.927798 -300.86004) (xy 283.968301 -300.887996)
			(xy 284.003794 -300.922088) (xy 284.033359 -300.961432) (xy 284.05623 -301.005009) (xy 284.071814 -301.05169)
			(xy 284.079709 -301.100267) (xy 284.080204 -301.124874) (xy 284.419052 -301.124874) (xy 284.423012 -301.07582)
			(xy 284.434789 -301.028036) (xy 284.45408 -300.98276) (xy 284.480383 -300.941164) (xy 284.513018 -300.904327)
			(xy 284.551139 -300.873202) (xy 284.59376 -300.848595) (xy 284.639776 -300.831143) (xy 284.687995 -300.821299)
			(xy 284.73717 -300.819318) (xy 284.786025 -300.82525) (xy 284.833296 -300.838942) (xy 284.877758 -300.86004)
			(xy 284.918261 -300.887996) (xy 284.953754 -300.922088) (xy 284.983319 -300.961432) (xy 285.00619 -301.005009)
			(xy 285.021774 -301.05169) (xy 285.029669 -301.100267) (xy 285.030164 -301.124874) (xy 285.369012 -301.124874)
			(xy 285.372972 -301.07582) (xy 285.384749 -301.028036) (xy 285.40404 -300.98276) (xy 285.430343 -300.941164)
			(xy 285.462978 -300.904327) (xy 285.501099 -300.873202) (xy 285.54372 -300.848595) (xy 285.589736 -300.831143)
			(xy 285.637955 -300.821299) (xy 285.68713 -300.819318) (xy 285.735985 -300.82525) (xy 285.783256 -300.838942)
			(xy 285.827718 -300.86004) (xy 285.868221 -300.887996) (xy 285.903714 -300.922088) (xy 285.933279 -300.961432)
			(xy 285.95615 -301.005009) (xy 285.971734 -301.05169) (xy 285.979629 -301.100267) (xy 285.980124 -301.124874)
			(xy 286.318972 -301.124874) (xy 286.322932 -301.07582) (xy 286.334709 -301.028036) (xy 286.354 -300.98276)
			(xy 286.380303 -300.941164) (xy 286.412938 -300.904327) (xy 286.451059 -300.873202) (xy 286.49368 -300.848595)
			(xy 286.539696 -300.831143) (xy 286.587915 -300.821299) (xy 286.63709 -300.819318) (xy 286.685945 -300.82525)
			(xy 286.733216 -300.838942) (xy 286.777678 -300.86004) (xy 286.818181 -300.887996) (xy 286.853674 -300.922088)
			(xy 286.883239 -300.961432) (xy 286.90611 -301.005009) (xy 286.921694 -301.05169) (xy 286.929589 -301.100267)
			(xy 286.930084 -301.124874) (xy 287.268932 -301.124874) (xy 287.272892 -301.07582) (xy 287.284669 -301.028036)
			(xy 287.30396 -300.98276) (xy 287.330263 -300.941164) (xy 287.362898 -300.904327) (xy 287.401019 -300.873202)
			(xy 287.44364 -300.848595) (xy 287.489656 -300.831143) (xy 287.537875 -300.821299) (xy 287.58705 -300.819318)
			(xy 287.635905 -300.82525) (xy 287.683176 -300.838942) (xy 287.727638 -300.86004) (xy 287.768141 -300.887996)
			(xy 287.803634 -300.922088) (xy 287.833199 -300.961432) (xy 287.85607 -301.005009) (xy 287.871654 -301.05169)
			(xy 287.879549 -301.100267) (xy 287.880044 -301.124874) (xy 288.218892 -301.124874) (xy 288.222852 -301.07582)
			(xy 288.234629 -301.028036) (xy 288.25392 -300.98276) (xy 288.280223 -300.941164) (xy 288.312858 -300.904327)
			(xy 288.350979 -300.873202) (xy 288.3936 -300.848595) (xy 288.439616 -300.831143) (xy 288.487835 -300.821299)
			(xy 288.53701 -300.819318) (xy 288.585865 -300.82525) (xy 288.633136 -300.838942) (xy 288.677598 -300.86004)
			(xy 288.718101 -300.887996) (xy 288.753594 -300.922088) (xy 288.783159 -300.961432) (xy 288.80603 -301.005009)
			(xy 288.821614 -301.05169) (xy 288.829509 -301.100267) (xy 288.830004 -301.124874) (xy 289.169106 -301.124874)
			(xy 289.173066 -301.07582) (xy 289.184843 -301.028036) (xy 289.204134 -300.98276) (xy 289.230437 -300.941164)
			(xy 289.263072 -300.904327) (xy 289.301193 -300.873202) (xy 289.343814 -300.848595) (xy 289.38983 -300.831143)
			(xy 289.438049 -300.821299) (xy 289.487224 -300.819318) (xy 289.536079 -300.82525) (xy 289.58335 -300.838942)
			(xy 289.627812 -300.86004) (xy 289.668315 -300.887996) (xy 289.703808 -300.922088) (xy 289.733373 -300.961432)
			(xy 289.756244 -301.005009) (xy 289.771828 -301.05169) (xy 289.779723 -301.100267) (xy 289.780218 -301.124874)
			(xy 289.779723 -301.149481) (xy 289.771828 -301.198058) (xy 289.756244 -301.244739) (xy 289.733373 -301.288316)
			(xy 289.703808 -301.32766) (xy 289.668315 -301.361752) (xy 289.627812 -301.389708) (xy 289.58335 -301.410806)
			(xy 289.536079 -301.424498) (xy 289.487224 -301.43043) (xy 289.438049 -301.428449) (xy 289.38983 -301.418605)
			(xy 289.343814 -301.401153) (xy 289.301193 -301.376546) (xy 289.263072 -301.345421) (xy 289.230437 -301.308584)
			(xy 289.204134 -301.266988) (xy 289.184843 -301.221712) (xy 289.173066 -301.173928) (xy 289.169106 -301.124874)
			(xy 288.830004 -301.124874) (xy 288.829509 -301.149481) (xy 288.821614 -301.198058) (xy 288.80603 -301.244739)
			(xy 288.783159 -301.288316) (xy 288.753594 -301.32766) (xy 288.718101 -301.361752) (xy 288.677598 -301.389708)
			(xy 288.633136 -301.410806) (xy 288.585865 -301.424498) (xy 288.53701 -301.43043) (xy 288.487835 -301.428449)
			(xy 288.439616 -301.418605) (xy 288.3936 -301.401153) (xy 288.350979 -301.376546) (xy 288.312858 -301.345421)
			(xy 288.280223 -301.308584) (xy 288.25392 -301.266988) (xy 288.234629 -301.221712) (xy 288.222852 -301.173928)
			(xy 288.218892 -301.124874) (xy 287.880044 -301.124874) (xy 287.879549 -301.149481) (xy 287.871654 -301.198058)
			(xy 287.85607 -301.244739) (xy 287.833199 -301.288316) (xy 287.803634 -301.32766) (xy 287.768141 -301.361752)
			(xy 287.727638 -301.389708) (xy 287.683176 -301.410806) (xy 287.635905 -301.424498) (xy 287.58705 -301.43043)
			(xy 287.537875 -301.428449) (xy 287.489656 -301.418605) (xy 287.44364 -301.401153) (xy 287.401019 -301.376546)
			(xy 287.362898 -301.345421) (xy 287.330263 -301.308584) (xy 287.30396 -301.266988) (xy 287.284669 -301.221712)
			(xy 287.272892 -301.173928) (xy 287.268932 -301.124874) (xy 286.930084 -301.124874) (xy 286.929589 -301.149481)
			(xy 286.921694 -301.198058) (xy 286.90611 -301.244739) (xy 286.883239 -301.288316) (xy 286.853674 -301.32766)
			(xy 286.818181 -301.361752) (xy 286.777678 -301.389708) (xy 286.733216 -301.410806) (xy 286.685945 -301.424498)
			(xy 286.63709 -301.43043) (xy 286.587915 -301.428449) (xy 286.539696 -301.418605) (xy 286.49368 -301.401153)
			(xy 286.451059 -301.376546) (xy 286.412938 -301.345421) (xy 286.380303 -301.308584) (xy 286.354 -301.266988)
			(xy 286.334709 -301.221712) (xy 286.322932 -301.173928) (xy 286.318972 -301.124874) (xy 285.980124 -301.124874)
			(xy 285.979629 -301.149481) (xy 285.971734 -301.198058) (xy 285.95615 -301.244739) (xy 285.933279 -301.288316)
			(xy 285.903714 -301.32766) (xy 285.868221 -301.361752) (xy 285.827718 -301.389708) (xy 285.783256 -301.410806)
			(xy 285.735985 -301.424498) (xy 285.68713 -301.43043) (xy 285.637955 -301.428449) (xy 285.589736 -301.418605)
			(xy 285.54372 -301.401153) (xy 285.501099 -301.376546) (xy 285.462978 -301.345421) (xy 285.430343 -301.308584)
			(xy 285.40404 -301.266988) (xy 285.384749 -301.221712) (xy 285.372972 -301.173928) (xy 285.369012 -301.124874)
			(xy 285.030164 -301.124874) (xy 285.029669 -301.149481) (xy 285.021774 -301.198058) (xy 285.00619 -301.244739)
			(xy 284.983319 -301.288316) (xy 284.953754 -301.32766) (xy 284.918261 -301.361752) (xy 284.877758 -301.389708)
			(xy 284.833296 -301.410806) (xy 284.786025 -301.424498) (xy 284.73717 -301.43043) (xy 284.687995 -301.428449)
			(xy 284.639776 -301.418605) (xy 284.59376 -301.401153) (xy 284.551139 -301.376546) (xy 284.513018 -301.345421)
			(xy 284.480383 -301.308584) (xy 284.45408 -301.266988) (xy 284.434789 -301.221712) (xy 284.423012 -301.173928)
			(xy 284.419052 -301.124874) (xy 284.080204 -301.124874) (xy 284.079709 -301.149481) (xy 284.071814 -301.198058)
			(xy 284.05623 -301.244739) (xy 284.033359 -301.288316) (xy 284.003794 -301.32766) (xy 283.968301 -301.361752)
			(xy 283.927798 -301.389708) (xy 283.883336 -301.410806) (xy 283.836065 -301.424498) (xy 283.78721 -301.43043)
			(xy 283.738035 -301.428449) (xy 283.689816 -301.418605) (xy 283.6438 -301.401153) (xy 283.601179 -301.376546)
			(xy 283.563058 -301.345421) (xy 283.530423 -301.308584) (xy 283.50412 -301.266988) (xy 283.484829 -301.221712)
			(xy 283.473052 -301.173928) (xy 283.469092 -301.124874) (xy 283.130244 -301.124874) (xy 283.129749 -301.149481)
			(xy 283.121854 -301.198058) (xy 283.10627 -301.244739) (xy 283.083399 -301.288316) (xy 283.053834 -301.32766)
			(xy 283.018341 -301.361752) (xy 282.977838 -301.389708) (xy 282.933376 -301.410806) (xy 282.886105 -301.424498)
			(xy 282.83725 -301.43043) (xy 282.788075 -301.428449) (xy 282.739856 -301.418605) (xy 282.69384 -301.401153)
			(xy 282.651219 -301.376546) (xy 282.613098 -301.345421) (xy 282.580463 -301.308584) (xy 282.55416 -301.266988)
			(xy 282.534869 -301.221712) (xy 282.523092 -301.173928) (xy 282.519132 -301.124874) (xy 281.23007 -301.124874)
			(xy 281.229575 -301.149481) (xy 281.22168 -301.198058) (xy 281.206096 -301.244739) (xy 281.183225 -301.288316)
			(xy 281.15366 -301.32766) (xy 281.118167 -301.361752) (xy 281.077664 -301.389708) (xy 281.033202 -301.410806)
			(xy 280.985931 -301.424498) (xy 280.937076 -301.43043) (xy 280.887901 -301.428449) (xy 280.839682 -301.418605)
			(xy 280.793666 -301.401153) (xy 280.751045 -301.376546) (xy 280.712924 -301.345421) (xy 280.680289 -301.308584)
			(xy 280.653986 -301.266988) (xy 280.634695 -301.221712) (xy 280.622918 -301.173928) (xy 280.618958 -301.124874)
			(xy 279.33015 -301.124874) (xy 279.329655 -301.149481) (xy 279.32176 -301.198058) (xy 279.306176 -301.244739)
			(xy 279.283305 -301.288316) (xy 279.25374 -301.32766) (xy 279.218247 -301.361752) (xy 279.177744 -301.389708)
			(xy 279.133282 -301.410806) (xy 279.086011 -301.424498) (xy 279.037156 -301.43043) (xy 278.987981 -301.428449)
			(xy 278.939762 -301.418605) (xy 278.893746 -301.401153) (xy 278.851125 -301.376546) (xy 278.813004 -301.345421)
			(xy 278.780369 -301.308584) (xy 278.754066 -301.266988) (xy 278.734775 -301.221712) (xy 278.722998 -301.173928)
			(xy 278.719038 -301.124874) (xy 267.783555 -301.124874) (xy 267.282843 -301.625562) (xy 270.62328 -301.625562)
			(xy 270.62328 -301.574146) (xy 270.631323 -301.523364) (xy 270.647211 -301.474465) (xy 270.670554 -301.428653)
			(xy 270.700775 -301.387057) (xy 270.737131 -301.350701) (xy 270.778727 -301.32048) (xy 270.824539 -301.297137)
			(xy 270.873438 -301.281249) (xy 270.92422 -301.273206) (xy 270.975636 -301.273206) (xy 271.026418 -301.281249)
			(xy 271.075317 -301.297137) (xy 271.121129 -301.32048) (xy 271.162725 -301.350701) (xy 271.199081 -301.387057)
			(xy 271.229302 -301.428653) (xy 271.252645 -301.474465) (xy 271.268533 -301.523364) (xy 271.276576 -301.574146)
			(xy 271.27708 -301.599854) (xy 271.276576 -301.625562) (xy 271.57324 -301.625562) (xy 271.57324 -301.574146)
			(xy 271.581283 -301.523364) (xy 271.597171 -301.474465) (xy 271.620514 -301.428653) (xy 271.650735 -301.387057)
			(xy 271.687091 -301.350701) (xy 271.728687 -301.32048) (xy 271.774499 -301.297137) (xy 271.823398 -301.281249)
			(xy 271.87418 -301.273206) (xy 271.925596 -301.273206) (xy 271.976378 -301.281249) (xy 272.025277 -301.297137)
			(xy 272.071089 -301.32048) (xy 272.112685 -301.350701) (xy 272.149041 -301.387057) (xy 272.179262 -301.428653)
			(xy 272.202605 -301.474465) (xy 272.218493 -301.523364) (xy 272.226536 -301.574146) (xy 272.22704 -301.599854)
			(xy 272.226536 -301.625562) (xy 273.47316 -301.625562) (xy 273.47316 -301.574146) (xy 273.481203 -301.523364)
			(xy 273.497091 -301.474465) (xy 273.520434 -301.428653) (xy 273.550655 -301.387057) (xy 273.587011 -301.350701)
			(xy 273.628607 -301.32048) (xy 273.674419 -301.297137) (xy 273.723318 -301.281249) (xy 273.7741 -301.273206)
			(xy 273.825516 -301.273206) (xy 273.876298 -301.281249) (xy 273.925197 -301.297137) (xy 273.971009 -301.32048)
			(xy 274.012605 -301.350701) (xy 274.048961 -301.387057) (xy 274.079182 -301.428653) (xy 274.102525 -301.474465)
			(xy 274.118413 -301.523364) (xy 274.126456 -301.574146) (xy 274.12696 -301.599854) (xy 274.126456 -301.625562)
			(xy 274.42312 -301.625562) (xy 274.42312 -301.574146) (xy 274.431163 -301.523364) (xy 274.447051 -301.474465)
			(xy 274.470394 -301.428653) (xy 274.500615 -301.387057) (xy 274.536971 -301.350701) (xy 274.578567 -301.32048)
			(xy 274.624379 -301.297137) (xy 274.673278 -301.281249) (xy 274.72406 -301.273206) (xy 274.775476 -301.273206)
			(xy 274.826258 -301.281249) (xy 274.875157 -301.297137) (xy 274.920969 -301.32048) (xy 274.962565 -301.350701)
			(xy 274.998921 -301.387057) (xy 275.029142 -301.428653) (xy 275.052485 -301.474465) (xy 275.068373 -301.523364)
			(xy 275.076416 -301.574146) (xy 275.07692 -301.599854) (xy 275.076416 -301.625562) (xy 275.068373 -301.676344)
			(xy 275.052485 -301.725243) (xy 275.029142 -301.771055) (xy 274.998921 -301.812651) (xy 274.962565 -301.849007)
			(xy 274.920969 -301.879228) (xy 274.875157 -301.902571) (xy 274.826258 -301.918459) (xy 274.775476 -301.926502)
			(xy 274.72406 -301.926502) (xy 274.673278 -301.918459) (xy 274.624379 -301.902571) (xy 274.578567 -301.879228)
			(xy 274.536971 -301.849007) (xy 274.500615 -301.812651) (xy 274.470394 -301.771055) (xy 274.447051 -301.725243)
			(xy 274.431163 -301.676344) (xy 274.42312 -301.625562) (xy 274.126456 -301.625562) (xy 274.118413 -301.676344)
			(xy 274.102525 -301.725243) (xy 274.079182 -301.771055) (xy 274.048961 -301.812651) (xy 274.012605 -301.849007)
			(xy 273.971009 -301.879228) (xy 273.925197 -301.902571) (xy 273.876298 -301.918459) (xy 273.825516 -301.926502)
			(xy 273.7741 -301.926502) (xy 273.723318 -301.918459) (xy 273.674419 -301.902571) (xy 273.628607 -301.879228)
			(xy 273.587011 -301.849007) (xy 273.550655 -301.812651) (xy 273.520434 -301.771055) (xy 273.497091 -301.725243)
			(xy 273.481203 -301.676344) (xy 273.47316 -301.625562) (xy 272.226536 -301.625562) (xy 272.218493 -301.676344)
			(xy 272.202605 -301.725243) (xy 272.179262 -301.771055) (xy 272.149041 -301.812651) (xy 272.112685 -301.849007)
			(xy 272.071089 -301.879228) (xy 272.025277 -301.902571) (xy 271.976378 -301.918459) (xy 271.925596 -301.926502)
			(xy 271.87418 -301.926502) (xy 271.823398 -301.918459) (xy 271.774499 -301.902571) (xy 271.728687 -301.879228)
			(xy 271.687091 -301.849007) (xy 271.650735 -301.812651) (xy 271.620514 -301.771055) (xy 271.597171 -301.725243)
			(xy 271.581283 -301.676344) (xy 271.57324 -301.625562) (xy 271.276576 -301.625562) (xy 271.268533 -301.676344)
			(xy 271.252645 -301.725243) (xy 271.229302 -301.771055) (xy 271.199081 -301.812651) (xy 271.162725 -301.849007)
			(xy 271.121129 -301.879228) (xy 271.075317 -301.902571) (xy 271.026418 -301.918459) (xy 270.975636 -301.926502)
			(xy 270.92422 -301.926502) (xy 270.873438 -301.918459) (xy 270.824539 -301.902571) (xy 270.778727 -301.879228)
			(xy 270.737131 -301.849007) (xy 270.700775 -301.812651) (xy 270.670554 -301.771055) (xy 270.647211 -301.725243)
			(xy 270.631323 -301.676344) (xy 270.62328 -301.625562) (xy 267.282843 -301.625562) (xy 266.332839 -302.575522)
			(xy 268.723106 -302.575522) (xy 268.723106 -302.524106) (xy 268.731149 -302.473324) (xy 268.747037 -302.424425)
			(xy 268.77038 -302.378613) (xy 268.800601 -302.337017) (xy 268.836957 -302.300661) (xy 268.878553 -302.27044)
			(xy 268.924365 -302.247097) (xy 268.973264 -302.231209) (xy 269.024046 -302.223166) (xy 269.075462 -302.223166)
			(xy 269.126244 -302.231209) (xy 269.175143 -302.247097) (xy 269.220955 -302.27044) (xy 269.262551 -302.300661)
			(xy 269.298907 -302.337017) (xy 269.329128 -302.378613) (xy 269.352471 -302.424425) (xy 269.368359 -302.473324)
			(xy 269.376402 -302.524106) (xy 269.376906 -302.549814) (xy 269.376402 -302.575522) (xy 269.673066 -302.575522)
			(xy 269.673066 -302.524106) (xy 269.681109 -302.473324) (xy 269.696997 -302.424425) (xy 269.72034 -302.378613)
			(xy 269.750561 -302.337017) (xy 269.786917 -302.300661) (xy 269.828513 -302.27044) (xy 269.874325 -302.247097)
			(xy 269.923224 -302.231209) (xy 269.974006 -302.223166) (xy 270.025422 -302.223166) (xy 270.076204 -302.231209)
			(xy 270.125103 -302.247097) (xy 270.170915 -302.27044) (xy 270.212511 -302.300661) (xy 270.248867 -302.337017)
			(xy 270.279088 -302.378613) (xy 270.302431 -302.424425) (xy 270.318319 -302.473324) (xy 270.326362 -302.524106)
			(xy 270.326866 -302.549814) (xy 270.326362 -302.575522) (xy 275.37308 -302.575522) (xy 275.37308 -302.524106)
			(xy 275.381123 -302.473324) (xy 275.397011 -302.424425) (xy 275.420354 -302.378613) (xy 275.450575 -302.337017)
			(xy 275.486931 -302.300661) (xy 275.528527 -302.27044) (xy 275.574339 -302.247097) (xy 275.623238 -302.231209)
			(xy 275.67402 -302.223166) (xy 275.725436 -302.223166) (xy 275.776218 -302.231209) (xy 275.825117 -302.247097)
			(xy 275.870929 -302.27044) (xy 275.912525 -302.300661) (xy 275.948881 -302.337017) (xy 275.979102 -302.378613)
			(xy 276.002445 -302.424425) (xy 276.018333 -302.473324) (xy 276.026376 -302.524106) (xy 276.02688 -302.549814)
			(xy 276.026376 -302.575522) (xy 276.32304 -302.575522) (xy 276.32304 -302.524106) (xy 276.331083 -302.473324)
			(xy 276.346971 -302.424425) (xy 276.370314 -302.378613) (xy 276.400535 -302.337017) (xy 276.436891 -302.300661)
			(xy 276.478487 -302.27044) (xy 276.524299 -302.247097) (xy 276.573198 -302.231209) (xy 276.62398 -302.223166)
			(xy 276.675396 -302.223166) (xy 276.726178 -302.231209) (xy 276.775077 -302.247097) (xy 276.820889 -302.27044)
			(xy 276.862485 -302.300661) (xy 276.898841 -302.337017) (xy 276.929062 -302.378613) (xy 276.952405 -302.424425)
			(xy 276.968293 -302.473324) (xy 276.976336 -302.524106) (xy 276.97684 -302.549814) (xy 276.976336 -302.575522)
			(xy 276.968293 -302.626304) (xy 276.952405 -302.675203) (xy 276.929062 -302.721015) (xy 276.898841 -302.762611)
			(xy 276.862485 -302.798967) (xy 276.820889 -302.829188) (xy 276.775077 -302.852531) (xy 276.726178 -302.868419)
			(xy 276.675396 -302.876462) (xy 276.62398 -302.876462) (xy 276.573198 -302.868419) (xy 276.524299 -302.852531)
			(xy 276.478487 -302.829188) (xy 276.436891 -302.798967) (xy 276.400535 -302.762611) (xy 276.370314 -302.721015)
			(xy 276.346971 -302.675203) (xy 276.331083 -302.626304) (xy 276.32304 -302.575522) (xy 276.026376 -302.575522)
			(xy 276.018333 -302.626304) (xy 276.002445 -302.675203) (xy 275.979102 -302.721015) (xy 275.948881 -302.762611)
			(xy 275.912525 -302.798967) (xy 275.870929 -302.829188) (xy 275.825117 -302.852531) (xy 275.776218 -302.868419)
			(xy 275.725436 -302.876462) (xy 275.67402 -302.876462) (xy 275.623238 -302.868419) (xy 275.574339 -302.852531)
			(xy 275.528527 -302.829188) (xy 275.486931 -302.798967) (xy 275.450575 -302.762611) (xy 275.420354 -302.721015)
			(xy 275.397011 -302.675203) (xy 275.381123 -302.626304) (xy 275.37308 -302.575522) (xy 270.326362 -302.575522)
			(xy 270.318319 -302.626304) (xy 270.302431 -302.675203) (xy 270.279088 -302.721015) (xy 270.248867 -302.762611)
			(xy 270.212511 -302.798967) (xy 270.170915 -302.829188) (xy 270.125103 -302.852531) (xy 270.076204 -302.868419)
			(xy 270.025422 -302.876462) (xy 269.974006 -302.876462) (xy 269.923224 -302.868419) (xy 269.874325 -302.852531)
			(xy 269.828513 -302.829188) (xy 269.786917 -302.798967) (xy 269.750561 -302.762611) (xy 269.72034 -302.721015)
			(xy 269.696997 -302.675203) (xy 269.681109 -302.626304) (xy 269.673066 -302.575522) (xy 269.376402 -302.575522)
			(xy 269.368359 -302.626304) (xy 269.352471 -302.675203) (xy 269.329128 -302.721015) (xy 269.298907 -302.762611)
			(xy 269.262551 -302.798967) (xy 269.220955 -302.829188) (xy 269.175143 -302.852531) (xy 269.126244 -302.868419)
			(xy 269.075462 -302.876462) (xy 269.024046 -302.876462) (xy 268.973264 -302.868419) (xy 268.924365 -302.852531)
			(xy 268.878553 -302.829188) (xy 268.836957 -302.798967) (xy 268.800601 -302.762611) (xy 268.77038 -302.721015)
			(xy 268.747037 -302.675203) (xy 268.731149 -302.626304) (xy 268.723106 -302.575522) (xy 266.332839 -302.575522)
			(xy 265.883546 -303.024794) (xy 280.618958 -303.024794) (xy 280.622918 -302.97574) (xy 280.634695 -302.927956)
			(xy 280.653986 -302.88268) (xy 280.680289 -302.841084) (xy 280.712924 -302.804247) (xy 280.751045 -302.773122)
			(xy 280.793666 -302.748515) (xy 280.839682 -302.731063) (xy 280.887901 -302.721219) (xy 280.937076 -302.719238)
			(xy 280.985931 -302.72517) (xy 281.033202 -302.738862) (xy 281.077664 -302.75996) (xy 281.118167 -302.787916)
			(xy 281.15366 -302.822008) (xy 281.183225 -302.861352) (xy 281.206096 -302.904929) (xy 281.22168 -302.95161)
			(xy 281.229575 -303.000187) (xy 281.23007 -303.024794) (xy 282.519132 -303.024794) (xy 282.523092 -302.97574)
			(xy 282.534869 -302.927956) (xy 282.55416 -302.88268) (xy 282.580463 -302.841084) (xy 282.613098 -302.804247)
			(xy 282.651219 -302.773122) (xy 282.69384 -302.748515) (xy 282.739856 -302.731063) (xy 282.788075 -302.721219)
			(xy 282.83725 -302.719238) (xy 282.886105 -302.72517) (xy 282.933376 -302.738862) (xy 282.977838 -302.75996)
			(xy 283.018341 -302.787916) (xy 283.053834 -302.822008) (xy 283.083399 -302.861352) (xy 283.10627 -302.904929)
			(xy 283.121854 -302.95161) (xy 283.129749 -303.000187) (xy 283.130244 -303.024794) (xy 283.469092 -303.024794)
			(xy 283.473052 -302.97574) (xy 283.484829 -302.927956) (xy 283.50412 -302.88268) (xy 283.530423 -302.841084)
			(xy 283.563058 -302.804247) (xy 283.601179 -302.773122) (xy 283.6438 -302.748515) (xy 283.689816 -302.731063)
			(xy 283.738035 -302.721219) (xy 283.78721 -302.719238) (xy 283.836065 -302.72517) (xy 283.883336 -302.738862)
			(xy 283.927798 -302.75996) (xy 283.968301 -302.787916) (xy 284.003794 -302.822008) (xy 284.033359 -302.861352)
			(xy 284.05623 -302.904929) (xy 284.071814 -302.95161) (xy 284.079709 -303.000187) (xy 284.080204 -303.024794)
			(xy 284.419052 -303.024794) (xy 284.423012 -302.97574) (xy 284.434789 -302.927956) (xy 284.45408 -302.88268)
			(xy 284.480383 -302.841084) (xy 284.513018 -302.804247) (xy 284.551139 -302.773122) (xy 284.59376 -302.748515)
			(xy 284.639776 -302.731063) (xy 284.687995 -302.721219) (xy 284.73717 -302.719238) (xy 284.786025 -302.72517)
			(xy 284.833296 -302.738862) (xy 284.877758 -302.75996) (xy 284.918261 -302.787916) (xy 284.953754 -302.822008)
			(xy 284.983319 -302.861352) (xy 285.00619 -302.904929) (xy 285.021774 -302.95161) (xy 285.029669 -303.000187)
			(xy 285.030164 -303.024794) (xy 285.369012 -303.024794) (xy 285.372972 -302.97574) (xy 285.384749 -302.927956)
			(xy 285.40404 -302.88268) (xy 285.430343 -302.841084) (xy 285.462978 -302.804247) (xy 285.501099 -302.773122)
			(xy 285.54372 -302.748515) (xy 285.589736 -302.731063) (xy 285.637955 -302.721219) (xy 285.68713 -302.719238)
			(xy 285.735985 -302.72517) (xy 285.783256 -302.738862) (xy 285.827718 -302.75996) (xy 285.868221 -302.787916)
			(xy 285.903714 -302.822008) (xy 285.933279 -302.861352) (xy 285.95615 -302.904929) (xy 285.971734 -302.95161)
			(xy 285.979629 -303.000187) (xy 285.980124 -303.024794) (xy 286.318972 -303.024794) (xy 286.322932 -302.97574)
			(xy 286.334709 -302.927956) (xy 286.354 -302.88268) (xy 286.380303 -302.841084) (xy 286.412938 -302.804247)
			(xy 286.451059 -302.773122) (xy 286.49368 -302.748515) (xy 286.539696 -302.731063) (xy 286.587915 -302.721219)
			(xy 286.63709 -302.719238) (xy 286.685945 -302.72517) (xy 286.733216 -302.738862) (xy 286.777678 -302.75996)
			(xy 286.818181 -302.787916) (xy 286.853674 -302.822008) (xy 286.883239 -302.861352) (xy 286.90611 -302.904929)
			(xy 286.921694 -302.95161) (xy 286.929589 -303.000187) (xy 286.930084 -303.024794) (xy 287.268932 -303.024794)
			(xy 287.272892 -302.97574) (xy 287.284669 -302.927956) (xy 287.30396 -302.88268) (xy 287.330263 -302.841084)
			(xy 287.362898 -302.804247) (xy 287.401019 -302.773122) (xy 287.44364 -302.748515) (xy 287.489656 -302.731063)
			(xy 287.537875 -302.721219) (xy 287.58705 -302.719238) (xy 287.635905 -302.72517) (xy 287.683176 -302.738862)
			(xy 287.727638 -302.75996) (xy 287.768141 -302.787916) (xy 287.803634 -302.822008) (xy 287.833199 -302.861352)
			(xy 287.85607 -302.904929) (xy 287.871654 -302.95161) (xy 287.879549 -303.000187) (xy 287.880044 -303.024794)
			(xy 288.218892 -303.024794) (xy 288.222852 -302.97574) (xy 288.234629 -302.927956) (xy 288.25392 -302.88268)
			(xy 288.280223 -302.841084) (xy 288.312858 -302.804247) (xy 288.350979 -302.773122) (xy 288.3936 -302.748515)
			(xy 288.439616 -302.731063) (xy 288.487835 -302.721219) (xy 288.53701 -302.719238) (xy 288.585865 -302.72517)
			(xy 288.633136 -302.738862) (xy 288.677598 -302.75996) (xy 288.718101 -302.787916) (xy 288.753594 -302.822008)
			(xy 288.783159 -302.861352) (xy 288.80603 -302.904929) (xy 288.821614 -302.95161) (xy 288.829509 -303.000187)
			(xy 288.830004 -303.024794) (xy 289.169106 -303.024794) (xy 289.173066 -302.97574) (xy 289.184843 -302.927956)
			(xy 289.204134 -302.88268) (xy 289.230437 -302.841084) (xy 289.263072 -302.804247) (xy 289.301193 -302.773122)
			(xy 289.343814 -302.748515) (xy 289.38983 -302.731063) (xy 289.438049 -302.721219) (xy 289.487224 -302.719238)
			(xy 289.536079 -302.72517) (xy 289.58335 -302.738862) (xy 289.627812 -302.75996) (xy 289.668315 -302.787916)
			(xy 289.703808 -302.822008) (xy 289.733373 -302.861352) (xy 289.756244 -302.904929) (xy 289.771828 -302.95161)
			(xy 289.779723 -303.000187) (xy 289.780218 -303.024794) (xy 289.779723 -303.049401) (xy 289.771828 -303.097978)
			(xy 289.756244 -303.144659) (xy 289.733373 -303.188236) (xy 289.703808 -303.22758) (xy 289.668315 -303.261672)
			(xy 289.627812 -303.289628) (xy 289.58335 -303.310726) (xy 289.536079 -303.324418) (xy 289.487224 -303.33035)
			(xy 289.438049 -303.328369) (xy 289.38983 -303.318525) (xy 289.343814 -303.301073) (xy 289.301193 -303.276466)
			(xy 289.263072 -303.245341) (xy 289.230437 -303.208504) (xy 289.204134 -303.166908) (xy 289.184843 -303.121632)
			(xy 289.173066 -303.073848) (xy 289.169106 -303.024794) (xy 288.830004 -303.024794) (xy 288.829509 -303.049401)
			(xy 288.821614 -303.097978) (xy 288.80603 -303.144659) (xy 288.783159 -303.188236) (xy 288.753594 -303.22758)
			(xy 288.718101 -303.261672) (xy 288.677598 -303.289628) (xy 288.633136 -303.310726) (xy 288.585865 -303.324418)
			(xy 288.53701 -303.33035) (xy 288.487835 -303.328369) (xy 288.439616 -303.318525) (xy 288.3936 -303.301073)
			(xy 288.350979 -303.276466) (xy 288.312858 -303.245341) (xy 288.280223 -303.208504) (xy 288.25392 -303.166908)
			(xy 288.234629 -303.121632) (xy 288.222852 -303.073848) (xy 288.218892 -303.024794) (xy 287.880044 -303.024794)
			(xy 287.879549 -303.049401) (xy 287.871654 -303.097978) (xy 287.85607 -303.144659) (xy 287.833199 -303.188236)
			(xy 287.803634 -303.22758) (xy 287.768141 -303.261672) (xy 287.727638 -303.289628) (xy 287.683176 -303.310726)
			(xy 287.635905 -303.324418) (xy 287.58705 -303.33035) (xy 287.537875 -303.328369) (xy 287.489656 -303.318525)
			(xy 287.44364 -303.301073) (xy 287.401019 -303.276466) (xy 287.362898 -303.245341) (xy 287.330263 -303.208504)
			(xy 287.30396 -303.166908) (xy 287.284669 -303.121632) (xy 287.272892 -303.073848) (xy 287.268932 -303.024794)
			(xy 286.930084 -303.024794) (xy 286.929589 -303.049401) (xy 286.921694 -303.097978) (xy 286.90611 -303.144659)
			(xy 286.883239 -303.188236) (xy 286.853674 -303.22758) (xy 286.818181 -303.261672) (xy 286.777678 -303.289628)
			(xy 286.733216 -303.310726) (xy 286.685945 -303.324418) (xy 286.63709 -303.33035) (xy 286.587915 -303.328369)
			(xy 286.539696 -303.318525) (xy 286.49368 -303.301073) (xy 286.451059 -303.276466) (xy 286.412938 -303.245341)
			(xy 286.380303 -303.208504) (xy 286.354 -303.166908) (xy 286.334709 -303.121632) (xy 286.322932 -303.073848)
			(xy 286.318972 -303.024794) (xy 285.980124 -303.024794) (xy 285.979629 -303.049401) (xy 285.971734 -303.097978)
			(xy 285.95615 -303.144659) (xy 285.933279 -303.188236) (xy 285.903714 -303.22758) (xy 285.868221 -303.261672)
			(xy 285.827718 -303.289628) (xy 285.783256 -303.310726) (xy 285.735985 -303.324418) (xy 285.68713 -303.33035)
			(xy 285.637955 -303.328369) (xy 285.589736 -303.318525) (xy 285.54372 -303.301073) (xy 285.501099 -303.276466)
			(xy 285.462978 -303.245341) (xy 285.430343 -303.208504) (xy 285.40404 -303.166908) (xy 285.384749 -303.121632)
			(xy 285.372972 -303.073848) (xy 285.369012 -303.024794) (xy 285.030164 -303.024794) (xy 285.029669 -303.049401)
			(xy 285.021774 -303.097978) (xy 285.00619 -303.144659) (xy 284.983319 -303.188236) (xy 284.953754 -303.22758)
			(xy 284.918261 -303.261672) (xy 284.877758 -303.289628) (xy 284.833296 -303.310726) (xy 284.786025 -303.324418)
			(xy 284.73717 -303.33035) (xy 284.687995 -303.328369) (xy 284.639776 -303.318525) (xy 284.59376 -303.301073)
			(xy 284.551139 -303.276466) (xy 284.513018 -303.245341) (xy 284.480383 -303.208504) (xy 284.45408 -303.166908)
			(xy 284.434789 -303.121632) (xy 284.423012 -303.073848) (xy 284.419052 -303.024794) (xy 284.080204 -303.024794)
			(xy 284.079709 -303.049401) (xy 284.071814 -303.097978) (xy 284.05623 -303.144659) (xy 284.033359 -303.188236)
			(xy 284.003794 -303.22758) (xy 283.968301 -303.261672) (xy 283.927798 -303.289628) (xy 283.883336 -303.310726)
			(xy 283.836065 -303.324418) (xy 283.78721 -303.33035) (xy 283.738035 -303.328369) (xy 283.689816 -303.318525)
			(xy 283.6438 -303.301073) (xy 283.601179 -303.276466) (xy 283.563058 -303.245341) (xy 283.530423 -303.208504)
			(xy 283.50412 -303.166908) (xy 283.484829 -303.121632) (xy 283.473052 -303.073848) (xy 283.469092 -303.024794)
			(xy 283.130244 -303.024794) (xy 283.129749 -303.049401) (xy 283.121854 -303.097978) (xy 283.10627 -303.144659)
			(xy 283.083399 -303.188236) (xy 283.053834 -303.22758) (xy 283.018341 -303.261672) (xy 282.977838 -303.289628)
			(xy 282.933376 -303.310726) (xy 282.886105 -303.324418) (xy 282.83725 -303.33035) (xy 282.788075 -303.328369)
			(xy 282.739856 -303.318525) (xy 282.69384 -303.301073) (xy 282.651219 -303.276466) (xy 282.613098 -303.245341)
			(xy 282.580463 -303.208504) (xy 282.55416 -303.166908) (xy 282.534869 -303.121632) (xy 282.523092 -303.073848)
			(xy 282.519132 -303.024794) (xy 281.23007 -303.024794) (xy 281.229575 -303.049401) (xy 281.22168 -303.097978)
			(xy 281.206096 -303.144659) (xy 281.183225 -303.188236) (xy 281.15366 -303.22758) (xy 281.118167 -303.261672)
			(xy 281.077664 -303.289628) (xy 281.033202 -303.310726) (xy 280.985931 -303.324418) (xy 280.937076 -303.33035)
			(xy 280.887901 -303.328369) (xy 280.839682 -303.318525) (xy 280.793666 -303.301073) (xy 280.751045 -303.276466)
			(xy 280.712924 -303.245341) (xy 280.680289 -303.208504) (xy 280.653986 -303.166908) (xy 280.634695 -303.121632)
			(xy 280.622918 -303.073848) (xy 280.618958 -303.024794) (xy 265.883546 -303.024794) (xy 265.382834 -303.525482)
			(xy 270.62328 -303.525482) (xy 270.62328 -303.474066) (xy 270.631323 -303.423284) (xy 270.647211 -303.374385)
			(xy 270.670554 -303.328573) (xy 270.700775 -303.286977) (xy 270.737131 -303.250621) (xy 270.778727 -303.2204)
			(xy 270.824539 -303.197057) (xy 270.873438 -303.181169) (xy 270.92422 -303.173126) (xy 270.975636 -303.173126)
			(xy 271.026418 -303.181169) (xy 271.075317 -303.197057) (xy 271.121129 -303.2204) (xy 271.162725 -303.250621)
			(xy 271.199081 -303.286977) (xy 271.229302 -303.328573) (xy 271.252645 -303.374385) (xy 271.268533 -303.423284)
			(xy 271.276576 -303.474066) (xy 271.27708 -303.499774) (xy 271.276576 -303.525482) (xy 271.57324 -303.525482)
			(xy 271.57324 -303.474066) (xy 271.581283 -303.423284) (xy 271.597171 -303.374385) (xy 271.620514 -303.328573)
			(xy 271.650735 -303.286977) (xy 271.687091 -303.250621) (xy 271.728687 -303.2204) (xy 271.774499 -303.197057)
			(xy 271.823398 -303.181169) (xy 271.87418 -303.173126) (xy 271.925596 -303.173126) (xy 271.976378 -303.181169)
			(xy 272.025277 -303.197057) (xy 272.071089 -303.2204) (xy 272.112685 -303.250621) (xy 272.149041 -303.286977)
			(xy 272.179262 -303.328573) (xy 272.202605 -303.374385) (xy 272.218493 -303.423284) (xy 272.226536 -303.474066)
			(xy 272.22704 -303.499774) (xy 272.226536 -303.525482) (xy 273.47316 -303.525482) (xy 273.47316 -303.474066)
			(xy 273.481203 -303.423284) (xy 273.497091 -303.374385) (xy 273.520434 -303.328573) (xy 273.550655 -303.286977)
			(xy 273.587011 -303.250621) (xy 273.628607 -303.2204) (xy 273.674419 -303.197057) (xy 273.723318 -303.181169)
			(xy 273.7741 -303.173126) (xy 273.825516 -303.173126) (xy 273.876298 -303.181169) (xy 273.925197 -303.197057)
			(xy 273.971009 -303.2204) (xy 274.012605 -303.250621) (xy 274.048961 -303.286977) (xy 274.079182 -303.328573)
			(xy 274.102525 -303.374385) (xy 274.118413 -303.423284) (xy 274.126456 -303.474066) (xy 274.12696 -303.499774)
			(xy 274.126456 -303.525482) (xy 274.42312 -303.525482) (xy 274.42312 -303.474066) (xy 274.431163 -303.423284)
			(xy 274.447051 -303.374385) (xy 274.470394 -303.328573) (xy 274.500615 -303.286977) (xy 274.536971 -303.250621)
			(xy 274.578567 -303.2204) (xy 274.624379 -303.197057) (xy 274.673278 -303.181169) (xy 274.72406 -303.173126)
			(xy 274.775476 -303.173126) (xy 274.826258 -303.181169) (xy 274.875157 -303.197057) (xy 274.920969 -303.2204)
			(xy 274.962565 -303.250621) (xy 274.998921 -303.286977) (xy 275.029142 -303.328573) (xy 275.052485 -303.374385)
			(xy 275.068373 -303.423284) (xy 275.076416 -303.474066) (xy 275.07692 -303.499774) (xy 275.076416 -303.525482)
			(xy 275.068373 -303.576264) (xy 275.052485 -303.625163) (xy 275.029142 -303.670975) (xy 274.998921 -303.712571)
			(xy 274.962565 -303.748927) (xy 274.920969 -303.779148) (xy 274.875157 -303.802491) (xy 274.826258 -303.818379)
			(xy 274.775476 -303.826422) (xy 274.72406 -303.826422) (xy 274.673278 -303.818379) (xy 274.624379 -303.802491)
			(xy 274.578567 -303.779148) (xy 274.536971 -303.748927) (xy 274.500615 -303.712571) (xy 274.470394 -303.670975)
			(xy 274.447051 -303.625163) (xy 274.431163 -303.576264) (xy 274.42312 -303.525482) (xy 274.126456 -303.525482)
			(xy 274.118413 -303.576264) (xy 274.102525 -303.625163) (xy 274.079182 -303.670975) (xy 274.048961 -303.712571)
			(xy 274.012605 -303.748927) (xy 273.971009 -303.779148) (xy 273.925197 -303.802491) (xy 273.876298 -303.818379)
			(xy 273.825516 -303.826422) (xy 273.7741 -303.826422) (xy 273.723318 -303.818379) (xy 273.674419 -303.802491)
			(xy 273.628607 -303.779148) (xy 273.587011 -303.748927) (xy 273.550655 -303.712571) (xy 273.520434 -303.670975)
			(xy 273.497091 -303.625163) (xy 273.481203 -303.576264) (xy 273.47316 -303.525482) (xy 272.226536 -303.525482)
			(xy 272.218493 -303.576264) (xy 272.202605 -303.625163) (xy 272.179262 -303.670975) (xy 272.149041 -303.712571)
			(xy 272.112685 -303.748927) (xy 272.071089 -303.779148) (xy 272.025277 -303.802491) (xy 271.976378 -303.818379)
			(xy 271.925596 -303.826422) (xy 271.87418 -303.826422) (xy 271.823398 -303.818379) (xy 271.774499 -303.802491)
			(xy 271.728687 -303.779148) (xy 271.687091 -303.748927) (xy 271.650735 -303.712571) (xy 271.620514 -303.670975)
			(xy 271.597171 -303.625163) (xy 271.581283 -303.576264) (xy 271.57324 -303.525482) (xy 271.276576 -303.525482)
			(xy 271.268533 -303.576264) (xy 271.252645 -303.625163) (xy 271.229302 -303.670975) (xy 271.199081 -303.712571)
			(xy 271.162725 -303.748927) (xy 271.121129 -303.779148) (xy 271.075317 -303.802491) (xy 271.026418 -303.818379)
			(xy 270.975636 -303.826422) (xy 270.92422 -303.826422) (xy 270.873438 -303.818379) (xy 270.824539 -303.802491)
			(xy 270.778727 -303.779148) (xy 270.737131 -303.748927) (xy 270.700775 -303.712571) (xy 270.670554 -303.670975)
			(xy 270.647211 -303.625163) (xy 270.631323 -303.576264) (xy 270.62328 -303.525482) (xy 265.382834 -303.525482)
			(xy 264.43283 -304.475442) (xy 268.723106 -304.475442) (xy 268.723106 -304.424026) (xy 268.731149 -304.373244)
			(xy 268.747037 -304.324345) (xy 268.77038 -304.278533) (xy 268.800601 -304.236937) (xy 268.836957 -304.200581)
			(xy 268.878553 -304.17036) (xy 268.924365 -304.147017) (xy 268.973264 -304.131129) (xy 269.024046 -304.123086)
			(xy 269.075462 -304.123086) (xy 269.126244 -304.131129) (xy 269.175143 -304.147017) (xy 269.220955 -304.17036)
			(xy 269.262551 -304.200581) (xy 269.298907 -304.236937) (xy 269.329128 -304.278533) (xy 269.352471 -304.324345)
			(xy 269.368359 -304.373244) (xy 269.376402 -304.424026) (xy 269.376906 -304.449734) (xy 269.376402 -304.475442)
			(xy 269.673066 -304.475442) (xy 269.673066 -304.424026) (xy 269.681109 -304.373244) (xy 269.696997 -304.324345)
			(xy 269.72034 -304.278533) (xy 269.750561 -304.236937) (xy 269.786917 -304.200581) (xy 269.828513 -304.17036)
			(xy 269.874325 -304.147017) (xy 269.923224 -304.131129) (xy 269.974006 -304.123086) (xy 270.025422 -304.123086)
			(xy 270.076204 -304.131129) (xy 270.125103 -304.147017) (xy 270.170915 -304.17036) (xy 270.212511 -304.200581)
			(xy 270.248867 -304.236937) (xy 270.279088 -304.278533) (xy 270.302431 -304.324345) (xy 270.318319 -304.373244)
			(xy 270.326362 -304.424026) (xy 270.326866 -304.449734) (xy 270.326362 -304.475442) (xy 275.37308 -304.475442)
			(xy 275.37308 -304.424026) (xy 275.381123 -304.373244) (xy 275.397011 -304.324345) (xy 275.420354 -304.278533)
			(xy 275.450575 -304.236937) (xy 275.486931 -304.200581) (xy 275.528527 -304.17036) (xy 275.574339 -304.147017)
			(xy 275.623238 -304.131129) (xy 275.67402 -304.123086) (xy 275.725436 -304.123086) (xy 275.776218 -304.131129)
			(xy 275.825117 -304.147017) (xy 275.870929 -304.17036) (xy 275.912525 -304.200581) (xy 275.948881 -304.236937)
			(xy 275.979102 -304.278533) (xy 276.002445 -304.324345) (xy 276.018333 -304.373244) (xy 276.026376 -304.424026)
			(xy 276.02688 -304.449734) (xy 276.026376 -304.475442) (xy 276.32304 -304.475442) (xy 276.32304 -304.424026)
			(xy 276.331083 -304.373244) (xy 276.346971 -304.324345) (xy 276.370314 -304.278533) (xy 276.400535 -304.236937)
			(xy 276.436891 -304.200581) (xy 276.478487 -304.17036) (xy 276.524299 -304.147017) (xy 276.573198 -304.131129)
			(xy 276.62398 -304.123086) (xy 276.675396 -304.123086) (xy 276.726178 -304.131129) (xy 276.775077 -304.147017)
			(xy 276.820889 -304.17036) (xy 276.862485 -304.200581) (xy 276.898841 -304.236937) (xy 276.929062 -304.278533)
			(xy 276.952405 -304.324345) (xy 276.968293 -304.373244) (xy 276.976336 -304.424026) (xy 276.97684 -304.449734)
			(xy 276.976336 -304.475442) (xy 276.968293 -304.526224) (xy 276.952405 -304.575123) (xy 276.929062 -304.620935)
			(xy 276.898841 -304.662531) (xy 276.862485 -304.698887) (xy 276.820889 -304.729108) (xy 276.775077 -304.752451)
			(xy 276.726178 -304.768339) (xy 276.675396 -304.776382) (xy 276.62398 -304.776382) (xy 276.573198 -304.768339)
			(xy 276.524299 -304.752451) (xy 276.478487 -304.729108) (xy 276.436891 -304.698887) (xy 276.400535 -304.662531)
			(xy 276.370314 -304.620935) (xy 276.346971 -304.575123) (xy 276.331083 -304.526224) (xy 276.32304 -304.475442)
			(xy 276.026376 -304.475442) (xy 276.018333 -304.526224) (xy 276.002445 -304.575123) (xy 275.979102 -304.620935)
			(xy 275.948881 -304.662531) (xy 275.912525 -304.698887) (xy 275.870929 -304.729108) (xy 275.825117 -304.752451)
			(xy 275.776218 -304.768339) (xy 275.725436 -304.776382) (xy 275.67402 -304.776382) (xy 275.623238 -304.768339)
			(xy 275.574339 -304.752451) (xy 275.528527 -304.729108) (xy 275.486931 -304.698887) (xy 275.450575 -304.662531)
			(xy 275.420354 -304.620935) (xy 275.397011 -304.575123) (xy 275.381123 -304.526224) (xy 275.37308 -304.475442)
			(xy 270.326362 -304.475442) (xy 270.318319 -304.526224) (xy 270.302431 -304.575123) (xy 270.279088 -304.620935)
			(xy 270.248867 -304.662531) (xy 270.212511 -304.698887) (xy 270.170915 -304.729108) (xy 270.125103 -304.752451)
			(xy 270.076204 -304.768339) (xy 270.025422 -304.776382) (xy 269.974006 -304.776382) (xy 269.923224 -304.768339)
			(xy 269.874325 -304.752451) (xy 269.828513 -304.729108) (xy 269.786917 -304.698887) (xy 269.750561 -304.662531)
			(xy 269.72034 -304.620935) (xy 269.696997 -304.575123) (xy 269.681109 -304.526224) (xy 269.673066 -304.475442)
			(xy 269.376402 -304.475442) (xy 269.368359 -304.526224) (xy 269.352471 -304.575123) (xy 269.329128 -304.620935)
			(xy 269.298907 -304.662531) (xy 269.262551 -304.698887) (xy 269.220955 -304.729108) (xy 269.175143 -304.752451)
			(xy 269.126244 -304.768339) (xy 269.075462 -304.776382) (xy 269.024046 -304.776382) (xy 268.973264 -304.768339)
			(xy 268.924365 -304.752451) (xy 268.878553 -304.729108) (xy 268.836957 -304.698887) (xy 268.800601 -304.662531)
			(xy 268.77038 -304.620935) (xy 268.747037 -304.575123) (xy 268.731149 -304.526224) (xy 268.723106 -304.475442)
			(xy 264.43283 -304.475442) (xy 263.482572 -305.425656) (xy 270.62328 -305.425656) (xy 270.62328 -305.37424)
			(xy 270.631323 -305.323458) (xy 270.647211 -305.274559) (xy 270.670554 -305.228747) (xy 270.700775 -305.187151)
			(xy 270.737131 -305.150795) (xy 270.778727 -305.120574) (xy 270.824539 -305.097231) (xy 270.873438 -305.081343)
			(xy 270.92422 -305.0733) (xy 270.975636 -305.0733) (xy 271.026418 -305.081343) (xy 271.075317 -305.097231)
			(xy 271.121129 -305.120574) (xy 271.162725 -305.150795) (xy 271.199081 -305.187151) (xy 271.229302 -305.228747)
			(xy 271.252645 -305.274559) (xy 271.268533 -305.323458) (xy 271.276576 -305.37424) (xy 271.27708 -305.399948)
			(xy 271.276576 -305.425656) (xy 271.57324 -305.425656) (xy 271.57324 -305.37424) (xy 271.581283 -305.323458)
			(xy 271.597171 -305.274559) (xy 271.620514 -305.228747) (xy 271.650735 -305.187151) (xy 271.687091 -305.150795)
			(xy 271.728687 -305.120574) (xy 271.774499 -305.097231) (xy 271.823398 -305.081343) (xy 271.87418 -305.0733)
			(xy 271.925596 -305.0733) (xy 271.976378 -305.081343) (xy 272.025277 -305.097231) (xy 272.071089 -305.120574)
			(xy 272.112685 -305.150795) (xy 272.149041 -305.187151) (xy 272.179262 -305.228747) (xy 272.202605 -305.274559)
			(xy 272.218493 -305.323458) (xy 272.226536 -305.37424) (xy 272.22704 -305.399948) (xy 272.226536 -305.425656)
			(xy 273.47316 -305.425656) (xy 273.47316 -305.37424) (xy 273.481203 -305.323458) (xy 273.497091 -305.274559)
			(xy 273.520434 -305.228747) (xy 273.550655 -305.187151) (xy 273.587011 -305.150795) (xy 273.628607 -305.120574)
			(xy 273.674419 -305.097231) (xy 273.723318 -305.081343) (xy 273.7741 -305.0733) (xy 273.825516 -305.0733)
			(xy 273.876298 -305.081343) (xy 273.925197 -305.097231) (xy 273.971009 -305.120574) (xy 274.012605 -305.150795)
			(xy 274.048961 -305.187151) (xy 274.079182 -305.228747) (xy 274.102525 -305.274559) (xy 274.118413 -305.323458)
			(xy 274.126456 -305.37424) (xy 274.12696 -305.399948) (xy 274.126456 -305.425656) (xy 274.42312 -305.425656)
			(xy 274.42312 -305.37424) (xy 274.431163 -305.323458) (xy 274.447051 -305.274559) (xy 274.470394 -305.228747)
			(xy 274.500615 -305.187151) (xy 274.536971 -305.150795) (xy 274.578567 -305.120574) (xy 274.624379 -305.097231)
			(xy 274.673278 -305.081343) (xy 274.72406 -305.0733) (xy 274.775476 -305.0733) (xy 274.826258 -305.081343)
			(xy 274.875157 -305.097231) (xy 274.920969 -305.120574) (xy 274.962565 -305.150795) (xy 274.998921 -305.187151)
			(xy 275.029142 -305.228747) (xy 275.052485 -305.274559) (xy 275.068373 -305.323458) (xy 275.076416 -305.37424)
			(xy 275.07692 -305.399948) (xy 275.076416 -305.425656) (xy 275.068373 -305.476438) (xy 275.052485 -305.525337)
			(xy 275.029142 -305.571149) (xy 274.998921 -305.612745) (xy 274.962565 -305.649101) (xy 274.920969 -305.679322)
			(xy 274.875157 -305.702665) (xy 274.826258 -305.718553) (xy 274.775476 -305.726596) (xy 274.72406 -305.726596)
			(xy 274.673278 -305.718553) (xy 274.624379 -305.702665) (xy 274.578567 -305.679322) (xy 274.536971 -305.649101)
			(xy 274.500615 -305.612745) (xy 274.470394 -305.571149) (xy 274.447051 -305.525337) (xy 274.431163 -305.476438)
			(xy 274.42312 -305.425656) (xy 274.126456 -305.425656) (xy 274.118413 -305.476438) (xy 274.102525 -305.525337)
			(xy 274.079182 -305.571149) (xy 274.048961 -305.612745) (xy 274.012605 -305.649101) (xy 273.971009 -305.679322)
			(xy 273.925197 -305.702665) (xy 273.876298 -305.718553) (xy 273.825516 -305.726596) (xy 273.7741 -305.726596)
			(xy 273.723318 -305.718553) (xy 273.674419 -305.702665) (xy 273.628607 -305.679322) (xy 273.587011 -305.649101)
			(xy 273.550655 -305.612745) (xy 273.520434 -305.571149) (xy 273.497091 -305.525337) (xy 273.481203 -305.476438)
			(xy 273.47316 -305.425656) (xy 272.226536 -305.425656) (xy 272.218493 -305.476438) (xy 272.202605 -305.525337)
			(xy 272.179262 -305.571149) (xy 272.149041 -305.612745) (xy 272.112685 -305.649101) (xy 272.071089 -305.679322)
			(xy 272.025277 -305.702665) (xy 271.976378 -305.718553) (xy 271.925596 -305.726596) (xy 271.87418 -305.726596)
			(xy 271.823398 -305.718553) (xy 271.774499 -305.702665) (xy 271.728687 -305.679322) (xy 271.687091 -305.649101)
			(xy 271.650735 -305.612745) (xy 271.620514 -305.571149) (xy 271.597171 -305.525337) (xy 271.581283 -305.476438)
			(xy 271.57324 -305.425656) (xy 271.276576 -305.425656) (xy 271.268533 -305.476438) (xy 271.252645 -305.525337)
			(xy 271.229302 -305.571149) (xy 271.199081 -305.612745) (xy 271.162725 -305.649101) (xy 271.121129 -305.679322)
			(xy 271.075317 -305.702665) (xy 271.026418 -305.718553) (xy 270.975636 -305.726596) (xy 270.92422 -305.726596)
			(xy 270.873438 -305.718553) (xy 270.824539 -305.702665) (xy 270.778727 -305.679322) (xy 270.737131 -305.649101)
			(xy 270.700775 -305.612745) (xy 270.670554 -305.571149) (xy 270.647211 -305.525337) (xy 270.631323 -305.476438)
			(xy 270.62328 -305.425656) (xy 263.482572 -305.425656) (xy 262.551418 -306.356766) (xy 262.544007 -306.364943)
			(xy 262.540055 -306.375616) (xy 268.723106 -306.375616) (xy 268.723106 -306.3242) (xy 268.731149 -306.273418)
			(xy 268.747037 -306.224519) (xy 268.77038 -306.178707) (xy 268.800601 -306.137111) (xy 268.836957 -306.100755)
			(xy 268.878553 -306.070534) (xy 268.924365 -306.047191) (xy 268.973264 -306.031303) (xy 269.024046 -306.02326)
			(xy 269.075462 -306.02326) (xy 269.126244 -306.031303) (xy 269.175143 -306.047191) (xy 269.220955 -306.070534)
			(xy 269.262551 -306.100755) (xy 269.298907 -306.137111) (xy 269.329128 -306.178707) (xy 269.352471 -306.224519)
			(xy 269.368359 -306.273418) (xy 269.376402 -306.3242) (xy 269.376906 -306.349908) (xy 269.376402 -306.375616)
			(xy 269.673066 -306.375616) (xy 269.673066 -306.3242) (xy 269.681109 -306.273418) (xy 269.696997 -306.224519)
			(xy 269.72034 -306.178707) (xy 269.750561 -306.137111) (xy 269.786917 -306.100755) (xy 269.828513 -306.070534)
			(xy 269.874325 -306.047191) (xy 269.923224 -306.031303) (xy 269.974006 -306.02326) (xy 270.025422 -306.02326)
			(xy 270.076204 -306.031303) (xy 270.125103 -306.047191) (xy 270.170915 -306.070534) (xy 270.212511 -306.100755)
			(xy 270.248867 -306.137111) (xy 270.279088 -306.178707) (xy 270.302431 -306.224519) (xy 270.318319 -306.273418)
			(xy 270.326362 -306.3242) (xy 270.326866 -306.349908) (xy 270.326362 -306.375616) (xy 275.37308 -306.375616)
			(xy 275.37308 -306.3242) (xy 275.381123 -306.273418) (xy 275.397011 -306.224519) (xy 275.420354 -306.178707)
			(xy 275.450575 -306.137111) (xy 275.486931 -306.100755) (xy 275.528527 -306.070534) (xy 275.574339 -306.047191)
			(xy 275.623238 -306.031303) (xy 275.67402 -306.02326) (xy 275.725436 -306.02326) (xy 275.776218 -306.031303)
			(xy 275.825117 -306.047191) (xy 275.870929 -306.070534) (xy 275.912525 -306.100755) (xy 275.948881 -306.137111)
			(xy 275.979102 -306.178707) (xy 276.002445 -306.224519) (xy 276.018333 -306.273418) (xy 276.026376 -306.3242)
			(xy 276.02688 -306.349908) (xy 276.026376 -306.375616) (xy 276.32304 -306.375616) (xy 276.32304 -306.3242)
			(xy 276.331083 -306.273418) (xy 276.346971 -306.224519) (xy 276.370314 -306.178707) (xy 276.400535 -306.137111)
			(xy 276.436891 -306.100755) (xy 276.478487 -306.070534) (xy 276.524299 -306.047191) (xy 276.573198 -306.031303)
			(xy 276.62398 -306.02326) (xy 276.675396 -306.02326) (xy 276.726178 -306.031303) (xy 276.775077 -306.047191)
			(xy 276.820889 -306.070534) (xy 276.862485 -306.100755) (xy 276.898841 -306.137111) (xy 276.929062 -306.178707)
			(xy 276.952405 -306.224519) (xy 276.968293 -306.273418) (xy 276.976336 -306.3242) (xy 276.97684 -306.349908)
			(xy 276.976336 -306.375616) (xy 276.968293 -306.426398) (xy 276.952405 -306.475297) (xy 276.929062 -306.521109)
			(xy 276.898841 -306.562705) (xy 276.862485 -306.599061) (xy 276.820889 -306.629282) (xy 276.775077 -306.652625)
			(xy 276.726178 -306.668513) (xy 276.675396 -306.676556) (xy 276.62398 -306.676556) (xy 276.573198 -306.668513)
			(xy 276.524299 -306.652625) (xy 276.478487 -306.629282) (xy 276.436891 -306.599061) (xy 276.400535 -306.562705)
			(xy 276.370314 -306.521109) (xy 276.346971 -306.475297) (xy 276.331083 -306.426398) (xy 276.32304 -306.375616)
			(xy 276.026376 -306.375616) (xy 276.018333 -306.426398) (xy 276.002445 -306.475297) (xy 275.979102 -306.521109)
			(xy 275.948881 -306.562705) (xy 275.912525 -306.599061) (xy 275.870929 -306.629282) (xy 275.825117 -306.652625)
			(xy 275.776218 -306.668513) (xy 275.725436 -306.676556) (xy 275.67402 -306.676556) (xy 275.623238 -306.668513)
			(xy 275.574339 -306.652625) (xy 275.528527 -306.629282) (xy 275.486931 -306.599061) (xy 275.450575 -306.562705)
			(xy 275.420354 -306.521109) (xy 275.397011 -306.475297) (xy 275.381123 -306.426398) (xy 275.37308 -306.375616)
			(xy 270.326362 -306.375616) (xy 270.318319 -306.426398) (xy 270.302431 -306.475297) (xy 270.279088 -306.521109)
			(xy 270.248867 -306.562705) (xy 270.212511 -306.599061) (xy 270.170915 -306.629282) (xy 270.125103 -306.652625)
			(xy 270.076204 -306.668513) (xy 270.025422 -306.676556) (xy 269.974006 -306.676556) (xy 269.923224 -306.668513)
			(xy 269.874325 -306.652625) (xy 269.828513 -306.629282) (xy 269.786917 -306.599061) (xy 269.750561 -306.562705)
			(xy 269.72034 -306.521109) (xy 269.696997 -306.475297) (xy 269.681109 -306.426398) (xy 269.673066 -306.375616)
			(xy 269.376402 -306.375616) (xy 269.368359 -306.426398) (xy 269.352471 -306.475297) (xy 269.329128 -306.521109)
			(xy 269.298907 -306.562705) (xy 269.262551 -306.599061) (xy 269.220955 -306.629282) (xy 269.175143 -306.652625)
			(xy 269.126244 -306.668513) (xy 269.075462 -306.676556) (xy 269.024046 -306.676556) (xy 268.973264 -306.668513)
			(xy 268.924365 -306.652625) (xy 268.878553 -306.629282) (xy 268.836957 -306.599061) (xy 268.800601 -306.562705)
			(xy 268.77038 -306.521109) (xy 268.747037 -306.475297) (xy 268.731149 -306.426398) (xy 268.723106 -306.375616)
			(xy 262.540055 -306.375616) (xy 262.536353 -306.385615) (xy 262.536686 -306.396644) (xy 262.543544 -306.484782)
			(xy 262.554466 -306.504086) (xy 262.56361 -306.51069) (xy 262.584125 -306.526143) (xy 262.621218 -306.56167)
			(xy 262.653211 -306.601852) (xy 262.679525 -306.645961) (xy 262.699684 -306.693202) (xy 262.713325 -306.742719)
			(xy 262.720201 -306.793619) (xy 262.720582 -306.8193) (xy 262.720119 -306.846552) (xy 262.712362 -306.900502)
			(xy 262.697005 -306.952798) (xy 262.674362 -307.002377) (xy 262.644894 -307.048228) (xy 262.6092 -307.089418)
			(xy 262.568007 -307.12511) (xy 262.522154 -307.154575) (xy 262.472574 -307.177214) (xy 262.420276 -307.192567)
			(xy 262.366326 -307.200321) (xy 262.339074 -307.200808) (xy 262.309113 -307.200221) (xy 262.249926 -307.190859)
			(xy 262.192928 -307.172367) (xy 262.139518 -307.1452) (xy 262.091005 -307.110026) (xy 262.048582 -307.067706)
			(xy 262.030464 -307.043836) (xy 262.02386 -307.034692) (xy 262.004556 -307.02377) (xy 261.916418 -307.016912)
			(xy 261.905384 -307.016567) (xy 261.8847 -307.024209) (xy 261.87654 -307.031644) (xy 261.582608 -307.325576)
			(xy 270.62328 -307.325576) (xy 270.62328 -307.27416) (xy 270.631323 -307.223378) (xy 270.647211 -307.174479)
			(xy 270.670554 -307.128667) (xy 270.700775 -307.087071) (xy 270.737131 -307.050715) (xy 270.778727 -307.020494)
			(xy 270.824539 -306.997151) (xy 270.873438 -306.981263) (xy 270.92422 -306.97322) (xy 270.975636 -306.97322)
			(xy 271.026418 -306.981263) (xy 271.075317 -306.997151) (xy 271.121129 -307.020494) (xy 271.162725 -307.050715)
			(xy 271.199081 -307.087071) (xy 271.229302 -307.128667) (xy 271.252645 -307.174479) (xy 271.268533 -307.223378)
			(xy 271.276576 -307.27416) (xy 271.27708 -307.299868) (xy 271.276576 -307.325576) (xy 271.57324 -307.325576)
			(xy 271.57324 -307.27416) (xy 271.581283 -307.223378) (xy 271.597171 -307.174479) (xy 271.620514 -307.128667)
			(xy 271.650735 -307.087071) (xy 271.687091 -307.050715) (xy 271.728687 -307.020494) (xy 271.774499 -306.997151)
			(xy 271.823398 -306.981263) (xy 271.87418 -306.97322) (xy 271.925596 -306.97322) (xy 271.976378 -306.981263)
			(xy 272.025277 -306.997151) (xy 272.071089 -307.020494) (xy 272.112685 -307.050715) (xy 272.149041 -307.087071)
			(xy 272.179262 -307.128667) (xy 272.202605 -307.174479) (xy 272.218493 -307.223378) (xy 272.226536 -307.27416)
			(xy 272.22704 -307.299868) (xy 272.226536 -307.325576) (xy 273.47316 -307.325576) (xy 273.47316 -307.27416)
			(xy 273.481203 -307.223378) (xy 273.497091 -307.174479) (xy 273.520434 -307.128667) (xy 273.550655 -307.087071)
			(xy 273.587011 -307.050715) (xy 273.628607 -307.020494) (xy 273.674419 -306.997151) (xy 273.723318 -306.981263)
			(xy 273.7741 -306.97322) (xy 273.825516 -306.97322) (xy 273.876298 -306.981263) (xy 273.925197 -306.997151)
			(xy 273.971009 -307.020494) (xy 274.012605 -307.050715) (xy 274.048961 -307.087071) (xy 274.079182 -307.128667)
			(xy 274.102525 -307.174479) (xy 274.118413 -307.223378) (xy 274.126456 -307.27416) (xy 274.12696 -307.299868)
			(xy 274.126456 -307.325576) (xy 274.42312 -307.325576) (xy 274.42312 -307.27416) (xy 274.431163 -307.223378)
			(xy 274.447051 -307.174479) (xy 274.470394 -307.128667) (xy 274.500615 -307.087071) (xy 274.536971 -307.050715)
			(xy 274.578567 -307.020494) (xy 274.624379 -306.997151) (xy 274.673278 -306.981263) (xy 274.72406 -306.97322)
			(xy 274.775476 -306.97322) (xy 274.826258 -306.981263) (xy 274.875157 -306.997151) (xy 274.920969 -307.020494)
			(xy 274.962565 -307.050715) (xy 274.998921 -307.087071) (xy 275.029142 -307.128667) (xy 275.052485 -307.174479)
			(xy 275.068373 -307.223378) (xy 275.076416 -307.27416) (xy 275.07692 -307.299868) (xy 275.076416 -307.325576)
			(xy 275.068373 -307.376358) (xy 275.052485 -307.425257) (xy 275.029142 -307.471069) (xy 274.998921 -307.512665)
			(xy 274.962565 -307.549021) (xy 274.920969 -307.579242) (xy 274.875157 -307.602585) (xy 274.826258 -307.618473)
			(xy 274.775476 -307.626516) (xy 274.72406 -307.626516) (xy 274.673278 -307.618473) (xy 274.624379 -307.602585)
			(xy 274.578567 -307.579242) (xy 274.536971 -307.549021) (xy 274.500615 -307.512665) (xy 274.470394 -307.471069)
			(xy 274.447051 -307.425257) (xy 274.431163 -307.376358) (xy 274.42312 -307.325576) (xy 274.126456 -307.325576)
			(xy 274.118413 -307.376358) (xy 274.102525 -307.425257) (xy 274.079182 -307.471069) (xy 274.048961 -307.512665)
			(xy 274.012605 -307.549021) (xy 273.971009 -307.579242) (xy 273.925197 -307.602585) (xy 273.876298 -307.618473)
			(xy 273.825516 -307.626516) (xy 273.7741 -307.626516) (xy 273.723318 -307.618473) (xy 273.674419 -307.602585)
			(xy 273.628607 -307.579242) (xy 273.587011 -307.549021) (xy 273.550655 -307.512665) (xy 273.520434 -307.471069)
			(xy 273.497091 -307.425257) (xy 273.481203 -307.376358) (xy 273.47316 -307.325576) (xy 272.226536 -307.325576)
			(xy 272.218493 -307.376358) (xy 272.202605 -307.425257) (xy 272.179262 -307.471069) (xy 272.149041 -307.512665)
			(xy 272.112685 -307.549021) (xy 272.071089 -307.579242) (xy 272.025277 -307.602585) (xy 271.976378 -307.618473)
			(xy 271.925596 -307.626516) (xy 271.87418 -307.626516) (xy 271.823398 -307.618473) (xy 271.774499 -307.602585)
			(xy 271.728687 -307.579242) (xy 271.687091 -307.549021) (xy 271.650735 -307.512665) (xy 271.620514 -307.471069)
			(xy 271.597171 -307.425257) (xy 271.581283 -307.376358) (xy 271.57324 -307.325576) (xy 271.276576 -307.325576)
			(xy 271.268533 -307.376358) (xy 271.252645 -307.425257) (xy 271.229302 -307.471069) (xy 271.199081 -307.512665)
			(xy 271.162725 -307.549021) (xy 271.121129 -307.579242) (xy 271.075317 -307.602585) (xy 271.026418 -307.618473)
			(xy 270.975636 -307.626516) (xy 270.92422 -307.626516) (xy 270.873438 -307.618473) (xy 270.824539 -307.602585)
			(xy 270.778727 -307.579242) (xy 270.737131 -307.549021) (xy 270.700775 -307.512665) (xy 270.670554 -307.471069)
			(xy 270.647211 -307.425257) (xy 270.631323 -307.376358) (xy 270.62328 -307.325576) (xy 261.582608 -307.325576)
			(xy 260.899148 -308.009036) (xy 260.89209 -308.016894) (xy 260.884485 -308.036574) (xy 260.884416 -308.047136)
			(xy 260.887718 -308.122066) (xy 260.88868 -308.13248) (xy 260.897856 -308.15125) (xy 260.905498 -308.158388)
			(xy 260.905752 -308.158642) (xy 260.926643 -308.176853) (xy 260.963454 -308.218281) (xy 260.993876 -308.264603)
			(xy 260.998967 -308.275536) (xy 268.723106 -308.275536) (xy 268.723106 -308.22412) (xy 268.731149 -308.173338)
			(xy 268.747037 -308.124439) (xy 268.77038 -308.078627) (xy 268.800601 -308.037031) (xy 268.836957 -308.000675)
			(xy 268.878553 -307.970454) (xy 268.924365 -307.947111) (xy 268.973264 -307.931223) (xy 269.024046 -307.92318)
			(xy 269.075462 -307.92318) (xy 269.126244 -307.931223) (xy 269.175143 -307.947111) (xy 269.220955 -307.970454)
			(xy 269.262551 -308.000675) (xy 269.298907 -308.037031) (xy 269.329128 -308.078627) (xy 269.352471 -308.124439)
			(xy 269.368359 -308.173338) (xy 269.376402 -308.22412) (xy 269.376906 -308.249828) (xy 269.376402 -308.275536)
			(xy 269.673066 -308.275536) (xy 269.673066 -308.22412) (xy 269.681109 -308.173338) (xy 269.696997 -308.124439)
			(xy 269.72034 -308.078627) (xy 269.750561 -308.037031) (xy 269.786917 -308.000675) (xy 269.828513 -307.970454)
			(xy 269.874325 -307.947111) (xy 269.923224 -307.931223) (xy 269.974006 -307.92318) (xy 270.025422 -307.92318)
			(xy 270.076204 -307.931223) (xy 270.125103 -307.947111) (xy 270.170915 -307.970454) (xy 270.212511 -308.000675)
			(xy 270.248867 -308.037031) (xy 270.279088 -308.078627) (xy 270.302431 -308.124439) (xy 270.318319 -308.173338)
			(xy 270.326362 -308.22412) (xy 270.326866 -308.249828) (xy 270.326362 -308.275536) (xy 275.37308 -308.275536)
			(xy 275.37308 -308.22412) (xy 275.381123 -308.173338) (xy 275.397011 -308.124439) (xy 275.420354 -308.078627)
			(xy 275.450575 -308.037031) (xy 275.486931 -308.000675) (xy 275.528527 -307.970454) (xy 275.574339 -307.947111)
			(xy 275.623238 -307.931223) (xy 275.67402 -307.92318) (xy 275.725436 -307.92318) (xy 275.776218 -307.931223)
			(xy 275.825117 -307.947111) (xy 275.870929 -307.970454) (xy 275.912525 -308.000675) (xy 275.948881 -308.037031)
			(xy 275.979102 -308.078627) (xy 276.002445 -308.124439) (xy 276.018333 -308.173338) (xy 276.026376 -308.22412)
			(xy 276.02688 -308.249828) (xy 276.026376 -308.275536) (xy 276.32304 -308.275536) (xy 276.32304 -308.22412)
			(xy 276.331083 -308.173338) (xy 276.346971 -308.124439) (xy 276.370314 -308.078627) (xy 276.400535 -308.037031)
			(xy 276.436891 -308.000675) (xy 276.478487 -307.970454) (xy 276.524299 -307.947111) (xy 276.573198 -307.931223)
			(xy 276.62398 -307.92318) (xy 276.675396 -307.92318) (xy 276.726178 -307.931223) (xy 276.775077 -307.947111)
			(xy 276.820889 -307.970454) (xy 276.862485 -308.000675) (xy 276.898841 -308.037031) (xy 276.929062 -308.078627)
			(xy 276.952405 -308.124439) (xy 276.968293 -308.173338) (xy 276.976336 -308.22412) (xy 276.97684 -308.249828)
			(xy 276.976336 -308.275536) (xy 276.968293 -308.326318) (xy 276.952405 -308.375217) (xy 276.929062 -308.421029)
			(xy 276.898841 -308.462625) (xy 276.862485 -308.498981) (xy 276.820889 -308.529202) (xy 276.775077 -308.552545)
			(xy 276.726178 -308.568433) (xy 276.675396 -308.576476) (xy 276.62398 -308.576476) (xy 276.573198 -308.568433)
			(xy 276.524299 -308.552545) (xy 276.478487 -308.529202) (xy 276.436891 -308.498981) (xy 276.400535 -308.462625)
			(xy 276.370314 -308.421029) (xy 276.346971 -308.375217) (xy 276.331083 -308.326318) (xy 276.32304 -308.275536)
			(xy 276.026376 -308.275536) (xy 276.018333 -308.326318) (xy 276.002445 -308.375217) (xy 275.979102 -308.421029)
			(xy 275.948881 -308.462625) (xy 275.912525 -308.498981) (xy 275.870929 -308.529202) (xy 275.825117 -308.552545)
			(xy 275.776218 -308.568433) (xy 275.725436 -308.576476) (xy 275.67402 -308.576476) (xy 275.623238 -308.568433)
			(xy 275.574339 -308.552545) (xy 275.528527 -308.529202) (xy 275.486931 -308.498981) (xy 275.450575 -308.462625)
			(xy 275.420354 -308.421029) (xy 275.397011 -308.375217) (xy 275.381123 -308.326318) (xy 275.37308 -308.275536)
			(xy 270.326362 -308.275536) (xy 270.318319 -308.326318) (xy 270.302431 -308.375217) (xy 270.279088 -308.421029)
			(xy 270.248867 -308.462625) (xy 270.212511 -308.498981) (xy 270.170915 -308.529202) (xy 270.125103 -308.552545)
			(xy 270.076204 -308.568433) (xy 270.025422 -308.576476) (xy 269.974006 -308.576476) (xy 269.923224 -308.568433)
			(xy 269.874325 -308.552545) (xy 269.828513 -308.529202) (xy 269.786917 -308.498981) (xy 269.750561 -308.462625)
			(xy 269.72034 -308.421029) (xy 269.696997 -308.375217) (xy 269.681109 -308.326318) (xy 269.673066 -308.275536)
			(xy 269.376402 -308.275536) (xy 269.368359 -308.326318) (xy 269.352471 -308.375217) (xy 269.329128 -308.421029)
			(xy 269.298907 -308.462625) (xy 269.262551 -308.498981) (xy 269.220955 -308.529202) (xy 269.175143 -308.552545)
			(xy 269.126244 -308.568433) (xy 269.075462 -308.576476) (xy 269.024046 -308.576476) (xy 268.973264 -308.568433)
			(xy 268.924365 -308.552545) (xy 268.878553 -308.529202) (xy 268.836957 -308.498981) (xy 268.800601 -308.462625)
			(xy 268.77038 -308.421029) (xy 268.747037 -308.375217) (xy 268.731149 -308.326318) (xy 268.723106 -308.275536)
			(xy 260.998967 -308.275536) (xy 261.01727 -308.314843) (xy 261.03314 -308.367941) (xy 261.041154 -308.422778)
			(xy 261.041642 -308.450488) (xy 261.041157 -308.477741) (xy 261.033402 -308.531692) (xy 261.018048 -308.58399)
			(xy 260.995408 -308.633571) (xy 260.965943 -308.679425) (xy 260.930252 -308.720619) (xy 260.925418 -308.724808)
			(xy 278.719038 -308.724808) (xy 278.722998 -308.675754) (xy 278.734775 -308.62797) (xy 278.754066 -308.582694)
			(xy 278.780369 -308.541098) (xy 278.813004 -308.504261) (xy 278.851125 -308.473136) (xy 278.893746 -308.448529)
			(xy 278.939762 -308.431077) (xy 278.987981 -308.421233) (xy 279.037156 -308.419252) (xy 279.086011 -308.425184)
			(xy 279.133282 -308.438876) (xy 279.177744 -308.459974) (xy 279.218247 -308.48793) (xy 279.25374 -308.522022)
			(xy 279.283305 -308.561366) (xy 279.306176 -308.604943) (xy 279.32176 -308.651624) (xy 279.329655 -308.700201)
			(xy 279.33015 -308.724808) (xy 279.668998 -308.724808) (xy 279.672958 -308.675754) (xy 279.684735 -308.62797)
			(xy 279.704026 -308.582694) (xy 279.730329 -308.541098) (xy 279.762964 -308.504261) (xy 279.801085 -308.473136)
			(xy 279.843706 -308.448529) (xy 279.889722 -308.431077) (xy 279.937941 -308.421233) (xy 279.987116 -308.419252)
			(xy 280.035971 -308.425184) (xy 280.083242 -308.438876) (xy 280.127704 -308.459974) (xy 280.168207 -308.48793)
			(xy 280.2037 -308.522022) (xy 280.233265 -308.561366) (xy 280.256136 -308.604943) (xy 280.27172 -308.651624)
			(xy 280.279615 -308.700201) (xy 280.28011 -308.724808) (xy 280.618958 -308.724808) (xy 280.622918 -308.675754)
			(xy 280.634695 -308.62797) (xy 280.653986 -308.582694) (xy 280.680289 -308.541098) (xy 280.712924 -308.504261)
			(xy 280.751045 -308.473136) (xy 280.793666 -308.448529) (xy 280.839682 -308.431077) (xy 280.887901 -308.421233)
			(xy 280.937076 -308.419252) (xy 280.985931 -308.425184) (xy 281.033202 -308.438876) (xy 281.077664 -308.459974)
			(xy 281.118167 -308.48793) (xy 281.15366 -308.522022) (xy 281.183225 -308.561366) (xy 281.206096 -308.604943)
			(xy 281.22168 -308.651624) (xy 281.229575 -308.700201) (xy 281.23007 -308.724808) (xy 281.229575 -308.749415)
			(xy 281.22168 -308.797992) (xy 281.206096 -308.844673) (xy 281.183225 -308.88825) (xy 281.15366 -308.927594)
			(xy 281.118167 -308.961686) (xy 281.077664 -308.989642) (xy 281.033202 -309.01074) (xy 280.985931 -309.024432)
			(xy 280.937076 -309.030364) (xy 280.887901 -309.028383) (xy 280.839682 -309.018539) (xy 280.793666 -309.001087)
			(xy 280.751045 -308.97648) (xy 280.712924 -308.945355) (xy 280.680289 -308.908518) (xy 280.653986 -308.866922)
			(xy 280.634695 -308.821646) (xy 280.622918 -308.773862) (xy 280.618958 -308.724808) (xy 280.28011 -308.724808)
			(xy 280.279615 -308.749415) (xy 280.27172 -308.797992) (xy 280.256136 -308.844673) (xy 280.233265 -308.88825)
			(xy 280.2037 -308.927594) (xy 280.168207 -308.961686) (xy 280.127704 -308.989642) (xy 280.083242 -309.01074)
			(xy 280.035971 -309.024432) (xy 279.987116 -309.030364) (xy 279.937941 -309.028383) (xy 279.889722 -309.018539)
			(xy 279.843706 -309.001087) (xy 279.801085 -308.97648) (xy 279.762964 -308.945355) (xy 279.730329 -308.908518)
			(xy 279.704026 -308.866922) (xy 279.684735 -308.821646) (xy 279.672958 -308.773862) (xy 279.668998 -308.724808)
			(xy 279.33015 -308.724808) (xy 279.329655 -308.749415) (xy 279.32176 -308.797992) (xy 279.306176 -308.844673)
			(xy 279.283305 -308.88825) (xy 279.25374 -308.927594) (xy 279.218247 -308.961686) (xy 279.177744 -308.989642)
			(xy 279.133282 -309.01074) (xy 279.086011 -309.024432) (xy 279.037156 -309.030364) (xy 278.987981 -309.028383)
			(xy 278.939762 -309.018539) (xy 278.893746 -309.001087) (xy 278.851125 -308.97648) (xy 278.813004 -308.945355)
			(xy 278.780369 -308.908518) (xy 278.754066 -308.866922) (xy 278.734775 -308.821646) (xy 278.722998 -308.773862)
			(xy 278.719038 -308.724808) (xy 260.925418 -308.724808) (xy 260.889062 -308.756315) (xy 260.843211 -308.785786)
			(xy 260.793633 -308.808432) (xy 260.741337 -308.823792) (xy 260.687387 -308.831554) (xy 260.660134 -308.831996)
			(xy 260.632427 -308.831495) (xy 260.577597 -308.823466) (xy 260.524507 -308.807587) (xy 260.474273 -308.784192)
			(xy 260.427954 -308.753773) (xy 260.386525 -308.716972) (xy 260.368288 -308.696106) (xy 260.368034 -308.695852)
			(xy 260.360868 -308.688242) (xy 260.342118 -308.679047) (xy 260.331712 -308.678072) (xy 260.256782 -308.67477)
			(xy 260.24622 -308.674826) (xy 260.226546 -308.682448) (xy 260.218682 -308.689502) (xy 259.878068 -309.030116)
			(xy 259.871666 -309.037101) (xy 259.864091 -309.054454) (xy 259.863336 -309.063898) (xy 259.860288 -309.142638)
			(xy 259.866384 -309.160672) (xy 259.87248 -309.167784) (xy 259.88957 -309.188565) (xy 259.912946 -309.225496)
			(xy 270.62328 -309.225496) (xy 270.62328 -309.17408) (xy 270.631323 -309.123298) (xy 270.647211 -309.074399)
			(xy 270.670554 -309.028587) (xy 270.700775 -308.986991) (xy 270.737131 -308.950635) (xy 270.778727 -308.920414)
			(xy 270.824539 -308.897071) (xy 270.873438 -308.881183) (xy 270.92422 -308.87314) (xy 270.975636 -308.87314)
			(xy 271.026418 -308.881183) (xy 271.075317 -308.897071) (xy 271.121129 -308.920414) (xy 271.162725 -308.950635)
			(xy 271.199081 -308.986991) (xy 271.229302 -309.028587) (xy 271.252645 -309.074399) (xy 271.268533 -309.123298)
			(xy 271.276576 -309.17408) (xy 271.27708 -309.199788) (xy 271.276576 -309.225496) (xy 271.57324 -309.225496)
			(xy 271.57324 -309.17408) (xy 271.581283 -309.123298) (xy 271.597171 -309.074399) (xy 271.620514 -309.028587)
			(xy 271.650735 -308.986991) (xy 271.687091 -308.950635) (xy 271.728687 -308.920414) (xy 271.774499 -308.897071)
			(xy 271.823398 -308.881183) (xy 271.87418 -308.87314) (xy 271.925596 -308.87314) (xy 271.976378 -308.881183)
			(xy 272.025277 -308.897071) (xy 272.071089 -308.920414) (xy 272.112685 -308.950635) (xy 272.149041 -308.986991)
			(xy 272.179262 -309.028587) (xy 272.202605 -309.074399) (xy 272.218493 -309.123298) (xy 272.226536 -309.17408)
			(xy 272.22704 -309.199788) (xy 272.226536 -309.225496) (xy 273.47316 -309.225496) (xy 273.47316 -309.17408)
			(xy 273.481203 -309.123298) (xy 273.497091 -309.074399) (xy 273.520434 -309.028587) (xy 273.550655 -308.986991)
			(xy 273.587011 -308.950635) (xy 273.628607 -308.920414) (xy 273.674419 -308.897071) (xy 273.723318 -308.881183)
			(xy 273.7741 -308.87314) (xy 273.825516 -308.87314) (xy 273.876298 -308.881183) (xy 273.925197 -308.897071)
			(xy 273.971009 -308.920414) (xy 274.012605 -308.950635) (xy 274.048961 -308.986991) (xy 274.079182 -309.028587)
			(xy 274.102525 -309.074399) (xy 274.118413 -309.123298) (xy 274.126456 -309.17408) (xy 274.12696 -309.199788)
			(xy 274.126456 -309.225496) (xy 274.42312 -309.225496) (xy 274.42312 -309.17408) (xy 274.431163 -309.123298)
			(xy 274.447051 -309.074399) (xy 274.470394 -309.028587) (xy 274.500615 -308.986991) (xy 274.536971 -308.950635)
			(xy 274.578567 -308.920414) (xy 274.624379 -308.897071) (xy 274.673278 -308.881183) (xy 274.72406 -308.87314)
			(xy 274.775476 -308.87314) (xy 274.826258 -308.881183) (xy 274.875157 -308.897071) (xy 274.920969 -308.920414)
			(xy 274.962565 -308.950635) (xy 274.998921 -308.986991) (xy 275.029142 -309.028587) (xy 275.052485 -309.074399)
			(xy 275.068373 -309.123298) (xy 275.076416 -309.17408) (xy 275.07692 -309.199788) (xy 275.076416 -309.225496)
			(xy 275.068373 -309.276278) (xy 275.052485 -309.325177) (xy 275.029142 -309.370989) (xy 274.998921 -309.412585)
			(xy 274.962565 -309.448941) (xy 274.920969 -309.479162) (xy 274.875157 -309.502505) (xy 274.826258 -309.518393)
			(xy 274.775476 -309.526436) (xy 274.72406 -309.526436) (xy 274.673278 -309.518393) (xy 274.624379 -309.502505)
			(xy 274.578567 -309.479162) (xy 274.536971 -309.448941) (xy 274.500615 -309.412585) (xy 274.470394 -309.370989)
			(xy 274.447051 -309.325177) (xy 274.431163 -309.276278) (xy 274.42312 -309.225496) (xy 274.126456 -309.225496)
			(xy 274.118413 -309.276278) (xy 274.102525 -309.325177) (xy 274.079182 -309.370989) (xy 274.048961 -309.412585)
			(xy 274.012605 -309.448941) (xy 273.971009 -309.479162) (xy 273.925197 -309.502505) (xy 273.876298 -309.518393)
			(xy 273.825516 -309.526436) (xy 273.7741 -309.526436) (xy 273.723318 -309.518393) (xy 273.674419 -309.502505)
			(xy 273.628607 -309.479162) (xy 273.587011 -309.448941) (xy 273.550655 -309.412585) (xy 273.520434 -309.370989)
			(xy 273.497091 -309.325177) (xy 273.481203 -309.276278) (xy 273.47316 -309.225496) (xy 272.226536 -309.225496)
			(xy 272.218493 -309.276278) (xy 272.202605 -309.325177) (xy 272.179262 -309.370989) (xy 272.149041 -309.412585)
			(xy 272.112685 -309.448941) (xy 272.071089 -309.479162) (xy 272.025277 -309.502505) (xy 271.976378 -309.518393)
			(xy 271.925596 -309.526436) (xy 271.87418 -309.526436) (xy 271.823398 -309.518393) (xy 271.774499 -309.502505)
			(xy 271.728687 -309.479162) (xy 271.687091 -309.448941) (xy 271.650735 -309.412585) (xy 271.620514 -309.370989)
			(xy 271.597171 -309.325177) (xy 271.581283 -309.276278) (xy 271.57324 -309.225496) (xy 271.276576 -309.225496)
			(xy 271.268533 -309.276278) (xy 271.252645 -309.325177) (xy 271.229302 -309.370989) (xy 271.199081 -309.412585)
			(xy 271.162725 -309.448941) (xy 271.121129 -309.479162) (xy 271.075317 -309.502505) (xy 271.026418 -309.518393)
			(xy 270.975636 -309.526436) (xy 270.92422 -309.526436) (xy 270.873438 -309.518393) (xy 270.824539 -309.502505)
			(xy 270.778727 -309.479162) (xy 270.737131 -309.448941) (xy 270.700775 -309.412585) (xy 270.670554 -309.370989)
			(xy 270.647211 -309.325177) (xy 270.631323 -309.276278) (xy 270.62328 -309.225496) (xy 259.912946 -309.225496)
			(xy 259.918345 -309.234025) (xy 259.940442 -309.283081) (xy 259.955421 -309.334756) (xy 259.962984 -309.388025)
			(xy 259.963412 -309.414926) (xy 259.962924 -309.442176) (xy 259.955165 -309.496121) (xy 259.939808 -309.548413)
			(xy 259.917165 -309.597987) (xy 259.887698 -309.643835) (xy 259.852007 -309.685022) (xy 259.810817 -309.720711)
			(xy 259.764968 -309.750176) (xy 259.715392 -309.772815) (xy 259.6631 -309.78817) (xy 259.609154 -309.795926)
			(xy 259.581904 -309.796434) (xy 259.555004 -309.795973) (xy 259.501739 -309.788411) (xy 259.450065 -309.773439)
			(xy 259.401008 -309.751352) (xy 259.355543 -309.722589) (xy 259.334762 -309.705502) (xy 259.32765 -309.699406)
			(xy 259.309616 -309.69331) (xy 259.230876 -309.696358) (xy 259.221432 -309.697119) (xy 259.204077 -309.704687)
			(xy 259.197094 -309.71109) (xy 258.794267 -310.113934) (xy 261.18642 -310.113934) (xy 261.190491 -310.058312)
			(xy 261.202617 -310.003875) (xy 261.22254 -309.951784) (xy 261.249836 -309.903149) (xy 261.283922 -309.859006)
			(xy 261.324071 -309.820297) (xy 261.369429 -309.787846) (xy 261.419029 -309.762345) (xy 261.471813 -309.744338)
			(xy 261.526656 -309.734208) (xy 261.58239 -309.732171) (xy 261.637827 -309.738271) (xy 261.691784 -309.752377)
			(xy 261.743113 -309.774189) (xy 261.790719 -309.803243) (xy 261.833587 -309.838918) (xy 261.870804 -309.880455)
			(xy 261.901577 -309.926968) (xy 261.925249 -309.977465) (xy 261.941317 -310.030872) (xy 261.949437 -310.086048)
			(xy 261.949946 -310.113934) (xy 261.949437 -310.14182) (xy 261.941317 -310.196996) (xy 261.929168 -310.237378)
			(xy 266.300712 -310.237378) (xy 266.301198 -310.210127) (xy 266.308954 -310.156179) (xy 266.324309 -310.103884)
			(xy 266.346951 -310.054307) (xy 266.376417 -310.008457) (xy 266.412108 -309.967266) (xy 266.453299 -309.931575)
			(xy 266.499149 -309.902109) (xy 266.548726 -309.879467) (xy 266.601021 -309.864112) (xy 266.654969 -309.856356)
			(xy 266.709471 -309.856356) (xy 266.763419 -309.864112) (xy 266.815714 -309.879467) (xy 266.865291 -309.902109)
			(xy 266.911141 -309.931575) (xy 266.952332 -309.967266) (xy 266.988023 -310.008457) (xy 267.017489 -310.054307)
			(xy 267.040131 -310.103884) (xy 267.055486 -310.156179) (xy 267.058257 -310.175456) (xy 268.723106 -310.175456)
			(xy 268.723106 -310.12404) (xy 268.731149 -310.073258) (xy 268.747037 -310.024359) (xy 268.77038 -309.978547)
			(xy 268.800601 -309.936951) (xy 268.836957 -309.900595) (xy 268.878553 -309.870374) (xy 268.924365 -309.847031)
			(xy 268.973264 -309.831143) (xy 269.024046 -309.8231) (xy 269.075462 -309.8231) (xy 269.126244 -309.831143)
			(xy 269.175143 -309.847031) (xy 269.220955 -309.870374) (xy 269.262551 -309.900595) (xy 269.298907 -309.936951)
			(xy 269.329128 -309.978547) (xy 269.352471 -310.024359) (xy 269.368359 -310.073258) (xy 269.376402 -310.12404)
			(xy 269.376906 -310.149748) (xy 269.376402 -310.175456) (xy 269.673066 -310.175456) (xy 269.673066 -310.12404)
			(xy 269.681109 -310.073258) (xy 269.696997 -310.024359) (xy 269.72034 -309.978547) (xy 269.750561 -309.936951)
			(xy 269.786917 -309.900595) (xy 269.828513 -309.870374) (xy 269.874325 -309.847031) (xy 269.923224 -309.831143)
			(xy 269.974006 -309.8231) (xy 270.025422 -309.8231) (xy 270.076204 -309.831143) (xy 270.125103 -309.847031)
			(xy 270.170915 -309.870374) (xy 270.212511 -309.900595) (xy 270.248867 -309.936951) (xy 270.279088 -309.978547)
			(xy 270.302431 -310.024359) (xy 270.318319 -310.073258) (xy 270.326362 -310.12404) (xy 270.326866 -310.149748)
			(xy 270.326362 -310.175456) (xy 270.318319 -310.226238) (xy 270.302431 -310.275137) (xy 270.279088 -310.320949)
			(xy 270.248867 -310.362545) (xy 270.212511 -310.398901) (xy 270.170915 -310.429122) (xy 270.125103 -310.452465)
			(xy 270.076204 -310.468353) (xy 270.025422 -310.476396) (xy 269.974006 -310.476396) (xy 269.923224 -310.468353)
			(xy 269.874325 -310.452465) (xy 269.828513 -310.429122) (xy 269.786917 -310.398901) (xy 269.750561 -310.362545)
			(xy 269.72034 -310.320949) (xy 269.696997 -310.275137) (xy 269.681109 -310.226238) (xy 269.673066 -310.175456)
			(xy 269.376402 -310.175456) (xy 269.368359 -310.226238) (xy 269.352471 -310.275137) (xy 269.329128 -310.320949)
			(xy 269.298907 -310.362545) (xy 269.262551 -310.398901) (xy 269.220955 -310.429122) (xy 269.175143 -310.452465)
			(xy 269.126244 -310.468353) (xy 269.075462 -310.476396) (xy 269.024046 -310.476396) (xy 268.973264 -310.468353)
			(xy 268.924365 -310.452465) (xy 268.878553 -310.429122) (xy 268.836957 -310.398901) (xy 268.800601 -310.362545)
			(xy 268.77038 -310.320949) (xy 268.747037 -310.275137) (xy 268.731149 -310.226238) (xy 268.723106 -310.175456)
			(xy 267.058257 -310.175456) (xy 267.063242 -310.210127) (xy 267.063728 -310.237378) (xy 267.063203 -310.266152)
			(xy 267.054551 -310.323046) (xy 267.037455 -310.377996) (xy 267.012301 -310.429756) (xy 266.979662 -310.477153)
			(xy 266.96035 -310.49849) (xy 266.951009 -310.509061) (xy 266.93809 -310.534129) (xy 266.932524 -310.561776)
			(xy 266.934738 -310.58989) (xy 266.944561 -310.616326) (xy 266.961243 -310.639064) (xy 266.983512 -310.656368)
			(xy 266.996418 -310.662066) (xy 267.022494 -310.673139) (xy 267.071314 -310.701876) (xy 267.115349 -310.737516)
			(xy 267.153631 -310.779275) (xy 267.185318 -310.826234) (xy 267.209715 -310.877362) (xy 267.226283 -310.931535)
			(xy 267.234661 -310.987563) (xy 267.235178 -311.015888) (xy 267.234692 -311.043139) (xy 267.226936 -311.097087)
			(xy 267.218543 -311.12567) (xy 271.57324 -311.12567) (xy 271.57324 -311.074254) (xy 271.581283 -311.023472)
			(xy 271.597171 -310.974573) (xy 271.620514 -310.928761) (xy 271.650735 -310.887165) (xy 271.687091 -310.850809)
			(xy 271.728687 -310.820588) (xy 271.774499 -310.797245) (xy 271.823398 -310.781357) (xy 271.87418 -310.773314)
			(xy 271.925596 -310.773314) (xy 271.976378 -310.781357) (xy 272.025277 -310.797245) (xy 272.071089 -310.820588)
			(xy 272.112685 -310.850809) (xy 272.149041 -310.887165) (xy 272.179262 -310.928761) (xy 272.202605 -310.974573)
			(xy 272.218493 -311.023472) (xy 272.226536 -311.074254) (xy 272.22704 -311.099962) (xy 272.226536 -311.12567)
			(xy 273.47316 -311.12567) (xy 273.47316 -311.074254) (xy 273.481203 -311.023472) (xy 273.497091 -310.974573)
			(xy 273.520434 -310.928761) (xy 273.550655 -310.887165) (xy 273.587011 -310.850809) (xy 273.628607 -310.820588)
			(xy 273.674419 -310.797245) (xy 273.723318 -310.781357) (xy 273.7741 -310.773314) (xy 273.825516 -310.773314)
			(xy 273.876298 -310.781357) (xy 273.925197 -310.797245) (xy 273.971009 -310.820588) (xy 274.012605 -310.850809)
			(xy 274.048961 -310.887165) (xy 274.079182 -310.928761) (xy 274.102525 -310.974573) (xy 274.118413 -311.023472)
			(xy 274.126456 -311.074254) (xy 274.12696 -311.099962) (xy 275.393924 -311.099962) (xy 275.397884 -311.050908)
			(xy 275.409661 -311.003124) (xy 275.428952 -310.957848) (xy 275.455255 -310.916252) (xy 275.48789 -310.879415)
			(xy 275.526011 -310.84829) (xy 275.568632 -310.823683) (xy 275.614648 -310.806231) (xy 275.662867 -310.796387)
			(xy 275.712042 -310.794406) (xy 275.760897 -310.800338) (xy 275.808168 -310.81403) (xy 275.85263 -310.835128)
			(xy 275.893133 -310.863084) (xy 275.928626 -310.897176) (xy 275.958191 -310.93652) (xy 275.981062 -310.980097)
			(xy 275.996646 -311.026778) (xy 276.004541 -311.075355) (xy 276.005036 -311.099962) (xy 277.294098 -311.099962)
			(xy 277.298058 -311.050908) (xy 277.309835 -311.003124) (xy 277.329126 -310.957848) (xy 277.355429 -310.916252)
			(xy 277.388064 -310.879415) (xy 277.426185 -310.84829) (xy 277.468806 -310.823683) (xy 277.514822 -310.806231)
			(xy 277.563041 -310.796387) (xy 277.612216 -310.794406) (xy 277.661071 -310.800338) (xy 277.708342 -310.81403)
			(xy 277.752804 -310.835128) (xy 277.793307 -310.863084) (xy 277.8288 -310.897176) (xy 277.858365 -310.93652)
			(xy 277.881236 -310.980097) (xy 277.89682 -311.026778) (xy 277.904715 -311.075355) (xy 277.90521 -311.099962)
			(xy 279.194018 -311.099962) (xy 279.197978 -311.050908) (xy 279.209755 -311.003124) (xy 279.229046 -310.957848)
			(xy 279.255349 -310.916252) (xy 279.287984 -310.879415) (xy 279.326105 -310.84829) (xy 279.368726 -310.823683)
			(xy 279.414742 -310.806231) (xy 279.462961 -310.796387) (xy 279.512136 -310.794406) (xy 279.560991 -310.800338)
			(xy 279.608262 -310.81403) (xy 279.652724 -310.835128) (xy 279.693227 -310.863084) (xy 279.72872 -310.897176)
			(xy 279.758285 -310.93652) (xy 279.781156 -310.980097) (xy 279.79674 -311.026778) (xy 279.804635 -311.075355)
			(xy 279.80513 -311.099962) (xy 281.093938 -311.099962) (xy 281.097898 -311.050908) (xy 281.109675 -311.003124)
			(xy 281.128966 -310.957848) (xy 281.155269 -310.916252) (xy 281.187904 -310.879415) (xy 281.226025 -310.84829)
			(xy 281.268646 -310.823683) (xy 281.314662 -310.806231) (xy 281.362881 -310.796387) (xy 281.412056 -310.794406)
			(xy 281.460911 -310.800338) (xy 281.508182 -310.81403) (xy 281.552644 -310.835128) (xy 281.593147 -310.863084)
			(xy 281.62864 -310.897176) (xy 281.658205 -310.93652) (xy 281.681076 -310.980097) (xy 281.69666 -311.026778)
			(xy 281.704555 -311.075355) (xy 281.70505 -311.099962) (xy 281.704555 -311.124569) (xy 281.69666 -311.173146)
			(xy 281.681076 -311.219827) (xy 281.658205 -311.263404) (xy 281.62864 -311.302748) (xy 281.593147 -311.33684)
			(xy 281.552644 -311.364796) (xy 281.508182 -311.385894) (xy 281.460911 -311.399586) (xy 281.412056 -311.405518)
			(xy 281.362881 -311.403537) (xy 281.314662 -311.393693) (xy 281.268646 -311.376241) (xy 281.226025 -311.351634)
			(xy 281.187904 -311.320509) (xy 281.155269 -311.283672) (xy 281.128966 -311.242076) (xy 281.109675 -311.1968)
			(xy 281.097898 -311.149016) (xy 281.093938 -311.099962) (xy 279.80513 -311.099962) (xy 279.804635 -311.124569)
			(xy 279.79674 -311.173146) (xy 279.781156 -311.219827) (xy 279.758285 -311.263404) (xy 279.72872 -311.302748)
			(xy 279.693227 -311.33684) (xy 279.652724 -311.364796) (xy 279.608262 -311.385894) (xy 279.560991 -311.399586)
			(xy 279.512136 -311.405518) (xy 279.462961 -311.403537) (xy 279.414742 -311.393693) (xy 279.368726 -311.376241)
			(xy 279.326105 -311.351634) (xy 279.287984 -311.320509) (xy 279.255349 -311.283672) (xy 279.229046 -311.242076)
			(xy 279.209755 -311.1968) (xy 279.197978 -311.149016) (xy 279.194018 -311.099962) (xy 277.90521 -311.099962)
			(xy 277.904715 -311.124569) (xy 277.89682 -311.173146) (xy 277.881236 -311.219827) (xy 277.858365 -311.263404)
			(xy 277.8288 -311.302748) (xy 277.793307 -311.33684) (xy 277.752804 -311.364796) (xy 277.708342 -311.385894)
			(xy 277.661071 -311.399586) (xy 277.612216 -311.405518) (xy 277.563041 -311.403537) (xy 277.514822 -311.393693)
			(xy 277.468806 -311.376241) (xy 277.426185 -311.351634) (xy 277.388064 -311.320509) (xy 277.355429 -311.283672)
			(xy 277.329126 -311.242076) (xy 277.309835 -311.1968) (xy 277.298058 -311.149016) (xy 277.294098 -311.099962)
			(xy 276.005036 -311.099962) (xy 276.004541 -311.124569) (xy 275.996646 -311.173146) (xy 275.981062 -311.219827)
			(xy 275.958191 -311.263404) (xy 275.928626 -311.302748) (xy 275.893133 -311.33684) (xy 275.85263 -311.364796)
			(xy 275.808168 -311.385894) (xy 275.760897 -311.399586) (xy 275.712042 -311.405518) (xy 275.662867 -311.403537)
			(xy 275.614648 -311.393693) (xy 275.568632 -311.376241) (xy 275.526011 -311.351634) (xy 275.48789 -311.320509)
			(xy 275.455255 -311.283672) (xy 275.428952 -311.242076) (xy 275.409661 -311.1968) (xy 275.397884 -311.149016)
			(xy 275.393924 -311.099962) (xy 274.12696 -311.099962) (xy 274.126456 -311.12567) (xy 274.118413 -311.176452)
			(xy 274.102525 -311.225351) (xy 274.079182 -311.271163) (xy 274.048961 -311.312759) (xy 274.012605 -311.349115)
			(xy 273.971009 -311.379336) (xy 273.925197 -311.402679) (xy 273.876298 -311.418567) (xy 273.825516 -311.42661)
			(xy 273.7741 -311.42661) (xy 273.723318 -311.418567) (xy 273.674419 -311.402679) (xy 273.628607 -311.379336)
			(xy 273.587011 -311.349115) (xy 273.550655 -311.312759) (xy 273.520434 -311.271163) (xy 273.497091 -311.225351)
			(xy 273.481203 -311.176452) (xy 273.47316 -311.12567) (xy 272.226536 -311.12567) (xy 272.218493 -311.176452)
			(xy 272.202605 -311.225351) (xy 272.179262 -311.271163) (xy 272.149041 -311.312759) (xy 272.112685 -311.349115)
			(xy 272.071089 -311.379336) (xy 272.025277 -311.402679) (xy 271.976378 -311.418567) (xy 271.925596 -311.42661)
			(xy 271.87418 -311.42661) (xy 271.823398 -311.418567) (xy 271.774499 -311.402679) (xy 271.728687 -311.379336)
			(xy 271.687091 -311.349115) (xy 271.650735 -311.312759) (xy 271.620514 -311.271163) (xy 271.597171 -311.225351)
			(xy 271.581283 -311.176452) (xy 271.57324 -311.12567) (xy 267.218543 -311.12567) (xy 267.211581 -311.149382)
			(xy 267.188939 -311.198959) (xy 267.159473 -311.244809) (xy 267.123782 -311.286) (xy 267.082591 -311.321691)
			(xy 267.036741 -311.351157) (xy 266.987164 -311.373799) (xy 266.934869 -311.389154) (xy 266.880921 -311.39691)
			(xy 266.826419 -311.39691) (xy 266.772471 -311.389154) (xy 266.720176 -311.373799) (xy 266.670599 -311.351157)
			(xy 266.624749 -311.321691) (xy 266.583558 -311.286) (xy 266.547867 -311.244809) (xy 266.518401 -311.198959)
			(xy 266.495759 -311.149382) (xy 266.480404 -311.097087) (xy 266.472648 -311.043139) (xy 266.472162 -311.015888)
			(xy 266.472669 -310.987113) (xy 266.481326 -310.930219) (xy 266.498427 -310.875269) (xy 266.523584 -310.823509)
			(xy 266.556227 -310.776113) (xy 266.57554 -310.754776) (xy 266.584808 -310.744144) (xy 266.597733 -310.719093)
			(xy 266.603308 -310.691461) (xy 266.601106 -310.663358) (xy 266.591296 -310.636931) (xy 266.574626 -310.614199)
			(xy 266.552371 -310.596898) (xy 266.539472 -310.5912) (xy 266.513381 -310.58016) (xy 266.46456 -310.551418)
			(xy 266.420525 -310.515774) (xy 266.382244 -310.47401) (xy 266.350559 -310.427046) (xy 266.326165 -310.375913)
			(xy 266.3096 -310.321736) (xy 266.301227 -310.265705) (xy 266.300712 -310.237378) (xy 261.929168 -310.237378)
			(xy 261.925249 -310.250403) (xy 261.901577 -310.3009) (xy 261.870804 -310.347413) (xy 261.833587 -310.38895)
			(xy 261.790719 -310.424625) (xy 261.743113 -310.453679) (xy 261.691784 -310.475491) (xy 261.637827 -310.489597)
			(xy 261.58239 -310.495697) (xy 261.526656 -310.49366) (xy 261.471813 -310.48353) (xy 261.419029 -310.465523)
			(xy 261.369429 -310.440022) (xy 261.324071 -310.407571) (xy 261.283922 -310.368862) (xy 261.249836 -310.324719)
			(xy 261.22254 -310.276084) (xy 261.202617 -310.223993) (xy 261.190491 -310.169556) (xy 261.18642 -310.113934)
			(xy 258.794267 -310.113934) (xy 257.174068 -311.7342) (xy 264.689334 -311.7342) (xy 264.693405 -311.678578)
			(xy 264.705531 -311.624141) (xy 264.725454 -311.57205) (xy 264.75275 -311.523415) (xy 264.786836 -311.479272)
			(xy 264.826985 -311.440563) (xy 264.872343 -311.408112) (xy 264.921943 -311.382611) (xy 264.974727 -311.364604)
			(xy 265.02957 -311.354474) (xy 265.085304 -311.352437) (xy 265.140741 -311.358537) (xy 265.194698 -311.372643)
			(xy 265.246027 -311.394455) (xy 265.293633 -311.423509) (xy 265.336501 -311.459184) (xy 265.373718 -311.500721)
			(xy 265.404491 -311.547234) (xy 265.428163 -311.597731) (xy 265.444231 -311.651138) (xy 265.452351 -311.706314)
			(xy 265.45286 -311.7342) (xy 265.452351 -311.762086) (xy 265.444231 -311.817262) (xy 265.428163 -311.870669)
			(xy 265.404491 -311.921166) (xy 265.373718 -311.967679) (xy 265.336501 -312.009216) (xy 265.293633 -312.044891)
			(xy 265.246027 -312.073945) (xy 265.194698 -312.095757) (xy 265.140741 -312.109863) (xy 265.085304 -312.115963)
			(xy 265.02957 -312.113926) (xy 264.974727 -312.103796) (xy 264.921943 -312.085789) (xy 264.872343 -312.060288)
			(xy 264.826985 -312.027837) (xy 264.786836 -311.989128) (xy 264.75275 -311.944985) (xy 264.725454 -311.89635)
			(xy 264.705531 -311.844259) (xy 264.693405 -311.789822) (xy 264.689334 -311.7342) (xy 257.174068 -311.7342)
			(xy 256.384923 -312.523378) (xy 263.931906 -312.523378) (xy 263.935977 -312.467756) (xy 263.948103 -312.413319)
			(xy 263.968026 -312.361228) (xy 263.995322 -312.312593) (xy 264.029408 -312.26845) (xy 264.069557 -312.229741)
			(xy 264.114915 -312.19729) (xy 264.164515 -312.171789) (xy 264.217299 -312.153782) (xy 264.272142 -312.143652)
			(xy 264.327876 -312.141615) (xy 264.383313 -312.147715) (xy 264.43727 -312.161821) (xy 264.488599 -312.183633)
			(xy 264.536205 -312.212687) (xy 264.579073 -312.248362) (xy 264.596765 -312.268108) (xy 266.259562 -312.268108)
			(xy 266.263633 -312.212486) (xy 266.275759 -312.158049) (xy 266.295682 -312.105958) (xy 266.322978 -312.057323)
			(xy 266.357064 -312.01318) (xy 266.397213 -311.974471) (xy 266.442571 -311.94202) (xy 266.492171 -311.916519)
			(xy 266.544955 -311.898512) (xy 266.599798 -311.888382) (xy 266.655532 -311.886345) (xy 266.710969 -311.892445)
			(xy 266.764926 -311.906551) (xy 266.816255 -311.928363) (xy 266.863861 -311.957417) (xy 266.906729 -311.993092)
			(xy 266.943946 -312.034629) (xy 266.971072 -312.07563) (xy 268.723106 -312.07563) (xy 268.723106 -312.024214)
			(xy 268.731149 -311.973432) (xy 268.747037 -311.924533) (xy 268.77038 -311.878721) (xy 268.800601 -311.837125)
			(xy 268.836957 -311.800769) (xy 268.878553 -311.770548) (xy 268.924365 -311.747205) (xy 268.973264 -311.731317)
			(xy 269.024046 -311.723274) (xy 269.075462 -311.723274) (xy 269.126244 -311.731317) (xy 269.175143 -311.747205)
			(xy 269.220955 -311.770548) (xy 269.262551 -311.800769) (xy 269.298907 -311.837125) (xy 269.329128 -311.878721)
			(xy 269.352471 -311.924533) (xy 269.368359 -311.973432) (xy 269.376402 -312.024214) (xy 269.376906 -312.049922)
			(xy 269.376402 -312.07563) (xy 269.673066 -312.07563) (xy 269.673066 -312.024214) (xy 269.681109 -311.973432)
			(xy 269.696997 -311.924533) (xy 269.72034 -311.878721) (xy 269.750561 -311.837125) (xy 269.786917 -311.800769)
			(xy 269.828513 -311.770548) (xy 269.874325 -311.747205) (xy 269.923224 -311.731317) (xy 269.974006 -311.723274)
			(xy 270.025422 -311.723274) (xy 270.076204 -311.731317) (xy 270.125103 -311.747205) (xy 270.170915 -311.770548)
			(xy 270.212511 -311.800769) (xy 270.248867 -311.837125) (xy 270.279088 -311.878721) (xy 270.302431 -311.924533)
			(xy 270.318319 -311.973432) (xy 270.326362 -312.024214) (xy 270.326866 -312.049922) (xy 270.326362 -312.07563)
			(xy 271.57324 -312.07563) (xy 271.57324 -312.024214) (xy 271.581283 -311.973432) (xy 271.597171 -311.924533)
			(xy 271.620514 -311.878721) (xy 271.650735 -311.837125) (xy 271.687091 -311.800769) (xy 271.728687 -311.770548)
			(xy 271.774499 -311.747205) (xy 271.823398 -311.731317) (xy 271.87418 -311.723274) (xy 271.925596 -311.723274)
			(xy 271.976378 -311.731317) (xy 272.025277 -311.747205) (xy 272.071089 -311.770548) (xy 272.112685 -311.800769)
			(xy 272.149041 -311.837125) (xy 272.179262 -311.878721) (xy 272.202605 -311.924533) (xy 272.218493 -311.973432)
			(xy 272.226536 -312.024214) (xy 272.22704 -312.049922) (xy 272.226536 -312.07563) (xy 273.47316 -312.07563)
			(xy 273.47316 -312.024214) (xy 273.481203 -311.973432) (xy 273.497091 -311.924533) (xy 273.520434 -311.878721)
			(xy 273.550655 -311.837125) (xy 273.587011 -311.800769) (xy 273.628607 -311.770548) (xy 273.674419 -311.747205)
			(xy 273.723318 -311.731317) (xy 273.7741 -311.723274) (xy 273.825516 -311.723274) (xy 273.876298 -311.731317)
			(xy 273.925197 -311.747205) (xy 273.971009 -311.770548) (xy 274.012605 -311.800769) (xy 274.048961 -311.837125)
			(xy 274.079182 -311.878721) (xy 274.102525 -311.924533) (xy 274.118413 -311.973432) (xy 274.126456 -312.024214)
			(xy 274.12696 -312.049922) (xy 275.393924 -312.049922) (xy 275.397884 -312.000868) (xy 275.409661 -311.953084)
			(xy 275.428952 -311.907808) (xy 275.455255 -311.866212) (xy 275.48789 -311.829375) (xy 275.526011 -311.79825)
			(xy 275.568632 -311.773643) (xy 275.614648 -311.756191) (xy 275.662867 -311.746347) (xy 275.712042 -311.744366)
			(xy 275.760897 -311.750298) (xy 275.808168 -311.76399) (xy 275.85263 -311.785088) (xy 275.893133 -311.813044)
			(xy 275.928626 -311.847136) (xy 275.958191 -311.88648) (xy 275.981062 -311.930057) (xy 275.996646 -311.976738)
			(xy 276.004541 -312.025315) (xy 276.005036 -312.049922) (xy 277.294098 -312.049922) (xy 277.298058 -312.000868)
			(xy 277.309835 -311.953084) (xy 277.329126 -311.907808) (xy 277.355429 -311.866212) (xy 277.388064 -311.829375)
			(xy 277.426185 -311.79825) (xy 277.468806 -311.773643) (xy 277.514822 -311.756191) (xy 277.563041 -311.746347)
			(xy 277.612216 -311.744366) (xy 277.661071 -311.750298) (xy 277.708342 -311.76399) (xy 277.752804 -311.785088)
			(xy 277.793307 -311.813044) (xy 277.8288 -311.847136) (xy 277.858365 -311.88648) (xy 277.881236 -311.930057)
			(xy 277.89682 -311.976738) (xy 277.904715 -312.025315) (xy 277.90521 -312.049922) (xy 279.194018 -312.049922)
			(xy 279.197978 -312.000868) (xy 279.209755 -311.953084) (xy 279.229046 -311.907808) (xy 279.255349 -311.866212)
			(xy 279.287984 -311.829375) (xy 279.326105 -311.79825) (xy 279.368726 -311.773643) (xy 279.414742 -311.756191)
			(xy 279.462961 -311.746347) (xy 279.512136 -311.744366) (xy 279.560991 -311.750298) (xy 279.608262 -311.76399)
			(xy 279.652724 -311.785088) (xy 279.693227 -311.813044) (xy 279.72872 -311.847136) (xy 279.758285 -311.88648)
			(xy 279.781156 -311.930057) (xy 279.79674 -311.976738) (xy 279.804635 -312.025315) (xy 279.80513 -312.049922)
			(xy 281.093938 -312.049922) (xy 281.097898 -312.000868) (xy 281.109675 -311.953084) (xy 281.128966 -311.907808)
			(xy 281.155269 -311.866212) (xy 281.187904 -311.829375) (xy 281.226025 -311.79825) (xy 281.268646 -311.773643)
			(xy 281.314662 -311.756191) (xy 281.362881 -311.746347) (xy 281.412056 -311.744366) (xy 281.460911 -311.750298)
			(xy 281.508182 -311.76399) (xy 281.552644 -311.785088) (xy 281.593147 -311.813044) (xy 281.62864 -311.847136)
			(xy 281.658205 -311.88648) (xy 281.681076 -311.930057) (xy 281.69666 -311.976738) (xy 281.704555 -312.025315)
			(xy 281.70505 -312.049922) (xy 281.704555 -312.074529) (xy 281.69666 -312.123106) (xy 281.681076 -312.169787)
			(xy 281.658205 -312.213364) (xy 281.62864 -312.252708) (xy 281.593147 -312.2868) (xy 281.552644 -312.314756)
			(xy 281.508182 -312.335854) (xy 281.460911 -312.349546) (xy 281.412056 -312.355478) (xy 281.362881 -312.353497)
			(xy 281.314662 -312.343653) (xy 281.268646 -312.326201) (xy 281.226025 -312.301594) (xy 281.187904 -312.270469)
			(xy 281.155269 -312.233632) (xy 281.128966 -312.192036) (xy 281.109675 -312.14676) (xy 281.097898 -312.098976)
			(xy 281.093938 -312.049922) (xy 279.80513 -312.049922) (xy 279.804635 -312.074529) (xy 279.79674 -312.123106)
			(xy 279.781156 -312.169787) (xy 279.758285 -312.213364) (xy 279.72872 -312.252708) (xy 279.693227 -312.2868)
			(xy 279.652724 -312.314756) (xy 279.608262 -312.335854) (xy 279.560991 -312.349546) (xy 279.512136 -312.355478)
			(xy 279.462961 -312.353497) (xy 279.414742 -312.343653) (xy 279.368726 -312.326201) (xy 279.326105 -312.301594)
			(xy 279.287984 -312.270469) (xy 279.255349 -312.233632) (xy 279.229046 -312.192036) (xy 279.209755 -312.14676)
			(xy 279.197978 -312.098976) (xy 279.194018 -312.049922) (xy 277.90521 -312.049922) (xy 277.904715 -312.074529)
			(xy 277.89682 -312.123106) (xy 277.881236 -312.169787) (xy 277.858365 -312.213364) (xy 277.8288 -312.252708)
			(xy 277.793307 -312.2868) (xy 277.752804 -312.314756) (xy 277.708342 -312.335854) (xy 277.661071 -312.349546)
			(xy 277.612216 -312.355478) (xy 277.563041 -312.353497) (xy 277.514822 -312.343653) (xy 277.468806 -312.326201)
			(xy 277.426185 -312.301594) (xy 277.388064 -312.270469) (xy 277.355429 -312.233632) (xy 277.329126 -312.192036)
			(xy 277.309835 -312.14676) (xy 277.298058 -312.098976) (xy 277.294098 -312.049922) (xy 276.005036 -312.049922)
			(xy 276.004541 -312.074529) (xy 275.996646 -312.123106) (xy 275.981062 -312.169787) (xy 275.958191 -312.213364)
			(xy 275.928626 -312.252708) (xy 275.893133 -312.2868) (xy 275.85263 -312.314756) (xy 275.808168 -312.335854)
			(xy 275.760897 -312.349546) (xy 275.712042 -312.355478) (xy 275.662867 -312.353497) (xy 275.614648 -312.343653)
			(xy 275.568632 -312.326201) (xy 275.526011 -312.301594) (xy 275.48789 -312.270469) (xy 275.455255 -312.233632)
			(xy 275.428952 -312.192036) (xy 275.409661 -312.14676) (xy 275.397884 -312.098976) (xy 275.393924 -312.049922)
			(xy 274.12696 -312.049922) (xy 274.126456 -312.07563) (xy 274.118413 -312.126412) (xy 274.102525 -312.175311)
			(xy 274.079182 -312.221123) (xy 274.048961 -312.262719) (xy 274.012605 -312.299075) (xy 273.971009 -312.329296)
			(xy 273.925197 -312.352639) (xy 273.876298 -312.368527) (xy 273.825516 -312.37657) (xy 273.7741 -312.37657)
			(xy 273.723318 -312.368527) (xy 273.674419 -312.352639) (xy 273.628607 -312.329296) (xy 273.587011 -312.299075)
			(xy 273.550655 -312.262719) (xy 273.520434 -312.221123) (xy 273.497091 -312.175311) (xy 273.481203 -312.126412)
			(xy 273.47316 -312.07563) (xy 272.226536 -312.07563) (xy 272.218493 -312.126412) (xy 272.202605 -312.175311)
			(xy 272.179262 -312.221123) (xy 272.149041 -312.262719) (xy 272.112685 -312.299075) (xy 272.071089 -312.329296)
			(xy 272.025277 -312.352639) (xy 271.976378 -312.368527) (xy 271.925596 -312.37657) (xy 271.87418 -312.37657)
			(xy 271.823398 -312.368527) (xy 271.774499 -312.352639) (xy 271.728687 -312.329296) (xy 271.687091 -312.299075)
			(xy 271.650735 -312.262719) (xy 271.620514 -312.221123) (xy 271.597171 -312.175311) (xy 271.581283 -312.126412)
			(xy 271.57324 -312.07563) (xy 270.326362 -312.07563) (xy 270.318319 -312.126412) (xy 270.302431 -312.175311)
			(xy 270.279088 -312.221123) (xy 270.248867 -312.262719) (xy 270.212511 -312.299075) (xy 270.170915 -312.329296)
			(xy 270.125103 -312.352639) (xy 270.076204 -312.368527) (xy 270.025422 -312.37657) (xy 269.974006 -312.37657)
			(xy 269.923224 -312.368527) (xy 269.874325 -312.352639) (xy 269.828513 -312.329296) (xy 269.786917 -312.299075)
			(xy 269.750561 -312.262719) (xy 269.72034 -312.221123) (xy 269.696997 -312.175311) (xy 269.681109 -312.126412)
			(xy 269.673066 -312.07563) (xy 269.376402 -312.07563) (xy 269.368359 -312.126412) (xy 269.352471 -312.175311)
			(xy 269.329128 -312.221123) (xy 269.298907 -312.262719) (xy 269.262551 -312.299075) (xy 269.220955 -312.329296)
			(xy 269.175143 -312.352639) (xy 269.126244 -312.368527) (xy 269.075462 -312.37657) (xy 269.024046 -312.37657)
			(xy 268.973264 -312.368527) (xy 268.924365 -312.352639) (xy 268.878553 -312.329296) (xy 268.836957 -312.299075)
			(xy 268.800601 -312.262719) (xy 268.77038 -312.221123) (xy 268.747037 -312.175311) (xy 268.731149 -312.126412)
			(xy 268.723106 -312.07563) (xy 266.971072 -312.07563) (xy 266.974719 -312.081142) (xy 266.998391 -312.131639)
			(xy 267.014459 -312.185046) (xy 267.022579 -312.240222) (xy 267.023088 -312.268108) (xy 267.022579 -312.295994)
			(xy 267.014459 -312.35117) (xy 266.998391 -312.404577) (xy 266.974719 -312.455074) (xy 266.943946 -312.501587)
			(xy 266.906729 -312.543124) (xy 266.863861 -312.578799) (xy 266.816255 -312.607853) (xy 266.764926 -312.629665)
			(xy 266.710969 -312.643771) (xy 266.655532 -312.649871) (xy 266.599798 -312.647834) (xy 266.544955 -312.637704)
			(xy 266.492171 -312.619697) (xy 266.442571 -312.594196) (xy 266.397213 -312.561745) (xy 266.357064 -312.523036)
			(xy 266.322978 -312.478893) (xy 266.295682 -312.430258) (xy 266.275759 -312.378167) (xy 266.263633 -312.32373)
			(xy 266.259562 -312.268108) (xy 264.596765 -312.268108) (xy 264.61629 -312.289899) (xy 264.647063 -312.336412)
			(xy 264.670735 -312.386909) (xy 264.686803 -312.440316) (xy 264.694923 -312.495492) (xy 264.695432 -312.523378)
			(xy 264.694923 -312.551264) (xy 264.686803 -312.60644) (xy 264.670735 -312.659847) (xy 264.647063 -312.710344)
			(xy 264.61629 -312.756857) (xy 264.579073 -312.798394) (xy 264.536205 -312.834069) (xy 264.488599 -312.863123)
			(xy 264.43727 -312.884935) (xy 264.383313 -312.899041) (xy 264.327876 -312.905141) (xy 264.272142 -312.903104)
			(xy 264.217299 -312.892974) (xy 264.164515 -312.874967) (xy 264.114915 -312.849466) (xy 264.069557 -312.817015)
			(xy 264.029408 -312.778306) (xy 263.995322 -312.734163) (xy 263.968026 -312.685528) (xy 263.948103 -312.633437)
			(xy 263.935977 -312.579) (xy 263.931906 -312.523378) (xy 256.384923 -312.523378) (xy 255.882732 -313.02559)
			(xy 270.62328 -313.02559) (xy 270.62328 -312.974174) (xy 270.631323 -312.923392) (xy 270.647211 -312.874493)
			(xy 270.670554 -312.828681) (xy 270.700775 -312.787085) (xy 270.737131 -312.750729) (xy 270.778727 -312.720508)
			(xy 270.824539 -312.697165) (xy 270.873438 -312.681277) (xy 270.92422 -312.673234) (xy 270.975636 -312.673234)
			(xy 271.026418 -312.681277) (xy 271.075317 -312.697165) (xy 271.121129 -312.720508) (xy 271.162725 -312.750729)
			(xy 271.199081 -312.787085) (xy 271.229302 -312.828681) (xy 271.252645 -312.874493) (xy 271.268533 -312.923392)
			(xy 271.276576 -312.974174) (xy 271.27708 -312.999882) (xy 271.276576 -313.02559) (xy 272.5232 -313.02559)
			(xy 272.5232 -312.974174) (xy 272.531243 -312.923392) (xy 272.547131 -312.874493) (xy 272.570474 -312.828681)
			(xy 272.600695 -312.787085) (xy 272.637051 -312.750729) (xy 272.678647 -312.720508) (xy 272.724459 -312.697165)
			(xy 272.773358 -312.681277) (xy 272.82414 -312.673234) (xy 272.875556 -312.673234) (xy 272.926338 -312.681277)
			(xy 272.975237 -312.697165) (xy 273.021049 -312.720508) (xy 273.062645 -312.750729) (xy 273.099001 -312.787085)
			(xy 273.129222 -312.828681) (xy 273.152565 -312.874493) (xy 273.168453 -312.923392) (xy 273.176496 -312.974174)
			(xy 273.177 -312.999882) (xy 273.176496 -313.02559) (xy 274.42312 -313.02559) (xy 274.42312 -312.974174)
			(xy 274.431163 -312.923392) (xy 274.447051 -312.874493) (xy 274.470394 -312.828681) (xy 274.500615 -312.787085)
			(xy 274.536971 -312.750729) (xy 274.578567 -312.720508) (xy 274.624379 -312.697165) (xy 274.673278 -312.681277)
			(xy 274.72406 -312.673234) (xy 274.775476 -312.673234) (xy 274.826258 -312.681277) (xy 274.875157 -312.697165)
			(xy 274.920969 -312.720508) (xy 274.962565 -312.750729) (xy 274.998921 -312.787085) (xy 275.029142 -312.828681)
			(xy 275.052485 -312.874493) (xy 275.068373 -312.923392) (xy 275.076416 -312.974174) (xy 275.07692 -312.999882)
			(xy 276.343884 -312.999882) (xy 276.347844 -312.950828) (xy 276.359621 -312.903044) (xy 276.378912 -312.857768)
			(xy 276.405215 -312.816172) (xy 276.43785 -312.779335) (xy 276.475971 -312.74821) (xy 276.518592 -312.723603)
			(xy 276.564608 -312.706151) (xy 276.612827 -312.696307) (xy 276.662002 -312.694326) (xy 276.710857 -312.700258)
			(xy 276.758128 -312.71395) (xy 276.80259 -312.735048) (xy 276.843093 -312.763004) (xy 276.878586 -312.797096)
			(xy 276.908151 -312.83644) (xy 276.931022 -312.880017) (xy 276.946606 -312.926698) (xy 276.954501 -312.975275)
			(xy 276.954996 -312.999882) (xy 278.244058 -312.999882) (xy 278.248018 -312.950828) (xy 278.259795 -312.903044)
			(xy 278.279086 -312.857768) (xy 278.305389 -312.816172) (xy 278.338024 -312.779335) (xy 278.376145 -312.74821)
			(xy 278.418766 -312.723603) (xy 278.464782 -312.706151) (xy 278.513001 -312.696307) (xy 278.562176 -312.694326)
			(xy 278.611031 -312.700258) (xy 278.658302 -312.71395) (xy 278.702764 -312.735048) (xy 278.743267 -312.763004)
			(xy 278.77876 -312.797096) (xy 278.808325 -312.83644) (xy 278.831196 -312.880017) (xy 278.84678 -312.926698)
			(xy 278.854675 -312.975275) (xy 278.85517 -312.999882) (xy 280.143978 -312.999882) (xy 280.147938 -312.950828)
			(xy 280.159715 -312.903044) (xy 280.179006 -312.857768) (xy 280.205309 -312.816172) (xy 280.237944 -312.779335)
			(xy 280.276065 -312.74821) (xy 280.318686 -312.723603) (xy 280.364702 -312.706151) (xy 280.412921 -312.696307)
			(xy 280.462096 -312.694326) (xy 280.510951 -312.700258) (xy 280.558222 -312.71395) (xy 280.602684 -312.735048)
			(xy 280.643187 -312.763004) (xy 280.67868 -312.797096) (xy 280.708245 -312.83644) (xy 280.731116 -312.880017)
			(xy 280.7467 -312.926698) (xy 280.754595 -312.975275) (xy 280.75509 -312.999882) (xy 280.754595 -313.024489)
			(xy 280.7467 -313.073066) (xy 280.731116 -313.119747) (xy 280.708245 -313.163324) (xy 280.67868 -313.202668)
			(xy 280.643187 -313.23676) (xy 280.602684 -313.264716) (xy 280.558222 -313.285814) (xy 280.510951 -313.299506)
			(xy 280.462096 -313.305438) (xy 280.412921 -313.303457) (xy 280.364702 -313.293613) (xy 280.318686 -313.276161)
			(xy 280.276065 -313.251554) (xy 280.237944 -313.220429) (xy 280.205309 -313.183592) (xy 280.179006 -313.141996)
			(xy 280.159715 -313.09672) (xy 280.147938 -313.048936) (xy 280.143978 -312.999882) (xy 278.85517 -312.999882)
			(xy 278.854675 -313.024489) (xy 278.84678 -313.073066) (xy 278.831196 -313.119747) (xy 278.808325 -313.163324)
			(xy 278.77876 -313.202668) (xy 278.743267 -313.23676) (xy 278.702764 -313.264716) (xy 278.658302 -313.285814)
			(xy 278.611031 -313.299506) (xy 278.562176 -313.305438) (xy 278.513001 -313.303457) (xy 278.464782 -313.293613)
			(xy 278.418766 -313.276161) (xy 278.376145 -313.251554) (xy 278.338024 -313.220429) (xy 278.305389 -313.183592)
			(xy 278.279086 -313.141996) (xy 278.259795 -313.09672) (xy 278.248018 -313.048936) (xy 278.244058 -312.999882)
			(xy 276.954996 -312.999882) (xy 276.954501 -313.024489) (xy 276.946606 -313.073066) (xy 276.931022 -313.119747)
			(xy 276.908151 -313.163324) (xy 276.878586 -313.202668) (xy 276.843093 -313.23676) (xy 276.80259 -313.264716)
			(xy 276.758128 -313.285814) (xy 276.710857 -313.299506) (xy 276.662002 -313.305438) (xy 276.612827 -313.303457)
			(xy 276.564608 -313.293613) (xy 276.518592 -313.276161) (xy 276.475971 -313.251554) (xy 276.43785 -313.220429)
			(xy 276.405215 -313.183592) (xy 276.378912 -313.141996) (xy 276.359621 -313.09672) (xy 276.347844 -313.048936)
			(xy 276.343884 -312.999882) (xy 275.07692 -312.999882) (xy 275.076416 -313.02559) (xy 275.068373 -313.076372)
			(xy 275.052485 -313.125271) (xy 275.029142 -313.171083) (xy 274.998921 -313.212679) (xy 274.962565 -313.249035)
			(xy 274.920969 -313.279256) (xy 274.875157 -313.302599) (xy 274.826258 -313.318487) (xy 274.775476 -313.32653)
			(xy 274.72406 -313.32653) (xy 274.673278 -313.318487) (xy 274.624379 -313.302599) (xy 274.578567 -313.279256)
			(xy 274.536971 -313.249035) (xy 274.500615 -313.212679) (xy 274.470394 -313.171083) (xy 274.447051 -313.125271)
			(xy 274.431163 -313.076372) (xy 274.42312 -313.02559) (xy 273.176496 -313.02559) (xy 273.168453 -313.076372)
			(xy 273.152565 -313.125271) (xy 273.129222 -313.171083) (xy 273.099001 -313.212679) (xy 273.062645 -313.249035)
			(xy 273.021049 -313.279256) (xy 272.975237 -313.302599) (xy 272.926338 -313.318487) (xy 272.875556 -313.32653)
			(xy 272.82414 -313.32653) (xy 272.773358 -313.318487) (xy 272.724459 -313.302599) (xy 272.678647 -313.279256)
			(xy 272.637051 -313.249035) (xy 272.600695 -313.212679) (xy 272.570474 -313.171083) (xy 272.547131 -313.125271)
			(xy 272.531243 -313.076372) (xy 272.5232 -313.02559) (xy 271.276576 -313.02559) (xy 271.268533 -313.076372)
			(xy 271.252645 -313.125271) (xy 271.229302 -313.171083) (xy 271.199081 -313.212679) (xy 271.162725 -313.249035)
			(xy 271.121129 -313.279256) (xy 271.075317 -313.302599) (xy 271.026418 -313.318487) (xy 270.975636 -313.32653)
			(xy 270.92422 -313.32653) (xy 270.873438 -313.318487) (xy 270.824539 -313.302599) (xy 270.778727 -313.279256)
			(xy 270.737131 -313.249035) (xy 270.700775 -313.212679) (xy 270.670554 -313.171083) (xy 270.647211 -313.125271)
			(xy 270.631323 -313.076372) (xy 270.62328 -313.02559) (xy 255.882732 -313.02559) (xy 255.238414 -313.669934)
			(xy 266.246862 -313.669934) (xy 266.250933 -313.614312) (xy 266.263059 -313.559875) (xy 266.282982 -313.507784)
			(xy 266.310278 -313.459149) (xy 266.344364 -313.415006) (xy 266.384513 -313.376297) (xy 266.429871 -313.343846)
			(xy 266.479471 -313.318345) (xy 266.532255 -313.300338) (xy 266.587098 -313.290208) (xy 266.642832 -313.288171)
			(xy 266.698269 -313.294271) (xy 266.752226 -313.308377) (xy 266.803555 -313.330189) (xy 266.851161 -313.359243)
			(xy 266.894029 -313.394918) (xy 266.931246 -313.436455) (xy 266.962019 -313.482968) (xy 266.985691 -313.533465)
			(xy 267.001759 -313.586872) (xy 267.009879 -313.642048) (xy 267.010388 -313.669934) (xy 267.009879 -313.69782)
			(xy 267.001759 -313.752996) (xy 266.985691 -313.806403) (xy 266.962019 -313.8569) (xy 266.931246 -313.903413)
			(xy 266.894029 -313.94495) (xy 266.857259 -313.97555) (xy 270.62328 -313.97555) (xy 270.62328 -313.924134)
			(xy 270.631323 -313.873352) (xy 270.647211 -313.824453) (xy 270.670554 -313.778641) (xy 270.700775 -313.737045)
			(xy 270.737131 -313.700689) (xy 270.778727 -313.670468) (xy 270.824539 -313.647125) (xy 270.873438 -313.631237)
			(xy 270.92422 -313.623194) (xy 270.975636 -313.623194) (xy 271.026418 -313.631237) (xy 271.075317 -313.647125)
			(xy 271.121129 -313.670468) (xy 271.162725 -313.700689) (xy 271.199081 -313.737045) (xy 271.229302 -313.778641)
			(xy 271.252645 -313.824453) (xy 271.268533 -313.873352) (xy 271.276576 -313.924134) (xy 271.27708 -313.949842)
			(xy 271.276576 -313.97555) (xy 272.5232 -313.97555) (xy 272.5232 -313.924134) (xy 272.531243 -313.873352)
			(xy 272.547131 -313.824453) (xy 272.570474 -313.778641) (xy 272.600695 -313.737045) (xy 272.637051 -313.700689)
			(xy 272.678647 -313.670468) (xy 272.724459 -313.647125) (xy 272.773358 -313.631237) (xy 272.82414 -313.623194)
			(xy 272.875556 -313.623194) (xy 272.926338 -313.631237) (xy 272.975237 -313.647125) (xy 273.021049 -313.670468)
			(xy 273.062645 -313.700689) (xy 273.099001 -313.737045) (xy 273.129222 -313.778641) (xy 273.152565 -313.824453)
			(xy 273.168453 -313.873352) (xy 273.176496 -313.924134) (xy 273.177 -313.949842) (xy 273.176496 -313.97555)
			(xy 274.42312 -313.97555) (xy 274.42312 -313.924134) (xy 274.431163 -313.873352) (xy 274.447051 -313.824453)
			(xy 274.470394 -313.778641) (xy 274.500615 -313.737045) (xy 274.536971 -313.700689) (xy 274.578567 -313.670468)
			(xy 274.624379 -313.647125) (xy 274.673278 -313.631237) (xy 274.72406 -313.623194) (xy 274.775476 -313.623194)
			(xy 274.826258 -313.631237) (xy 274.875157 -313.647125) (xy 274.920969 -313.670468) (xy 274.962565 -313.700689)
			(xy 274.998921 -313.737045) (xy 275.029142 -313.778641) (xy 275.052485 -313.824453) (xy 275.068373 -313.873352)
			(xy 275.076416 -313.924134) (xy 275.07692 -313.949842) (xy 276.343884 -313.949842) (xy 276.347844 -313.900788)
			(xy 276.359621 -313.853004) (xy 276.378912 -313.807728) (xy 276.405215 -313.766132) (xy 276.43785 -313.729295)
			(xy 276.475971 -313.69817) (xy 276.518592 -313.673563) (xy 276.564608 -313.656111) (xy 276.612827 -313.646267)
			(xy 276.662002 -313.644286) (xy 276.710857 -313.650218) (xy 276.758128 -313.66391) (xy 276.80259 -313.685008)
			(xy 276.843093 -313.712964) (xy 276.878586 -313.747056) (xy 276.908151 -313.7864) (xy 276.931022 -313.829977)
			(xy 276.946606 -313.876658) (xy 276.954501 -313.925235) (xy 276.954996 -313.949842) (xy 278.244058 -313.949842)
			(xy 278.248018 -313.900788) (xy 278.259795 -313.853004) (xy 278.279086 -313.807728) (xy 278.305389 -313.766132)
			(xy 278.338024 -313.729295) (xy 278.376145 -313.69817) (xy 278.418766 -313.673563) (xy 278.464782 -313.656111)
			(xy 278.513001 -313.646267) (xy 278.562176 -313.644286) (xy 278.611031 -313.650218) (xy 278.658302 -313.66391)
			(xy 278.702764 -313.685008) (xy 278.743267 -313.712964) (xy 278.77876 -313.747056) (xy 278.808325 -313.7864)
			(xy 278.831196 -313.829977) (xy 278.84678 -313.876658) (xy 278.854675 -313.925235) (xy 278.85517 -313.949842)
			(xy 280.143978 -313.949842) (xy 280.147938 -313.900788) (xy 280.159715 -313.853004) (xy 280.179006 -313.807728)
			(xy 280.205309 -313.766132) (xy 280.237944 -313.729295) (xy 280.276065 -313.69817) (xy 280.318686 -313.673563)
			(xy 280.364702 -313.656111) (xy 280.412921 -313.646267) (xy 280.462096 -313.644286) (xy 280.510951 -313.650218)
			(xy 280.558222 -313.66391) (xy 280.602684 -313.685008) (xy 280.643187 -313.712964) (xy 280.67868 -313.747056)
			(xy 280.708245 -313.7864) (xy 280.731116 -313.829977) (xy 280.7467 -313.876658) (xy 280.754595 -313.925235)
			(xy 280.75509 -313.949842) (xy 280.754595 -313.974449) (xy 280.7467 -314.023026) (xy 280.731116 -314.069707)
			(xy 280.708245 -314.113284) (xy 280.67868 -314.152628) (xy 280.643187 -314.18672) (xy 280.602684 -314.214676)
			(xy 280.558222 -314.235774) (xy 280.510951 -314.249466) (xy 280.462096 -314.255398) (xy 280.412921 -314.253417)
			(xy 280.364702 -314.243573) (xy 280.318686 -314.226121) (xy 280.276065 -314.201514) (xy 280.237944 -314.170389)
			(xy 280.205309 -314.133552) (xy 280.179006 -314.091956) (xy 280.159715 -314.04668) (xy 280.147938 -313.998896)
			(xy 280.143978 -313.949842) (xy 278.85517 -313.949842) (xy 278.854675 -313.974449) (xy 278.84678 -314.023026)
			(xy 278.831196 -314.069707) (xy 278.808325 -314.113284) (xy 278.77876 -314.152628) (xy 278.743267 -314.18672)
			(xy 278.702764 -314.214676) (xy 278.658302 -314.235774) (xy 278.611031 -314.249466) (xy 278.562176 -314.255398)
			(xy 278.513001 -314.253417) (xy 278.464782 -314.243573) (xy 278.418766 -314.226121) (xy 278.376145 -314.201514)
			(xy 278.338024 -314.170389) (xy 278.305389 -314.133552) (xy 278.279086 -314.091956) (xy 278.259795 -314.04668)
			(xy 278.248018 -313.998896) (xy 278.244058 -313.949842) (xy 276.954996 -313.949842) (xy 276.954501 -313.974449)
			(xy 276.946606 -314.023026) (xy 276.931022 -314.069707) (xy 276.908151 -314.113284) (xy 276.878586 -314.152628)
			(xy 276.843093 -314.18672) (xy 276.80259 -314.214676) (xy 276.758128 -314.235774) (xy 276.710857 -314.249466)
			(xy 276.662002 -314.255398) (xy 276.612827 -314.253417) (xy 276.564608 -314.243573) (xy 276.518592 -314.226121)
			(xy 276.475971 -314.201514) (xy 276.43785 -314.170389) (xy 276.405215 -314.133552) (xy 276.378912 -314.091956)
			(xy 276.359621 -314.04668) (xy 276.347844 -313.998896) (xy 276.343884 -313.949842) (xy 275.07692 -313.949842)
			(xy 275.076416 -313.97555) (xy 275.068373 -314.026332) (xy 275.052485 -314.075231) (xy 275.029142 -314.121043)
			(xy 274.998921 -314.162639) (xy 274.962565 -314.198995) (xy 274.920969 -314.229216) (xy 274.875157 -314.252559)
			(xy 274.826258 -314.268447) (xy 274.775476 -314.27649) (xy 274.72406 -314.27649) (xy 274.673278 -314.268447)
			(xy 274.624379 -314.252559) (xy 274.578567 -314.229216) (xy 274.536971 -314.198995) (xy 274.500615 -314.162639)
			(xy 274.470394 -314.121043) (xy 274.447051 -314.075231) (xy 274.431163 -314.026332) (xy 274.42312 -313.97555)
			(xy 273.176496 -313.97555) (xy 273.168453 -314.026332) (xy 273.152565 -314.075231) (xy 273.129222 -314.121043)
			(xy 273.099001 -314.162639) (xy 273.062645 -314.198995) (xy 273.021049 -314.229216) (xy 272.975237 -314.252559)
			(xy 272.926338 -314.268447) (xy 272.875556 -314.27649) (xy 272.82414 -314.27649) (xy 272.773358 -314.268447)
			(xy 272.724459 -314.252559) (xy 272.678647 -314.229216) (xy 272.637051 -314.198995) (xy 272.600695 -314.162639)
			(xy 272.570474 -314.121043) (xy 272.547131 -314.075231) (xy 272.531243 -314.026332) (xy 272.5232 -313.97555)
			(xy 271.276576 -313.97555) (xy 271.268533 -314.026332) (xy 271.252645 -314.075231) (xy 271.229302 -314.121043)
			(xy 271.199081 -314.162639) (xy 271.162725 -314.198995) (xy 271.121129 -314.229216) (xy 271.075317 -314.252559)
			(xy 271.026418 -314.268447) (xy 270.975636 -314.27649) (xy 270.92422 -314.27649) (xy 270.873438 -314.268447)
			(xy 270.824539 -314.252559) (xy 270.778727 -314.229216) (xy 270.737131 -314.198995) (xy 270.700775 -314.162639)
			(xy 270.670554 -314.121043) (xy 270.647211 -314.075231) (xy 270.631323 -314.026332) (xy 270.62328 -313.97555)
			(xy 266.857259 -313.97555) (xy 266.851161 -313.980625) (xy 266.803555 -314.009679) (xy 266.752226 -314.031491)
			(xy 266.698269 -314.045597) (xy 266.642832 -314.051697) (xy 266.587098 -314.04966) (xy 266.532255 -314.03953)
			(xy 266.479471 -314.021523) (xy 266.429871 -313.996022) (xy 266.384513 -313.963571) (xy 266.344364 -313.924862)
			(xy 266.310278 -313.880719) (xy 266.282982 -313.832084) (xy 266.263059 -313.779993) (xy 266.250933 -313.725556)
			(xy 266.246862 -313.669934) (xy 255.238414 -313.669934) (xy 253.98289 -314.92551) (xy 268.723106 -314.92551)
			(xy 268.723106 -314.874094) (xy 268.731149 -314.823312) (xy 268.747037 -314.774413) (xy 268.77038 -314.728601)
			(xy 268.800601 -314.687005) (xy 268.836957 -314.650649) (xy 268.878553 -314.620428) (xy 268.924365 -314.597085)
			(xy 268.973264 -314.581197) (xy 269.024046 -314.573154) (xy 269.075462 -314.573154) (xy 269.126244 -314.581197)
			(xy 269.175143 -314.597085) (xy 269.220955 -314.620428) (xy 269.262551 -314.650649) (xy 269.298907 -314.687005)
			(xy 269.329128 -314.728601) (xy 269.352471 -314.774413) (xy 269.368359 -314.823312) (xy 269.376402 -314.874094)
			(xy 269.376906 -314.899802) (xy 269.376402 -314.92551) (xy 269.673066 -314.92551) (xy 269.673066 -314.874094)
			(xy 269.681109 -314.823312) (xy 269.696997 -314.774413) (xy 269.72034 -314.728601) (xy 269.750561 -314.687005)
			(xy 269.786917 -314.650649) (xy 269.828513 -314.620428) (xy 269.874325 -314.597085) (xy 269.923224 -314.581197)
			(xy 269.974006 -314.573154) (xy 270.025422 -314.573154) (xy 270.076204 -314.581197) (xy 270.125103 -314.597085)
			(xy 270.170915 -314.620428) (xy 270.212511 -314.650649) (xy 270.248867 -314.687005) (xy 270.279088 -314.728601)
			(xy 270.302431 -314.774413) (xy 270.318319 -314.823312) (xy 270.326362 -314.874094) (xy 270.326866 -314.899802)
			(xy 270.326362 -314.92551) (xy 270.318319 -314.976292) (xy 270.302431 -315.025191) (xy 270.279088 -315.071003)
			(xy 270.248867 -315.112599) (xy 270.212511 -315.148955) (xy 270.170915 -315.179176) (xy 270.125103 -315.202519)
			(xy 270.076204 -315.218407) (xy 270.025422 -315.22645) (xy 269.974006 -315.22645) (xy 269.923224 -315.218407)
			(xy 269.874325 -315.202519) (xy 269.828513 -315.179176) (xy 269.786917 -315.148955) (xy 269.750561 -315.112599)
			(xy 269.72034 -315.071003) (xy 269.696997 -315.025191) (xy 269.681109 -314.976292) (xy 269.673066 -314.92551)
			(xy 269.376402 -314.92551) (xy 269.368359 -314.976292) (xy 269.352471 -315.025191) (xy 269.329128 -315.071003)
			(xy 269.298907 -315.112599) (xy 269.262551 -315.148955) (xy 269.220955 -315.179176) (xy 269.175143 -315.202519)
			(xy 269.126244 -315.218407) (xy 269.075462 -315.22645) (xy 269.024046 -315.22645) (xy 268.973264 -315.218407)
			(xy 268.924365 -315.202519) (xy 268.878553 -315.179176) (xy 268.836957 -315.148955) (xy 268.800601 -315.112599)
			(xy 268.77038 -315.071003) (xy 268.747037 -315.025191) (xy 268.731149 -314.976292) (xy 268.723106 -314.92551)
			(xy 253.98289 -314.92551) (xy 253.075186 -315.833252) (xy 253.068339 -315.840649) (xy 253.06061 -315.859248)
			(xy 253.0602 -315.86932) (xy 253.0602 -315.87547) (xy 271.57324 -315.87547) (xy 271.57324 -315.824054)
			(xy 271.581283 -315.773272) (xy 271.597171 -315.724373) (xy 271.620514 -315.678561) (xy 271.650735 -315.636965)
			(xy 271.687091 -315.600609) (xy 271.728687 -315.570388) (xy 271.774499 -315.547045) (xy 271.823398 -315.531157)
			(xy 271.87418 -315.523114) (xy 271.925596 -315.523114) (xy 271.976378 -315.531157) (xy 272.025277 -315.547045)
			(xy 272.071089 -315.570388) (xy 272.112685 -315.600609) (xy 272.149041 -315.636965) (xy 272.179262 -315.678561)
			(xy 272.202605 -315.724373) (xy 272.218493 -315.773272) (xy 272.226536 -315.824054) (xy 272.22704 -315.849762)
			(xy 272.226536 -315.87547) (xy 273.47316 -315.87547) (xy 273.47316 -315.824054) (xy 273.481203 -315.773272)
			(xy 273.497091 -315.724373) (xy 273.520434 -315.678561) (xy 273.550655 -315.636965) (xy 273.587011 -315.600609)
			(xy 273.628607 -315.570388) (xy 273.674419 -315.547045) (xy 273.723318 -315.531157) (xy 273.7741 -315.523114)
			(xy 273.825516 -315.523114) (xy 273.876298 -315.531157) (xy 273.925197 -315.547045) (xy 273.971009 -315.570388)
			(xy 274.012605 -315.600609) (xy 274.048961 -315.636965) (xy 274.079182 -315.678561) (xy 274.102525 -315.724373)
			(xy 274.118413 -315.773272) (xy 274.126456 -315.824054) (xy 274.12696 -315.849762) (xy 274.126456 -315.87547)
			(xy 275.37308 -315.87547) (xy 275.37308 -315.824054) (xy 275.381123 -315.773272) (xy 275.397011 -315.724373)
			(xy 275.420354 -315.678561) (xy 275.450575 -315.636965) (xy 275.486931 -315.600609) (xy 275.528527 -315.570388)
			(xy 275.574339 -315.547045) (xy 275.623238 -315.531157) (xy 275.67402 -315.523114) (xy 275.725436 -315.523114)
			(xy 275.776218 -315.531157) (xy 275.825117 -315.547045) (xy 275.870929 -315.570388) (xy 275.912525 -315.600609)
			(xy 275.948881 -315.636965) (xy 275.979102 -315.678561) (xy 276.002445 -315.724373) (xy 276.018333 -315.773272)
			(xy 276.026376 -315.824054) (xy 276.02688 -315.849762) (xy 276.026376 -315.87547) (xy 277.273254 -315.87547)
			(xy 277.273254 -315.824054) (xy 277.281297 -315.773272) (xy 277.297185 -315.724373) (xy 277.320528 -315.678561)
			(xy 277.350749 -315.636965) (xy 277.387105 -315.600609) (xy 277.428701 -315.570388) (xy 277.474513 -315.547045)
			(xy 277.523412 -315.531157) (xy 277.574194 -315.523114) (xy 277.62561 -315.523114) (xy 277.676392 -315.531157)
			(xy 277.725291 -315.547045) (xy 277.771103 -315.570388) (xy 277.812699 -315.600609) (xy 277.849055 -315.636965)
			(xy 277.879276 -315.678561) (xy 277.902619 -315.724373) (xy 277.918507 -315.773272) (xy 277.92655 -315.824054)
			(xy 277.927054 -315.849762) (xy 277.92655 -315.87547) (xy 279.173174 -315.87547) (xy 279.173174 -315.824054)
			(xy 279.181217 -315.773272) (xy 279.197105 -315.724373) (xy 279.220448 -315.678561) (xy 279.250669 -315.636965)
			(xy 279.287025 -315.600609) (xy 279.328621 -315.570388) (xy 279.374433 -315.547045) (xy 279.423332 -315.531157)
			(xy 279.474114 -315.523114) (xy 279.52553 -315.523114) (xy 279.576312 -315.531157) (xy 279.625211 -315.547045)
			(xy 279.671023 -315.570388) (xy 279.712619 -315.600609) (xy 279.748975 -315.636965) (xy 279.779196 -315.678561)
			(xy 279.802539 -315.724373) (xy 279.818427 -315.773272) (xy 279.82647 -315.824054) (xy 279.826974 -315.849762)
			(xy 279.82647 -315.87547) (xy 281.073094 -315.87547) (xy 281.073094 -315.824054) (xy 281.081137 -315.773272)
			(xy 281.097025 -315.724373) (xy 281.120368 -315.678561) (xy 281.150589 -315.636965) (xy 281.186945 -315.600609)
			(xy 281.228541 -315.570388) (xy 281.274353 -315.547045) (xy 281.323252 -315.531157) (xy 281.374034 -315.523114)
			(xy 281.42545 -315.523114) (xy 281.476232 -315.531157) (xy 281.525131 -315.547045) (xy 281.570943 -315.570388)
			(xy 281.612539 -315.600609) (xy 281.648895 -315.636965) (xy 281.679116 -315.678561) (xy 281.702459 -315.724373)
			(xy 281.718347 -315.773272) (xy 281.72639 -315.824054) (xy 281.726894 -315.849762) (xy 281.72639 -315.87547)
			(xy 281.718347 -315.926252) (xy 281.702459 -315.975151) (xy 281.679116 -316.020963) (xy 281.648895 -316.062559)
			(xy 281.612539 -316.098915) (xy 281.570943 -316.129136) (xy 281.525131 -316.152479) (xy 281.476232 -316.168367)
			(xy 281.42545 -316.17641) (xy 281.374034 -316.17641) (xy 281.323252 -316.168367) (xy 281.274353 -316.152479)
			(xy 281.228541 -316.129136) (xy 281.186945 -316.098915) (xy 281.150589 -316.062559) (xy 281.120368 -316.020963)
			(xy 281.097025 -315.975151) (xy 281.081137 -315.926252) (xy 281.073094 -315.87547) (xy 279.82647 -315.87547)
			(xy 279.818427 -315.926252) (xy 279.802539 -315.975151) (xy 279.779196 -316.020963) (xy 279.748975 -316.062559)
			(xy 279.712619 -316.098915) (xy 279.671023 -316.129136) (xy 279.625211 -316.152479) (xy 279.576312 -316.168367)
			(xy 279.52553 -316.17641) (xy 279.474114 -316.17641) (xy 279.423332 -316.168367) (xy 279.374433 -316.152479)
			(xy 279.328621 -316.129136) (xy 279.287025 -316.098915) (xy 279.250669 -316.062559) (xy 279.220448 -316.020963)
			(xy 279.197105 -315.975151) (xy 279.181217 -315.926252) (xy 279.173174 -315.87547) (xy 277.92655 -315.87547)
			(xy 277.918507 -315.926252) (xy 277.902619 -315.975151) (xy 277.879276 -316.020963) (xy 277.849055 -316.062559)
			(xy 277.812699 -316.098915) (xy 277.771103 -316.129136) (xy 277.725291 -316.152479) (xy 277.676392 -316.168367)
			(xy 277.62561 -316.17641) (xy 277.574194 -316.17641) (xy 277.523412 -316.168367) (xy 277.474513 -316.152479)
			(xy 277.428701 -316.129136) (xy 277.387105 -316.098915) (xy 277.350749 -316.062559) (xy 277.320528 -316.020963)
			(xy 277.297185 -315.975151) (xy 277.281297 -315.926252) (xy 277.273254 -315.87547) (xy 276.026376 -315.87547)
			(xy 276.018333 -315.926252) (xy 276.002445 -315.975151) (xy 275.979102 -316.020963) (xy 275.948881 -316.062559)
			(xy 275.912525 -316.098915) (xy 275.870929 -316.129136) (xy 275.825117 -316.152479) (xy 275.776218 -316.168367)
			(xy 275.725436 -316.17641) (xy 275.67402 -316.17641) (xy 275.623238 -316.168367) (xy 275.574339 -316.152479)
			(xy 275.528527 -316.129136) (xy 275.486931 -316.098915) (xy 275.450575 -316.062559) (xy 275.420354 -316.020963)
			(xy 275.397011 -315.975151) (xy 275.381123 -315.926252) (xy 275.37308 -315.87547) (xy 274.126456 -315.87547)
			(xy 274.118413 -315.926252) (xy 274.102525 -315.975151) (xy 274.079182 -316.020963) (xy 274.048961 -316.062559)
			(xy 274.012605 -316.098915) (xy 273.971009 -316.129136) (xy 273.925197 -316.152479) (xy 273.876298 -316.168367)
			(xy 273.825516 -316.17641) (xy 273.7741 -316.17641) (xy 273.723318 -316.168367) (xy 273.674419 -316.152479)
			(xy 273.628607 -316.129136) (xy 273.587011 -316.098915) (xy 273.550655 -316.062559) (xy 273.520434 -316.020963)
			(xy 273.497091 -315.975151) (xy 273.481203 -315.926252) (xy 273.47316 -315.87547) (xy 272.226536 -315.87547)
			(xy 272.218493 -315.926252) (xy 272.202605 -315.975151) (xy 272.179262 -316.020963) (xy 272.149041 -316.062559)
			(xy 272.112685 -316.098915) (xy 272.071089 -316.129136) (xy 272.025277 -316.152479) (xy 271.976378 -316.168367)
			(xy 271.925596 -316.17641) (xy 271.87418 -316.17641) (xy 271.823398 -316.168367) (xy 271.774499 -316.152479)
			(xy 271.728687 -316.129136) (xy 271.687091 -316.098915) (xy 271.650735 -316.062559) (xy 271.620514 -316.020963)
			(xy 271.597171 -315.975151) (xy 271.581283 -315.926252) (xy 271.57324 -315.87547) (xy 253.0602 -315.87547)
			(xy 253.0602 -316.82543) (xy 268.723106 -316.82543) (xy 268.723106 -316.774014) (xy 268.731149 -316.723232)
			(xy 268.747037 -316.674333) (xy 268.77038 -316.628521) (xy 268.800601 -316.586925) (xy 268.836957 -316.550569)
			(xy 268.878553 -316.520348) (xy 268.924365 -316.497005) (xy 268.973264 -316.481117) (xy 269.024046 -316.473074)
			(xy 269.075462 -316.473074) (xy 269.126244 -316.481117) (xy 269.175143 -316.497005) (xy 269.220955 -316.520348)
			(xy 269.262551 -316.550569) (xy 269.298907 -316.586925) (xy 269.329128 -316.628521) (xy 269.352471 -316.674333)
			(xy 269.368359 -316.723232) (xy 269.376402 -316.774014) (xy 269.376906 -316.799722) (xy 269.376402 -316.82543)
			(xy 269.673066 -316.82543) (xy 269.673066 -316.774014) (xy 269.681109 -316.723232) (xy 269.696997 -316.674333)
			(xy 269.72034 -316.628521) (xy 269.750561 -316.586925) (xy 269.786917 -316.550569) (xy 269.828513 -316.520348)
			(xy 269.874325 -316.497005) (xy 269.923224 -316.481117) (xy 269.974006 -316.473074) (xy 270.025422 -316.473074)
			(xy 270.076204 -316.481117) (xy 270.125103 -316.497005) (xy 270.170915 -316.520348) (xy 270.212511 -316.550569)
			(xy 270.248867 -316.586925) (xy 270.279088 -316.628521) (xy 270.302431 -316.674333) (xy 270.318319 -316.723232)
			(xy 270.326362 -316.774014) (xy 270.326866 -316.799722) (xy 270.326362 -316.82543) (xy 271.57324 -316.82543)
			(xy 271.57324 -316.774014) (xy 271.581283 -316.723232) (xy 271.597171 -316.674333) (xy 271.620514 -316.628521)
			(xy 271.650735 -316.586925) (xy 271.687091 -316.550569) (xy 271.728687 -316.520348) (xy 271.774499 -316.497005)
			(xy 271.823398 -316.481117) (xy 271.87418 -316.473074) (xy 271.925596 -316.473074) (xy 271.976378 -316.481117)
			(xy 272.025277 -316.497005) (xy 272.071089 -316.520348) (xy 272.112685 -316.550569) (xy 272.149041 -316.586925)
			(xy 272.179262 -316.628521) (xy 272.202605 -316.674333) (xy 272.218493 -316.723232) (xy 272.226536 -316.774014)
			(xy 272.22704 -316.799722) (xy 272.226536 -316.82543) (xy 273.47316 -316.82543) (xy 273.47316 -316.774014)
			(xy 273.481203 -316.723232) (xy 273.497091 -316.674333) (xy 273.520434 -316.628521) (xy 273.550655 -316.586925)
			(xy 273.587011 -316.550569) (xy 273.628607 -316.520348) (xy 273.674419 -316.497005) (xy 273.723318 -316.481117)
			(xy 273.7741 -316.473074) (xy 273.825516 -316.473074) (xy 273.876298 -316.481117) (xy 273.925197 -316.497005)
			(xy 273.971009 -316.520348) (xy 274.012605 -316.550569) (xy 274.048961 -316.586925) (xy 274.079182 -316.628521)
			(xy 274.102525 -316.674333) (xy 274.118413 -316.723232) (xy 274.126456 -316.774014) (xy 274.12696 -316.799722)
			(xy 274.126456 -316.82543) (xy 275.37308 -316.82543) (xy 275.37308 -316.774014) (xy 275.381123 -316.723232)
			(xy 275.397011 -316.674333) (xy 275.420354 -316.628521) (xy 275.450575 -316.586925) (xy 275.486931 -316.550569)
			(xy 275.528527 -316.520348) (xy 275.574339 -316.497005) (xy 275.623238 -316.481117) (xy 275.67402 -316.473074)
			(xy 275.725436 -316.473074) (xy 275.776218 -316.481117) (xy 275.825117 -316.497005) (xy 275.870929 -316.520348)
			(xy 275.912525 -316.550569) (xy 275.948881 -316.586925) (xy 275.979102 -316.628521) (xy 276.002445 -316.674333)
			(xy 276.018333 -316.723232) (xy 276.026376 -316.774014) (xy 276.02688 -316.799722) (xy 276.026376 -316.82543)
			(xy 277.273254 -316.82543) (xy 277.273254 -316.774014) (xy 277.281297 -316.723232) (xy 277.297185 -316.674333)
			(xy 277.320528 -316.628521) (xy 277.350749 -316.586925) (xy 277.387105 -316.550569) (xy 277.428701 -316.520348)
			(xy 277.474513 -316.497005) (xy 277.523412 -316.481117) (xy 277.574194 -316.473074) (xy 277.62561 -316.473074)
			(xy 277.676392 -316.481117) (xy 277.725291 -316.497005) (xy 277.771103 -316.520348) (xy 277.812699 -316.550569)
			(xy 277.849055 -316.586925) (xy 277.879276 -316.628521) (xy 277.902619 -316.674333) (xy 277.918507 -316.723232)
			(xy 277.92655 -316.774014) (xy 277.927054 -316.799722) (xy 277.92655 -316.82543) (xy 279.173174 -316.82543)
			(xy 279.173174 -316.774014) (xy 279.181217 -316.723232) (xy 279.197105 -316.674333) (xy 279.220448 -316.628521)
			(xy 279.250669 -316.586925) (xy 279.287025 -316.550569) (xy 279.328621 -316.520348) (xy 279.374433 -316.497005)
			(xy 279.423332 -316.481117) (xy 279.474114 -316.473074) (xy 279.52553 -316.473074) (xy 279.576312 -316.481117)
			(xy 279.625211 -316.497005) (xy 279.671023 -316.520348) (xy 279.712619 -316.550569) (xy 279.748975 -316.586925)
			(xy 279.779196 -316.628521) (xy 279.802539 -316.674333) (xy 279.818427 -316.723232) (xy 279.82647 -316.774014)
			(xy 279.826974 -316.799722) (xy 279.82647 -316.82543) (xy 279.818427 -316.876212) (xy 279.802539 -316.925111)
			(xy 279.779196 -316.970923) (xy 279.748975 -317.012519) (xy 279.712619 -317.048875) (xy 279.671023 -317.079096)
			(xy 279.625211 -317.102439) (xy 279.576312 -317.118327) (xy 279.52553 -317.12637) (xy 279.474114 -317.12637)
			(xy 279.423332 -317.118327) (xy 279.374433 -317.102439) (xy 279.328621 -317.079096) (xy 279.287025 -317.048875)
			(xy 279.250669 -317.012519) (xy 279.220448 -316.970923) (xy 279.197105 -316.925111) (xy 279.181217 -316.876212)
			(xy 279.173174 -316.82543) (xy 277.92655 -316.82543) (xy 277.918507 -316.876212) (xy 277.902619 -316.925111)
			(xy 277.879276 -316.970923) (xy 277.849055 -317.012519) (xy 277.812699 -317.048875) (xy 277.771103 -317.079096)
			(xy 277.725291 -317.102439) (xy 277.676392 -317.118327) (xy 277.62561 -317.12637) (xy 277.574194 -317.12637)
			(xy 277.523412 -317.118327) (xy 277.474513 -317.102439) (xy 277.428701 -317.079096) (xy 277.387105 -317.048875)
			(xy 277.350749 -317.012519) (xy 277.320528 -316.970923) (xy 277.297185 -316.925111) (xy 277.281297 -316.876212)
			(xy 277.273254 -316.82543) (xy 276.026376 -316.82543) (xy 276.018333 -316.876212) (xy 276.002445 -316.925111)
			(xy 275.979102 -316.970923) (xy 275.948881 -317.012519) (xy 275.912525 -317.048875) (xy 275.870929 -317.079096)
			(xy 275.825117 -317.102439) (xy 275.776218 -317.118327) (xy 275.725436 -317.12637) (xy 275.67402 -317.12637)
			(xy 275.623238 -317.118327) (xy 275.574339 -317.102439) (xy 275.528527 -317.079096) (xy 275.486931 -317.048875)
			(xy 275.450575 -317.012519) (xy 275.420354 -316.970923) (xy 275.397011 -316.925111) (xy 275.381123 -316.876212)
			(xy 275.37308 -316.82543) (xy 274.126456 -316.82543) (xy 274.118413 -316.876212) (xy 274.102525 -316.925111)
			(xy 274.079182 -316.970923) (xy 274.048961 -317.012519) (xy 274.012605 -317.048875) (xy 273.971009 -317.079096)
			(xy 273.925197 -317.102439) (xy 273.876298 -317.118327) (xy 273.825516 -317.12637) (xy 273.7741 -317.12637)
			(xy 273.723318 -317.118327) (xy 273.674419 -317.102439) (xy 273.628607 -317.079096) (xy 273.587011 -317.048875)
			(xy 273.550655 -317.012519) (xy 273.520434 -316.970923) (xy 273.497091 -316.925111) (xy 273.481203 -316.876212)
			(xy 273.47316 -316.82543) (xy 272.226536 -316.82543) (xy 272.218493 -316.876212) (xy 272.202605 -316.925111)
			(xy 272.179262 -316.970923) (xy 272.149041 -317.012519) (xy 272.112685 -317.048875) (xy 272.071089 -317.079096)
			(xy 272.025277 -317.102439) (xy 271.976378 -317.118327) (xy 271.925596 -317.12637) (xy 271.87418 -317.12637)
			(xy 271.823398 -317.118327) (xy 271.774499 -317.102439) (xy 271.728687 -317.079096) (xy 271.687091 -317.048875)
			(xy 271.650735 -317.012519) (xy 271.620514 -316.970923) (xy 271.597171 -316.925111) (xy 271.581283 -316.876212)
			(xy 271.57324 -316.82543) (xy 270.326362 -316.82543) (xy 270.318319 -316.876212) (xy 270.302431 -316.925111)
			(xy 270.279088 -316.970923) (xy 270.248867 -317.012519) (xy 270.212511 -317.048875) (xy 270.170915 -317.079096)
			(xy 270.125103 -317.102439) (xy 270.076204 -317.118327) (xy 270.025422 -317.12637) (xy 269.974006 -317.12637)
			(xy 269.923224 -317.118327) (xy 269.874325 -317.102439) (xy 269.828513 -317.079096) (xy 269.786917 -317.048875)
			(xy 269.750561 -317.012519) (xy 269.72034 -316.970923) (xy 269.696997 -316.925111) (xy 269.681109 -316.876212)
			(xy 269.673066 -316.82543) (xy 269.376402 -316.82543) (xy 269.368359 -316.876212) (xy 269.352471 -316.925111)
			(xy 269.329128 -316.970923) (xy 269.298907 -317.012519) (xy 269.262551 -317.048875) (xy 269.220955 -317.079096)
			(xy 269.175143 -317.102439) (xy 269.126244 -317.118327) (xy 269.075462 -317.12637) (xy 269.024046 -317.12637)
			(xy 268.973264 -317.118327) (xy 268.924365 -317.102439) (xy 268.878553 -317.079096) (xy 268.836957 -317.048875)
			(xy 268.800601 -317.012519) (xy 268.77038 -316.970923) (xy 268.747037 -316.925111) (xy 268.731149 -316.876212)
			(xy 268.723106 -316.82543) (xy 253.0602 -316.82543) (xy 253.0602 -317.775644) (xy 270.62328 -317.775644)
			(xy 270.62328 -317.724228) (xy 270.631323 -317.673446) (xy 270.647211 -317.624547) (xy 270.670554 -317.578735)
			(xy 270.700775 -317.537139) (xy 270.737131 -317.500783) (xy 270.778727 -317.470562) (xy 270.824539 -317.447219)
			(xy 270.873438 -317.431331) (xy 270.92422 -317.423288) (xy 270.975636 -317.423288) (xy 271.026418 -317.431331)
			(xy 271.075317 -317.447219) (xy 271.121129 -317.470562) (xy 271.162725 -317.500783) (xy 271.199081 -317.537139)
			(xy 271.229302 -317.578735) (xy 271.252645 -317.624547) (xy 271.268533 -317.673446) (xy 271.276576 -317.724228)
			(xy 271.27708 -317.749936) (xy 271.276576 -317.775644) (xy 272.5232 -317.775644) (xy 272.5232 -317.724228)
			(xy 272.531243 -317.673446) (xy 272.547131 -317.624547) (xy 272.570474 -317.578735) (xy 272.600695 -317.537139)
			(xy 272.637051 -317.500783) (xy 272.678647 -317.470562) (xy 272.724459 -317.447219) (xy 272.773358 -317.431331)
			(xy 272.82414 -317.423288) (xy 272.875556 -317.423288) (xy 272.926338 -317.431331) (xy 272.975237 -317.447219)
			(xy 273.021049 -317.470562) (xy 273.062645 -317.500783) (xy 273.099001 -317.537139) (xy 273.129222 -317.578735)
			(xy 273.152565 -317.624547) (xy 273.168453 -317.673446) (xy 273.176496 -317.724228) (xy 273.177 -317.749936)
			(xy 273.176496 -317.775644) (xy 274.42312 -317.775644) (xy 274.42312 -317.724228) (xy 274.431163 -317.673446)
			(xy 274.447051 -317.624547) (xy 274.470394 -317.578735) (xy 274.500615 -317.537139) (xy 274.536971 -317.500783)
			(xy 274.578567 -317.470562) (xy 274.624379 -317.447219) (xy 274.673278 -317.431331) (xy 274.72406 -317.423288)
			(xy 274.775476 -317.423288) (xy 274.826258 -317.431331) (xy 274.875157 -317.447219) (xy 274.920969 -317.470562)
			(xy 274.962565 -317.500783) (xy 274.998921 -317.537139) (xy 275.029142 -317.578735) (xy 275.052485 -317.624547)
			(xy 275.068373 -317.673446) (xy 275.076416 -317.724228) (xy 275.07692 -317.749936) (xy 275.076416 -317.775644)
			(xy 276.32304 -317.775644) (xy 276.32304 -317.724228) (xy 276.331083 -317.673446) (xy 276.346971 -317.624547)
			(xy 276.370314 -317.578735) (xy 276.400535 -317.537139) (xy 276.436891 -317.500783) (xy 276.478487 -317.470562)
			(xy 276.524299 -317.447219) (xy 276.573198 -317.431331) (xy 276.62398 -317.423288) (xy 276.675396 -317.423288)
			(xy 276.726178 -317.431331) (xy 276.775077 -317.447219) (xy 276.820889 -317.470562) (xy 276.862485 -317.500783)
			(xy 276.898841 -317.537139) (xy 276.929062 -317.578735) (xy 276.952405 -317.624547) (xy 276.968293 -317.673446)
			(xy 276.976336 -317.724228) (xy 276.97684 -317.749936) (xy 276.976336 -317.775644) (xy 278.223214 -317.775644)
			(xy 278.223214 -317.724228) (xy 278.231257 -317.673446) (xy 278.247145 -317.624547) (xy 278.270488 -317.578735)
			(xy 278.300709 -317.537139) (xy 278.337065 -317.500783) (xy 278.378661 -317.470562) (xy 278.424473 -317.447219)
			(xy 278.473372 -317.431331) (xy 278.524154 -317.423288) (xy 278.57557 -317.423288) (xy 278.626352 -317.431331)
			(xy 278.675251 -317.447219) (xy 278.721063 -317.470562) (xy 278.762659 -317.500783) (xy 278.799015 -317.537139)
			(xy 278.829236 -317.578735) (xy 278.852579 -317.624547) (xy 278.868467 -317.673446) (xy 278.87651 -317.724228)
			(xy 278.877014 -317.749936) (xy 278.87651 -317.775644) (xy 280.123134 -317.775644) (xy 280.123134 -317.724228)
			(xy 280.131177 -317.673446) (xy 280.147065 -317.624547) (xy 280.170408 -317.578735) (xy 280.200629 -317.537139)
			(xy 280.236985 -317.500783) (xy 280.278581 -317.470562) (xy 280.324393 -317.447219) (xy 280.373292 -317.431331)
			(xy 280.424074 -317.423288) (xy 280.47549 -317.423288) (xy 280.526272 -317.431331) (xy 280.575171 -317.447219)
			(xy 280.620983 -317.470562) (xy 280.662579 -317.500783) (xy 280.698935 -317.537139) (xy 280.729156 -317.578735)
			(xy 280.752499 -317.624547) (xy 280.768387 -317.673446) (xy 280.77643 -317.724228) (xy 280.776934 -317.749936)
			(xy 280.77643 -317.775644) (xy 280.768387 -317.826426) (xy 280.752499 -317.875325) (xy 280.729156 -317.921137)
			(xy 280.698935 -317.962733) (xy 280.662579 -317.999089) (xy 280.620983 -318.02931) (xy 280.575171 -318.052653)
			(xy 280.526272 -318.068541) (xy 280.47549 -318.076584) (xy 280.424074 -318.076584) (xy 280.373292 -318.068541)
			(xy 280.324393 -318.052653) (xy 280.278581 -318.02931) (xy 280.236985 -317.999089) (xy 280.200629 -317.962733)
			(xy 280.170408 -317.921137) (xy 280.147065 -317.875325) (xy 280.131177 -317.826426) (xy 280.123134 -317.775644)
			(xy 278.87651 -317.775644) (xy 278.868467 -317.826426) (xy 278.852579 -317.875325) (xy 278.829236 -317.921137)
			(xy 278.799015 -317.962733) (xy 278.762659 -317.999089) (xy 278.721063 -318.02931) (xy 278.675251 -318.052653)
			(xy 278.626352 -318.068541) (xy 278.57557 -318.076584) (xy 278.524154 -318.076584) (xy 278.473372 -318.068541)
			(xy 278.424473 -318.052653) (xy 278.378661 -318.02931) (xy 278.337065 -317.999089) (xy 278.300709 -317.962733)
			(xy 278.270488 -317.921137) (xy 278.247145 -317.875325) (xy 278.231257 -317.826426) (xy 278.223214 -317.775644)
			(xy 276.976336 -317.775644) (xy 276.968293 -317.826426) (xy 276.952405 -317.875325) (xy 276.929062 -317.921137)
			(xy 276.898841 -317.962733) (xy 276.862485 -317.999089) (xy 276.820889 -318.02931) (xy 276.775077 -318.052653)
			(xy 276.726178 -318.068541) (xy 276.675396 -318.076584) (xy 276.62398 -318.076584) (xy 276.573198 -318.068541)
			(xy 276.524299 -318.052653) (xy 276.478487 -318.02931) (xy 276.436891 -317.999089) (xy 276.400535 -317.962733)
			(xy 276.370314 -317.921137) (xy 276.346971 -317.875325) (xy 276.331083 -317.826426) (xy 276.32304 -317.775644)
			(xy 275.076416 -317.775644) (xy 275.068373 -317.826426) (xy 275.052485 -317.875325) (xy 275.029142 -317.921137)
			(xy 274.998921 -317.962733) (xy 274.962565 -317.999089) (xy 274.920969 -318.02931) (xy 274.875157 -318.052653)
			(xy 274.826258 -318.068541) (xy 274.775476 -318.076584) (xy 274.72406 -318.076584) (xy 274.673278 -318.068541)
			(xy 274.624379 -318.052653) (xy 274.578567 -318.02931) (xy 274.536971 -317.999089) (xy 274.500615 -317.962733)
			(xy 274.470394 -317.921137) (xy 274.447051 -317.875325) (xy 274.431163 -317.826426) (xy 274.42312 -317.775644)
			(xy 273.176496 -317.775644) (xy 273.168453 -317.826426) (xy 273.152565 -317.875325) (xy 273.129222 -317.921137)
			(xy 273.099001 -317.962733) (xy 273.062645 -317.999089) (xy 273.021049 -318.02931) (xy 272.975237 -318.052653)
			(xy 272.926338 -318.068541) (xy 272.875556 -318.076584) (xy 272.82414 -318.076584) (xy 272.773358 -318.068541)
			(xy 272.724459 -318.052653) (xy 272.678647 -318.02931) (xy 272.637051 -317.999089) (xy 272.600695 -317.962733)
			(xy 272.570474 -317.921137) (xy 272.547131 -317.875325) (xy 272.531243 -317.826426) (xy 272.5232 -317.775644)
			(xy 271.276576 -317.775644) (xy 271.268533 -317.826426) (xy 271.252645 -317.875325) (xy 271.229302 -317.921137)
			(xy 271.199081 -317.962733) (xy 271.162725 -317.999089) (xy 271.121129 -318.02931) (xy 271.075317 -318.052653)
			(xy 271.026418 -318.068541) (xy 270.975636 -318.076584) (xy 270.92422 -318.076584) (xy 270.873438 -318.068541)
			(xy 270.824539 -318.052653) (xy 270.778727 -318.02931) (xy 270.737131 -317.999089) (xy 270.700775 -317.962733)
			(xy 270.670554 -317.921137) (xy 270.647211 -317.875325) (xy 270.631323 -317.826426) (xy 270.62328 -317.775644)
			(xy 253.0602 -317.775644) (xy 253.0602 -319.00876) (xy 253.059764 -319.041215) (xy 253.052499 -319.105718)
			(xy 253.038055 -319.169001) (xy 253.016615 -319.230268) (xy 252.988449 -319.288749) (xy 252.95391 -319.343708)
			(xy 252.913433 -319.394452) (xy 252.890782 -319.4177) (xy 251.408438 -320.900044) (xy 259.082549 -320.900044)
			(xy 259.086538 -320.751504) (xy 259.098495 -320.603391) (xy 259.118385 -320.456134) (xy 259.14615 -320.310158)
			(xy 259.181711 -320.165881) (xy 259.224965 -320.023722) (xy 259.275787 -319.884089) (xy 259.334031 -319.747386)
			(xy 259.399529 -319.614006) (xy 259.472092 -319.484334) (xy 259.55151 -319.358744) (xy 259.637555 -319.237597)
			(xy 259.729979 -319.121244) (xy 259.828515 -319.01002) (xy 259.932879 -318.904245) (xy 260.042771 -318.804225)
			(xy 260.157872 -318.710247) (xy 260.277852 -318.622583) (xy 260.402365 -318.541486) (xy 260.531051 -318.467189)
			(xy 260.66354 -318.399907) (xy 260.799449 -318.339833) (xy 260.938387 -318.287141) (xy 261.079953 -318.241982)
			(xy 261.223739 -318.204487) (xy 261.36933 -318.174765) (xy 261.516306 -318.1529) (xy 261.664245 -318.138956)
			(xy 261.812718 -318.132972) (xy 261.961299 -318.134967) (xy 262.109558 -318.144935) (xy 262.257069 -318.162846)
			(xy 262.403405 -318.188649) (xy 262.548146 -318.222269) (xy 262.690873 -318.263611) (xy 262.831176 -318.312554)
			(xy 262.968649 -318.368957) (xy 263.102896 -318.432658) (xy 263.233531 -318.503474) (xy 263.360176 -318.581199)
			(xy 263.482466 -318.66561) (xy 263.560111 -318.725604) (xy 270.62328 -318.725604) (xy 270.62328 -318.674188)
			(xy 270.631323 -318.623406) (xy 270.647211 -318.574507) (xy 270.670554 -318.528695) (xy 270.700775 -318.487099)
			(xy 270.737131 -318.450743) (xy 270.778727 -318.420522) (xy 270.824539 -318.397179) (xy 270.873438 -318.381291)
			(xy 270.92422 -318.373248) (xy 270.975636 -318.373248) (xy 271.026418 -318.381291) (xy 271.075317 -318.397179)
			(xy 271.121129 -318.420522) (xy 271.162725 -318.450743) (xy 271.199081 -318.487099) (xy 271.229302 -318.528695)
			(xy 271.252645 -318.574507) (xy 271.268533 -318.623406) (xy 271.276576 -318.674188) (xy 271.27708 -318.699896)
			(xy 271.276576 -318.725604) (xy 272.5232 -318.725604) (xy 272.5232 -318.674188) (xy 272.531243 -318.623406)
			(xy 272.547131 -318.574507) (xy 272.570474 -318.528695) (xy 272.600695 -318.487099) (xy 272.637051 -318.450743)
			(xy 272.678647 -318.420522) (xy 272.724459 -318.397179) (xy 272.773358 -318.381291) (xy 272.82414 -318.373248)
			(xy 272.875556 -318.373248) (xy 272.926338 -318.381291) (xy 272.975237 -318.397179) (xy 273.021049 -318.420522)
			(xy 273.062645 -318.450743) (xy 273.099001 -318.487099) (xy 273.129222 -318.528695) (xy 273.152565 -318.574507)
			(xy 273.168453 -318.623406) (xy 273.176496 -318.674188) (xy 273.177 -318.699896) (xy 273.176496 -318.725604)
			(xy 274.42312 -318.725604) (xy 274.42312 -318.674188) (xy 274.431163 -318.623406) (xy 274.447051 -318.574507)
			(xy 274.470394 -318.528695) (xy 274.500615 -318.487099) (xy 274.536971 -318.450743) (xy 274.578567 -318.420522)
			(xy 274.624379 -318.397179) (xy 274.673278 -318.381291) (xy 274.72406 -318.373248) (xy 274.775476 -318.373248)
			(xy 274.826258 -318.381291) (xy 274.875157 -318.397179) (xy 274.920969 -318.420522) (xy 274.962565 -318.450743)
			(xy 274.998921 -318.487099) (xy 275.029142 -318.528695) (xy 275.052485 -318.574507) (xy 275.068373 -318.623406)
			(xy 275.076416 -318.674188) (xy 275.07692 -318.699896) (xy 275.076416 -318.725604) (xy 276.32304 -318.725604)
			(xy 276.32304 -318.674188) (xy 276.331083 -318.623406) (xy 276.346971 -318.574507) (xy 276.370314 -318.528695)
			(xy 276.400535 -318.487099) (xy 276.436891 -318.450743) (xy 276.478487 -318.420522) (xy 276.524299 -318.397179)
			(xy 276.573198 -318.381291) (xy 276.62398 -318.373248) (xy 276.675396 -318.373248) (xy 276.726178 -318.381291)
			(xy 276.775077 -318.397179) (xy 276.820889 -318.420522) (xy 276.862485 -318.450743) (xy 276.898841 -318.487099)
			(xy 276.929062 -318.528695) (xy 276.952405 -318.574507) (xy 276.968293 -318.623406) (xy 276.976336 -318.674188)
			(xy 276.97684 -318.699896) (xy 276.976336 -318.725604) (xy 278.223214 -318.725604) (xy 278.223214 -318.674188)
			(xy 278.231257 -318.623406) (xy 278.247145 -318.574507) (xy 278.270488 -318.528695) (xy 278.300709 -318.487099)
			(xy 278.337065 -318.450743) (xy 278.378661 -318.420522) (xy 278.424473 -318.397179) (xy 278.473372 -318.381291)
			(xy 278.524154 -318.373248) (xy 278.57557 -318.373248) (xy 278.626352 -318.381291) (xy 278.675251 -318.397179)
			(xy 278.721063 -318.420522) (xy 278.762659 -318.450743) (xy 278.799015 -318.487099) (xy 278.829236 -318.528695)
			(xy 278.852579 -318.574507) (xy 278.868467 -318.623406) (xy 278.87651 -318.674188) (xy 278.877014 -318.699896)
			(xy 278.87651 -318.725604) (xy 280.123134 -318.725604) (xy 280.123134 -318.674188) (xy 280.131177 -318.623406)
			(xy 280.147065 -318.574507) (xy 280.170408 -318.528695) (xy 280.200629 -318.487099) (xy 280.236985 -318.450743)
			(xy 280.278581 -318.420522) (xy 280.324393 -318.397179) (xy 280.373292 -318.381291) (xy 280.424074 -318.373248)
			(xy 280.47549 -318.373248) (xy 280.526272 -318.381291) (xy 280.575171 -318.397179) (xy 280.620983 -318.420522)
			(xy 280.662579 -318.450743) (xy 280.698935 -318.487099) (xy 280.729156 -318.528695) (xy 280.752499 -318.574507)
			(xy 280.768387 -318.623406) (xy 280.77643 -318.674188) (xy 280.776934 -318.699896) (xy 280.77643 -318.725604)
			(xy 280.768387 -318.776386) (xy 280.752499 -318.825285) (xy 280.729156 -318.871097) (xy 280.698935 -318.912693)
			(xy 280.662579 -318.949049) (xy 280.620983 -318.97927) (xy 280.575171 -319.002613) (xy 280.526272 -319.018501)
			(xy 280.47549 -319.026544) (xy 280.424074 -319.026544) (xy 280.373292 -319.018501) (xy 280.324393 -319.002613)
			(xy 280.278581 -318.97927) (xy 280.236985 -318.949049) (xy 280.200629 -318.912693) (xy 280.170408 -318.871097)
			(xy 280.147065 -318.825285) (xy 280.131177 -318.776386) (xy 280.123134 -318.725604) (xy 278.87651 -318.725604)
			(xy 278.868467 -318.776386) (xy 278.852579 -318.825285) (xy 278.829236 -318.871097) (xy 278.799015 -318.912693)
			(xy 278.762659 -318.949049) (xy 278.721063 -318.97927) (xy 278.675251 -319.002613) (xy 278.626352 -319.018501)
			(xy 278.57557 -319.026544) (xy 278.524154 -319.026544) (xy 278.473372 -319.018501) (xy 278.424473 -319.002613)
			(xy 278.378661 -318.97927) (xy 278.337065 -318.949049) (xy 278.300709 -318.912693) (xy 278.270488 -318.871097)
			(xy 278.247145 -318.825285) (xy 278.231257 -318.776386) (xy 278.223214 -318.725604) (xy 276.976336 -318.725604)
			(xy 276.968293 -318.776386) (xy 276.952405 -318.825285) (xy 276.929062 -318.871097) (xy 276.898841 -318.912693)
			(xy 276.862485 -318.949049) (xy 276.820889 -318.97927) (xy 276.775077 -319.002613) (xy 276.726178 -319.018501)
			(xy 276.675396 -319.026544) (xy 276.62398 -319.026544) (xy 276.573198 -319.018501) (xy 276.524299 -319.002613)
			(xy 276.478487 -318.97927) (xy 276.436891 -318.949049) (xy 276.400535 -318.912693) (xy 276.370314 -318.871097)
			(xy 276.346971 -318.825285) (xy 276.331083 -318.776386) (xy 276.32304 -318.725604) (xy 275.076416 -318.725604)
			(xy 275.068373 -318.776386) (xy 275.052485 -318.825285) (xy 275.029142 -318.871097) (xy 274.998921 -318.912693)
			(xy 274.962565 -318.949049) (xy 274.920969 -318.97927) (xy 274.875157 -319.002613) (xy 274.826258 -319.018501)
			(xy 274.775476 -319.026544) (xy 274.72406 -319.026544) (xy 274.673278 -319.018501) (xy 274.624379 -319.002613)
			(xy 274.578567 -318.97927) (xy 274.536971 -318.949049) (xy 274.500615 -318.912693) (xy 274.470394 -318.871097)
			(xy 274.447051 -318.825285) (xy 274.431163 -318.776386) (xy 274.42312 -318.725604) (xy 273.176496 -318.725604)
			(xy 273.168453 -318.776386) (xy 273.152565 -318.825285) (xy 273.129222 -318.871097) (xy 273.099001 -318.912693)
			(xy 273.062645 -318.949049) (xy 273.021049 -318.97927) (xy 272.975237 -319.002613) (xy 272.926338 -319.018501)
			(xy 272.875556 -319.026544) (xy 272.82414 -319.026544) (xy 272.773358 -319.018501) (xy 272.724459 -319.002613)
			(xy 272.678647 -318.97927) (xy 272.637051 -318.949049) (xy 272.600695 -318.912693) (xy 272.570474 -318.871097)
			(xy 272.547131 -318.825285) (xy 272.531243 -318.776386) (xy 272.5232 -318.725604) (xy 271.276576 -318.725604)
			(xy 271.268533 -318.776386) (xy 271.252645 -318.825285) (xy 271.229302 -318.871097) (xy 271.199081 -318.912693)
			(xy 271.162725 -318.949049) (xy 271.121129 -318.97927) (xy 271.075317 -319.002613) (xy 271.026418 -319.018501)
			(xy 270.975636 -319.026544) (xy 270.92422 -319.026544) (xy 270.873438 -319.018501) (xy 270.824539 -319.002613)
			(xy 270.778727 -318.97927) (xy 270.737131 -318.949049) (xy 270.700775 -318.912693) (xy 270.670554 -318.871097)
			(xy 270.647211 -318.825285) (xy 270.631323 -318.776386) (xy 270.62328 -318.725604) (xy 263.560111 -318.725604)
			(xy 263.600049 -318.756463) (xy 263.712586 -318.853497) (xy 263.819753 -318.956432) (xy 263.92124 -319.064971)
			(xy 264.016754 -319.1788) (xy 264.106021 -319.297593) (xy 264.188782 -319.421005) (xy 264.2648 -319.548683)
			(xy 264.333855 -319.680256) (xy 264.395748 -319.815347) (xy 264.450301 -319.953564) (xy 264.497356 -320.094511)
			(xy 264.536778 -320.237781) (xy 264.568452 -320.38296) (xy 264.592288 -320.529629) (xy 264.608217 -320.677367)
			(xy 264.616193 -320.825747) (xy 264.616692 -320.900044) (xy 264.616193 -320.974341) (xy 264.608217 -321.122721)
			(xy 264.592288 -321.270459) (xy 264.568452 -321.417128) (xy 264.536778 -321.562307) (xy 264.497356 -321.705577)
			(xy 264.450301 -321.846524) (xy 264.395748 -321.984741) (xy 264.333855 -322.119832) (xy 264.2648 -322.251405)
			(xy 264.188782 -322.379083) (xy 264.106021 -322.502495) (xy 264.016754 -322.621288) (xy 263.92124 -322.735117)
			(xy 263.819753 -322.843656) (xy 263.712586 -322.946591) (xy 263.600049 -323.043625) (xy 263.482466 -323.134478)
			(xy 263.360176 -323.218889) (xy 263.233531 -323.296614) (xy 263.102896 -323.36743) (xy 262.968649 -323.431131)
			(xy 262.831176 -323.487534) (xy 262.690873 -323.536477) (xy 262.548146 -323.577819) (xy 262.403405 -323.611439)
			(xy 262.257069 -323.637242) (xy 262.109558 -323.655153) (xy 261.961299 -323.665121) (xy 261.812718 -323.667116)
			(xy 261.664245 -323.661132) (xy 261.516306 -323.647188) (xy 261.36933 -323.625323) (xy 261.223739 -323.595601)
			(xy 261.079953 -323.558106) (xy 260.938387 -323.512947) (xy 260.799449 -323.460255) (xy 260.66354 -323.400181)
			(xy 260.531051 -323.332899) (xy 260.402365 -323.258602) (xy 260.277852 -323.177505) (xy 260.157872 -323.089841)
			(xy 260.042771 -322.995863) (xy 259.932879 -322.895843) (xy 259.828515 -322.790068) (xy 259.729979 -322.678844)
			(xy 259.637555 -322.562491) (xy 259.55151 -322.441344) (xy 259.472092 -322.315754) (xy 259.399529 -322.186082)
			(xy 259.334031 -322.052702) (xy 259.275787 -321.915999) (xy 259.224965 -321.776366) (xy 259.181711 -321.634207)
			(xy 259.14615 -321.48993) (xy 259.118385 -321.343954) (xy 259.098495 -321.196697) (xy 259.086538 -321.048584)
			(xy 259.082549 -320.900044) (xy 251.408438 -320.900044) (xy 244.921532 -327.38695) (xy 248.284236 -327.38695)
			(xy 248.288307 -327.331328) (xy 248.300433 -327.276891) (xy 248.320356 -327.2248) (xy 248.347652 -327.176165)
			(xy 248.381738 -327.132022) (xy 248.421887 -327.093313) (xy 248.467245 -327.060862) (xy 248.516845 -327.035361)
			(xy 248.569629 -327.017354) (xy 248.624472 -327.007224) (xy 248.680206 -327.005187) (xy 248.735643 -327.011287)
			(xy 248.7896 -327.025393) (xy 248.840929 -327.047205) (xy 248.888535 -327.076259) (xy 248.931403 -327.111934)
			(xy 248.96862 -327.153471) (xy 248.999393 -327.199984) (xy 249.023065 -327.250481) (xy 249.039133 -327.303888)
			(xy 249.047253 -327.359064) (xy 249.047762 -327.38695) (xy 249.047253 -327.414836) (xy 249.039133 -327.470012)
			(xy 249.023065 -327.523419) (xy 248.999393 -327.573916) (xy 248.96862 -327.620429) (xy 248.931403 -327.661966)
			(xy 248.888535 -327.697641) (xy 248.840929 -327.726695) (xy 248.7896 -327.748507) (xy 248.735643 -327.762613)
			(xy 248.680206 -327.768713) (xy 248.624472 -327.766676) (xy 248.569629 -327.756546) (xy 248.516845 -327.738539)
			(xy 248.467245 -327.713038) (xy 248.421887 -327.680587) (xy 248.381738 -327.641878) (xy 248.347652 -327.597735)
			(xy 248.320356 -327.5491) (xy 248.300433 -327.497009) (xy 248.288307 -327.442572) (xy 248.284236 -327.38695)
			(xy 244.921532 -327.38695) (xy 244.407182 -327.9013) (xy 247.264172 -327.9013) (xy 247.268243 -327.845678)
			(xy 247.280369 -327.791241) (xy 247.300292 -327.73915) (xy 247.327588 -327.690515) (xy 247.361674 -327.646372)
			(xy 247.401823 -327.607663) (xy 247.447181 -327.575212) (xy 247.496781 -327.549711) (xy 247.549565 -327.531704)
			(xy 247.604408 -327.521574) (xy 247.660142 -327.519537) (xy 247.715579 -327.525637) (xy 247.769536 -327.539743)
			(xy 247.820865 -327.561555) (xy 247.868471 -327.590609) (xy 247.911339 -327.626284) (xy 247.948556 -327.667821)
			(xy 247.979329 -327.714334) (xy 248.003001 -327.764831) (xy 248.019069 -327.818238) (xy 248.027189 -327.873414)
			(xy 248.027698 -327.9013) (xy 248.027189 -327.929186) (xy 248.019069 -327.984362) (xy 248.003001 -328.037769)
			(xy 247.979329 -328.088266) (xy 247.948556 -328.134779) (xy 247.911339 -328.176316) (xy 247.868471 -328.211991)
			(xy 247.820865 -328.241045) (xy 247.769536 -328.262857) (xy 247.715579 -328.276963) (xy 247.660142 -328.283063)
			(xy 247.604408 -328.281026) (xy 247.549565 -328.270896) (xy 247.496781 -328.252889) (xy 247.447181 -328.227388)
			(xy 247.401823 -328.194937) (xy 247.361674 -328.156228) (xy 247.327588 -328.112085) (xy 247.300292 -328.06345)
			(xy 247.280369 -328.011359) (xy 247.268243 -327.956922) (xy 247.264172 -327.9013) (xy 244.407182 -327.9013)
			(xy 243.787327 -328.521155) (xy 266.319437 -328.521155) (xy 266.319437 -328.466645) (xy 266.327194 -328.412691)
			(xy 266.342552 -328.36039) (xy 266.365196 -328.310807) (xy 266.394666 -328.264951) (xy 266.430362 -328.223757)
			(xy 266.471558 -328.188061) (xy 266.517414 -328.158592) (xy 266.566998 -328.135949) (xy 266.619299 -328.120593)
			(xy 266.673253 -328.112836) (xy 266.700508 -328.112374) (xy 266.729661 -328.112946) (xy 266.787288 -328.121812)
			(xy 266.842897 -328.139336) (xy 266.895195 -328.165112) (xy 266.942966 -328.198539) (xy 266.964414 -328.218292)
			(xy 266.97178 -328.225404) (xy 266.990068 -328.23277) (xy 267.071094 -328.231754) (xy 267.080842 -328.231227)
			(xy 267.098871 -328.223785) (xy 267.106146 -328.217276) (xy 267.1064 -328.217022) (xy 267.127992 -328.19632)
			(xy 267.176429 -328.161227) (xy 267.229752 -328.134126) (xy 267.286651 -328.115683) (xy 267.345733 -328.10635)
			(xy 267.37564 -328.10577) (xy 267.402888 -328.106303) (xy 267.456828 -328.114064) (xy 267.509115 -328.129421)
			(xy 267.558684 -328.152063) (xy 267.604527 -328.181529) (xy 267.64571 -328.217218) (xy 267.681395 -328.258405)
			(xy 267.710856 -328.304251) (xy 267.733493 -328.353823) (xy 267.748845 -328.406111) (xy 267.7566 -328.460052)
			(xy 267.7566 -328.514548) (xy 267.748845 -328.568489) (xy 267.733493 -328.620777) (xy 267.710856 -328.670349)
			(xy 267.681395 -328.716195) (xy 267.64571 -328.757382) (xy 267.604527 -328.793071) (xy 267.558684 -328.822537)
			(xy 267.509115 -328.845179) (xy 267.456828 -328.860536) (xy 267.402888 -328.868297) (xy 267.37564 -328.868786)
			(xy 267.346486 -328.868257) (xy 267.288856 -328.859383) (xy 267.233246 -328.841849) (xy 267.180949 -328.816063)
			(xy 267.13318 -328.782626) (xy 267.111734 -328.762868) (xy 267.104368 -328.755756) (xy 267.08608 -328.74839)
			(xy 267.005054 -328.749406) (xy 266.995306 -328.749941) (xy 266.977277 -328.757376) (xy 266.970002 -328.763884)
			(xy 266.969748 -328.764138) (xy 266.948128 -328.78481) (xy 266.8997 -328.819909) (xy 266.846384 -328.847016)
			(xy 266.78949 -328.865466) (xy 266.730413 -328.874806) (xy 266.700508 -328.87539) (xy 266.673253 -328.874964)
			(xy 266.619299 -328.867207) (xy 266.566998 -328.851851) (xy 266.517414 -328.829208) (xy 266.471558 -328.799739)
			(xy 266.430362 -328.764043) (xy 266.394666 -328.722849) (xy 266.365196 -328.676993) (xy 266.342552 -328.62741)
			(xy 266.327194 -328.575109) (xy 266.319437 -328.521155) (xy 243.787327 -328.521155) (xy 242.862862 -329.44562)
			(xy 242.856012 -329.453017) (xy 242.848275 -329.471615) (xy 242.847876 -329.481688) (xy 242.847876 -331.037438)
			(xy 249.7615 -331.037438) (xy 249.765571 -330.981816) (xy 249.777697 -330.927379) (xy 249.79762 -330.875288)
			(xy 249.824916 -330.826653) (xy 249.859002 -330.78251) (xy 249.899151 -330.743801) (xy 249.944509 -330.71135)
			(xy 249.994109 -330.685849) (xy 250.046893 -330.667842) (xy 250.101736 -330.657712) (xy 250.15747 -330.655675)
			(xy 250.212907 -330.661775) (xy 250.266864 -330.675881) (xy 250.318193 -330.697693) (xy 250.365799 -330.726747)
			(xy 250.408667 -330.762422) (xy 250.445884 -330.803959) (xy 250.476657 -330.850472) (xy 250.500329 -330.900969)
			(xy 250.516397 -330.954376) (xy 250.524517 -331.009552) (xy 250.525026 -331.037438) (xy 250.524517 -331.065324)
			(xy 250.516397 -331.1205) (xy 250.500329 -331.173907) (xy 250.476657 -331.224404) (xy 250.445884 -331.270917)
			(xy 250.408667 -331.312454) (xy 250.365799 -331.348129) (xy 250.318193 -331.377183) (xy 250.266864 -331.398995)
			(xy 250.212907 -331.413101) (xy 250.15747 -331.419201) (xy 250.101736 -331.417164) (xy 250.046893 -331.407034)
			(xy 249.994109 -331.389027) (xy 249.944509 -331.363526) (xy 249.899151 -331.331075) (xy 249.859002 -331.292366)
			(xy 249.824916 -331.248223) (xy 249.79762 -331.199588) (xy 249.777697 -331.147497) (xy 249.765571 -331.09306)
			(xy 249.7615 -331.037438) (xy 242.847876 -331.037438) (xy 242.847876 -331.585824) (xy 242.847441 -331.61828)
			(xy 242.84018 -331.682784) (xy 242.825739 -331.746069) (xy 242.804301 -331.807339) (xy 242.776136 -331.865821)
			(xy 242.741598 -331.920782) (xy 242.701122 -331.971528) (xy 242.678458 -331.994764) (xy 239.93983 -334.733392)
			(xy 239.933888 -334.739929) (xy 239.92644 -334.755933) (xy 239.924818 -334.773511) (xy 239.926622 -334.78216)
			(xy 239.948974 -334.866996) (xy 239.984534 -334.903064) (xy 240.017816 -334.912774) (xy 240.082008 -334.938969)
			(xy 240.142659 -334.972561) (xy 240.19892 -335.013077) (xy 240.250004 -335.059952) (xy 240.295196 -335.112531)
			(xy 240.333865 -335.170077) (xy 240.36547 -335.231786) (xy 240.389569 -335.296794) (xy 240.405824 -335.364193)
			(xy 240.414009 -335.43304) (xy 240.414556 -335.467706) (xy 240.414556 -335.472024) (xy 251.205236 -335.472024)
			(xy 251.209307 -335.416402) (xy 251.221433 -335.361965) (xy 251.241356 -335.309874) (xy 251.268652 -335.261239)
			(xy 251.302738 -335.217096) (xy 251.342887 -335.178387) (xy 251.388245 -335.145936) (xy 251.437845 -335.120435)
			(xy 251.490629 -335.102428) (xy 251.545472 -335.092298) (xy 251.601206 -335.090261) (xy 251.656643 -335.096361)
			(xy 251.7106 -335.110467) (xy 251.761929 -335.132279) (xy 251.809535 -335.161333) (xy 251.852403 -335.197008)
			(xy 251.88962 -335.238545) (xy 251.920393 -335.285058) (xy 251.944065 -335.335555) (xy 251.960133 -335.388962)
			(xy 251.968253 -335.444138) (xy 251.968762 -335.472024) (xy 251.968253 -335.49991) (xy 251.960133 -335.555086)
			(xy 251.944065 -335.608493) (xy 251.920393 -335.65899) (xy 251.88962 -335.705503) (xy 251.852403 -335.74704)
			(xy 251.809535 -335.782715) (xy 251.761929 -335.811769) (xy 251.7106 -335.833581) (xy 251.656643 -335.847687)
			(xy 251.601206 -335.853787) (xy 251.545472 -335.85175) (xy 251.490629 -335.84162) (xy 251.437845 -335.823613)
			(xy 251.388245 -335.798112) (xy 251.342887 -335.765661) (xy 251.302738 -335.726952) (xy 251.268652 -335.682809)
			(xy 251.241356 -335.634174) (xy 251.221433 -335.582083) (xy 251.209307 -335.527646) (xy 251.205236 -335.472024)
			(xy 240.414556 -335.472024) (xy 240.414556 -335.878678) (xy 240.415027 -335.889675) (xy 240.424106 -335.909701)
			(xy 240.432082 -335.917286) (xy 240.490248 -335.967324) (xy 240.498828 -335.974089) (xy 240.519757 -335.98029)
			(xy 240.530634 -335.979262) (xy 240.530888 -335.979262) (xy 240.5521 -335.976303) (xy 240.594815 -335.973124)
			(xy 240.616232 -335.972912) (xy 240.651618 -335.973447) (xy 240.721873 -335.981979) (xy 240.790588 -335.998915)
			(xy 240.856761 -336.024008) (xy 240.919429 -336.056893) (xy 240.977677 -336.097089) (xy 241.030657 -336.144012)
			(xy 241.077596 -336.196976) (xy 241.117811 -336.255212) (xy 241.150715 -336.317869) (xy 241.175829 -336.384034)
			(xy 241.192787 -336.452744) (xy 241.201341 -336.522997) (xy 241.201956 -336.558382) (xy 241.201956 -336.891376)
			(xy 241.201497 -336.92423) (xy 241.194144 -336.989527) (xy 241.179526 -337.053589) (xy 241.173718 -337.070192)
			(xy 251.234194 -337.070192) (xy 251.234658 -337.043878) (xy 251.241894 -336.991749) (xy 251.256214 -336.941107)
			(xy 251.277347 -336.892908) (xy 251.304893 -336.848064) (xy 251.338332 -336.807425) (xy 251.357384 -336.789268)
			(xy 251.364799 -336.781758) (xy 251.373316 -336.762469) (xy 251.373894 -336.75193) (xy 251.373894 -336.677254)
			(xy 251.373351 -336.666706) (xy 251.364826 -336.64741) (xy 251.357384 -336.639916) (xy 251.33834 -336.621749)
			(xy 251.304883 -336.581121) (xy 251.277322 -336.536283) (xy 251.256182 -336.488085) (xy 251.241862 -336.43744)
			(xy 251.234634 -336.385307) (xy 251.234194 -336.358992) (xy 251.23467 -336.33174) (xy 251.242428 -336.277792)
			(xy 251.257784 -336.225497) (xy 251.280426 -336.17592) (xy 251.309894 -336.130069) (xy 251.345586 -336.088879)
			(xy 251.386777 -336.053188) (xy 251.432629 -336.023722) (xy 251.482207 -336.001081) (xy 251.534502 -335.985726)
			(xy 251.58845 -335.97797) (xy 251.615702 -335.977484) (xy 251.642016 -335.977955) (xy 251.694144 -335.98519)
			(xy 251.744786 -335.999509) (xy 251.792985 -336.02064) (xy 251.837829 -336.048186) (xy 251.878469 -336.081623)
			(xy 251.896626 -336.100674) (xy 251.904139 -336.108085) (xy 251.923426 -336.116605) (xy 251.933964 -336.117184)
			(xy 252.00864 -336.117184) (xy 252.019188 -336.116641) (xy 252.038484 -336.108116) (xy 252.045978 -336.100674)
			(xy 252.065798 -336.079886) (xy 252.11057 -336.043911) (xy 252.160228 -336.015051) (xy 252.21365 -335.993958)
			(xy 252.269629 -335.981109) (xy 252.326902 -335.976794) (xy 252.384175 -335.981109) (xy 252.440154 -335.993958)
			(xy 252.493576 -336.015051) (xy 252.543234 -336.043911) (xy 252.588006 -336.079886) (xy 252.607826 -336.100674)
			(xy 252.615339 -336.108085) (xy 252.634626 -336.116605) (xy 252.645164 -336.117184) (xy 252.71984 -336.117184)
			(xy 252.730388 -336.116641) (xy 252.749684 -336.108116) (xy 252.757178 -336.100674) (xy 252.775346 -336.081631)
			(xy 252.815974 -336.048174) (xy 252.860812 -336.020614) (xy 252.90901 -335.999473) (xy 252.959655 -335.985153)
			(xy 253.011787 -335.977925) (xy 253.038102 -335.977484) (xy 253.065353 -335.977976) (xy 253.1193 -335.985732)
			(xy 253.171594 -336.001087) (xy 253.221171 -336.023728) (xy 253.267021 -336.053194) (xy 253.308211 -336.088885)
			(xy 253.343902 -336.130074) (xy 253.373369 -336.175924) (xy 253.39601 -336.2255) (xy 253.411366 -336.277794)
			(xy 253.419124 -336.331741) (xy 253.41961 -336.358992) (xy 253.419134 -336.385306) (xy 253.4119 -336.437434)
			(xy 253.397583 -336.488076) (xy 253.376452 -336.536275) (xy 253.348908 -336.581119) (xy 253.315471 -336.621759)
			(xy 253.29642 -336.639916) (xy 253.289012 -336.647432) (xy 253.280491 -336.666716) (xy 253.27991 -336.677254)
			(xy 253.27991 -336.75193) (xy 253.280461 -336.762477) (xy 253.28898 -336.781773) (xy 253.29642 -336.789268)
			(xy 253.315505 -336.807394) (xy 253.348959 -336.84803) (xy 253.376514 -336.892877) (xy 253.397647 -336.941083)
			(xy 253.411958 -336.991736) (xy 253.419175 -337.043874) (xy 253.41961 -337.070192) (xy 253.419137 -337.097445)
			(xy 253.411381 -337.151395) (xy 253.396026 -337.203693) (xy 253.373385 -337.253273) (xy 253.343918 -337.299126)
			(xy 253.308225 -337.340318) (xy 253.267034 -337.376012) (xy 253.221181 -337.40548) (xy 253.171602 -337.428123)
			(xy 253.119305 -337.443479) (xy 253.065355 -337.451237) (xy 253.038102 -337.4517) (xy 253.011788 -337.451231)
			(xy 252.95966 -337.443997) (xy 252.909017 -337.429678) (xy 252.860818 -337.408546) (xy 252.815974 -337.381)
			(xy 252.775335 -337.347561) (xy 252.757178 -337.32851) (xy 252.749665 -337.321098) (xy 252.730379 -337.312579)
			(xy 252.71984 -337.312) (xy 252.645164 -337.312) (xy 252.634617 -337.31255) (xy 252.615321 -337.321071)
			(xy 252.607826 -337.32851) (xy 252.588006 -337.349298) (xy 252.543234 -337.385273) (xy 252.493576 -337.414133)
			(xy 252.440154 -337.435226) (xy 252.384175 -337.448075) (xy 252.326902 -337.45239) (xy 252.269629 -337.448075)
			(xy 252.21365 -337.435226) (xy 252.160228 -337.414133) (xy 252.11057 -337.385273) (xy 252.065798 -337.349298)
			(xy 252.045978 -337.32851) (xy 252.038465 -337.321098) (xy 252.019179 -337.312579) (xy 252.00864 -337.312)
			(xy 251.933964 -337.312) (xy 251.923417 -337.31255) (xy 251.904121 -337.321071) (xy 251.896626 -337.32851)
			(xy 251.878453 -337.347548) (xy 251.837827 -337.381006) (xy 251.79299 -337.408567) (xy 251.744793 -337.429709)
			(xy 251.694148 -337.44403) (xy 251.642017 -337.451259) (xy 251.615702 -337.4517) (xy 251.588449 -337.451243)
			(xy 251.534497 -337.443486) (xy 251.482199 -337.42813) (xy 251.432618 -337.405487) (xy 251.386765 -337.376018)
			(xy 251.345572 -337.340324) (xy 251.309878 -337.299131) (xy 251.28041 -337.253277) (xy 251.257768 -337.203696)
			(xy 251.242413 -337.151397) (xy 251.234657 -337.097445) (xy 251.234194 -337.070192) (xy 241.173718 -337.070192)
			(xy 241.157829 -337.115612) (xy 241.129325 -337.174816) (xy 241.094371 -337.230457) (xy 241.053409 -337.281836)
			(xy 241.030506 -337.305396) (xy 238.642144 -339.693758) (xy 266.115798 -339.693758) (xy 266.119869 -339.638136)
			(xy 266.131995 -339.583699) (xy 266.151918 -339.531608) (xy 266.179214 -339.482973) (xy 266.2133 -339.43883)
			(xy 266.253449 -339.400121) (xy 266.298807 -339.36767) (xy 266.348407 -339.342169) (xy 266.401191 -339.324162)
			(xy 266.456034 -339.314032) (xy 266.511768 -339.311995) (xy 266.567205 -339.318095) (xy 266.621162 -339.332201)
			(xy 266.672491 -339.354013) (xy 266.720097 -339.383067) (xy 266.762965 -339.418742) (xy 266.800182 -339.460279)
			(xy 266.830955 -339.506792) (xy 266.854627 -339.557289) (xy 266.870695 -339.610696) (xy 266.878815 -339.665872)
			(xy 266.879324 -339.693758) (xy 266.878815 -339.721644) (xy 266.870695 -339.77682) (xy 266.854627 -339.830227)
			(xy 266.830955 -339.880724) (xy 266.800182 -339.927237) (xy 266.762965 -339.968774) (xy 266.720097 -340.004449)
			(xy 266.672491 -340.033503) (xy 266.621162 -340.055315) (xy 266.567205 -340.069421) (xy 266.511768 -340.075521)
			(xy 266.456034 -340.073484) (xy 266.401191 -340.063354) (xy 266.348407 -340.045347) (xy 266.298807 -340.019846)
			(xy 266.253449 -339.987395) (xy 266.2133 -339.948686) (xy 266.179214 -339.904543) (xy 266.151918 -339.855908)
			(xy 266.131995 -339.803817) (xy 266.119869 -339.74938) (xy 266.115798 -339.693758) (xy 238.642144 -339.693758)
			(xy 238.120428 -340.215474) (xy 238.096863 -340.23837) (xy 238.045478 -340.27932) (xy 237.989835 -340.314264)
			(xy 237.930632 -340.342763) (xy 237.868611 -340.36446) (xy 237.804553 -340.379081) (xy 237.739261 -340.386445)
			(xy 237.706408 -340.386924) (xy 234.11053 -340.386924) (xy 234.100482 -340.387344) (xy 234.081921 -340.395046)
			(xy 234.067739 -340.409282) (xy 234.06354 -340.41842) (xy 234.057444 -340.432644) (xy 234.06354 -340.462616)
			(xy 235.660775 -342.060022) (xy 255.91262 -342.060022) (xy 255.91262 -341.196422) (xy 255.91311 -341.166438)
			(xy 255.920938 -341.106982) (xy 255.936459 -341.049057) (xy 255.959408 -340.993653) (xy 255.989392 -340.941719)
			(xy 256.025898 -340.894143) (xy 256.068303 -340.851738) (xy 256.115879 -340.815232) (xy 256.167813 -340.785248)
			(xy 256.223217 -340.762299) (xy 256.281142 -340.746778) (xy 256.340598 -340.73895) (xy 256.400566 -340.73895)
			(xy 256.460022 -340.746778) (xy 256.517947 -340.762299) (xy 256.573351 -340.785248) (xy 256.625285 -340.815232)
			(xy 256.672861 -340.851738) (xy 256.715266 -340.894143) (xy 256.751772 -340.941719) (xy 256.781756 -340.993653)
			(xy 256.804705 -341.049057) (xy 256.820226 -341.106982) (xy 256.828054 -341.166438) (xy 256.828544 -341.196422)
			(xy 256.828544 -342.060022) (xy 256.828054 -342.090006) (xy 256.820226 -342.149462) (xy 256.804705 -342.207387)
			(xy 256.781756 -342.262791) (xy 256.751772 -342.314725) (xy 256.715266 -342.362301) (xy 256.672861 -342.404706)
			(xy 256.625285 -342.441212) (xy 256.573351 -342.471196) (xy 256.517947 -342.494145) (xy 256.460022 -342.509666)
			(xy 256.400566 -342.517494) (xy 256.340598 -342.517494) (xy 256.281142 -342.509666) (xy 256.223217 -342.494145)
			(xy 256.167813 -342.471196) (xy 256.115879 -342.441212) (xy 256.068303 -342.404706) (xy 256.025898 -342.362301)
			(xy 255.989392 -342.314725) (xy 255.959408 -342.262791) (xy 255.936459 -342.207387) (xy 255.920938 -342.149462)
			(xy 255.91311 -342.090006) (xy 255.91262 -342.060022) (xy 235.660775 -342.060022) (xy 236.430312 -342.829642)
			(xy 236.437708 -342.836493) (xy 236.456307 -342.844232) (xy 236.46638 -342.844628) (xy 264.08126 -342.844628)
			(xy 264.107284 -342.845156) (xy 264.158687 -342.853324) (xy 264.208183 -342.869418) (xy 264.25456 -342.893045)
			(xy 264.296678 -342.923623) (xy 264.315448 -342.941656) (xy 264.438892 -343.0651) (xy 265.321032 -343.0651)
			(xy 265.325103 -343.009478) (xy 265.337229 -342.955041) (xy 265.357152 -342.90295) (xy 265.384448 -342.854315)
			(xy 265.418534 -342.810172) (xy 265.458683 -342.771463) (xy 265.504041 -342.739012) (xy 265.553641 -342.713511)
			(xy 265.606425 -342.695504) (xy 265.661268 -342.685374) (xy 265.717002 -342.683337) (xy 265.772439 -342.689437)
			(xy 265.826396 -342.703543) (xy 265.877725 -342.725355) (xy 265.925331 -342.754409) (xy 265.968199 -342.790084)
			(xy 266.005416 -342.831621) (xy 266.036189 -342.878134) (xy 266.059861 -342.928631) (xy 266.075929 -342.982038)
			(xy 266.084049 -343.037214) (xy 266.084558 -343.0651) (xy 266.084354 -343.076276) (xy 266.189714 -343.076276)
			(xy 266.190326 -343.047047) (xy 266.19926 -342.989274) (xy 266.2169 -342.93354) (xy 266.242834 -342.881148)
			(xy 266.276455 -342.833324) (xy 266.316975 -342.791186) (xy 266.363448 -342.755721) (xy 266.38885 -342.74125)
			(xy 266.401636 -342.733738) (xy 266.422542 -342.712728) (xy 266.43653 -342.686596) (xy 266.442421 -342.657548)
			(xy 266.439718 -342.628031) (xy 266.428649 -342.600536) (xy 266.410146 -342.57738) (xy 266.398248 -342.56853)
			(xy 266.376969 -342.553153) (xy 266.338401 -342.517536) (xy 266.305078 -342.476968) (xy 266.277631 -342.432216)
			(xy 266.256577 -342.384124) (xy 266.242315 -342.3336) (xy 266.235112 -342.281597) (xy 266.234672 -342.255348)
			(xy 266.235158 -342.228097) (xy 266.242914 -342.174149) (xy 266.258269 -342.121854) (xy 266.280911 -342.072277)
			(xy 266.310377 -342.026427) (xy 266.346068 -341.985236) (xy 266.387259 -341.949545) (xy 266.433109 -341.920079)
			(xy 266.482686 -341.897437) (xy 266.534981 -341.882082) (xy 266.588929 -341.874326) (xy 266.643431 -341.874326)
			(xy 266.697379 -341.882082) (xy 266.749674 -341.897437) (xy 266.799251 -341.920079) (xy 266.845101 -341.949545)
			(xy 266.886292 -341.985236) (xy 266.921983 -342.026427) (xy 266.951449 -342.072277) (xy 266.974091 -342.121854)
			(xy 266.989446 -342.174149) (xy 266.997202 -342.228097) (xy 266.997688 -342.255348) (xy 266.997094 -342.284578)
			(xy 266.988156 -342.342351) (xy 266.970513 -342.398086) (xy 266.944576 -342.450478) (xy 266.933121 -342.466771)
			(xy 267.515799 -342.466771) (xy 267.515799 -342.412229) (xy 267.523562 -342.358241) (xy 267.538928 -342.305908)
			(xy 267.561586 -342.256295) (xy 267.591074 -342.210411) (xy 267.626792 -342.16919) (xy 267.668012 -342.133473)
			(xy 267.713897 -342.103985) (xy 267.76351 -342.081327) (xy 267.815843 -342.065961) (xy 267.869831 -342.058199)
			(xy 267.897102 -342.057736) (xy 268.760702 -342.057736) (xy 268.787971 -342.058227) (xy 268.841954 -342.065988)
			(xy 268.894283 -342.081354) (xy 268.943893 -342.10401) (xy 268.989773 -342.133496) (xy 269.030991 -342.169211)
			(xy 269.066705 -342.210428) (xy 269.096191 -342.256309) (xy 269.118847 -342.305919) (xy 269.134212 -342.358248)
			(xy 269.141974 -342.412231) (xy 269.141974 -342.466768) (xy 270.624822 -342.466768) (xy 270.624822 -342.412232)
			(xy 270.632583 -342.358252) (xy 270.647947 -342.305925) (xy 270.6706 -342.256317) (xy 270.700083 -342.210438)
			(xy 270.735794 -342.169221) (xy 270.777007 -342.133505) (xy 270.822884 -342.104018) (xy 270.872489 -342.08136)
			(xy 270.924814 -342.065991) (xy 270.978794 -342.058225) (xy 271.006062 -342.057736) (xy 271.869662 -342.057736)
			(xy 271.896935 -342.058201) (xy 271.950925 -342.065959) (xy 272.003262 -342.081321) (xy 272.05288 -342.103977)
			(xy 272.098768 -342.133463) (xy 272.139993 -342.16918) (xy 272.175714 -342.210401) (xy 272.205205 -342.256287)
			(xy 272.227865 -342.305902) (xy 272.243233 -342.358237) (xy 272.250996 -342.412227) (xy 272.250996 -342.466772)
			(xy 273.7337 -342.466772) (xy 273.7337 -342.412228) (xy 273.741462 -342.358239) (xy 273.75683 -342.305904)
			(xy 273.779489 -342.256289) (xy 273.808979 -342.210404) (xy 273.844699 -342.169183) (xy 273.885922 -342.133466)
			(xy 273.931809 -342.103979) (xy 273.981425 -342.081322) (xy 274.03376 -342.065958) (xy 274.08775 -342.058198)
			(xy 274.115022 -342.057736) (xy 274.978622 -342.057736) (xy 275.00589 -342.058228) (xy 275.059871 -342.065992)
			(xy 275.112198 -342.081359) (xy 275.161805 -342.104017) (xy 275.207683 -342.133503) (xy 275.248898 -342.169218)
			(xy 275.28461 -342.210435) (xy 275.314094 -342.256314) (xy 275.336748 -342.305923) (xy 275.352113 -342.35825)
			(xy 275.359874 -342.412232) (xy 275.359874 -342.466768) (xy 275.359874 -342.466769) (xy 276.842722 -342.466769)
			(xy 276.842722 -342.412231) (xy 276.850484 -342.358249) (xy 276.865848 -342.305921) (xy 276.888503 -342.256311)
			(xy 276.917987 -342.210431) (xy 276.953701 -342.169214) (xy 276.994917 -342.133498) (xy 277.040796 -342.104012)
			(xy 277.090404 -342.081354) (xy 277.142731 -342.065987) (xy 277.196713 -342.058224) (xy 277.223982 -342.057736)
			(xy 278.087582 -342.057736) (xy 278.114854 -342.058202) (xy 278.168842 -342.065962) (xy 278.221177 -342.081327)
			(xy 278.270792 -342.103983) (xy 278.316678 -342.13347) (xy 278.3579 -342.169188) (xy 278.393619 -342.210408)
			(xy 278.423108 -342.256292) (xy 278.445767 -342.305906) (xy 278.461134 -342.35824) (xy 278.468896 -342.412228)
			(xy 278.468896 -342.466772) (xy 278.468896 -342.466773) (xy 279.9516 -342.466773) (xy 279.9516 -342.412227)
			(xy 279.959363 -342.358236) (xy 279.974731 -342.3059) (xy 279.997392 -342.256284) (xy 280.026884 -342.210398)
			(xy 280.062606 -342.169176) (xy 280.103831 -342.133459) (xy 280.14972 -342.103972) (xy 280.199339 -342.081317)
			(xy 280.251677 -342.065954) (xy 280.305669 -342.058197) (xy 280.332942 -342.057736) (xy 281.196542 -342.057736)
			(xy 281.223809 -342.058229) (xy 281.277788 -342.065996) (xy 281.330112 -342.081365) (xy 281.379717 -342.104023)
			(xy 281.425592 -342.13351) (xy 281.466805 -342.169225) (xy 281.502515 -342.210441) (xy 281.531997 -342.25632)
			(xy 281.55465 -342.305927) (xy 281.570013 -342.358253) (xy 281.577774 -342.412233) (xy 281.577774 -342.466767)
			(xy 281.577773 -342.466771) (xy 283.060599 -342.466771) (xy 283.060599 -342.412229) (xy 283.068362 -342.358241)
			(xy 283.083728 -342.305908) (xy 283.106386 -342.256295) (xy 283.135874 -342.210411) (xy 283.171592 -342.16919)
			(xy 283.212812 -342.133473) (xy 283.258697 -342.103985) (xy 283.30831 -342.081327) (xy 283.360643 -342.065961)
			(xy 283.414631 -342.058199) (xy 283.441902 -342.057736) (xy 284.305502 -342.057736) (xy 284.332771 -342.058227)
			(xy 284.386754 -342.065988) (xy 284.439083 -342.081354) (xy 284.488693 -342.10401) (xy 284.534573 -342.133496)
			(xy 284.575791 -342.169211) (xy 284.611505 -342.210428) (xy 284.640991 -342.256309) (xy 284.663647 -342.305919)
			(xy 284.679012 -342.358248) (xy 284.686774 -342.412231) (xy 284.686774 -342.466768) (xy 286.169622 -342.466768)
			(xy 286.169622 -342.412232) (xy 286.177383 -342.358252) (xy 286.192747 -342.305925) (xy 286.2154 -342.256317)
			(xy 286.244883 -342.210438) (xy 286.280594 -342.169221) (xy 286.321807 -342.133505) (xy 286.367684 -342.104018)
			(xy 286.417289 -342.08136) (xy 286.469614 -342.065991) (xy 286.523594 -342.058225) (xy 286.550862 -342.057736)
			(xy 287.414462 -342.057736) (xy 287.441735 -342.058201) (xy 287.495725 -342.065959) (xy 287.548062 -342.081321)
			(xy 287.59768 -342.103977) (xy 287.643568 -342.133463) (xy 287.684793 -342.16918) (xy 287.720514 -342.210401)
			(xy 287.750005 -342.256287) (xy 287.772665 -342.305902) (xy 287.788033 -342.358237) (xy 287.795796 -342.412227)
			(xy 287.795796 -342.466772) (xy 289.2785 -342.466772) (xy 289.2785 -342.412228) (xy 289.286262 -342.358239)
			(xy 289.30163 -342.305904) (xy 289.324289 -342.256289) (xy 289.353779 -342.210404) (xy 289.389499 -342.169183)
			(xy 289.430722 -342.133466) (xy 289.476609 -342.103979) (xy 289.526225 -342.081322) (xy 289.57856 -342.065958)
			(xy 289.63255 -342.058198) (xy 289.659822 -342.057736) (xy 290.523422 -342.057736) (xy 290.55069 -342.058228)
			(xy 290.604671 -342.065992) (xy 290.656998 -342.081359) (xy 290.706605 -342.104017) (xy 290.752483 -342.133503)
			(xy 290.793698 -342.169218) (xy 290.82941 -342.210435) (xy 290.858894 -342.256314) (xy 290.881548 -342.305923)
			(xy 290.896913 -342.35825) (xy 290.904674 -342.412232) (xy 290.904674 -342.466768) (xy 290.904674 -342.466769)
			(xy 292.387522 -342.466769) (xy 292.387522 -342.412231) (xy 292.395284 -342.358249) (xy 292.410648 -342.305921)
			(xy 292.433303 -342.256311) (xy 292.462787 -342.210431) (xy 292.498501 -342.169214) (xy 292.539717 -342.133498)
			(xy 292.585596 -342.104012) (xy 292.635204 -342.081354) (xy 292.687531 -342.065987) (xy 292.741513 -342.058224)
			(xy 292.768782 -342.057736) (xy 293.632382 -342.057736) (xy 293.659654 -342.058202) (xy 293.713642 -342.065962)
			(xy 293.765977 -342.081327) (xy 293.815592 -342.103983) (xy 293.861478 -342.13347) (xy 293.9027 -342.169188)
			(xy 293.938419 -342.210408) (xy 293.967908 -342.256292) (xy 293.990567 -342.305906) (xy 294.005934 -342.35824)
			(xy 294.013696 -342.412228) (xy 294.013696 -342.466772) (xy 294.013696 -342.466773) (xy 295.4964 -342.466773)
			(xy 295.4964 -342.412227) (xy 295.504163 -342.358236) (xy 295.519531 -342.3059) (xy 295.542192 -342.256284)
			(xy 295.571684 -342.210398) (xy 295.607406 -342.169176) (xy 295.648631 -342.133459) (xy 295.69452 -342.103972)
			(xy 295.744139 -342.081317) (xy 295.796477 -342.065954) (xy 295.850469 -342.058197) (xy 295.877742 -342.057736)
			(xy 296.741342 -342.057736) (xy 296.768609 -342.058229) (xy 296.822588 -342.065996) (xy 296.874912 -342.081365)
			(xy 296.924517 -342.104023) (xy 296.970392 -342.13351) (xy 297.011605 -342.169225) (xy 297.047315 -342.210441)
			(xy 297.076797 -342.25632) (xy 297.09945 -342.305927) (xy 297.114813 -342.358253) (xy 297.122574 -342.412233)
			(xy 297.122574 -342.466767) (xy 297.114813 -342.520747) (xy 297.09945 -342.573073) (xy 297.076797 -342.62268)
			(xy 297.047315 -342.668559) (xy 297.011605 -342.709775) (xy 296.970392 -342.74549) (xy 296.924517 -342.774977)
			(xy 296.874912 -342.797635) (xy 296.822588 -342.813004) (xy 296.768609 -342.820771) (xy 296.741342 -342.82126)
			(xy 295.877742 -342.82126) (xy 295.850469 -342.820803) (xy 295.796477 -342.813046) (xy 295.744139 -342.797683)
			(xy 295.694521 -342.775028) (xy 295.648631 -342.745541) (xy 295.607406 -342.709824) (xy 295.571684 -342.668602)
			(xy 295.542192 -342.622716) (xy 295.519531 -342.5731) (xy 295.504163 -342.520764) (xy 295.4964 -342.466773)
			(xy 294.013696 -342.466773) (xy 294.005934 -342.52076) (xy 293.990567 -342.573094) (xy 293.967908 -342.622708)
			(xy 293.938419 -342.668592) (xy 293.9027 -342.709812) (xy 293.861478 -342.74553) (xy 293.815592 -342.775017)
			(xy 293.765977 -342.797673) (xy 293.713642 -342.813038) (xy 293.659654 -342.820798) (xy 293.632382 -342.82126)
			(xy 292.768782 -342.82126) (xy 292.741513 -342.820776) (xy 292.687531 -342.813013) (xy 292.635204 -342.797646)
			(xy 292.585596 -342.774988) (xy 292.539717 -342.745502) (xy 292.498501 -342.709786) (xy 292.462787 -342.668569)
			(xy 292.433303 -342.622689) (xy 292.410648 -342.573079) (xy 292.395284 -342.520751) (xy 292.387522 -342.466769)
			(xy 290.904674 -342.466769) (xy 290.896913 -342.52075) (xy 290.881548 -342.573077) (xy 290.858894 -342.622686)
			(xy 290.82941 -342.668565) (xy 290.793698 -342.709782) (xy 290.752483 -342.745497) (xy 290.706605 -342.774983)
			(xy 290.656998 -342.797641) (xy 290.604671 -342.813008) (xy 290.55069 -342.820772) (xy 290.523422 -342.82126)
			(xy 289.659822 -342.82126) (xy 289.63255 -342.820802) (xy 289.57856 -342.813042) (xy 289.526225 -342.797678)
			(xy 289.476609 -342.775021) (xy 289.430722 -342.745534) (xy 289.389499 -342.709817) (xy 289.353779 -342.668596)
			(xy 289.324289 -342.622711) (xy 289.30163 -342.573096) (xy 289.286262 -342.520761) (xy 289.2785 -342.466772)
			(xy 287.795796 -342.466772) (xy 287.795796 -342.466773) (xy 287.788033 -342.520763) (xy 287.772665 -342.573098)
			(xy 287.750005 -342.622713) (xy 287.720514 -342.668599) (xy 287.684793 -342.70982) (xy 287.643568 -342.745537)
			(xy 287.59768 -342.775023) (xy 287.548062 -342.797679) (xy 287.495725 -342.813041) (xy 287.441735 -342.820799)
			(xy 287.414462 -342.82126) (xy 286.550862 -342.82126) (xy 286.523594 -342.820775) (xy 286.469614 -342.813009)
			(xy 286.417289 -342.79764) (xy 286.367684 -342.774982) (xy 286.321807 -342.745495) (xy 286.280594 -342.709779)
			(xy 286.244883 -342.668562) (xy 286.2154 -342.622683) (xy 286.192747 -342.573075) (xy 286.177383 -342.520748)
			(xy 286.169622 -342.466768) (xy 284.686774 -342.466768) (xy 284.686774 -342.466769) (xy 284.679012 -342.520752)
			(xy 284.663647 -342.573081) (xy 284.640991 -342.622691) (xy 284.611505 -342.668572) (xy 284.575791 -342.709789)
			(xy 284.534573 -342.745504) (xy 284.488693 -342.77499) (xy 284.439083 -342.797646) (xy 284.386754 -342.813012)
			(xy 284.332771 -342.820773) (xy 284.305502 -342.82126) (xy 283.441902 -342.82126) (xy 283.414631 -342.820801)
			(xy 283.360643 -342.813039) (xy 283.30831 -342.797673) (xy 283.258697 -342.775015) (xy 283.212812 -342.745527)
			(xy 283.171592 -342.70981) (xy 283.135874 -342.668589) (xy 283.106386 -342.622705) (xy 283.083728 -342.573092)
			(xy 283.068362 -342.520759) (xy 283.060599 -342.466771) (xy 281.577773 -342.466771) (xy 281.570013 -342.520747)
			(xy 281.55465 -342.573073) (xy 281.531997 -342.62268) (xy 281.502515 -342.668559) (xy 281.466805 -342.709775)
			(xy 281.425592 -342.74549) (xy 281.379717 -342.774977) (xy 281.330112 -342.797635) (xy 281.277788 -342.813004)
			(xy 281.223809 -342.820771) (xy 281.196542 -342.82126) (xy 280.332942 -342.82126) (xy 280.305669 -342.820803)
			(xy 280.251677 -342.813046) (xy 280.199339 -342.797683) (xy 280.149721 -342.775028) (xy 280.103831 -342.745541)
			(xy 280.062606 -342.709824) (xy 280.026884 -342.668602) (xy 279.997392 -342.622716) (xy 279.974731 -342.5731)
			(xy 279.959363 -342.520764) (xy 279.9516 -342.466773) (xy 278.468896 -342.466773) (xy 278.461134 -342.52076)
			(xy 278.445767 -342.573094) (xy 278.423108 -342.622708) (xy 278.393619 -342.668592) (xy 278.3579 -342.709812)
			(xy 278.316678 -342.74553) (xy 278.270792 -342.775017) (xy 278.221177 -342.797673) (xy 278.168842 -342.813038)
			(xy 278.114854 -342.820798) (xy 278.087582 -342.82126) (xy 277.223982 -342.82126) (xy 277.196713 -342.820776)
			(xy 277.142731 -342.813013) (xy 277.090404 -342.797646) (xy 277.040796 -342.774988) (xy 276.994917 -342.745502)
			(xy 276.953701 -342.709786) (xy 276.917987 -342.668569) (xy 276.888503 -342.622689) (xy 276.865848 -342.573079)
			(xy 276.850484 -342.520751) (xy 276.842722 -342.466769) (xy 275.359874 -342.466769) (xy 275.352113 -342.52075)
			(xy 275.336748 -342.573077) (xy 275.314094 -342.622686) (xy 275.28461 -342.668565) (xy 275.248898 -342.709782)
			(xy 275.207683 -342.745497) (xy 275.161805 -342.774983) (xy 275.112198 -342.797641) (xy 275.059871 -342.813008)
			(xy 275.00589 -342.820772) (xy 274.978622 -342.82126) (xy 274.115022 -342.82126) (xy 274.08775 -342.820802)
			(xy 274.03376 -342.813042) (xy 273.981425 -342.797678) (xy 273.931809 -342.775021) (xy 273.885922 -342.745534)
			(xy 273.844699 -342.709817) (xy 273.808979 -342.668596) (xy 273.779489 -342.622711) (xy 273.75683 -342.573096)
			(xy 273.741462 -342.520761) (xy 273.7337 -342.466772) (xy 272.250996 -342.466772) (xy 272.250996 -342.466773)
			(xy 272.243233 -342.520763) (xy 272.227865 -342.573098) (xy 272.205205 -342.622713) (xy 272.175714 -342.668599)
			(xy 272.139993 -342.70982) (xy 272.098768 -342.745537) (xy 272.05288 -342.775023) (xy 272.003262 -342.797679)
			(xy 271.950925 -342.813041) (xy 271.896935 -342.820799) (xy 271.869662 -342.82126) (xy 271.006062 -342.82126)
			(xy 270.978794 -342.820775) (xy 270.924814 -342.813009) (xy 270.872489 -342.79764) (xy 270.822884 -342.774982)
			(xy 270.777007 -342.745495) (xy 270.735794 -342.709779) (xy 270.700083 -342.668562) (xy 270.6706 -342.622683)
			(xy 270.647947 -342.573075) (xy 270.632583 -342.520748) (xy 270.624822 -342.466768) (xy 269.141974 -342.466768)
			(xy 269.141974 -342.466769) (xy 269.134212 -342.520752) (xy 269.118847 -342.573081) (xy 269.096191 -342.622691)
			(xy 269.066705 -342.668572) (xy 269.030991 -342.709789) (xy 268.989773 -342.745504) (xy 268.943893 -342.77499)
			(xy 268.894283 -342.797646) (xy 268.841954 -342.813012) (xy 268.787971 -342.820773) (xy 268.760702 -342.82126)
			(xy 267.897102 -342.82126) (xy 267.869831 -342.820801) (xy 267.815843 -342.813039) (xy 267.76351 -342.797673)
			(xy 267.713897 -342.775015) (xy 267.668012 -342.745527) (xy 267.626792 -342.70981) (xy 267.591074 -342.668589)
			(xy 267.561586 -342.622705) (xy 267.538928 -342.573092) (xy 267.523562 -342.520759) (xy 267.515799 -342.466771)
			(xy 266.933121 -342.466771) (xy 266.910953 -342.498302) (xy 266.87043 -342.540439) (xy 266.823955 -342.575903)
			(xy 266.798552 -342.590374) (xy 266.785745 -342.597852) (xy 266.764836 -342.61887) (xy 266.750848 -342.645008)
			(xy 266.744959 -342.674064) (xy 266.747667 -342.703586) (xy 266.758742 -342.731086) (xy 266.777252 -342.754244)
			(xy 266.789154 -342.763094) (xy 266.810445 -342.778455) (xy 266.849013 -342.814075) (xy 266.882334 -342.854646)
			(xy 266.90978 -342.899401) (xy 266.930831 -342.947495) (xy 266.945092 -342.998022) (xy 266.952292 -343.050026)
			(xy 266.95273 -343.076276) (xy 266.952244 -343.103527) (xy 266.944488 -343.157475) (xy 266.929133 -343.20977)
			(xy 266.906491 -343.259347) (xy 266.877025 -343.305197) (xy 266.841334 -343.346388) (xy 266.800143 -343.382079)
			(xy 266.754293 -343.411545) (xy 266.704716 -343.434187) (xy 266.652421 -343.449542) (xy 266.598473 -343.457298)
			(xy 266.543971 -343.457298) (xy 266.490023 -343.449542) (xy 266.437728 -343.434187) (xy 266.388151 -343.411545)
			(xy 266.342301 -343.382079) (xy 266.30111 -343.346388) (xy 266.265419 -343.305197) (xy 266.235953 -343.259347)
			(xy 266.213311 -343.20977) (xy 266.197956 -343.157475) (xy 266.1902 -343.103527) (xy 266.189714 -343.076276)
			(xy 266.084354 -343.076276) (xy 266.084049 -343.092986) (xy 266.075929 -343.148162) (xy 266.059861 -343.201569)
			(xy 266.036189 -343.252066) (xy 266.005416 -343.298579) (xy 265.968199 -343.340116) (xy 265.925331 -343.375791)
			(xy 265.877725 -343.404845) (xy 265.826396 -343.426657) (xy 265.772439 -343.440763) (xy 265.717002 -343.446863)
			(xy 265.661268 -343.444826) (xy 265.606425 -343.434696) (xy 265.553641 -343.416689) (xy 265.504041 -343.391188)
			(xy 265.458683 -343.358737) (xy 265.418534 -343.320028) (xy 265.384448 -343.275885) (xy 265.357152 -343.22725)
			(xy 265.337229 -343.175159) (xy 265.325103 -343.120722) (xy 265.321032 -343.0651) (xy 264.438892 -343.0651)
			(xy 266.83335 -345.459558) (xy 266.85146 -345.47834) (xy 266.861658 -345.492368) (xy 267.515847 -345.492368)
			(xy 267.515847 -345.437832) (xy 267.523609 -345.383852) (xy 267.538973 -345.331525) (xy 267.561628 -345.281918)
			(xy 267.591112 -345.23604) (xy 267.626826 -345.194824) (xy 267.668041 -345.159111) (xy 267.71392 -345.129627)
			(xy 267.763527 -345.106972) (xy 267.815854 -345.091608) (xy 267.869834 -345.083847) (xy 267.897102 -345.083384)
			(xy 268.760702 -345.083384) (xy 268.787975 -345.083779) (xy 268.841964 -345.091542) (xy 268.8943 -345.106909)
			(xy 268.943916 -345.129568) (xy 268.989802 -345.159057) (xy 269.031024 -345.194777) (xy 269.066744 -345.236)
			(xy 269.096233 -345.281886) (xy 269.118892 -345.331502) (xy 269.134259 -345.383838) (xy 269.142021 -345.437827)
			(xy 269.142021 -345.492364) (xy 270.62487 -345.492364) (xy 270.62487 -345.437836) (xy 270.63263 -345.383862)
			(xy 270.647992 -345.331542) (xy 270.670642 -345.28194) (xy 270.700121 -345.236066) (xy 270.735828 -345.194855)
			(xy 270.777036 -345.159144) (xy 270.822907 -345.12966) (xy 270.872506 -345.107005) (xy 270.924825 -345.091638)
			(xy 270.978798 -345.083873) (xy 271.006062 -345.083384) (xy 271.869662 -345.083384) (xy 271.896938 -345.083753)
			(xy 271.950936 -345.091512) (xy 272.003279 -345.106877) (xy 272.052903 -345.129535) (xy 272.098797 -345.159025)
			(xy 272.140027 -345.194747) (xy 272.175752 -345.235973) (xy 272.205247 -345.281864) (xy 272.22791 -345.331485)
			(xy 272.24328 -345.383827) (xy 272.251044 -345.437824) (xy 272.251044 -345.492369) (xy 273.733747 -345.492369)
			(xy 273.733747 -345.437831) (xy 273.741509 -345.383849) (xy 273.756875 -345.331521) (xy 273.779531 -345.281912)
			(xy 273.809017 -345.236033) (xy 273.844733 -345.194817) (xy 273.885951 -345.159104) (xy 273.931832 -345.129621)
			(xy 273.981441 -345.106967) (xy 274.033771 -345.091605) (xy 274.087753 -345.083846) (xy 274.115022 -345.083384)
			(xy 274.978622 -345.083384) (xy 275.005894 -345.08378) (xy 275.059881 -345.091545) (xy 275.112215 -345.106914)
			(xy 275.161828 -345.129574) (xy 275.207712 -345.159064) (xy 275.248932 -345.194784) (xy 275.284649 -345.236006)
			(xy 275.314136 -345.281891) (xy 275.336793 -345.331506) (xy 275.352159 -345.38384) (xy 275.359922 -345.437828)
			(xy 275.359922 -345.492365) (xy 276.84277 -345.492365) (xy 276.84277 -345.437835) (xy 276.850531 -345.383859)
			(xy 276.865893 -345.331537) (xy 276.888545 -345.281934) (xy 276.918026 -345.23606) (xy 276.953735 -345.194848)
			(xy 276.994945 -345.159137) (xy 277.040819 -345.129654) (xy 277.090421 -345.106999) (xy 277.142742 -345.091634)
			(xy 277.196717 -345.083872) (xy 277.223982 -345.083384) (xy 278.087582 -345.083384) (xy 278.114857 -345.083754)
			(xy 278.168852 -345.091515) (xy 278.221194 -345.106882) (xy 278.270815 -345.129541) (xy 278.316706 -345.159032)
			(xy 278.357934 -345.194754) (xy 278.393657 -345.235979) (xy 278.42315 -345.281869) (xy 278.445812 -345.33149)
			(xy 278.461181 -345.38383) (xy 278.468944 -345.437825) (xy 278.468944 -345.49237) (xy 279.951648 -345.49237)
			(xy 279.951648 -345.43783) (xy 279.95941 -345.383846) (xy 279.974776 -345.331517) (xy 279.997434 -345.281907)
			(xy 280.026922 -345.236026) (xy 280.06264 -345.19481) (xy 280.10386 -345.159097) (xy 280.149744 -345.129614)
			(xy 280.199356 -345.106962) (xy 280.251687 -345.091601) (xy 280.305672 -345.083845) (xy 280.332942 -345.083384)
			(xy 281.196542 -345.083384) (xy 281.223813 -345.083781) (xy 281.277798 -345.091549) (xy 281.330129 -345.10692)
			(xy 281.37974 -345.129581) (xy 281.425621 -345.159072) (xy 281.466839 -345.194791) (xy 281.502554 -345.236013)
			(xy 281.532039 -345.281897) (xy 281.554695 -345.33151) (xy 281.57006 -345.383843) (xy 281.577822 -345.437829)
			(xy 281.577822 -345.492368) (xy 283.060647 -345.492368) (xy 283.060647 -345.437832) (xy 283.068409 -345.383852)
			(xy 283.083773 -345.331525) (xy 283.106428 -345.281918) (xy 283.135912 -345.23604) (xy 283.171626 -345.194824)
			(xy 283.212841 -345.159111) (xy 283.25872 -345.129627) (xy 283.308327 -345.106972) (xy 283.360654 -345.091608)
			(xy 283.414634 -345.083847) (xy 283.441902 -345.083384) (xy 284.305502 -345.083384) (xy 284.332775 -345.083779)
			(xy 284.386764 -345.091542) (xy 284.4391 -345.106909) (xy 284.488716 -345.129568) (xy 284.534602 -345.159057)
			(xy 284.575824 -345.194777) (xy 284.611544 -345.236) (xy 284.641033 -345.281886) (xy 284.663692 -345.331502)
			(xy 284.679059 -345.383838) (xy 284.686821 -345.437827) (xy 284.686821 -345.492364) (xy 286.16967 -345.492364)
			(xy 286.16967 -345.437836) (xy 286.17743 -345.383862) (xy 286.192792 -345.331542) (xy 286.215442 -345.28194)
			(xy 286.244921 -345.236066) (xy 286.280628 -345.194855) (xy 286.321836 -345.159144) (xy 286.367707 -345.12966)
			(xy 286.417306 -345.107005) (xy 286.469625 -345.091638) (xy 286.523598 -345.083873) (xy 286.550862 -345.083384)
			(xy 287.414462 -345.083384) (xy 287.441738 -345.083753) (xy 287.495736 -345.091512) (xy 287.548079 -345.106877)
			(xy 287.597703 -345.129535) (xy 287.643597 -345.159025) (xy 287.684827 -345.194747) (xy 287.720552 -345.235973)
			(xy 287.750047 -345.281864) (xy 287.77271 -345.331485) (xy 287.78808 -345.383827) (xy 287.795844 -345.437824)
			(xy 287.795844 -345.492369) (xy 289.278547 -345.492369) (xy 289.278547 -345.437831) (xy 289.286309 -345.383849)
			(xy 289.301675 -345.331521) (xy 289.324331 -345.281912) (xy 289.353817 -345.236033) (xy 289.389533 -345.194817)
			(xy 289.430751 -345.159104) (xy 289.476632 -345.129621) (xy 289.526241 -345.106967) (xy 289.578571 -345.091605)
			(xy 289.632553 -345.083846) (xy 289.659822 -345.083384) (xy 290.523422 -345.083384) (xy 290.550694 -345.08378)
			(xy 290.604681 -345.091545) (xy 290.657015 -345.106914) (xy 290.706628 -345.129574) (xy 290.752512 -345.159064)
			(xy 290.793732 -345.194784) (xy 290.829449 -345.236006) (xy 290.858936 -345.281891) (xy 290.881593 -345.331506)
			(xy 290.896959 -345.38384) (xy 290.904722 -345.437828) (xy 290.904722 -345.492365) (xy 292.38757 -345.492365)
			(xy 292.38757 -345.437835) (xy 292.395331 -345.383859) (xy 292.410693 -345.331537) (xy 292.433345 -345.281934)
			(xy 292.462826 -345.23606) (xy 292.498535 -345.194848) (xy 292.539745 -345.159137) (xy 292.585619 -345.129654)
			(xy 292.635221 -345.106999) (xy 292.687542 -345.091634) (xy 292.741517 -345.083872) (xy 292.768782 -345.083384)
			(xy 293.632382 -345.083384) (xy 293.659657 -345.083754) (xy 293.713652 -345.091515) (xy 293.765994 -345.106882)
			(xy 293.815615 -345.129541) (xy 293.861506 -345.159032) (xy 293.902734 -345.194754) (xy 293.938457 -345.235979)
			(xy 293.96795 -345.281869) (xy 293.990612 -345.33149) (xy 294.005981 -345.38383) (xy 294.013744 -345.437825)
			(xy 294.013744 -345.49237) (xy 295.496448 -345.49237) (xy 295.496448 -345.43783) (xy 295.50421 -345.383846)
			(xy 295.519576 -345.331517) (xy 295.542234 -345.281907) (xy 295.571722 -345.236026) (xy 295.60744 -345.19481)
			(xy 295.64866 -345.159097) (xy 295.694544 -345.129614) (xy 295.744156 -345.106962) (xy 295.796487 -345.091601)
			(xy 295.850472 -345.083845) (xy 295.877742 -345.083384) (xy 296.741342 -345.083384) (xy 296.768613 -345.083781)
			(xy 296.822598 -345.091549) (xy 296.874929 -345.10692) (xy 296.92454 -345.129581) (xy 296.970421 -345.159072)
			(xy 297.011639 -345.194791) (xy 297.047354 -345.236013) (xy 297.076839 -345.281897) (xy 297.099495 -345.33151)
			(xy 297.11486 -345.383843) (xy 297.122622 -345.437829) (xy 297.122622 -345.492368) (xy 298.605447 -345.492368)
			(xy 298.605447 -345.437832) (xy 298.613209 -345.383852) (xy 298.628573 -345.331525) (xy 298.651228 -345.281918)
			(xy 298.680712 -345.23604) (xy 298.716426 -345.194824) (xy 298.757641 -345.159111) (xy 298.80352 -345.129627)
			(xy 298.853127 -345.106972) (xy 298.905454 -345.091608) (xy 298.959434 -345.083847) (xy 298.986702 -345.083384)
			(xy 299.850302 -345.083384) (xy 299.877575 -345.083779) (xy 299.931564 -345.091542) (xy 299.9839 -345.106909)
			(xy 300.033516 -345.129568) (xy 300.079402 -345.159057) (xy 300.120624 -345.194777) (xy 300.156344 -345.236)
			(xy 300.185833 -345.281886) (xy 300.208492 -345.331502) (xy 300.223859 -345.383838) (xy 300.231621 -345.437827)
			(xy 300.231621 -345.492373) (xy 300.223859 -345.546362) (xy 300.208492 -345.598698) (xy 300.185833 -345.648314)
			(xy 300.156344 -345.6942) (xy 300.120624 -345.735423) (xy 300.079402 -345.771143) (xy 300.033516 -345.800632)
			(xy 299.9839 -345.823291) (xy 299.931564 -345.838658) (xy 299.877575 -345.846421) (xy 299.850302 -345.846908)
			(xy 298.986702 -345.846908) (xy 298.959434 -345.846353) (xy 298.905454 -345.838592) (xy 298.853127 -345.823228)
			(xy 298.80352 -345.800573) (xy 298.757641 -345.771089) (xy 298.716426 -345.735376) (xy 298.680712 -345.69416)
			(xy 298.651228 -345.648282) (xy 298.628573 -345.598675) (xy 298.613209 -345.546348) (xy 298.605447 -345.492368)
			(xy 297.122622 -345.492368) (xy 297.122622 -345.492371) (xy 297.11486 -345.546357) (xy 297.099495 -345.59869)
			(xy 297.076839 -345.648303) (xy 297.047354 -345.694187) (xy 297.011639 -345.735409) (xy 296.970421 -345.771128)
			(xy 296.92454 -345.800619) (xy 296.874929 -345.82328) (xy 296.822598 -345.838651) (xy 296.768613 -345.846419)
			(xy 296.741342 -345.846908) (xy 295.877742 -345.846908) (xy 295.850472 -345.846355) (xy 295.796487 -345.838599)
			(xy 295.744156 -345.823238) (xy 295.694543 -345.800586) (xy 295.64866 -345.771103) (xy 295.60744 -345.73539)
			(xy 295.571722 -345.694174) (xy 295.542234 -345.648293) (xy 295.519576 -345.598683) (xy 295.50421 -345.546354)
			(xy 295.496448 -345.49237) (xy 294.013744 -345.49237) (xy 294.013744 -345.492375) (xy 294.005981 -345.54637)
			(xy 293.990612 -345.59871) (xy 293.96795 -345.648331) (xy 293.938457 -345.694221) (xy 293.902734 -345.735446)
			(xy 293.861506 -345.771168) (xy 293.815615 -345.800659) (xy 293.765994 -345.823318) (xy 293.713652 -345.838685)
			(xy 293.659657 -345.846446) (xy 293.632382 -345.846908) (xy 292.768782 -345.846908) (xy 292.741517 -345.846328)
			(xy 292.687542 -345.838566) (xy 292.635221 -345.823201) (xy 292.585619 -345.800546) (xy 292.539745 -345.771063)
			(xy 292.498535 -345.735352) (xy 292.462826 -345.69414) (xy 292.433345 -345.648266) (xy 292.410693 -345.598663)
			(xy 292.395331 -345.546341) (xy 292.38757 -345.492365) (xy 290.904722 -345.492365) (xy 290.904722 -345.492372)
			(xy 290.896959 -345.54636) (xy 290.881593 -345.598694) (xy 290.858936 -345.648309) (xy 290.829449 -345.694194)
			(xy 290.793732 -345.735416) (xy 290.752512 -345.771136) (xy 290.706628 -345.800626) (xy 290.657015 -345.823286)
			(xy 290.604681 -345.838655) (xy 290.550694 -345.84642) (xy 290.523422 -345.846908) (xy 289.659822 -345.846908)
			(xy 289.632553 -345.846354) (xy 289.57857 -345.838595) (xy 289.526241 -345.823233) (xy 289.476632 -345.800579)
			(xy 289.430751 -345.771096) (xy 289.389533 -345.735383) (xy 289.353817 -345.694167) (xy 289.324331 -345.648288)
			(xy 289.301675 -345.598679) (xy 289.286309 -345.546351) (xy 289.278547 -345.492369) (xy 287.795844 -345.492369)
			(xy 287.795844 -345.492376) (xy 287.78808 -345.546373) (xy 287.77271 -345.598715) (xy 287.750047 -345.648336)
			(xy 287.720552 -345.694227) (xy 287.684827 -345.735453) (xy 287.643597 -345.771175) (xy 287.597703 -345.800665)
			(xy 287.548079 -345.823323) (xy 287.495736 -345.838688) (xy 287.441738 -345.846447) (xy 287.414462 -345.846908)
			(xy 286.550862 -345.846908) (xy 286.523598 -345.846327) (xy 286.469625 -345.838562) (xy 286.417306 -345.823195)
			(xy 286.367707 -345.80054) (xy 286.321836 -345.771056) (xy 286.280628 -345.735345) (xy 286.244921 -345.694134)
			(xy 286.215442 -345.64826) (xy 286.192792 -345.598658) (xy 286.17743 -345.546338) (xy 286.16967 -345.492364)
			(xy 284.686821 -345.492364) (xy 284.686821 -345.492373) (xy 284.679059 -345.546362) (xy 284.663692 -345.598698)
			(xy 284.641033 -345.648314) (xy 284.611544 -345.6942) (xy 284.575824 -345.735423) (xy 284.534602 -345.771143)
			(xy 284.488716 -345.800632) (xy 284.4391 -345.823291) (xy 284.386764 -345.838658) (xy 284.332775 -345.846421)
			(xy 284.305502 -345.846908) (xy 283.441902 -345.846908) (xy 283.414634 -345.846353) (xy 283.360654 -345.838592)
			(xy 283.308327 -345.823228) (xy 283.25872 -345.800573) (xy 283.212841 -345.771089) (xy 283.171626 -345.735376)
			(xy 283.135912 -345.69416) (xy 283.106428 -345.648282) (xy 283.083773 -345.598675) (xy 283.068409 -345.546348)
			(xy 283.060647 -345.492368) (xy 281.577822 -345.492368) (xy 281.577822 -345.492371) (xy 281.57006 -345.546357)
			(xy 281.554695 -345.59869) (xy 281.532039 -345.648303) (xy 281.502554 -345.694187) (xy 281.466839 -345.735409)
			(xy 281.425621 -345.771128) (xy 281.37974 -345.800619) (xy 281.330129 -345.82328) (xy 281.277798 -345.838651)
			(xy 281.223813 -345.846419) (xy 281.196542 -345.846908) (xy 280.332942 -345.846908) (xy 280.305672 -345.846355)
			(xy 280.251687 -345.838599) (xy 280.199356 -345.823238) (xy 280.149743 -345.800586) (xy 280.10386 -345.771103)
			(xy 280.06264 -345.73539) (xy 280.026922 -345.694174) (xy 279.997434 -345.648293) (xy 279.974776 -345.598683)
			(xy 279.95941 -345.546354) (xy 279.951648 -345.49237) (xy 278.468944 -345.49237) (xy 278.468944 -345.492375)
			(xy 278.461181 -345.54637) (xy 278.445812 -345.59871) (xy 278.42315 -345.648331) (xy 278.393657 -345.694221)
			(xy 278.357934 -345.735446) (xy 278.316706 -345.771168) (xy 278.270815 -345.800659) (xy 278.221194 -345.823318)
			(xy 278.168852 -345.838685) (xy 278.114857 -345.846446) (xy 278.087582 -345.846908) (xy 277.223982 -345.846908)
			(xy 277.196717 -345.846328) (xy 277.142742 -345.838566) (xy 277.090421 -345.823201) (xy 277.040819 -345.800546)
			(xy 276.994945 -345.771063) (xy 276.953735 -345.735352) (xy 276.918026 -345.69414) (xy 276.888545 -345.648266)
			(xy 276.865893 -345.598663) (xy 276.850531 -345.546341) (xy 276.84277 -345.492365) (xy 275.359922 -345.492365)
			(xy 275.359922 -345.492372) (xy 275.352159 -345.54636) (xy 275.336793 -345.598694) (xy 275.314136 -345.648309)
			(xy 275.284649 -345.694194) (xy 275.248932 -345.735416) (xy 275.207712 -345.771136) (xy 275.161828 -345.800626)
			(xy 275.112215 -345.823286) (xy 275.059881 -345.838655) (xy 275.005894 -345.84642) (xy 274.978622 -345.846908)
			(xy 274.115022 -345.846908) (xy 274.087753 -345.846354) (xy 274.03377 -345.838595) (xy 273.981441 -345.823233)
			(xy 273.931832 -345.800579) (xy 273.885951 -345.771096) (xy 273.844733 -345.735383) (xy 273.809017 -345.694167)
			(xy 273.779531 -345.648288) (xy 273.756875 -345.598679) (xy 273.741509 -345.546351) (xy 273.733747 -345.492369)
			(xy 272.251044 -345.492369) (xy 272.251044 -345.492376) (xy 272.24328 -345.546373) (xy 272.22791 -345.598715)
			(xy 272.205247 -345.648336) (xy 272.175752 -345.694227) (xy 272.140027 -345.735453) (xy 272.098797 -345.771175)
			(xy 272.052903 -345.800665) (xy 272.003279 -345.823323) (xy 271.950936 -345.838688) (xy 271.896938 -345.846447)
			(xy 271.869662 -345.846908) (xy 271.006062 -345.846908) (xy 270.978798 -345.846327) (xy 270.924825 -345.838562)
			(xy 270.872506 -345.823195) (xy 270.822907 -345.80054) (xy 270.777036 -345.771056) (xy 270.735828 -345.735345)
			(xy 270.700121 -345.694134) (xy 270.670642 -345.64826) (xy 270.647992 -345.598658) (xy 270.63263 -345.546338)
			(xy 270.62487 -345.492364) (xy 269.142021 -345.492364) (xy 269.142021 -345.492373) (xy 269.134259 -345.546362)
			(xy 269.118892 -345.598698) (xy 269.096233 -345.648314) (xy 269.066744 -345.6942) (xy 269.031024 -345.735423)
			(xy 268.989802 -345.771143) (xy 268.943916 -345.800632) (xy 268.8943 -345.823291) (xy 268.841964 -345.838658)
			(xy 268.787975 -345.846421) (xy 268.760702 -345.846908) (xy 267.897102 -345.846908) (xy 267.869834 -345.846353)
			(xy 267.815854 -345.838592) (xy 267.763527 -345.823228) (xy 267.71392 -345.800573) (xy 267.668041 -345.771089)
			(xy 267.626826 -345.735376) (xy 267.591112 -345.69416) (xy 267.561628 -345.648282) (xy 267.538973 -345.598675)
			(xy 267.523609 -345.546348) (xy 267.515847 -345.492368) (xy 266.861658 -345.492368) (xy 266.882138 -345.520539)
			(xy 266.905832 -345.56702) (xy 266.921957 -345.616638) (xy 266.930116 -345.668168) (xy 266.930632 -345.694254)
			(xy 266.930632 -348.613072) (xy 267.515792 -348.613072) (xy 267.515792 -348.558528) (xy 267.523554 -348.50454)
			(xy 267.538921 -348.452206) (xy 267.561579 -348.402591) (xy 267.591068 -348.356706) (xy 267.626786 -348.315485)
			(xy 267.668008 -348.279766) (xy 267.713893 -348.250278) (xy 267.763507 -348.22762) (xy 267.815842 -348.212253)
			(xy 267.86983 -348.204491) (xy 267.897102 -348.204028) (xy 268.760702 -348.204028) (xy 268.787971 -348.204535)
			(xy 268.841953 -348.212296) (xy 268.89428 -348.227661) (xy 268.943889 -348.250317) (xy 268.989769 -348.279802)
			(xy 269.030985 -348.315517) (xy 269.066699 -348.356733) (xy 269.096184 -348.402613) (xy 269.118839 -348.452221)
			(xy 269.134204 -348.504549) (xy 269.141966 -348.558531) (xy 269.141966 -348.613068) (xy 270.624814 -348.613068)
			(xy 270.624814 -348.558532) (xy 270.632575 -348.50455) (xy 270.647939 -348.452222) (xy 270.670593 -348.402613)
			(xy 270.700076 -348.356733) (xy 270.735788 -348.315515) (xy 270.777002 -348.279799) (xy 270.82288 -348.250311)
			(xy 270.872486 -348.227652) (xy 270.924813 -348.212283) (xy 270.978794 -348.204517) (xy 271.006062 -348.204028)
			(xy 271.869662 -348.204028) (xy 271.896934 -348.204509) (xy 271.950924 -348.212266) (xy 272.00326 -348.227629)
			(xy 272.052876 -348.250284) (xy 272.098763 -348.27977) (xy 272.139987 -348.315486) (xy 272.175708 -348.356706)
			(xy 272.205198 -348.40259) (xy 272.227858 -348.452205) (xy 272.243226 -348.504539) (xy 272.250988 -348.558528)
			(xy 272.250988 -348.613072) (xy 272.250988 -348.613073) (xy 273.733692 -348.613073) (xy 273.733692 -348.558527)
			(xy 273.741454 -348.504537) (xy 273.756822 -348.452201) (xy 273.779482 -348.402585) (xy 273.808972 -348.356699)
			(xy 273.844693 -348.315478) (xy 273.885917 -348.279759) (xy 273.931805 -348.250271) (xy 273.981422 -348.227615)
			(xy 274.033759 -348.21225) (xy 274.087749 -348.20449) (xy 274.115022 -348.204028) (xy 274.978622 -348.204028)
			(xy 275.00589 -348.204536) (xy 275.059869 -348.2123) (xy 275.112195 -348.227667) (xy 275.161801 -348.250324)
			(xy 275.207678 -348.279809) (xy 275.248892 -348.315524) (xy 275.284604 -348.35674) (xy 275.314087 -348.402618)
			(xy 275.336741 -348.452226) (xy 275.352105 -348.504552) (xy 275.359866 -348.558532) (xy 275.359866 -348.613068)
			(xy 275.359866 -348.613069) (xy 276.842714 -348.613069) (xy 276.842714 -348.558531) (xy 276.850476 -348.504547)
			(xy 276.865841 -348.452218) (xy 276.888496 -348.402608) (xy 276.917981 -348.356726) (xy 276.953695 -348.315508)
			(xy 276.994912 -348.279792) (xy 277.040792 -348.250305) (xy 277.090401 -348.227647) (xy 277.14273 -348.21228)
			(xy 277.196713 -348.204516) (xy 277.223982 -348.204028) (xy 278.087582 -348.204028) (xy 278.114853 -348.20451)
			(xy 278.168841 -348.21227) (xy 278.221174 -348.227634) (xy 278.270788 -348.25029) (xy 278.316673 -348.279777)
			(xy 278.357894 -348.315493) (xy 278.393612 -348.356713) (xy 278.423101 -348.402596) (xy 278.445759 -348.452209)
			(xy 278.461126 -348.504542) (xy 278.468888 -348.558529) (xy 278.468888 -348.613071) (xy 278.468888 -348.613074)
			(xy 279.951592 -348.613074) (xy 279.951592 -348.558526) (xy 279.959355 -348.504534) (xy 279.974724 -348.452197)
			(xy 279.997385 -348.40258) (xy 280.026877 -348.356693) (xy 280.0626 -348.315471) (xy 280.103827 -348.279752)
			(xy 280.149717 -348.250265) (xy 280.199336 -348.227609) (xy 280.251676 -348.212246) (xy 280.305668 -348.204489)
			(xy 280.332942 -348.204028) (xy 281.196542 -348.204028) (xy 281.223809 -348.204537) (xy 281.277786 -348.212304)
			(xy 281.330109 -348.227672) (xy 281.379713 -348.25033) (xy 281.425587 -348.279816) (xy 281.466799 -348.315531)
			(xy 281.502509 -348.356746) (xy 281.53199 -348.402624) (xy 281.554643 -348.45223) (xy 281.570005 -348.504555)
			(xy 281.577766 -348.558533) (xy 281.577766 -348.613067) (xy 281.577765 -348.613072) (xy 283.060592 -348.613072)
			(xy 283.060592 -348.558528) (xy 283.068354 -348.50454) (xy 283.083721 -348.452206) (xy 283.106379 -348.402591)
			(xy 283.135868 -348.356706) (xy 283.171586 -348.315485) (xy 283.212808 -348.279766) (xy 283.258693 -348.250278)
			(xy 283.308307 -348.22762) (xy 283.360642 -348.212253) (xy 283.41463 -348.204491) (xy 283.441902 -348.204028)
			(xy 284.305502 -348.204028) (xy 284.332771 -348.204535) (xy 284.386753 -348.212296) (xy 284.43908 -348.227661)
			(xy 284.488689 -348.250317) (xy 284.534569 -348.279802) (xy 284.575785 -348.315517) (xy 284.611499 -348.356733)
			(xy 284.640984 -348.402613) (xy 284.663639 -348.452221) (xy 284.679004 -348.504549) (xy 284.686766 -348.558531)
			(xy 284.686766 -348.613068) (xy 286.169614 -348.613068) (xy 286.169614 -348.558532) (xy 286.177375 -348.50455)
			(xy 286.192739 -348.452222) (xy 286.215393 -348.402613) (xy 286.244876 -348.356733) (xy 286.280588 -348.315515)
			(xy 286.321802 -348.279799) (xy 286.36768 -348.250311) (xy 286.417286 -348.227652) (xy 286.469613 -348.212283)
			(xy 286.523594 -348.204517) (xy 286.550862 -348.204028) (xy 287.414462 -348.204028) (xy 287.441734 -348.204509)
			(xy 287.495724 -348.212266) (xy 287.54806 -348.227629) (xy 287.597676 -348.250284) (xy 287.643563 -348.27977)
			(xy 287.684787 -348.315486) (xy 287.720508 -348.356706) (xy 287.749998 -348.40259) (xy 287.772658 -348.452205)
			(xy 287.788026 -348.504539) (xy 287.795788 -348.558528) (xy 287.795788 -348.613072) (xy 287.795788 -348.613073)
			(xy 289.278492 -348.613073) (xy 289.278492 -348.558527) (xy 289.286254 -348.504537) (xy 289.301622 -348.452201)
			(xy 289.324282 -348.402585) (xy 289.353772 -348.356699) (xy 289.389493 -348.315478) (xy 289.430717 -348.279759)
			(xy 289.476605 -348.250271) (xy 289.526222 -348.227615) (xy 289.578559 -348.21225) (xy 289.632549 -348.20449)
			(xy 289.659822 -348.204028) (xy 290.523422 -348.204028) (xy 290.55069 -348.204536) (xy 290.604669 -348.2123)
			(xy 290.656995 -348.227667) (xy 290.706601 -348.250324) (xy 290.752478 -348.279809) (xy 290.793692 -348.315524)
			(xy 290.829404 -348.35674) (xy 290.858887 -348.402618) (xy 290.881541 -348.452226) (xy 290.896905 -348.504552)
			(xy 290.904666 -348.558532) (xy 290.904666 -348.613068) (xy 290.904666 -348.613069) (xy 292.387514 -348.613069)
			(xy 292.387514 -348.558531) (xy 292.395276 -348.504547) (xy 292.410641 -348.452218) (xy 292.433296 -348.402608)
			(xy 292.462781 -348.356726) (xy 292.498495 -348.315508) (xy 292.539712 -348.279792) (xy 292.585592 -348.250305)
			(xy 292.635201 -348.227647) (xy 292.68753 -348.21228) (xy 292.741513 -348.204516) (xy 292.768782 -348.204028)
			(xy 293.632382 -348.204028) (xy 293.659653 -348.20451) (xy 293.713641 -348.21227) (xy 293.765974 -348.227634)
			(xy 293.815588 -348.25029) (xy 293.861473 -348.279777) (xy 293.902694 -348.315493) (xy 293.938412 -348.356713)
			(xy 293.967901 -348.402596) (xy 293.990559 -348.452209) (xy 294.005926 -348.504542) (xy 294.013688 -348.558529)
			(xy 294.013688 -348.613071) (xy 294.013688 -348.613074) (xy 295.496392 -348.613074) (xy 295.496392 -348.558526)
			(xy 295.504155 -348.504534) (xy 295.519524 -348.452197) (xy 295.542185 -348.40258) (xy 295.571677 -348.356693)
			(xy 295.6074 -348.315471) (xy 295.648627 -348.279752) (xy 295.694517 -348.250265) (xy 295.744136 -348.227609)
			(xy 295.796476 -348.212246) (xy 295.850468 -348.204489) (xy 295.877742 -348.204028) (xy 296.741342 -348.204028)
			(xy 296.768609 -348.204537) (xy 296.822586 -348.212304) (xy 296.874909 -348.227672) (xy 296.924513 -348.25033)
			(xy 296.970387 -348.279816) (xy 297.011599 -348.315531) (xy 297.047309 -348.356746) (xy 297.07679 -348.402624)
			(xy 297.099443 -348.45223) (xy 297.114805 -348.504555) (xy 297.122566 -348.558533) (xy 297.122566 -348.613067)
			(xy 297.122565 -348.613072) (xy 298.605392 -348.613072) (xy 298.605392 -348.558528) (xy 298.613154 -348.50454)
			(xy 298.628521 -348.452206) (xy 298.651179 -348.402591) (xy 298.680668 -348.356706) (xy 298.716386 -348.315485)
			(xy 298.757608 -348.279766) (xy 298.803493 -348.250278) (xy 298.853107 -348.22762) (xy 298.905442 -348.212253)
			(xy 298.95943 -348.204491) (xy 298.986702 -348.204028) (xy 299.850302 -348.204028) (xy 299.877571 -348.204535)
			(xy 299.931553 -348.212296) (xy 299.98388 -348.227661) (xy 300.033489 -348.250317) (xy 300.079369 -348.279802)
			(xy 300.120585 -348.315517) (xy 300.156299 -348.356733) (xy 300.185784 -348.402613) (xy 300.208439 -348.452221)
			(xy 300.223804 -348.504549) (xy 300.231566 -348.558531) (xy 300.231566 -348.613069) (xy 300.223804 -348.667051)
			(xy 300.208439 -348.719379) (xy 300.185784 -348.768987) (xy 300.156299 -348.814867) (xy 300.120585 -348.856083)
			(xy 300.079369 -348.891798) (xy 300.033489 -348.921283) (xy 299.98388 -348.943939) (xy 299.931553 -348.959304)
			(xy 299.877571 -348.967065) (xy 299.850302 -348.967552) (xy 298.986702 -348.967552) (xy 298.95943 -348.967109)
			(xy 298.905442 -348.959347) (xy 298.853107 -348.94398) (xy 298.803493 -348.921322) (xy 298.757608 -348.891834)
			(xy 298.716386 -348.856115) (xy 298.680668 -348.814894) (xy 298.651179 -348.769009) (xy 298.628521 -348.719394)
			(xy 298.613154 -348.66706) (xy 298.605392 -348.613072) (xy 297.122565 -348.613072) (xy 297.114805 -348.667045)
			(xy 297.099443 -348.71937) (xy 297.07679 -348.768976) (xy 297.047309 -348.814854) (xy 297.011599 -348.856069)
			(xy 296.970387 -348.891784) (xy 296.924513 -348.92127) (xy 296.874909 -348.943928) (xy 296.822586 -348.959296)
			(xy 296.768609 -348.967063) (xy 296.741342 -348.967552) (xy 295.877742 -348.967552) (xy 295.850468 -348.967111)
			(xy 295.796476 -348.959354) (xy 295.744136 -348.943991) (xy 295.694517 -348.921335) (xy 295.648627 -348.891848)
			(xy 295.6074 -348.856129) (xy 295.571677 -348.814907) (xy 295.542185 -348.76902) (xy 295.519524 -348.719403)
			(xy 295.504155 -348.667066) (xy 295.496392 -348.613074) (xy 294.013688 -348.613074) (xy 294.005926 -348.667058)
			(xy 293.990559 -348.719391) (xy 293.967901 -348.769004) (xy 293.938412 -348.814887) (xy 293.902694 -348.856107)
			(xy 293.861473 -348.891823) (xy 293.815588 -348.92131) (xy 293.765974 -348.943966) (xy 293.713641 -348.95933)
			(xy 293.659653 -348.96709) (xy 293.632382 -348.967552) (xy 292.768782 -348.967552) (xy 292.741513 -348.967084)
			(xy 292.68753 -348.95932) (xy 292.635201 -348.943953) (xy 292.585592 -348.921295) (xy 292.539712 -348.891808)
			(xy 292.498495 -348.856092) (xy 292.462781 -348.814874) (xy 292.433296 -348.768992) (xy 292.410641 -348.719382)
			(xy 292.395276 -348.667053) (xy 292.387514 -348.613069) (xy 290.904666 -348.613069) (xy 290.896905 -348.667048)
			(xy 290.881541 -348.719374) (xy 290.858887 -348.768982) (xy 290.829404 -348.81486) (xy 290.793692 -348.856076)
			(xy 290.752478 -348.891791) (xy 290.706601 -348.921276) (xy 290.656995 -348.943933) (xy 290.604669 -348.9593)
			(xy 290.55069 -348.967064) (xy 290.523422 -348.967552) (xy 289.659822 -348.967552) (xy 289.632549 -348.96711)
			(xy 289.578559 -348.95935) (xy 289.526222 -348.943985) (xy 289.476605 -348.921329) (xy 289.430717 -348.891841)
			(xy 289.389493 -348.856122) (xy 289.353772 -348.814901) (xy 289.324282 -348.769015) (xy 289.301622 -348.719399)
			(xy 289.286254 -348.667063) (xy 289.278492 -348.613073) (xy 287.795788 -348.613073) (xy 287.788026 -348.667061)
			(xy 287.772658 -348.719395) (xy 287.749998 -348.76901) (xy 287.720508 -348.814894) (xy 287.684787 -348.856114)
			(xy 287.643563 -348.89183) (xy 287.597676 -348.921316) (xy 287.54806 -348.943971) (xy 287.495724 -348.959334)
			(xy 287.441734 -348.967091) (xy 287.414462 -348.967552) (xy 286.550862 -348.967552) (xy 286.523594 -348.967083)
			(xy 286.469613 -348.959317) (xy 286.417286 -348.943948) (xy 286.36768 -348.921289) (xy 286.321802 -348.891801)
			(xy 286.280588 -348.856085) (xy 286.244876 -348.814867) (xy 286.215393 -348.768987) (xy 286.192739 -348.719378)
			(xy 286.177375 -348.66705) (xy 286.169614 -348.613068) (xy 284.686766 -348.613068) (xy 284.686766 -348.613069)
			(xy 284.679004 -348.667051) (xy 284.663639 -348.719379) (xy 284.640984 -348.768987) (xy 284.611499 -348.814867)
			(xy 284.575785 -348.856083) (xy 284.534569 -348.891798) (xy 284.488689 -348.921283) (xy 284.43908 -348.943939)
			(xy 284.386753 -348.959304) (xy 284.332771 -348.967065) (xy 284.305502 -348.967552) (xy 283.441902 -348.967552)
			(xy 283.41463 -348.967109) (xy 283.360642 -348.959347) (xy 283.308307 -348.94398) (xy 283.258693 -348.921322)
			(xy 283.212808 -348.891834) (xy 283.171586 -348.856115) (xy 283.135868 -348.814894) (xy 283.106379 -348.769009)
			(xy 283.083721 -348.719394) (xy 283.068354 -348.66706) (xy 283.060592 -348.613072) (xy 281.577765 -348.613072)
			(xy 281.570005 -348.667045) (xy 281.554643 -348.71937) (xy 281.53199 -348.768976) (xy 281.502509 -348.814854)
			(xy 281.466799 -348.856069) (xy 281.425587 -348.891784) (xy 281.379713 -348.92127) (xy 281.330109 -348.943928)
			(xy 281.277786 -348.959296) (xy 281.223809 -348.967063) (xy 281.196542 -348.967552) (xy 280.332942 -348.967552)
			(xy 280.305668 -348.967111) (xy 280.251676 -348.959354) (xy 280.199336 -348.943991) (xy 280.149717 -348.921335)
			(xy 280.103827 -348.891848) (xy 280.0626 -348.856129) (xy 280.026877 -348.814907) (xy 279.997385 -348.76902)
			(xy 279.974724 -348.719403) (xy 279.959355 -348.667066) (xy 279.951592 -348.613074) (xy 278.468888 -348.613074)
			(xy 278.461126 -348.667058) (xy 278.445759 -348.719391) (xy 278.423101 -348.769004) (xy 278.393612 -348.814887)
			(xy 278.357894 -348.856107) (xy 278.316673 -348.891823) (xy 278.270788 -348.92131) (xy 278.221174 -348.943966)
			(xy 278.168841 -348.95933) (xy 278.114853 -348.96709) (xy 278.087582 -348.967552) (xy 277.223982 -348.967552)
			(xy 277.196713 -348.967084) (xy 277.14273 -348.95932) (xy 277.090401 -348.943953) (xy 277.040792 -348.921295)
			(xy 276.994912 -348.891808) (xy 276.953695 -348.856092) (xy 276.917981 -348.814874) (xy 276.888496 -348.768992)
			(xy 276.865841 -348.719382) (xy 276.850476 -348.667053) (xy 276.842714 -348.613069) (xy 275.359866 -348.613069)
			(xy 275.352105 -348.667048) (xy 275.336741 -348.719374) (xy 275.314087 -348.768982) (xy 275.284604 -348.81486)
			(xy 275.248892 -348.856076) (xy 275.207678 -348.891791) (xy 275.161801 -348.921276) (xy 275.112195 -348.943933)
			(xy 275.059869 -348.9593) (xy 275.00589 -348.967064) (xy 274.978622 -348.967552) (xy 274.115022 -348.967552)
			(xy 274.087749 -348.96711) (xy 274.033759 -348.95935) (xy 273.981422 -348.943985) (xy 273.931805 -348.921329)
			(xy 273.885917 -348.891841) (xy 273.844693 -348.856122) (xy 273.808972 -348.814901) (xy 273.779482 -348.769015)
			(xy 273.756822 -348.719399) (xy 273.741454 -348.667063) (xy 273.733692 -348.613073) (xy 272.250988 -348.613073)
			(xy 272.243226 -348.667061) (xy 272.227858 -348.719395) (xy 272.205198 -348.76901) (xy 272.175708 -348.814894)
			(xy 272.139987 -348.856114) (xy 272.098763 -348.89183) (xy 272.052876 -348.921316) (xy 272.00326 -348.943971)
			(xy 271.950924 -348.959334) (xy 271.896934 -348.967091) (xy 271.869662 -348.967552) (xy 271.006062 -348.967552)
			(xy 270.978794 -348.967083) (xy 270.924813 -348.959317) (xy 270.872486 -348.943948) (xy 270.82288 -348.921289)
			(xy 270.777002 -348.891801) (xy 270.735788 -348.856085) (xy 270.700076 -348.814867) (xy 270.670593 -348.768987)
			(xy 270.647939 -348.719378) (xy 270.632575 -348.66705) (xy 270.624814 -348.613068) (xy 269.141966 -348.613068)
			(xy 269.141966 -348.613069) (xy 269.134204 -348.667051) (xy 269.118839 -348.719379) (xy 269.096184 -348.768987)
			(xy 269.066699 -348.814867) (xy 269.030985 -348.856083) (xy 268.989769 -348.891798) (xy 268.943889 -348.921283)
			(xy 268.89428 -348.943939) (xy 268.841953 -348.959304) (xy 268.787971 -348.967065) (xy 268.760702 -348.967552)
			(xy 267.897102 -348.967552) (xy 267.86983 -348.967109) (xy 267.815842 -348.959347) (xy 267.763507 -348.94398)
			(xy 267.713893 -348.921322) (xy 267.668008 -348.891834) (xy 267.626786 -348.856115) (xy 267.591068 -348.814894)
			(xy 267.561579 -348.769009) (xy 267.538921 -348.719394) (xy 267.523554 -348.66706) (xy 267.515792 -348.613072)
			(xy 266.930632 -348.613072) (xy 266.930632 -349.740982) (xy 266.931049 -349.751003) (xy 266.938717 -349.769521)
			(xy 266.952891 -349.783691) (xy 266.971411 -349.791354) (xy 266.981432 -349.791782) (xy 267.157708 -349.791782)
			(xy 267.167716 -349.792271) (xy 267.186208 -349.799931) (xy 267.200363 -349.814083) (xy 267.208027 -349.832574)
			(xy 267.208508 -349.842582) (xy 267.208508 -351.638668) (xy 267.515839 -351.638668) (xy 267.515839 -351.584132)
			(xy 267.523601 -351.53015) (xy 267.538966 -351.477822) (xy 267.561621 -351.428214) (xy 267.591106 -351.382335)
			(xy 267.62682 -351.341119) (xy 267.668036 -351.305405) (xy 267.713916 -351.27592) (xy 267.763524 -351.253265)
			(xy 267.815852 -351.2379) (xy 267.869834 -351.230139) (xy 267.897102 -351.229676) (xy 268.760702 -351.229676)
			(xy 268.787974 -351.230087) (xy 268.841963 -351.237849) (xy 268.894297 -351.253216) (xy 268.943912 -351.275875)
			(xy 268.989797 -351.305364) (xy 269.031019 -351.341083) (xy 269.066737 -351.382304) (xy 269.096226 -351.42819)
			(xy 269.118884 -351.477805) (xy 269.134251 -351.530139) (xy 269.142013 -351.584128) (xy 269.142013 -351.638665)
			(xy 270.624862 -351.638665) (xy 270.624862 -351.584135) (xy 270.632622 -351.53016) (xy 270.647984 -351.477839)
			(xy 270.670635 -351.428236) (xy 270.700115 -351.382362) (xy 270.735822 -351.341149) (xy 270.777031 -351.305437)
			(xy 270.822903 -351.275953) (xy 270.872503 -351.253297) (xy 270.924823 -351.23793) (xy 270.978797 -351.230165)
			(xy 271.006062 -351.229676) (xy 271.869662 -351.229676) (xy 271.896937 -351.230061) (xy 271.950934 -351.23782)
			(xy 272.003276 -351.253184) (xy 272.052899 -351.275842) (xy 272.098792 -351.305331) (xy 272.140021 -351.341052)
			(xy 272.175746 -351.382277) (xy 272.20524 -351.428167) (xy 272.227903 -351.477788) (xy 272.243272 -351.530129)
			(xy 272.251036 -351.584125) (xy 272.251036 -351.638669) (xy 273.733739 -351.638669) (xy 273.733739 -351.584131)
			(xy 273.741501 -351.530147) (xy 273.756867 -351.477818) (xy 273.779524 -351.428208) (xy 273.809011 -351.382328)
			(xy 273.844727 -351.341112) (xy 273.885946 -351.305398) (xy 273.931828 -351.275914) (xy 273.981439 -351.25326)
			(xy 274.033769 -351.237897) (xy 274.087753 -351.230138) (xy 274.115022 -351.229676) (xy 274.978622 -351.229676)
			(xy 275.005893 -351.230088) (xy 275.05988 -351.237853) (xy 275.112212 -351.253222) (xy 275.161824 -351.275881)
			(xy 275.207707 -351.305371) (xy 275.248926 -351.34109) (xy 275.284642 -351.382311) (xy 275.314129 -351.428195)
			(xy 275.336786 -351.477809) (xy 275.352152 -351.530142) (xy 275.359914 -351.584129) (xy 275.359914 -351.638666)
			(xy 276.842762 -351.638666) (xy 276.842762 -351.584134) (xy 276.850523 -351.530158) (xy 276.865886 -351.477835)
			(xy 276.888538 -351.428231) (xy 276.91802 -351.382355) (xy 276.953729 -351.341142) (xy 276.994941 -351.30543)
			(xy 277.040815 -351.275947) (xy 277.090418 -351.253292) (xy 277.14274 -351.237927) (xy 277.196716 -351.230164)
			(xy 277.223982 -351.229676) (xy 278.087582 -351.229676) (xy 278.114857 -351.230062) (xy 278.168851 -351.237823)
			(xy 278.221191 -351.253189) (xy 278.270811 -351.275848) (xy 278.316702 -351.305338) (xy 278.357928 -351.341059)
			(xy 278.393651 -351.382284) (xy 278.423143 -351.428173) (xy 278.445804 -351.477792) (xy 278.461173 -351.530132)
			(xy 278.468936 -351.584125) (xy 278.468936 -351.63867) (xy 279.95164 -351.63867) (xy 279.95164 -351.58413)
			(xy 279.959402 -351.530145) (xy 279.974769 -351.477814) (xy 279.997427 -351.428203) (xy 280.026916 -351.382322)
			(xy 280.062634 -351.341105) (xy 280.103855 -351.305391) (xy 280.14974 -351.275907) (xy 280.199353 -351.253254)
			(xy 280.251686 -351.237893) (xy 280.305672 -351.230137) (xy 280.332942 -351.229676) (xy 281.196542 -351.229676)
			(xy 281.223812 -351.230089) (xy 281.277797 -351.237857) (xy 281.330126 -351.253227) (xy 281.379736 -351.275888)
			(xy 281.425616 -351.305378) (xy 281.466833 -351.341097) (xy 281.502547 -351.382317) (xy 281.532032 -351.428201)
			(xy 281.554688 -351.477813) (xy 281.570052 -351.530145) (xy 281.577814 -351.58413) (xy 281.577814 -351.638668)
			(xy 283.060639 -351.638668) (xy 283.060639 -351.584132) (xy 283.068401 -351.53015) (xy 283.083766 -351.477822)
			(xy 283.106421 -351.428214) (xy 283.135906 -351.382335) (xy 283.17162 -351.341119) (xy 283.212836 -351.305405)
			(xy 283.258716 -351.27592) (xy 283.308324 -351.253265) (xy 283.360652 -351.2379) (xy 283.414634 -351.230139)
			(xy 283.441902 -351.229676) (xy 284.305502 -351.229676) (xy 284.332774 -351.230087) (xy 284.386763 -351.237849)
			(xy 284.439097 -351.253216) (xy 284.488712 -351.275875) (xy 284.534597 -351.305364) (xy 284.575819 -351.341083)
			(xy 284.611537 -351.382304) (xy 284.641026 -351.42819) (xy 284.663684 -351.477805) (xy 284.679051 -351.530139)
			(xy 284.686813 -351.584128) (xy 284.686813 -351.638665) (xy 286.169662 -351.638665) (xy 286.169662 -351.584135)
			(xy 286.177422 -351.53016) (xy 286.192784 -351.477839) (xy 286.215435 -351.428236) (xy 286.244915 -351.382362)
			(xy 286.280622 -351.341149) (xy 286.321831 -351.305437) (xy 286.367703 -351.275953) (xy 286.417303 -351.253297)
			(xy 286.469623 -351.23793) (xy 286.523597 -351.230165) (xy 286.550862 -351.229676) (xy 287.414462 -351.229676)
			(xy 287.441737 -351.230061) (xy 287.495734 -351.23782) (xy 287.548076 -351.253184) (xy 287.597699 -351.275842)
			(xy 287.643592 -351.305331) (xy 287.684821 -351.341052) (xy 287.720546 -351.382277) (xy 287.75004 -351.428167)
			(xy 287.772703 -351.477788) (xy 287.788072 -351.530129) (xy 287.795836 -351.584125) (xy 287.795836 -351.638669)
			(xy 289.278539 -351.638669) (xy 289.278539 -351.584131) (xy 289.286301 -351.530147) (xy 289.301667 -351.477818)
			(xy 289.324324 -351.428208) (xy 289.353811 -351.382328) (xy 289.389527 -351.341112) (xy 289.430746 -351.305398)
			(xy 289.476628 -351.275914) (xy 289.526239 -351.25326) (xy 289.578569 -351.237897) (xy 289.632553 -351.230138)
			(xy 289.659822 -351.229676) (xy 290.523422 -351.229676) (xy 290.550693 -351.230088) (xy 290.60468 -351.237853)
			(xy 290.657012 -351.253222) (xy 290.706624 -351.275881) (xy 290.752507 -351.305371) (xy 290.793726 -351.34109)
			(xy 290.829442 -351.382311) (xy 290.858929 -351.428195) (xy 290.881586 -351.477809) (xy 290.896952 -351.530142)
			(xy 290.904714 -351.584129) (xy 290.904714 -351.638666) (xy 292.387562 -351.638666) (xy 292.387562 -351.584134)
			(xy 292.395323 -351.530158) (xy 292.410686 -351.477835) (xy 292.433338 -351.428231) (xy 292.46282 -351.382355)
			(xy 292.498529 -351.341142) (xy 292.539741 -351.30543) (xy 292.585615 -351.275947) (xy 292.635218 -351.253292)
			(xy 292.68754 -351.237927) (xy 292.741516 -351.230164) (xy 292.768782 -351.229676) (xy 293.632382 -351.229676)
			(xy 293.659657 -351.230062) (xy 293.713651 -351.237823) (xy 293.765991 -351.253189) (xy 293.815611 -351.275848)
			(xy 293.861502 -351.305338) (xy 293.902728 -351.341059) (xy 293.938451 -351.382284) (xy 293.967943 -351.428173)
			(xy 293.990604 -351.477792) (xy 294.005973 -351.530132) (xy 294.013736 -351.584125) (xy 294.013736 -351.63867)
			(xy 295.49644 -351.63867) (xy 295.49644 -351.58413) (xy 295.504202 -351.530145) (xy 295.519569 -351.477814)
			(xy 295.542227 -351.428203) (xy 295.571716 -351.382322) (xy 295.607434 -351.341105) (xy 295.648655 -351.305391)
			(xy 295.69454 -351.275907) (xy 295.744153 -351.253254) (xy 295.796486 -351.237893) (xy 295.850472 -351.230137)
			(xy 295.877742 -351.229676) (xy 296.741342 -351.229676) (xy 296.768612 -351.230089) (xy 296.822597 -351.237857)
			(xy 296.874926 -351.253227) (xy 296.924536 -351.275888) (xy 296.970416 -351.305378) (xy 297.011633 -351.341097)
			(xy 297.047347 -351.382317) (xy 297.076832 -351.428201) (xy 297.099488 -351.477813) (xy 297.114852 -351.530145)
			(xy 297.122614 -351.58413) (xy 297.122614 -351.638668) (xy 298.605439 -351.638668) (xy 298.605439 -351.584132)
			(xy 298.613201 -351.53015) (xy 298.628566 -351.477822) (xy 298.651221 -351.428214) (xy 298.680706 -351.382335)
			(xy 298.71642 -351.341119) (xy 298.757636 -351.305405) (xy 298.803516 -351.27592) (xy 298.853124 -351.253265)
			(xy 298.905452 -351.2379) (xy 298.959434 -351.230139) (xy 298.986702 -351.229676) (xy 299.850302 -351.229676)
			(xy 299.877574 -351.230087) (xy 299.931563 -351.237849) (xy 299.983897 -351.253216) (xy 300.033512 -351.275875)
			(xy 300.079397 -351.305364) (xy 300.120619 -351.341083) (xy 300.156337 -351.382304) (xy 300.185826 -351.42819)
			(xy 300.208484 -351.477805) (xy 300.223851 -351.530139) (xy 300.231613 -351.584128) (xy 300.231613 -351.638672)
			(xy 300.223851 -351.692661) (xy 300.208484 -351.744995) (xy 300.185826 -351.79461) (xy 300.156337 -351.840496)
			(xy 300.120619 -351.881717) (xy 300.079397 -351.917436) (xy 300.033512 -351.946925) (xy 299.983897 -351.969584)
			(xy 299.931563 -351.984951) (xy 299.877574 -351.992713) (xy 299.850302 -351.9932) (xy 298.986702 -351.9932)
			(xy 298.959434 -351.992661) (xy 298.905452 -351.9849) (xy 298.853124 -351.969535) (xy 298.803516 -351.94688)
			(xy 298.757636 -351.917395) (xy 298.71642 -351.881681) (xy 298.680706 -351.840465) (xy 298.651221 -351.794586)
			(xy 298.628566 -351.744978) (xy 298.613201 -351.69265) (xy 298.605439 -351.638668) (xy 297.122614 -351.638668)
			(xy 297.122614 -351.63867) (xy 297.114852 -351.692655) (xy 297.099488 -351.744987) (xy 297.076832 -351.794599)
			(xy 297.047347 -351.840483) (xy 297.011633 -351.881703) (xy 296.970416 -351.917422) (xy 296.924536 -351.946912)
			(xy 296.874926 -351.969573) (xy 296.822597 -351.984943) (xy 296.768612 -351.992711) (xy 296.741342 -351.9932)
			(xy 295.877742 -351.9932) (xy 295.850472 -351.992663) (xy 295.796486 -351.984907) (xy 295.744153 -351.969546)
			(xy 295.69454 -351.946893) (xy 295.648655 -351.917409) (xy 295.607434 -351.881695) (xy 295.571716 -351.840478)
			(xy 295.542227 -351.794597) (xy 295.519569 -351.744986) (xy 295.504202 -351.692655) (xy 295.49644 -351.63867)
			(xy 294.013736 -351.63867) (xy 294.013736 -351.638675) (xy 294.005973 -351.692668) (xy 293.990604 -351.745008)
			(xy 293.967943 -351.794627) (xy 293.938451 -351.840516) (xy 293.902728 -351.881741) (xy 293.861502 -351.917462)
			(xy 293.815611 -351.946952) (xy 293.765991 -351.969611) (xy 293.713651 -351.984977) (xy 293.659657 -351.992738)
			(xy 293.632382 -351.9932) (xy 292.768782 -351.9932) (xy 292.741516 -351.992636) (xy 292.68754 -351.984873)
			(xy 292.635218 -351.969508) (xy 292.585615 -351.946853) (xy 292.539741 -351.91737) (xy 292.498529 -351.881658)
			(xy 292.46282 -351.840445) (xy 292.433338 -351.794569) (xy 292.410686 -351.744965) (xy 292.395323 -351.692642)
			(xy 292.387562 -351.638666) (xy 290.904714 -351.638666) (xy 290.904714 -351.638671) (xy 290.896952 -351.692658)
			(xy 290.881586 -351.744991) (xy 290.858929 -351.794605) (xy 290.829442 -351.840489) (xy 290.793726 -351.88171)
			(xy 290.752507 -351.917429) (xy 290.706624 -351.946919) (xy 290.657012 -351.969578) (xy 290.60468 -351.984947)
			(xy 290.550693 -351.992712) (xy 290.523422 -351.9932) (xy 289.659822 -351.9932) (xy 289.632553 -351.992662)
			(xy 289.578569 -351.984903) (xy 289.526239 -351.96954) (xy 289.476628 -351.946886) (xy 289.430746 -351.917402)
			(xy 289.389527 -351.881688) (xy 289.353811 -351.840472) (xy 289.324324 -351.794592) (xy 289.301667 -351.744982)
			(xy 289.286301 -351.692653) (xy 289.278539 -351.638669) (xy 287.795836 -351.638669) (xy 287.795836 -351.638675)
			(xy 287.788072 -351.692671) (xy 287.772703 -351.745012) (xy 287.75004 -351.794633) (xy 287.720546 -351.840523)
			(xy 287.684821 -351.881748) (xy 287.643592 -351.917469) (xy 287.597699 -351.946958) (xy 287.548076 -351.969616)
			(xy 287.495734 -351.98498) (xy 287.441737 -351.992739) (xy 287.414462 -351.9932) (xy 286.550862 -351.9932)
			(xy 286.523597 -351.992635) (xy 286.469623 -351.98487) (xy 286.417303 -351.969503) (xy 286.367703 -351.946847)
			(xy 286.321831 -351.917363) (xy 286.280622 -351.881651) (xy 286.244915 -351.840438) (xy 286.215435 -351.794564)
			(xy 286.192784 -351.744961) (xy 286.177422 -351.69264) (xy 286.169662 -351.638665) (xy 284.686813 -351.638665)
			(xy 284.686813 -351.638672) (xy 284.679051 -351.692661) (xy 284.663684 -351.744995) (xy 284.641026 -351.79461)
			(xy 284.611537 -351.840496) (xy 284.575819 -351.881717) (xy 284.534597 -351.917436) (xy 284.488712 -351.946925)
			(xy 284.439097 -351.969584) (xy 284.386763 -351.984951) (xy 284.332774 -351.992713) (xy 284.305502 -351.9932)
			(xy 283.441902 -351.9932) (xy 283.414634 -351.992661) (xy 283.360652 -351.9849) (xy 283.308324 -351.969535)
			(xy 283.258716 -351.94688) (xy 283.212836 -351.917395) (xy 283.17162 -351.881681) (xy 283.135906 -351.840465)
			(xy 283.106421 -351.794586) (xy 283.083766 -351.744978) (xy 283.068401 -351.69265) (xy 283.060639 -351.638668)
			(xy 281.577814 -351.638668) (xy 281.577814 -351.63867) (xy 281.570052 -351.692655) (xy 281.554688 -351.744987)
			(xy 281.532032 -351.794599) (xy 281.502547 -351.840483) (xy 281.466833 -351.881703) (xy 281.425616 -351.917422)
			(xy 281.379736 -351.946912) (xy 281.330126 -351.969573) (xy 281.277797 -351.984943) (xy 281.223812 -351.992711)
			(xy 281.196542 -351.9932) (xy 280.332942 -351.9932) (xy 280.305672 -351.992663) (xy 280.251686 -351.984907)
			(xy 280.199353 -351.969546) (xy 280.14974 -351.946893) (xy 280.103855 -351.917409) (xy 280.062634 -351.881695)
			(xy 280.026916 -351.840478) (xy 279.997427 -351.794597) (xy 279.974769 -351.744986) (xy 279.959402 -351.692655)
			(xy 279.95164 -351.63867) (xy 278.468936 -351.63867) (xy 278.468936 -351.638675) (xy 278.461173 -351.692668)
			(xy 278.445804 -351.745008) (xy 278.423143 -351.794627) (xy 278.393651 -351.840516) (xy 278.357928 -351.881741)
			(xy 278.316702 -351.917462) (xy 278.270811 -351.946952) (xy 278.221191 -351.969611) (xy 278.168851 -351.984977)
			(xy 278.114857 -351.992738) (xy 278.087582 -351.9932) (xy 277.223982 -351.9932) (xy 277.196716 -351.992636)
			(xy 277.14274 -351.984873) (xy 277.090418 -351.969508) (xy 277.040815 -351.946853) (xy 276.994941 -351.91737)
			(xy 276.953729 -351.881658) (xy 276.91802 -351.840445) (xy 276.888538 -351.794569) (xy 276.865886 -351.744965)
			(xy 276.850523 -351.692642) (xy 276.842762 -351.638666) (xy 275.359914 -351.638666) (xy 275.359914 -351.638671)
			(xy 275.352152 -351.692658) (xy 275.336786 -351.744991) (xy 275.314129 -351.794605) (xy 275.284642 -351.840489)
			(xy 275.248926 -351.88171) (xy 275.207707 -351.917429) (xy 275.161824 -351.946919) (xy 275.112212 -351.969578)
			(xy 275.05988 -351.984947) (xy 275.005893 -351.992712) (xy 274.978622 -351.9932) (xy 274.115022 -351.9932)
			(xy 274.087753 -351.992662) (xy 274.033769 -351.984903) (xy 273.981439 -351.96954) (xy 273.931828 -351.946886)
			(xy 273.885946 -351.917402) (xy 273.844727 -351.881688) (xy 273.809011 -351.840472) (xy 273.779524 -351.794592)
			(xy 273.756867 -351.744982) (xy 273.741501 -351.692653) (xy 273.733739 -351.638669) (xy 272.251036 -351.638669)
			(xy 272.251036 -351.638675) (xy 272.243272 -351.692671) (xy 272.227903 -351.745012) (xy 272.20524 -351.794633)
			(xy 272.175746 -351.840523) (xy 272.140021 -351.881748) (xy 272.098792 -351.917469) (xy 272.052899 -351.946958)
			(xy 272.003276 -351.969616) (xy 271.950934 -351.98498) (xy 271.896937 -351.992739) (xy 271.869662 -351.9932)
			(xy 271.006062 -351.9932) (xy 270.978797 -351.992635) (xy 270.924823 -351.98487) (xy 270.872503 -351.969503)
			(xy 270.822903 -351.946847) (xy 270.777031 -351.917363) (xy 270.735822 -351.881651) (xy 270.700115 -351.840438)
			(xy 270.670635 -351.794564) (xy 270.647984 -351.744961) (xy 270.632622 -351.69264) (xy 270.624862 -351.638665)
			(xy 269.142013 -351.638665) (xy 269.142013 -351.638672) (xy 269.134251 -351.692661) (xy 269.118884 -351.744995)
			(xy 269.096226 -351.79461) (xy 269.066737 -351.840496) (xy 269.031019 -351.881717) (xy 268.989797 -351.917436)
			(xy 268.943912 -351.946925) (xy 268.894297 -351.969584) (xy 268.841963 -351.984951) (xy 268.787974 -351.992713)
			(xy 268.760702 -351.9932) (xy 267.897102 -351.9932) (xy 267.869834 -351.992661) (xy 267.815852 -351.9849)
			(xy 267.763524 -351.969535) (xy 267.713916 -351.94688) (xy 267.668036 -351.917395) (xy 267.62682 -351.881681)
			(xy 267.591106 -351.840465) (xy 267.561621 -351.794586) (xy 267.538966 -351.744978) (xy 267.523601 -351.69265)
			(xy 267.515839 -351.638668) (xy 267.208508 -351.638668) (xy 267.208508 -354.759369) (xy 270.624806 -354.759369)
			(xy 270.624806 -354.704831) (xy 270.632567 -354.650848) (xy 270.647932 -354.598519) (xy 270.670586 -354.548909)
			(xy 270.70007 -354.503028) (xy 270.735783 -354.46181) (xy 270.776998 -354.426093) (xy 270.822876 -354.396604)
			(xy 270.872484 -354.373945) (xy 270.924811 -354.358575) (xy 270.978793 -354.350809) (xy 271.006062 -354.35032)
			(xy 271.869662 -354.35032) (xy 271.896933 -354.350817) (xy 271.950922 -354.358574) (xy 272.003257 -354.373936)
			(xy 272.052872 -354.396591) (xy 272.098759 -354.426076) (xy 272.139981 -354.461792) (xy 272.175701 -354.503011)
			(xy 272.205191 -354.548894) (xy 272.22785 -354.598508) (xy 272.243218 -354.650841) (xy 272.25098 -354.704829)
			(xy 272.25098 -354.759371) (xy 272.25098 -354.759373) (xy 273.733684 -354.759373) (xy 273.733684 -354.704827)
			(xy 273.741447 -354.650835) (xy 273.756815 -354.598498) (xy 273.779475 -354.548882) (xy 273.808966 -354.502995)
			(xy 273.844688 -354.461772) (xy 273.885912 -354.426053) (xy 273.931801 -354.396564) (xy 273.981419 -354.373907)
			(xy 274.033757 -354.358542) (xy 274.087749 -354.350782) (xy 274.115022 -354.35032) (xy 274.978622 -354.35032)
			(xy 275.005889 -354.350844) (xy 275.059868 -354.358608) (xy 275.112192 -354.373974) (xy 275.161797 -354.396631)
			(xy 275.207673 -354.426116) (xy 275.248886 -354.461829) (xy 275.284597 -354.503044) (xy 275.31408 -354.548922)
			(xy 275.336733 -354.598528) (xy 275.352097 -354.650854) (xy 275.359858 -354.704833) (xy 275.359858 -354.759367)
			(xy 275.359858 -354.75937) (xy 276.842706 -354.75937) (xy 276.842706 -354.70483) (xy 276.850468 -354.650846)
			(xy 276.865833 -354.598515) (xy 276.888489 -354.548904) (xy 276.917975 -354.503022) (xy 276.95369 -354.461802)
			(xy 276.994907 -354.426085) (xy 277.040788 -354.396598) (xy 277.090398 -354.373939) (xy 277.142728 -354.358572)
			(xy 277.196712 -354.350808) (xy 277.223982 -354.35032) (xy 278.087582 -354.35032) (xy 278.114853 -354.350818)
			(xy 278.168839 -354.358578) (xy 278.221171 -354.373942) (xy 278.270784 -354.396597) (xy 278.316668 -354.426083)
			(xy 278.357888 -354.461799) (xy 278.393606 -354.503018) (xy 278.423094 -354.5489) (xy 278.445752 -354.598512)
			(xy 278.461118 -354.650844) (xy 278.468881 -354.704829) (xy 278.468881 -354.759371) (xy 278.468881 -354.759374)
			(xy 279.951584 -354.759374) (xy 279.951584 -354.704826) (xy 279.959347 -354.650833) (xy 279.974716 -354.598494)
			(xy 279.997378 -354.548876) (xy 280.026871 -354.502988) (xy 280.062595 -354.461765) (xy 280.103822 -354.426046)
			(xy 280.149713 -354.396558) (xy 280.199334 -354.373902) (xy 280.251674 -354.358538) (xy 280.305668 -354.350781)
			(xy 280.332942 -354.35032) (xy 281.196542 -354.35032) (xy 281.223808 -354.350845) (xy 281.277785 -354.358611)
			(xy 281.330107 -354.37398) (xy 281.379709 -354.396637) (xy 281.425583 -354.426123) (xy 281.466793 -354.461836)
			(xy 281.502502 -354.503051) (xy 281.531983 -354.548928) (xy 281.554635 -354.598533) (xy 281.569998 -354.650856)
			(xy 281.577758 -354.704834) (xy 281.577758 -354.759366) (xy 281.577757 -354.759372) (xy 283.060584 -354.759372)
			(xy 283.060584 -354.704828) (xy 283.068346 -354.650838) (xy 283.083713 -354.598503) (xy 283.106372 -354.548887)
			(xy 283.135861 -354.503001) (xy 283.171581 -354.461779) (xy 283.212803 -354.42606) (xy 283.258689 -354.396571)
			(xy 283.308305 -354.373912) (xy 283.36064 -354.358546) (xy 283.41463 -354.350783) (xy 283.441902 -354.35032)
			(xy 284.305502 -354.35032) (xy 284.33277 -354.350843) (xy 284.386751 -354.358604) (xy 284.439078 -354.373969)
			(xy 284.488685 -354.396624) (xy 284.534564 -354.426109) (xy 284.575779 -354.461822) (xy 284.611493 -354.503038)
			(xy 284.640977 -354.548917) (xy 284.663632 -354.598524) (xy 284.678996 -354.650851) (xy 284.686758 -354.704832)
			(xy 284.686758 -354.759368) (xy 284.686758 -354.759369) (xy 286.169606 -354.759369) (xy 286.169606 -354.704831)
			(xy 286.177367 -354.650848) (xy 286.192732 -354.598519) (xy 286.215386 -354.548909) (xy 286.24487 -354.503028)
			(xy 286.280583 -354.46181) (xy 286.321798 -354.426093) (xy 286.367676 -354.396604) (xy 286.417284 -354.373945)
			(xy 286.469611 -354.358575) (xy 286.523593 -354.350809) (xy 286.550862 -354.35032) (xy 287.414462 -354.35032)
			(xy 287.441733 -354.350817) (xy 287.495722 -354.358574) (xy 287.548057 -354.373936) (xy 287.597672 -354.396591)
			(xy 287.643559 -354.426076) (xy 287.684781 -354.461792) (xy 287.720501 -354.503011) (xy 287.749991 -354.548894)
			(xy 287.77265 -354.598508) (xy 287.788018 -354.650841) (xy 287.79578 -354.704829) (xy 287.79578 -354.759371)
			(xy 287.79578 -354.759373) (xy 289.278484 -354.759373) (xy 289.278484 -354.704827) (xy 289.286247 -354.650835)
			(xy 289.301615 -354.598498) (xy 289.324275 -354.548882) (xy 289.353766 -354.502995) (xy 289.389488 -354.461772)
			(xy 289.430712 -354.426053) (xy 289.476601 -354.396564) (xy 289.526219 -354.373907) (xy 289.578557 -354.358542)
			(xy 289.632549 -354.350782) (xy 289.659822 -354.35032) (xy 290.523422 -354.35032) (xy 290.550689 -354.350844)
			(xy 290.604668 -354.358608) (xy 290.656992 -354.373974) (xy 290.706597 -354.396631) (xy 290.752473 -354.426116)
			(xy 290.793686 -354.461829) (xy 290.829397 -354.503044) (xy 290.85888 -354.548922) (xy 290.881533 -354.598528)
			(xy 290.896897 -354.650854) (xy 290.904658 -354.704833) (xy 290.904658 -354.759367) (xy 290.904658 -354.75937)
			(xy 292.387506 -354.75937) (xy 292.387506 -354.70483) (xy 292.395268 -354.650846) (xy 292.410633 -354.598515)
			(xy 292.433289 -354.548904) (xy 292.462775 -354.503022) (xy 292.49849 -354.461802) (xy 292.539707 -354.426085)
			(xy 292.585588 -354.396598) (xy 292.635198 -354.373939) (xy 292.687528 -354.358572) (xy 292.741512 -354.350808)
			(xy 292.768782 -354.35032) (xy 293.632382 -354.35032) (xy 293.659653 -354.350818) (xy 293.713639 -354.358578)
			(xy 293.765971 -354.373942) (xy 293.815584 -354.396597) (xy 293.861468 -354.426083) (xy 293.902688 -354.461799)
			(xy 293.938406 -354.503018) (xy 293.967894 -354.5489) (xy 293.990552 -354.598512) (xy 294.005918 -354.650844)
			(xy 294.013681 -354.704829) (xy 294.013681 -354.759371) (xy 294.013681 -354.759374) (xy 295.496384 -354.759374)
			(xy 295.496384 -354.704826) (xy 295.504147 -354.650833) (xy 295.519516 -354.598494) (xy 295.542178 -354.548876)
			(xy 295.571671 -354.502988) (xy 295.607395 -354.461765) (xy 295.648622 -354.426046) (xy 295.694513 -354.396558)
			(xy 295.744134 -354.373902) (xy 295.796474 -354.358538) (xy 295.850468 -354.350781) (xy 295.877742 -354.35032)
			(xy 296.741342 -354.35032) (xy 296.768608 -354.350845) (xy 296.822585 -354.358611) (xy 296.874907 -354.37398)
			(xy 296.924509 -354.396637) (xy 296.970383 -354.426123) (xy 297.011593 -354.461836) (xy 297.047302 -354.503051)
			(xy 297.076783 -354.548928) (xy 297.099435 -354.598533) (xy 297.114798 -354.650856) (xy 297.122558 -354.704834)
			(xy 297.122558 -354.759366) (xy 297.122557 -354.759372) (xy 298.605384 -354.759372) (xy 298.605384 -354.704828)
			(xy 298.613146 -354.650838) (xy 298.628513 -354.598503) (xy 298.651172 -354.548887) (xy 298.680661 -354.503001)
			(xy 298.716381 -354.461779) (xy 298.757603 -354.42606) (xy 298.803489 -354.396571) (xy 298.853105 -354.373912)
			(xy 298.90544 -354.358546) (xy 298.95943 -354.350783) (xy 298.986702 -354.35032) (xy 299.850302 -354.35032)
			(xy 299.87757 -354.350843) (xy 299.931551 -354.358604) (xy 299.983878 -354.373969) (xy 300.033485 -354.396624)
			(xy 300.079364 -354.426109) (xy 300.120579 -354.461822) (xy 300.156293 -354.503038) (xy 300.185777 -354.548917)
			(xy 300.208432 -354.598524) (xy 300.223796 -354.650851) (xy 300.231558 -354.704832) (xy 300.231558 -354.759368)
			(xy 300.223796 -354.813349) (xy 300.208432 -354.865676) (xy 300.185777 -354.915283) (xy 300.156293 -354.961162)
			(xy 300.120579 -355.002378) (xy 300.079364 -355.038091) (xy 300.033485 -355.067576) (xy 299.983878 -355.090231)
			(xy 299.931551 -355.105596) (xy 299.87757 -355.113357) (xy 299.850302 -355.113844) (xy 298.986702 -355.113844)
			(xy 298.95943 -355.113417) (xy 298.90544 -355.105654) (xy 298.853105 -355.090288) (xy 298.803489 -355.067629)
			(xy 298.757603 -355.03814) (xy 298.716381 -355.002421) (xy 298.680661 -354.961199) (xy 298.651172 -354.915313)
			(xy 298.628513 -354.865697) (xy 298.613146 -354.813362) (xy 298.605384 -354.759372) (xy 297.122557 -354.759372)
			(xy 297.114798 -354.813344) (xy 297.099435 -354.865667) (xy 297.076783 -354.915272) (xy 297.047302 -354.961149)
			(xy 297.011593 -355.002364) (xy 296.970383 -355.038077) (xy 296.924509 -355.067563) (xy 296.874907 -355.09022)
			(xy 296.822585 -355.105589) (xy 296.768608 -355.113355) (xy 296.741342 -355.113844) (xy 295.877742 -355.113844)
			(xy 295.850468 -355.113419) (xy 295.796474 -355.105662) (xy 295.744134 -355.090298) (xy 295.694513 -355.067642)
			(xy 295.648622 -355.038154) (xy 295.607395 -355.002435) (xy 295.571671 -354.961212) (xy 295.542178 -354.915324)
			(xy 295.519516 -354.865706) (xy 295.504147 -354.813367) (xy 295.496384 -354.759374) (xy 294.013681 -354.759374)
			(xy 294.005918 -354.813356) (xy 293.990552 -354.865688) (xy 293.967894 -354.9153) (xy 293.938406 -354.961182)
			(xy 293.902688 -355.002401) (xy 293.861468 -355.038117) (xy 293.815584 -355.067603) (xy 293.765971 -355.090258)
			(xy 293.713639 -355.105622) (xy 293.659653 -355.113382) (xy 293.632382 -355.113844) (xy 292.768782 -355.113844)
			(xy 292.741512 -355.113392) (xy 292.687528 -355.105628) (xy 292.635198 -355.090261) (xy 292.585588 -355.067602)
			(xy 292.539707 -355.038115) (xy 292.49849 -355.002398) (xy 292.462775 -354.961178) (xy 292.433289 -354.915296)
			(xy 292.410633 -354.865685) (xy 292.395268 -354.813354) (xy 292.387506 -354.75937) (xy 290.904658 -354.75937)
			(xy 290.896897 -354.813346) (xy 290.881533 -354.865672) (xy 290.85888 -354.915278) (xy 290.829397 -354.961156)
			(xy 290.793686 -355.002371) (xy 290.752473 -355.038084) (xy 290.706597 -355.067569) (xy 290.656992 -355.090226)
			(xy 290.604668 -355.105592) (xy 290.550689 -355.113356) (xy 290.523422 -355.113844) (xy 289.659822 -355.113844)
			(xy 289.632549 -355.113418) (xy 289.578557 -355.105658) (xy 289.526219 -355.090293) (xy 289.476601 -355.067636)
			(xy 289.430712 -355.038147) (xy 289.389488 -355.002428) (xy 289.353766 -354.961205) (xy 289.324275 -354.915318)
			(xy 289.301615 -354.865702) (xy 289.286247 -354.813365) (xy 289.278484 -354.759373) (xy 287.79578 -354.759373)
			(xy 287.788018 -354.813359) (xy 287.77265 -354.865692) (xy 287.749991 -354.915306) (xy 287.720501 -354.961189)
			(xy 287.684781 -355.002408) (xy 287.643559 -355.038124) (xy 287.597672 -355.067609) (xy 287.548057 -355.090264)
			(xy 287.495722 -355.105626) (xy 287.441733 -355.113383) (xy 287.414462 -355.113844) (xy 286.550862 -355.113844)
			(xy 286.523593 -355.113391) (xy 286.469611 -355.105625) (xy 286.417284 -355.090255) (xy 286.367676 -355.067596)
			(xy 286.321798 -355.038107) (xy 286.280583 -355.00239) (xy 286.24487 -354.961172) (xy 286.215386 -354.915291)
			(xy 286.192732 -354.865681) (xy 286.177367 -354.813352) (xy 286.169606 -354.759369) (xy 284.686758 -354.759369)
			(xy 284.678996 -354.813349) (xy 284.663632 -354.865676) (xy 284.640977 -354.915283) (xy 284.611493 -354.961162)
			(xy 284.575779 -355.002378) (xy 284.534564 -355.038091) (xy 284.488685 -355.067576) (xy 284.439078 -355.090231)
			(xy 284.386751 -355.105596) (xy 284.33277 -355.113357) (xy 284.305502 -355.113844) (xy 283.441902 -355.113844)
			(xy 283.41463 -355.113417) (xy 283.36064 -355.105654) (xy 283.308305 -355.090288) (xy 283.258689 -355.067629)
			(xy 283.212803 -355.03814) (xy 283.171581 -355.002421) (xy 283.135861 -354.961199) (xy 283.106372 -354.915313)
			(xy 283.083713 -354.865697) (xy 283.068346 -354.813362) (xy 283.060584 -354.759372) (xy 281.577757 -354.759372)
			(xy 281.569998 -354.813344) (xy 281.554635 -354.865667) (xy 281.531983 -354.915272) (xy 281.502502 -354.961149)
			(xy 281.466793 -355.002364) (xy 281.425583 -355.038077) (xy 281.379709 -355.067563) (xy 281.330107 -355.09022)
			(xy 281.277785 -355.105589) (xy 281.223808 -355.113355) (xy 281.196542 -355.113844) (xy 280.332942 -355.113844)
			(xy 280.305668 -355.113419) (xy 280.251674 -355.105662) (xy 280.199334 -355.090298) (xy 280.149713 -355.067642)
			(xy 280.103822 -355.038154) (xy 280.062595 -355.002435) (xy 280.026871 -354.961212) (xy 279.997378 -354.915324)
			(xy 279.974716 -354.865706) (xy 279.959347 -354.813367) (xy 279.951584 -354.759374) (xy 278.468881 -354.759374)
			(xy 278.461118 -354.813356) (xy 278.445752 -354.865688) (xy 278.423094 -354.9153) (xy 278.393606 -354.961182)
			(xy 278.357888 -355.002401) (xy 278.316668 -355.038117) (xy 278.270784 -355.067603) (xy 278.221171 -355.090258)
			(xy 278.168839 -355.105622) (xy 278.114853 -355.113382) (xy 278.087582 -355.113844) (xy 277.223982 -355.113844)
			(xy 277.196712 -355.113392) (xy 277.142728 -355.105628) (xy 277.090398 -355.090261) (xy 277.040788 -355.067602)
			(xy 276.994907 -355.038115) (xy 276.95369 -355.002398) (xy 276.917975 -354.961178) (xy 276.888489 -354.915296)
			(xy 276.865833 -354.865685) (xy 276.850468 -354.813354) (xy 276.842706 -354.75937) (xy 275.359858 -354.75937)
			(xy 275.352097 -354.813346) (xy 275.336733 -354.865672) (xy 275.31408 -354.915278) (xy 275.284597 -354.961156)
			(xy 275.248886 -355.002371) (xy 275.207673 -355.038084) (xy 275.161797 -355.067569) (xy 275.112192 -355.090226)
			(xy 275.059868 -355.105592) (xy 275.005889 -355.113356) (xy 274.978622 -355.113844) (xy 274.115022 -355.113844)
			(xy 274.087749 -355.113418) (xy 274.033757 -355.105658) (xy 273.981419 -355.090293) (xy 273.931801 -355.067636)
			(xy 273.885912 -355.038147) (xy 273.844688 -355.002428) (xy 273.808966 -354.961205) (xy 273.779475 -354.915318)
			(xy 273.756815 -354.865702) (xy 273.741447 -354.813365) (xy 273.733684 -354.759373) (xy 272.25098 -354.759373)
			(xy 272.243218 -354.813359) (xy 272.22785 -354.865692) (xy 272.205191 -354.915306) (xy 272.175701 -354.961189)
			(xy 272.139981 -355.002408) (xy 272.098759 -355.038124) (xy 272.052872 -355.067609) (xy 272.003257 -355.090264)
			(xy 271.950922 -355.105626) (xy 271.896933 -355.113383) (xy 271.869662 -355.113844) (xy 271.006062 -355.113844)
			(xy 270.978793 -355.113391) (xy 270.924811 -355.105625) (xy 270.872484 -355.090255) (xy 270.822876 -355.067596)
			(xy 270.776998 -355.038107) (xy 270.735783 -355.00239) (xy 270.70007 -354.961172) (xy 270.670586 -354.915291)
			(xy 270.647932 -354.865681) (xy 270.632567 -354.813352) (xy 270.624806 -354.759369) (xy 267.208508 -354.759369)
			(xy 267.208508 -355.193854) (xy 267.208941 -355.20392) (xy 267.21667 -355.222509) (xy 267.223494 -355.229922)
			(xy 268.563598 -356.569772) (xy 268.563598 -356.570026) (xy 269.778538 -357.784966) (xy 270.624854 -357.784966)
			(xy 270.624854 -357.730435) (xy 270.632614 -357.676458) (xy 270.647977 -357.624136) (xy 270.670628 -357.574532)
			(xy 270.700108 -357.528657) (xy 270.735817 -357.487443) (xy 270.777026 -357.451731) (xy 270.822899 -357.422246)
			(xy 270.8725 -357.39959) (xy 270.924821 -357.384222) (xy 270.978797 -357.376457) (xy 271.006062 -357.375968)
			(xy 271.869662 -357.375968) (xy 271.896937 -357.376369) (xy 271.950932 -357.384127) (xy 272.003273 -357.399491)
			(xy 272.052895 -357.422149) (xy 272.098787 -357.451638) (xy 272.140015 -357.487358) (xy 272.17574 -357.528582)
			(xy 272.205233 -357.574471) (xy 272.227895 -357.624091) (xy 272.243265 -357.676431) (xy 272.251028 -357.730425)
			(xy 272.251028 -357.78497) (xy 273.733731 -357.78497) (xy 273.733731 -357.73043) (xy 273.741494 -357.676446)
			(xy 273.75686 -357.624115) (xy 273.779517 -357.574505) (xy 273.809005 -357.528623) (xy 273.844722 -357.487406)
			(xy 273.885941 -357.451691) (xy 273.931824 -357.422207) (xy 273.981436 -357.399552) (xy 274.033767 -357.384189)
			(xy 274.087752 -357.37643) (xy 274.115022 -357.375968) (xy 274.978622 -357.375968) (xy 275.005892 -357.376396)
			(xy 275.059878 -357.384161) (xy 275.112209 -357.399529) (xy 275.16182 -357.422189) (xy 275.207702 -357.451677)
			(xy 275.24892 -357.487395) (xy 275.284636 -357.528616) (xy 275.314122 -357.574499) (xy 275.336778 -357.624112)
			(xy 275.352144 -357.676444) (xy 275.359906 -357.730429) (xy 275.359906 -357.784966) (xy 276.842754 -357.784966)
			(xy 276.842754 -357.730434) (xy 276.850515 -357.676456) (xy 276.865878 -357.624132) (xy 276.888531 -357.574527)
			(xy 276.918013 -357.52865) (xy 276.953724 -357.487436) (xy 276.994936 -357.451724) (xy 277.040811 -357.42224)
			(xy 277.090415 -357.399584) (xy 277.142738 -357.384219) (xy 277.196716 -357.376456) (xy 277.223982 -357.375968)
			(xy 278.087582 -357.375968) (xy 278.114856 -357.37637) (xy 278.168849 -357.384131) (xy 278.221188 -357.399497)
			(xy 278.270807 -357.422155) (xy 278.316697 -357.451645) (xy 278.357922 -357.487365) (xy 278.393644 -357.528589)
			(xy 278.423136 -357.574477) (xy 278.445797 -357.624095) (xy 278.461165 -357.676433) (xy 278.468928 -357.730426)
			(xy 278.468928 -357.784971) (xy 279.951632 -357.784971) (xy 279.951632 -357.730429) (xy 279.959394 -357.676443)
			(xy 279.974761 -357.624111) (xy 279.99742 -357.574499) (xy 280.026909 -357.528617) (xy 280.062629 -357.487399)
			(xy 280.103851 -357.451684) (xy 280.149736 -357.4222) (xy 280.19935 -357.399547) (xy 280.251684 -357.384185)
			(xy 280.305671 -357.376429) (xy 280.332942 -357.375968) (xy 281.196542 -357.375968) (xy 281.223812 -357.376397)
			(xy 281.277795 -357.384165) (xy 281.330123 -357.399535) (xy 281.379732 -357.422195) (xy 281.425611 -357.451684)
			(xy 281.466827 -357.487402) (xy 281.502541 -357.528622) (xy 281.532025 -357.574505) (xy 281.55468 -357.624116)
			(xy 281.570044 -357.676446) (xy 281.577806 -357.73043) (xy 281.577806 -357.784969) (xy 283.060631 -357.784969)
			(xy 283.060631 -357.730431) (xy 283.068393 -357.676448) (xy 283.083758 -357.62412) (xy 283.106414 -357.57451)
			(xy 283.1359 -357.52863) (xy 283.171614 -357.487413) (xy 283.212832 -357.451698) (xy 283.258712 -357.422213)
			(xy 283.308321 -357.399557) (xy 283.36065 -357.384193) (xy 283.414633 -357.376431) (xy 283.441902 -357.375968)
			(xy 284.305502 -357.375968) (xy 284.332773 -357.376395) (xy 284.386761 -357.384157) (xy 284.439094 -357.399524)
			(xy 284.488708 -357.422182) (xy 284.534593 -357.45167) (xy 284.575813 -357.487388) (xy 284.611531 -357.528609)
			(xy 284.641019 -357.574493) (xy 284.663677 -357.624107) (xy 284.679043 -357.676441) (xy 284.686806 -357.730429)
			(xy 284.686806 -357.784966) (xy 286.169654 -357.784966) (xy 286.169654 -357.730435) (xy 286.177414 -357.676458)
			(xy 286.192777 -357.624136) (xy 286.215428 -357.574532) (xy 286.244908 -357.528657) (xy 286.280617 -357.487443)
			(xy 286.321826 -357.451731) (xy 286.367699 -357.422246) (xy 286.4173 -357.39959) (xy 286.469621 -357.384222)
			(xy 286.523597 -357.376457) (xy 286.550862 -357.375968) (xy 287.414462 -357.375968) (xy 287.441737 -357.376369)
			(xy 287.495732 -357.384127) (xy 287.548073 -357.399491) (xy 287.597695 -357.422149) (xy 287.643587 -357.451638)
			(xy 287.684815 -357.487358) (xy 287.72054 -357.528582) (xy 287.750033 -357.574471) (xy 287.772695 -357.624091)
			(xy 287.788065 -357.676431) (xy 287.795828 -357.730425) (xy 287.795828 -357.78497) (xy 289.278531 -357.78497)
			(xy 289.278531 -357.73043) (xy 289.286294 -357.676446) (xy 289.30166 -357.624115) (xy 289.324317 -357.574505)
			(xy 289.353805 -357.528623) (xy 289.389522 -357.487406) (xy 289.430741 -357.451691) (xy 289.476624 -357.422207)
			(xy 289.526236 -357.399552) (xy 289.578567 -357.384189) (xy 289.632552 -357.37643) (xy 289.659822 -357.375968)
			(xy 290.523422 -357.375968) (xy 290.550692 -357.376396) (xy 290.604678 -357.384161) (xy 290.657009 -357.399529)
			(xy 290.70662 -357.422189) (xy 290.752502 -357.451677) (xy 290.79372 -357.487395) (xy 290.829436 -357.528616)
			(xy 290.858922 -357.574499) (xy 290.881578 -357.624112) (xy 290.896944 -357.676444) (xy 290.904706 -357.730429)
			(xy 290.904706 -357.784966) (xy 292.387554 -357.784966) (xy 292.387554 -357.730434) (xy 292.395315 -357.676456)
			(xy 292.410678 -357.624132) (xy 292.433331 -357.574527) (xy 292.462813 -357.52865) (xy 292.498524 -357.487436)
			(xy 292.539736 -357.451724) (xy 292.585611 -357.42224) (xy 292.635215 -357.399584) (xy 292.687538 -357.384219)
			(xy 292.741516 -357.376456) (xy 292.768782 -357.375968) (xy 293.632382 -357.375968) (xy 293.659656 -357.37637)
			(xy 293.713649 -357.384131) (xy 293.765988 -357.399497) (xy 293.815607 -357.422155) (xy 293.861497 -357.451645)
			(xy 293.902722 -357.487365) (xy 293.938444 -357.528589) (xy 293.967936 -357.574477) (xy 293.990597 -357.624095)
			(xy 294.005965 -357.676433) (xy 294.013728 -357.730426) (xy 294.013728 -357.784971) (xy 295.496432 -357.784971)
			(xy 295.496432 -357.730429) (xy 295.504194 -357.676443) (xy 295.519561 -357.624111) (xy 295.54222 -357.574499)
			(xy 295.571709 -357.528617) (xy 295.607429 -357.487399) (xy 295.648651 -357.451684) (xy 295.694536 -357.4222)
			(xy 295.74415 -357.399547) (xy 295.796484 -357.384185) (xy 295.850471 -357.376429) (xy 295.877742 -357.375968)
			(xy 296.741342 -357.375968) (xy 296.768612 -357.376397) (xy 296.822595 -357.384165) (xy 296.874923 -357.399535)
			(xy 296.924532 -357.422195) (xy 296.970411 -357.451684) (xy 297.011627 -357.487402) (xy 297.047341 -357.528622)
			(xy 297.076825 -357.574505) (xy 297.09948 -357.624116) (xy 297.114844 -357.676446) (xy 297.122606 -357.73043)
			(xy 297.122606 -357.784969) (xy 298.605431 -357.784969) (xy 298.605431 -357.730431) (xy 298.613193 -357.676448)
			(xy 298.628558 -357.62412) (xy 298.651214 -357.57451) (xy 298.6807 -357.52863) (xy 298.716414 -357.487413)
			(xy 298.757632 -357.451698) (xy 298.803512 -357.422213) (xy 298.853121 -357.399557) (xy 298.90545 -357.384193)
			(xy 298.959433 -357.376431) (xy 298.986702 -357.375968) (xy 299.850302 -357.375968) (xy 299.877573 -357.376395)
			(xy 299.931561 -357.384157) (xy 299.983894 -357.399524) (xy 300.033508 -357.422182) (xy 300.079393 -357.45167)
			(xy 300.120613 -357.487388) (xy 300.156331 -357.528609) (xy 300.185819 -357.574493) (xy 300.208477 -357.624107)
			(xy 300.223843 -357.676441) (xy 300.231606 -357.730429) (xy 300.231606 -357.784971) (xy 300.223843 -357.838959)
			(xy 300.208477 -357.891293) (xy 300.185819 -357.940907) (xy 300.156331 -357.986791) (xy 300.120613 -358.028012)
			(xy 300.079393 -358.06373) (xy 300.033508 -358.093218) (xy 299.983894 -358.115876) (xy 299.931561 -358.131243)
			(xy 299.877573 -358.139005) (xy 299.850302 -358.139492) (xy 298.986702 -358.139492) (xy 298.959433 -358.138969)
			(xy 298.90545 -358.131207) (xy 298.853121 -358.115843) (xy 298.803512 -358.093187) (xy 298.757632 -358.063702)
			(xy 298.716414 -358.027987) (xy 298.6807 -357.98677) (xy 298.651214 -357.94089) (xy 298.628558 -357.89128)
			(xy 298.613193 -357.838952) (xy 298.605431 -357.784969) (xy 297.122606 -357.784969) (xy 297.122606 -357.78497)
			(xy 297.114844 -357.838954) (xy 297.09948 -357.891284) (xy 297.076825 -357.940895) (xy 297.047341 -357.986778)
			(xy 297.011627 -358.027998) (xy 296.970411 -358.063716) (xy 296.924532 -358.093205) (xy 296.874923 -358.115865)
			(xy 296.822595 -358.131235) (xy 296.768612 -358.139003) (xy 296.741342 -358.139492) (xy 295.877742 -358.139492)
			(xy 295.850471 -358.138971) (xy 295.796484 -358.131215) (xy 295.74415 -358.115853) (xy 295.694536 -358.0932)
			(xy 295.64865 -358.063716) (xy 295.607429 -358.028001) (xy 295.571709 -357.986783) (xy 295.54222 -357.940901)
			(xy 295.519561 -357.891289) (xy 295.504194 -357.838957) (xy 295.496432 -357.784971) (xy 294.013728 -357.784971)
			(xy 294.013728 -357.784974) (xy 294.005965 -357.838967) (xy 293.990597 -357.891305) (xy 293.967936 -357.940923)
			(xy 293.938444 -357.986811) (xy 293.902722 -358.028035) (xy 293.861497 -358.063755) (xy 293.815607 -358.093245)
			(xy 293.765988 -358.115903) (xy 293.713649 -358.131269) (xy 293.659656 -358.13903) (xy 293.632382 -358.139492)
			(xy 292.768782 -358.139492) (xy 292.741516 -358.138944) (xy 292.687538 -358.131181) (xy 292.635215 -358.115816)
			(xy 292.585611 -358.09316) (xy 292.539736 -358.063676) (xy 292.498524 -358.027964) (xy 292.462813 -357.98675)
			(xy 292.433331 -357.940873) (xy 292.410678 -357.891268) (xy 292.395315 -357.838944) (xy 292.387554 -357.784966)
			(xy 290.904706 -357.784966) (xy 290.904706 -357.784971) (xy 290.896944 -357.838956) (xy 290.881578 -357.891288)
			(xy 290.858922 -357.940901) (xy 290.829436 -357.986784) (xy 290.79372 -358.028005) (xy 290.752502 -358.063723)
			(xy 290.70662 -358.093211) (xy 290.657009 -358.115871) (xy 290.604678 -358.131239) (xy 290.550692 -358.139004)
			(xy 290.523422 -358.139492) (xy 289.659822 -358.139492) (xy 289.632552 -358.13897) (xy 289.578567 -358.131211)
			(xy 289.526236 -358.115848) (xy 289.476624 -358.093193) (xy 289.430741 -358.063709) (xy 289.389522 -358.027994)
			(xy 289.353805 -357.986777) (xy 289.324317 -357.940895) (xy 289.30166 -357.891285) (xy 289.286294 -357.838954)
			(xy 289.278531 -357.78497) (xy 287.795828 -357.78497) (xy 287.795828 -357.784975) (xy 287.788065 -357.838969)
			(xy 287.772695 -357.891309) (xy 287.750033 -357.940929) (xy 287.72054 -357.986818) (xy 287.684815 -358.028042)
			(xy 287.643587 -358.063762) (xy 287.597695 -358.093251) (xy 287.548073 -358.115908) (xy 287.495732 -358.131273)
			(xy 287.441737 -358.139031) (xy 287.414462 -358.139492) (xy 286.550862 -358.139492) (xy 286.523597 -358.138943)
			(xy 286.469621 -358.131178) (xy 286.4173 -358.11581) (xy 286.367699 -358.093154) (xy 286.321826 -358.063669)
			(xy 286.280617 -358.027957) (xy 286.244908 -357.986743) (xy 286.215428 -357.940868) (xy 286.192777 -357.891264)
			(xy 286.177414 -357.838942) (xy 286.169654 -357.784966) (xy 284.686806 -357.784966) (xy 284.686806 -357.784971)
			(xy 284.679043 -357.838959) (xy 284.663677 -357.891293) (xy 284.641019 -357.940907) (xy 284.611531 -357.986791)
			(xy 284.575813 -358.028012) (xy 284.534593 -358.06373) (xy 284.488708 -358.093218) (xy 284.439094 -358.115876)
			(xy 284.386761 -358.131243) (xy 284.332773 -358.139005) (xy 284.305502 -358.139492) (xy 283.441902 -358.139492)
			(xy 283.414633 -358.138969) (xy 283.36065 -358.131207) (xy 283.308321 -358.115843) (xy 283.258712 -358.093187)
			(xy 283.212832 -358.063702) (xy 283.171614 -358.027987) (xy 283.1359 -357.98677) (xy 283.106414 -357.94089)
			(xy 283.083758 -357.89128) (xy 283.068393 -357.838952) (xy 283.060631 -357.784969) (xy 281.577806 -357.784969)
			(xy 281.577806 -357.78497) (xy 281.570044 -357.838954) (xy 281.55468 -357.891284) (xy 281.532025 -357.940895)
			(xy 281.502541 -357.986778) (xy 281.466827 -358.027998) (xy 281.425611 -358.063716) (xy 281.379732 -358.093205)
			(xy 281.330123 -358.115865) (xy 281.277795 -358.131235) (xy 281.223812 -358.139003) (xy 281.196542 -358.139492)
			(xy 280.332942 -358.139492) (xy 280.305671 -358.138971) (xy 280.251684 -358.131215) (xy 280.19935 -358.115853)
			(xy 280.149736 -358.0932) (xy 280.10385 -358.063716) (xy 280.062629 -358.028001) (xy 280.026909 -357.986783)
			(xy 279.99742 -357.940901) (xy 279.974761 -357.891289) (xy 279.959394 -357.838957) (xy 279.951632 -357.784971)
			(xy 278.468928 -357.784971) (xy 278.468928 -357.784974) (xy 278.461165 -357.838967) (xy 278.445797 -357.891305)
			(xy 278.423136 -357.940923) (xy 278.393644 -357.986811) (xy 278.357922 -358.028035) (xy 278.316697 -358.063755)
			(xy 278.270807 -358.093245) (xy 278.221188 -358.115903) (xy 278.168849 -358.131269) (xy 278.114856 -358.13903)
			(xy 278.087582 -358.139492) (xy 277.223982 -358.139492) (xy 277.196716 -358.138944) (xy 277.142738 -358.131181)
			(xy 277.090415 -358.115816) (xy 277.040811 -358.09316) (xy 276.994936 -358.063676) (xy 276.953724 -358.027964)
			(xy 276.918013 -357.98675) (xy 276.888531 -357.940873) (xy 276.865878 -357.891268) (xy 276.850515 -357.838944)
			(xy 276.842754 -357.784966) (xy 275.359906 -357.784966) (xy 275.359906 -357.784971) (xy 275.352144 -357.838956)
			(xy 275.336778 -357.891288) (xy 275.314122 -357.940901) (xy 275.284636 -357.986784) (xy 275.24892 -358.028005)
			(xy 275.207702 -358.063723) (xy 275.16182 -358.093211) (xy 275.112209 -358.115871) (xy 275.059878 -358.131239)
			(xy 275.005892 -358.139004) (xy 274.978622 -358.139492) (xy 274.115022 -358.139492) (xy 274.087752 -358.13897)
			(xy 274.033767 -358.131211) (xy 273.981436 -358.115848) (xy 273.931824 -358.093193) (xy 273.885941 -358.063709)
			(xy 273.844722 -358.027994) (xy 273.809005 -357.986777) (xy 273.779517 -357.940895) (xy 273.75686 -357.891285)
			(xy 273.741494 -357.838954) (xy 273.733731 -357.78497) (xy 272.251028 -357.78497) (xy 272.251028 -357.784975)
			(xy 272.243265 -357.838969) (xy 272.227895 -357.891309) (xy 272.205233 -357.940929) (xy 272.17574 -357.986818)
			(xy 272.140015 -358.028042) (xy 272.098787 -358.063762) (xy 272.052895 -358.093251) (xy 272.003273 -358.115908)
			(xy 271.950932 -358.131273) (xy 271.896937 -358.139031) (xy 271.869662 -358.139492) (xy 271.006062 -358.139492)
			(xy 270.978797 -358.138943) (xy 270.924821 -358.131178) (xy 270.8725 -358.11581) (xy 270.822899 -358.093154)
			(xy 270.777026 -358.063669) (xy 270.735817 -358.027957) (xy 270.700108 -357.986743) (xy 270.670628 -357.940868)
			(xy 270.647977 -357.891264) (xy 270.632614 -357.838942) (xy 270.624854 -357.784966) (xy 269.778538 -357.784966)
			(xy 273.94789 -361.954318) (xy 273.955284 -361.961175) (xy 273.973883 -361.968926) (xy 273.983958 -361.969304)
			(xy 279.136348 -361.969304) (xy 279.146414 -361.969736) (xy 279.165006 -361.977463) (xy 279.172416 -361.98429)
			(xy 282.760166 -365.57204) (xy 282.76701 -365.579439) (xy 282.774735 -365.598038) (xy 282.775152 -365.608108)
			(xy 282.775152 -368.990118) (xy 289.203646 -368.990118) (xy 289.207637 -368.927951) (xy 289.219546 -368.866804)
			(xy 289.239175 -368.807683) (xy 289.266204 -368.751557) (xy 289.300188 -368.699348) (xy 289.34057 -368.651913)
			(xy 289.386686 -368.610032) (xy 289.437778 -368.574392) (xy 289.493009 -368.545578) (xy 289.551471 -368.524064)
			(xy 289.612205 -368.510202) (xy 289.674212 -368.50422) (xy 289.736475 -368.506216) (xy 289.797972 -368.516159)
			(xy 289.857693 -368.533883) (xy 289.914656 -368.5591) (xy 289.967927 -368.591393) (xy 290.016632 -368.630233)
			(xy 290.059969 -368.674983) (xy 290.097229 -368.724907) (xy 290.127798 -368.779186) (xy 290.151176 -368.836929)
			(xy 290.166977 -368.897187) (xy 290.174943 -368.95897) (xy 290.175442 -368.990118) (xy 293.603688 -368.990118)
			(xy 293.607679 -368.927951) (xy 293.619588 -368.866804) (xy 293.639217 -368.807683) (xy 293.666246 -368.751557)
			(xy 293.70023 -368.699348) (xy 293.740612 -368.651913) (xy 293.786728 -368.610032) (xy 293.83782 -368.574392)
			(xy 293.893051 -368.545578) (xy 293.951513 -368.524064) (xy 294.012247 -368.510202) (xy 294.074254 -368.50422)
			(xy 294.136517 -368.506216) (xy 294.198014 -368.516159) (xy 294.257735 -368.533883) (xy 294.314698 -368.5591)
			(xy 294.367969 -368.591393) (xy 294.416674 -368.630233) (xy 294.460011 -368.674983) (xy 294.497271 -368.724907)
			(xy 294.52784 -368.779186) (xy 294.551218 -368.836929) (xy 294.567019 -368.897187) (xy 294.574985 -368.95897)
			(xy 294.575484 -368.990118) (xy 298.00373 -368.990118) (xy 298.007721 -368.927951) (xy 298.01963 -368.866804)
			(xy 298.039259 -368.807683) (xy 298.066288 -368.751557) (xy 298.100272 -368.699348) (xy 298.140654 -368.651913)
			(xy 298.18677 -368.610032) (xy 298.237862 -368.574392) (xy 298.293093 -368.545578) (xy 298.351555 -368.524064)
			(xy 298.412289 -368.510202) (xy 298.474296 -368.50422) (xy 298.536559 -368.506216) (xy 298.598056 -368.516159)
			(xy 298.657777 -368.533883) (xy 298.71474 -368.5591) (xy 298.768011 -368.591393) (xy 298.816716 -368.630233)
			(xy 298.860053 -368.674983) (xy 298.897313 -368.724907) (xy 298.927882 -368.779186) (xy 298.95126 -368.836929)
			(xy 298.967061 -368.897187) (xy 298.975027 -368.95897) (xy 298.975526 -368.990118) (xy 302.403772 -368.990118)
			(xy 302.407763 -368.927951) (xy 302.419672 -368.866804) (xy 302.439301 -368.807683) (xy 302.46633 -368.751557)
			(xy 302.500314 -368.699348) (xy 302.540696 -368.651913) (xy 302.586812 -368.610032) (xy 302.637904 -368.574392)
			(xy 302.693135 -368.545578) (xy 302.751597 -368.524064) (xy 302.812331 -368.510202) (xy 302.874338 -368.50422)
			(xy 302.936601 -368.506216) (xy 302.998098 -368.516159) (xy 303.057819 -368.533883) (xy 303.114782 -368.5591)
			(xy 303.168053 -368.591393) (xy 303.216758 -368.630233) (xy 303.260095 -368.674983) (xy 303.297355 -368.724907)
			(xy 303.327924 -368.779186) (xy 303.351302 -368.836929) (xy 303.367103 -368.897187) (xy 303.375069 -368.95897)
			(xy 303.375568 -368.990118) (xy 306.803814 -368.990118) (xy 306.807805 -368.927951) (xy 306.819714 -368.866804)
			(xy 306.839343 -368.807683) (xy 306.866372 -368.751557) (xy 306.900356 -368.699348) (xy 306.940738 -368.651913)
			(xy 306.986854 -368.610032) (xy 307.037946 -368.574392) (xy 307.093177 -368.545578) (xy 307.151639 -368.524064)
			(xy 307.212373 -368.510202) (xy 307.27438 -368.50422) (xy 307.336643 -368.506216) (xy 307.39814 -368.516159)
			(xy 307.457861 -368.533883) (xy 307.514824 -368.5591) (xy 307.568095 -368.591393) (xy 307.6168 -368.630233)
			(xy 307.660137 -368.674983) (xy 307.697397 -368.724907) (xy 307.727966 -368.779186) (xy 307.751344 -368.836929)
			(xy 307.767145 -368.897187) (xy 307.775111 -368.95897) (xy 307.77561 -368.990118) (xy 307.775111 -369.021266)
			(xy 307.767145 -369.083049) (xy 307.751344 -369.143307) (xy 307.727966 -369.20105) (xy 307.697397 -369.255329)
			(xy 307.660137 -369.305253) (xy 307.6168 -369.350003) (xy 307.568095 -369.388843) (xy 307.514824 -369.421136)
			(xy 307.457861 -369.446353) (xy 307.39814 -369.464077) (xy 307.336643 -369.47402) (xy 307.27438 -369.476016)
			(xy 307.212373 -369.470034) (xy 307.151639 -369.456172) (xy 307.093177 -369.434658) (xy 307.037946 -369.405844)
			(xy 306.986854 -369.370204) (xy 306.940738 -369.328323) (xy 306.900356 -369.280888) (xy 306.866372 -369.228679)
			(xy 306.839343 -369.172553) (xy 306.819714 -369.113432) (xy 306.807805 -369.052285) (xy 306.803814 -368.990118)
			(xy 303.375568 -368.990118) (xy 303.375069 -369.021266) (xy 303.367103 -369.083049) (xy 303.351302 -369.143307)
			(xy 303.327924 -369.20105) (xy 303.297355 -369.255329) (xy 303.260095 -369.305253) (xy 303.216758 -369.350003)
			(xy 303.168053 -369.388843) (xy 303.114782 -369.421136) (xy 303.057819 -369.446353) (xy 302.998098 -369.464077)
			(xy 302.936601 -369.47402) (xy 302.874338 -369.476016) (xy 302.812331 -369.470034) (xy 302.751597 -369.456172)
			(xy 302.693135 -369.434658) (xy 302.637904 -369.405844) (xy 302.586812 -369.370204) (xy 302.540696 -369.328323)
			(xy 302.500314 -369.280888) (xy 302.46633 -369.228679) (xy 302.439301 -369.172553) (xy 302.419672 -369.113432)
			(xy 302.407763 -369.052285) (xy 302.403772 -368.990118) (xy 298.975526 -368.990118) (xy 298.975027 -369.021266)
			(xy 298.967061 -369.083049) (xy 298.95126 -369.143307) (xy 298.927882 -369.20105) (xy 298.897313 -369.255329)
			(xy 298.860053 -369.305253) (xy 298.816716 -369.350003) (xy 298.768011 -369.388843) (xy 298.71474 -369.421136)
			(xy 298.657777 -369.446353) (xy 298.598056 -369.464077) (xy 298.536559 -369.47402) (xy 298.474296 -369.476016)
			(xy 298.412289 -369.470034) (xy 298.351555 -369.456172) (xy 298.293093 -369.434658) (xy 298.237862 -369.405844)
			(xy 298.18677 -369.370204) (xy 298.140654 -369.328323) (xy 298.100272 -369.280888) (xy 298.066288 -369.228679)
			(xy 298.039259 -369.172553) (xy 298.01963 -369.113432) (xy 298.007721 -369.052285) (xy 298.00373 -368.990118)
			(xy 294.575484 -368.990118) (xy 294.574985 -369.021266) (xy 294.567019 -369.083049) (xy 294.551218 -369.143307)
			(xy 294.52784 -369.20105) (xy 294.497271 -369.255329) (xy 294.460011 -369.305253) (xy 294.416674 -369.350003)
			(xy 294.367969 -369.388843) (xy 294.314698 -369.421136) (xy 294.257735 -369.446353) (xy 294.198014 -369.464077)
			(xy 294.136517 -369.47402) (xy 294.074254 -369.476016) (xy 294.012247 -369.470034) (xy 293.951513 -369.456172)
			(xy 293.893051 -369.434658) (xy 293.83782 -369.405844) (xy 293.786728 -369.370204) (xy 293.740612 -369.328323)
			(xy 293.70023 -369.280888) (xy 293.666246 -369.228679) (xy 293.639217 -369.172553) (xy 293.619588 -369.113432)
			(xy 293.607679 -369.052285) (xy 293.603688 -368.990118) (xy 290.175442 -368.990118) (xy 290.174943 -369.021266)
			(xy 290.166977 -369.083049) (xy 290.151176 -369.143307) (xy 290.127798 -369.20105) (xy 290.097229 -369.255329)
			(xy 290.059969 -369.305253) (xy 290.016632 -369.350003) (xy 289.967927 -369.388843) (xy 289.914656 -369.421136)
			(xy 289.857693 -369.446353) (xy 289.797972 -369.464077) (xy 289.736475 -369.47402) (xy 289.674212 -369.476016)
			(xy 289.612205 -369.470034) (xy 289.551471 -369.456172) (xy 289.493009 -369.434658) (xy 289.437778 -369.405844)
			(xy 289.386686 -369.370204) (xy 289.34057 -369.328323) (xy 289.300188 -369.280888) (xy 289.266204 -369.228679)
			(xy 289.239175 -369.172553) (xy 289.219546 -369.113432) (xy 289.207637 -369.052285) (xy 289.203646 -368.990118)
			(xy 282.775152 -368.990118) (xy 282.775152 -371.790214) (xy 287.004252 -371.790214) (xy 287.004808 -371.757484)
			(xy 287.013668 -371.692626) (xy 287.031161 -371.629546) (xy 287.05697 -371.569388) (xy 287.07334 -371.54104)
			(xy 287.076636 -371.535006) (xy 287.080254 -371.52175) (xy 287.080452 -371.514878) (xy 287.080452 -370.765324)
			(xy 287.080257 -370.758451) (xy 287.076651 -370.745188) (xy 287.07334 -370.739162) (xy 287.056963 -370.710819)
			(xy 287.031163 -370.650657) (xy 287.013676 -370.587576) (xy 287.00482 -370.522718) (xy 287.004252 -370.489988)
			(xy 287.004841 -370.457259) (xy 287.013691 -370.392402) (xy 287.031174 -370.329322) (xy 287.056975 -370.269163)
			(xy 287.07334 -370.240814) (xy 287.076645 -370.234785) (xy 287.080258 -370.221525) (xy 287.080452 -370.214652)
			(xy 287.080452 -369.928902) (xy 287.080929 -369.918774) (xy 287.088658 -369.900051) (xy 287.102947 -369.885694)
			(xy 287.121634 -369.877877) (xy 287.13176 -369.87734) (xy 287.84804 -369.87734) (xy 287.858202 -369.87769)
			(xy 287.876963 -369.885506) (xy 287.891286 -369.899925) (xy 287.898977 -369.918738) (xy 287.899348 -369.928902)
			(xy 287.899348 -370.214652) (xy 287.899552 -370.221524) (xy 287.903151 -370.234787) (xy 287.90646 -370.240814)
			(xy 287.922827 -370.269162) (xy 287.94863 -370.329322) (xy 287.966119 -370.392402) (xy 287.974978 -370.457259)
			(xy 287.975548 -370.489988) (xy 287.974993 -370.522708) (xy 291.404891 -370.522708) (xy 291.404893 -370.457271)
			(xy 291.413677 -370.392426) (xy 291.431087 -370.329347) (xy 291.456805 -370.269175) (xy 291.473128 -370.240814)
			(xy 291.47644 -370.234788) (xy 291.480047 -370.221525) (xy 291.48024 -370.214652) (xy 291.48024 -369.928902)
			(xy 291.480665 -369.91873) (xy 291.48845 -369.899935) (xy 291.502835 -369.88555) (xy 291.52163 -369.877765)
			(xy 291.531802 -369.87734) (xy 292.248082 -369.87734) (xy 292.258253 -369.877778) (xy 292.277047 -369.885558)
			(xy 292.291433 -369.899939) (xy 292.299218 -369.918731) (xy 292.299644 -369.928902) (xy 292.299644 -370.214652)
			(xy 292.299849 -370.221524) (xy 292.303448 -370.234787) (xy 292.306756 -370.240814) (xy 292.323068 -370.269181)
			(xy 292.348787 -370.329351) (xy 292.366196 -370.392428) (xy 292.374981 -370.457272) (xy 292.374983 -370.522708)
			(xy 292.366201 -370.587552) (xy 292.348794 -370.65063) (xy 292.323078 -370.710801) (xy 292.306756 -370.739162)
			(xy 292.303459 -370.745196) (xy 292.299842 -370.758452) (xy 292.299644 -370.765324) (xy 292.299644 -371.514878)
			(xy 292.299839 -371.521751) (xy 292.303445 -371.535014) (xy 292.306756 -371.54104) (xy 292.32309 -371.569395)
			(xy 292.348807 -371.629567) (xy 292.366214 -371.692647) (xy 292.374996 -371.757493) (xy 292.374995 -371.822931)
			(xy 292.366209 -371.887776) (xy 292.348799 -371.950855) (xy 292.323079 -372.011027) (xy 292.306756 -372.039388)
			(xy 292.30345 -372.045417) (xy 292.299838 -372.058677) (xy 292.299644 -372.06555) (xy 292.299644 -372.351554)
			(xy 292.299198 -372.361725) (xy 292.291425 -372.380522) (xy 292.277046 -372.394909) (xy 292.258253 -372.402693)
			(xy 292.248082 -372.403116) (xy 291.531802 -372.403116) (xy 291.521625 -372.402733) (xy 291.502821 -372.394941)
			(xy 291.488435 -372.380542) (xy 291.480658 -372.361732) (xy 291.48024 -372.351554) (xy 291.48024 -372.06555)
			(xy 291.480024 -372.058679) (xy 291.476432 -372.045416) (xy 291.473128 -372.039388) (xy 291.456818 -372.01102)
			(xy 291.4311 -371.95085) (xy 291.413691 -371.887773) (xy 291.404906 -371.82293) (xy 291.404904 -371.757494)
			(xy 291.413686 -371.692651) (xy 291.431092 -371.629572) (xy 291.456807 -371.569401) (xy 291.473128 -371.54104)
			(xy 291.47643 -371.535009) (xy 291.480043 -371.52175) (xy 291.48024 -371.514878) (xy 291.48024 -370.765324)
			(xy 291.480034 -370.758452) (xy 291.476435 -370.745189) (xy 291.473128 -370.739162) (xy 291.456796 -370.710806)
			(xy 291.43108 -370.650634) (xy 291.413673 -370.587554) (xy 291.404891 -370.522708) (xy 287.974993 -370.522708)
			(xy 287.974993 -370.522718) (xy 287.966133 -370.587576) (xy 287.948639 -370.650656) (xy 287.92283 -370.710814)
			(xy 287.90646 -370.739162) (xy 287.903163 -370.745196) (xy 287.899546 -370.758452) (xy 287.899348 -370.765324)
			(xy 287.899348 -371.514878) (xy 287.899542 -371.521751) (xy 287.903148 -371.535014) (xy 287.90646 -371.54104)
			(xy 287.922838 -371.569383) (xy 287.945739 -371.622787) (xy 289.204721 -371.622787) (xy 289.204726 -371.557347)
			(xy 289.213515 -371.492501) (xy 289.230929 -371.42942) (xy 289.256654 -371.369249) (xy 289.27298 -371.340888)
			(xy 289.276298 -371.334865) (xy 289.279902 -371.3216) (xy 289.280092 -371.314726) (xy 289.280092 -371.028722)
			(xy 289.28065 -371.018571) (xy 289.288409 -370.999811) (xy 289.302754 -370.985447) (xy 289.321504 -370.977663)
			(xy 289.331654 -370.97716) (xy 290.047934 -370.97716) (xy 290.058097 -370.977606) (xy 290.076871 -370.985396)
			(xy 290.091236 -370.999776) (xy 290.099005 -371.018559) (xy 290.099496 -371.028722) (xy 290.099496 -371.314726)
			(xy 290.099678 -371.3216) (xy 290.103293 -371.334863) (xy 290.106608 -371.340888) (xy 290.122897 -371.369268)
			(xy 290.148615 -371.429435) (xy 290.166025 -371.49251) (xy 290.174811 -371.557351) (xy 290.174816 -371.622784)
			(xy 290.166038 -371.687626) (xy 290.148636 -371.750703) (xy 290.122926 -371.810874) (xy 290.106608 -371.839236)
			(xy 290.103281 -371.845255) (xy 290.099683 -371.858523) (xy 290.099496 -371.865398) (xy 290.099496 -372.614698)
			(xy 290.099689 -372.621571) (xy 290.103296 -372.634834) (xy 290.106608 -372.64086) (xy 290.122958 -372.669206)
			(xy 290.14867 -372.729381) (xy 290.166073 -372.792463) (xy 290.174852 -372.85731) (xy 290.17485 -372.890034)
			(xy 293.604188 -372.890034) (xy 293.604748 -372.857304) (xy 293.613606 -372.792446) (xy 293.631098 -372.729366)
			(xy 293.656907 -372.669208) (xy 293.673276 -372.64086) (xy 293.676603 -372.634841) (xy 293.680201 -372.621573)
			(xy 293.680388 -372.614698) (xy 293.680388 -371.865398) (xy 293.680199 -371.858525) (xy 293.676589 -371.845262)
			(xy 293.673276 -371.839236) (xy 293.656922 -371.81088) (xy 293.631118 -371.750723) (xy 293.613625 -371.687645)
			(xy 293.604761 -371.62279) (xy 293.604188 -371.590062) (xy 293.604761 -371.557333) (xy 293.613615 -371.492475)
			(xy 293.631103 -371.429395) (xy 293.656909 -371.369236) (xy 293.673276 -371.340888) (xy 293.676593 -371.334865)
			(xy 293.680198 -371.3216) (xy 293.680388 -371.314726) (xy 293.680388 -371.028722) (xy 293.680943 -371.018603)
			(xy 293.688654 -370.999892) (xy 293.702919 -370.985537) (xy 293.72158 -370.977708) (xy 293.731696 -370.97716)
			(xy 294.447976 -370.97716) (xy 294.458124 -370.97764) (xy 294.476868 -370.98542) (xy 294.491191 -370.999799)
			(xy 294.498898 -371.018573) (xy 294.499284 -371.028722) (xy 294.499284 -371.314726) (xy 294.499468 -371.3216)
			(xy 294.503082 -371.334863) (xy 294.506396 -371.340888) (xy 294.522756 -371.36924) (xy 294.54856 -371.429399)
			(xy 294.566051 -371.492477) (xy 294.574913 -371.557333) (xy 294.575484 -371.590062) (xy 294.574926 -371.622792)
			(xy 294.566068 -371.68765) (xy 294.548576 -371.750731) (xy 294.531636 -371.790214) (xy 295.804336 -371.790214)
			(xy 295.804894 -371.757484) (xy 295.813754 -371.692626) (xy 295.831246 -371.629546) (xy 295.857055 -371.569388)
			(xy 295.873424 -371.54104) (xy 295.876726 -371.535009) (xy 295.880339 -371.52175) (xy 295.880536 -371.514878)
			(xy 295.880536 -370.765324) (xy 295.88033 -370.758452) (xy 295.876731 -370.745189) (xy 295.873424 -370.739162)
			(xy 295.857046 -370.71082) (xy 295.831246 -370.650658) (xy 295.81376 -370.587576) (xy 295.804904 -370.522718)
			(xy 295.804336 -370.489988) (xy 295.804927 -370.457259) (xy 295.813777 -370.392402) (xy 295.83126 -370.329322)
			(xy 295.857059 -370.269163) (xy 295.873424 -370.240814) (xy 295.876735 -370.234788) (xy 295.880343 -370.221525)
			(xy 295.880536 -370.214652) (xy 295.880536 -369.928902) (xy 295.881028 -369.918776) (xy 295.888755 -369.900056)
			(xy 295.903039 -369.885699) (xy 295.92172 -369.877879) (xy 295.931844 -369.87734) (xy 296.648124 -369.87734)
			(xy 296.658285 -369.877703) (xy 296.677045 -369.885514) (xy 296.691369 -369.899929) (xy 296.699061 -369.918739)
			(xy 296.699432 -369.928902) (xy 296.699432 -370.214652) (xy 296.699638 -370.221524) (xy 296.703236 -370.234787)
			(xy 296.706544 -370.240814) (xy 296.72291 -370.269163) (xy 296.748713 -370.329322) (xy 296.766203 -370.392402)
			(xy 296.775062 -370.457259) (xy 296.775632 -370.489988) (xy 296.775079 -370.522718) (xy 296.766219 -370.587577)
			(xy 296.748725 -370.650657) (xy 296.722914 -370.710814) (xy 296.706544 -370.739162) (xy 296.703246 -370.745195)
			(xy 296.699629 -370.758452) (xy 296.699432 -370.765324) (xy 296.699432 -371.514878) (xy 296.699628 -371.521751)
			(xy 296.703233 -371.535014) (xy 296.706544 -371.54104) (xy 296.72292 -371.569384) (xy 296.745823 -371.622787)
			(xy 298.004807 -371.622787) (xy 298.004812 -371.557348) (xy 298.0136 -371.492501) (xy 298.031014 -371.429421)
			(xy 298.056738 -371.369249) (xy 298.073064 -371.340888) (xy 298.07638 -371.334864) (xy 298.079985 -371.3216)
			(xy 298.080176 -371.314726) (xy 298.080176 -371.028722) (xy 298.080583 -371.018547) (xy 298.088368 -370.999746)
			(xy 298.102759 -370.985359) (xy 298.121563 -370.97758) (xy 298.131738 -370.97716) (xy 298.848018 -370.97716)
			(xy 298.858193 -370.97755) (xy 298.876993 -370.985345) (xy 298.891378 -370.999741) (xy 298.899158 -371.018546)
			(xy 298.89958 -371.028722) (xy 298.89958 -371.314726) (xy 298.899765 -371.3216) (xy 298.903378 -371.334862)
			(xy 298.906692 -371.340888) (xy 298.922981 -371.369267) (xy 298.9487 -371.429435) (xy 298.966111 -371.49251)
			(xy 298.974898 -371.557351) (xy 298.974902 -371.622784) (xy 298.966124 -371.687626) (xy 298.948722 -371.750704)
			(xy 298.931839 -371.790214) (xy 300.204124 -371.790214) (xy 300.20467 -371.757484) (xy 300.213532 -371.692625)
			(xy 300.231027 -371.629545) (xy 300.256841 -371.569387) (xy 300.273212 -371.54104) (xy 300.276513 -371.535009)
			(xy 300.280127 -371.52175) (xy 300.280324 -371.514878) (xy 300.280324 -370.765324) (xy 300.28012 -370.758452)
			(xy 300.27652 -370.745189) (xy 300.273212 -370.739162) (xy 300.256832 -370.71082) (xy 300.231034 -370.650658)
			(xy 300.213548 -370.587576) (xy 300.204692 -370.522718) (xy 300.204124 -370.489988) (xy 300.204703 -370.457259)
			(xy 300.213555 -370.392401) (xy 300.231041 -370.329321) (xy 300.256845 -370.269162) (xy 300.273212 -370.240814)
			(xy 300.276523 -370.234787) (xy 300.280131 -370.221525) (xy 300.280324 -370.214652) (xy 300.280324 -369.928902)
			(xy 300.280828 -369.918777) (xy 300.288552 -369.900059) (xy 300.302833 -369.885704) (xy 300.32151 -369.877882)
			(xy 300.331632 -369.87734) (xy 301.047912 -369.87734) (xy 301.058072 -369.877712) (xy 301.076832 -369.885519)
			(xy 301.091157 -369.899932) (xy 301.098849 -369.91874) (xy 301.09922 -369.928902) (xy 301.09922 -370.214652)
			(xy 301.099428 -370.221524) (xy 301.103025 -370.234787) (xy 301.106332 -370.240814) (xy 301.122697 -370.269164)
			(xy 301.1485 -370.329323) (xy 301.16599 -370.392402) (xy 301.17485 -370.457259) (xy 301.17542 -370.489988)
			(xy 304.603666 -370.489988) (xy 304.607657 -370.427821) (xy 304.619566 -370.366674) (xy 304.639195 -370.307553)
			(xy 304.666224 -370.251427) (xy 304.700208 -370.199218) (xy 304.74059 -370.151783) (xy 304.786706 -370.109902)
			(xy 304.837798 -370.074262) (xy 304.893029 -370.045448) (xy 304.951491 -370.023934) (xy 305.012225 -370.010072)
			(xy 305.074232 -370.00409) (xy 305.136495 -370.006086) (xy 305.197992 -370.016029) (xy 305.257713 -370.033753)
			(xy 305.314676 -370.05897) (xy 305.367947 -370.091263) (xy 305.416652 -370.130103) (xy 305.459989 -370.174853)
			(xy 305.497249 -370.224777) (xy 305.527818 -370.279056) (xy 305.551196 -370.336799) (xy 305.566997 -370.397057)
			(xy 305.574963 -370.45884) (xy 305.575462 -370.489988) (xy 305.574963 -370.521136) (xy 305.566997 -370.582919)
			(xy 305.551196 -370.643177) (xy 305.527818 -370.70092) (xy 305.497249 -370.755199) (xy 305.459989 -370.805123)
			(xy 305.416652 -370.849873) (xy 305.367947 -370.888713) (xy 305.314676 -370.921006) (xy 305.257713 -370.946223)
			(xy 305.197992 -370.963947) (xy 305.136495 -370.97389) (xy 305.074232 -370.975886) (xy 305.012225 -370.969904)
			(xy 304.951491 -370.956042) (xy 304.893029 -370.934528) (xy 304.837798 -370.905714) (xy 304.786706 -370.870074)
			(xy 304.74059 -370.828193) (xy 304.700208 -370.780758) (xy 304.666224 -370.728549) (xy 304.639195 -370.672423)
			(xy 304.619566 -370.613302) (xy 304.607657 -370.552155) (xy 304.603666 -370.489988) (xy 301.17542 -370.489988)
			(xy 301.174869 -370.522718) (xy 301.166008 -370.587577) (xy 301.148514 -370.650657) (xy 301.122703 -370.710814)
			(xy 301.106332 -370.739162) (xy 301.103033 -370.745195) (xy 301.099417 -370.758452) (xy 301.09922 -370.765324)
			(xy 301.09922 -371.514878) (xy 301.099418 -371.521751) (xy 301.103022 -371.535014) (xy 301.106332 -371.54104)
			(xy 301.122707 -371.569384) (xy 301.148508 -371.629545) (xy 301.165995 -371.692626) (xy 301.174852 -371.757484)
			(xy 301.17542 -371.790214) (xy 301.174835 -371.822943) (xy 301.165985 -371.8878) (xy 301.1485 -371.95088)
			(xy 301.122698 -372.011039) (xy 301.106332 -372.039388) (xy 301.103024 -372.045416) (xy 301.099414 -372.058677)
			(xy 301.09922 -372.06555) (xy 301.09922 -372.351554) (xy 301.098734 -372.361683) (xy 301.091014 -372.38041)
			(xy 301.076727 -372.39477) (xy 301.058038 -372.402583) (xy 301.047912 -372.403116) (xy 300.331632 -372.403116)
			(xy 300.321482 -372.402653) (xy 300.302733 -372.394871) (xy 300.288409 -372.380487) (xy 300.280705 -372.361706)
			(xy 300.280324 -372.351554) (xy 300.280324 -372.06555) (xy 300.28011 -372.058678) (xy 300.276517 -372.045416)
			(xy 300.273212 -372.039388) (xy 300.256843 -372.011041) (xy 300.231042 -371.950881) (xy 300.213553 -371.8878)
			(xy 300.204694 -371.822943) (xy 300.204124 -371.790214) (xy 298.931839 -371.790214) (xy 298.923011 -371.810874)
			(xy 298.906692 -371.839236) (xy 298.903364 -371.845254) (xy 298.899767 -371.858523) (xy 298.89958 -371.865398)
			(xy 298.89958 -372.614698) (xy 298.899775 -372.621571) (xy 298.903381 -372.634834) (xy 298.906692 -372.64086)
			(xy 298.923042 -372.669206) (xy 298.948755 -372.729381) (xy 298.966159 -372.792463) (xy 298.974939 -372.85731)
			(xy 298.974937 -372.890034) (xy 302.404272 -372.890034) (xy 302.404834 -372.857304) (xy 302.413692 -372.792446)
			(xy 302.431183 -372.729366) (xy 302.456991 -372.669208) (xy 302.47336 -372.64086) (xy 302.476686 -372.634841)
			(xy 302.480285 -372.621573) (xy 302.480472 -372.614698) (xy 302.480472 -371.865398) (xy 302.480284 -371.858524)
			(xy 302.476673 -371.845262) (xy 302.47336 -371.839236) (xy 302.457014 -371.810876) (xy 302.431206 -371.750721)
			(xy 302.413711 -371.687644) (xy 302.404845 -371.62279) (xy 302.404272 -371.590062) (xy 302.404847 -371.557333)
			(xy 302.413701 -371.492475) (xy 302.431188 -371.429395) (xy 302.456993 -371.369237) (xy 302.47336 -371.340888)
			(xy 302.476676 -371.334864) (xy 302.480281 -371.3216) (xy 302.480472 -371.314726) (xy 302.480472 -371.028722)
			(xy 302.480945 -371.018593) (xy 302.488672 -370.999866) (xy 302.502963 -370.985508) (xy 302.521653 -370.977693)
			(xy 302.53178 -370.97716) (xy 303.24806 -370.97716) (xy 303.258207 -370.977654) (xy 303.27695 -370.985429)
			(xy 303.291274 -370.999803) (xy 303.298982 -371.018574) (xy 303.299368 -371.028722) (xy 303.299368 -371.314726)
			(xy 303.299554 -371.3216) (xy 303.303167 -371.334862) (xy 303.30648 -371.340888) (xy 303.322839 -371.369241)
			(xy 303.348643 -371.429399) (xy 303.366134 -371.492477) (xy 303.374997 -371.557333) (xy 303.375568 -371.590062)
			(xy 303.374998 -371.622791) (xy 303.366142 -371.687649) (xy 303.348653 -371.750729) (xy 303.331716 -371.790214)
			(xy 304.603666 -371.790214) (xy 304.607657 -371.728047) (xy 304.619566 -371.6669) (xy 304.639195 -371.607779)
			(xy 304.666224 -371.551653) (xy 304.700208 -371.499444) (xy 304.74059 -371.452009) (xy 304.786706 -371.410128)
			(xy 304.837798 -371.374488) (xy 304.893029 -371.345674) (xy 304.951491 -371.32416) (xy 305.012225 -371.310298)
			(xy 305.074232 -371.304316) (xy 305.136495 -371.306312) (xy 305.197992 -371.316255) (xy 305.257713 -371.333979)
			(xy 305.314676 -371.359196) (xy 305.367947 -371.391489) (xy 305.416652 -371.430329) (xy 305.459989 -371.475079)
			(xy 305.497249 -371.525003) (xy 305.527818 -371.579282) (xy 305.532182 -371.590062) (xy 306.803814 -371.590062)
			(xy 306.807805 -371.527895) (xy 306.819714 -371.466748) (xy 306.839343 -371.407627) (xy 306.866372 -371.351501)
			(xy 306.900356 -371.299292) (xy 306.940738 -371.251857) (xy 306.986854 -371.209976) (xy 307.037946 -371.174336)
			(xy 307.093177 -371.145522) (xy 307.151639 -371.124008) (xy 307.212373 -371.110146) (xy 307.27438 -371.104164)
			(xy 307.336643 -371.10616) (xy 307.39814 -371.116103) (xy 307.457861 -371.133827) (xy 307.514824 -371.159044)
			(xy 307.568095 -371.191337) (xy 307.6168 -371.230177) (xy 307.660137 -371.274927) (xy 307.697397 -371.324851)
			(xy 307.727966 -371.37913) (xy 307.751344 -371.436873) (xy 307.767145 -371.497131) (xy 307.775111 -371.558914)
			(xy 307.77561 -371.590062) (xy 307.775111 -371.62121) (xy 307.767145 -371.682993) (xy 307.751344 -371.743251)
			(xy 307.727966 -371.800994) (xy 307.697397 -371.855273) (xy 307.660137 -371.905197) (xy 307.6168 -371.949947)
			(xy 307.568095 -371.988787) (xy 307.514824 -372.02108) (xy 307.457861 -372.046297) (xy 307.39814 -372.064021)
			(xy 307.336643 -372.073964) (xy 307.27438 -372.07596) (xy 307.212373 -372.069978) (xy 307.151639 -372.056116)
			(xy 307.093177 -372.034602) (xy 307.037946 -372.005788) (xy 306.986854 -371.970148) (xy 306.940738 -371.928267)
			(xy 306.900356 -371.880832) (xy 306.866372 -371.828623) (xy 306.839343 -371.772497) (xy 306.819714 -371.713376)
			(xy 306.807805 -371.652229) (xy 306.803814 -371.590062) (xy 305.532182 -371.590062) (xy 305.551196 -371.637025)
			(xy 305.566997 -371.697283) (xy 305.574963 -371.759066) (xy 305.575462 -371.790214) (xy 305.574963 -371.821362)
			(xy 305.566997 -371.883145) (xy 305.551196 -371.943403) (xy 305.527818 -372.001146) (xy 305.497249 -372.055425)
			(xy 305.459989 -372.105349) (xy 305.416652 -372.150099) (xy 305.367947 -372.188939) (xy 305.314676 -372.221232)
			(xy 305.257713 -372.246449) (xy 305.197992 -372.264173) (xy 305.136495 -372.274116) (xy 305.074232 -372.276112)
			(xy 305.012225 -372.27013) (xy 304.951491 -372.256268) (xy 304.893029 -372.234754) (xy 304.837798 -372.20594)
			(xy 304.786706 -372.1703) (xy 304.74059 -372.128419) (xy 304.700208 -372.080984) (xy 304.666224 -372.028775)
			(xy 304.639195 -371.972649) (xy 304.619566 -371.913528) (xy 304.607657 -371.852381) (xy 304.603666 -371.790214)
			(xy 303.331716 -371.790214) (xy 303.322848 -371.810888) (xy 303.30648 -371.839236) (xy 303.303151 -371.845254)
			(xy 303.299555 -371.858523) (xy 303.299368 -371.865398) (xy 303.299368 -372.614698) (xy 303.299565 -372.621571)
			(xy 303.30317 -372.634833) (xy 303.30648 -372.64086) (xy 303.322828 -372.669219) (xy 303.348634 -372.729375)
			(xy 303.366129 -372.792451) (xy 303.374995 -372.857306) (xy 303.375568 -372.890034) (xy 306.803814 -372.890034)
			(xy 306.807805 -372.827867) (xy 306.819714 -372.76672) (xy 306.839343 -372.707599) (xy 306.866372 -372.651473)
			(xy 306.900356 -372.599264) (xy 306.940738 -372.551829) (xy 306.986854 -372.509948) (xy 307.037946 -372.474308)
			(xy 307.093177 -372.445494) (xy 307.151639 -372.42398) (xy 307.212373 -372.410118) (xy 307.27438 -372.404136)
			(xy 307.336643 -372.406132) (xy 307.39814 -372.416075) (xy 307.457861 -372.433799) (xy 307.514824 -372.459016)
			(xy 307.568095 -372.491309) (xy 307.6168 -372.530149) (xy 307.660137 -372.574899) (xy 307.697397 -372.624823)
			(xy 307.727966 -372.679102) (xy 307.751344 -372.736845) (xy 307.767145 -372.797103) (xy 307.775111 -372.858886)
			(xy 307.77561 -372.890034) (xy 307.775111 -372.921182) (xy 307.767145 -372.982965) (xy 307.751344 -373.043223)
			(xy 307.727966 -373.100966) (xy 307.697397 -373.155245) (xy 307.660137 -373.205169) (xy 307.6168 -373.249919)
			(xy 307.568095 -373.288759) (xy 307.514824 -373.321052) (xy 307.457861 -373.346269) (xy 307.39814 -373.363993)
			(xy 307.336643 -373.373936) (xy 307.27438 -373.375932) (xy 307.212373 -373.36995) (xy 307.151639 -373.356088)
			(xy 307.093177 -373.334574) (xy 307.037946 -373.30576) (xy 306.986854 -373.27012) (xy 306.940738 -373.228239)
			(xy 306.900356 -373.180804) (xy 306.866372 -373.128595) (xy 306.839343 -373.072469) (xy 306.819714 -373.013348)
			(xy 306.807805 -372.952201) (xy 306.803814 -372.890034) (xy 303.375568 -372.890034) (xy 303.374986 -372.922763)
			(xy 303.366134 -372.98762) (xy 303.348648 -373.0507) (xy 303.322846 -373.110859) (xy 303.30648 -373.139208)
			(xy 303.303161 -373.14523) (xy 303.299558 -373.158496) (xy 303.299368 -373.16537) (xy 303.299368 -373.451374)
			(xy 303.298853 -373.461498) (xy 303.291135 -373.480217) (xy 303.276857 -373.494574) (xy 303.258181 -373.502396)
			(xy 303.24806 -373.502936) (xy 302.53178 -373.502936) (xy 302.521629 -373.502496) (xy 302.502883 -373.4947)
			(xy 302.488562 -373.48031) (xy 302.480856 -373.461527) (xy 302.480472 -373.451374) (xy 302.480472 -373.16537)
			(xy 302.480295 -373.158496) (xy 302.476677 -373.145233) (xy 302.47336 -373.139208) (xy 302.457003 -373.110854)
			(xy 302.431198 -373.050696) (xy 302.413706 -372.987618) (xy 302.404843 -372.922763) (xy 302.404272 -372.890034)
			(xy 298.974937 -372.890034) (xy 298.974935 -372.922748) (xy 298.966147 -372.987595) (xy 298.948736 -373.050674)
			(xy 298.923016 -373.110846) (xy 298.906692 -373.139208) (xy 298.903374 -373.145231) (xy 298.899771 -373.158496)
			(xy 298.89958 -373.16537) (xy 298.89958 -373.451374) (xy 298.899115 -373.461542) (xy 298.891342 -373.480332)
			(xy 298.876969 -373.494717) (xy 298.858185 -373.502506) (xy 298.848018 -373.502936) (xy 298.131738 -373.502936)
			(xy 298.121566 -373.502504) (xy 298.102767 -373.494727) (xy 298.08838 -373.480343) (xy 298.080598 -373.461546)
			(xy 298.080176 -373.451374) (xy 298.080176 -373.16537) (xy 298.079999 -373.158496) (xy 298.076381 -373.145233)
			(xy 298.073064 -373.139208) (xy 298.05677 -373.110831) (xy 298.031048 -373.050664) (xy 298.013636 -372.987588)
			(xy 298.004848 -372.922746) (xy 298.004844 -372.857312) (xy 298.013624 -372.792469) (xy 298.031029 -372.729391)
			(xy 298.056743 -372.669221) (xy 298.073064 -372.64086) (xy 298.07639 -372.634841) (xy 298.079989 -372.621573)
			(xy 298.080176 -372.614698) (xy 298.080176 -371.865398) (xy 298.079988 -371.858524) (xy 298.076377 -371.845262)
			(xy 298.073064 -371.839236) (xy 298.056709 -371.810893) (xy 298.030993 -371.750718) (xy 298.013587 -371.687635)
			(xy 298.004807 -371.622787) (xy 296.745823 -371.622787) (xy 296.748721 -371.629545) (xy 296.766208 -371.692626)
			(xy 296.775064 -371.757484) (xy 296.775632 -371.790214) (xy 296.775046 -371.822943) (xy 296.766195 -371.8878)
			(xy 296.748711 -371.95088) (xy 296.722909 -372.011039) (xy 296.706544 -372.039388) (xy 296.703237 -372.045417)
			(xy 296.699626 -372.058677) (xy 296.699432 -372.06555) (xy 296.699432 -372.351554) (xy 296.698935 -372.361681)
			(xy 296.691217 -372.380407) (xy 296.676933 -372.394765) (xy 296.658249 -372.402581) (xy 296.648124 -372.403116)
			(xy 295.931844 -372.403116) (xy 295.921695 -372.402643) (xy 295.902946 -372.394865) (xy 295.888622 -372.380484)
			(xy 295.880918 -372.361705) (xy 295.880536 -372.351554) (xy 295.880536 -372.06555) (xy 295.880321 -372.058679)
			(xy 295.876728 -372.045416) (xy 295.873424 -372.039388) (xy 295.857056 -372.01104) (xy 295.831254 -371.95088)
			(xy 295.813765 -371.8878) (xy 295.804906 -371.822943) (xy 295.804336 -371.790214) (xy 294.531636 -371.790214)
			(xy 294.522766 -371.810888) (xy 294.506396 -371.839236) (xy 294.503068 -371.845254) (xy 294.499471 -371.858523)
			(xy 294.499284 -371.865398) (xy 294.499284 -372.614698) (xy 294.499479 -372.621571) (xy 294.503085 -372.634834)
			(xy 294.506396 -372.64086) (xy 294.522745 -372.669218) (xy 294.548551 -372.729374) (xy 294.566045 -372.792451)
			(xy 294.574911 -372.857306) (xy 294.575484 -372.890034) (xy 294.574913 -372.922763) (xy 294.566059 -372.987622)
			(xy 294.54857 -373.050702) (xy 294.522764 -373.11086) (xy 294.506396 -373.139208) (xy 294.503078 -373.145231)
			(xy 294.499475 -373.158496) (xy 294.499284 -373.16537) (xy 294.499284 -373.451374) (xy 294.498753 -373.461496)
			(xy 294.491038 -373.480212) (xy 294.476766 -373.494569) (xy 294.458095 -373.502393) (xy 294.447976 -373.502936)
			(xy 293.731696 -373.502936) (xy 293.721546 -373.502482) (xy 293.702801 -373.494692) (xy 293.688479 -373.480306)
			(xy 293.680773 -373.461526) (xy 293.680388 -373.451374) (xy 293.680388 -373.16537) (xy 293.680209 -373.158496)
			(xy 293.676592 -373.145233) (xy 293.673276 -373.139208) (xy 293.656911 -373.110858) (xy 293.63111 -373.050699)
			(xy 293.61362 -372.987619) (xy 293.604759 -372.922763) (xy 293.604188 -372.890034) (xy 290.17485 -372.890034)
			(xy 290.174848 -372.922748) (xy 290.166062 -372.987594) (xy 290.148651 -373.050674) (xy 290.122931 -373.110846)
			(xy 290.106608 -373.139208) (xy 290.103291 -373.145232) (xy 290.099687 -373.158496) (xy 290.099496 -373.16537)
			(xy 290.099496 -373.451374) (xy 290.098946 -373.461526) (xy 290.091187 -373.480288) (xy 290.076838 -373.494653)
			(xy 290.058085 -373.502435) (xy 290.047934 -373.502936) (xy 289.331654 -373.502936) (xy 289.32149 -373.502504)
			(xy 289.302715 -373.494709) (xy 289.28835 -373.480325) (xy 289.280582 -373.461539) (xy 289.280092 -373.451374)
			(xy 289.280092 -373.16537) (xy 289.279913 -373.158496) (xy 289.276296 -373.145233) (xy 289.27298 -373.139208)
			(xy 289.256685 -373.110831) (xy 289.230963 -373.050664) (xy 289.21355 -372.987589) (xy 289.204762 -372.922747)
			(xy 289.204758 -372.857312) (xy 289.213538 -372.792469) (xy 289.230944 -372.729391) (xy 289.256659 -372.669221)
			(xy 289.27298 -372.64086) (xy 289.276308 -372.634842) (xy 289.279905 -372.621573) (xy 289.280092 -372.614698)
			(xy 289.280092 -371.865398) (xy 289.279902 -371.858525) (xy 289.276293 -371.845262) (xy 289.27298 -371.839236)
			(xy 289.256624 -371.810893) (xy 289.230908 -371.750718) (xy 289.213501 -371.687635) (xy 289.204721 -371.622787)
			(xy 287.945739 -371.622787) (xy 287.948637 -371.629544) (xy 287.966124 -371.692626) (xy 287.97498 -371.757484)
			(xy 287.975548 -371.790214) (xy 287.97496 -371.822943) (xy 287.96611 -371.8878) (xy 287.948626 -371.95088)
			(xy 287.922825 -372.011039) (xy 287.90646 -372.039388) (xy 287.903154 -372.045417) (xy 287.899542 -372.058677)
			(xy 287.899348 -372.06555) (xy 287.899348 -372.351554) (xy 287.898835 -372.361679) (xy 287.89112 -372.380402)
			(xy 287.876842 -372.39476) (xy 287.858162 -372.402579) (xy 287.84804 -372.403116) (xy 287.13176 -372.403116)
			(xy 287.121605 -372.402711) (xy 287.102855 -372.394906) (xy 287.088534 -372.380504) (xy 287.080833 -372.361711)
			(xy 287.080452 -372.351554) (xy 287.080452 -372.06555) (xy 287.080247 -372.058678) (xy 287.076648 -372.045415)
			(xy 287.07334 -372.039388) (xy 287.056973 -372.011039) (xy 287.031171 -371.95088) (xy 287.013681 -371.8878)
			(xy 287.004822 -371.822943) (xy 287.004252 -371.790214) (xy 282.775152 -371.790214) (xy 282.775152 -375.69013)
			(xy 287.004252 -375.69013) (xy 287.004815 -375.6574) (xy 287.013673 -375.592542) (xy 287.031164 -375.529462)
			(xy 287.056971 -375.469304) (xy 287.07334 -375.440956) (xy 287.076666 -375.434937) (xy 287.080265 -375.421669)
			(xy 287.080452 -375.414794) (xy 287.080452 -374.665494) (xy 287.080268 -374.65862) (xy 287.076655 -374.645357)
			(xy 287.07334 -374.639332) (xy 287.056991 -374.610974) (xy 287.031184 -374.550818) (xy 287.01369 -374.487741)
			(xy 287.004825 -374.422886) (xy 287.004252 -374.390158) (xy 287.004828 -374.357429) (xy 287.013681 -374.292571)
			(xy 287.031169 -374.229491) (xy 287.056973 -374.169332) (xy 287.07334 -374.140984) (xy 287.076656 -374.13496)
			(xy 287.080262 -374.121696) (xy 287.080452 -374.114822) (xy 287.080452 -373.828818) (xy 287.080942 -373.818691)
			(xy 287.088666 -373.799968) (xy 287.102951 -373.785611) (xy 287.121636 -373.777793) (xy 287.13176 -373.777256)
			(xy 287.84804 -373.777256) (xy 287.858191 -373.777688) (xy 287.876936 -373.785489) (xy 287.891256 -373.799881)
			(xy 287.898963 -373.818665) (xy 287.899348 -373.828818) (xy 287.899348 -374.114822) (xy 287.899526 -374.121696)
			(xy 287.903143 -374.134959) (xy 287.90646 -374.140984) (xy 287.922815 -374.169339) (xy 287.948621 -374.229496)
			(xy 287.966113 -374.292574) (xy 287.974976 -374.357429) (xy 287.975548 -374.390158) (xy 287.974979 -374.422884)
			(xy 291.404874 -374.422884) (xy 291.404879 -374.357444) (xy 291.413668 -374.292598) (xy 291.431081 -374.229517)
			(xy 291.456803 -374.169345) (xy 291.473128 -374.140984) (xy 291.47645 -374.134963) (xy 291.480051 -374.121696)
			(xy 291.48024 -374.114822) (xy 291.48024 -373.828818) (xy 291.480678 -373.818647) (xy 291.488458 -373.799853)
			(xy 291.502839 -373.785467) (xy 291.521631 -373.777682) (xy 291.531802 -373.777256) (xy 292.248082 -373.777256)
			(xy 292.258255 -373.777679) (xy 292.277053 -373.785461) (xy 292.291439 -373.799847) (xy 292.299221 -373.818645)
			(xy 292.299644 -373.828818) (xy 292.299644 -374.114822) (xy 292.299822 -374.121696) (xy 292.303439 -374.134959)
			(xy 292.306756 -374.140984) (xy 292.323043 -374.169365) (xy 292.348764 -374.229531) (xy 292.366176 -374.292606)
			(xy 292.374964 -374.357447) (xy 292.374969 -374.422881) (xy 292.366191 -374.487723) (xy 292.348788 -374.5508)
			(xy 292.323076 -374.610971) (xy 292.306756 -374.639332) (xy 292.303434 -374.645353) (xy 292.299832 -374.65862)
			(xy 292.299644 -374.665494) (xy 292.299644 -375.414794) (xy 292.299833 -375.421668) (xy 292.303443 -375.434931)
			(xy 292.306756 -375.440956) (xy 292.323104 -375.469303) (xy 292.348819 -375.529478) (xy 292.366225 -375.592559)
			(xy 292.375005 -375.657406) (xy 292.375002 -375.722845) (xy 292.366214 -375.787691) (xy 292.348802 -375.850771)
			(xy 292.32308 -375.910943) (xy 292.306756 -375.939304) (xy 292.303444 -375.94533) (xy 292.299836 -375.958593)
			(xy 292.299644 -375.965466) (xy 292.299644 -376.25147) (xy 292.299211 -376.261642) (xy 292.291433 -376.280439)
			(xy 292.277049 -376.294826) (xy 292.258254 -376.302609) (xy 292.248082 -376.303032) (xy 291.531802 -376.303032)
			(xy 291.521627 -376.302634) (xy 291.502826 -376.294844) (xy 291.48844 -376.28045) (xy 291.480661 -376.261645)
			(xy 291.48024 -376.25147) (xy 291.48024 -375.965466) (xy 291.480056 -375.958592) (xy 291.476442 -375.94533)
			(xy 291.473128 -375.939304) (xy 291.456832 -375.910929) (xy 291.431112 -375.850761) (xy 291.413702 -375.787685)
			(xy 291.404915 -375.722843) (xy 291.404912 -375.657408) (xy 291.413691 -375.592566) (xy 291.431095 -375.529488)
			(xy 291.456808 -375.469317) (xy 291.473128 -375.440956) (xy 291.47646 -375.43494) (xy 291.480054 -375.42167)
			(xy 291.48024 -375.414794) (xy 291.48024 -374.665494) (xy 291.480045 -374.658621) (xy 291.476438 -374.645358)
			(xy 291.473128 -374.639332) (xy 291.456771 -374.61099) (xy 291.431057 -374.550814) (xy 291.413653 -374.487732)
			(xy 291.404874 -374.422884) (xy 287.974979 -374.422884) (xy 287.974979 -374.422887) (xy 287.966124 -374.487745)
			(xy 287.948634 -374.550825) (xy 287.922828 -374.610984) (xy 287.90646 -374.639332) (xy 287.903139 -374.645353)
			(xy 287.899536 -374.65862) (xy 287.899348 -374.665494) (xy 287.899348 -375.414794) (xy 287.899536 -375.421668)
			(xy 287.903146 -375.434931) (xy 287.90646 -375.440956) (xy 287.922804 -375.469317) (xy 287.948612 -375.529472)
			(xy 287.966108 -375.592548) (xy 287.974975 -375.657402) (xy 287.975548 -375.69013) (xy 287.974967 -375.722859)
			(xy 287.966115 -375.787716) (xy 287.948629 -375.850797) (xy 287.922826 -375.910955) (xy 287.90646 -375.939304)
			(xy 287.903149 -375.94533) (xy 287.89954 -375.958593) (xy 287.899348 -375.965466) (xy 287.899348 -376.25147)
			(xy 287.898849 -376.261596) (xy 287.891129 -376.280319) (xy 287.876846 -376.294677) (xy 287.858164 -376.302495)
			(xy 287.84804 -376.303032) (xy 287.13176 -376.303032) (xy 287.121607 -376.302612) (xy 287.10286 -376.294809)
			(xy 287.088539 -376.280413) (xy 287.080835 -376.261625) (xy 287.080452 -376.25147) (xy 287.080452 -375.965466)
			(xy 287.080279 -375.958591) (xy 287.076658 -375.945328) (xy 287.07334 -375.939304) (xy 287.05698 -375.910952)
			(xy 287.031176 -375.850794) (xy 287.013684 -375.787715) (xy 287.004823 -375.722859) (xy 287.004252 -375.69013)
			(xy 282.775152 -375.69013) (xy 282.775152 -376.822922) (xy 289.204745 -376.822922) (xy 289.204745 -376.757485)
			(xy 289.213528 -376.69264) (xy 289.230938 -376.629562) (xy 289.256657 -376.569391) (xy 289.27298 -376.54103)
			(xy 289.276283 -376.534999) (xy 289.279896 -376.52174) (xy 289.280092 -376.514868) (xy 289.280092 -375.765568)
			(xy 289.279913 -375.758694) (xy 289.276296 -375.745431) (xy 289.27298 -375.739406) (xy 289.256684 -375.71103)
			(xy 289.230961 -375.650863) (xy 289.213549 -375.587787) (xy 289.204761 -375.522945) (xy 289.204757 -375.45751)
			(xy 289.213538 -375.392667) (xy 289.230943 -375.329589) (xy 289.256659 -375.269419) (xy 289.27298 -375.241058)
			(xy 289.276308 -375.23504) (xy 289.279906 -375.221771) (xy 289.280092 -375.214896) (xy 289.280092 -374.928638)
			(xy 289.280664 -374.918488) (xy 289.288417 -374.899729) (xy 289.302758 -374.885364) (xy 289.321505 -374.87758)
			(xy 289.331654 -374.877076) (xy 290.047934 -374.877076) (xy 290.058113 -374.877437) (xy 290.076915 -374.88524)
			(xy 290.0913 -374.899645) (xy 290.099077 -374.918459) (xy 290.099496 -374.928638) (xy 290.099496 -375.214896)
			(xy 290.09969 -375.221769) (xy 290.103297 -375.235032) (xy 290.106608 -375.241058) (xy 290.122956 -375.269405)
			(xy 290.148668 -375.32958) (xy 290.166072 -375.392662) (xy 290.174851 -375.457508) (xy 290.174847 -375.522947)
			(xy 290.166061 -375.587792) (xy 290.14865 -375.650872) (xy 290.122931 -375.711044) (xy 290.106608 -375.739406)
			(xy 290.103292 -375.74543) (xy 290.099687 -375.758694) (xy 290.099496 -375.765568) (xy 290.099496 -376.514868)
			(xy 290.099701 -376.52174) (xy 290.103301 -376.535003) (xy 290.106608 -376.54103) (xy 290.122932 -376.56939)
			(xy 290.148647 -376.629562) (xy 290.166053 -376.692641) (xy 290.174835 -376.757485) (xy 290.174835 -376.790204)
			(xy 293.604188 -376.790204) (xy 293.604735 -376.757474) (xy 293.613596 -376.692615) (xy 293.631092 -376.629535)
			(xy 293.656905 -376.569377) (xy 293.673276 -376.54103) (xy 293.676578 -376.534999) (xy 293.680192 -376.52174)
			(xy 293.680388 -376.514868) (xy 293.680388 -375.765568) (xy 293.68021 -375.758694) (xy 293.676592 -375.745431)
			(xy 293.673276 -375.739406) (xy 293.656911 -375.711057) (xy 293.631109 -375.650897) (xy 293.61362 -375.587818)
			(xy 293.604759 -375.522961) (xy 293.604188 -375.490232) (xy 293.604747 -375.457502) (xy 293.613605 -375.392644)
			(xy 293.631097 -375.329564) (xy 293.656906 -375.269406) (xy 293.673276 -375.241058) (xy 293.676604 -375.23504)
			(xy 293.680202 -375.221771) (xy 293.680388 -375.214896) (xy 293.680388 -374.928638) (xy 293.680956 -374.91852)
			(xy 293.688662 -374.89981) (xy 293.702923 -374.885454) (xy 293.721582 -374.877624) (xy 293.731696 -374.877076)
			(xy 294.447976 -374.877076) (xy 294.458126 -374.877541) (xy 294.476873 -374.885324) (xy 294.491196 -374.899707)
			(xy 294.498901 -374.918487) (xy 294.499284 -374.928638) (xy 294.499284 -375.214896) (xy 294.499479 -375.221769)
			(xy 294.503085 -375.235032) (xy 294.506396 -375.241058) (xy 294.522744 -375.269417) (xy 294.548551 -375.329573)
			(xy 294.566045 -375.392649) (xy 294.574911 -375.457504) (xy 294.575484 -375.490232) (xy 294.574912 -375.522961)
			(xy 294.566059 -375.587819) (xy 294.54857 -375.6509) (xy 294.531741 -375.69013) (xy 295.804336 -375.69013)
			(xy 295.804901 -375.657401) (xy 295.813759 -375.592543) (xy 295.831249 -375.529463) (xy 295.857056 -375.469304)
			(xy 295.873424 -375.440956) (xy 295.876756 -375.43494) (xy 295.88035 -375.42167) (xy 295.880536 -375.414794)
			(xy 295.880536 -374.665494) (xy 295.880342 -374.658621) (xy 295.876735 -374.645358) (xy 295.873424 -374.639332)
			(xy 295.857073 -374.610974) (xy 295.831267 -374.550818) (xy 295.813773 -374.487741) (xy 295.804909 -374.422886)
			(xy 295.804336 -374.390158) (xy 295.804914 -374.357429) (xy 295.813767 -374.292571) (xy 295.831254 -374.229491)
			(xy 295.857058 -374.169333) (xy 295.873424 -374.140984) (xy 295.876746 -374.134963) (xy 295.880347 -374.121696)
			(xy 295.880536 -374.114822) (xy 295.880536 -373.828818) (xy 295.881041 -373.818693) (xy 295.888762 -373.799973)
			(xy 295.903043 -373.785616) (xy 295.921722 -373.777796) (xy 295.931844 -373.777256) (xy 296.648124 -373.777256)
			(xy 296.658274 -373.777701) (xy 296.677019 -373.785496) (xy 296.69134 -373.799885) (xy 296.699046 -373.818666)
			(xy 296.699432 -373.828818) (xy 296.699432 -374.114822) (xy 296.699612 -374.121696) (xy 296.703228 -374.134959)
			(xy 296.706544 -374.140984) (xy 296.722898 -374.16934) (xy 296.748704 -374.229497) (xy 296.766197 -374.292574)
			(xy 296.77506 -374.357429) (xy 296.775632 -374.390158) (xy 296.775066 -374.422887) (xy 296.766209 -374.487746)
			(xy 296.748719 -374.550826) (xy 296.722912 -374.610984) (xy 296.706544 -374.639332) (xy 296.703221 -374.645353)
			(xy 296.69962 -374.658619) (xy 296.699432 -374.665494) (xy 296.699432 -375.414794) (xy 296.699622 -375.421667)
			(xy 296.703231 -375.43493) (xy 296.706544 -375.440956) (xy 296.722887 -375.469318) (xy 296.748695 -375.529472)
			(xy 296.766192 -375.592548) (xy 296.775059 -375.657402) (xy 296.775632 -375.69013) (xy 296.775053 -375.722859)
			(xy 296.7662 -375.787717) (xy 296.748714 -375.850797) (xy 296.72291 -375.910955) (xy 296.706544 -375.939304)
			(xy 296.703231 -375.94533) (xy 296.699624 -375.958593) (xy 296.699432 -375.965466) (xy 296.699432 -376.25147)
			(xy 296.698948 -376.261598) (xy 296.691225 -376.280324) (xy 296.676937 -376.294683) (xy 296.65825 -376.302498)
			(xy 296.648124 -376.303032) (xy 295.931844 -376.303032) (xy 295.921697 -376.302543) (xy 295.902951 -376.294768)
			(xy 295.888628 -376.280392) (xy 295.880921 -376.261619) (xy 295.880536 -376.25147) (xy 295.880536 -375.965466)
			(xy 295.880352 -375.958592) (xy 295.876738 -375.94533) (xy 295.873424 -375.939304) (xy 295.857062 -375.910953)
			(xy 295.831259 -375.850794) (xy 295.813768 -375.787715) (xy 295.804907 -375.722859) (xy 295.804336 -375.69013)
			(xy 294.531741 -375.69013) (xy 294.522764 -375.711058) (xy 294.506396 -375.739406) (xy 294.503079 -375.745429)
			(xy 294.499475 -375.758694) (xy 294.499284 -375.765568) (xy 294.499284 -376.514868) (xy 294.49949 -376.52174)
			(xy 294.503089 -376.535003) (xy 294.506396 -376.54103) (xy 294.522773 -376.569373) (xy 294.548572 -376.629535)
			(xy 294.566059 -376.692616) (xy 294.574916 -376.757474) (xy 294.575484 -376.790204) (xy 294.574944 -376.822922)
			(xy 298.004831 -376.822922) (xy 298.004831 -376.757485) (xy 298.013614 -376.69264) (xy 298.031023 -376.629562)
			(xy 298.056741 -376.569391) (xy 298.073064 -376.54103) (xy 298.076365 -376.534999) (xy 298.07998 -376.52174)
			(xy 298.080176 -376.514868) (xy 298.080176 -375.765568) (xy 298.079999 -375.758694) (xy 298.076381 -375.745431)
			(xy 298.073064 -375.739406) (xy 298.056768 -375.71103) (xy 298.031047 -375.650863) (xy 298.013635 -375.587787)
			(xy 298.004847 -375.522945) (xy 298.004844 -375.45751) (xy 298.013624 -375.392667) (xy 298.031028 -375.329589)
			(xy 298.056743 -375.269419) (xy 298.073064 -375.241058) (xy 298.076391 -375.235039) (xy 298.079989 -375.221771)
			(xy 298.080176 -375.214896) (xy 298.080176 -374.928638) (xy 298.080596 -374.918464) (xy 298.088376 -374.899663)
			(xy 298.102763 -374.885276) (xy 298.121564 -374.877496) (xy 298.131738 -374.877076) (xy 298.848018 -374.877076)
			(xy 298.858195 -374.87745) (xy 298.876998 -374.885248) (xy 298.891383 -374.899649) (xy 298.899161 -374.91846)
			(xy 298.89958 -374.928638) (xy 298.89958 -375.214896) (xy 298.899776 -375.221769) (xy 298.903382 -375.235032)
			(xy 298.906692 -375.241058) (xy 298.92304 -375.269405) (xy 298.948754 -375.32958) (xy 298.966158 -375.392661)
			(xy 298.974937 -375.457508) (xy 298.974934 -375.522947) (xy 298.966147 -375.587793) (xy 298.948736 -375.650872)
			(xy 298.931955 -375.69013) (xy 300.204124 -375.69013) (xy 300.204678 -375.6574) (xy 300.213537 -375.592541)
			(xy 300.23103 -375.529461) (xy 300.256842 -375.469304) (xy 300.273212 -375.440956) (xy 300.276543 -375.434939)
			(xy 300.280138 -375.421669) (xy 300.280324 -375.414794) (xy 300.280324 -374.665494) (xy 300.280131 -374.658621)
			(xy 300.276523 -374.645358) (xy 300.273212 -374.639332) (xy 300.25686 -374.610975) (xy 300.231055 -374.550818)
			(xy 300.213561 -374.487741) (xy 300.204697 -374.422886) (xy 300.204124 -374.390158) (xy 300.20469 -374.357428)
			(xy 300.213545 -374.29257) (xy 300.231035 -374.22949) (xy 300.256843 -374.169332) (xy 300.273212 -374.140984)
			(xy 300.276533 -374.134963) (xy 300.280135 -374.121696) (xy 300.280324 -374.114822) (xy 300.280324 -373.828818)
			(xy 300.280841 -373.818694) (xy 300.28856 -373.799977) (xy 300.302837 -373.78562) (xy 300.321511 -373.777798)
			(xy 300.331632 -373.777256) (xy 301.047912 -373.777256) (xy 301.058061 -373.777711) (xy 301.076806 -373.785502)
			(xy 301.091127 -373.799888) (xy 301.098834 -373.818667) (xy 301.09922 -373.828818) (xy 301.09922 -374.114822)
			(xy 301.099401 -374.121696) (xy 301.103016 -374.134959) (xy 301.106332 -374.140984) (xy 301.122685 -374.16934)
			(xy 301.148491 -374.229497) (xy 301.165985 -374.292574) (xy 301.174848 -374.35743) (xy 301.17542 -374.390158)
			(xy 304.603666 -374.390158) (xy 304.607657 -374.327991) (xy 304.619566 -374.266844) (xy 304.639195 -374.207723)
			(xy 304.666224 -374.151597) (xy 304.700208 -374.099388) (xy 304.74059 -374.051953) (xy 304.786706 -374.010072)
			(xy 304.837798 -373.974432) (xy 304.893029 -373.945618) (xy 304.951491 -373.924104) (xy 305.012225 -373.910242)
			(xy 305.074232 -373.90426) (xy 305.136495 -373.906256) (xy 305.197992 -373.916199) (xy 305.257713 -373.933923)
			(xy 305.314676 -373.95914) (xy 305.367947 -373.991433) (xy 305.416652 -374.030273) (xy 305.459989 -374.075023)
			(xy 305.497249 -374.124947) (xy 305.527818 -374.179226) (xy 305.551196 -374.236969) (xy 305.566997 -374.297227)
			(xy 305.574963 -374.35901) (xy 305.575462 -374.390158) (xy 305.574963 -374.421306) (xy 305.566997 -374.483089)
			(xy 305.551196 -374.543347) (xy 305.527818 -374.60109) (xy 305.497249 -374.655369) (xy 305.459989 -374.705293)
			(xy 305.416652 -374.750043) (xy 305.367947 -374.788883) (xy 305.314676 -374.821176) (xy 305.257713 -374.846393)
			(xy 305.197992 -374.864117) (xy 305.136495 -374.87406) (xy 305.074232 -374.876056) (xy 305.012225 -374.870074)
			(xy 304.951491 -374.856212) (xy 304.893029 -374.834698) (xy 304.837798 -374.805884) (xy 304.786706 -374.770244)
			(xy 304.74059 -374.728363) (xy 304.700208 -374.680928) (xy 304.666224 -374.628719) (xy 304.639195 -374.572593)
			(xy 304.619566 -374.513472) (xy 304.607657 -374.452325) (xy 304.603666 -374.390158) (xy 301.17542 -374.390158)
			(xy 301.174855 -374.422888) (xy 301.165999 -374.487746) (xy 301.148508 -374.550826) (xy 301.122701 -374.610984)
			(xy 301.106332 -374.639332) (xy 301.103009 -374.645352) (xy 301.099408 -374.658619) (xy 301.09922 -374.665494)
			(xy 301.09922 -375.414794) (xy 301.099412 -375.421667) (xy 301.10302 -375.43493) (xy 301.106332 -375.440956)
			(xy 301.122674 -375.469319) (xy 301.148483 -375.529473) (xy 301.165979 -375.592548) (xy 301.174846 -375.657402)
			(xy 301.17542 -375.69013) (xy 301.174842 -375.722859) (xy 301.16599 -375.787717) (xy 301.148503 -375.850797)
			(xy 301.122699 -375.910955) (xy 301.106332 -375.939304) (xy 301.103019 -375.945329) (xy 301.099412 -375.958592)
			(xy 301.09922 -375.965466) (xy 301.09922 -376.25147) (xy 301.098748 -376.2616) (xy 301.091023 -376.280328)
			(xy 301.076731 -376.294687) (xy 301.058039 -376.3025) (xy 301.047912 -376.303032) (xy 300.331632 -376.303032)
			(xy 300.321484 -376.302553) (xy 300.302738 -376.294774) (xy 300.288415 -376.280395) (xy 300.280708 -376.26162)
			(xy 300.280324 -376.25147) (xy 300.280324 -375.965466) (xy 300.280142 -375.958592) (xy 300.276527 -375.945329)
			(xy 300.273212 -375.939304) (xy 300.256849 -375.910953) (xy 300.231046 -375.850794) (xy 300.213556 -375.787715)
			(xy 300.204695 -375.722859) (xy 300.204124 -375.69013) (xy 298.931955 -375.69013) (xy 298.923015 -375.711044)
			(xy 298.906692 -375.739406) (xy 298.903375 -375.745429) (xy 298.899771 -375.758694) (xy 298.89958 -375.765568)
			(xy 298.89958 -376.514868) (xy 298.899787 -376.52174) (xy 298.903385 -376.535003) (xy 298.906692 -376.54103)
			(xy 298.923017 -376.56939) (xy 298.948732 -376.629562) (xy 298.966139 -376.692641) (xy 298.974921 -376.757485)
			(xy 298.974921 -376.790204) (xy 302.404272 -376.790204) (xy 302.404821 -376.757474) (xy 302.413682 -376.692615)
			(xy 302.431177 -376.629535) (xy 302.456989 -376.569377) (xy 302.47336 -376.54103) (xy 302.476661 -376.534998)
			(xy 302.480276 -376.52174) (xy 302.480472 -376.514868) (xy 302.480472 -375.765568) (xy 302.480296 -375.758694)
			(xy 302.476677 -375.745431) (xy 302.47336 -375.739406) (xy 302.457003 -375.711052) (xy 302.431197 -375.650895)
			(xy 302.413705 -375.587817) (xy 302.404843 -375.522961) (xy 302.404272 -375.490232) (xy 302.404833 -375.457502)
			(xy 302.413691 -375.392644) (xy 302.431183 -375.329564) (xy 302.456991 -375.269406) (xy 302.47336 -375.241058)
			(xy 302.476686 -375.235039) (xy 302.480285 -375.221771) (xy 302.480472 -375.214896) (xy 302.480472 -374.928638)
			(xy 302.480959 -374.91851) (xy 302.48868 -374.899784) (xy 302.502967 -374.885425) (xy 302.521654 -374.87761)
			(xy 302.53178 -374.877076) (xy 303.24806 -374.877076) (xy 303.258209 -374.877554) (xy 303.276955 -374.885332)
			(xy 303.291279 -374.899711) (xy 303.298985 -374.918488) (xy 303.299368 -374.928638) (xy 303.299368 -375.214896)
			(xy 303.299565 -375.221769) (xy 303.30317 -375.235031) (xy 303.30648 -375.241058) (xy 303.322827 -375.269418)
			(xy 303.348634 -375.329573) (xy 303.366129 -375.392649) (xy 303.374995 -375.457504) (xy 303.375568 -375.490232)
			(xy 303.374985 -375.522961) (xy 303.366133 -375.587818) (xy 303.348648 -375.650898) (xy 303.331822 -375.69013)
			(xy 304.603666 -375.69013) (xy 304.607657 -375.627963) (xy 304.619566 -375.566816) (xy 304.639195 -375.507695)
			(xy 304.666224 -375.451569) (xy 304.700208 -375.39936) (xy 304.74059 -375.351925) (xy 304.786706 -375.310044)
			(xy 304.837798 -375.274404) (xy 304.893029 -375.24559) (xy 304.951491 -375.224076) (xy 305.012225 -375.210214)
			(xy 305.074232 -375.204232) (xy 305.136495 -375.206228) (xy 305.197992 -375.216171) (xy 305.257713 -375.233895)
			(xy 305.314676 -375.259112) (xy 305.367947 -375.291405) (xy 305.416652 -375.330245) (xy 305.459989 -375.374995)
			(xy 305.497249 -375.424919) (xy 305.527818 -375.479198) (xy 305.532285 -375.490232) (xy 306.803814 -375.490232)
			(xy 306.807805 -375.428065) (xy 306.819714 -375.366918) (xy 306.839343 -375.307797) (xy 306.866372 -375.251671)
			(xy 306.900356 -375.199462) (xy 306.940738 -375.152027) (xy 306.986854 -375.110146) (xy 307.037946 -375.074506)
			(xy 307.093177 -375.045692) (xy 307.151639 -375.024178) (xy 307.212373 -375.010316) (xy 307.27438 -375.004334)
			(xy 307.336643 -375.00633) (xy 307.39814 -375.016273) (xy 307.457861 -375.033997) (xy 307.514824 -375.059214)
			(xy 307.568095 -375.091507) (xy 307.6168 -375.130347) (xy 307.660137 -375.175097) (xy 307.697397 -375.225021)
			(xy 307.727966 -375.2793) (xy 307.751344 -375.337043) (xy 307.767145 -375.397301) (xy 307.775111 -375.459084)
			(xy 307.77561 -375.490232) (xy 307.775111 -375.52138) (xy 307.767145 -375.583163) (xy 307.751344 -375.643421)
			(xy 307.727966 -375.701164) (xy 307.697397 -375.755443) (xy 307.660137 -375.805367) (xy 307.6168 -375.850117)
			(xy 307.568095 -375.888957) (xy 307.514824 -375.92125) (xy 307.457861 -375.946467) (xy 307.39814 -375.964191)
			(xy 307.336643 -375.974134) (xy 307.27438 -375.97613) (xy 307.212373 -375.970148) (xy 307.151639 -375.956286)
			(xy 307.093177 -375.934772) (xy 307.037946 -375.905958) (xy 306.986854 -375.870318) (xy 306.940738 -375.828437)
			(xy 306.900356 -375.781002) (xy 306.866372 -375.728793) (xy 306.839343 -375.672667) (xy 306.819714 -375.613546)
			(xy 306.807805 -375.552399) (xy 306.803814 -375.490232) (xy 305.532285 -375.490232) (xy 305.551196 -375.536941)
			(xy 305.566997 -375.597199) (xy 305.574963 -375.658982) (xy 305.575462 -375.69013) (xy 305.574963 -375.721278)
			(xy 305.566997 -375.783061) (xy 305.551196 -375.843319) (xy 305.527818 -375.901062) (xy 305.497249 -375.955341)
			(xy 305.459989 -376.005265) (xy 305.416652 -376.050015) (xy 305.367947 -376.088855) (xy 305.314676 -376.121148)
			(xy 305.257713 -376.146365) (xy 305.197992 -376.164089) (xy 305.136495 -376.174032) (xy 305.074232 -376.176028)
			(xy 305.012225 -376.170046) (xy 304.951491 -376.156184) (xy 304.893029 -376.13467) (xy 304.837798 -376.105856)
			(xy 304.786706 -376.070216) (xy 304.74059 -376.028335) (xy 304.700208 -375.9809) (xy 304.666224 -375.928691)
			(xy 304.639195 -375.872565) (xy 304.619566 -375.813444) (xy 304.607657 -375.752297) (xy 304.603666 -375.69013)
			(xy 303.331822 -375.69013) (xy 303.322846 -375.711057) (xy 303.30648 -375.739406) (xy 303.303162 -375.745429)
			(xy 303.299559 -375.758694) (xy 303.299368 -375.765568) (xy 303.299368 -376.514868) (xy 303.299576 -376.52174)
			(xy 303.303174 -376.535003) (xy 303.30648 -376.54103) (xy 303.322856 -376.569374) (xy 303.348655 -376.629535)
			(xy 303.366142 -376.692616) (xy 303.374999 -376.757475) (xy 303.375568 -376.790204) (xy 306.803814 -376.790204)
			(xy 306.807805 -376.728037) (xy 306.819714 -376.66689) (xy 306.839343 -376.607769) (xy 306.866372 -376.551643)
			(xy 306.900356 -376.499434) (xy 306.940738 -376.451999) (xy 306.986854 -376.410118) (xy 307.037946 -376.374478)
			(xy 307.093177 -376.345664) (xy 307.151639 -376.32415) (xy 307.212373 -376.310288) (xy 307.27438 -376.304306)
			(xy 307.336643 -376.306302) (xy 307.39814 -376.316245) (xy 307.457861 -376.333969) (xy 307.514824 -376.359186)
			(xy 307.568095 -376.391479) (xy 307.6168 -376.430319) (xy 307.660137 -376.475069) (xy 307.697397 -376.524993)
			(xy 307.727966 -376.579272) (xy 307.751344 -376.637015) (xy 307.767145 -376.697273) (xy 307.775111 -376.759056)
			(xy 307.77561 -376.790204) (xy 307.775111 -376.821352) (xy 307.767145 -376.883135) (xy 307.751344 -376.943393)
			(xy 307.727966 -377.001136) (xy 307.697397 -377.055415) (xy 307.660137 -377.105339) (xy 307.6168 -377.150089)
			(xy 307.568095 -377.188929) (xy 307.514824 -377.221222) (xy 307.457861 -377.246439) (xy 307.39814 -377.264163)
			(xy 307.336643 -377.274106) (xy 307.27438 -377.276102) (xy 307.212373 -377.27012) (xy 307.151639 -377.256258)
			(xy 307.093177 -377.234744) (xy 307.037946 -377.20593) (xy 306.986854 -377.17029) (xy 306.940738 -377.128409)
			(xy 306.900356 -377.080974) (xy 306.866372 -377.028765) (xy 306.839343 -376.972639) (xy 306.819714 -376.913518)
			(xy 306.807805 -376.852371) (xy 306.803814 -376.790204) (xy 303.375568 -376.790204) (xy 303.375017 -376.822934)
			(xy 303.366155 -376.887792) (xy 303.348661 -376.950872) (xy 303.32285 -377.01103) (xy 303.30648 -377.039378)
			(xy 303.303172 -377.045406) (xy 303.299562 -377.058667) (xy 303.299368 -377.06554) (xy 303.299368 -377.35129)
			(xy 303.298865 -377.361415) (xy 303.291142 -377.380135) (xy 303.276861 -377.394491) (xy 303.258182 -377.402312)
			(xy 303.24806 -377.402852) (xy 302.53178 -377.402852) (xy 302.521631 -377.402396) (xy 302.502888 -377.394604)
			(xy 302.488567 -377.380218) (xy 302.480859 -377.361441) (xy 302.480472 -377.35129) (xy 302.480472 -377.06554)
			(xy 302.480268 -377.058668) (xy 302.476668 -377.045405) (xy 302.47336 -377.039378) (xy 302.456991 -377.01103)
			(xy 302.431189 -376.950871) (xy 302.4137 -376.887791) (xy 302.404841 -376.822933) (xy 302.404272 -376.790204)
			(xy 298.974921 -376.790204) (xy 298.974921 -376.822922) (xy 298.966138 -376.887766) (xy 298.94873 -376.950845)
			(xy 298.923014 -377.011016) (xy 298.906692 -377.039378) (xy 298.903385 -377.045406) (xy 298.899774 -377.058667)
			(xy 298.89958 -377.06554) (xy 298.89958 -377.35129) (xy 298.899059 -377.361445) (xy 298.891291 -377.38021)
			(xy 298.876934 -377.394575) (xy 298.858173 -377.402353) (xy 298.848018 -377.402852) (xy 298.131738 -377.402852)
			(xy 298.121568 -377.402405) (xy 298.102772 -377.39463) (xy 298.088385 -377.380252) (xy 298.080601 -377.36146)
			(xy 298.080176 -377.35129) (xy 298.080176 -377.06554) (xy 298.079972 -377.058668) (xy 298.076372 -377.045405)
			(xy 298.073064 -377.039378) (xy 298.056744 -377.011015) (xy 298.031025 -376.950845) (xy 298.013616 -376.887766)
			(xy 298.004831 -376.822922) (xy 294.574944 -376.822922) (xy 294.574944 -376.822934) (xy 294.566081 -376.887794)
			(xy 294.548583 -376.950874) (xy 294.522768 -377.011031) (xy 294.506396 -377.039378) (xy 294.503089 -377.045406)
			(xy 294.499478 -377.058667) (xy 294.499284 -377.06554) (xy 294.499284 -377.35129) (xy 294.498766 -377.361413)
			(xy 294.491046 -377.38013) (xy 294.47677 -377.394485) (xy 294.458096 -377.402309) (xy 294.447976 -377.402852)
			(xy 293.731696 -377.402852) (xy 293.721548 -377.402383) (xy 293.702806 -377.394595) (xy 293.688484 -377.380214)
			(xy 293.680776 -377.36144) (xy 293.680388 -377.35129) (xy 293.680388 -377.06554) (xy 293.680182 -377.058668)
			(xy 293.676583 -377.045405) (xy 293.673276 -377.039378) (xy 293.656899 -377.011035) (xy 293.631101 -376.950873)
			(xy 293.613614 -376.887792) (xy 293.604757 -376.822933) (xy 293.604188 -376.790204) (xy 290.174835 -376.790204)
			(xy 290.174835 -376.822922) (xy 290.166052 -376.887766) (xy 290.148645 -376.950845) (xy 290.122929 -377.011016)
			(xy 290.106608 -377.039378) (xy 290.103302 -377.045407) (xy 290.099691 -377.058667) (xy 290.099496 -377.06554)
			(xy 290.099496 -377.35129) (xy 290.098959 -377.361443) (xy 290.091194 -377.380205) (xy 290.076842 -377.39457)
			(xy 290.058087 -377.402351) (xy 290.047934 -377.402852) (xy 289.331654 -377.402852) (xy 289.321492 -377.402404)
			(xy 289.30272 -377.394613) (xy 289.288356 -377.380233) (xy 289.280585 -377.361452) (xy 289.280092 -377.35129)
			(xy 289.280092 -377.06554) (xy 289.279886 -377.058668) (xy 289.276287 -377.045405) (xy 289.27298 -377.039378)
			(xy 289.25666 -377.011015) (xy 289.23094 -376.950845) (xy 289.21353 -376.887767) (xy 289.204745 -376.822922)
			(xy 282.775152 -376.822922) (xy 282.775152 -379.590046) (xy 287.004252 -379.590046) (xy 287.004822 -379.557317)
			(xy 287.013678 -379.492459) (xy 287.031167 -379.429379) (xy 287.056972 -379.36922) (xy 287.07334 -379.340872)
			(xy 287.07666 -379.33485) (xy 287.080263 -379.321584) (xy 287.080452 -379.31471) (xy 287.080452 -378.56541)
			(xy 287.080262 -378.558537) (xy 287.076653 -378.545274) (xy 287.07334 -378.539248) (xy 287.056958 -378.510908)
			(xy 287.031159 -378.450745) (xy 287.013674 -378.387663) (xy 287.004819 -378.322804) (xy 287.004252 -378.290074)
			(xy 287.004835 -378.257345) (xy 287.013686 -378.192488) (xy 287.031172 -378.129408) (xy 287.056974 -378.069249)
			(xy 287.07334 -378.0409) (xy 287.07665 -378.034873) (xy 287.080259 -378.021611) (xy 287.080452 -378.014738)
			(xy 287.080452 -377.728734) (xy 287.080955 -377.718608) (xy 287.088674 -377.699885) (xy 287.102955 -377.685528)
			(xy 287.121637 -377.677709) (xy 287.13176 -377.677172) (xy 287.84804 -377.677172) (xy 287.858193 -377.677588)
			(xy 287.876941 -377.685392) (xy 287.891262 -377.699789) (xy 287.898965 -377.718579) (xy 287.899348 -377.728734)
			(xy 287.899348 -378.014738) (xy 287.899558 -378.02161) (xy 287.903153 -378.034873) (xy 287.90646 -378.0409)
			(xy 287.922822 -378.069251) (xy 287.948625 -378.12941) (xy 287.966116 -378.192489) (xy 287.974977 -378.257345)
			(xy 287.975548 -378.290074) (xy 287.974987 -378.322797) (xy 291.404883 -378.322797) (xy 291.404886 -378.257359)
			(xy 291.413673 -378.192513) (xy 291.431084 -378.129433) (xy 291.456804 -378.069261) (xy 291.473128 -378.0409)
			(xy 291.476445 -378.034876) (xy 291.480049 -378.021612) (xy 291.48024 -378.014738) (xy 291.48024 -377.728734)
			(xy 291.480692 -377.718564) (xy 291.488466 -377.69977) (xy 291.502843 -377.685384) (xy 291.521633 -377.677598)
			(xy 291.531802 -377.677172) (xy 292.248082 -377.677172) (xy 292.258257 -377.677579) (xy 292.277058 -377.685365)
			(xy 292.291444 -377.699756) (xy 292.299224 -377.718559) (xy 292.299644 -377.728734) (xy 292.299644 -378.014738)
			(xy 292.299854 -378.02161) (xy 292.303449 -378.034873) (xy 292.306756 -378.0409) (xy 292.323056 -378.069273)
			(xy 292.348776 -378.129442) (xy 292.366187 -378.192518) (xy 292.374973 -378.25736) (xy 292.374976 -378.322795)
			(xy 292.366196 -378.387638) (xy 292.348791 -378.450716) (xy 292.323077 -378.510887) (xy 292.306756 -378.539248)
			(xy 292.303429 -378.545267) (xy 292.29983 -378.558535) (xy 292.299644 -378.56541) (xy 292.299644 -379.31471)
			(xy 292.299827 -379.321584) (xy 292.303441 -379.334847) (xy 292.306756 -379.340872) (xy 292.323117 -379.369212)
			(xy 292.348832 -379.429388) (xy 292.366236 -379.492471) (xy 292.375014 -379.557319) (xy 292.375009 -379.622759)
			(xy 292.36622 -379.687606) (xy 292.348805 -379.750687) (xy 292.323081 -379.810859) (xy 292.306756 -379.83922)
			(xy 292.303439 -379.845243) (xy 292.299834 -379.858508) (xy 292.299644 -379.865382) (xy 292.299644 -380.151386)
			(xy 292.299224 -380.161559) (xy 292.291441 -380.180357) (xy 292.277054 -380.194743) (xy 292.258255 -380.202525)
			(xy 292.248082 -380.202948) (xy 291.531802 -380.202948) (xy 291.521629 -380.202534) (xy 291.502831 -380.194747)
			(xy 291.488446 -380.180358) (xy 291.480663 -380.161559) (xy 291.48024 -380.151386) (xy 291.48024 -379.865382)
			(xy 291.48005 -379.858509) (xy 291.47644 -379.845246) (xy 291.473128 -379.83922) (xy 291.456845 -379.810837)
			(xy 291.431124 -379.750671) (xy 291.413712 -379.687597) (xy 291.404924 -379.622756) (xy 291.404919 -379.557323)
			(xy 291.413697 -379.492481) (xy 291.431098 -379.429404) (xy 291.456809 -379.369233) (xy 291.473128 -379.340872)
			(xy 291.476455 -379.334853) (xy 291.480052 -379.321585) (xy 291.48024 -379.31471) (xy 291.48024 -378.56541)
			(xy 291.480039 -378.558537) (xy 291.476436 -378.545275) (xy 291.473128 -378.539248) (xy 291.456784 -378.510899)
			(xy 291.431069 -378.450725) (xy 291.413664 -378.387643) (xy 291.404883 -378.322797) (xy 287.974987 -378.322797)
			(xy 287.974987 -378.322804) (xy 287.966129 -378.387662) (xy 287.948637 -378.450742) (xy 287.922829 -378.5109)
			(xy 287.90646 -378.539248) (xy 287.903133 -378.545267) (xy 287.899534 -378.558535) (xy 287.899348 -378.56541)
			(xy 287.899348 -379.31471) (xy 287.89953 -379.321584) (xy 287.903144 -379.334847) (xy 287.90646 -379.340872)
			(xy 287.922811 -379.36923) (xy 287.948617 -379.429386) (xy 287.966111 -379.492463) (xy 287.974976 -379.557318)
			(xy 287.975548 -379.590046) (xy 287.974974 -379.622775) (xy 287.96612 -379.687633) (xy 287.948632 -379.750713)
			(xy 287.922827 -379.810872) (xy 287.90646 -379.83922) (xy 287.903143 -379.845244) (xy 287.899538 -379.858508)
			(xy 287.899348 -379.865382) (xy 287.899348 -380.151386) (xy 287.898862 -380.161513) (xy 287.891136 -380.180236)
			(xy 287.87685 -380.194594) (xy 287.858165 -380.202411) (xy 287.84804 -380.202948) (xy 287.13176 -380.202948)
			(xy 287.121609 -380.202512) (xy 287.102865 -380.194712) (xy 287.088545 -380.180321) (xy 287.080838 -380.161539)
			(xy 287.080452 -380.151386) (xy 287.080452 -379.865382) (xy 287.080273 -379.858508) (xy 287.076656 -379.845245)
			(xy 287.07334 -379.83922) (xy 287.056986 -379.810864) (xy 287.031181 -379.750707) (xy 287.013687 -379.68763)
			(xy 287.004824 -379.622774) (xy 287.004252 -379.590046) (xy 282.775152 -379.590046) (xy 282.775152 -380.657399)
			(xy 289.204752 -380.657399) (xy 289.213534 -380.592555) (xy 289.230941 -380.529477) (xy 289.256658 -380.469307)
			(xy 289.27298 -380.440946) (xy 289.276277 -380.434913) (xy 289.279894 -380.421656) (xy 289.280092 -380.414784)
			(xy 289.280092 -379.665484) (xy 289.279907 -379.65861) (xy 289.276294 -379.645347) (xy 289.27298 -379.639322)
			(xy 289.256697 -379.610939) (xy 289.230974 -379.550773) (xy 289.21356 -379.487699) (xy 289.20477 -379.422858)
			(xy 289.204765 -379.357424) (xy 289.213543 -379.292582) (xy 289.230946 -379.229505) (xy 289.25666 -379.169335)
			(xy 289.27298 -379.140974) (xy 289.276303 -379.134953) (xy 289.279904 -379.121687) (xy 289.280092 -379.114812)
			(xy 289.280092 -378.828554) (xy 289.280595 -378.818399) (xy 289.288376 -378.799638) (xy 289.302738 -378.785276)
			(xy 289.321499 -378.777495) (xy 289.331654 -378.776992) (xy 290.047934 -378.776992) (xy 290.058088 -378.777504)
			(xy 290.076849 -378.785281) (xy 290.091212 -378.799641) (xy 290.098993 -378.8184) (xy 290.099496 -378.828554)
			(xy 290.099496 -379.114812) (xy 290.099684 -379.121686) (xy 290.103295 -379.134948) (xy 290.106608 -379.140974)
			(xy 290.122969 -379.169313) (xy 290.148681 -379.22949) (xy 290.166083 -379.292573) (xy 290.17486 -379.357421)
			(xy 290.174855 -379.422861) (xy 290.166066 -379.487707) (xy 290.148654 -379.550788) (xy 290.122932 -379.61096)
			(xy 290.106608 -379.639322) (xy 290.103286 -379.645343) (xy 290.099685 -379.65861) (xy 290.099496 -379.665484)
			(xy 290.099496 -380.414784) (xy 290.099694 -380.421657) (xy 290.103298 -380.43492) (xy 290.106608 -380.440946)
			(xy 290.122946 -380.469298) (xy 290.148659 -380.529472) (xy 290.166064 -380.592553) (xy 290.174844 -380.657398)
			(xy 290.174843 -380.69012) (xy 293.604188 -380.69012) (xy 293.604742 -380.65739) (xy 293.613601 -380.592531)
			(xy 293.631095 -380.529451) (xy 293.656906 -380.469294) (xy 293.673276 -380.440946) (xy 293.676573 -380.434912)
			(xy 293.68019 -380.421656) (xy 293.680388 -380.414784) (xy 293.680388 -379.665484) (xy 293.680204 -379.65861)
			(xy 293.676591 -379.645347) (xy 293.673276 -379.639322) (xy 293.656917 -379.610969) (xy 293.631114 -379.550811)
			(xy 293.613623 -379.487732) (xy 293.60476 -379.422877) (xy 293.604188 -379.390148) (xy 293.604755 -379.357419)
			(xy 293.61361 -379.29256) (xy 293.631101 -379.22948) (xy 293.656908 -379.169322) (xy 293.673276 -379.140974)
			(xy 293.676598 -379.134953) (xy 293.6802 -379.121687) (xy 293.680388 -379.114812) (xy 293.680388 -378.828554)
			(xy 293.680887 -378.818431) (xy 293.688621 -378.799718) (xy 293.702902 -378.785366) (xy 293.721575 -378.777539)
			(xy 293.731696 -378.776992) (xy 294.447976 -378.776992) (xy 294.458128 -378.777441) (xy 294.476878 -378.785227)
			(xy 294.491202 -378.799615) (xy 294.498904 -378.818401) (xy 294.499284 -378.828554) (xy 294.499284 -379.114812)
			(xy 294.499473 -379.121685) (xy 294.503084 -379.134948) (xy 294.506396 -379.140974) (xy 294.522751 -379.169329)
			(xy 294.548555 -379.229486) (xy 294.566048 -379.292564) (xy 294.574912 -379.35742) (xy 294.575484 -379.390148)
			(xy 294.574919 -379.422878) (xy 294.566064 -379.487736) (xy 294.548573 -379.550816) (xy 294.531743 -379.590046)
			(xy 295.804336 -379.590046) (xy 295.804909 -379.557317) (xy 295.813764 -379.492459) (xy 295.831252 -379.429379)
			(xy 295.857057 -379.36922) (xy 295.873424 -379.340872) (xy 295.87675 -379.334853) (xy 295.880348 -379.321585)
			(xy 295.880536 -379.31471) (xy 295.880536 -378.56541) (xy 295.880336 -378.558537) (xy 295.876733 -378.545275)
			(xy 295.873424 -378.539248) (xy 295.85704 -378.510909) (xy 295.831242 -378.450746) (xy 295.813758 -378.387663)
			(xy 295.804903 -378.322804) (xy 295.804336 -378.290074) (xy 295.804921 -378.257345) (xy 295.813772 -378.192488)
			(xy 295.831257 -378.129408) (xy 295.857058 -378.069249) (xy 295.873424 -378.0409) (xy 295.87674 -378.034876)
			(xy 295.880345 -378.021612) (xy 295.880536 -378.014738) (xy 295.880536 -377.728734) (xy 295.881055 -377.71861)
			(xy 295.88877 -377.69989) (xy 295.903047 -377.685533) (xy 295.921723 -377.677712) (xy 295.931844 -377.677172)
			(xy 296.648124 -377.677172) (xy 296.658276 -377.677601) (xy 296.677024 -377.6854) (xy 296.691345 -377.699793)
			(xy 296.699049 -377.71858) (xy 296.699432 -377.728734) (xy 296.699432 -378.014738) (xy 296.699644 -378.02161)
			(xy 296.703238 -378.034873) (xy 296.706544 -378.0409) (xy 296.722904 -378.069252) (xy 296.748709 -378.12941)
			(xy 296.7662 -378.192489) (xy 296.775061 -378.257345) (xy 296.775632 -378.290074) (xy 296.775073 -378.322804)
			(xy 296.766214 -378.387662) (xy 296.748722 -378.450742) (xy 296.722913 -378.5109) (xy 296.706544 -378.539248)
			(xy 296.703216 -378.545266) (xy 296.699618 -378.558535) (xy 296.699432 -378.56541) (xy 296.699432 -379.31471)
			(xy 296.699616 -379.321584) (xy 296.703229 -379.334847) (xy 296.706544 -379.340872) (xy 296.722893 -379.36923)
			(xy 296.7487 -379.429386) (xy 296.766195 -379.492463) (xy 296.77506 -379.557318) (xy 296.775632 -379.590046)
			(xy 296.77506 -379.622775) (xy 296.766206 -379.687633) (xy 296.748717 -379.750713) (xy 296.722912 -379.810872)
			(xy 296.706544 -379.83922) (xy 296.703226 -379.845243) (xy 296.699622 -379.858508) (xy 296.699432 -379.865382)
			(xy 296.699432 -380.151386) (xy 296.698961 -380.161515) (xy 296.691233 -380.180241) (xy 296.676941 -380.194599)
			(xy 296.658251 -380.202414) (xy 296.648124 -380.202948) (xy 295.931844 -380.202948) (xy 295.921699 -380.202443)
			(xy 295.902957 -380.194671) (xy 295.888633 -380.1803) (xy 295.880924 -380.161533) (xy 295.880536 -380.151386)
			(xy 295.880536 -379.865382) (xy 295.880346 -379.858509) (xy 295.876736 -379.845246) (xy 295.873424 -379.83922)
			(xy 295.857069 -379.810865) (xy 295.831264 -379.750708) (xy 295.813771 -379.68763) (xy 295.804908 -379.622775)
			(xy 295.804336 -379.590046) (xy 294.531743 -379.590046) (xy 294.522765 -379.610974) (xy 294.506396 -379.639322)
			(xy 294.503073 -379.645343) (xy 294.499473 -379.658609) (xy 294.499284 -379.665484) (xy 294.499284 -380.414784)
			(xy 294.499484 -380.421657) (xy 294.503087 -380.434919) (xy 294.506396 -380.440946) (xy 294.52278 -380.469285)
			(xy 294.548577 -380.529448) (xy 294.566062 -380.592531) (xy 294.574917 -380.65739) (xy 294.574917 -380.657399)
			(xy 298.004838 -380.657399) (xy 298.01362 -380.592556) (xy 298.031026 -380.529478) (xy 298.056742 -380.469307)
			(xy 298.073064 -380.440946) (xy 298.076359 -380.434912) (xy 298.079978 -380.421656) (xy 298.080176 -380.414784)
			(xy 298.080176 -379.665484) (xy 298.079993 -379.65861) (xy 298.076379 -379.645347) (xy 298.073064 -379.639322)
			(xy 298.056782 -379.610939) (xy 298.031059 -379.550773) (xy 298.013645 -379.487699) (xy 298.004856 -379.422858)
			(xy 298.004851 -379.357424) (xy 298.013629 -379.292582) (xy 298.031032 -379.229505) (xy 298.056744 -379.169335)
			(xy 298.073064 -379.140974) (xy 298.076385 -379.134952) (xy 298.079987 -379.121686) (xy 298.080176 -379.114812)
			(xy 298.080176 -378.828554) (xy 298.080597 -378.818389) (xy 298.088393 -378.799611) (xy 298.102782 -378.785246)
			(xy 298.121572 -378.77748) (xy 298.131738 -378.776992) (xy 298.848018 -378.776992) (xy 298.858171 -378.777517)
			(xy 298.876932 -378.785289) (xy 298.891295 -378.799644) (xy 298.899077 -378.818401) (xy 298.89958 -378.828554)
			(xy 298.89958 -379.114812) (xy 298.89977 -379.121685) (xy 298.90338 -379.134948) (xy 298.906692 -379.140974)
			(xy 298.923054 -379.169313) (xy 298.948766 -379.22949) (xy 298.966169 -379.292573) (xy 298.974947 -379.357421)
			(xy 298.974941 -379.422861) (xy 298.966152 -379.487708) (xy 298.948739 -379.550788) (xy 298.931957 -379.590046)
			(xy 300.204124 -379.590046) (xy 300.204685 -379.557316) (xy 300.213542 -379.492458) (xy 300.231033 -379.429378)
			(xy 300.256843 -379.36922) (xy 300.273212 -379.340872) (xy 300.276538 -379.334853) (xy 300.280136 -379.321585)
			(xy 300.280324 -379.31471) (xy 300.280324 -378.56541) (xy 300.280125 -378.558537) (xy 300.276521 -378.545275)
			(xy 300.273212 -378.539248) (xy 300.256827 -378.510909) (xy 300.231029 -378.450746) (xy 300.213545 -378.387663)
			(xy 300.204691 -378.322804) (xy 300.204124 -378.290074) (xy 300.204697 -378.257345) (xy 300.21355 -378.192487)
			(xy 300.231038 -378.129406) (xy 300.256844 -378.069248) (xy 300.273212 -378.0409) (xy 300.276528 -378.034876)
			(xy 300.280132 -378.021612) (xy 300.280324 -378.014738) (xy 300.280324 -377.728734) (xy 300.280854 -377.718611)
			(xy 300.288568 -377.699894) (xy 300.302841 -377.685537) (xy 300.321512 -377.677714) (xy 300.331632 -377.677172)
			(xy 301.047912 -377.677172) (xy 301.058063 -377.677611) (xy 301.076811 -377.685405) (xy 301.091133 -377.699796)
			(xy 301.098837 -377.718581) (xy 301.09922 -377.728734) (xy 301.09922 -378.014738) (xy 301.099433 -378.02161)
			(xy 301.103027 -378.034873) (xy 301.106332 -378.0409) (xy 301.122691 -378.069253) (xy 301.148496 -378.129411)
			(xy 301.165988 -378.192489) (xy 301.174849 -378.257345) (xy 301.17542 -378.290074) (xy 304.603666 -378.290074)
			(xy 304.607657 -378.227907) (xy 304.619566 -378.16676) (xy 304.639195 -378.107639) (xy 304.666224 -378.051513)
			(xy 304.700208 -377.999304) (xy 304.74059 -377.951869) (xy 304.786706 -377.909988) (xy 304.837798 -377.874348)
			(xy 304.893029 -377.845534) (xy 304.951491 -377.82402) (xy 305.012225 -377.810158) (xy 305.074232 -377.804176)
			(xy 305.136495 -377.806172) (xy 305.197992 -377.816115) (xy 305.257713 -377.833839) (xy 305.314676 -377.859056)
			(xy 305.367947 -377.891349) (xy 305.416652 -377.930189) (xy 305.459989 -377.974939) (xy 305.497249 -378.024863)
			(xy 305.527818 -378.079142) (xy 305.551196 -378.136885) (xy 305.566997 -378.197143) (xy 305.574963 -378.258926)
			(xy 305.575462 -378.290074) (xy 305.574963 -378.321222) (xy 305.57476 -378.322797) (xy 331.005004 -378.322797)
			(xy 331.005007 -378.257358) (xy 331.013794 -378.192512) (xy 331.031206 -378.129433) (xy 331.056928 -378.069261)
			(xy 331.073252 -378.0409) (xy 331.076563 -378.034873) (xy 331.080172 -378.021611) (xy 331.080364 -378.014738)
			(xy 331.080364 -377.728734) (xy 331.080792 -377.718561) (xy 331.088571 -377.699763) (xy 331.102956 -377.685376)
			(xy 331.121753 -377.677594) (xy 331.131926 -377.677172) (xy 331.848206 -377.677172) (xy 331.858382 -377.67756)
			(xy 331.877184 -377.685353) (xy 331.891569 -377.69975) (xy 331.899348 -377.718557) (xy 331.899768 -377.728734)
			(xy 331.899768 -378.014738) (xy 331.899987 -378.021609) (xy 331.903577 -378.034872) (xy 331.90688 -378.0409)
			(xy 331.92318 -378.069274) (xy 331.948898 -378.129442) (xy 331.966308 -378.192518) (xy 331.975094 -378.25736)
			(xy 331.975097 -378.322795) (xy 331.966317 -378.387638) (xy 331.948913 -378.450716) (xy 331.9232 -378.510887)
			(xy 331.90688 -378.539248) (xy 331.903547 -378.545264) (xy 331.899953 -378.558534) (xy 331.899768 -378.56541)
			(xy 331.899768 -379.31471) (xy 331.89996 -379.321583) (xy 331.903569 -379.334846) (xy 331.90688 -379.340872)
			(xy 331.923241 -379.369212) (xy 331.948954 -379.429388) (xy 331.966357 -379.492471) (xy 331.975135 -379.55732)
			(xy 331.97513 -379.622759) (xy 331.966341 -379.687606) (xy 331.948927 -379.750686) (xy 331.923205 -379.810858)
			(xy 331.90688 -379.83922) (xy 331.903557 -379.84524) (xy 331.899957 -379.858507) (xy 331.899768 -379.865382)
			(xy 331.899768 -380.151386) (xy 331.899325 -380.161556) (xy 331.891546 -380.180349) (xy 331.877166 -380.194734)
			(xy 331.858376 -380.202521) (xy 331.848206 -380.202948) (xy 331.131926 -380.202948) (xy 331.121754 -380.202514)
			(xy 331.102958 -380.194735) (xy 331.088571 -380.180352) (xy 331.080788 -380.161558) (xy 331.080364 -380.151386)
			(xy 331.080364 -379.865382) (xy 331.080183 -379.858508) (xy 331.076568 -379.845245) (xy 331.073252 -379.83922)
			(xy 331.056968 -379.810837) (xy 331.031246 -379.750671) (xy 331.013834 -379.687597) (xy 331.005045 -379.622756)
			(xy 331.00504 -379.557323) (xy 331.013818 -379.49248) (xy 331.03122 -379.429403) (xy 331.056932 -379.369233)
			(xy 331.073252 -379.340872) (xy 331.076573 -379.33485) (xy 331.080175 -379.321584) (xy 331.080364 -379.31471)
			(xy 331.080364 -378.56541) (xy 331.080173 -378.558537) (xy 331.076564 -378.545274) (xy 331.073252 -378.539248)
			(xy 331.056907 -378.510899) (xy 331.031191 -378.450725) (xy 331.013785 -378.387644) (xy 331.005004 -378.322797)
			(xy 305.57476 -378.322797) (xy 305.566997 -378.383005) (xy 305.551196 -378.443263) (xy 305.527818 -378.501006)
			(xy 305.497249 -378.555285) (xy 305.459989 -378.605209) (xy 305.416652 -378.649959) (xy 305.367947 -378.688799)
			(xy 305.314676 -378.721092) (xy 305.257713 -378.746309) (xy 305.197992 -378.764033) (xy 305.136495 -378.773976)
			(xy 305.074232 -378.775972) (xy 305.012225 -378.76999) (xy 304.951491 -378.756128) (xy 304.893029 -378.734614)
			(xy 304.837798 -378.7058) (xy 304.786706 -378.67016) (xy 304.74059 -378.628279) (xy 304.700208 -378.580844)
			(xy 304.666224 -378.528635) (xy 304.639195 -378.472509) (xy 304.619566 -378.413388) (xy 304.607657 -378.352241)
			(xy 304.603666 -378.290074) (xy 301.17542 -378.290074) (xy 301.174863 -378.322804) (xy 301.166004 -378.387662)
			(xy 301.148511 -378.450742) (xy 301.122702 -378.5109) (xy 301.106332 -378.539248) (xy 301.103003 -378.545266)
			(xy 301.099406 -378.558535) (xy 301.09922 -378.56541) (xy 301.09922 -379.31471) (xy 301.099406 -379.321584)
			(xy 301.103018 -379.334847) (xy 301.106332 -379.340872) (xy 301.12268 -379.369231) (xy 301.148488 -379.429387)
			(xy 301.165982 -379.492463) (xy 301.174848 -379.557318) (xy 301.17542 -379.590046) (xy 301.17485 -379.622775)
			(xy 301.165995 -379.687633) (xy 301.148506 -379.750713) (xy 301.1227 -379.810872) (xy 301.106332 -379.83922)
			(xy 301.103013 -379.845243) (xy 301.09941 -379.858508) (xy 301.09922 -379.865382) (xy 301.09922 -380.151386)
			(xy 301.098761 -380.161517) (xy 301.09103 -380.180245) (xy 301.076735 -380.194603) (xy 301.058041 -380.202416)
			(xy 301.047912 -380.202948) (xy 300.331632 -380.202948) (xy 300.321486 -380.202453) (xy 300.302743 -380.194677)
			(xy 300.28842 -380.180304) (xy 300.280711 -380.161534) (xy 300.280324 -380.151386) (xy 300.280324 -379.865382)
			(xy 300.280136 -379.858509) (xy 300.276525 -379.845246) (xy 300.273212 -379.83922) (xy 300.256856 -379.810866)
			(xy 300.231051 -379.750708) (xy 300.213559 -379.68763) (xy 300.204696 -379.622775) (xy 300.204124 -379.590046)
			(xy 298.931957 -379.590046) (xy 298.923016 -379.61096) (xy 298.906692 -379.639322) (xy 298.903369 -379.645342)
			(xy 298.899769 -379.658609) (xy 298.89958 -379.665484) (xy 298.89958 -380.414784) (xy 298.89978 -380.421657)
			(xy 298.903383 -380.434919) (xy 298.906692 -380.440946) (xy 298.92303 -380.469298) (xy 298.948745 -380.529472)
			(xy 298.96615 -380.592552) (xy 298.974931 -380.657398) (xy 298.974929 -380.69012) (xy 302.404272 -380.69012)
			(xy 302.404828 -380.65739) (xy 302.413687 -380.592532) (xy 302.43118 -380.529452) (xy 302.45699 -380.469294)
			(xy 302.47336 -380.440946) (xy 302.476655 -380.434912) (xy 302.480274 -380.421655) (xy 302.480472 -380.414784)
			(xy 302.480472 -379.665484) (xy 302.480289 -379.65861) (xy 302.476675 -379.645347) (xy 302.47336 -379.639322)
			(xy 302.457009 -379.610965) (xy 302.431202 -379.550809) (xy 302.413708 -379.487731) (xy 302.404844 -379.422876)
			(xy 302.404272 -379.390148) (xy 302.40484 -379.357419) (xy 302.413696 -379.292561) (xy 302.431185 -379.22948)
			(xy 302.456992 -379.169322) (xy 302.47336 -379.140974) (xy 302.476681 -379.134952) (xy 302.480283 -379.121686)
			(xy 302.480472 -379.114812) (xy 302.480472 -378.828554) (xy 302.48089 -378.81842) (xy 302.488639 -378.799692)
			(xy 302.502946 -378.785336) (xy 302.521648 -378.777525) (xy 302.53178 -378.776992) (xy 303.24806 -378.776992)
			(xy 303.258211 -378.777454) (xy 303.27696 -378.785235) (xy 303.291285 -378.79962) (xy 303.298987 -378.818402)
			(xy 303.299368 -378.828554) (xy 303.299368 -379.114812) (xy 303.299559 -379.121685) (xy 303.303168 -379.134948)
			(xy 303.30648 -379.140974) (xy 303.322833 -379.16933) (xy 303.348639 -379.229487) (xy 303.366132 -379.292564)
			(xy 303.374996 -379.35742) (xy 303.375568 -379.390148) (xy 303.374992 -379.422877) (xy 303.366138 -379.487735)
			(xy 303.34865 -379.550815) (xy 303.331823 -379.590046) (xy 304.603666 -379.590046) (xy 304.607657 -379.527879)
			(xy 304.619566 -379.466732) (xy 304.639195 -379.407611) (xy 304.666224 -379.351485) (xy 304.700208 -379.299276)
			(xy 304.74059 -379.251841) (xy 304.786706 -379.20996) (xy 304.837798 -379.17432) (xy 304.893029 -379.145506)
			(xy 304.951491 -379.123992) (xy 305.012225 -379.11013) (xy 305.074232 -379.104148) (xy 305.136495 -379.106144)
			(xy 305.197992 -379.116087) (xy 305.257713 -379.133811) (xy 305.314676 -379.159028) (xy 305.367947 -379.191321)
			(xy 305.416652 -379.230161) (xy 305.459989 -379.274911) (xy 305.497249 -379.324835) (xy 305.527818 -379.379114)
			(xy 305.532285 -379.390148) (xy 306.803814 -379.390148) (xy 306.807805 -379.327981) (xy 306.819714 -379.266834)
			(xy 306.839343 -379.207713) (xy 306.866372 -379.151587) (xy 306.900356 -379.099378) (xy 306.940738 -379.051943)
			(xy 306.986854 -379.010062) (xy 307.037946 -378.974422) (xy 307.093177 -378.945608) (xy 307.151639 -378.924094)
			(xy 307.212373 -378.910232) (xy 307.27438 -378.90425) (xy 307.336643 -378.906246) (xy 307.39814 -378.916189)
			(xy 307.457861 -378.933913) (xy 307.514824 -378.95913) (xy 307.568095 -378.991423) (xy 307.6168 -379.030263)
			(xy 307.660137 -379.075013) (xy 307.697397 -379.124937) (xy 307.727966 -379.179216) (xy 307.751344 -379.236959)
			(xy 307.767145 -379.297217) (xy 307.775111 -379.359) (xy 307.77561 -379.390148) (xy 307.775111 -379.421296)
			(xy 307.767145 -379.483079) (xy 307.751344 -379.543337) (xy 307.727966 -379.60108) (xy 307.697397 -379.655359)
			(xy 307.660137 -379.705283) (xy 307.6168 -379.750033) (xy 307.568095 -379.788873) (xy 307.514824 -379.821166)
			(xy 307.457861 -379.846383) (xy 307.39814 -379.864107) (xy 307.336643 -379.87405) (xy 307.27438 -379.876046)
			(xy 307.212373 -379.870064) (xy 307.151639 -379.856202) (xy 307.093177 -379.834688) (xy 307.037946 -379.805874)
			(xy 306.986854 -379.770234) (xy 306.940738 -379.728353) (xy 306.900356 -379.680918) (xy 306.866372 -379.628709)
			(xy 306.839343 -379.572583) (xy 306.819714 -379.513462) (xy 306.807805 -379.452315) (xy 306.803814 -379.390148)
			(xy 305.532285 -379.390148) (xy 305.551196 -379.436857) (xy 305.566997 -379.497115) (xy 305.574963 -379.558898)
			(xy 305.575462 -379.590046) (xy 305.574963 -379.621194) (xy 305.566997 -379.682977) (xy 305.551196 -379.743235)
			(xy 305.527818 -379.800978) (xy 305.497249 -379.855257) (xy 305.459989 -379.905181) (xy 305.416652 -379.949931)
			(xy 305.367947 -379.988771) (xy 305.314676 -380.021064) (xy 305.257713 -380.046281) (xy 305.197992 -380.064005)
			(xy 305.136495 -380.073948) (xy 305.074232 -380.075944) (xy 305.012225 -380.069962) (xy 304.951491 -380.0561)
			(xy 304.893029 -380.034586) (xy 304.837798 -380.005772) (xy 304.786706 -379.970132) (xy 304.74059 -379.928251)
			(xy 304.700208 -379.880816) (xy 304.666224 -379.828607) (xy 304.639195 -379.772481) (xy 304.619566 -379.71336)
			(xy 304.607657 -379.652213) (xy 304.603666 -379.590046) (xy 303.331823 -379.590046) (xy 303.322847 -379.610973)
			(xy 303.30648 -379.639322) (xy 303.303156 -379.645342) (xy 303.299557 -379.658609) (xy 303.299368 -379.665484)
			(xy 303.299368 -380.414784) (xy 303.29957 -380.421656) (xy 303.303172 -380.434919) (xy 303.30648 -380.440946)
			(xy 303.322862 -380.469286) (xy 303.34866 -380.529449) (xy 303.366145 -380.592531) (xy 303.375001 -380.65739)
			(xy 303.375568 -380.69012) (xy 306.803814 -380.69012) (xy 306.807805 -380.627953) (xy 306.819714 -380.566806)
			(xy 306.839343 -380.507685) (xy 306.866372 -380.451559) (xy 306.900356 -380.39935) (xy 306.940738 -380.351915)
			(xy 306.986854 -380.310034) (xy 307.037946 -380.274394) (xy 307.093177 -380.24558) (xy 307.151639 -380.224066)
			(xy 307.212373 -380.210204) (xy 307.27438 -380.204222) (xy 307.336643 -380.206218) (xy 307.39814 -380.216161)
			(xy 307.457861 -380.233885) (xy 307.514824 -380.259102) (xy 307.568095 -380.291395) (xy 307.6168 -380.330235)
			(xy 307.660137 -380.374985) (xy 307.697397 -380.424909) (xy 307.727966 -380.479188) (xy 307.751344 -380.536931)
			(xy 307.767145 -380.597189) (xy 307.775111 -380.658972) (xy 307.77561 -380.69012) (xy 333.204312 -380.69012)
			(xy 333.204863 -380.65739) (xy 333.213723 -380.592531) (xy 333.231217 -380.529451) (xy 333.257029 -380.469294)
			(xy 333.2734 -380.440946) (xy 333.276698 -380.434913) (xy 333.280314 -380.421656) (xy 333.280512 -380.414784)
			(xy 333.280512 -379.665484) (xy 333.280325 -379.65861) (xy 333.276713 -379.645348) (xy 333.2734 -379.639322)
			(xy 333.257043 -379.610968) (xy 333.231239 -379.55081) (xy 333.213747 -379.487732) (xy 333.204884 -379.422877)
			(xy 333.204312 -379.390148) (xy 333.204875 -379.357418) (xy 333.213732 -379.29256) (xy 333.231223 -379.22948)
			(xy 333.257031 -379.169322) (xy 333.2734 -379.140974) (xy 333.276724 -379.134954) (xy 333.280324 -379.121687)
			(xy 333.280512 -379.114812) (xy 333.280512 -378.828554) (xy 333.280988 -378.818428) (xy 333.288726 -378.799711)
			(xy 333.303015 -378.785357) (xy 333.321696 -378.777535) (xy 333.33182 -378.776992) (xy 334.0481 -378.776992)
			(xy 334.058253 -378.777422) (xy 334.077004 -378.785216) (xy 334.091327 -378.79961) (xy 334.099028 -378.818399)
			(xy 334.099408 -378.828554) (xy 334.099408 -379.114812) (xy 334.099594 -379.121686) (xy 334.103206 -379.134949)
			(xy 334.10652 -379.140974) (xy 334.122877 -379.169328) (xy 334.148681 -379.229486) (xy 334.166172 -379.292564)
			(xy 334.175036 -379.357419) (xy 334.175608 -379.390148) (xy 334.17504 -379.422877) (xy 334.166185 -379.487736)
			(xy 334.148695 -379.550816) (xy 334.131866 -379.590046) (xy 335.40446 -379.590046) (xy 335.405029 -379.557317)
			(xy 335.413885 -379.492459) (xy 335.431374 -379.429379) (xy 335.45718 -379.36922) (xy 335.473548 -379.340872)
			(xy 335.476869 -379.33485) (xy 335.480471 -379.321584) (xy 335.48066 -379.31471) (xy 335.48066 -378.56541)
			(xy 335.480469 -378.558537) (xy 335.476861 -378.545274) (xy 335.473548 -378.539248) (xy 335.457166 -378.510908)
			(xy 335.431367 -378.450745) (xy 335.413882 -378.387663) (xy 335.405027 -378.322804) (xy 335.40446 -378.290074)
			(xy 335.405042 -378.257345) (xy 335.413894 -378.192488) (xy 335.431379 -378.129407) (xy 335.457182 -378.069249)
			(xy 335.473548 -378.0409) (xy 335.476859 -378.034873) (xy 335.480467 -378.021611) (xy 335.48066 -378.014738)
			(xy 335.48066 -377.728734) (xy 335.481155 -377.718607) (xy 335.488875 -377.699883) (xy 335.50316 -377.685525)
			(xy 335.521844 -377.677708) (xy 335.531968 -377.677172) (xy 336.248248 -377.677172) (xy 336.258402 -377.677582)
			(xy 336.27715 -377.685388) (xy 336.29147 -377.699787) (xy 336.299173 -377.718578) (xy 336.299556 -377.728734)
			(xy 336.299556 -378.014738) (xy 336.299764 -378.02161) (xy 336.303361 -378.034873) (xy 336.306668 -378.0409)
			(xy 336.323031 -378.069251) (xy 336.348834 -378.12941) (xy 336.366324 -378.192489) (xy 336.375185 -378.257345)
			(xy 336.375756 -378.290074) (xy 336.375193 -378.322797) (xy 339.80509 -378.322797) (xy 339.805093 -378.257358)
			(xy 339.81388 -378.192513) (xy 339.831291 -378.129433) (xy 339.857012 -378.069261) (xy 339.873336 -378.0409)
			(xy 339.876646 -378.034873) (xy 339.880255 -378.021611) (xy 339.880448 -378.014738) (xy 339.880448 -377.728734)
			(xy 339.880892 -377.718563) (xy 339.888668 -377.699768) (xy 339.903047 -377.685381) (xy 339.92184 -377.677597)
			(xy 339.93201 -377.677172) (xy 340.64829 -377.677172) (xy 340.658465 -377.677573) (xy 340.677266 -377.685361)
			(xy 340.691653 -377.699754) (xy 340.699432 -377.718559) (xy 340.699852 -377.728734) (xy 340.699852 -378.014738)
			(xy 340.700061 -378.02161) (xy 340.703657 -378.034873) (xy 340.706964 -378.0409) (xy 340.723264 -378.069273)
			(xy 340.748984 -378.129442) (xy 340.766394 -378.192518) (xy 340.77518 -378.25736) (xy 340.775183 -378.322795)
			(xy 340.775183 -378.322797) (xy 344.20488 -378.322797) (xy 344.204883 -378.257359) (xy 344.213669 -378.192513)
			(xy 344.23108 -378.129433) (xy 344.2568 -378.069261) (xy 344.273124 -378.0409) (xy 344.27644 -378.034876)
			(xy 344.280045 -378.021612) (xy 344.280236 -378.014738) (xy 344.280236 -377.728734) (xy 344.280692 -377.718565)
			(xy 344.288465 -377.699771) (xy 344.302841 -377.685385) (xy 344.321629 -377.677599) (xy 344.331798 -377.677172)
			(xy 345.048078 -377.677172) (xy 345.058252 -377.677583) (xy 345.077053 -377.685367) (xy 345.09144 -377.699757)
			(xy 345.099219 -377.71856) (xy 345.09964 -377.728734) (xy 345.09964 -378.014738) (xy 345.099851 -378.02161)
			(xy 345.103446 -378.034873) (xy 345.106752 -378.0409) (xy 345.123052 -378.069273) (xy 345.148773 -378.129442)
			(xy 345.166183 -378.192518) (xy 345.17497 -378.25736) (xy 345.174973 -378.322795) (xy 345.166192 -378.387638)
			(xy 345.148787 -378.450716) (xy 345.123073 -378.510887) (xy 345.106752 -378.539248) (xy 345.103424 -378.545266)
			(xy 345.099826 -378.558535) (xy 345.09964 -378.56541) (xy 345.09964 -379.31471) (xy 345.099823 -379.321584)
			(xy 345.103437 -379.334847) (xy 345.106752 -379.340872) (xy 345.123113 -379.369212) (xy 345.148828 -379.429388)
			(xy 345.166232 -379.492471) (xy 345.175011 -379.557319) (xy 345.175006 -379.622759) (xy 345.166216 -379.687607)
			(xy 345.148802 -379.750687) (xy 345.123078 -379.810859) (xy 345.106752 -379.83922) (xy 345.103434 -379.845243)
			(xy 345.09983 -379.858508) (xy 345.09964 -379.865382) (xy 345.09964 -380.151386) (xy 345.099224 -380.161559)
			(xy 345.09144 -380.180358) (xy 345.077051 -380.194744) (xy 345.058252 -380.202526) (xy 345.048078 -380.202948)
			(xy 344.331798 -380.202948) (xy 344.321625 -380.202537) (xy 344.302827 -380.194749) (xy 344.288442 -380.180359)
			(xy 344.280659 -380.16156) (xy 344.280236 -380.151386) (xy 344.280236 -379.865382) (xy 344.280046 -379.858509)
			(xy 344.276436 -379.845246) (xy 344.273124 -379.83922) (xy 344.256841 -379.810837) (xy 344.231121 -379.750671)
			(xy 344.213709 -379.687597) (xy 344.204921 -379.622756) (xy 344.204915 -379.557323) (xy 344.213693 -379.492481)
			(xy 344.231095 -379.429404) (xy 344.256805 -379.369233) (xy 344.273124 -379.340872) (xy 344.27645 -379.334853)
			(xy 344.280048 -379.321585) (xy 344.280236 -379.31471) (xy 344.280236 -378.56541) (xy 344.280036 -378.558537)
			(xy 344.276433 -378.545275) (xy 344.273124 -378.539248) (xy 344.25678 -378.510899) (xy 344.231065 -378.450725)
			(xy 344.21366 -378.387643) (xy 344.20488 -378.322797) (xy 340.775183 -378.322797) (xy 340.766403 -378.387638)
			(xy 340.748998 -378.450716) (xy 340.723284 -378.510887) (xy 340.706964 -378.539248) (xy 340.703637 -378.545267)
			(xy 340.700038 -378.558535) (xy 340.699852 -378.56541) (xy 340.699852 -379.31471) (xy 340.700034 -379.321584)
			(xy 340.703648 -379.334847) (xy 340.706964 -379.340872) (xy 340.723325 -379.369212) (xy 340.749039 -379.429388)
			(xy 340.766443 -379.492471) (xy 340.775221 -379.55732) (xy 340.775216 -379.622759) (xy 340.766427 -379.687606)
			(xy 340.749013 -379.750687) (xy 340.723289 -379.810859) (xy 340.706964 -379.83922) (xy 340.703647 -379.845244)
			(xy 340.700042 -379.858508) (xy 340.699852 -379.865382) (xy 340.699852 -380.151386) (xy 340.699425 -380.161558)
			(xy 340.691642 -380.180354) (xy 340.677258 -380.19474) (xy 340.658462 -380.202524) (xy 340.64829 -380.202948)
			(xy 339.93201 -380.202948) (xy 339.921837 -380.202528) (xy 339.90304 -380.194743) (xy 339.888654 -380.180357)
			(xy 339.880871 -380.161559) (xy 339.880448 -380.151386) (xy 339.880448 -379.865382) (xy 339.880269 -379.858508)
			(xy 339.876653 -379.845245) (xy 339.873336 -379.83922) (xy 339.857053 -379.810837) (xy 339.831332 -379.750671)
			(xy 339.813919 -379.687597) (xy 339.805131 -379.622756) (xy 339.805126 -379.557323) (xy 339.813904 -379.492481)
			(xy 339.831306 -379.429404) (xy 339.857017 -379.369233) (xy 339.873336 -379.340872) (xy 339.876656 -379.33485)
			(xy 339.880259 -379.321584) (xy 339.880448 -379.31471) (xy 339.880448 -378.56541) (xy 339.880259 -378.558536)
			(xy 339.876649 -378.545273) (xy 339.873336 -378.539248) (xy 339.856992 -378.510899) (xy 339.831276 -378.450725)
			(xy 339.813871 -378.387644) (xy 339.80509 -378.322797) (xy 336.375193 -378.322797) (xy 336.375193 -378.322804)
			(xy 336.366336 -378.387662) (xy 336.348844 -378.450742) (xy 336.323037 -378.5109) (xy 336.306668 -378.539248)
			(xy 336.303334 -378.545263) (xy 336.299741 -378.558534) (xy 336.299556 -378.56541) (xy 336.299556 -379.31471)
			(xy 336.299737 -379.321584) (xy 336.303352 -379.334847) (xy 336.306668 -379.340872) (xy 336.323019 -379.369229)
			(xy 336.348825 -379.429386) (xy 336.366319 -379.492463) (xy 336.375184 -379.557318) (xy 336.375756 -379.590046)
			(xy 336.375181 -379.622775) (xy 336.366327 -379.687633) (xy 336.348839 -379.750713) (xy 336.323035 -379.810871)
			(xy 336.306668 -379.83922) (xy 336.303344 -379.84524) (xy 336.299745 -379.858507) (xy 336.299556 -379.865382)
			(xy 336.299556 -380.151386) (xy 336.299062 -380.161512) (xy 336.291338 -380.180234) (xy 336.277054 -380.194591)
			(xy 336.258372 -380.20241) (xy 336.248248 -380.202948) (xy 335.531968 -380.202948) (xy 335.521818 -380.202506)
			(xy 335.503074 -380.194708) (xy 335.488753 -380.180319) (xy 335.481046 -380.161538) (xy 335.48066 -380.151386)
			(xy 335.48066 -379.865382) (xy 335.48048 -379.858508) (xy 335.476864 -379.845245) (xy 335.473548 -379.83922)
			(xy 335.457195 -379.810864) (xy 335.431389 -379.750707) (xy 335.413896 -379.68763) (xy 335.405032 -379.622774)
			(xy 335.40446 -379.590046) (xy 334.131866 -379.590046) (xy 334.122888 -379.610974) (xy 334.10652 -379.639322)
			(xy 334.103199 -379.645344) (xy 334.099597 -379.65861) (xy 334.099408 -379.665484) (xy 334.099408 -380.414784)
			(xy 334.099605 -380.421657) (xy 334.10321 -380.43492) (xy 334.10652 -380.440946) (xy 334.122906 -380.469284)
			(xy 334.148702 -380.529448) (xy 334.166186 -380.592531) (xy 334.175041 -380.65739) (xy 334.175041 -380.6574)
			(xy 337.604973 -380.6574) (xy 337.613753 -380.592557) (xy 337.631156 -380.529479) (xy 337.656869 -380.469308)
			(xy 337.673188 -380.440946) (xy 337.676486 -380.434913) (xy 337.680102 -380.421656) (xy 337.6803 -380.414784)
			(xy 337.6803 -379.665484) (xy 337.680114 -379.65861) (xy 337.676502 -379.645347) (xy 337.673188 -379.639322)
			(xy 337.656908 -379.610938) (xy 337.631189 -379.550771) (xy 337.613779 -379.487698) (xy 337.604991 -379.422858)
			(xy 337.604985 -379.357425) (xy 337.613762 -379.292583) (xy 337.631162 -379.229506) (xy 337.656871 -379.169336)
			(xy 337.673188 -379.140974) (xy 337.676511 -379.134953) (xy 337.680112 -379.121687) (xy 337.6803 -379.114812)
			(xy 337.6803 -378.828554) (xy 337.680795 -378.818398) (xy 337.688577 -378.799635) (xy 337.702942 -378.785273)
			(xy 337.721706 -378.777493) (xy 337.731862 -378.776992) (xy 338.448142 -378.776992) (xy 338.458297 -378.777498)
			(xy 338.477058 -378.785278) (xy 338.49142 -378.799639) (xy 338.499201 -378.818399) (xy 338.499704 -378.828554)
			(xy 338.499704 -379.114812) (xy 338.499891 -379.121686) (xy 338.503502 -379.134948) (xy 338.506816 -379.140974)
			(xy 338.52318 -379.169312) (xy 338.548896 -379.229488) (xy 338.566302 -379.292572) (xy 338.575081 -379.357421)
			(xy 338.575076 -379.422861) (xy 338.566285 -379.487709) (xy 338.548869 -379.55079) (xy 338.523143 -379.610961)
			(xy 338.506816 -379.639322) (xy 338.503495 -379.645343) (xy 338.499893 -379.65861) (xy 338.499704 -379.665484)
			(xy 338.499704 -380.414784) (xy 338.499902 -380.421657) (xy 338.503506 -380.43492) (xy 338.506816 -380.440946)
			(xy 338.523157 -380.469297) (xy 338.548875 -380.52947) (xy 338.566283 -380.592551) (xy 338.575065 -380.657398)
			(xy 338.575064 -380.69012) (xy 342.004396 -380.69012) (xy 342.004949 -380.65739) (xy 342.013808 -380.592531)
			(xy 342.031302 -380.529451) (xy 342.057113 -380.469293) (xy 342.073484 -380.440946) (xy 342.076781 -380.434913)
			(xy 342.080398 -380.421656) (xy 342.080596 -380.414784) (xy 342.080596 -379.665484) (xy 342.080411 -379.65861)
			(xy 342.076798 -379.645347) (xy 342.073484 -379.639322) (xy 342.057126 -379.610969) (xy 342.031322 -379.550811)
			(xy 342.013831 -379.487732) (xy 342.004968 -379.422877) (xy 342.004396 -379.390148) (xy 342.004962 -379.357418)
			(xy 342.013818 -379.29256) (xy 342.031308 -379.22948) (xy 342.057116 -379.169322) (xy 342.073484 -379.140974)
			(xy 342.076807 -379.134953) (xy 342.080408 -379.121687) (xy 342.080596 -379.114812) (xy 342.080596 -378.828554)
			(xy 342.081088 -378.81843) (xy 342.088822 -378.799716) (xy 342.103106 -378.785363) (xy 342.121782 -378.777538)
			(xy 342.131904 -378.776992) (xy 342.848184 -378.776992) (xy 342.858336 -378.777434) (xy 342.877087 -378.785223)
			(xy 342.89141 -378.799614) (xy 342.899112 -378.8184) (xy 342.899492 -378.828554) (xy 342.899492 -379.114812)
			(xy 342.89968 -379.121685) (xy 342.903291 -379.134948) (xy 342.906604 -379.140974) (xy 342.92296 -379.169329)
			(xy 342.948764 -379.229486) (xy 342.966256 -379.292564) (xy 342.97512 -379.357419) (xy 342.975692 -379.390148)
			(xy 342.975126 -379.422878) (xy 342.966271 -379.487736) (xy 342.94878 -379.550816) (xy 342.922973 -379.610974)
			(xy 342.906604 -379.639322) (xy 342.903282 -379.645343) (xy 342.899681 -379.65861) (xy 342.899492 -379.665484)
			(xy 342.899492 -380.414784) (xy 342.899691 -380.421657) (xy 342.903294 -380.43492) (xy 342.906604 -380.440946)
			(xy 342.922988 -380.469285) (xy 342.948786 -380.529448) (xy 342.96627 -380.592531) (xy 342.975125 -380.65739)
			(xy 342.975125 -380.657399) (xy 346.405045 -380.657399) (xy 346.413827 -380.592555) (xy 346.431233 -380.529477)
			(xy 346.45695 -380.469307) (xy 346.473272 -380.440946) (xy 346.476568 -380.434912) (xy 346.480186 -380.421656)
			(xy 346.480384 -380.414784) (xy 346.480384 -379.665484) (xy 346.4802 -379.65861) (xy 346.476587 -379.645347)
			(xy 346.473272 -379.639322) (xy 346.456989 -379.610939) (xy 346.431266 -379.550773) (xy 346.413852 -379.487699)
			(xy 346.405063 -379.422858) (xy 346.405058 -379.357424) (xy 346.413836 -379.292582) (xy 346.431239 -379.229505)
			(xy 346.456952 -379.169335) (xy 346.473272 -379.140974) (xy 346.476594 -379.134953) (xy 346.480196 -379.121686)
			(xy 346.480384 -379.114812) (xy 346.480384 -378.828554) (xy 346.480797 -378.818388) (xy 346.488595 -378.799609)
			(xy 346.502986 -378.785243) (xy 346.521779 -378.777479) (xy 346.531946 -378.776992) (xy 347.248226 -378.776992)
			(xy 347.25838 -378.777511) (xy 347.277141 -378.785285) (xy 347.291504 -378.799642) (xy 347.299285 -378.8184)
			(xy 347.299788 -378.828554) (xy 347.299788 -379.114812) (xy 347.299977 -379.121685) (xy 347.303587 -379.134948)
			(xy 347.3069 -379.140974) (xy 347.323262 -379.169313) (xy 347.348973 -379.22949) (xy 347.366376 -379.292573)
			(xy 347.375153 -379.357421) (xy 347.375148 -379.422861) (xy 347.366359 -379.487708) (xy 347.348946 -379.550788)
			(xy 347.323224 -379.61096) (xy 347.3069 -379.639322) (xy 347.303577 -379.645343) (xy 347.299977 -379.65861)
			(xy 347.299788 -379.665484) (xy 347.299788 -380.414784) (xy 347.299987 -380.421657) (xy 347.303591 -380.434919)
			(xy 347.3069 -380.440946) (xy 347.323238 -380.469298) (xy 347.348952 -380.529472) (xy 347.366357 -380.592553)
			(xy 347.375137 -380.657398) (xy 347.375135 -380.722836) (xy 347.36635 -380.787681) (xy 347.348941 -380.85076)
			(xy 347.323222 -380.910932) (xy 347.3069 -380.939294) (xy 347.303587 -380.94532) (xy 347.29998 -380.958583)
			(xy 347.299788 -380.965456) (xy 347.299788 -381.251206) (xy 347.299272 -381.261361) (xy 347.2915 -381.280125)
			(xy 347.277142 -381.294489) (xy 347.258381 -381.302268) (xy 347.248226 -381.302768) (xy 346.531946 -381.302768)
			(xy 346.521778 -381.302299) (xy 346.502986 -381.29453) (xy 346.488599 -381.280158) (xy 346.480812 -381.261373)
			(xy 346.480384 -381.251206) (xy 346.480384 -380.965456) (xy 346.480173 -380.958584) (xy 346.476578 -380.945321)
			(xy 346.473272 -380.939294) (xy 346.456966 -380.910924) (xy 346.431245 -380.850755) (xy 346.413834 -380.787678)
			(xy 346.405047 -380.722835) (xy 346.405045 -380.657399) (xy 342.975125 -380.657399) (xy 342.975692 -380.69012)
			(xy 342.975114 -380.722849) (xy 342.966262 -380.787707) (xy 342.948775 -380.850787) (xy 342.922971 -380.910946)
			(xy 342.906604 -380.939294) (xy 342.903292 -380.94532) (xy 342.899684 -380.958583) (xy 342.899492 -380.965456)
			(xy 342.899492 -381.251206) (xy 342.898979 -381.261329) (xy 342.891255 -381.280044) (xy 342.876978 -381.294399)
			(xy 342.858304 -381.302224) (xy 342.848184 -381.302768) (xy 342.131904 -381.302768) (xy 342.121746 -381.302374)
			(xy 342.102988 -381.294574) (xy 342.088663 -381.280168) (xy 342.080969 -381.261366) (xy 342.080596 -381.251206)
			(xy 342.080596 -380.965456) (xy 342.080383 -380.958584) (xy 342.076789 -380.945322) (xy 342.073484 -380.939294)
			(xy 342.057115 -380.910947) (xy 342.031314 -380.850787) (xy 342.013826 -380.787706) (xy 342.004966 -380.722849)
			(xy 342.004396 -380.69012) (xy 338.575064 -380.69012) (xy 338.575063 -380.722836) (xy 338.566276 -380.787683)
			(xy 338.548864 -380.850762) (xy 338.523141 -380.910933) (xy 338.506816 -380.939294) (xy 338.503505 -380.94532)
			(xy 338.499897 -380.958583) (xy 338.499704 -380.965456) (xy 338.499704 -381.251206) (xy 338.499172 -381.261359)
			(xy 338.491404 -381.28012) (xy 338.47705 -381.294484) (xy 338.458295 -381.302265) (xy 338.448142 -381.302768)
			(xy 337.731862 -381.302768) (xy 337.721703 -381.302298) (xy 337.702934 -381.294512) (xy 337.68857 -381.280139)
			(xy 337.680796 -381.261366) (xy 337.6803 -381.251206) (xy 337.6803 -380.965456) (xy 337.680086 -380.958584)
			(xy 337.676493 -380.945322) (xy 337.673188 -380.939294) (xy 337.656884 -380.910923) (xy 337.631168 -380.850753)
			(xy 337.61376 -380.787677) (xy 337.604975 -380.722834) (xy 337.604973 -380.6574) (xy 334.175041 -380.6574)
			(xy 334.175608 -380.69012) (xy 334.175028 -380.722849) (xy 334.166176 -380.787707) (xy 334.14869 -380.850787)
			(xy 334.122886 -380.910945) (xy 334.10652 -380.939294) (xy 334.103209 -380.94532) (xy 334.099601 -380.958583)
			(xy 334.099408 -380.965456) (xy 334.099408 -381.251206) (xy 334.09888 -381.261327) (xy 334.091159 -381.280039)
			(xy 334.076886 -381.294394) (xy 334.058218 -381.302221) (xy 334.0481 -381.302768) (xy 333.33182 -381.302768)
			(xy 333.321663 -381.302362) (xy 333.302905 -381.294567) (xy 333.28858 -381.280165) (xy 333.280885 -381.261365)
			(xy 333.280512 -381.251206) (xy 333.280512 -380.965456) (xy 333.280297 -380.958584) (xy 333.276704 -380.945322)
			(xy 333.2734 -380.939294) (xy 333.257032 -380.910946) (xy 333.231231 -380.850786) (xy 333.213742 -380.787706)
			(xy 333.204882 -380.722849) (xy 333.204312 -380.69012) (xy 307.77561 -380.69012) (xy 307.775111 -380.721268)
			(xy 307.767145 -380.783051) (xy 307.751344 -380.843309) (xy 307.727966 -380.901052) (xy 307.697397 -380.955331)
			(xy 307.660137 -381.005255) (xy 307.6168 -381.050005) (xy 307.568095 -381.088845) (xy 307.514824 -381.121138)
			(xy 307.457861 -381.146355) (xy 307.39814 -381.164079) (xy 307.336643 -381.174022) (xy 307.27438 -381.176018)
			(xy 307.212373 -381.170036) (xy 307.151639 -381.156174) (xy 307.093177 -381.13466) (xy 307.037946 -381.105846)
			(xy 306.986854 -381.070206) (xy 306.940738 -381.028325) (xy 306.900356 -380.98089) (xy 306.866372 -380.928681)
			(xy 306.839343 -380.872555) (xy 306.819714 -380.813434) (xy 306.807805 -380.752287) (xy 306.803814 -380.69012)
			(xy 303.375568 -380.69012) (xy 303.37498 -380.722849) (xy 303.366129 -380.787706) (xy 303.348645 -380.850786)
			(xy 303.322845 -380.910945) (xy 303.30648 -380.939294) (xy 303.303166 -380.945319) (xy 303.29956 -380.958582)
			(xy 303.299368 -380.965456) (xy 303.299368 -381.251206) (xy 303.298878 -381.261332) (xy 303.29115 -381.280052)
			(xy 303.276865 -381.294408) (xy 303.258184 -381.302228) (xy 303.24806 -381.302768) (xy 302.53178 -381.302768)
			(xy 302.521621 -381.302394) (xy 302.502861 -381.294586) (xy 302.488538 -381.280174) (xy 302.480844 -381.261368)
			(xy 302.480472 -381.251206) (xy 302.480472 -380.965456) (xy 302.480262 -380.958584) (xy 302.476666 -380.945321)
			(xy 302.47336 -380.939294) (xy 302.456998 -380.910943) (xy 302.431194 -380.850784) (xy 302.413703 -380.787705)
			(xy 302.404842 -380.722849) (xy 302.404272 -380.69012) (xy 298.974929 -380.69012) (xy 298.974928 -380.722836)
			(xy 298.966143 -380.787681) (xy 298.948733 -380.850761) (xy 298.923015 -380.910932) (xy 298.906692 -380.939294)
			(xy 298.903379 -380.945319) (xy 298.899772 -380.958583) (xy 298.89958 -380.965456) (xy 298.89958 -381.251206)
			(xy 298.899072 -381.261362) (xy 298.891299 -381.280128) (xy 298.876938 -381.294492) (xy 298.858174 -381.302269)
			(xy 298.848018 -381.302768) (xy 298.131738 -381.302768) (xy 298.12157 -381.302305) (xy 298.102777 -381.294534)
			(xy 298.088391 -381.28016) (xy 298.080604 -381.261374) (xy 298.080176 -381.251206) (xy 298.080176 -380.965456)
			(xy 298.079966 -380.958584) (xy 298.07637 -380.945321) (xy 298.073064 -380.939294) (xy 298.056758 -380.910924)
			(xy 298.031037 -380.850755) (xy 298.013627 -380.787678) (xy 298.00484 -380.722835) (xy 298.004838 -380.657399)
			(xy 294.574917 -380.657399) (xy 294.575484 -380.69012) (xy 294.574907 -380.722849) (xy 294.566055 -380.787707)
			(xy 294.548568 -380.850787) (xy 294.522763 -380.910946) (xy 294.506396 -380.939294) (xy 294.503083 -380.94532)
			(xy 294.499476 -380.958583) (xy 294.499284 -380.965456) (xy 294.499284 -381.251206) (xy 294.498779 -381.26133)
			(xy 294.491054 -381.280047) (xy 294.476773 -381.294402) (xy 294.458097 -381.302225) (xy 294.447976 -381.302768)
			(xy 293.731696 -381.302768) (xy 293.721538 -381.302381) (xy 293.702779 -381.294578) (xy 293.688455 -381.28017)
			(xy 293.680761 -381.261367) (xy 293.680388 -381.251206) (xy 293.680388 -380.965456) (xy 293.680176 -380.958584)
			(xy 293.676582 -380.945321) (xy 293.673276 -380.939294) (xy 293.656906 -380.910947) (xy 293.631106 -380.850787)
			(xy 293.613617 -380.787706) (xy 293.604758 -380.722849) (xy 293.604188 -380.69012) (xy 290.174843 -380.69012)
			(xy 290.174842 -380.722836) (xy 290.166057 -380.787681) (xy 290.148648 -380.85076) (xy 290.12293 -380.910932)
			(xy 290.106608 -380.939294) (xy 290.103296 -380.94532) (xy 290.099688 -380.958583) (xy 290.099496 -380.965456)
			(xy 290.099496 -381.251206) (xy 290.098972 -381.26136) (xy 290.091202 -381.280123) (xy 290.076846 -381.294486)
			(xy 290.058088 -381.302267) (xy 290.047934 -381.302768) (xy 289.331654 -381.302768) (xy 289.321494 -381.302304)
			(xy 289.302725 -381.294516) (xy 289.288362 -381.280141) (xy 289.280588 -381.261366) (xy 289.280092 -381.251206)
			(xy 289.280092 -380.965456) (xy 289.27988 -380.958584) (xy 289.276285 -380.945321) (xy 289.27298 -380.939294)
			(xy 289.256673 -380.910924) (xy 289.230952 -380.850755) (xy 289.213541 -380.787678) (xy 289.204754 -380.722835)
			(xy 289.204752 -380.657399) (xy 282.775152 -380.657399) (xy 282.775152 -383.490216) (xy 287.004252 -383.490216)
			(xy 287.004809 -383.457486) (xy 287.013668 -383.392628) (xy 287.031161 -383.329548) (xy 287.056971 -383.26939)
			(xy 287.07334 -383.241042) (xy 287.076635 -383.235008) (xy 287.080254 -383.221752) (xy 287.080452 -383.21488)
			(xy 287.080452 -382.465326) (xy 287.080256 -382.458453) (xy 287.076651 -382.44519) (xy 287.07334 -382.439164)
			(xy 287.056964 -382.41082) (xy 287.031164 -382.350659) (xy 287.013677 -382.287578) (xy 287.00482 -382.22272)
			(xy 287.004252 -382.18999) (xy 287.004842 -382.157261) (xy 287.013691 -382.092404) (xy 287.031175 -382.029324)
			(xy 287.056975 -381.969165) (xy 287.07334 -381.940816) (xy 287.076644 -381.934786) (xy 287.080257 -381.921527)
			(xy 287.080452 -381.914654) (xy 287.080452 -381.628904) (xy 287.080987 -381.618801) (xy 287.088715 -381.600133)
			(xy 287.102996 -381.585839) (xy 287.121658 -381.578096) (xy 287.13176 -381.577596) (xy 287.84804 -381.577596)
			(xy 287.858151 -381.578052) (xy 287.876829 -381.585802) (xy 287.891122 -381.600108) (xy 287.898856 -381.618793)
			(xy 287.899348 -381.628904) (xy 287.899348 -381.914654) (xy 287.899551 -381.921526) (xy 287.903151 -381.93479)
			(xy 287.90646 -381.940816) (xy 287.922828 -381.969164) (xy 287.94863 -382.029324) (xy 287.966119 -382.092404)
			(xy 287.974979 -382.157261) (xy 287.975548 -382.18999) (xy 287.974994 -382.22271) (xy 291.404892 -382.22271)
			(xy 291.404893 -382.157273) (xy 291.413678 -382.092428) (xy 291.431087 -382.029349) (xy 291.456805 -381.969177)
			(xy 291.473128 -381.940816) (xy 291.476439 -381.93479) (xy 291.480047 -381.921527) (xy 291.48024 -381.914654)
			(xy 291.48024 -381.628904) (xy 291.480626 -381.618745) (xy 291.488427 -381.599985) (xy 291.502836 -381.58566)
			(xy 291.521641 -381.577968) (xy 291.531802 -381.577596) (xy 292.248082 -381.577596) (xy 292.258202 -381.57814)
			(xy 292.276915 -381.585854) (xy 292.29127 -381.600122) (xy 292.299098 -381.618787) (xy 292.299644 -381.628904)
			(xy 292.299644 -381.914654) (xy 292.299848 -381.921526) (xy 292.303447 -381.934789) (xy 292.306756 -381.940816)
			(xy 292.32307 -381.969182) (xy 292.348789 -382.029352) (xy 292.366198 -382.09243) (xy 292.374982 -382.157273)
			(xy 292.374984 -382.222709) (xy 292.366201 -382.287554) (xy 292.348794 -382.350632) (xy 292.323078 -382.410803)
			(xy 292.306756 -382.439164) (xy 292.303458 -382.445197) (xy 292.299841 -382.458454) (xy 292.299644 -382.465326)
			(xy 292.299644 -383.21488) (xy 292.299838 -383.221753) (xy 292.303444 -383.235016) (xy 292.306756 -383.241042)
			(xy 292.323092 -383.269396) (xy 292.348809 -383.329569) (xy 292.366215 -383.392649) (xy 292.374997 -383.457495)
			(xy 292.374995 -383.522933) (xy 292.36621 -383.587778) (xy 292.348799 -383.650857) (xy 292.323079 -383.711029)
			(xy 292.306756 -383.73939) (xy 292.303449 -383.745419) (xy 292.299838 -383.758679) (xy 292.299644 -383.765552)
			(xy 292.299644 -384.051556) (xy 292.299143 -384.061702) (xy 292.29137 -384.080445) (xy 292.276998 -384.094768)
			(xy 292.258229 -384.102477) (xy 292.248082 -384.102864) (xy 291.531802 -384.102864) (xy 291.521676 -384.102372)
			(xy 291.502956 -384.094645) (xy 291.488599 -384.080361) (xy 291.480779 -384.06168) (xy 291.48024 -384.051556)
			(xy 291.48024 -383.765552) (xy 291.480023 -383.758681) (xy 291.476431 -383.745418) (xy 291.473128 -383.73939)
			(xy 291.45682 -383.711021) (xy 291.431101 -383.650852) (xy 291.413692 -383.587775) (xy 291.404907 -383.522931)
			(xy 291.404905 -383.457496) (xy 291.413687 -383.392652) (xy 291.431092 -383.329574) (xy 291.456807 -383.269403)
			(xy 291.473128 -383.241042) (xy 291.47643 -383.235011) (xy 291.480043 -383.221752) (xy 291.48024 -383.21488)
			(xy 291.48024 -382.465326) (xy 291.480033 -382.458454) (xy 291.476435 -382.445191) (xy 291.473128 -382.439164)
			(xy 291.456798 -382.410807) (xy 291.431081 -382.350635) (xy 291.413675 -382.287555) (xy 291.404892 -382.22271)
			(xy 287.974994 -382.22271) (xy 287.974994 -382.22272) (xy 287.966134 -382.287578) (xy 287.94864 -382.350658)
			(xy 287.92283 -382.410816) (xy 287.90646 -382.439164) (xy 287.903163 -382.445197) (xy 287.899545 -382.458454)
			(xy 287.899348 -382.465326) (xy 287.899348 -383.21488) (xy 287.899542 -383.221753) (xy 287.903148 -383.235016)
			(xy 287.90646 -383.241042) (xy 287.922838 -383.269384) (xy 287.94574 -383.322789) (xy 289.204722 -383.322789)
			(xy 289.204726 -383.257349) (xy 289.213515 -383.192502) (xy 289.23093 -383.129422) (xy 289.256654 -383.069251)
			(xy 289.27298 -383.04089) (xy 289.276297 -383.034866) (xy 289.279902 -383.021602) (xy 289.280092 -383.014728)
			(xy 289.280092 -382.728724) (xy 289.280541 -382.718572) (xy 289.288327 -382.699822) (xy 289.302715 -382.685498)
			(xy 289.321501 -382.677796) (xy 289.331654 -382.677416) (xy 290.047934 -382.677416) (xy 290.05806 -382.677898)
			(xy 290.076777 -382.685632) (xy 290.091132 -382.69992) (xy 290.098954 -382.7186) (xy 290.099496 -382.728724)
			(xy 290.099496 -383.014728) (xy 290.099678 -383.021602) (xy 290.103293 -383.034865) (xy 290.106608 -383.04089)
			(xy 290.122898 -383.069269) (xy 290.148616 -383.129436) (xy 290.166026 -383.192511) (xy 290.174812 -383.257352)
			(xy 290.174817 -383.322786) (xy 290.166038 -383.387628) (xy 290.148637 -383.450705) (xy 290.122926 -383.510876)
			(xy 290.106608 -383.539238) (xy 290.10328 -383.545256) (xy 290.099683 -383.558525) (xy 290.099496 -383.5654)
			(xy 290.099496 -384.3147) (xy 290.099688 -384.321573) (xy 290.103296 -384.334836) (xy 290.106608 -384.340862)
			(xy 290.122959 -384.369207) (xy 290.148672 -384.429382) (xy 290.166075 -384.492464) (xy 290.174853 -384.557312)
			(xy 290.174851 -384.590036) (xy 293.604188 -384.590036) (xy 293.604749 -384.557306) (xy 293.613607 -384.492448)
			(xy 293.631098 -384.429368) (xy 293.656907 -384.36921) (xy 293.673276 -384.340862) (xy 293.676603 -384.334843)
			(xy 293.680201 -384.321575) (xy 293.680388 -384.3147) (xy 293.680388 -383.5654) (xy 293.680197 -383.558527)
			(xy 293.676588 -383.545264) (xy 293.673276 -383.539238) (xy 293.656923 -383.510882) (xy 293.631119 -383.450725)
			(xy 293.613626 -383.387647) (xy 293.604761 -383.322792) (xy 293.604188 -383.290064) (xy 293.604762 -383.257335)
			(xy 293.613615 -383.192477) (xy 293.631104 -383.129397) (xy 293.656909 -383.069238) (xy 293.673276 -383.04089)
			(xy 293.676593 -383.034866) (xy 293.680198 -383.021602) (xy 293.680388 -383.014728) (xy 293.680388 -382.728724)
			(xy 293.680835 -382.718605) (xy 293.688573 -382.699904) (xy 293.70288 -382.685589) (xy 293.721577 -382.677841)
			(xy 293.731696 -382.677416) (xy 294.447976 -382.677416) (xy 294.458099 -382.677836) (xy 294.476805 -382.685579)
			(xy 294.491121 -382.699895) (xy 294.498864 -382.718601) (xy 294.499284 -382.728724) (xy 294.499284 -383.014728)
			(xy 294.499467 -383.021602) (xy 294.503082 -383.034865) (xy 294.506396 -383.04089) (xy 294.522757 -383.069242)
			(xy 294.54856 -383.1294) (xy 294.566051 -383.192479) (xy 294.574913 -383.257335) (xy 294.575484 -383.290064)
			(xy 294.574927 -383.322794) (xy 294.566069 -383.387652) (xy 294.548576 -383.450733) (xy 294.531636 -383.490216)
			(xy 295.804336 -383.490216) (xy 295.804895 -383.457486) (xy 295.813754 -383.392628) (xy 295.831247 -383.329548)
			(xy 295.857055 -383.26939) (xy 295.873424 -383.241042) (xy 295.876726 -383.235011) (xy 295.880339 -383.221752)
			(xy 295.880536 -383.21488) (xy 295.880536 -382.465326) (xy 295.88033 -382.458454) (xy 295.876731 -382.445191)
			(xy 295.873424 -382.439164) (xy 295.857046 -382.410821) (xy 295.831247 -382.35066) (xy 295.813761 -382.287578)
			(xy 295.804904 -382.22272) (xy 295.804336 -382.18999) (xy 295.804928 -382.157262) (xy 295.813777 -382.092404)
			(xy 295.83126 -382.029324) (xy 295.857059 -381.969165) (xy 295.873424 -381.940816) (xy 295.876735 -381.934789)
			(xy 295.880342 -381.921527) (xy 295.880536 -381.914654) (xy 295.880536 -381.628904) (xy 295.88092 -381.618777)
			(xy 295.888674 -381.600067) (xy 295.903001 -381.585751) (xy 295.921717 -381.578012) (xy 295.931844 -381.577596)
			(xy 296.648124 -381.577596) (xy 296.658234 -381.578065) (xy 296.676912 -381.58581) (xy 296.691206 -381.600112)
			(xy 296.69894 -381.618794) (xy 296.699432 -381.628904) (xy 296.699432 -381.914654) (xy 296.699638 -381.921526)
			(xy 296.703236 -381.934789) (xy 296.706544 -381.940816) (xy 296.722911 -381.969165) (xy 296.748713 -382.029324)
			(xy 296.766203 -382.092404) (xy 296.775062 -382.157261) (xy 296.775632 -382.18999) (xy 296.77508 -382.22272)
			(xy 296.766219 -382.287579) (xy 296.748725 -382.350659) (xy 296.722914 -382.410816) (xy 296.706544 -382.439164)
			(xy 296.703246 -382.445197) (xy 296.699629 -382.458454) (xy 296.699432 -382.465326) (xy 296.699432 -383.21488)
			(xy 296.699628 -383.221753) (xy 296.703233 -383.235016) (xy 296.706544 -383.241042) (xy 296.722921 -383.269385)
			(xy 296.745823 -383.322789) (xy 298.004809 -383.322789) (xy 298.004813 -383.257349) (xy 298.013601 -383.192503)
			(xy 298.031015 -383.129423) (xy 298.056739 -383.069251) (xy 298.073064 -383.04089) (xy 298.076379 -383.034866)
			(xy 298.079985 -383.021602) (xy 298.080176 -383.014728) (xy 298.080176 -382.728724) (xy 298.080641 -382.718574)
			(xy 298.088424 -382.699827) (xy 298.102807 -382.685504) (xy 298.121587 -382.677799) (xy 298.131738 -382.677416)
			(xy 298.848018 -382.677416) (xy 298.858143 -382.677911) (xy 298.87686 -382.68564) (xy 298.891215 -382.699923)
			(xy 298.899038 -382.718602) (xy 298.89958 -382.728724) (xy 298.89958 -383.014728) (xy 298.899764 -383.021602)
			(xy 298.903378 -383.034864) (xy 298.906692 -383.04089) (xy 298.922983 -383.069268) (xy 298.948702 -383.129436)
			(xy 298.966112 -383.192511) (xy 298.974899 -383.257352) (xy 298.974903 -383.322786) (xy 298.966124 -383.387628)
			(xy 298.948722 -383.450706) (xy 298.931839 -383.490216) (xy 300.204124 -383.490216) (xy 300.204671 -383.457486)
			(xy 300.213532 -383.392627) (xy 300.231028 -383.329547) (xy 300.256841 -383.269389) (xy 300.273212 -383.241042)
			(xy 300.276513 -383.23501) (xy 300.280127 -383.221752) (xy 300.280324 -383.21488) (xy 300.280324 -382.465326)
			(xy 300.280119 -382.458454) (xy 300.276519 -382.445191) (xy 300.273212 -382.439164) (xy 300.256833 -382.410822)
			(xy 300.231034 -382.35066) (xy 300.213548 -382.287578) (xy 300.204692 -382.22272) (xy 300.204124 -382.18999)
			(xy 300.204704 -382.157261) (xy 300.213555 -382.092403) (xy 300.231041 -382.029323) (xy 300.256845 -381.969164)
			(xy 300.273212 -381.940816) (xy 300.276522 -381.934789) (xy 300.28013 -381.921527) (xy 300.280324 -381.914654)
			(xy 300.280324 -381.628904) (xy 300.28072 -381.618779) (xy 300.288471 -381.600071) (xy 300.302794 -381.585755)
			(xy 300.321507 -381.578014) (xy 300.331632 -381.577596) (xy 301.047912 -381.577596) (xy 301.058021 -381.578075)
			(xy 301.076699 -381.585816) (xy 301.090993 -381.600115) (xy 301.098728 -381.618795) (xy 301.09922 -381.628904)
			(xy 301.09922 -381.914654) (xy 301.099427 -381.921526) (xy 301.103025 -381.934789) (xy 301.106332 -381.940816)
			(xy 301.122697 -381.969165) (xy 301.148501 -382.029324) (xy 301.165991 -382.092404) (xy 301.17485 -382.157261)
			(xy 301.17542 -382.18999) (xy 304.603666 -382.18999) (xy 304.607657 -382.127823) (xy 304.619566 -382.066676)
			(xy 304.639195 -382.007555) (xy 304.666224 -381.951429) (xy 304.700208 -381.89922) (xy 304.74059 -381.851785)
			(xy 304.786706 -381.809904) (xy 304.837798 -381.774264) (xy 304.893029 -381.74545) (xy 304.951491 -381.723936)
			(xy 305.012225 -381.710074) (xy 305.074232 -381.704092) (xy 305.136495 -381.706088) (xy 305.197992 -381.716031)
			(xy 305.257713 -381.733755) (xy 305.314676 -381.758972) (xy 305.367947 -381.791265) (xy 305.416652 -381.830105)
			(xy 305.459989 -381.874855) (xy 305.497249 -381.924779) (xy 305.527818 -381.979058) (xy 305.551196 -382.036801)
			(xy 305.566997 -382.097059) (xy 305.574963 -382.158842) (xy 305.575462 -382.18999) (xy 305.574963 -382.221138)
			(xy 305.57476 -382.22271) (xy 331.005013 -382.22271) (xy 331.005014 -382.157273) (xy 331.013799 -382.092427)
			(xy 331.031209 -382.029348) (xy 331.056929 -381.969177) (xy 331.073252 -381.940816) (xy 331.076557 -381.934787)
			(xy 331.080169 -381.921527) (xy 331.080364 -381.914654) (xy 331.080364 -381.628904) (xy 331.080824 -381.618755)
			(xy 331.088612 -381.600009) (xy 331.102996 -381.585687) (xy 331.121775 -381.577981) (xy 331.131926 -381.577596)
			(xy 331.848206 -381.577596) (xy 331.858328 -381.57812) (xy 331.877041 -381.585842) (xy 331.891395 -381.600116)
			(xy 331.899222 -381.618785) (xy 331.899768 -381.628904) (xy 331.899768 -381.914654) (xy 331.899981 -381.921526)
			(xy 331.903575 -381.934788) (xy 331.90688 -381.940816) (xy 331.923193 -381.969182) (xy 331.948911 -382.029352)
			(xy 331.966319 -382.09243) (xy 331.975103 -382.157274) (xy 331.975104 -382.222709) (xy 331.966322 -382.287553)
			(xy 331.948916 -382.350631) (xy 331.923201 -382.410803) (xy 331.90688 -382.439164) (xy 331.903577 -382.445194)
			(xy 331.899964 -382.458454) (xy 331.899768 -382.465326) (xy 331.899768 -383.21488) (xy 331.899972 -383.221752)
			(xy 331.903572 -383.235015) (xy 331.90688 -383.241042) (xy 331.923215 -383.269396) (xy 331.948931 -383.329569)
			(xy 331.966336 -383.392649) (xy 331.975118 -383.457495) (xy 331.975116 -383.522933) (xy 331.966331 -383.587778)
			(xy 331.948921 -383.650857) (xy 331.923203 -383.711029) (xy 331.90688 -383.73939) (xy 331.903567 -383.745416)
			(xy 331.899961 -383.758679) (xy 331.899768 -383.765552) (xy 331.899768 -384.051556) (xy 331.899342 -384.061711)
			(xy 331.891555 -384.080469) (xy 331.877159 -384.094795) (xy 331.858363 -384.10249) (xy 331.848206 -384.102864)
			(xy 331.131926 -384.102864) (xy 331.121801 -384.102352) (xy 331.103082 -384.094634) (xy 331.088724 -384.080355)
			(xy 331.080904 -384.061678) (xy 331.080364 -384.051556) (xy 331.080364 -383.765552) (xy 331.080157 -383.75868)
			(xy 331.076559 -383.745417) (xy 331.073252 -383.73939) (xy 331.056943 -383.711021) (xy 331.031223 -383.650852)
			(xy 331.013813 -383.587775) (xy 331.005028 -383.522932) (xy 331.005026 -383.457496) (xy 331.013808 -383.392652)
			(xy 331.031214 -383.329574) (xy 331.05693 -383.269403) (xy 331.073252 -383.241042) (xy 331.076548 -383.235008)
			(xy 331.080166 -383.221752) (xy 331.080364 -383.21488) (xy 331.080364 -382.465326) (xy 331.080167 -382.458453)
			(xy 331.076563 -382.44519) (xy 331.073252 -382.439164) (xy 331.056921 -382.410808) (xy 331.031203 -382.350635)
			(xy 331.013796 -382.287556) (xy 331.005013 -382.22271) (xy 305.57476 -382.22271) (xy 305.566997 -382.282921)
			(xy 305.551196 -382.343179) (xy 305.527818 -382.400922) (xy 305.497249 -382.455201) (xy 305.459989 -382.505125)
			(xy 305.416652 -382.549875) (xy 305.367947 -382.588715) (xy 305.314676 -382.621008) (xy 305.257713 -382.646225)
			(xy 305.197992 -382.663949) (xy 305.136495 -382.673892) (xy 305.074232 -382.675888) (xy 305.012225 -382.669906)
			(xy 304.951491 -382.656044) (xy 304.893029 -382.63453) (xy 304.837798 -382.605716) (xy 304.786706 -382.570076)
			(xy 304.74059 -382.528195) (xy 304.700208 -382.48076) (xy 304.666224 -382.428551) (xy 304.639195 -382.372425)
			(xy 304.619566 -382.313304) (xy 304.607657 -382.252157) (xy 304.603666 -382.18999) (xy 301.17542 -382.18999)
			(xy 301.17487 -382.22272) (xy 301.166009 -382.287579) (xy 301.148514 -382.350659) (xy 301.122703 -382.410817)
			(xy 301.106332 -382.439164) (xy 301.103033 -382.445196) (xy 301.099417 -382.458454) (xy 301.09922 -382.465326)
			(xy 301.09922 -383.21488) (xy 301.099417 -383.221753) (xy 301.103022 -383.235016) (xy 301.106332 -383.241042)
			(xy 301.122708 -383.269386) (xy 301.148509 -383.329547) (xy 301.165996 -383.392628) (xy 301.174852 -383.457486)
			(xy 301.17542 -383.490216) (xy 301.174836 -383.522945) (xy 301.165985 -383.587802) (xy 301.1485 -383.650882)
			(xy 301.122698 -383.711041) (xy 301.106332 -383.73939) (xy 301.103024 -383.745418) (xy 301.099414 -383.758679)
			(xy 301.09922 -383.765552) (xy 301.09922 -384.051556) (xy 301.098748 -384.061673) (xy 301.091018 -384.080372)
			(xy 301.076719 -384.094687) (xy 301.058029 -384.102437) (xy 301.047912 -384.102864) (xy 300.331632 -384.102864)
			(xy 300.321507 -384.102457) (xy 300.302797 -384.094713) (xy 300.28848 -384.080393) (xy 300.28074 -384.061681)
			(xy 300.280324 -384.051556) (xy 300.280324 -383.765552) (xy 300.280109 -383.75868) (xy 300.276516 -383.745418)
			(xy 300.273212 -383.73939) (xy 300.256844 -383.711042) (xy 300.231042 -383.650882) (xy 300.213553 -383.587802)
			(xy 300.204694 -383.522945) (xy 300.204124 -383.490216) (xy 298.931839 -383.490216) (xy 298.923011 -383.510876)
			(xy 298.906692 -383.539238) (xy 298.903363 -383.545256) (xy 298.899767 -383.558525) (xy 298.89958 -383.5654)
			(xy 298.89958 -384.3147) (xy 298.899774 -384.321573) (xy 298.903381 -384.334836) (xy 298.906692 -384.340862)
			(xy 298.923044 -384.369207) (xy 298.948757 -384.429382) (xy 298.966161 -384.492464) (xy 298.97494 -384.557311)
			(xy 298.974938 -384.590036) (xy 302.404272 -384.590036) (xy 302.404835 -384.557306) (xy 302.413692 -384.492448)
			(xy 302.431183 -384.429368) (xy 302.456991 -384.36921) (xy 302.47336 -384.340862) (xy 302.476685 -384.334842)
			(xy 302.480285 -384.321575) (xy 302.480472 -384.3147) (xy 302.480472 -383.5654) (xy 302.480283 -383.558526)
			(xy 302.476673 -383.545264) (xy 302.47336 -383.539238) (xy 302.457015 -383.510877) (xy 302.431207 -383.450722)
			(xy 302.413711 -383.387646) (xy 302.404845 -383.322792) (xy 302.404272 -383.290064) (xy 302.404848 -383.257335)
			(xy 302.413701 -383.192477) (xy 302.431189 -383.129397) (xy 302.456993 -383.069239) (xy 302.47336 -383.04089)
			(xy 302.476675 -383.034865) (xy 302.480281 -383.021602) (xy 302.480472 -383.014728) (xy 302.480472 -382.728724)
			(xy 302.480935 -382.718606) (xy 302.48867 -382.699909) (xy 302.502972 -382.685595) (xy 302.521663 -382.677843)
			(xy 302.53178 -382.677416) (xy 303.24806 -382.677416) (xy 303.258182 -382.677849) (xy 303.276888 -382.685587)
			(xy 303.291204 -382.699899) (xy 303.298948 -382.718602) (xy 303.299368 -382.728724) (xy 303.299368 -383.014728)
			(xy 303.299553 -383.021602) (xy 303.303167 -383.034864) (xy 303.30648 -383.04089) (xy 303.32284 -383.069243)
			(xy 303.348643 -383.129401) (xy 303.366135 -383.192479) (xy 303.374997 -383.257335) (xy 303.375568 -383.290064)
			(xy 303.374999 -383.322793) (xy 303.366143 -383.387651) (xy 303.348653 -383.450731) (xy 303.331716 -383.490216)
			(xy 304.603666 -383.490216) (xy 304.607657 -383.428049) (xy 304.619566 -383.366902) (xy 304.639195 -383.307781)
			(xy 304.666224 -383.251655) (xy 304.700208 -383.199446) (xy 304.74059 -383.152011) (xy 304.786706 -383.11013)
			(xy 304.837798 -383.07449) (xy 304.893029 -383.045676) (xy 304.951491 -383.024162) (xy 305.012225 -383.0103)
			(xy 305.074232 -383.004318) (xy 305.136495 -383.006314) (xy 305.197992 -383.016257) (xy 305.257713 -383.033981)
			(xy 305.314676 -383.059198) (xy 305.367947 -383.091491) (xy 305.416652 -383.130331) (xy 305.459989 -383.175081)
			(xy 305.497249 -383.225005) (xy 305.527818 -383.279284) (xy 305.532182 -383.290064) (xy 306.803814 -383.290064)
			(xy 306.807805 -383.227897) (xy 306.819714 -383.16675) (xy 306.839343 -383.107629) (xy 306.866372 -383.051503)
			(xy 306.900356 -382.999294) (xy 306.940738 -382.951859) (xy 306.986854 -382.909978) (xy 307.037946 -382.874338)
			(xy 307.093177 -382.845524) (xy 307.151639 -382.82401) (xy 307.212373 -382.810148) (xy 307.27438 -382.804166)
			(xy 307.336643 -382.806162) (xy 307.39814 -382.816105) (xy 307.457861 -382.833829) (xy 307.514824 -382.859046)
			(xy 307.568095 -382.891339) (xy 307.6168 -382.930179) (xy 307.660137 -382.974929) (xy 307.697397 -383.024853)
			(xy 307.727966 -383.079132) (xy 307.751344 -383.136875) (xy 307.767145 -383.197133) (xy 307.775111 -383.258916)
			(xy 307.77561 -383.290064) (xy 307.775111 -383.321212) (xy 307.767145 -383.382995) (xy 307.751344 -383.443253)
			(xy 307.727966 -383.500996) (xy 307.697397 -383.555275) (xy 307.660137 -383.605199) (xy 307.6168 -383.649949)
			(xy 307.568095 -383.688789) (xy 307.514824 -383.721082) (xy 307.457861 -383.746299) (xy 307.39814 -383.764023)
			(xy 307.336643 -383.773966) (xy 307.27438 -383.775962) (xy 307.212373 -383.76998) (xy 307.151639 -383.756118)
			(xy 307.093177 -383.734604) (xy 307.037946 -383.70579) (xy 306.986854 -383.67015) (xy 306.940738 -383.628269)
			(xy 306.900356 -383.580834) (xy 306.866372 -383.528625) (xy 306.839343 -383.472499) (xy 306.819714 -383.413378)
			(xy 306.807805 -383.352231) (xy 306.803814 -383.290064) (xy 305.532182 -383.290064) (xy 305.551196 -383.337027)
			(xy 305.566997 -383.397285) (xy 305.574963 -383.459068) (xy 305.575462 -383.490216) (xy 305.574963 -383.521364)
			(xy 305.566997 -383.583147) (xy 305.551196 -383.643405) (xy 305.527818 -383.701148) (xy 305.497249 -383.755427)
			(xy 305.459989 -383.805351) (xy 305.416652 -383.850101) (xy 305.367947 -383.888941) (xy 305.314676 -383.921234)
			(xy 305.257713 -383.946451) (xy 305.197992 -383.964175) (xy 305.136495 -383.974118) (xy 305.074232 -383.976114)
			(xy 305.012225 -383.970132) (xy 304.951491 -383.95627) (xy 304.893029 -383.934756) (xy 304.837798 -383.905942)
			(xy 304.786706 -383.870302) (xy 304.74059 -383.828421) (xy 304.700208 -383.780986) (xy 304.666224 -383.728777)
			(xy 304.639195 -383.672651) (xy 304.619566 -383.61353) (xy 304.607657 -383.552383) (xy 304.603666 -383.490216)
			(xy 303.331716 -383.490216) (xy 303.322848 -383.51089) (xy 303.30648 -383.539238) (xy 303.30315 -383.545255)
			(xy 303.299554 -383.558525) (xy 303.299368 -383.5654) (xy 303.299368 -384.3147) (xy 303.299564 -384.321573)
			(xy 303.30317 -384.334836) (xy 303.30648 -384.340862) (xy 303.322829 -384.369221) (xy 303.348635 -384.429377)
			(xy 303.366129 -384.492453) (xy 303.374995 -384.557308) (xy 303.375568 -384.590036) (xy 306.803814 -384.590036)
			(xy 306.807805 -384.527869) (xy 306.819714 -384.466722) (xy 306.839343 -384.407601) (xy 306.866372 -384.351475)
			(xy 306.900356 -384.299266) (xy 306.940738 -384.251831) (xy 306.986854 -384.20995) (xy 307.037946 -384.17431)
			(xy 307.093177 -384.145496) (xy 307.151639 -384.123982) (xy 307.212373 -384.11012) (xy 307.27438 -384.104138)
			(xy 307.336643 -384.106134) (xy 307.39814 -384.116077) (xy 307.457861 -384.133801) (xy 307.514824 -384.159018)
			(xy 307.568095 -384.191311) (xy 307.6168 -384.230151) (xy 307.660137 -384.274901) (xy 307.697397 -384.324825)
			(xy 307.727966 -384.379104) (xy 307.751344 -384.436847) (xy 307.767145 -384.497105) (xy 307.775111 -384.558888)
			(xy 307.77561 -384.590036) (xy 333.204312 -384.590036) (xy 333.20487 -384.557306) (xy 333.213728 -384.492448)
			(xy 333.23122 -384.429367) (xy 333.25703 -384.36921) (xy 333.2734 -384.340862) (xy 333.276728 -384.334844)
			(xy 333.280325 -384.321575) (xy 333.280512 -384.3147) (xy 333.280512 -383.5654) (xy 333.280319 -383.558527)
			(xy 333.276711 -383.545264) (xy 333.2734 -383.539238) (xy 333.25705 -383.51088) (xy 333.231244 -383.450724)
			(xy 333.21375 -383.387647) (xy 333.204885 -383.322792) (xy 333.204312 -383.290064) (xy 333.204882 -383.257335)
			(xy 333.213737 -383.192477) (xy 333.231226 -383.129396) (xy 333.257032 -383.069238) (xy 333.2734 -383.04089)
			(xy 333.276718 -383.034867) (xy 333.280322 -383.021602) (xy 333.280512 -383.014728) (xy 333.280512 -382.728724)
			(xy 333.280936 -382.718602) (xy 333.288678 -382.699896) (xy 333.302993 -382.685581) (xy 333.321698 -382.677837)
			(xy 333.33182 -382.677416) (xy 334.0481 -382.677416) (xy 334.058224 -382.677816) (xy 334.076931 -382.685568)
			(xy 334.091246 -382.699889) (xy 334.098988 -382.718599) (xy 334.099408 -382.728724) (xy 334.099408 -383.014728)
			(xy 334.099588 -383.021602) (xy 334.103204 -383.034865) (xy 334.10652 -383.04089) (xy 334.122884 -383.06924)
			(xy 334.148685 -383.1294) (xy 334.166176 -383.192479) (xy 334.175037 -383.257335) (xy 334.175608 -383.290064)
			(xy 334.175047 -383.322794) (xy 334.16619 -383.387652) (xy 334.148698 -383.450732) (xy 334.131759 -383.490216)
			(xy 335.40446 -383.490216) (xy 335.405016 -383.457486) (xy 335.413875 -383.392628) (xy 335.431369 -383.329548)
			(xy 335.457178 -383.26939) (xy 335.473548 -383.241042) (xy 335.476844 -383.235008) (xy 335.480462 -383.221752)
			(xy 335.48066 -383.21488) (xy 335.48066 -382.465326) (xy 335.480463 -382.458453) (xy 335.476859 -382.44519)
			(xy 335.473548 -382.439164) (xy 335.457173 -382.41082) (xy 335.431372 -382.350659) (xy 335.413885 -382.287578)
			(xy 335.405028 -382.22272) (xy 335.40446 -382.18999) (xy 335.405049 -382.157261) (xy 335.413899 -382.092404)
			(xy 335.431383 -382.029324) (xy 335.457183 -381.969165) (xy 335.473548 -381.940816) (xy 335.476853 -381.934786)
			(xy 335.480465 -381.921527) (xy 335.48066 -381.914654) (xy 335.48066 -381.628904) (xy 335.481187 -381.6188)
			(xy 335.488916 -381.60013) (xy 335.5032 -381.585837) (xy 335.521865 -381.578095) (xy 335.531968 -381.577596)
			(xy 336.248248 -381.577596) (xy 336.258359 -381.578046) (xy 336.277038 -381.585799) (xy 336.291331 -381.600106)
			(xy 336.299064 -381.618792) (xy 336.299556 -381.628904) (xy 336.299556 -381.914654) (xy 336.299758 -381.921527)
			(xy 336.303359 -381.93479) (xy 336.306668 -381.940816) (xy 336.323037 -381.969163) (xy 336.348839 -382.029323)
			(xy 336.366327 -382.092403) (xy 336.375187 -382.157261) (xy 336.375756 -382.18999) (xy 336.375201 -382.22271)
			(xy 339.805099 -382.22271) (xy 339.8051 -382.157273) (xy 339.813885 -382.092428) (xy 339.831294 -382.029349)
			(xy 339.857013 -381.969177) (xy 339.873336 -381.940816) (xy 339.87664 -381.934786) (xy 339.880253 -381.921527)
			(xy 339.880448 -381.914654) (xy 339.880448 -381.628904) (xy 339.880924 -381.618757) (xy 339.888708 -381.600014)
			(xy 339.903088 -381.585693) (xy 339.921861 -381.577984) (xy 339.93201 -381.577596) (xy 340.64829 -381.577596)
			(xy 340.658411 -381.578133) (xy 340.677123 -381.58585) (xy 340.691478 -381.60012) (xy 340.699306 -381.618786)
			(xy 340.699852 -381.628904) (xy 340.699852 -381.914654) (xy 340.700055 -381.921527) (xy 340.703655 -381.93479)
			(xy 340.706964 -381.940816) (xy 340.723278 -381.969182) (xy 340.748996 -382.029352) (xy 340.766405 -382.09243)
			(xy 340.775189 -382.157273) (xy 340.775191 -382.222709) (xy 340.775191 -382.22271) (xy 344.204889 -382.22271)
			(xy 344.20489 -382.157273) (xy 344.213675 -382.092428) (xy 344.231083 -382.029349) (xy 344.256802 -381.969177)
			(xy 344.273124 -381.940816) (xy 344.276435 -381.934789) (xy 344.280042 -381.921527) (xy 344.280236 -381.914654)
			(xy 344.280236 -381.628904) (xy 344.280626 -381.618746) (xy 344.288427 -381.599986) (xy 344.302834 -381.585662)
			(xy 344.321637 -381.577968) (xy 344.331798 -381.577596) (xy 345.048078 -381.577596) (xy 345.058198 -381.578143)
			(xy 345.07691 -381.585856) (xy 345.091266 -381.600123) (xy 345.099094 -381.618787) (xy 345.09964 -381.628904)
			(xy 345.09964 -381.914654) (xy 345.099844 -381.921526) (xy 345.103444 -381.934789) (xy 345.106752 -381.940816)
			(xy 345.123066 -381.969182) (xy 345.148785 -382.029352) (xy 345.166194 -382.09243) (xy 345.174979 -382.157273)
			(xy 345.17498 -382.222709) (xy 345.166198 -382.287554) (xy 345.148791 -382.350632) (xy 345.123074 -382.410803)
			(xy 345.106752 -382.439164) (xy 345.103454 -382.445197) (xy 345.099837 -382.458454) (xy 345.09964 -382.465326)
			(xy 345.09964 -383.21488) (xy 345.099835 -383.221753) (xy 345.103441 -383.235016) (xy 345.106752 -383.241042)
			(xy 345.123088 -383.269396) (xy 345.145907 -383.322789) (xy 346.405015 -383.322789) (xy 346.40502 -383.257349)
			(xy 346.413808 -383.192503) (xy 346.431222 -383.129422) (xy 346.456946 -383.069251) (xy 346.473272 -383.04089)
			(xy 346.476588 -383.034866) (xy 346.480193 -383.021602) (xy 346.480384 -383.014728) (xy 346.480384 -382.728724)
			(xy 346.480841 -382.718573) (xy 346.488625 -382.699825) (xy 346.503011 -382.685501) (xy 346.521794 -382.677797)
			(xy 346.531946 -382.677416) (xy 347.248226 -382.677416) (xy 347.258351 -382.677904) (xy 347.277069 -382.685636)
			(xy 347.291423 -382.699921) (xy 347.299246 -382.718601) (xy 347.299788 -382.728724) (xy 347.299788 -383.014728)
			(xy 347.299971 -383.021602) (xy 347.303585 -383.034865) (xy 347.3069 -383.04089) (xy 347.323191 -383.069268)
			(xy 347.348909 -383.129436) (xy 347.366319 -383.192511) (xy 347.375106 -383.257352) (xy 347.37511 -383.322786)
			(xy 347.366331 -383.387628) (xy 347.348929 -383.450706) (xy 347.323219 -383.510876) (xy 347.3069 -383.539238)
			(xy 347.303572 -383.545256) (xy 347.299975 -383.558525) (xy 347.299788 -383.5654) (xy 347.299788 -384.3147)
			(xy 347.299981 -384.321573) (xy 347.303589 -384.334836) (xy 347.3069 -384.340862) (xy 347.323252 -384.369207)
			(xy 347.348964 -384.429382) (xy 347.366368 -384.492464) (xy 347.375147 -384.557312) (xy 347.375142 -384.62275)
			(xy 347.366355 -384.687596) (xy 347.348944 -384.750676) (xy 347.323223 -384.810848) (xy 347.3069 -384.83921)
			(xy 347.303582 -384.845233) (xy 347.299978 -384.858498) (xy 347.299788 -384.865372) (xy 347.299788 -385.151376)
			(xy 347.299359 -385.16153) (xy 347.291569 -385.180284) (xy 347.277174 -385.194609) (xy 347.258382 -385.202307)
			(xy 347.248226 -385.202684) (xy 346.531946 -385.202684) (xy 346.521825 -385.202136) (xy 346.50311 -385.194428)
			(xy 346.488753 -385.180161) (xy 346.480928 -385.161494) (xy 346.480384 -385.151376) (xy 346.480384 -384.865372)
			(xy 346.480205 -384.858498) (xy 346.476588 -384.845235) (xy 346.473272 -384.83921) (xy 346.456979 -384.810832)
			(xy 346.431257 -384.750665) (xy 346.413844 -384.68759) (xy 346.405056 -384.622748) (xy 346.405052 -384.557314)
			(xy 346.413832 -384.492471) (xy 346.431237 -384.429393) (xy 346.456951 -384.369223) (xy 346.473272 -384.340862)
			(xy 346.476598 -384.334843) (xy 346.480197 -384.321575) (xy 346.480384 -384.3147) (xy 346.480384 -383.5654)
			(xy 346.480194 -383.558527) (xy 346.476584 -383.545264) (xy 346.473272 -383.539238) (xy 346.456918 -383.510894)
			(xy 346.431202 -383.450719) (xy 346.413796 -383.387637) (xy 346.405015 -383.322789) (xy 345.145907 -383.322789)
			(xy 345.148805 -383.329569) (xy 345.166212 -383.392649) (xy 345.174994 -383.457495) (xy 345.174992 -383.522933)
			(xy 345.166206 -383.587778) (xy 345.148796 -383.650857) (xy 345.123076 -383.711029) (xy 345.106752 -383.73939)
			(xy 345.103445 -383.745418) (xy 345.099834 -383.758679) (xy 345.09964 -383.765552) (xy 345.09964 -384.051556)
			(xy 345.099143 -384.061702) (xy 345.09137 -384.080446) (xy 345.076996 -384.094769) (xy 345.058226 -384.102478)
			(xy 345.048078 -384.102864) (xy 344.331798 -384.102864) (xy 344.321672 -384.102375) (xy 344.302951 -384.094647)
			(xy 344.288595 -384.080362) (xy 344.280775 -384.06168) (xy 344.280236 -384.051556) (xy 344.280236 -383.765552)
			(xy 344.28002 -383.758681) (xy 344.276428 -383.745418) (xy 344.273124 -383.73939) (xy 344.256816 -383.711021)
			(xy 344.231098 -383.650852) (xy 344.213689 -383.587774) (xy 344.204904 -383.522931) (xy 344.204902 -383.457496)
			(xy 344.213683 -383.392652) (xy 344.231089 -383.329574) (xy 344.256803 -383.269403) (xy 344.273124 -383.241042)
			(xy 344.276426 -383.235011) (xy 344.280039 -383.221752) (xy 344.280236 -383.21488) (xy 344.280236 -382.465326)
			(xy 344.28003 -382.458454) (xy 344.276431 -382.445191) (xy 344.273124 -382.439164) (xy 344.256794 -382.410807)
			(xy 344.231078 -382.350635) (xy 344.213671 -382.287555) (xy 344.204889 -382.22271) (xy 340.775191 -382.22271)
			(xy 340.766408 -382.287553) (xy 340.749002 -382.350632) (xy 340.723285 -382.410803) (xy 340.706964 -382.439164)
			(xy 340.703667 -382.445197) (xy 340.700049 -382.458454) (xy 340.699852 -382.465326) (xy 340.699852 -383.21488)
			(xy 340.700045 -383.221753) (xy 340.703652 -383.235016) (xy 340.706964 -383.241042) (xy 340.7233 -383.269396)
			(xy 340.749016 -383.329569) (xy 340.766422 -383.392649) (xy 340.775204 -383.457495) (xy 340.775202 -383.522933)
			(xy 340.766417 -383.587778) (xy 340.749007 -383.650857) (xy 340.723287 -383.711029) (xy 340.706964 -383.73939)
			(xy 340.703658 -383.745419) (xy 340.700046 -383.758679) (xy 340.699852 -383.765552) (xy 340.699852 -384.051556)
			(xy 340.699343 -384.061701) (xy 340.691572 -384.080442) (xy 340.677202 -384.094765) (xy 340.658436 -384.102476)
			(xy 340.64829 -384.102864) (xy 339.93201 -384.102864) (xy 339.921884 -384.102365) (xy 339.903164 -384.094642)
			(xy 339.888808 -384.080359) (xy 339.880987 -384.061679) (xy 339.880448 -384.051556) (xy 339.880448 -383.765552)
			(xy 339.880243 -383.75868) (xy 339.876644 -383.745417) (xy 339.873336 -383.73939) (xy 339.857027 -383.711021)
			(xy 339.831309 -383.650852) (xy 339.813899 -383.587775) (xy 339.805114 -383.522932) (xy 339.805112 -383.457496)
			(xy 339.813894 -383.392652) (xy 339.8313 -383.329574) (xy 339.857015 -383.269403) (xy 339.873336 -383.241042)
			(xy 339.876631 -383.235007) (xy 339.88025 -383.221751) (xy 339.880448 -383.21488) (xy 339.880448 -382.465326)
			(xy 339.880253 -382.458453) (xy 339.876647 -382.44519) (xy 339.873336 -382.439164) (xy 339.857005 -382.410807)
			(xy 339.831289 -382.350635) (xy 339.813882 -382.287555) (xy 339.805099 -382.22271) (xy 336.375201 -382.22271)
			(xy 336.375201 -382.22272) (xy 336.366341 -382.287578) (xy 336.348847 -382.350658) (xy 336.323038 -382.410816)
			(xy 336.306668 -382.439164) (xy 336.303364 -382.445194) (xy 336.299752 -382.458454) (xy 336.299556 -382.465326)
			(xy 336.299556 -383.21488) (xy 336.299749 -383.221753) (xy 336.303356 -383.235016) (xy 336.306668 -383.241042)
			(xy 336.323047 -383.269384) (xy 336.345949 -383.322788) (xy 337.604943 -383.322788) (xy 337.604947 -383.25735)
			(xy 337.613734 -383.192504) (xy 337.631145 -383.129424) (xy 337.656865 -383.069252) (xy 337.673188 -383.04089)
			(xy 337.676505 -383.034867) (xy 337.68011 -383.021602) (xy 337.6803 -383.014728) (xy 337.6803 -382.728724)
			(xy 337.680741 -382.718571) (xy 337.688529 -382.699819) (xy 337.70292 -382.685495) (xy 337.721708 -382.677795)
			(xy 337.731862 -382.677416) (xy 338.448142 -382.677416) (xy 338.458268 -382.677891) (xy 338.476986 -382.685629)
			(xy 338.49134 -382.699918) (xy 338.499162 -382.7186) (xy 338.499704 -382.728724) (xy 338.499704 -383.014728)
			(xy 338.499885 -383.021602) (xy 338.5035 -383.034865) (xy 338.506816 -383.04089) (xy 338.523109 -383.069268)
			(xy 338.548832 -383.129434) (xy 338.566245 -383.19251) (xy 338.575033 -383.257352) (xy 338.575037 -383.322787)
			(xy 338.566257 -383.38763) (xy 338.548852 -383.450707) (xy 338.523137 -383.510877) (xy 338.506816 -383.539238)
			(xy 338.503489 -383.545257) (xy 338.499891 -383.558525) (xy 338.499704 -383.5654) (xy 338.499704 -384.3147)
			(xy 338.499895 -384.321573) (xy 338.503504 -384.334836) (xy 338.506816 -384.340862) (xy 338.52317 -384.369206)
			(xy 338.548887 -384.429381) (xy 338.566294 -384.492463) (xy 338.575074 -384.557311) (xy 338.575072 -384.590036)
			(xy 342.004396 -384.590036) (xy 342.004956 -384.557306) (xy 342.013814 -384.492448) (xy 342.031306 -384.429368)
			(xy 342.057115 -384.36921) (xy 342.073484 -384.340862) (xy 342.076811 -384.334843) (xy 342.080409 -384.321575)
			(xy 342.080596 -384.3147) (xy 342.080596 -383.5654) (xy 342.080405 -383.558527) (xy 342.076796 -383.545264)
			(xy 342.073484 -383.539238) (xy 342.057132 -383.510881) (xy 342.031327 -383.450724) (xy 342.013834 -383.387647)
			(xy 342.004969 -383.322792) (xy 342.004396 -383.290064) (xy 342.004969 -383.257335) (xy 342.013823 -383.192477)
			(xy 342.031311 -383.129397) (xy 342.057116 -383.069238) (xy 342.073484 -383.04089) (xy 342.076801 -383.034867)
			(xy 342.080406 -383.021602) (xy 342.080596 -383.014728) (xy 342.080596 -382.728724) (xy 342.081035 -382.718604)
			(xy 342.088775 -382.699901) (xy 342.103084 -382.685586) (xy 342.121784 -382.677839) (xy 342.131904 -382.677416)
			(xy 342.848184 -382.677416) (xy 342.858307 -382.677829) (xy 342.877014 -382.685575) (xy 342.891329 -382.699893)
			(xy 342.899072 -382.7186) (xy 342.899492 -382.728724) (xy 342.899492 -383.014728) (xy 342.899674 -383.021602)
			(xy 342.903289 -383.034865) (xy 342.906604 -383.04089) (xy 342.922966 -383.069241) (xy 342.948769 -383.1294)
			(xy 342.966259 -383.192479) (xy 342.975121 -383.257335) (xy 342.975692 -383.290064) (xy 342.975133 -383.322794)
			(xy 342.966276 -383.387652) (xy 342.948783 -383.450732) (xy 342.922974 -383.51089) (xy 342.906604 -383.539238)
			(xy 342.903276 -383.545256) (xy 342.899679 -383.558525) (xy 342.899492 -383.5654) (xy 342.899492 -384.3147)
			(xy 342.899685 -384.321573) (xy 342.903292 -384.334836) (xy 342.906604 -384.340862) (xy 342.922955 -384.369219)
			(xy 342.94876 -384.429376) (xy 342.966254 -384.492453) (xy 342.975119 -384.557308) (xy 342.975692 -384.590036)
			(xy 342.975121 -384.622765) (xy 342.966267 -384.687623) (xy 342.948778 -384.750704) (xy 342.922972 -384.810862)
			(xy 342.906604 -384.83921) (xy 342.903286 -384.845233) (xy 342.899682 -384.858498) (xy 342.899492 -384.865372)
			(xy 342.899492 -385.151376) (xy 342.899064 -385.161498) (xy 342.891323 -385.180203) (xy 342.877009 -385.194518)
			(xy 342.858306 -385.202263) (xy 342.848184 -385.202684) (xy 342.131904 -385.202684) (xy 342.12178 -385.20228)
			(xy 342.103073 -385.194531) (xy 342.088758 -385.18021) (xy 342.081016 -385.1615) (xy 342.080596 -385.151376)
			(xy 342.080596 -384.865372) (xy 342.080415 -384.858498) (xy 342.0768 -384.845235) (xy 342.073484 -384.83921)
			(xy 342.057121 -384.810859) (xy 342.031319 -384.7507) (xy 342.013829 -384.687621) (xy 342.004967 -384.622765)
			(xy 342.004396 -384.590036) (xy 338.575072 -384.590036) (xy 338.57507 -384.622751) (xy 338.566281 -384.687598)
			(xy 338.548867 -384.750678) (xy 338.523142 -384.810849) (xy 338.506816 -384.83921) (xy 338.503499 -384.845233)
			(xy 338.499894 -384.858498) (xy 338.499704 -384.865372) (xy 338.499704 -385.151376) (xy 338.499259 -385.161528)
			(xy 338.491472 -385.180279) (xy 338.477082 -385.194603) (xy 338.458296 -385.202305) (xy 338.448142 -385.202684)
			(xy 337.731862 -385.202684) (xy 337.721736 -385.202205) (xy 337.703018 -385.194469) (xy 337.688664 -385.180181)
			(xy 337.680842 -385.1615) (xy 337.6803 -385.151376) (xy 337.6803 -384.865372) (xy 337.680119 -384.858498)
			(xy 337.676503 -384.845235) (xy 337.673188 -384.83921) (xy 337.656898 -384.810831) (xy 337.63118 -384.750664)
			(xy 337.61377 -384.687589) (xy 337.604984 -384.622748) (xy 337.60498 -384.557314) (xy 337.613758 -384.492472)
			(xy 337.63116 -384.429395) (xy 337.65687 -384.369224) (xy 337.673188 -384.340862) (xy 337.676515 -384.334844)
			(xy 337.680113 -384.321575) (xy 337.6803 -384.3147) (xy 337.6803 -383.5654) (xy 337.680108 -383.558527)
			(xy 337.6765 -383.545264) (xy 337.673188 -383.539238) (xy 337.656837 -383.510893) (xy 337.631125 -383.450717)
			(xy 337.613722 -383.387635) (xy 337.604943 -383.322788) (xy 336.345949 -383.322788) (xy 336.348847 -383.329546)
			(xy 336.366332 -383.392628) (xy 336.375188 -383.457486) (xy 336.375756 -383.490216) (xy 336.375168 -383.522945)
			(xy 336.366317 -383.587802) (xy 336.348834 -383.650882) (xy 336.323033 -383.711041) (xy 336.306668 -383.73939)
			(xy 336.303355 -383.745415) (xy 336.299749 -383.758679) (xy 336.299556 -383.765552) (xy 336.299556 -384.051556)
			(xy 336.29898 -384.061655) (xy 336.291267 -384.080321) (xy 336.276999 -384.094616) (xy 336.258346 -384.102362)
			(xy 336.248248 -384.102864) (xy 335.531968 -384.102864) (xy 335.521839 -384.102509) (xy 335.503128 -384.094744)
			(xy 335.488813 -384.080408) (xy 335.481076 -384.061686) (xy 335.48066 -384.051556) (xy 335.48066 -383.765552)
			(xy 335.480453 -383.75868) (xy 335.476856 -383.745417) (xy 335.473548 -383.73939) (xy 335.457183 -383.71104)
			(xy 335.43138 -383.650881) (xy 335.41389 -383.587802) (xy 335.40503 -383.522945) (xy 335.40446 -383.490216)
			(xy 334.131759 -383.490216) (xy 334.122889 -383.51089) (xy 334.10652 -383.539238) (xy 334.103193 -383.545257)
			(xy 334.099595 -383.558525) (xy 334.099408 -383.5654) (xy 334.099408 -384.3147) (xy 334.099599 -384.321573)
			(xy 334.103208 -384.334836) (xy 334.10652 -384.340862) (xy 334.122872 -384.369218) (xy 334.148677 -384.429376)
			(xy 334.16617 -384.492453) (xy 334.175035 -384.557308) (xy 334.175608 -384.590036) (xy 334.175035 -384.622765)
			(xy 334.166181 -384.687623) (xy 334.148693 -384.750703) (xy 334.122887 -384.810862) (xy 334.10652 -384.83921)
			(xy 334.103203 -384.845234) (xy 334.099598 -384.858498) (xy 334.099408 -384.865372) (xy 334.099408 -385.151376)
			(xy 334.098965 -385.161496) (xy 334.091226 -385.180198) (xy 334.076918 -385.194512) (xy 334.05822 -385.20226)
			(xy 334.0481 -385.202684) (xy 333.33182 -385.202684) (xy 333.321697 -385.202267) (xy 333.302991 -385.194523)
			(xy 333.288675 -385.180206) (xy 333.280932 -385.161499) (xy 333.280512 -385.151376) (xy 333.280512 -384.865372)
			(xy 333.280329 -384.858498) (xy 333.276715 -384.845235) (xy 333.2734 -384.83921) (xy 333.257038 -384.810859)
			(xy 333.231236 -384.7507) (xy 333.213745 -384.687621) (xy 333.204883 -384.622765) (xy 333.204312 -384.590036)
			(xy 307.77561 -384.590036) (xy 307.775111 -384.621184) (xy 307.767145 -384.682967) (xy 307.751344 -384.743225)
			(xy 307.727966 -384.800968) (xy 307.697397 -384.855247) (xy 307.660137 -384.905171) (xy 307.6168 -384.949921)
			(xy 307.568095 -384.988761) (xy 307.514824 -385.021054) (xy 307.457861 -385.046271) (xy 307.39814 -385.063995)
			(xy 307.336643 -385.073938) (xy 307.27438 -385.075934) (xy 307.212373 -385.069952) (xy 307.151639 -385.05609)
			(xy 307.093177 -385.034576) (xy 307.037946 -385.005762) (xy 306.986854 -384.970122) (xy 306.940738 -384.928241)
			(xy 306.900356 -384.880806) (xy 306.866372 -384.828597) (xy 306.839343 -384.772471) (xy 306.819714 -384.71335)
			(xy 306.807805 -384.652203) (xy 306.803814 -384.590036) (xy 303.375568 -384.590036) (xy 303.374987 -384.622765)
			(xy 303.366134 -384.687622) (xy 303.348648 -384.750702) (xy 303.322846 -384.810861) (xy 303.30648 -384.83921)
			(xy 303.30316 -384.845232) (xy 303.299558 -384.858498) (xy 303.299368 -384.865372) (xy 303.299368 -385.151376)
			(xy 303.298964 -385.161501) (xy 303.291218 -385.18021) (xy 303.276897 -385.194527) (xy 303.258185 -385.202267)
			(xy 303.24806 -385.202684) (xy 302.53178 -385.202684) (xy 302.521654 -385.2023) (xy 302.502947 -385.194542)
			(xy 302.488633 -385.180216) (xy 302.480891 -385.161502) (xy 302.480472 -385.151376) (xy 302.480472 -384.865372)
			(xy 302.480295 -384.858498) (xy 302.476677 -384.845235) (xy 302.47336 -384.83921) (xy 302.457004 -384.810855)
			(xy 302.431199 -384.750698) (xy 302.413706 -384.68762) (xy 302.404843 -384.622765) (xy 302.404272 -384.590036)
			(xy 298.974938 -384.590036) (xy 298.974936 -384.62275) (xy 298.966148 -384.687596) (xy 298.948736 -384.750676)
			(xy 298.923016 -384.810848) (xy 298.906692 -384.83921) (xy 298.903373 -384.845233) (xy 298.89977 -384.858498)
			(xy 298.89958 -384.865372) (xy 298.89958 -385.151376) (xy 298.899159 -385.161531) (xy 298.891367 -385.180287)
			(xy 298.87697 -385.194612) (xy 298.858175 -385.202309) (xy 298.848018 -385.202684) (xy 298.131738 -385.202684)
			(xy 298.121617 -385.202143) (xy 298.102901 -385.194432) (xy 298.088544 -385.180162) (xy 298.08072 -385.161494)
			(xy 298.080176 -385.151376) (xy 298.080176 -384.865372) (xy 298.079998 -384.858498) (xy 298.076381 -384.845235)
			(xy 298.073064 -384.83921) (xy 298.056771 -384.810832) (xy 298.03105 -384.750665) (xy 298.013637 -384.68759)
			(xy 298.00485 -384.622748) (xy 298.004845 -384.557314) (xy 298.013625 -384.492471) (xy 298.031029 -384.429393)
			(xy 298.056743 -384.369223) (xy 298.073064 -384.340862) (xy 298.076389 -384.334842) (xy 298.079989 -384.321575)
			(xy 298.080176 -384.3147) (xy 298.080176 -383.5654) (xy 298.079987 -383.558527) (xy 298.076377 -383.545264)
			(xy 298.073064 -383.539238) (xy 298.05671 -383.510894) (xy 298.030994 -383.450719) (xy 298.013589 -383.387637)
			(xy 298.004809 -383.322789) (xy 296.745823 -383.322789) (xy 296.748721 -383.329546) (xy 296.766208 -383.392628)
			(xy 296.775064 -383.457486) (xy 296.775632 -383.490216) (xy 296.775046 -383.522945) (xy 296.766196 -383.587802)
			(xy 296.748711 -383.650882) (xy 296.722909 -383.711041) (xy 296.706544 -383.73939) (xy 296.703236 -383.745418)
			(xy 296.699626 -383.758679) (xy 296.699432 -383.765552) (xy 296.699432 -384.051556) (xy 296.698949 -384.061672)
			(xy 296.691221 -384.080368) (xy 296.676925 -384.094683) (xy 296.658239 -384.102435) (xy 296.648124 -384.102864)
			(xy 295.931844 -384.102864) (xy 295.92172 -384.102447) (xy 295.90301 -384.094707) (xy 295.888693 -384.08039)
			(xy 295.880953 -384.06168) (xy 295.880536 -384.051556) (xy 295.880536 -383.765552) (xy 295.88032 -383.758681)
			(xy 295.876728 -383.745418) (xy 295.873424 -383.73939) (xy 295.857057 -383.711042) (xy 295.831255 -383.650882)
			(xy 295.813765 -383.587802) (xy 295.804906 -383.522945) (xy 295.804336 -383.490216) (xy 294.531636 -383.490216)
			(xy 294.522766 -383.51089) (xy 294.506396 -383.539238) (xy 294.503067 -383.545256) (xy 294.499471 -383.558525)
			(xy 294.499284 -383.5654) (xy 294.499284 -384.3147) (xy 294.499478 -384.321573) (xy 294.503085 -384.334836)
			(xy 294.506396 -384.340862) (xy 294.522746 -384.36922) (xy 294.548552 -384.429376) (xy 294.566046 -384.492453)
			(xy 294.574911 -384.557308) (xy 294.575484 -384.590036) (xy 294.574914 -384.622765) (xy 294.56606 -384.687624)
			(xy 294.548571 -384.750704) (xy 294.522764 -384.810862) (xy 294.506396 -384.83921) (xy 294.503077 -384.845233)
			(xy 294.499474 -384.858498) (xy 294.499284 -384.865372) (xy 294.499284 -385.151376) (xy 294.498864 -385.161499)
			(xy 294.491121 -385.180205) (xy 294.476805 -385.194521) (xy 294.458099 -385.202264) (xy 294.447976 -385.202684)
			(xy 293.731696 -385.202684) (xy 293.721571 -385.202287) (xy 293.702865 -385.194534) (xy 293.68855 -385.180212)
			(xy 293.680808 -385.161501) (xy 293.680388 -385.151376) (xy 293.680388 -384.865372) (xy 293.680208 -384.858498)
			(xy 293.676592 -384.845235) (xy 293.673276 -384.83921) (xy 293.656912 -384.81086) (xy 293.63111 -384.7507)
			(xy 293.61362 -384.687621) (xy 293.604759 -384.622765) (xy 293.604188 -384.590036) (xy 290.174851 -384.590036)
			(xy 290.174849 -384.62275) (xy 290.166062 -384.687596) (xy 290.148651 -384.750676) (xy 290.122931 -384.810848)
			(xy 290.106608 -384.83921) (xy 290.10329 -384.845233) (xy 290.099686 -384.858498) (xy 290.099496 -384.865372)
			(xy 290.099496 -385.151376) (xy 290.099059 -385.161529) (xy 290.09127 -385.180282) (xy 290.076878 -385.194606)
			(xy 290.058089 -385.202306) (xy 290.047934 -385.202684) (xy 289.331654 -385.202684) (xy 289.321527 -385.202212)
			(xy 289.30281 -385.194473) (xy 289.288456 -385.180183) (xy 289.280634 -385.1615) (xy 289.280092 -385.151376)
			(xy 289.280092 -384.865372) (xy 289.279912 -384.858498) (xy 289.276296 -384.845235) (xy 289.27298 -384.83921)
			(xy 289.256687 -384.810832) (xy 289.230964 -384.750665) (xy 289.213551 -384.68759) (xy 289.204763 -384.622748)
			(xy 289.204759 -384.557313) (xy 289.213539 -384.49247) (xy 289.230944 -384.429393) (xy 289.256659 -384.369223)
			(xy 289.27298 -384.340862) (xy 289.276307 -384.334843) (xy 289.279905 -384.321575) (xy 289.280092 -384.3147)
			(xy 289.280092 -383.5654) (xy 289.279901 -383.558527) (xy 289.276292 -383.545264) (xy 289.27298 -383.539238)
			(xy 289.256626 -383.510894) (xy 289.230909 -383.450719) (xy 289.213503 -383.387637) (xy 289.204722 -383.322789)
			(xy 287.94574 -383.322789) (xy 287.948638 -383.329546) (xy 287.966124 -383.392628) (xy 287.97498 -383.457486)
			(xy 287.975548 -383.490216) (xy 287.974961 -383.522945) (xy 287.96611 -383.587802) (xy 287.948626 -383.650882)
			(xy 287.922825 -383.711041) (xy 287.90646 -383.73939) (xy 287.903154 -383.745419) (xy 287.899542 -383.758679)
			(xy 287.899348 -383.765552) (xy 287.899348 -384.051556) (xy 287.898849 -384.06167) (xy 287.891124 -384.080363)
			(xy 287.876834 -384.094677) (xy 287.858153 -384.102432) (xy 287.84804 -384.102864) (xy 287.13176 -384.102864)
			(xy 287.12163 -384.102516) (xy 287.102919 -384.094748) (xy 287.088605 -384.08041) (xy 287.080868 -384.061686)
			(xy 287.080452 -384.051556) (xy 287.080452 -383.765552) (xy 287.080246 -383.75868) (xy 287.076648 -383.745417)
			(xy 287.07334 -383.73939) (xy 287.056974 -383.711041) (xy 287.031172 -383.650882) (xy 287.013682 -383.587802)
			(xy 287.004822 -383.522945) (xy 287.004252 -383.490216) (xy 282.775152 -383.490216) (xy 282.775152 -385.98983)
			(xy 318.109598 -385.98983) (xy 318.113669 -385.934208) (xy 318.125795 -385.879771) (xy 318.145718 -385.82768)
			(xy 318.173014 -385.779045) (xy 318.2071 -385.734902) (xy 318.247249 -385.696193) (xy 318.292607 -385.663742)
			(xy 318.342207 -385.638241) (xy 318.394991 -385.620234) (xy 318.449834 -385.610104) (xy 318.505568 -385.608067)
			(xy 318.561005 -385.614167) (xy 318.614962 -385.628273) (xy 318.666291 -385.650085) (xy 318.713897 -385.679139)
			(xy 318.756765 -385.714814) (xy 318.793982 -385.756351) (xy 318.824755 -385.802864) (xy 318.848427 -385.853361)
			(xy 318.864495 -385.906768) (xy 318.872615 -385.961944) (xy 318.873124 -385.98983) (xy 318.872615 -386.017716)
			(xy 318.864495 -386.072892) (xy 318.848427 -386.126299) (xy 318.824755 -386.176796) (xy 318.793982 -386.223309)
			(xy 318.756765 -386.264846) (xy 318.713897 -386.300521) (xy 318.666291 -386.329575) (xy 318.614962 -386.351387)
			(xy 318.561005 -386.365493) (xy 318.505568 -386.371593) (xy 318.449834 -386.369556) (xy 318.394991 -386.359426)
			(xy 318.342207 -386.341419) (xy 318.292607 -386.315918) (xy 318.247249 -386.283467) (xy 318.2071 -386.244758)
			(xy 318.173014 -386.200615) (xy 318.145718 -386.15198) (xy 318.125795 -386.099889) (xy 318.113669 -386.045452)
			(xy 318.109598 -385.98983) (xy 282.775152 -385.98983) (xy 282.775152 -397.790162) (xy 287.004252 -397.790162)
			(xy 287.004829 -397.757433) (xy 287.013683 -397.692575) (xy 287.03117 -397.629495) (xy 287.056973 -397.569337)
			(xy 287.07334 -397.540988) (xy 287.076654 -397.534963) (xy 287.080261 -397.5217) (xy 287.080452 -397.514826)
			(xy 287.080452 -396.765526) (xy 287.080256 -396.758653) (xy 287.076651 -396.74539) (xy 287.07334 -396.739364)
			(xy 287.056964 -396.71102) (xy 287.031164 -396.650859) (xy 287.013677 -396.587778) (xy 287.00482 -396.52292)
			(xy 287.004252 -396.49019) (xy 287.004842 -396.457461) (xy 287.013691 -396.392604) (xy 287.031175 -396.329524)
			(xy 287.056975 -396.269365) (xy 287.07334 -396.241016) (xy 287.076644 -396.234986) (xy 287.080257 -396.221727)
			(xy 287.080452 -396.214854) (xy 287.080452 -395.92885) (xy 287.080968 -395.918725) (xy 287.088682 -395.900003)
			(xy 287.102959 -395.885644) (xy 287.121638 -395.877825) (xy 287.13176 -395.877288) (xy 287.84804 -395.877288)
			(xy 287.858195 -395.877689) (xy 287.876946 -395.885495) (xy 287.891268 -395.899898) (xy 287.898968 -395.918693)
			(xy 287.899348 -395.92885) (xy 287.899348 -396.214854) (xy 287.899551 -396.221726) (xy 287.903151 -396.23499)
			(xy 287.90646 -396.241016) (xy 287.922828 -396.269364) (xy 287.94863 -396.329524) (xy 287.966119 -396.392604)
			(xy 287.974979 -396.457461) (xy 287.975548 -396.49019) (xy 287.974994 -396.52292) (xy 287.966134 -396.587778)
			(xy 287.94864 -396.650858) (xy 287.92283 -396.711016) (xy 287.90646 -396.739364) (xy 287.903163 -396.745397)
			(xy 287.899545 -396.758654) (xy 287.899348 -396.765526) (xy 287.899348 -397.514826) (xy 287.899524 -397.5217)
			(xy 287.903143 -397.534963) (xy 287.90646 -397.540988) (xy 287.915864 -397.55729) (xy 289.204747 -397.55729)
			(xy 289.21353 -397.492446) (xy 289.230939 -397.429367) (xy 289.256657 -397.369197) (xy 289.27298 -397.340836)
			(xy 289.276281 -397.334804) (xy 289.279896 -397.321546) (xy 289.280092 -397.314674) (xy 289.280092 -397.028924)
			(xy 289.280541 -397.018772) (xy 289.288327 -397.000022) (xy 289.302715 -396.985698) (xy 289.321501 -396.977996)
			(xy 289.331654 -396.977616) (xy 290.047934 -396.977616) (xy 290.05806 -396.978098) (xy 290.076777 -396.985832)
			(xy 290.091132 -397.00012) (xy 290.098954 -397.0188) (xy 290.099496 -397.028924) (xy 290.099496 -397.314674)
			(xy 290.099698 -397.321546) (xy 290.103299 -397.334809) (xy 290.106608 -397.340836) (xy 290.122937 -397.369193)
			(xy 290.148652 -397.429366) (xy 290.166057 -397.492445) (xy 290.174839 -397.55729) (xy 290.174837 -397.622727)
			(xy 290.166054 -397.687572) (xy 290.148646 -397.75065) (xy 290.122929 -397.810822) (xy 290.115986 -397.822887)
			(xy 291.404876 -397.822887) (xy 291.404881 -397.757448) (xy 291.413669 -397.692601) (xy 291.431081 -397.629521)
			(xy 291.456804 -397.569349) (xy 291.473128 -397.540988) (xy 291.476449 -397.534966) (xy 291.48005 -397.5217)
			(xy 291.48024 -397.514826) (xy 291.48024 -396.765526) (xy 291.480033 -396.758654) (xy 291.476435 -396.745391)
			(xy 291.473128 -396.739364) (xy 291.456798 -396.711007) (xy 291.431081 -396.650835) (xy 291.413675 -396.587755)
			(xy 291.404892 -396.52291) (xy 291.404893 -396.457473) (xy 291.413678 -396.392628) (xy 291.431087 -396.329549)
			(xy 291.456805 -396.269377) (xy 291.473128 -396.241016) (xy 291.476439 -396.23499) (xy 291.480047 -396.221727)
			(xy 291.48024 -396.214854) (xy 291.48024 -395.92885) (xy 291.480705 -395.918681) (xy 291.488474 -395.899887)
			(xy 291.502847 -395.885501) (xy 291.521634 -395.877714) (xy 291.531802 -395.877288) (xy 292.248082 -395.877288)
			(xy 292.258259 -395.87768) (xy 292.277063 -395.885468) (xy 292.29145 -395.899864) (xy 292.299227 -395.918673)
			(xy 292.299644 -395.92885) (xy 292.299644 -396.214854) (xy 292.299848 -396.221726) (xy 292.303447 -396.234989)
			(xy 292.306756 -396.241016) (xy 292.32307 -396.269382) (xy 292.348789 -396.329552) (xy 292.366198 -396.39263)
			(xy 292.374982 -396.457473) (xy 292.374984 -396.522909) (xy 292.366201 -396.587754) (xy 292.348794 -396.650832)
			(xy 292.323078 -396.711003) (xy 292.306756 -396.739364) (xy 292.303458 -396.745397) (xy 292.299841 -396.758654)
			(xy 292.299644 -396.765526) (xy 292.299644 -397.514826) (xy 292.299821 -397.5217) (xy 292.303439 -397.534963)
			(xy 292.306756 -397.540988) (xy 292.323046 -397.569367) (xy 292.348767 -397.629534) (xy 292.366179 -397.692609)
			(xy 292.374967 -397.75745) (xy 292.374971 -397.822884) (xy 292.366192 -397.887727) (xy 292.348789 -397.950804)
			(xy 292.323076 -398.010975) (xy 292.306756 -398.039336) (xy 292.303433 -398.045357) (xy 292.299832 -398.058623)
			(xy 292.299644 -398.065498) (xy 292.299644 -398.351502) (xy 292.299237 -398.361676) (xy 292.291448 -398.380474)
			(xy 292.277057 -398.39486) (xy 292.258256 -398.402641) (xy 292.248082 -398.403064) (xy 291.531802 -398.403064)
			(xy 291.521645 -398.402565) (xy 291.502876 -398.394792) (xy 291.488511 -398.380427) (xy 291.480736 -398.361659)
			(xy 291.48024 -398.351502) (xy 291.48024 -398.065498) (xy 291.480044 -398.058625) (xy 291.476438 -398.045363)
			(xy 291.473128 -398.039336) (xy 291.456774 -398.010992) (xy 291.43106 -397.950817) (xy 291.413656 -397.887735)
			(xy 291.404876 -397.822887) (xy 290.115986 -397.822887) (xy 290.106608 -397.839184) (xy 290.1033 -397.845212)
			(xy 290.09969 -397.858473) (xy 290.099496 -397.865346) (xy 290.099496 -398.6149) (xy 290.099688 -398.621773)
			(xy 290.103296 -398.635036) (xy 290.106608 -398.641062) (xy 290.122959 -398.669407) (xy 290.148672 -398.729582)
			(xy 290.166075 -398.792664) (xy 290.174853 -398.857512) (xy 290.174851 -398.890236) (xy 293.604188 -398.890236)
			(xy 293.604749 -398.857506) (xy 293.613607 -398.792648) (xy 293.631098 -398.729568) (xy 293.656907 -398.66941)
			(xy 293.673276 -398.641062) (xy 293.676603 -398.635043) (xy 293.680201 -398.621775) (xy 293.680388 -398.6149)
			(xy 293.680388 -397.865346) (xy 293.68018 -397.858474) (xy 293.676583 -397.845211) (xy 293.673276 -397.839184)
			(xy 293.656902 -397.81084) (xy 293.631103 -397.750678) (xy 293.613615 -397.687597) (xy 293.604757 -397.622739)
			(xy 293.604188 -397.59001) (xy 293.604737 -397.55728) (xy 293.613598 -397.492421) (xy 293.631093 -397.429341)
			(xy 293.656905 -397.369183) (xy 293.673276 -397.340836) (xy 293.676576 -397.334804) (xy 293.680191 -397.321546)
			(xy 293.680388 -397.314674) (xy 293.680388 -397.028924) (xy 293.680835 -397.018805) (xy 293.688573 -397.000104)
			(xy 293.70288 -396.985789) (xy 293.721577 -396.978041) (xy 293.731696 -396.977616) (xy 294.447976 -396.977616)
			(xy 294.458099 -396.978036) (xy 294.476805 -396.985779) (xy 294.491121 -397.000095) (xy 294.498864 -397.018801)
			(xy 294.499284 -397.028924) (xy 294.499284 -397.314674) (xy 294.499488 -397.321546) (xy 294.503088 -397.334809)
			(xy 294.506396 -397.340836) (xy 294.522776 -397.369178) (xy 294.548574 -397.42934) (xy 294.56606 -397.492422)
			(xy 294.574916 -397.55728) (xy 294.575484 -397.59001) (xy 294.574903 -397.622739) (xy 294.566052 -397.687597)
			(xy 294.548566 -397.750677) (xy 294.53163 -397.790162) (xy 295.804336 -397.790162) (xy 295.804916 -397.757433)
			(xy 295.813769 -397.692576) (xy 295.831255 -397.629496) (xy 295.857058 -397.569337) (xy 295.873424 -397.540988)
			(xy 295.876745 -397.534966) (xy 295.880346 -397.5217) (xy 295.880536 -397.514826) (xy 295.880536 -396.765526)
			(xy 295.88033 -396.758654) (xy 295.876731 -396.745391) (xy 295.873424 -396.739364) (xy 295.857046 -396.711021)
			(xy 295.831247 -396.65086) (xy 295.813761 -396.587778) (xy 295.804904 -396.52292) (xy 295.804336 -396.49019)
			(xy 295.804928 -396.457462) (xy 295.813777 -396.392604) (xy 295.83126 -396.329524) (xy 295.857059 -396.269365)
			(xy 295.873424 -396.241016) (xy 295.876735 -396.234989) (xy 295.880342 -396.221727) (xy 295.880536 -396.214854)
			(xy 295.880536 -395.92885) (xy 295.881067 -395.918727) (xy 295.888778 -395.900008) (xy 295.903051 -395.88565)
			(xy 295.921724 -395.877828) (xy 295.931844 -395.877288) (xy 296.648124 -395.877288) (xy 296.658278 -395.877702)
			(xy 296.677029 -395.885503) (xy 296.691351 -395.899902) (xy 296.699052 -395.918694) (xy 296.699432 -395.92885)
			(xy 296.699432 -396.214854) (xy 296.699638 -396.221726) (xy 296.703236 -396.234989) (xy 296.706544 -396.241016)
			(xy 296.722911 -396.269365) (xy 296.748713 -396.329524) (xy 296.766203 -396.392604) (xy 296.775062 -396.457461)
			(xy 296.775632 -396.49019) (xy 296.77508 -396.52292) (xy 296.766219 -396.587779) (xy 296.748725 -396.650859)
			(xy 296.722914 -396.711016) (xy 296.706544 -396.739364) (xy 296.703246 -396.745397) (xy 296.699629 -396.758654)
			(xy 296.699432 -396.765526) (xy 296.699432 -397.514826) (xy 296.69961 -397.5217) (xy 296.703228 -397.534963)
			(xy 296.706544 -397.540988) (xy 296.715947 -397.55729) (xy 298.004834 -397.55729) (xy 298.013616 -397.492446)
			(xy 298.031024 -397.429368) (xy 298.056742 -397.369197) (xy 298.073064 -397.340836) (xy 298.076363 -397.334804)
			(xy 298.079979 -397.321546) (xy 298.080176 -397.314674) (xy 298.080176 -397.028924) (xy 298.080641 -397.018774)
			(xy 298.088424 -397.000027) (xy 298.102807 -396.985704) (xy 298.121587 -396.977999) (xy 298.131738 -396.977616)
			(xy 298.848018 -396.977616) (xy 298.858143 -396.978111) (xy 298.87686 -396.98584) (xy 298.891215 -397.000123)
			(xy 298.899038 -397.018802) (xy 298.89958 -397.028924) (xy 298.89958 -397.314674) (xy 298.899784 -397.321546)
			(xy 298.903384 -397.334809) (xy 298.906692 -397.340836) (xy 298.923022 -397.369193) (xy 298.948737 -397.429365)
			(xy 298.966143 -397.492445) (xy 298.974925 -397.55729) (xy 298.974924 -397.622727) (xy 298.96614 -397.687572)
			(xy 298.948731 -397.750651) (xy 298.931844 -397.790162) (xy 300.204124 -397.790162) (xy 300.204692 -397.757433)
			(xy 300.213547 -397.692574) (xy 300.231036 -397.629494) (xy 300.256843 -397.569336) (xy 300.273212 -397.540988)
			(xy 300.276532 -397.534966) (xy 300.280134 -397.5217) (xy 300.280324 -397.514826) (xy 300.280324 -396.765526)
			(xy 300.280119 -396.758654) (xy 300.276519 -396.745391) (xy 300.273212 -396.739364) (xy 300.256833 -396.711022)
			(xy 300.231034 -396.65086) (xy 300.213548 -396.587778) (xy 300.204692 -396.52292) (xy 300.204124 -396.49019)
			(xy 300.204704 -396.457461) (xy 300.213555 -396.392603) (xy 300.231041 -396.329523) (xy 300.256845 -396.269364)
			(xy 300.273212 -396.241016) (xy 300.276522 -396.234989) (xy 300.28013 -396.221727) (xy 300.280324 -396.214854)
			(xy 300.280324 -395.92885) (xy 300.280867 -395.918728) (xy 300.288576 -395.900011) (xy 300.302845 -395.885654)
			(xy 300.321514 -395.87783) (xy 300.331632 -395.877288) (xy 301.047912 -395.877288) (xy 301.058065 -395.877711)
			(xy 301.076816 -395.885509) (xy 301.091138 -395.899904) (xy 301.09884 -395.918694) (xy 301.09922 -395.92885)
			(xy 301.09922 -396.214854) (xy 301.099427 -396.221726) (xy 301.103025 -396.234989) (xy 301.106332 -396.241016)
			(xy 301.122697 -396.269365) (xy 301.148501 -396.329524) (xy 301.165991 -396.392604) (xy 301.17485 -396.457461)
			(xy 301.17542 -396.49019) (xy 304.603666 -396.49019) (xy 304.607657 -396.428023) (xy 304.619566 -396.366876)
			(xy 304.639195 -396.307755) (xy 304.666224 -396.251629) (xy 304.700208 -396.19942) (xy 304.74059 -396.151985)
			(xy 304.786706 -396.110104) (xy 304.837798 -396.074464) (xy 304.893029 -396.04565) (xy 304.951491 -396.024136)
			(xy 305.012225 -396.010274) (xy 305.074232 -396.004292) (xy 305.136495 -396.006288) (xy 305.197992 -396.016231)
			(xy 305.257713 -396.033955) (xy 305.314676 -396.059172) (xy 305.367947 -396.091465) (xy 305.416652 -396.130305)
			(xy 305.459989 -396.175055) (xy 305.497249 -396.224979) (xy 305.527818 -396.279258) (xy 305.551196 -396.337001)
			(xy 305.566997 -396.397259) (xy 305.574963 -396.459042) (xy 305.575462 -396.49019) (xy 305.574963 -396.521338)
			(xy 305.566997 -396.583121) (xy 305.551196 -396.643379) (xy 305.527818 -396.701122) (xy 305.497249 -396.755401)
			(xy 305.459989 -396.805325) (xy 305.416652 -396.850075) (xy 305.367947 -396.888915) (xy 305.314676 -396.921208)
			(xy 305.257713 -396.946425) (xy 305.197992 -396.964149) (xy 305.136495 -396.974092) (xy 305.074232 -396.976088)
			(xy 305.012225 -396.970106) (xy 304.951491 -396.956244) (xy 304.893029 -396.93473) (xy 304.837798 -396.905916)
			(xy 304.786706 -396.870276) (xy 304.74059 -396.828395) (xy 304.700208 -396.78096) (xy 304.666224 -396.728751)
			(xy 304.639195 -396.672625) (xy 304.619566 -396.613504) (xy 304.607657 -396.552357) (xy 304.603666 -396.49019)
			(xy 301.17542 -396.49019) (xy 301.17487 -396.52292) (xy 301.166009 -396.587779) (xy 301.148514 -396.650859)
			(xy 301.122703 -396.711017) (xy 301.106332 -396.739364) (xy 301.103033 -396.745396) (xy 301.099417 -396.758654)
			(xy 301.09922 -396.765526) (xy 301.09922 -397.514826) (xy 301.099399 -397.5217) (xy 301.103016 -397.534963)
			(xy 301.106332 -397.540988) (xy 301.122686 -397.569344) (xy 301.148492 -397.6295) (xy 301.165986 -397.692578)
			(xy 301.174849 -397.757433) (xy 301.17542 -397.790162) (xy 301.174857 -397.822892) (xy 301.166 -397.88775)
			(xy 301.148509 -397.95083) (xy 301.122701 -398.010988) (xy 301.106332 -398.039336) (xy 301.103007 -398.045356)
			(xy 301.099408 -398.058623) (xy 301.09922 -398.065498) (xy 301.09922 -398.351502) (xy 301.098774 -398.361634)
			(xy 301.091038 -398.380362) (xy 301.076739 -398.39472) (xy 301.058042 -398.402532) (xy 301.047912 -398.403064)
			(xy 300.331632 -398.403064) (xy 300.321475 -398.402652) (xy 300.302717 -398.39486) (xy 300.288391 -398.38046)
			(xy 300.280696 -398.361661) (xy 300.280324 -398.351502) (xy 300.280324 -398.065498) (xy 300.28013 -398.058625)
			(xy 300.276523 -398.045362) (xy 300.273212 -398.039336) (xy 300.256862 -398.010978) (xy 300.231056 -397.950822)
			(xy 300.213562 -397.887745) (xy 300.204697 -397.82289) (xy 300.204124 -397.790162) (xy 298.931844 -397.790162)
			(xy 298.923014 -397.810822) (xy 298.906692 -397.839184) (xy 298.903382 -397.845211) (xy 298.899774 -397.858473)
			(xy 298.89958 -397.865346) (xy 298.89958 -398.6149) (xy 298.899774 -398.621773) (xy 298.903381 -398.635036)
			(xy 298.906692 -398.641062) (xy 298.923044 -398.669407) (xy 298.948757 -398.729582) (xy 298.966161 -398.792664)
			(xy 298.97494 -398.857511) (xy 298.974938 -398.890236) (xy 302.404272 -398.890236) (xy 302.404835 -398.857506)
			(xy 302.413692 -398.792648) (xy 302.431183 -398.729568) (xy 302.456991 -398.66941) (xy 302.47336 -398.641062)
			(xy 302.476685 -398.635042) (xy 302.480285 -398.621775) (xy 302.480472 -398.6149) (xy 302.480472 -397.865346)
			(xy 302.480266 -397.858474) (xy 302.476668 -397.845211) (xy 302.47336 -397.839184) (xy 302.456994 -397.810835)
			(xy 302.431191 -397.750676) (xy 302.413701 -397.687596) (xy 302.404842 -397.622739) (xy 302.404272 -397.59001)
			(xy 302.404823 -397.55728) (xy 302.413684 -397.492421) (xy 302.431179 -397.429341) (xy 302.45699 -397.369184)
			(xy 302.47336 -397.340836) (xy 302.476659 -397.334803) (xy 302.480275 -397.321546) (xy 302.480472 -397.314674)
			(xy 302.480472 -397.028924) (xy 302.480935 -397.018806) (xy 302.48867 -397.000109) (xy 302.502972 -396.985795)
			(xy 302.521663 -396.978043) (xy 302.53178 -396.977616) (xy 303.24806 -396.977616) (xy 303.258182 -396.978049)
			(xy 303.276888 -396.985787) (xy 303.291204 -397.000099) (xy 303.298948 -397.018802) (xy 303.299368 -397.028924)
			(xy 303.299368 -397.314674) (xy 303.299574 -397.321546) (xy 303.303173 -397.334809) (xy 303.30648 -397.340836)
			(xy 303.322858 -397.369178) (xy 303.348657 -397.42934) (xy 303.366144 -397.492422) (xy 303.375 -397.55728)
			(xy 303.375568 -397.59001) (xy 303.374975 -397.622738) (xy 303.366126 -397.687595) (xy 303.348643 -397.750675)
			(xy 303.331709 -397.790162) (xy 304.603666 -397.790162) (xy 304.607657 -397.727995) (xy 304.619566 -397.666848)
			(xy 304.639195 -397.607727) (xy 304.666224 -397.551601) (xy 304.700208 -397.499392) (xy 304.74059 -397.451957)
			(xy 304.786706 -397.410076) (xy 304.837798 -397.374436) (xy 304.893029 -397.345622) (xy 304.951491 -397.324108)
			(xy 305.012225 -397.310246) (xy 305.074232 -397.304264) (xy 305.136495 -397.30626) (xy 305.197992 -397.316203)
			(xy 305.257713 -397.333927) (xy 305.314676 -397.359144) (xy 305.367947 -397.391437) (xy 305.416652 -397.430277)
			(xy 305.459989 -397.475027) (xy 305.497249 -397.524951) (xy 305.527818 -397.57923) (xy 305.532182 -397.59001)
			(xy 306.803814 -397.59001) (xy 306.807805 -397.527843) (xy 306.819714 -397.466696) (xy 306.839343 -397.407575)
			(xy 306.866372 -397.351449) (xy 306.900356 -397.29924) (xy 306.940738 -397.251805) (xy 306.986854 -397.209924)
			(xy 307.037946 -397.174284) (xy 307.093177 -397.14547) (xy 307.151639 -397.123956) (xy 307.212373 -397.110094)
			(xy 307.27438 -397.104112) (xy 307.336643 -397.106108) (xy 307.39814 -397.116051) (xy 307.457861 -397.133775)
			(xy 307.514824 -397.158992) (xy 307.568095 -397.191285) (xy 307.6168 -397.230125) (xy 307.660137 -397.274875)
			(xy 307.697397 -397.324799) (xy 307.727966 -397.379078) (xy 307.751344 -397.436821) (xy 307.767145 -397.497079)
			(xy 307.775111 -397.558862) (xy 307.77561 -397.59001) (xy 307.775111 -397.621158) (xy 307.767145 -397.682941)
			(xy 307.751344 -397.743199) (xy 307.727966 -397.800942) (xy 307.697397 -397.855221) (xy 307.660137 -397.905145)
			(xy 307.6168 -397.949895) (xy 307.568095 -397.988735) (xy 307.514824 -398.021028) (xy 307.457861 -398.046245)
			(xy 307.39814 -398.063969) (xy 307.336643 -398.073912) (xy 307.27438 -398.075908) (xy 307.212373 -398.069926)
			(xy 307.151639 -398.056064) (xy 307.093177 -398.03455) (xy 307.037946 -398.005736) (xy 306.986854 -397.970096)
			(xy 306.940738 -397.928215) (xy 306.900356 -397.88078) (xy 306.866372 -397.828571) (xy 306.839343 -397.772445)
			(xy 306.819714 -397.713324) (xy 306.807805 -397.652177) (xy 306.803814 -397.59001) (xy 305.532182 -397.59001)
			(xy 305.551196 -397.636973) (xy 305.566997 -397.697231) (xy 305.574963 -397.759014) (xy 305.575462 -397.790162)
			(xy 305.574963 -397.82131) (xy 305.566997 -397.883093) (xy 305.551196 -397.943351) (xy 305.527818 -398.001094)
			(xy 305.497249 -398.055373) (xy 305.459989 -398.105297) (xy 305.416652 -398.150047) (xy 305.367947 -398.188887)
			(xy 305.314676 -398.22118) (xy 305.257713 -398.246397) (xy 305.197992 -398.264121) (xy 305.136495 -398.274064)
			(xy 305.074232 -398.27606) (xy 305.012225 -398.270078) (xy 304.951491 -398.256216) (xy 304.893029 -398.234702)
			(xy 304.837798 -398.205888) (xy 304.786706 -398.170248) (xy 304.74059 -398.128367) (xy 304.700208 -398.080932)
			(xy 304.666224 -398.028723) (xy 304.639195 -397.972597) (xy 304.619566 -397.913476) (xy 304.607657 -397.852329)
			(xy 304.603666 -397.790162) (xy 303.331709 -397.790162) (xy 303.322844 -397.810835) (xy 303.30648 -397.839184)
			(xy 303.30317 -397.845211) (xy 303.299562 -397.858473) (xy 303.299368 -397.865346) (xy 303.299368 -398.6149)
			(xy 303.299564 -398.621773) (xy 303.30317 -398.635036) (xy 303.30648 -398.641062) (xy 303.322829 -398.669421)
			(xy 303.348635 -398.729577) (xy 303.366129 -398.792653) (xy 303.374995 -398.857508) (xy 303.375568 -398.890236)
			(xy 306.803814 -398.890236) (xy 306.807805 -398.828069) (xy 306.819714 -398.766922) (xy 306.839343 -398.707801)
			(xy 306.866372 -398.651675) (xy 306.900356 -398.599466) (xy 306.940738 -398.552031) (xy 306.986854 -398.51015)
			(xy 307.037946 -398.47451) (xy 307.093177 -398.445696) (xy 307.151639 -398.424182) (xy 307.212373 -398.41032)
			(xy 307.27438 -398.404338) (xy 307.336643 -398.406334) (xy 307.39814 -398.416277) (xy 307.457861 -398.434001)
			(xy 307.514824 -398.459218) (xy 307.568095 -398.491511) (xy 307.6168 -398.530351) (xy 307.660137 -398.575101)
			(xy 307.697397 -398.625025) (xy 307.727966 -398.679304) (xy 307.751344 -398.737047) (xy 307.767145 -398.797305)
			(xy 307.775111 -398.859088) (xy 307.77561 -398.890236) (xy 307.775111 -398.921384) (xy 307.767145 -398.983167)
			(xy 307.751344 -399.043425) (xy 307.727966 -399.101168) (xy 307.697397 -399.155447) (xy 307.660137 -399.205371)
			(xy 307.6168 -399.250121) (xy 307.568095 -399.288961) (xy 307.514824 -399.321254) (xy 307.457861 -399.346471)
			(xy 307.39814 -399.364195) (xy 307.336643 -399.374138) (xy 307.27438 -399.376134) (xy 307.212373 -399.370152)
			(xy 307.151639 -399.35629) (xy 307.093177 -399.334776) (xy 307.037946 -399.305962) (xy 306.986854 -399.270322)
			(xy 306.940738 -399.228441) (xy 306.900356 -399.181006) (xy 306.866372 -399.128797) (xy 306.839343 -399.072671)
			(xy 306.819714 -399.01355) (xy 306.807805 -398.952403) (xy 306.803814 -398.890236) (xy 303.375568 -398.890236)
			(xy 303.374987 -398.922965) (xy 303.366134 -398.987822) (xy 303.348648 -399.050902) (xy 303.322846 -399.111061)
			(xy 303.30648 -399.13941) (xy 303.30316 -399.145432) (xy 303.299558 -399.158698) (xy 303.299368 -399.165572)
			(xy 303.299368 -399.451576) (xy 303.298964 -399.461701) (xy 303.291218 -399.48041) (xy 303.276897 -399.494727)
			(xy 303.258185 -399.502467) (xy 303.24806 -399.502884) (xy 302.53178 -399.502884) (xy 302.521654 -399.5025)
			(xy 302.502947 -399.494742) (xy 302.488633 -399.480416) (xy 302.480891 -399.461702) (xy 302.480472 -399.451576)
			(xy 302.480472 -399.165572) (xy 302.480295 -399.158698) (xy 302.476677 -399.145435) (xy 302.47336 -399.13941)
			(xy 302.457004 -399.111055) (xy 302.431199 -399.050898) (xy 302.413706 -398.98782) (xy 302.404843 -398.922965)
			(xy 302.404272 -398.890236) (xy 298.974938 -398.890236) (xy 298.974936 -398.92295) (xy 298.966148 -398.987796)
			(xy 298.948736 -399.050876) (xy 298.923016 -399.111048) (xy 298.906692 -399.13941) (xy 298.903373 -399.145433)
			(xy 298.89977 -399.158698) (xy 298.89958 -399.165572) (xy 298.89958 -399.451576) (xy 298.899159 -399.461731)
			(xy 298.891367 -399.480487) (xy 298.87697 -399.494812) (xy 298.858175 -399.502509) (xy 298.848018 -399.502884)
			(xy 298.131738 -399.502884) (xy 298.121617 -399.502343) (xy 298.102901 -399.494632) (xy 298.088544 -399.480362)
			(xy 298.08072 -399.461694) (xy 298.080176 -399.451576) (xy 298.080176 -399.165572) (xy 298.079998 -399.158698)
			(xy 298.076381 -399.145435) (xy 298.073064 -399.13941) (xy 298.056771 -399.111032) (xy 298.03105 -399.050865)
			(xy 298.013637 -398.98779) (xy 298.00485 -398.922948) (xy 298.004845 -398.857514) (xy 298.013625 -398.792671)
			(xy 298.031029 -398.729593) (xy 298.056743 -398.669423) (xy 298.073064 -398.641062) (xy 298.076389 -398.635042)
			(xy 298.079989 -398.621775) (xy 298.080176 -398.6149) (xy 298.080176 -397.865346) (xy 298.079969 -397.858474)
			(xy 298.076371 -397.845211) (xy 298.073064 -397.839184) (xy 298.056749 -397.810818) (xy 298.03103 -397.750648)
			(xy 298.01362 -397.687571) (xy 298.004835 -397.622727) (xy 298.004834 -397.55729) (xy 296.715947 -397.55729)
			(xy 296.722899 -397.569343) (xy 296.748705 -397.6295) (xy 296.766198 -397.692578) (xy 296.775061 -397.757433)
			(xy 296.775632 -397.790162) (xy 296.775067 -397.822892) (xy 296.766211 -397.88775) (xy 296.74872 -397.95083)
			(xy 296.722913 -398.010988) (xy 296.706544 -398.039336) (xy 296.70322 -398.045356) (xy 296.69962 -398.058623)
			(xy 296.699432 -398.065498) (xy 296.699432 -398.351502) (xy 296.698974 -398.361632) (xy 296.691241 -398.380359)
			(xy 296.676945 -398.394716) (xy 296.658252 -398.40253) (xy 296.648124 -398.403064) (xy 295.931844 -398.403064)
			(xy 295.921688 -398.402642) (xy 295.90293 -398.394854) (xy 295.888604 -398.380456) (xy 295.880909 -398.36166)
			(xy 295.880536 -398.351502) (xy 295.880536 -398.065498) (xy 295.88034 -398.058625) (xy 295.876734 -398.045362)
			(xy 295.873424 -398.039336) (xy 295.857075 -398.010978) (xy 295.831269 -397.950822) (xy 295.813774 -397.887745)
			(xy 295.804909 -397.82289) (xy 295.804336 -397.790162) (xy 294.53163 -397.790162) (xy 294.522763 -397.810836)
			(xy 294.506396 -397.839184) (xy 294.503087 -397.845211) (xy 294.499478 -397.858473) (xy 294.499284 -397.865346)
			(xy 294.499284 -398.6149) (xy 294.499478 -398.621773) (xy 294.503085 -398.635036) (xy 294.506396 -398.641062)
			(xy 294.522746 -398.66942) (xy 294.548552 -398.729576) (xy 294.566046 -398.792653) (xy 294.574911 -398.857508)
			(xy 294.575484 -398.890236) (xy 294.574914 -398.922965) (xy 294.56606 -398.987824) (xy 294.548571 -399.050904)
			(xy 294.522764 -399.111062) (xy 294.506396 -399.13941) (xy 294.503077 -399.145433) (xy 294.499474 -399.158698)
			(xy 294.499284 -399.165572) (xy 294.499284 -399.451576) (xy 294.498864 -399.461699) (xy 294.491121 -399.480405)
			(xy 294.476805 -399.494721) (xy 294.458099 -399.502464) (xy 294.447976 -399.502884) (xy 293.731696 -399.502884)
			(xy 293.721571 -399.502487) (xy 293.702865 -399.494734) (xy 293.68855 -399.480412) (xy 293.680808 -399.461701)
			(xy 293.680388 -399.451576) (xy 293.680388 -399.165572) (xy 293.680208 -399.158698) (xy 293.676592 -399.145435)
			(xy 293.673276 -399.13941) (xy 293.656912 -399.11106) (xy 293.63111 -399.0509) (xy 293.61362 -398.987821)
			(xy 293.604759 -398.922965) (xy 293.604188 -398.890236) (xy 290.174851 -398.890236) (xy 290.174849 -398.92295)
			(xy 290.166062 -398.987796) (xy 290.148651 -399.050876) (xy 290.122931 -399.111048) (xy 290.106608 -399.13941)
			(xy 290.10329 -399.145433) (xy 290.099686 -399.158698) (xy 290.099496 -399.165572) (xy 290.099496 -399.451576)
			(xy 290.099059 -399.461729) (xy 290.09127 -399.480482) (xy 290.076878 -399.494806) (xy 290.058089 -399.502506)
			(xy 290.047934 -399.502884) (xy 289.331654 -399.502884) (xy 289.321527 -399.502412) (xy 289.30281 -399.494673)
			(xy 289.288456 -399.480383) (xy 289.280634 -399.4617) (xy 289.280092 -399.451576) (xy 289.280092 -399.165572)
			(xy 289.279912 -399.158698) (xy 289.276296 -399.145435) (xy 289.27298 -399.13941) (xy 289.256687 -399.111032)
			(xy 289.230964 -399.050865) (xy 289.213551 -398.98779) (xy 289.204763 -398.922948) (xy 289.204759 -398.857513)
			(xy 289.213539 -398.79267) (xy 289.230944 -398.729593) (xy 289.256659 -398.669423) (xy 289.27298 -398.641062)
			(xy 289.276307 -398.635043) (xy 289.279905 -398.621775) (xy 289.280092 -398.6149) (xy 289.280092 -397.865346)
			(xy 289.279883 -397.858474) (xy 289.276287 -397.845211) (xy 289.27298 -397.839184) (xy 289.256665 -397.810819)
			(xy 289.230944 -397.750649) (xy 289.213534 -397.687571) (xy 289.204748 -397.622727) (xy 289.204747 -397.55729)
			(xy 287.915864 -397.55729) (xy 287.922817 -397.569342) (xy 287.948622 -397.6295) (xy 287.966114 -397.692578)
			(xy 287.974977 -397.757433) (xy 287.975548 -397.790162) (xy 287.974981 -397.822891) (xy 287.966125 -397.887749)
			(xy 287.948635 -397.95083) (xy 287.922828 -398.010988) (xy 287.90646 -398.039336) (xy 287.903137 -398.045357)
			(xy 287.899536 -398.058623) (xy 287.899348 -398.065498) (xy 287.899348 -398.351502) (xy 287.898875 -398.36163)
			(xy 287.891144 -398.380354) (xy 287.876853 -398.39471) (xy 287.858166 -398.402527) (xy 287.84804 -398.403064)
			(xy 287.13176 -398.403064) (xy 287.121599 -398.40271) (xy 287.102839 -398.394895) (xy 287.088515 -398.380477)
			(xy 287.080824 -398.361666) (xy 287.080452 -398.351502) (xy 287.080452 -398.065498) (xy 287.080267 -398.058624)
			(xy 287.076655 -398.045361) (xy 287.07334 -398.039336) (xy 287.056993 -398.010977) (xy 287.031185 -397.950821)
			(xy 287.013691 -397.887745) (xy 287.004825 -397.82289) (xy 287.004252 -397.790162) (xy 282.775152 -397.790162)
			(xy 282.775152 -401.690078) (xy 287.004252 -401.690078) (xy 287.004837 -401.657349) (xy 287.013688 -401.592492)
			(xy 287.031173 -401.529412) (xy 287.056974 -401.469253) (xy 287.07334 -401.440904) (xy 287.076649 -401.434876)
			(xy 287.080259 -401.421615) (xy 287.080452 -401.414742) (xy 287.080452 -400.665442) (xy 287.08025 -400.658569)
			(xy 287.076649 -400.645306) (xy 287.07334 -400.63928) (xy 287.05697 -400.610933) (xy 287.031169 -400.550773)
			(xy 287.01368 -400.487693) (xy 287.004821 -400.422835) (xy 287.004252 -400.390106) (xy 287.004804 -400.357376)
			(xy 287.013665 -400.292518) (xy 287.031159 -400.229438) (xy 287.05697 -400.16928) (xy 287.07334 -400.140932)
			(xy 287.076639 -400.134899) (xy 287.080255 -400.121642) (xy 287.080452 -400.11477) (xy 287.080452 -399.828766)
			(xy 287.080899 -399.818636) (xy 287.08864 -399.799911) (xy 287.102939 -399.785556) (xy 287.121632 -399.77774)
			(xy 287.13176 -399.777204) (xy 287.84804 -399.777204) (xy 287.858197 -399.777589) (xy 287.876951 -399.785399)
			(xy 287.891273 -399.799806) (xy 287.898971 -399.818606) (xy 287.899348 -399.828766) (xy 287.899348 -400.11477)
			(xy 287.899545 -400.121643) (xy 287.903149 -400.134906) (xy 287.90646 -400.140932) (xy 287.922834 -400.169276)
			(xy 287.948635 -400.229437) (xy 287.966122 -400.292518) (xy 287.97498 -400.357377) (xy 287.975548 -400.390106)
			(xy 287.974956 -400.422835) (xy 287.966107 -400.487692) (xy 287.948624 -400.550772) (xy 287.922825 -400.610931)
			(xy 287.90646 -400.63928) (xy 287.903157 -400.645311) (xy 287.899543 -400.65857) (xy 287.899348 -400.665442)
			(xy 287.899348 -401.414742) (xy 287.899556 -401.421614) (xy 287.903153 -401.434877) (xy 287.90646 -401.440904)
			(xy 287.922823 -401.469255) (xy 287.948627 -401.529413) (xy 287.966117 -401.592492) (xy 287.974978 -401.657349)
			(xy 287.975548 -401.690078) (xy 287.974988 -401.722808) (xy 287.96613 -401.787666) (xy 287.948638 -401.850746)
			(xy 287.922829 -401.910904) (xy 287.90646 -401.939252) (xy 287.903131 -401.94527) (xy 287.899534 -401.958539)
			(xy 287.899348 -401.965414) (xy 287.899348 -402.251418) (xy 287.898888 -402.261547) (xy 287.891152 -402.280271)
			(xy 287.876858 -402.294627) (xy 287.858167 -402.302444) (xy 287.84804 -402.30298) (xy 287.13176 -402.30298)
			(xy 287.121601 -402.302611) (xy 287.102844 -402.294798) (xy 287.088521 -402.280385) (xy 287.080826 -402.26158)
			(xy 287.080452 -402.251418) (xy 287.080452 -401.965414) (xy 287.080261 -401.958541) (xy 287.076653 -401.945278)
			(xy 287.07334 -401.939252) (xy 287.056959 -401.910911) (xy 287.03116 -401.850749) (xy 287.013675 -401.787667)
			(xy 287.004819 -401.722808) (xy 287.004252 -401.690078) (xy 282.775152 -401.690078) (xy 282.775152 -402.822879)
			(xy 289.204715 -402.822879) (xy 289.204721 -402.757439) (xy 289.213511 -402.692591) (xy 289.230927 -402.629511)
			(xy 289.256653 -402.569339) (xy 289.27298 -402.540978) (xy 289.276301 -402.534956) (xy 289.279903 -402.52169)
			(xy 289.280092 -402.514816) (xy 289.280092 -401.765516) (xy 289.279895 -401.758643) (xy 289.27629 -401.74538)
			(xy 289.27298 -401.739354) (xy 289.25664 -401.711003) (xy 289.230921 -401.65083) (xy 289.213514 -401.587749)
			(xy 289.204731 -401.522902) (xy 289.204734 -401.457464) (xy 289.213521 -401.392618) (xy 289.230933 -401.329538)
			(xy 289.256655 -401.269367) (xy 289.27298 -401.241006) (xy 289.276291 -401.23498) (xy 289.279899 -401.221717)
			(xy 289.280092 -401.214844) (xy 289.280092 -400.92884) (xy 289.280554 -400.918689) (xy 289.288335 -400.89994)
			(xy 289.30272 -400.885615) (xy 289.321502 -400.877913) (xy 289.331654 -400.877532) (xy 290.047934 -400.877532)
			(xy 290.058062 -400.877998) (xy 290.076782 -400.885736) (xy 290.091137 -400.900028) (xy 290.098957 -400.918714)
			(xy 290.099496 -400.92884) (xy 290.099496 -401.214844) (xy 290.09971 -401.221716) (xy 290.103303 -401.234978)
			(xy 290.106608 -401.241006) (xy 290.122912 -401.269377) (xy 290.148629 -401.329546) (xy 290.166037 -401.392623)
			(xy 290.174822 -401.457465) (xy 290.174824 -401.5229) (xy 290.166044 -401.587743) (xy 290.14864 -401.650821)
			(xy 290.122927 -401.710992) (xy 290.116133 -401.7228) (xy 291.404886 -401.7228) (xy 291.404888 -401.657362)
			(xy 291.413674 -401.592517) (xy 291.431085 -401.529437) (xy 291.456805 -401.469265) (xy 291.473128 -401.440904)
			(xy 291.476443 -401.43488) (xy 291.480048 -401.421616) (xy 291.48024 -401.414742) (xy 291.48024 -400.665442)
			(xy 291.480027 -400.65857) (xy 291.476433 -400.645308) (xy 291.473128 -400.63928) (xy 291.456811 -400.610916)
			(xy 291.431094 -400.550745) (xy 291.413685 -400.487667) (xy 291.404901 -400.422823) (xy 291.404901 -400.357387)
			(xy 291.413683 -400.292543) (xy 291.43109 -400.229465) (xy 291.456807 -400.169293) (xy 291.473128 -400.140932)
			(xy 291.476433 -400.134903) (xy 291.480044 -400.121643) (xy 291.48024 -400.11477) (xy 291.48024 -399.828766)
			(xy 291.480706 -399.818606) (xy 291.488492 -399.799835) (xy 291.502866 -399.785471) (xy 291.521641 -399.777698)
			(xy 291.531802 -399.777204) (xy 292.248082 -399.777204) (xy 292.258234 -399.777747) (xy 292.276997 -399.785509)
			(xy 292.291361 -399.79986) (xy 292.299143 -399.818614) (xy 292.299644 -399.828766) (xy 292.299644 -400.11477)
			(xy 292.299842 -400.121643) (xy 292.303445 -400.134906) (xy 292.306756 -400.140932) (xy 292.323083 -400.16929)
			(xy 292.348801 -400.229462) (xy 292.366209 -400.292541) (xy 292.374992 -400.357387) (xy 292.374991 -400.422824)
			(xy 292.366207 -400.487669) (xy 292.348797 -400.550748) (xy 292.323079 -400.610919) (xy 292.306756 -400.63928)
			(xy 292.303453 -400.64531) (xy 292.299839 -400.65857) (xy 292.299644 -400.665442) (xy 292.299644 -401.414742)
			(xy 292.299853 -401.421614) (xy 292.303449 -401.434877) (xy 292.306756 -401.440904) (xy 292.32306 -401.469275)
			(xy 292.348779 -401.529444) (xy 292.36619 -401.592521) (xy 292.374976 -401.657364) (xy 292.374978 -401.722799)
			(xy 292.366197 -401.787642) (xy 292.348792 -401.85072) (xy 292.323077 -401.910891) (xy 292.306756 -401.939252)
			(xy 292.303427 -401.94527) (xy 292.29983 -401.958539) (xy 292.299644 -401.965414) (xy 292.299644 -402.251418)
			(xy 292.299181 -402.261579) (xy 292.291397 -402.280352) (xy 292.277022 -402.294718) (xy 292.258244 -402.302488)
			(xy 292.248082 -402.30298) (xy 291.531802 -402.30298) (xy 291.521647 -402.302465) (xy 291.502881 -402.294695)
			(xy 291.488516 -402.280336) (xy 291.480739 -402.261573) (xy 291.48024 -402.251418) (xy 291.48024 -401.965414)
			(xy 291.480038 -401.958542) (xy 291.476436 -401.945279) (xy 291.473128 -401.939252) (xy 291.456787 -401.910901)
			(xy 291.431072 -401.850727) (xy 291.413667 -401.787646) (xy 291.404886 -401.7228) (xy 290.116133 -401.7228)
			(xy 290.106608 -401.739354) (xy 290.10331 -401.745387) (xy 290.099694 -401.758644) (xy 290.099496 -401.765516)
			(xy 290.099496 -402.514816) (xy 290.099682 -402.52169) (xy 290.103294 -402.534952) (xy 290.106608 -402.540978)
			(xy 290.122888 -402.569362) (xy 290.148607 -402.629529) (xy 290.166018 -402.692602) (xy 290.174806 -402.757442)
			(xy 290.174808 -402.790152) (xy 293.604188 -402.790152) (xy 293.604756 -402.757423) (xy 293.613612 -402.692565)
			(xy 293.631101 -402.629484) (xy 293.656908 -402.569326) (xy 293.673276 -402.540978) (xy 293.676597 -402.534956)
			(xy 293.680199 -402.52169) (xy 293.680388 -402.514816) (xy 293.680388 -401.765516) (xy 293.680191 -401.758643)
			(xy 293.676586 -401.74538) (xy 293.673276 -401.739354) (xy 293.65689 -401.711016) (xy 293.631093 -401.650852)
			(xy 293.61361 -401.587769) (xy 293.604755 -401.52291) (xy 293.604188 -401.49018) (xy 293.604769 -401.457451)
			(xy 293.61362 -401.392593) (xy 293.631106 -401.329513) (xy 293.65691 -401.269355) (xy 293.673276 -401.241006)
			(xy 293.676587 -401.234979) (xy 293.680195 -401.221717) (xy 293.680388 -401.214844) (xy 293.680388 -400.92884)
			(xy 293.680849 -400.918722) (xy 293.688581 -400.900021) (xy 293.702884 -400.885706) (xy 293.721578 -400.877957)
			(xy 293.731696 -400.877532) (xy 294.447976 -400.877532) (xy 294.458101 -400.877936) (xy 294.47681 -400.885682)
			(xy 294.491127 -400.900003) (xy 294.498867 -400.918715) (xy 294.499284 -400.92884) (xy 294.499284 -401.214844)
			(xy 294.4995 -401.221715) (xy 294.503092 -401.234978) (xy 294.506396 -401.241006) (xy 294.522764 -401.269354)
			(xy 294.548565 -401.329514) (xy 294.566054 -401.392594) (xy 294.574914 -401.457451) (xy 294.575484 -401.49018)
			(xy 294.574934 -401.52291) (xy 294.566074 -401.587769) (xy 294.548579 -401.650849) (xy 294.531747 -401.690078)
			(xy 295.804336 -401.690078) (xy 295.804923 -401.657349) (xy 295.813774 -401.592492) (xy 295.831258 -401.529412)
			(xy 295.857059 -401.469253) (xy 295.873424 -401.440904) (xy 295.876739 -401.43488) (xy 295.880344 -401.421616)
			(xy 295.880536 -401.414742) (xy 295.880536 -400.665442) (xy 295.880324 -400.65857) (xy 295.876729 -400.645308)
			(xy 295.873424 -400.63928) (xy 295.857053 -400.610934) (xy 295.831252 -400.550773) (xy 295.813764 -400.487693)
			(xy 295.804905 -400.422835) (xy 295.804336 -400.390106) (xy 295.804891 -400.357376) (xy 295.813751 -400.292518)
			(xy 295.831245 -400.229438) (xy 295.857054 -400.16928) (xy 295.873424 -400.140932) (xy 295.876729 -400.134903)
			(xy 295.88034 -400.121643) (xy 295.880536 -400.11477) (xy 295.880536 -399.828766) (xy 295.880999 -399.818638)
			(xy 295.888737 -399.799916) (xy 295.90303 -399.785561) (xy 295.921718 -399.777743) (xy 295.931844 -399.777204)
			(xy 296.648124 -399.777204) (xy 296.65828 -399.777602) (xy 296.677034 -399.785406) (xy 296.691357 -399.79981)
			(xy 296.699055 -399.818608) (xy 296.699432 -399.828766) (xy 296.699432 -400.11477) (xy 296.699631 -400.121643)
			(xy 296.703234 -400.134906) (xy 296.706544 -400.140932) (xy 296.722917 -400.169277) (xy 296.748718 -400.229438)
			(xy 296.766206 -400.292519) (xy 296.775064 -400.357377) (xy 296.775632 -400.390106) (xy 296.775042 -400.422835)
			(xy 296.766193 -400.487692) (xy 296.748709 -400.550772) (xy 296.722909 -400.610931) (xy 296.706544 -400.63928)
			(xy 296.70324 -400.64531) (xy 296.699627 -400.65857) (xy 296.699432 -400.665442) (xy 296.699432 -401.414742)
			(xy 296.699642 -401.421614) (xy 296.703238 -401.434877) (xy 296.706544 -401.440904) (xy 296.722906 -401.469255)
			(xy 296.74871 -401.529414) (xy 296.766201 -401.592493) (xy 296.775062 -401.657349) (xy 296.775632 -401.690078)
			(xy 296.775075 -401.722808) (xy 296.766216 -401.787666) (xy 296.748723 -401.850746) (xy 296.722914 -401.910904)
			(xy 296.706544 -401.939252) (xy 296.703214 -401.945269) (xy 296.699618 -401.958539) (xy 296.699432 -401.965414)
			(xy 296.699432 -402.251418) (xy 296.698988 -402.261549) (xy 296.691249 -402.280276) (xy 296.676949 -402.294633)
			(xy 296.658253 -402.302447) (xy 296.648124 -402.30298) (xy 295.931844 -402.30298) (xy 295.92169 -402.302542)
			(xy 295.902935 -402.294757) (xy 295.888609 -402.280365) (xy 295.880912 -402.261574) (xy 295.880536 -402.251418)
			(xy 295.880536 -401.965414) (xy 295.880334 -401.958542) (xy 295.876732 -401.945279) (xy 295.873424 -401.939252)
			(xy 295.857042 -401.910912) (xy 295.831243 -401.850749) (xy 295.813758 -401.787667) (xy 295.804903 -401.722808)
			(xy 295.804336 -401.690078) (xy 294.531747 -401.690078) (xy 294.522767 -401.711007) (xy 294.506396 -401.739354)
			(xy 294.503097 -401.745386) (xy 294.499482 -401.758644) (xy 294.499284 -401.765516) (xy 294.499284 -402.514816)
			(xy 294.499472 -402.52169) (xy 294.503083 -402.534952) (xy 294.506396 -402.540978) (xy 294.522752 -402.569332)
			(xy 294.548557 -402.62949) (xy 294.566049 -402.692568) (xy 294.574912 -402.757423) (xy 294.575484 -402.790152)
			(xy 294.574921 -402.822879) (xy 298.004802 -402.822879) (xy 298.004807 -402.757439) (xy 298.013597 -402.692591)
			(xy 298.031012 -402.629511) (xy 298.056738 -402.569339) (xy 298.073064 -402.540978) (xy 298.076384 -402.534956)
			(xy 298.079986 -402.52169) (xy 298.080176 -402.514816) (xy 298.080176 -401.765516) (xy 298.079981 -401.758643)
			(xy 298.076375 -401.74538) (xy 298.073064 -401.739354) (xy 298.056724 -401.711002) (xy 298.031007 -401.650829)
			(xy 298.0136 -401.587749) (xy 298.004818 -401.522902) (xy 298.00482 -401.457464) (xy 298.013606 -401.392618)
			(xy 298.031018 -401.329538) (xy 298.05674 -401.269367) (xy 298.073064 -401.241006) (xy 298.076374 -401.234979)
			(xy 298.079983 -401.221717) (xy 298.080176 -401.214844) (xy 298.080176 -400.92884) (xy 298.080654 -400.918691)
			(xy 298.088432 -400.899945) (xy 298.102811 -400.885621) (xy 298.121588 -400.877915) (xy 298.131738 -400.877532)
			(xy 298.848018 -400.877532) (xy 298.858145 -400.878011) (xy 298.876865 -400.885744) (xy 298.89122 -400.900032)
			(xy 298.89904 -400.918716) (xy 298.89958 -400.92884) (xy 298.89958 -401.214844) (xy 298.899796 -401.221715)
			(xy 298.903388 -401.234978) (xy 298.906692 -401.241006) (xy 298.922996 -401.269377) (xy 298.948714 -401.329546)
			(xy 298.966123 -401.392623) (xy 298.974908 -401.457465) (xy 298.97491 -401.5229) (xy 298.96613 -401.587743)
			(xy 298.948725 -401.650821) (xy 298.931949 -401.690078) (xy 300.204124 -401.690078) (xy 300.204699 -401.657349)
			(xy 300.213552 -401.592491) (xy 300.231039 -401.52941) (xy 300.256844 -401.469252) (xy 300.273212 -401.440904)
			(xy 300.276526 -401.434879) (xy 300.280132 -401.421616) (xy 300.280324 -401.414742) (xy 300.280324 -400.665442)
			(xy 300.280113 -400.65857) (xy 300.276518 -400.645307) (xy 300.273212 -400.63928) (xy 300.25684 -400.610934)
			(xy 300.231039 -400.550774) (xy 300.213551 -400.487693) (xy 300.204693 -400.422835) (xy 300.204124 -400.390106)
			(xy 300.204667 -400.357376) (xy 300.213529 -400.292516) (xy 300.231026 -400.229436) (xy 300.25684 -400.169279)
			(xy 300.273212 -400.140932) (xy 300.276516 -400.134902) (xy 300.280128 -400.121642) (xy 300.280324 -400.11477)
			(xy 300.280324 -399.828766) (xy 300.280798 -399.818639) (xy 300.288534 -399.79992) (xy 300.302824 -399.785566)
			(xy 300.321507 -399.777745) (xy 300.331632 -399.777204) (xy 301.047912 -399.777204) (xy 301.058067 -399.777612)
			(xy 301.076821 -399.785412) (xy 301.091144 -399.799813) (xy 301.098843 -399.818608) (xy 301.09922 -399.828766)
			(xy 301.09922 -400.11477) (xy 301.099421 -400.121643) (xy 301.103023 -400.134905) (xy 301.106332 -400.140932)
			(xy 301.122704 -400.169278) (xy 301.148506 -400.229438) (xy 301.165994 -400.292519) (xy 301.174852 -400.357377)
			(xy 301.17542 -400.390106) (xy 304.603666 -400.390106) (xy 304.607657 -400.327939) (xy 304.619566 -400.266792)
			(xy 304.639195 -400.207671) (xy 304.666224 -400.151545) (xy 304.700208 -400.099336) (xy 304.74059 -400.051901)
			(xy 304.786706 -400.01002) (xy 304.837798 -399.97438) (xy 304.893029 -399.945566) (xy 304.951491 -399.924052)
			(xy 305.012225 -399.91019) (xy 305.074232 -399.904208) (xy 305.136495 -399.906204) (xy 305.197992 -399.916147)
			(xy 305.257713 -399.933871) (xy 305.314676 -399.959088) (xy 305.367947 -399.991381) (xy 305.416652 -400.030221)
			(xy 305.459989 -400.074971) (xy 305.497249 -400.124895) (xy 305.527818 -400.179174) (xy 305.551196 -400.236917)
			(xy 305.566997 -400.297175) (xy 305.574963 -400.358958) (xy 305.575462 -400.390106) (xy 305.574963 -400.421254)
			(xy 305.566997 -400.483037) (xy 305.551196 -400.543295) (xy 305.527818 -400.601038) (xy 305.497249 -400.655317)
			(xy 305.459989 -400.705241) (xy 305.416652 -400.749991) (xy 305.367947 -400.788831) (xy 305.314676 -400.821124)
			(xy 305.257713 -400.846341) (xy 305.197992 -400.864065) (xy 305.136495 -400.874008) (xy 305.074232 -400.876004)
			(xy 305.012225 -400.870022) (xy 304.951491 -400.85616) (xy 304.893029 -400.834646) (xy 304.837798 -400.805832)
			(xy 304.786706 -400.770192) (xy 304.74059 -400.728311) (xy 304.700208 -400.680876) (xy 304.666224 -400.628667)
			(xy 304.639195 -400.572541) (xy 304.619566 -400.51342) (xy 304.607657 -400.452273) (xy 304.603666 -400.390106)
			(xy 301.17542 -400.390106) (xy 301.174832 -400.422835) (xy 301.165982 -400.487692) (xy 301.148498 -400.550772)
			(xy 301.122697 -400.610931) (xy 301.106332 -400.63928) (xy 301.103027 -400.645309) (xy 301.099415 -400.658569)
			(xy 301.09922 -400.665442) (xy 301.09922 -401.414742) (xy 301.099432 -401.421614) (xy 301.103026 -401.434877)
			(xy 301.106332 -401.440904) (xy 301.122693 -401.469256) (xy 301.148497 -401.529414) (xy 301.165989 -401.592493)
			(xy 301.17485 -401.657349) (xy 301.17542 -401.690078) (xy 301.174864 -401.722808) (xy 301.166005 -401.787666)
			(xy 301.148512 -401.850747) (xy 301.122702 -401.910904) (xy 301.106332 -401.939252) (xy 301.103001 -401.945269)
			(xy 301.099406 -401.958539) (xy 301.09922 -401.965414) (xy 301.09922 -402.251418) (xy 301.098787 -402.261551)
			(xy 301.091046 -402.28028) (xy 301.076743 -402.294637) (xy 301.058043 -402.302449) (xy 301.047912 -402.30298)
			(xy 300.331632 -402.30298) (xy 300.321477 -402.302552) (xy 300.302722 -402.294763) (xy 300.288396 -402.280368)
			(xy 300.280699 -402.261575) (xy 300.280324 -402.251418) (xy 300.280324 -401.965414) (xy 300.280124 -401.958541)
			(xy 300.276521 -401.945279) (xy 300.273212 -401.939252) (xy 300.256828 -401.910913) (xy 300.231031 -401.85075)
			(xy 300.213546 -401.787667) (xy 300.204691 -401.722808) (xy 300.204124 -401.690078) (xy 298.931949 -401.690078)
			(xy 298.923012 -401.710992) (xy 298.906692 -401.739354) (xy 298.903393 -401.745386) (xy 298.899778 -401.758644)
			(xy 298.89958 -401.765516) (xy 298.89958 -402.514816) (xy 298.899768 -402.521689) (xy 298.903379 -402.534952)
			(xy 298.906692 -402.540978) (xy 298.922973 -402.569362) (xy 298.948692 -402.629528) (xy 298.966104 -402.692602)
			(xy 298.974892 -402.757442) (xy 298.974894 -402.790152) (xy 302.404272 -402.790152) (xy 302.404842 -402.757423)
			(xy 302.413697 -402.692565) (xy 302.431186 -402.629485) (xy 302.456992 -402.569326) (xy 302.47336 -402.540978)
			(xy 302.476679 -402.534956) (xy 302.480282 -402.52169) (xy 302.480472 -402.514816) (xy 302.480472 -401.765516)
			(xy 302.480277 -401.758643) (xy 302.476671 -401.74538) (xy 302.47336 -401.739354) (xy 302.456982 -401.711012)
			(xy 302.431182 -401.65085) (xy 302.413695 -401.587768) (xy 302.40484 -401.52291) (xy 302.404272 -401.49018)
			(xy 302.404855 -401.457451) (xy 302.413706 -401.392594) (xy 302.431192 -401.329514) (xy 302.456994 -401.269355)
			(xy 302.47336 -401.241006) (xy 302.476669 -401.234979) (xy 302.480279 -401.221717) (xy 302.480472 -401.214844)
			(xy 302.480472 -400.92884) (xy 302.480948 -400.918724) (xy 302.488678 -400.900026) (xy 302.502976 -400.885712)
			(xy 302.521664 -400.87796) (xy 302.53178 -400.877532) (xy 303.24806 -400.877532) (xy 303.258184 -400.87795)
			(xy 303.276893 -400.885691) (xy 303.291209 -400.900007) (xy 303.29895 -400.918716) (xy 303.299368 -400.92884)
			(xy 303.299368 -401.214844) (xy 303.299585 -401.221715) (xy 303.303177 -401.234978) (xy 303.30648 -401.241006)
			(xy 303.322846 -401.269355) (xy 303.348648 -401.329514) (xy 303.366138 -401.392594) (xy 303.374998 -401.457451)
			(xy 303.375568 -401.49018) (xy 303.375006 -401.52291) (xy 303.366148 -401.587768) (xy 303.348656 -401.650848)
			(xy 303.331827 -401.690078) (xy 304.603666 -401.690078) (xy 304.607657 -401.627911) (xy 304.619566 -401.566764)
			(xy 304.639195 -401.507643) (xy 304.666224 -401.451517) (xy 304.700208 -401.399308) (xy 304.74059 -401.351873)
			(xy 304.786706 -401.309992) (xy 304.837798 -401.274352) (xy 304.893029 -401.245538) (xy 304.951491 -401.224024)
			(xy 305.012225 -401.210162) (xy 305.074232 -401.20418) (xy 305.136495 -401.206176) (xy 305.197992 -401.216119)
			(xy 305.257713 -401.233843) (xy 305.314676 -401.25906) (xy 305.367947 -401.291353) (xy 305.416652 -401.330193)
			(xy 305.459989 -401.374943) (xy 305.497249 -401.424867) (xy 305.527818 -401.479146) (xy 305.532285 -401.49018)
			(xy 306.803814 -401.49018) (xy 306.807805 -401.428013) (xy 306.819714 -401.366866) (xy 306.839343 -401.307745)
			(xy 306.866372 -401.251619) (xy 306.900356 -401.19941) (xy 306.940738 -401.151975) (xy 306.986854 -401.110094)
			(xy 307.037946 -401.074454) (xy 307.093177 -401.04564) (xy 307.151639 -401.024126) (xy 307.212373 -401.010264)
			(xy 307.27438 -401.004282) (xy 307.336643 -401.006278) (xy 307.39814 -401.016221) (xy 307.457861 -401.033945)
			(xy 307.514824 -401.059162) (xy 307.568095 -401.091455) (xy 307.6168 -401.130295) (xy 307.660137 -401.175045)
			(xy 307.697397 -401.224969) (xy 307.727966 -401.279248) (xy 307.751344 -401.336991) (xy 307.767145 -401.397249)
			(xy 307.775111 -401.459032) (xy 307.77561 -401.49018) (xy 307.775111 -401.521328) (xy 307.767145 -401.583111)
			(xy 307.751344 -401.643369) (xy 307.727966 -401.701112) (xy 307.697397 -401.755391) (xy 307.660137 -401.805315)
			(xy 307.6168 -401.850065) (xy 307.568095 -401.888905) (xy 307.514824 -401.921198) (xy 307.457861 -401.946415)
			(xy 307.39814 -401.964139) (xy 307.336643 -401.974082) (xy 307.27438 -401.976078) (xy 307.212373 -401.970096)
			(xy 307.151639 -401.956234) (xy 307.093177 -401.93472) (xy 307.037946 -401.905906) (xy 306.986854 -401.870266)
			(xy 306.940738 -401.828385) (xy 306.900356 -401.78095) (xy 306.866372 -401.728741) (xy 306.839343 -401.672615)
			(xy 306.819714 -401.613494) (xy 306.807805 -401.552347) (xy 306.803814 -401.49018) (xy 305.532285 -401.49018)
			(xy 305.551196 -401.536889) (xy 305.566997 -401.597147) (xy 305.574963 -401.65893) (xy 305.575462 -401.690078)
			(xy 305.574963 -401.721226) (xy 305.566997 -401.783009) (xy 305.551196 -401.843267) (xy 305.527818 -401.90101)
			(xy 305.497249 -401.955289) (xy 305.459989 -402.005213) (xy 305.416652 -402.049963) (xy 305.367947 -402.088803)
			(xy 305.314676 -402.121096) (xy 305.257713 -402.146313) (xy 305.197992 -402.164037) (xy 305.136495 -402.17398)
			(xy 305.074232 -402.175976) (xy 305.012225 -402.169994) (xy 304.951491 -402.156132) (xy 304.893029 -402.134618)
			(xy 304.837798 -402.105804) (xy 304.786706 -402.070164) (xy 304.74059 -402.028283) (xy 304.700208 -401.980848)
			(xy 304.666224 -401.928639) (xy 304.639195 -401.872513) (xy 304.619566 -401.813392) (xy 304.607657 -401.752245)
			(xy 304.603666 -401.690078) (xy 303.331827 -401.690078) (xy 303.322849 -401.711006) (xy 303.30648 -401.739354)
			(xy 303.30318 -401.745386) (xy 303.299565 -401.758644) (xy 303.299368 -401.765516) (xy 303.299368 -402.514816)
			(xy 303.299558 -402.521689) (xy 303.303168 -402.534952) (xy 303.30648 -402.540978) (xy 303.322835 -402.569333)
			(xy 303.34864 -402.62949) (xy 303.366132 -402.692568) (xy 303.374996 -402.757423) (xy 303.375568 -402.790152)
			(xy 306.803814 -402.790152) (xy 306.807805 -402.727985) (xy 306.819714 -402.666838) (xy 306.839343 -402.607717)
			(xy 306.866372 -402.551591) (xy 306.900356 -402.499382) (xy 306.940738 -402.451947) (xy 306.986854 -402.410066)
			(xy 307.037946 -402.374426) (xy 307.093177 -402.345612) (xy 307.151639 -402.324098) (xy 307.212373 -402.310236)
			(xy 307.27438 -402.304254) (xy 307.336643 -402.30625) (xy 307.39814 -402.316193) (xy 307.457861 -402.333917)
			(xy 307.514824 -402.359134) (xy 307.568095 -402.391427) (xy 307.6168 -402.430267) (xy 307.660137 -402.475017)
			(xy 307.697397 -402.524941) (xy 307.727966 -402.57922) (xy 307.751344 -402.636963) (xy 307.767145 -402.697221)
			(xy 307.775111 -402.759004) (xy 307.77561 -402.790152) (xy 307.775111 -402.8213) (xy 307.767145 -402.883083)
			(xy 307.751344 -402.943341) (xy 307.727966 -403.001084) (xy 307.697397 -403.055363) (xy 307.660137 -403.105287)
			(xy 307.6168 -403.150037) (xy 307.568095 -403.188877) (xy 307.514824 -403.22117) (xy 307.457861 -403.246387)
			(xy 307.39814 -403.264111) (xy 307.336643 -403.274054) (xy 307.27438 -403.27605) (xy 307.212373 -403.270068)
			(xy 307.151639 -403.256206) (xy 307.093177 -403.234692) (xy 307.037946 -403.205878) (xy 306.986854 -403.170238)
			(xy 306.940738 -403.128357) (xy 306.900356 -403.080922) (xy 306.866372 -403.028713) (xy 306.839343 -402.972587)
			(xy 306.819714 -402.913466) (xy 306.807805 -402.852319) (xy 306.803814 -402.790152) (xy 303.375568 -402.790152)
			(xy 303.374994 -402.822881) (xy 303.366139 -402.887739) (xy 303.348651 -402.950819) (xy 303.322847 -403.010977)
			(xy 303.30648 -403.039326) (xy 303.303155 -403.045345) (xy 303.299556 -403.058613) (xy 303.299368 -403.065488)
			(xy 303.299368 -403.351492) (xy 303.298977 -403.361618) (xy 303.291225 -403.380328) (xy 303.276901 -403.394643)
			(xy 303.258186 -403.402383) (xy 303.24806 -403.4028) (xy 302.53178 -403.4028) (xy 302.52167 -403.402331)
			(xy 302.502991 -403.394587) (xy 302.488697 -403.380285) (xy 302.480963 -403.361602) (xy 302.480472 -403.351492)
			(xy 302.480472 -403.065488) (xy 302.480288 -403.058614) (xy 302.476675 -403.045351) (xy 302.47336 -403.039326)
			(xy 302.457011 -403.010968) (xy 302.431203 -402.950812) (xy 302.413709 -402.887735) (xy 302.404844 -402.82288)
			(xy 302.404272 -402.790152) (xy 298.974894 -402.790152) (xy 298.974897 -402.822875) (xy 298.96612 -402.887717)
			(xy 298.94872 -402.950794) (xy 298.92301 -403.010964) (xy 298.906692 -403.039326) (xy 298.903367 -403.045346)
			(xy 298.899768 -403.058613) (xy 298.89958 -403.065488) (xy 298.89958 -403.351492) (xy 298.899171 -403.361648)
			(xy 298.891375 -403.380404) (xy 298.876974 -403.394729) (xy 298.858176 -403.402425) (xy 298.848018 -403.4028)
			(xy 298.131738 -403.4028) (xy 298.121619 -403.402243) (xy 298.102906 -403.394535) (xy 298.08855 -403.380271)
			(xy 298.080722 -403.361608) (xy 298.080176 -403.351492) (xy 298.080176 -403.065488) (xy 298.079991 -403.058614)
			(xy 298.076378 -403.045351) (xy 298.073064 -403.039326) (xy 298.0567 -403.010987) (xy 298.030985 -402.950811)
			(xy 298.013581 -402.887728) (xy 298.004802 -402.822879) (xy 294.574921 -402.822879) (xy 294.574921 -402.822882)
			(xy 294.566065 -402.88774) (xy 294.548574 -402.95082) (xy 294.522765 -403.010978) (xy 294.506396 -403.039326)
			(xy 294.503072 -403.045346) (xy 294.499472 -403.058613) (xy 294.499284 -403.065488) (xy 294.499284 -403.351492)
			(xy 294.498877 -403.361616) (xy 294.491129 -403.380322) (xy 294.476809 -403.394638) (xy 294.4581 -403.40238)
			(xy 294.447976 -403.4028) (xy 293.731696 -403.4028) (xy 293.721573 -403.402387) (xy 293.70287 -403.394638)
			(xy 293.688556 -403.38032) (xy 293.68081 -403.361615) (xy 293.680388 -403.351492) (xy 293.680388 -403.065488)
			(xy 293.680202 -403.058614) (xy 293.67659 -403.045351) (xy 293.673276 -403.039326) (xy 293.656918 -403.010972)
			(xy 293.631115 -402.950814) (xy 293.613623 -402.887736) (xy 293.60476 -402.822881) (xy 293.604188 -402.790152)
			(xy 290.174808 -402.790152) (xy 290.174811 -402.822875) (xy 290.166034 -402.887717) (xy 290.148634 -402.950794)
			(xy 290.122926 -403.010964) (xy 290.106608 -403.039326) (xy 290.103285 -403.045346) (xy 290.099684 -403.058613)
			(xy 290.099496 -403.065488) (xy 290.099496 -403.351492) (xy 290.099072 -403.361646) (xy 290.091278 -403.380399)
			(xy 290.076882 -403.394723) (xy 290.05809 -403.402422) (xy 290.047934 -403.4028) (xy 289.331654 -403.4028)
			(xy 289.321529 -403.402312) (xy 289.302815 -403.394577) (xy 289.288461 -403.380292) (xy 289.280637 -403.361614)
			(xy 289.280092 -403.351492) (xy 289.280092 -403.065488) (xy 289.279906 -403.058614) (xy 289.276294 -403.045351)
			(xy 289.27298 -403.039326) (xy 289.256616 -403.010988) (xy 289.2309 -402.950812) (xy 289.213495 -402.887728)
			(xy 289.204715 -402.822879) (xy 282.775152 -402.822879) (xy 282.775152 -405.589994) (xy 287.004252 -405.589994)
			(xy 287.004844 -405.557265) (xy 287.013693 -405.492408) (xy 287.031176 -405.429328) (xy 287.056975 -405.369169)
			(xy 287.07334 -405.34082) (xy 287.076643 -405.334789) (xy 287.080257 -405.32153) (xy 287.080452 -405.314658)
			(xy 287.080452 -404.565358) (xy 287.080244 -404.558486) (xy 287.076647 -404.545223) (xy 287.07334 -404.539196)
			(xy 287.056977 -404.510845) (xy 287.031173 -404.450687) (xy 287.013683 -404.387608) (xy 287.004822 -404.322751)
			(xy 287.004252 -404.290022) (xy 287.004812 -404.257292) (xy 287.01367 -404.192434) (xy 287.031162 -404.129354)
			(xy 287.056971 -404.069196) (xy 287.07334 -404.040848) (xy 287.076669 -404.03483) (xy 287.080266 -404.021561)
			(xy 287.080452 -404.014686) (xy 287.080452 -403.728682) (xy 287.080912 -403.718553) (xy 287.088648 -403.699829)
			(xy 287.102942 -403.685473) (xy 287.121633 -403.677656) (xy 287.13176 -403.67712) (xy 287.84804 -403.67712)
			(xy 287.858199 -403.677489) (xy 287.876956 -403.685302) (xy 287.891279 -403.699715) (xy 287.898974 -403.71852)
			(xy 287.899348 -403.728682) (xy 287.899348 -404.014686) (xy 287.899539 -404.021559) (xy 287.903147 -404.034822)
			(xy 287.90646 -404.040848) (xy 287.922841 -404.069189) (xy 287.94864 -404.129351) (xy 287.966125 -404.192433)
			(xy 287.974981 -404.257292) (xy 287.975548 -404.290022) (xy 287.974963 -404.322751) (xy 287.966112 -404.387608)
			(xy 287.948627 -404.450688) (xy 287.922826 -404.510847) (xy 287.90646 -404.539196) (xy 287.903151 -404.545224)
			(xy 287.899541 -404.558485) (xy 287.899348 -404.565358) (xy 287.899348 -405.314658) (xy 287.89955 -405.321531)
			(xy 287.903151 -405.334794) (xy 287.90646 -405.34082) (xy 287.92283 -405.369167) (xy 287.948631 -405.429327)
			(xy 287.96612 -405.492407) (xy 287.974979 -405.557265) (xy 287.975548 -405.589994) (xy 287.974996 -405.622724)
			(xy 287.966135 -405.687582) (xy 287.948641 -405.750662) (xy 287.92283 -405.81082) (xy 287.90646 -405.839168)
			(xy 287.903161 -405.845201) (xy 287.899545 -405.858458) (xy 287.899348 -405.86533) (xy 287.899348 -406.151334)
			(xy 287.898901 -406.161464) (xy 287.89116 -406.180189) (xy 287.876861 -406.194544) (xy 287.858168 -406.20236)
			(xy 287.84804 -406.202896) (xy 287.13176 -406.202896) (xy 287.121603 -406.202511) (xy 287.102849 -406.194701)
			(xy 287.088527 -406.180294) (xy 287.080829 -406.161494) (xy 287.080452 -406.151334) (xy 287.080452 -405.86533)
			(xy 287.080255 -405.858457) (xy 287.076651 -405.845194) (xy 287.07334 -405.839168) (xy 287.056966 -405.810824)
			(xy 287.031165 -405.750663) (xy 287.013678 -405.687582) (xy 287.00482 -405.622723) (xy 287.004252 -405.589994)
			(xy 282.775152 -405.589994) (xy 282.775152 -406.722792) (xy 289.204725 -406.722792) (xy 289.204728 -406.657353)
			(xy 289.213517 -406.592506) (xy 289.23093 -406.529426) (xy 289.256654 -406.469255) (xy 289.27298 -406.440894)
			(xy 289.276295 -406.43487) (xy 289.279901 -406.421606) (xy 289.280092 -406.414732) (xy 289.280092 -405.665432)
			(xy 289.279889 -405.65856) (xy 289.276288 -405.645297) (xy 289.27298 -405.63927) (xy 289.256653 -405.610911)
			(xy 289.230934 -405.55074) (xy 289.213524 -405.487661) (xy 289.204741 -405.422815) (xy 289.204741 -405.357378)
			(xy 289.213526 -405.292533) (xy 289.230936 -405.229454) (xy 289.256656 -405.169283) (xy 289.27298 -405.140922)
			(xy 289.276286 -405.134893) (xy 289.279897 -405.121633) (xy 289.280092 -405.11476) (xy 289.280092 -404.828756)
			(xy 289.280486 -404.8186) (xy 289.288294 -404.799848) (xy 289.302699 -404.785527) (xy 289.321496 -404.777827)
			(xy 289.331654 -404.777448) (xy 290.047934 -404.777448) (xy 290.058064 -404.777899) (xy 290.076787 -404.785639)
			(xy 290.091143 -404.799936) (xy 290.098959 -404.818628) (xy 290.099496 -404.828756) (xy 290.099496 -405.11476)
			(xy 290.099704 -405.121632) (xy 290.103301 -405.134895) (xy 290.106608 -405.140922) (xy 290.122925 -405.169286)
			(xy 290.148641 -405.229457) (xy 290.166048 -405.292535) (xy 290.174831 -405.357379) (xy 290.174831 -405.422814)
			(xy 290.166049 -405.487658) (xy 290.148643 -405.550737) (xy 290.122929 -405.610908) (xy 290.116136 -405.622713)
			(xy 291.404895 -405.622713) (xy 291.404895 -405.557276) (xy 291.413679 -405.492432) (xy 291.431088 -405.429353)
			(xy 291.456806 -405.369181) (xy 291.473128 -405.34082) (xy 291.476438 -405.334793) (xy 291.480046 -405.321531)
			(xy 291.48024 -405.314658) (xy 291.48024 -404.565358) (xy 291.480021 -404.558487) (xy 291.476431 -404.545224)
			(xy 291.473128 -404.539196) (xy 291.456825 -404.510824) (xy 291.431106 -404.450655) (xy 291.413696 -404.387579)
			(xy 291.404911 -404.322736) (xy 291.404908 -404.257301) (xy 291.413689 -404.192458) (xy 291.431093 -404.12938)
			(xy 291.456808 -404.069209) (xy 291.473128 -404.040848) (xy 291.476463 -404.034833) (xy 291.480055 -404.021562)
			(xy 291.48024 -404.014686) (xy 291.48024 -403.728682) (xy 291.480718 -403.718523) (xy 291.488499 -403.699753)
			(xy 291.50287 -403.685388) (xy 291.521643 -403.677615) (xy 291.531802 -403.67712) (xy 292.248082 -403.67712)
			(xy 292.258236 -403.677648) (xy 292.277002 -403.685413) (xy 292.291367 -403.699768) (xy 292.299145 -403.718528)
			(xy 292.299644 -403.728682) (xy 292.299644 -404.014686) (xy 292.299836 -404.021559) (xy 292.303444 -404.034822)
			(xy 292.306756 -404.040848) (xy 292.323097 -404.069199) (xy 292.348813 -404.129372) (xy 292.366219 -404.192453)
			(xy 292.375001 -404.2573) (xy 292.374998 -404.322738) (xy 292.366212 -404.387584) (xy 292.348801 -404.450663)
			(xy 292.32308 -404.510835) (xy 292.306756 -404.539196) (xy 292.303447 -404.545224) (xy 292.299837 -404.558485)
			(xy 292.299644 -404.565358) (xy 292.299644 -405.314658) (xy 292.299846 -405.321531) (xy 292.303447 -405.334794)
			(xy 292.306756 -405.34082) (xy 292.323073 -405.369184) (xy 292.348792 -405.429354) (xy 292.366201 -405.492433)
			(xy 292.374985 -405.557277) (xy 292.374985 -405.622713) (xy 292.366203 -405.687557) (xy 292.348795 -405.750636)
			(xy 292.323078 -405.810807) (xy 292.306756 -405.839168) (xy 292.303457 -405.8452) (xy 292.299841 -405.858458)
			(xy 292.299644 -405.86533) (xy 292.299644 -406.151334) (xy 292.299194 -406.161496) (xy 292.291405 -406.18027)
			(xy 292.277026 -406.194634) (xy 292.258245 -406.202404) (xy 292.248082 -406.202896) (xy 291.531802 -406.202896)
			(xy 291.521649 -406.202366) (xy 291.502886 -406.194598) (xy 291.488522 -406.180244) (xy 291.480741 -406.161487)
			(xy 291.48024 -406.151334) (xy 291.48024 -405.86533) (xy 291.480032 -405.858458) (xy 291.476434 -405.845195)
			(xy 291.473128 -405.839168) (xy 291.456801 -405.810809) (xy 291.431084 -405.750638) (xy 291.413677 -405.687558)
			(xy 291.404895 -405.622713) (xy 290.116136 -405.622713) (xy 290.106608 -405.63927) (xy 290.103304 -405.6453)
			(xy 290.099692 -405.65856) (xy 290.099496 -405.665432) (xy 290.099496 -406.414732) (xy 290.099676 -406.421606)
			(xy 290.103292 -406.434869) (xy 290.106608 -406.440894) (xy 290.122902 -406.469271) (xy 290.148619 -406.529439)
			(xy 290.166029 -406.592514) (xy 290.174815 -406.657356) (xy 290.174816 -406.690068) (xy 293.604188 -406.690068)
			(xy 293.604764 -406.657339) (xy 293.613617 -406.592481) (xy 293.631104 -406.529401) (xy 293.656909 -406.469242)
			(xy 293.673276 -406.440894) (xy 293.676591 -406.43487) (xy 293.680197 -406.421606) (xy 293.680388 -406.414732)
			(xy 293.680388 -405.665432) (xy 293.680185 -405.65856) (xy 293.676584 -405.645297) (xy 293.673276 -405.63927)
			(xy 293.656896 -405.610929) (xy 293.631098 -405.550766) (xy 293.613613 -405.487684) (xy 293.604756 -405.422826)
			(xy 293.604188 -405.390096) (xy 293.604731 -405.357366) (xy 293.613594 -405.292507) (xy 293.631091 -405.229426)
			(xy 293.656904 -405.169269) (xy 293.673276 -405.140922) (xy 293.676581 -405.134893) (xy 293.680193 -405.121633)
			(xy 293.680388 -405.11476) (xy 293.680388 -404.828756) (xy 293.680849 -404.818646) (xy 293.688599 -404.799969)
			(xy 293.702903 -404.785676) (xy 293.721586 -404.777941) (xy 293.731696 -404.777448) (xy 294.447976 -404.777448)
			(xy 294.458077 -404.778003) (xy 294.476745 -404.785723) (xy 294.491038 -404.799998) (xy 294.498783 -404.818656)
			(xy 294.499284 -404.828756) (xy 294.499284 -405.11476) (xy 294.499493 -405.121632) (xy 294.50309 -405.134895)
			(xy 294.506396 -405.140922) (xy 294.52277 -405.169267) (xy 294.54857 -405.229428) (xy 294.566057 -405.292509)
			(xy 294.574915 -405.357367) (xy 294.575484 -405.390096) (xy 294.574941 -405.422826) (xy 294.566079 -405.487685)
			(xy 294.548582 -405.550766) (xy 294.531749 -405.589994) (xy 295.804336 -405.589994) (xy 295.80493 -405.557266)
			(xy 295.813779 -405.492409) (xy 295.831261 -405.429329) (xy 295.85706 -405.369169) (xy 295.873424 -405.34082)
			(xy 295.876733 -405.334793) (xy 295.880342 -405.321531) (xy 295.880536 -405.314658) (xy 295.880536 -404.565358)
			(xy 295.880318 -404.558487) (xy 295.876727 -404.545224) (xy 295.873424 -404.539196) (xy 295.857059 -404.510846)
			(xy 295.831257 -404.450687) (xy 295.813767 -404.387608) (xy 295.804906 -404.322751) (xy 295.804336 -404.290022)
			(xy 295.804898 -404.257292) (xy 295.813756 -404.192434) (xy 295.831248 -404.129354) (xy 295.857055 -404.069196)
			(xy 295.873424 -404.040848) (xy 295.876759 -404.034833) (xy 295.880351 -404.021562) (xy 295.880536 -404.014686)
			(xy 295.880536 -403.728682) (xy 295.881011 -403.718555) (xy 295.888744 -403.699834) (xy 295.903034 -403.685478)
			(xy 295.921719 -403.677659) (xy 295.931844 -403.67712) (xy 296.648124 -403.67712) (xy 296.658282 -403.677502)
			(xy 296.677039 -403.685309) (xy 296.691362 -403.699718) (xy 296.699058 -403.718521) (xy 296.699432 -403.728682)
			(xy 296.699432 -404.014686) (xy 296.699625 -404.021559) (xy 296.703232 -404.034822) (xy 296.706544 -404.040848)
			(xy 296.722923 -404.06919) (xy 296.748723 -404.129352) (xy 296.766209 -404.192433) (xy 296.775065 -404.257292)
			(xy 296.775632 -404.290022) (xy 296.775049 -404.322751) (xy 296.766198 -404.387608) (xy 296.748712 -404.450688)
			(xy 296.72291 -404.510847) (xy 296.706544 -404.539196) (xy 296.703234 -404.545223) (xy 296.699625 -404.558485)
			(xy 296.699432 -404.565358) (xy 296.699432 -405.314658) (xy 296.699636 -405.32153) (xy 296.703236 -405.334793)
			(xy 296.706544 -405.34082) (xy 296.722912 -405.369168) (xy 296.748715 -405.429328) (xy 296.766204 -405.492407)
			(xy 296.775063 -405.557265) (xy 296.775632 -405.589994) (xy 296.775082 -405.622724) (xy 296.766221 -405.687583)
			(xy 296.748726 -405.750663) (xy 296.722915 -405.81082) (xy 296.706544 -405.839168) (xy 296.703244 -405.8452)
			(xy 296.699629 -405.858458) (xy 296.699432 -405.86533) (xy 296.699432 -406.151334) (xy 296.699001 -406.161466)
			(xy 296.691256 -406.180194) (xy 296.676953 -406.19455) (xy 296.658254 -406.202363) (xy 296.648124 -406.202896)
			(xy 295.931844 -406.202896) (xy 295.921692 -406.202442) (xy 295.90294 -406.19466) (xy 295.888615 -406.180273)
			(xy 295.880915 -406.161487) (xy 295.880536 -406.151334) (xy 295.880536 -405.86533) (xy 295.880328 -405.858458)
			(xy 295.87673 -405.845195) (xy 295.873424 -405.839168) (xy 295.857048 -405.810824) (xy 295.831248 -405.750663)
			(xy 295.813761 -405.687582) (xy 295.804904 -405.622724) (xy 295.804336 -405.589994) (xy 294.531749 -405.589994)
			(xy 294.522768 -405.610923) (xy 294.506396 -405.63927) (xy 294.503092 -405.6453) (xy 294.49948 -405.65856)
			(xy 294.499284 -405.665432) (xy 294.499284 -406.414732) (xy 294.499466 -406.421606) (xy 294.503081 -406.434869)
			(xy 294.506396 -406.440894) (xy 294.522759 -406.469245) (xy 294.548561 -406.529404) (xy 294.566052 -406.592483)
			(xy 294.574913 -406.657339) (xy 294.575484 -406.690068) (xy 294.574928 -406.722792) (xy 298.004811 -406.722792)
			(xy 298.004815 -406.657353) (xy 298.013602 -406.592506) (xy 298.031016 -406.529427) (xy 298.056739 -406.469255)
			(xy 298.073064 -406.440894) (xy 298.076378 -406.434869) (xy 298.079984 -406.421606) (xy 298.080176 -406.414732)
			(xy 298.080176 -405.665432) (xy 298.079975 -405.658559) (xy 298.076373 -405.645297) (xy 298.073064 -405.63927)
			(xy 298.056738 -405.610911) (xy 298.031019 -405.550739) (xy 298.01361 -405.48766) (xy 298.004827 -405.422815)
			(xy 298.004827 -405.357378) (xy 298.013612 -405.292533) (xy 298.031021 -405.229454) (xy 298.056741 -405.169283)
			(xy 298.073064 -405.140922) (xy 298.076368 -405.134892) (xy 298.079981 -405.121632) (xy 298.080176 -405.11476)
			(xy 298.080176 -404.828756) (xy 298.080585 -404.818602) (xy 298.088391 -404.799853) (xy 298.102791 -404.785532)
			(xy 298.121582 -404.77783) (xy 298.131738 -404.777448) (xy 298.848018 -404.777448) (xy 298.858147 -404.777912)
			(xy 298.87687 -404.785647) (xy 298.891226 -404.79994) (xy 298.899043 -404.818629) (xy 298.89958 -404.828756)
			(xy 298.89958 -405.11476) (xy 298.89979 -405.121632) (xy 298.903386 -405.134895) (xy 298.906692 -405.140922)
			(xy 298.92301 -405.169285) (xy 298.948726 -405.229456) (xy 298.966134 -405.292535) (xy 298.974917 -405.357379)
			(xy 298.974917 -405.422815) (xy 298.966135 -405.487659) (xy 298.948728 -405.550737) (xy 298.931951 -405.589994)
			(xy 300.204124 -405.589994) (xy 300.204706 -405.557265) (xy 300.213557 -405.492407) (xy 300.231042 -405.429327)
			(xy 300.256845 -405.369168) (xy 300.273212 -405.34082) (xy 300.27652 -405.334792) (xy 300.28013 -405.321531)
			(xy 300.280324 -405.314658) (xy 300.280324 -404.565358) (xy 300.280107 -404.558487) (xy 300.276516 -404.545224)
			(xy 300.273212 -404.539196) (xy 300.256846 -404.510847) (xy 300.231044 -404.450687) (xy 300.213554 -404.387608)
			(xy 300.204694 -404.322751) (xy 300.204124 -404.290022) (xy 300.204674 -404.257292) (xy 300.213534 -404.192433)
			(xy 300.231029 -404.129353) (xy 300.256841 -404.069195) (xy 300.273212 -404.040848) (xy 300.276546 -404.034833)
			(xy 300.280139 -404.021562) (xy 300.280324 -404.014686) (xy 300.280324 -403.728682) (xy 300.280811 -403.718556)
			(xy 300.288542 -403.699837) (xy 300.302828 -403.685482) (xy 300.321509 -403.677661) (xy 300.331632 -403.67712)
			(xy 301.047912 -403.67712) (xy 301.058069 -403.677512) (xy 301.076826 -403.685315) (xy 301.09115 -403.699721)
			(xy 301.098846 -403.718522) (xy 301.09922 -403.728682) (xy 301.09922 -404.014686) (xy 301.099415 -404.021559)
			(xy 301.103021 -404.034822) (xy 301.106332 -404.040848) (xy 301.12271 -404.06919) (xy 301.148511 -404.129352)
			(xy 301.165997 -404.192434) (xy 301.174853 -404.257292) (xy 301.17542 -404.290022) (xy 304.603666 -404.290022)
			(xy 304.607657 -404.227855) (xy 304.619566 -404.166708) (xy 304.639195 -404.107587) (xy 304.666224 -404.051461)
			(xy 304.700208 -403.999252) (xy 304.74059 -403.951817) (xy 304.786706 -403.909936) (xy 304.837798 -403.874296)
			(xy 304.893029 -403.845482) (xy 304.951491 -403.823968) (xy 305.012225 -403.810106) (xy 305.074232 -403.804124)
			(xy 305.136495 -403.80612) (xy 305.197992 -403.816063) (xy 305.257713 -403.833787) (xy 305.314676 -403.859004)
			(xy 305.367947 -403.891297) (xy 305.416652 -403.930137) (xy 305.459989 -403.974887) (xy 305.497249 -404.024811)
			(xy 305.527818 -404.07909) (xy 305.551196 -404.136833) (xy 305.566997 -404.197091) (xy 305.574963 -404.258874)
			(xy 305.575462 -404.290022) (xy 305.574963 -404.32117) (xy 305.566997 -404.382953) (xy 305.551196 -404.443211)
			(xy 305.527818 -404.500954) (xy 305.497249 -404.555233) (xy 305.459989 -404.605157) (xy 305.416652 -404.649907)
			(xy 305.367947 -404.688747) (xy 305.314676 -404.72104) (xy 305.257713 -404.746257) (xy 305.197992 -404.763981)
			(xy 305.136495 -404.773924) (xy 305.074232 -404.77592) (xy 305.012225 -404.769938) (xy 304.951491 -404.756076)
			(xy 304.893029 -404.734562) (xy 304.837798 -404.705748) (xy 304.786706 -404.670108) (xy 304.74059 -404.628227)
			(xy 304.700208 -404.580792) (xy 304.666224 -404.528583) (xy 304.639195 -404.472457) (xy 304.619566 -404.413336)
			(xy 304.607657 -404.352189) (xy 304.603666 -404.290022) (xy 301.17542 -404.290022) (xy 301.174839 -404.322751)
			(xy 301.165987 -404.387609) (xy 301.148501 -404.450689) (xy 301.122698 -404.510847) (xy 301.106332 -404.539196)
			(xy 301.103021 -404.545223) (xy 301.099413 -404.558485) (xy 301.09922 -404.565358) (xy 301.09922 -405.314658)
			(xy 301.099426 -405.32153) (xy 301.103024 -405.334793) (xy 301.106332 -405.34082) (xy 301.122699 -405.369169)
			(xy 301.148502 -405.429328) (xy 301.165992 -405.492408) (xy 301.174851 -405.557265) (xy 301.17542 -405.589994)
			(xy 301.174871 -405.622724) (xy 301.16601 -405.687583) (xy 301.148515 -405.750663) (xy 301.122703 -405.810821)
			(xy 301.106332 -405.839168) (xy 301.103031 -405.8452) (xy 301.099417 -405.858458) (xy 301.09922 -405.86533)
			(xy 301.09922 -406.151334) (xy 301.0988 -406.161468) (xy 301.091054 -406.180197) (xy 301.076747 -406.194554)
			(xy 301.058044 -406.202365) (xy 301.047912 -406.202896) (xy 300.331632 -406.202896) (xy 300.321479 -406.202452)
			(xy 300.302727 -406.194667) (xy 300.288402 -406.180276) (xy 300.280702 -406.161488) (xy 300.280324 -406.151334)
			(xy 300.280324 -405.86533) (xy 300.280118 -405.858458) (xy 300.276519 -405.845195) (xy 300.273212 -405.839168)
			(xy 300.256835 -405.810825) (xy 300.231036 -405.750663) (xy 300.213549 -405.687582) (xy 300.204692 -405.622724)
			(xy 300.204124 -405.589994) (xy 298.931951 -405.589994) (xy 298.923013 -405.610908) (xy 298.906692 -405.63927)
			(xy 298.903387 -405.6453) (xy 298.899775 -405.65856) (xy 298.89958 -405.665432) (xy 298.89958 -406.414732)
			(xy 298.899762 -406.421606) (xy 298.903377 -406.434869) (xy 298.906692 -406.440894) (xy 298.922986 -406.469271)
			(xy 298.948705 -406.529438) (xy 298.966115 -406.592514) (xy 298.974901 -406.657356) (xy 298.974903 -406.690068)
			(xy 302.404272 -406.690068) (xy 302.40485 -406.657339) (xy 302.413703 -406.592481) (xy 302.43119 -406.529401)
			(xy 302.456993 -406.469243) (xy 302.47336 -406.440894) (xy 302.476674 -406.434869) (xy 302.48028 -406.421606)
			(xy 302.480472 -406.414732) (xy 302.480472 -405.665432) (xy 302.480271 -405.658559) (xy 302.476669 -405.645296)
			(xy 302.47336 -405.63927) (xy 302.456988 -405.610924) (xy 302.431187 -405.550764) (xy 302.413698 -405.487683)
			(xy 302.404841 -405.422825) (xy 302.404272 -405.390096) (xy 302.404817 -405.357366) (xy 302.41368 -405.292507)
			(xy 302.431176 -405.229427) (xy 302.456989 -405.169269) (xy 302.47336 -405.140922) (xy 302.476664 -405.134892)
			(xy 302.480277 -405.121632) (xy 302.480472 -405.11476) (xy 302.480472 -404.828756) (xy 302.480948 -404.818648)
			(xy 302.488695 -404.799974) (xy 302.502994 -404.785682) (xy 302.521672 -404.777944) (xy 302.53178 -404.777448)
			(xy 303.24806 -404.777448) (xy 303.25816 -404.778017) (xy 303.276827 -404.785732) (xy 303.291121 -404.800002)
			(xy 303.298867 -404.818657) (xy 303.299368 -404.828756) (xy 303.299368 -405.11476) (xy 303.299579 -405.121632)
			(xy 303.303175 -405.134894) (xy 303.30648 -405.140922) (xy 303.322852 -405.169268) (xy 303.348653 -405.229428)
			(xy 303.366141 -405.292509) (xy 303.374999 -405.357367) (xy 303.375568 -405.390096) (xy 303.375014 -405.422826)
			(xy 303.366153 -405.487684) (xy 303.348659 -405.550764) (xy 303.331829 -405.589994) (xy 304.603666 -405.589994)
			(xy 304.607657 -405.527827) (xy 304.619566 -405.46668) (xy 304.639195 -405.407559) (xy 304.666224 -405.351433)
			(xy 304.700208 -405.299224) (xy 304.74059 -405.251789) (xy 304.786706 -405.209908) (xy 304.837798 -405.174268)
			(xy 304.893029 -405.145454) (xy 304.951491 -405.12394) (xy 305.012225 -405.110078) (xy 305.074232 -405.104096)
			(xy 305.136495 -405.106092) (xy 305.197992 -405.116035) (xy 305.257713 -405.133759) (xy 305.314676 -405.158976)
			(xy 305.367947 -405.191269) (xy 305.416652 -405.230109) (xy 305.459989 -405.274859) (xy 305.497249 -405.324783)
			(xy 305.527818 -405.379062) (xy 305.532285 -405.390096) (xy 306.803814 -405.390096) (xy 306.807805 -405.327929)
			(xy 306.819714 -405.266782) (xy 306.839343 -405.207661) (xy 306.866372 -405.151535) (xy 306.900356 -405.099326)
			(xy 306.940738 -405.051891) (xy 306.986854 -405.01001) (xy 307.037946 -404.97437) (xy 307.093177 -404.945556)
			(xy 307.151639 -404.924042) (xy 307.212373 -404.91018) (xy 307.27438 -404.904198) (xy 307.336643 -404.906194)
			(xy 307.39814 -404.916137) (xy 307.457861 -404.933861) (xy 307.514824 -404.959078) (xy 307.568095 -404.991371)
			(xy 307.6168 -405.030211) (xy 307.660137 -405.074961) (xy 307.697397 -405.124885) (xy 307.727966 -405.179164)
			(xy 307.751344 -405.236907) (xy 307.767145 -405.297165) (xy 307.775111 -405.358948) (xy 307.77561 -405.390096)
			(xy 307.775111 -405.421244) (xy 307.767145 -405.483027) (xy 307.751344 -405.543285) (xy 307.727966 -405.601028)
			(xy 307.697397 -405.655307) (xy 307.660137 -405.705231) (xy 307.6168 -405.749981) (xy 307.568095 -405.788821)
			(xy 307.514824 -405.821114) (xy 307.457861 -405.846331) (xy 307.39814 -405.864055) (xy 307.336643 -405.873998)
			(xy 307.27438 -405.875994) (xy 307.212373 -405.870012) (xy 307.151639 -405.85615) (xy 307.093177 -405.834636)
			(xy 307.037946 -405.805822) (xy 306.986854 -405.770182) (xy 306.940738 -405.728301) (xy 306.900356 -405.680866)
			(xy 306.866372 -405.628657) (xy 306.839343 -405.572531) (xy 306.819714 -405.51341) (xy 306.807805 -405.452263)
			(xy 306.803814 -405.390096) (xy 305.532285 -405.390096) (xy 305.551196 -405.436805) (xy 305.566997 -405.497063)
			(xy 305.574963 -405.558846) (xy 305.575462 -405.589994) (xy 305.574963 -405.621142) (xy 305.566997 -405.682925)
			(xy 305.551196 -405.743183) (xy 305.527818 -405.800926) (xy 305.497249 -405.855205) (xy 305.459989 -405.905129)
			(xy 305.416652 -405.949879) (xy 305.367947 -405.988719) (xy 305.314676 -406.021012) (xy 305.257713 -406.046229)
			(xy 305.197992 -406.063953) (xy 305.136495 -406.073896) (xy 305.074232 -406.075892) (xy 305.012225 -406.06991)
			(xy 304.951491 -406.056048) (xy 304.893029 -406.034534) (xy 304.837798 -406.00572) (xy 304.786706 -405.97008)
			(xy 304.74059 -405.928199) (xy 304.700208 -405.880764) (xy 304.666224 -405.828555) (xy 304.639195 -405.772429)
			(xy 304.619566 -405.713308) (xy 304.607657 -405.652161) (xy 304.603666 -405.589994) (xy 303.331829 -405.589994)
			(xy 303.32285 -405.610922) (xy 303.30648 -405.63927) (xy 303.303175 -405.645299) (xy 303.299563 -405.658559)
			(xy 303.299368 -405.665432) (xy 303.299368 -406.414732) (xy 303.299552 -406.421606) (xy 303.303166 -406.434868)
			(xy 303.30648 -406.440894) (xy 303.322841 -406.469246) (xy 303.348645 -406.529404) (xy 303.366136 -406.592483)
			(xy 303.374997 -406.657339) (xy 303.375568 -406.690068) (xy 306.803814 -406.690068) (xy 306.807805 -406.627901)
			(xy 306.819714 -406.566754) (xy 306.839343 -406.507633) (xy 306.866372 -406.451507) (xy 306.900356 -406.399298)
			(xy 306.940738 -406.351863) (xy 306.986854 -406.309982) (xy 307.037946 -406.274342) (xy 307.093177 -406.245528)
			(xy 307.151639 -406.224014) (xy 307.212373 -406.210152) (xy 307.27438 -406.20417) (xy 307.336643 -406.206166)
			(xy 307.39814 -406.216109) (xy 307.457861 -406.233833) (xy 307.514824 -406.25905) (xy 307.568095 -406.291343)
			(xy 307.6168 -406.330183) (xy 307.660137 -406.374933) (xy 307.697397 -406.424857) (xy 307.727966 -406.479136)
			(xy 307.751344 -406.536879) (xy 307.767145 -406.597137) (xy 307.775111 -406.65892) (xy 307.77561 -406.690068)
			(xy 307.775111 -406.721216) (xy 307.767145 -406.782999) (xy 307.751344 -406.843257) (xy 307.727966 -406.901)
			(xy 307.697397 -406.955279) (xy 307.660137 -407.005203) (xy 307.6168 -407.049953) (xy 307.568095 -407.088793)
			(xy 307.514824 -407.121086) (xy 307.457861 -407.146303) (xy 307.39814 -407.164027) (xy 307.336643 -407.17397)
			(xy 307.27438 -407.175966) (xy 307.212373 -407.169984) (xy 307.151639 -407.156122) (xy 307.093177 -407.134608)
			(xy 307.037946 -407.105794) (xy 306.986854 -407.070154) (xy 306.940738 -407.028273) (xy 306.900356 -406.980838)
			(xy 306.866372 -406.928629) (xy 306.839343 -406.872503) (xy 306.819714 -406.813382) (xy 306.807805 -406.752235)
			(xy 306.803814 -406.690068) (xy 303.375568 -406.690068) (xy 303.375001 -406.722797) (xy 303.366144 -406.787655)
			(xy 303.348654 -406.850735) (xy 303.322848 -406.910894) (xy 303.30648 -406.939242) (xy 303.303149 -406.945259)
			(xy 303.299554 -406.958529) (xy 303.299368 -406.965404) (xy 303.299368 -407.251408) (xy 303.29899 -407.261535)
			(xy 303.291233 -407.280245) (xy 303.276904 -407.29456) (xy 303.258187 -407.302299) (xy 303.24806 -407.302716)
			(xy 302.53178 -407.302716) (xy 302.521672 -407.302232) (xy 302.502996 -407.294491) (xy 302.488703 -407.280194)
			(xy 302.480966 -407.261516) (xy 302.480472 -407.251408) (xy 302.480472 -406.965404) (xy 302.480282 -406.958531)
			(xy 302.476673 -406.945268) (xy 302.47336 -406.939242) (xy 302.457017 -406.91088) (xy 302.431208 -406.850726)
			(xy 302.413712 -406.78765) (xy 302.404845 -406.722796) (xy 302.404272 -406.690068) (xy 298.974903 -406.690068)
			(xy 298.974905 -406.72279) (xy 298.966126 -406.787632) (xy 298.948723 -406.85071) (xy 298.923011 -406.91088)
			(xy 298.906692 -406.939242) (xy 298.903362 -406.945259) (xy 298.899766 -406.958529) (xy 298.89958 -406.965404)
			(xy 298.89958 -407.251408) (xy 298.899184 -407.261565) (xy 298.891382 -407.280321) (xy 298.876978 -407.294645)
			(xy 298.858177 -407.302341) (xy 298.848018 -407.302716) (xy 298.131738 -407.302716) (xy 298.121608 -407.302241)
			(xy 298.10288 -407.294517) (xy 298.088521 -407.280227) (xy 298.080708 -407.261535) (xy 298.080176 -407.251408)
			(xy 298.080176 -406.965404) (xy 298.079985 -406.958531) (xy 298.076376 -406.945268) (xy 298.073064 -406.939242)
			(xy 298.056714 -406.910896) (xy 298.030997 -406.850722) (xy 298.013591 -406.78764) (xy 298.004811 -406.722792)
			(xy 294.574928 -406.722792) (xy 294.574928 -406.722798) (xy 294.56607 -406.787657) (xy 294.548577 -406.850737)
			(xy 294.522766 -406.910894) (xy 294.506396 -406.939242) (xy 294.503066 -406.945259) (xy 294.49947 -406.958529)
			(xy 294.499284 -406.965404) (xy 294.499284 -407.251408) (xy 294.49889 -407.261533) (xy 294.491136 -407.28024)
			(xy 294.476813 -407.294554) (xy 294.458101 -407.302296) (xy 294.447976 -407.302716) (xy 293.731696 -407.302716)
			(xy 293.721589 -407.302218) (xy 293.702914 -407.294482) (xy 293.68862 -407.28019) (xy 293.680882 -407.261515)
			(xy 293.680388 -407.251408) (xy 293.680388 -406.965404) (xy 293.680196 -406.958531) (xy 293.676588 -406.945268)
			(xy 293.673276 -406.939242) (xy 293.656925 -406.910885) (xy 293.63112 -406.850728) (xy 293.613626 -406.787651)
			(xy 293.604761 -406.722796) (xy 293.604188 -406.690068) (xy 290.174816 -406.690068) (xy 290.174818 -406.72279)
			(xy 290.16604 -406.787632) (xy 290.148637 -406.850709) (xy 290.122927 -406.91088) (xy 290.106608 -406.939242)
			(xy 290.103279 -406.94526) (xy 290.099682 -406.958529) (xy 290.099496 -406.965404) (xy 290.099496 -407.251408)
			(xy 290.099085 -407.261563) (xy 290.091286 -407.280316) (xy 290.076886 -407.29464) (xy 290.058091 -407.302338)
			(xy 290.047934 -407.302716) (xy 289.331654 -407.302716) (xy 289.321519 -407.30231) (xy 289.302788 -407.294559)
			(xy 289.288432 -407.280248) (xy 289.280622 -407.261541) (xy 289.280092 -407.251408) (xy 289.280092 -406.965404)
			(xy 289.2799 -406.958531) (xy 289.276292 -406.945268) (xy 289.27298 -406.939242) (xy 289.256629 -406.910896)
			(xy 289.230912 -406.850722) (xy 289.213506 -406.78764) (xy 289.204725 -406.722792) (xy 282.775152 -406.722792)
			(xy 282.775152 -409.490164) (xy 287.004252 -409.490164) (xy 287.00483 -409.457435) (xy 287.013683 -409.392577)
			(xy 287.03117 -409.329497) (xy 287.056973 -409.269339) (xy 287.07334 -409.24099) (xy 287.076654 -409.234965)
			(xy 287.080261 -409.221702) (xy 287.080452 -409.214828) (xy 287.080452 -408.465528) (xy 287.080255 -408.458655)
			(xy 287.076651 -408.445392) (xy 287.07334 -408.439366) (xy 287.056965 -408.411022) (xy 287.031164 -408.350861)
			(xy 287.013677 -408.28778) (xy 287.00482 -408.222922) (xy 287.004252 -408.190192) (xy 287.004843 -408.157463)
			(xy 287.013692 -408.092606) (xy 287.031175 -408.029526) (xy 287.056975 -407.969367) (xy 287.07334 -407.941018)
			(xy 287.076644 -407.934988) (xy 287.080257 -407.921728) (xy 287.080452 -407.914856) (xy 287.080452 -407.628852)
			(xy 287.080945 -407.618746) (xy 287.088689 -407.600076) (xy 287.102983 -407.585785) (xy 287.121654 -407.578043)
			(xy 287.13176 -407.577544) (xy 287.84804 -407.577544) (xy 287.858144 -407.578051) (xy 287.876813 -407.585791)
			(xy 287.891104 -407.600081) (xy 287.898847 -407.618748) (xy 287.899348 -407.628852) (xy 287.899348 -407.914856)
			(xy 287.899551 -407.921729) (xy 287.903151 -407.934992) (xy 287.90646 -407.941018) (xy 287.922829 -407.969365)
			(xy 287.948631 -408.029525) (xy 287.96612 -408.092605) (xy 287.974979 -408.157463) (xy 287.975548 -408.190192)
			(xy 287.974995 -408.222922) (xy 287.966134 -408.28778) (xy 287.94864 -408.35086) (xy 287.92283 -408.411018)
			(xy 287.90646 -408.439366) (xy 287.903162 -408.445399) (xy 287.899545 -408.458656) (xy 287.899348 -408.465528)
			(xy 287.899348 -409.214828) (xy 287.899523 -409.221703) (xy 287.903142 -409.234966) (xy 287.90646 -409.24099)
			(xy 287.922818 -409.269344) (xy 287.948622 -409.329501) (xy 287.966114 -409.392579) (xy 287.974977 -409.457435)
			(xy 287.975548 -409.490164) (xy 287.974982 -409.522893) (xy 287.966125 -409.587751) (xy 287.948635 -409.650832)
			(xy 287.922828 -409.71099) (xy 287.90646 -409.739338) (xy 287.903136 -409.745358) (xy 287.899536 -409.758625)
			(xy 287.899348 -409.7655) (xy 287.899348 -410.051504) (xy 287.898819 -410.061607) (xy 287.891089 -410.080276)
			(xy 287.876806 -410.094569) (xy 287.858143 -410.102312) (xy 287.84804 -410.102812) (xy 287.13176 -410.102812)
			(xy 287.12165 -410.102348) (xy 287.102973 -410.094599) (xy 287.08868 -410.080296) (xy 287.080945 -410.061614)
			(xy 287.080452 -410.051504) (xy 287.080452 -409.7655) (xy 287.080266 -409.758626) (xy 287.076654 -409.745363)
			(xy 287.07334 -409.739338) (xy 287.056993 -409.710978) (xy 287.031186 -409.650823) (xy 287.013691 -409.587747)
			(xy 287.004825 -409.522892) (xy 287.004252 -409.490164) (xy 282.775152 -409.490164) (xy 282.775152 -410.622705)
			(xy 289.204734 -410.622705) (xy 289.204736 -410.557267) (xy 289.213522 -410.492421) (xy 289.230934 -410.429342)
			(xy 289.256655 -410.369171) (xy 289.27298 -410.34081) (xy 289.27629 -410.334783) (xy 289.279899 -410.321521)
			(xy 289.280092 -410.314648) (xy 289.280092 -409.565348) (xy 289.279883 -409.558476) (xy 289.276286 -409.545213)
			(xy 289.27298 -409.539186) (xy 289.256667 -409.51082) (xy 289.230946 -409.45065) (xy 289.213535 -409.387572)
			(xy 289.20475 -409.322728) (xy 289.204748 -409.257292) (xy 289.213531 -409.192448) (xy 289.230939 -409.129369)
			(xy 289.256657 -409.069199) (xy 289.27298 -409.040838) (xy 289.27628 -409.034806) (xy 289.279895 -409.021548)
			(xy 289.280092 -409.014676) (xy 289.280092 -408.728672) (xy 289.280498 -408.718517) (xy 289.288302 -408.699766)
			(xy 289.302703 -408.685443) (xy 289.321497 -408.677743) (xy 289.331654 -408.677364) (xy 290.047934 -408.677364)
			(xy 290.058066 -408.677799) (xy 290.076792 -408.685543) (xy 290.091148 -408.699845) (xy 290.098962 -408.718542)
			(xy 290.099496 -408.728672) (xy 290.099496 -409.014676) (xy 290.099697 -409.021549) (xy 290.103299 -409.034811)
			(xy 290.106608 -409.040838) (xy 290.122939 -409.069194) (xy 290.148653 -409.129367) (xy 290.166058 -409.192447)
			(xy 290.17484 -409.257292) (xy 290.174838 -409.322729) (xy 290.166054 -409.387573) (xy 290.148646 -409.450652)
			(xy 290.12293 -409.510824) (xy 290.115987 -409.522889) (xy 291.404878 -409.522889) (xy 291.404882 -409.45745)
			(xy 291.413669 -409.392603) (xy 291.431082 -409.329523) (xy 291.456804 -409.269351) (xy 291.473128 -409.24099)
			(xy 291.476448 -409.234968) (xy 291.48005 -409.221702) (xy 291.48024 -409.214828) (xy 291.48024 -408.465528)
			(xy 291.480032 -408.458656) (xy 291.476434 -408.445393) (xy 291.473128 -408.439366) (xy 291.456799 -408.411008)
			(xy 291.431083 -408.350836) (xy 291.413676 -408.287757) (xy 291.404893 -408.222912) (xy 291.404894 -408.157475)
			(xy 291.413679 -408.09263) (xy 291.431087 -408.029551) (xy 291.456806 -407.969379) (xy 291.473128 -407.941018)
			(xy 291.476438 -407.934991) (xy 291.480046 -407.921729) (xy 291.48024 -407.914856) (xy 291.48024 -407.628852)
			(xy 291.480583 -407.61869) (xy 291.488402 -407.599929) (xy 291.502823 -407.585606) (xy 291.521637 -407.577915)
			(xy 291.531802 -407.577544) (xy 292.248082 -407.577544) (xy 292.258208 -407.578041) (xy 292.27693 -407.585764)
			(xy 292.291287 -407.600047) (xy 292.299106 -407.618729) (xy 292.299644 -407.628852) (xy 292.299644 -407.914856)
			(xy 292.299847 -407.921728) (xy 292.303447 -407.934991) (xy 292.306756 -407.941018) (xy 292.323072 -407.969383)
			(xy 292.34879 -408.029553) (xy 292.366199 -408.092631) (xy 292.374984 -408.157475) (xy 292.374985 -408.222911)
			(xy 292.366202 -408.287755) (xy 292.348795 -408.350834) (xy 292.323078 -408.411005) (xy 292.306756 -408.439366)
			(xy 292.303458 -408.445399) (xy 292.299841 -408.458656) (xy 292.299644 -408.465528) (xy 292.299644 -409.214828)
			(xy 292.29982 -409.221703) (xy 292.303439 -409.234965) (xy 292.306756 -409.24099) (xy 292.323048 -409.269368)
			(xy 292.348769 -409.329535) (xy 292.36618 -409.39261) (xy 292.374968 -409.457452) (xy 292.374972 -409.522886)
			(xy 292.366193 -409.587729) (xy 292.348789 -409.650806) (xy 292.323076 -409.710977) (xy 292.306756 -409.739338)
			(xy 292.303432 -409.745358) (xy 292.299832 -409.758625) (xy 292.299644 -409.7655) (xy 292.299644 -410.051504)
			(xy 292.299182 -410.061653) (xy 292.291394 -410.080397) (xy 292.27701 -410.094718) (xy 292.258233 -410.102426)
			(xy 292.248082 -410.102812) (xy 291.531802 -410.102812) (xy 291.521682 -410.102273) (xy 291.502971 -410.094556)
			(xy 291.488616 -410.080286) (xy 291.480788 -410.061621) (xy 291.48024 -410.051504) (xy 291.48024 -409.7655)
			(xy 291.480043 -409.758627) (xy 291.476438 -409.745365) (xy 291.473128 -409.739338) (xy 291.456776 -409.710993)
			(xy 291.431061 -409.650818) (xy 291.413657 -409.587736) (xy 291.404878 -409.522889) (xy 290.115987 -409.522889)
			(xy 290.106608 -409.539186) (xy 290.103299 -409.545213) (xy 290.09969 -409.558475) (xy 290.099496 -409.565348)
			(xy 290.099496 -410.314648) (xy 290.099709 -410.32152) (xy 290.103303 -410.334782) (xy 290.106608 -410.34081)
			(xy 290.122915 -410.369179) (xy 290.148632 -410.429349) (xy 290.166039 -410.492426) (xy 290.174824 -410.557269)
			(xy 290.174825 -410.589984) (xy 293.604188 -410.589984) (xy 293.604771 -410.557255) (xy 293.613622 -410.492398)
			(xy 293.631107 -410.429317) (xy 293.65691 -410.369159) (xy 293.673276 -410.34081) (xy 293.676585 -410.334783)
			(xy 293.680195 -410.321521) (xy 293.680388 -410.314648) (xy 293.680388 -409.565348) (xy 293.680179 -409.558476)
			(xy 293.676583 -409.545213) (xy 293.673276 -409.539186) (xy 293.656903 -409.510841) (xy 293.631103 -409.45068)
			(xy 293.613616 -409.387599) (xy 293.604757 -409.322741) (xy 293.604188 -409.290012) (xy 293.604738 -409.257282)
			(xy 293.613599 -409.192423) (xy 293.631094 -409.129343) (xy 293.656905 -409.069185) (xy 293.673276 -409.040838)
			(xy 293.676576 -409.034806) (xy 293.680191 -409.021548) (xy 293.680388 -409.014676) (xy 293.680388 -408.728672)
			(xy 293.680862 -408.718563) (xy 293.688606 -408.699886) (xy 293.702907 -408.685593) (xy 293.721587 -408.677857)
			(xy 293.731696 -408.677364) (xy 294.447976 -408.677364) (xy 294.458079 -408.677904) (xy 294.47675 -408.685627)
			(xy 294.491044 -408.699907) (xy 294.498786 -408.71857) (xy 294.499284 -408.728672) (xy 294.499284 -409.014676)
			(xy 294.499487 -409.021548) (xy 294.503088 -409.034811) (xy 294.506396 -409.040838) (xy 294.522776 -409.069179)
			(xy 294.548575 -409.129342) (xy 294.56606 -409.192424) (xy 294.574916 -409.257282) (xy 294.575484 -409.290012)
			(xy 294.574903 -409.322741) (xy 294.566052 -409.387599) (xy 294.548566 -409.450679) (xy 294.53163 -409.490164)
			(xy 295.804336 -409.490164) (xy 295.804917 -409.457435) (xy 295.813769 -409.392578) (xy 295.831255 -409.329498)
			(xy 295.857058 -409.269339) (xy 295.873424 -409.24099) (xy 295.876744 -409.234968) (xy 295.880346 -409.221702)
			(xy 295.880536 -409.214828) (xy 295.880536 -408.465528) (xy 295.880329 -408.458656) (xy 295.876731 -408.445393)
			(xy 295.873424 -408.439366) (xy 295.857047 -408.411023) (xy 295.831248 -408.350861) (xy 295.813761 -408.28778)
			(xy 295.804904 -408.222922) (xy 295.804336 -408.190192) (xy 295.804929 -408.157464) (xy 295.813778 -408.092607)
			(xy 295.831261 -408.029526) (xy 295.85706 -407.969367) (xy 295.873424 -407.941018) (xy 295.876734 -407.934991)
			(xy 295.880342 -407.921729) (xy 295.880536 -407.914856) (xy 295.880536 -407.628852) (xy 295.880947 -407.618736)
			(xy 295.888707 -407.60005) (xy 295.903027 -407.585755) (xy 295.921727 -407.578029) (xy 295.931844 -407.577544)
			(xy 296.648124 -407.577544) (xy 296.658227 -407.578064) (xy 296.676895 -407.585799) (xy 296.691187 -407.600084)
			(xy 296.698931 -407.618749) (xy 296.699432 -407.628852) (xy 296.699432 -407.914856) (xy 296.699637 -407.921728)
			(xy 296.703236 -407.934991) (xy 296.706544 -407.941018) (xy 296.722911 -407.969366) (xy 296.748714 -408.029526)
			(xy 296.766203 -408.092606) (xy 296.775063 -408.157463) (xy 296.775632 -408.190192) (xy 296.775081 -408.222922)
			(xy 296.76622 -408.287781) (xy 296.748726 -408.350861) (xy 296.722914 -408.411018) (xy 296.706544 -408.439366)
			(xy 296.703245 -408.445398) (xy 296.699629 -408.458656) (xy 296.699432 -408.465528) (xy 296.699432 -409.214828)
			(xy 296.699609 -409.221702) (xy 296.703227 -409.234965) (xy 296.706544 -409.24099) (xy 296.7229 -409.269344)
			(xy 296.748706 -409.329502) (xy 296.766198 -409.39258) (xy 296.775061 -409.457435) (xy 296.775632 -409.490164)
			(xy 296.775068 -409.522894) (xy 296.766211 -409.587752) (xy 296.74872 -409.650832) (xy 296.722913 -409.71099)
			(xy 296.706544 -409.739338) (xy 296.703219 -409.745358) (xy 296.699619 -409.758625) (xy 296.699432 -409.7655)
			(xy 296.699432 -410.051504) (xy 296.698919 -410.061609) (xy 296.691186 -410.080281) (xy 296.676898 -410.094575)
			(xy 296.658229 -410.102315) (xy 296.648124 -410.102812) (xy 295.931844 -410.102812) (xy 295.921726 -410.102348)
			(xy 295.903026 -410.094617) (xy 295.88871 -410.080315) (xy 295.880961 -410.061622) (xy 295.880536 -410.051504)
			(xy 295.880536 -409.7655) (xy 295.88034 -409.758627) (xy 295.876734 -409.745365) (xy 295.873424 -409.739338)
			(xy 295.857076 -409.710979) (xy 295.831269 -409.650823) (xy 295.813775 -409.587747) (xy 295.804909 -409.522892)
			(xy 295.804336 -409.490164) (xy 294.53163 -409.490164) (xy 294.522763 -409.510838) (xy 294.506396 -409.539186)
			(xy 294.503086 -409.545213) (xy 294.499477 -409.558475) (xy 294.499284 -409.565348) (xy 294.499284 -410.314648)
			(xy 294.499498 -410.32152) (xy 294.503092 -410.334782) (xy 294.506396 -410.34081) (xy 294.522765 -410.369157)
			(xy 294.548566 -410.429317) (xy 294.566055 -410.492398) (xy 294.574914 -410.557255) (xy 294.575484 -410.589984)
			(xy 294.574936 -410.622705) (xy 298.00482 -410.622705) (xy 298.004822 -410.557267) (xy 298.013608 -410.492422)
			(xy 298.031019 -410.429342) (xy 298.05674 -410.369171) (xy 298.073064 -410.34081) (xy 298.076372 -410.334782)
			(xy 298.079982 -410.321521) (xy 298.080176 -410.314648) (xy 298.080176 -409.565348) (xy 298.079969 -409.558476)
			(xy 298.076371 -409.545213) (xy 298.073064 -409.539186) (xy 298.056751 -409.510819) (xy 298.031031 -409.45065)
			(xy 298.013621 -409.387572) (xy 298.004836 -409.322728) (xy 298.004834 -409.257292) (xy 298.013617 -409.192448)
			(xy 298.031024 -409.12937) (xy 298.056742 -409.069199) (xy 298.073064 -409.040838) (xy 298.076362 -409.034805)
			(xy 298.079979 -409.021548) (xy 298.080176 -409.014676) (xy 298.080176 -408.728672) (xy 298.080598 -408.718519)
			(xy 298.088398 -408.699771) (xy 298.102794 -408.685449) (xy 298.121583 -408.677746) (xy 298.131738 -408.677364)
			(xy 298.848018 -408.677364) (xy 298.858149 -408.677812) (xy 298.876875 -408.68555) (xy 298.891232 -408.699849)
			(xy 298.899046 -408.718543) (xy 298.89958 -408.728672) (xy 298.89958 -409.014676) (xy 298.899783 -409.021548)
			(xy 298.903384 -409.034811) (xy 298.906692 -409.040838) (xy 298.923023 -409.069194) (xy 298.948738 -409.129367)
			(xy 298.966144 -409.192446) (xy 298.974926 -409.257292) (xy 298.974925 -409.322729) (xy 298.96614 -409.387574)
			(xy 298.948732 -409.450653) (xy 298.931844 -409.490164) (xy 300.204124 -409.490164) (xy 300.204693 -409.457435)
			(xy 300.213547 -409.392576) (xy 300.231036 -409.329496) (xy 300.256844 -409.269338) (xy 300.273212 -409.24099)
			(xy 300.276531 -409.234968) (xy 300.280134 -409.221702) (xy 300.280324 -409.214828) (xy 300.280324 -408.465528)
			(xy 300.280118 -408.458656) (xy 300.276519 -408.445393) (xy 300.273212 -408.439366) (xy 300.256834 -408.411024)
			(xy 300.231035 -408.350862) (xy 300.213549 -408.28778) (xy 300.204692 -408.222922) (xy 300.204124 -408.190192)
			(xy 300.204705 -408.157463) (xy 300.213556 -408.092605) (xy 300.231042 -408.029525) (xy 300.256845 -407.969366)
			(xy 300.273212 -407.941018) (xy 300.276521 -407.934991) (xy 300.28013 -407.921729) (xy 300.280324 -407.914856)
			(xy 300.280324 -407.628852) (xy 300.280747 -407.618737) (xy 300.288504 -407.600053) (xy 300.302821 -407.585759)
			(xy 300.321516 -407.578031) (xy 300.331632 -407.577544) (xy 301.047912 -407.577544) (xy 301.058015 -407.578074)
			(xy 301.076682 -407.585805) (xy 301.090975 -407.600088) (xy 301.098719 -407.61875) (xy 301.09922 -407.628852)
			(xy 301.09922 -407.914856) (xy 301.099426 -407.921728) (xy 301.103025 -407.934991) (xy 301.106332 -407.941018)
			(xy 301.122698 -407.969367) (xy 301.148501 -408.029526) (xy 301.165991 -408.092606) (xy 301.174851 -408.157463)
			(xy 301.17542 -408.190192) (xy 304.603666 -408.190192) (xy 304.607657 -408.128025) (xy 304.619566 -408.066878)
			(xy 304.639195 -408.007757) (xy 304.666224 -407.951631) (xy 304.700208 -407.899422) (xy 304.74059 -407.851987)
			(xy 304.786706 -407.810106) (xy 304.837798 -407.774466) (xy 304.893029 -407.745652) (xy 304.951491 -407.724138)
			(xy 305.012225 -407.710276) (xy 305.074232 -407.704294) (xy 305.136495 -407.70629) (xy 305.197992 -407.716233)
			(xy 305.257713 -407.733957) (xy 305.314676 -407.759174) (xy 305.367947 -407.791467) (xy 305.416652 -407.830307)
			(xy 305.459989 -407.875057) (xy 305.497249 -407.924981) (xy 305.527818 -407.97926) (xy 305.551196 -408.037003)
			(xy 305.566997 -408.097261) (xy 305.574963 -408.159044) (xy 305.575462 -408.190192) (xy 305.574963 -408.22134)
			(xy 305.566997 -408.283123) (xy 305.551196 -408.343381) (xy 305.527818 -408.401124) (xy 305.497249 -408.455403)
			(xy 305.459989 -408.505327) (xy 305.416652 -408.550077) (xy 305.367947 -408.588917) (xy 305.314676 -408.62121)
			(xy 305.257713 -408.646427) (xy 305.197992 -408.664151) (xy 305.136495 -408.674094) (xy 305.074232 -408.67609)
			(xy 305.012225 -408.670108) (xy 304.951491 -408.656246) (xy 304.893029 -408.634732) (xy 304.837798 -408.605918)
			(xy 304.786706 -408.570278) (xy 304.74059 -408.528397) (xy 304.700208 -408.480962) (xy 304.666224 -408.428753)
			(xy 304.639195 -408.372627) (xy 304.619566 -408.313506) (xy 304.607657 -408.252359) (xy 304.603666 -408.190192)
			(xy 301.17542 -408.190192) (xy 301.174871 -408.222922) (xy 301.16601 -408.287781) (xy 301.148515 -408.350861)
			(xy 301.122703 -408.411019) (xy 301.106332 -408.439366) (xy 301.103032 -408.445398) (xy 301.099417 -408.458656)
			(xy 301.09922 -408.465528) (xy 301.09922 -409.214828) (xy 301.099399 -409.221702) (xy 301.103016 -409.234965)
			(xy 301.106332 -409.24099) (xy 301.122687 -409.269345) (xy 301.148493 -409.329502) (xy 301.165986 -409.39258)
			(xy 301.174849 -409.457435) (xy 301.17542 -409.490164) (xy 301.174858 -409.522894) (xy 301.166001 -409.587752)
			(xy 301.148509 -409.650832) (xy 301.122701 -409.71099) (xy 301.106332 -409.739338) (xy 301.103006 -409.745357)
			(xy 301.099407 -409.758625) (xy 301.09922 -409.7655) (xy 301.09922 -410.051504) (xy 301.098719 -410.06161)
			(xy 301.090983 -410.080285) (xy 301.076692 -410.094579) (xy 301.058018 -410.102317) (xy 301.047912 -410.102812)
			(xy 300.331632 -410.102812) (xy 300.321513 -410.102358) (xy 300.302812 -410.094623) (xy 300.288497 -410.080318)
			(xy 300.280749 -410.061623) (xy 300.280324 -410.051504) (xy 300.280324 -409.7655) (xy 300.280129 -409.758627)
			(xy 300.276523 -409.745364) (xy 300.273212 -409.739338) (xy 300.256863 -409.71098) (xy 300.231057 -409.650824)
			(xy 300.213562 -409.587747) (xy 300.204697 -409.522892) (xy 300.204124 -409.490164) (xy 298.931844 -409.490164)
			(xy 298.923014 -409.510824) (xy 298.906692 -409.539186) (xy 298.903382 -409.545213) (xy 298.899773 -409.558475)
			(xy 298.89958 -409.565348) (xy 298.89958 -410.314648) (xy 298.899794 -410.32152) (xy 298.903387 -410.334782)
			(xy 298.906692 -410.34081) (xy 298.923 -410.369179) (xy 298.948717 -410.429349) (xy 298.966125 -410.492426)
			(xy 298.97491 -410.557269) (xy 298.974911 -410.589984) (xy 302.404272 -410.589984) (xy 302.404857 -410.557255)
			(xy 302.413708 -410.492398) (xy 302.431193 -410.429318) (xy 302.456994 -410.369159) (xy 302.47336 -410.34081)
			(xy 302.476668 -410.334782) (xy 302.480278 -410.321521) (xy 302.480472 -410.314648) (xy 302.480472 -409.565348)
			(xy 302.480265 -409.558476) (xy 302.476667 -409.545213) (xy 302.47336 -409.539186) (xy 302.456995 -409.510837)
			(xy 302.431191 -409.450678) (xy 302.413701 -409.387598) (xy 302.404842 -409.322741) (xy 302.404272 -409.290012)
			(xy 302.404824 -409.257282) (xy 302.413685 -409.192423) (xy 302.431179 -409.129343) (xy 302.45699 -409.069186)
			(xy 302.47336 -409.040838) (xy 302.476658 -409.034805) (xy 302.480275 -409.021548) (xy 302.480472 -409.014676)
			(xy 302.480472 -408.728672) (xy 302.480961 -408.718565) (xy 302.488703 -408.699891) (xy 302.502998 -408.685599)
			(xy 302.521673 -408.67786) (xy 302.53178 -408.677364) (xy 303.24806 -408.677364) (xy 303.258175 -408.677848)
			(xy 303.276871 -408.685576) (xy 303.291186 -408.699872) (xy 303.298939 -408.718557) (xy 303.299368 -408.728672)
			(xy 303.299368 -409.014676) (xy 303.299573 -409.021548) (xy 303.303173 -409.034811) (xy 303.30648 -409.040838)
			(xy 303.322859 -409.06918) (xy 303.348658 -409.129342) (xy 303.366144 -409.192424) (xy 303.375 -409.257282)
			(xy 303.375568 -409.290012) (xy 303.374976 -409.32274) (xy 303.366127 -409.387598) (xy 303.348644 -409.450678)
			(xy 303.331711 -409.490164) (xy 304.603666 -409.490164) (xy 304.607657 -409.427997) (xy 304.619566 -409.36685)
			(xy 304.639195 -409.307729) (xy 304.666224 -409.251603) (xy 304.700208 -409.199394) (xy 304.74059 -409.151959)
			(xy 304.786706 -409.110078) (xy 304.837798 -409.074438) (xy 304.893029 -409.045624) (xy 304.951491 -409.02411)
			(xy 305.012225 -409.010248) (xy 305.074232 -409.004266) (xy 305.136495 -409.006262) (xy 305.197992 -409.016205)
			(xy 305.257713 -409.033929) (xy 305.314676 -409.059146) (xy 305.367947 -409.091439) (xy 305.416652 -409.130279)
			(xy 305.459989 -409.175029) (xy 305.497249 -409.224953) (xy 305.527818 -409.279232) (xy 305.532182 -409.290012)
			(xy 306.803814 -409.290012) (xy 306.807805 -409.227845) (xy 306.819714 -409.166698) (xy 306.839343 -409.107577)
			(xy 306.866372 -409.051451) (xy 306.900356 -408.999242) (xy 306.940738 -408.951807) (xy 306.986854 -408.909926)
			(xy 307.037946 -408.874286) (xy 307.093177 -408.845472) (xy 307.151639 -408.823958) (xy 307.212373 -408.810096)
			(xy 307.27438 -408.804114) (xy 307.336643 -408.80611) (xy 307.39814 -408.816053) (xy 307.457861 -408.833777)
			(xy 307.514824 -408.858994) (xy 307.568095 -408.891287) (xy 307.6168 -408.930127) (xy 307.660137 -408.974877)
			(xy 307.697397 -409.024801) (xy 307.727966 -409.07908) (xy 307.751344 -409.136823) (xy 307.767145 -409.197081)
			(xy 307.775111 -409.258864) (xy 307.77561 -409.290012) (xy 307.775111 -409.32116) (xy 307.767145 -409.382943)
			(xy 307.751344 -409.443201) (xy 307.727966 -409.500944) (xy 307.697397 -409.555223) (xy 307.660137 -409.605147)
			(xy 307.6168 -409.649897) (xy 307.568095 -409.688737) (xy 307.514824 -409.72103) (xy 307.457861 -409.746247)
			(xy 307.39814 -409.763971) (xy 307.336643 -409.773914) (xy 307.27438 -409.77591) (xy 307.212373 -409.769928)
			(xy 307.151639 -409.756066) (xy 307.093177 -409.734552) (xy 307.037946 -409.705738) (xy 306.986854 -409.670098)
			(xy 306.940738 -409.628217) (xy 306.900356 -409.580782) (xy 306.866372 -409.528573) (xy 306.839343 -409.472447)
			(xy 306.819714 -409.413326) (xy 306.807805 -409.352179) (xy 306.803814 -409.290012) (xy 305.532182 -409.290012)
			(xy 305.551196 -409.336975) (xy 305.566997 -409.397233) (xy 305.574963 -409.459016) (xy 305.575462 -409.490164)
			(xy 305.574963 -409.521312) (xy 305.566997 -409.583095) (xy 305.551196 -409.643353) (xy 305.527818 -409.701096)
			(xy 305.497249 -409.755375) (xy 305.459989 -409.805299) (xy 305.416652 -409.850049) (xy 305.367947 -409.888889)
			(xy 305.314676 -409.921182) (xy 305.257713 -409.946399) (xy 305.197992 -409.964123) (xy 305.136495 -409.974066)
			(xy 305.074232 -409.976062) (xy 305.012225 -409.97008) (xy 304.951491 -409.956218) (xy 304.893029 -409.934704)
			(xy 304.837798 -409.90589) (xy 304.786706 -409.87025) (xy 304.74059 -409.828369) (xy 304.700208 -409.780934)
			(xy 304.666224 -409.728725) (xy 304.639195 -409.672599) (xy 304.619566 -409.613478) (xy 304.607657 -409.552331)
			(xy 304.603666 -409.490164) (xy 303.331711 -409.490164) (xy 303.322845 -409.510837) (xy 303.30648 -409.539186)
			(xy 303.303169 -409.545212) (xy 303.299561 -409.558475) (xy 303.299368 -409.565348) (xy 303.299368 -410.314648)
			(xy 303.299584 -410.321519) (xy 303.303176 -410.334782) (xy 303.30648 -410.34081) (xy 303.322848 -410.369158)
			(xy 303.348649 -410.429318) (xy 303.366139 -410.492398) (xy 303.374998 -410.557255) (xy 303.375568 -410.589984)
			(xy 306.803814 -410.589984) (xy 306.807805 -410.527817) (xy 306.819714 -410.46667) (xy 306.839343 -410.407549)
			(xy 306.866372 -410.351423) (xy 306.900356 -410.299214) (xy 306.940738 -410.251779) (xy 306.986854 -410.209898)
			(xy 307.037946 -410.174258) (xy 307.093177 -410.145444) (xy 307.151639 -410.12393) (xy 307.212373 -410.110068)
			(xy 307.27438 -410.104086) (xy 307.336643 -410.106082) (xy 307.39814 -410.116025) (xy 307.457861 -410.133749)
			(xy 307.514824 -410.158966) (xy 307.568095 -410.191259) (xy 307.6168 -410.230099) (xy 307.660137 -410.274849)
			(xy 307.697397 -410.324773) (xy 307.727966 -410.379052) (xy 307.751344 -410.436795) (xy 307.767145 -410.497053)
			(xy 307.775111 -410.558836) (xy 307.77561 -410.589984) (xy 307.775111 -410.621132) (xy 307.767145 -410.682915)
			(xy 307.751344 -410.743173) (xy 307.727966 -410.800916) (xy 307.697397 -410.855195) (xy 307.660137 -410.905119)
			(xy 307.6168 -410.949869) (xy 307.568095 -410.988709) (xy 307.514824 -411.021002) (xy 307.457861 -411.046219)
			(xy 307.39814 -411.063943) (xy 307.336643 -411.073886) (xy 307.27438 -411.075882) (xy 307.212373 -411.0699)
			(xy 307.151639 -411.056038) (xy 307.093177 -411.034524) (xy 307.037946 -411.00571) (xy 306.986854 -410.97007)
			(xy 306.940738 -410.928189) (xy 306.900356 -410.880754) (xy 306.866372 -410.828545) (xy 306.839343 -410.772419)
			(xy 306.819714 -410.713298) (xy 306.807805 -410.652151) (xy 306.803814 -410.589984) (xy 303.375568 -410.589984)
			(xy 303.375008 -410.622714) (xy 303.366149 -410.687572) (xy 303.348657 -410.750652) (xy 303.322849 -410.81081)
			(xy 303.30648 -410.839158) (xy 303.303179 -410.845189) (xy 303.299565 -410.858448) (xy 303.299368 -410.86532)
			(xy 303.299368 -411.151324) (xy 303.299003 -411.161452) (xy 303.291241 -411.180162) (xy 303.276909 -411.194477)
			(xy 303.258189 -411.202216) (xy 303.24806 -411.202632) (xy 302.53178 -411.202632) (xy 302.521674 -411.202132)
			(xy 302.503001 -411.194394) (xy 302.488708 -411.180102) (xy 302.480969 -411.16143) (xy 302.480472 -411.151324)
			(xy 302.480472 -410.86532) (xy 302.480276 -410.858447) (xy 302.476671 -410.845184) (xy 302.47336 -410.839158)
			(xy 302.456983 -410.810815) (xy 302.431183 -410.750653) (xy 302.413696 -410.687572) (xy 302.40484 -410.622714)
			(xy 302.404272 -410.589984) (xy 298.974911 -410.589984) (xy 298.974912 -410.622704) (xy 298.966131 -410.687547)
			(xy 298.948726 -410.750625) (xy 298.923012 -410.810796) (xy 298.906692 -410.839158) (xy 298.903392 -410.84519)
			(xy 298.899777 -410.858448) (xy 298.89958 -410.86532) (xy 298.89958 -411.151324) (xy 298.899198 -411.161482)
			(xy 298.891391 -411.180239) (xy 298.876982 -411.194562) (xy 298.858179 -411.202258) (xy 298.848018 -411.202632)
			(xy 298.131738 -411.202632) (xy 298.12161 -411.202141) (xy 298.102885 -411.194421) (xy 298.088526 -411.180135)
			(xy 298.080711 -411.161449) (xy 298.080176 -411.151324) (xy 298.080176 -410.86532) (xy 298.079979 -410.858447)
			(xy 298.076375 -410.845184) (xy 298.073064 -410.839158) (xy 298.056727 -410.810804) (xy 298.03101 -410.750632)
			(xy 298.013602 -410.687551) (xy 298.00482 -410.622705) (xy 294.574936 -410.622705) (xy 294.574936 -410.622714)
			(xy 294.566075 -410.687573) (xy 294.54858 -410.750653) (xy 294.522767 -410.810811) (xy 294.506396 -410.839158)
			(xy 294.503096 -410.84519) (xy 294.499481 -410.858448) (xy 294.499284 -410.86532) (xy 294.499284 -411.151324)
			(xy 294.498834 -411.161436) (xy 294.491086 -411.180118) (xy 294.476778 -411.194413) (xy 294.458089 -411.202144)
			(xy 294.447976 -411.202632) (xy 293.731696 -411.202632) (xy 293.721591 -411.202119) (xy 293.702919 -411.194386)
			(xy 293.688625 -411.180098) (xy 293.680885 -411.161429) (xy 293.680388 -411.151324) (xy 293.680388 -410.86532)
			(xy 293.68019 -410.858447) (xy 293.676586 -410.845184) (xy 293.673276 -410.839158) (xy 293.656891 -410.810819)
			(xy 293.631095 -410.750656) (xy 293.613611 -410.687573) (xy 293.604756 -410.622714) (xy 293.604188 -410.589984)
			(xy 290.174825 -410.589984) (xy 290.174826 -410.622704) (xy 290.166045 -410.687547) (xy 290.148641 -410.750625)
			(xy 290.122928 -410.810796) (xy 290.106608 -410.839158) (xy 290.103309 -410.84519) (xy 290.099693 -410.858448)
			(xy 290.099496 -410.86532) (xy 290.099496 -411.151324) (xy 290.099098 -411.16148) (xy 290.091294 -411.180234)
			(xy 290.07689 -411.194557) (xy 290.058092 -411.202255) (xy 290.047934 -411.202632) (xy 289.331654 -411.202632)
			(xy 289.321521 -411.20221) (xy 289.302793 -411.194462) (xy 289.288438 -411.180156) (xy 289.280625 -411.161455)
			(xy 289.280092 -411.151324) (xy 289.280092 -410.86532) (xy 289.279893 -410.858447) (xy 289.27629 -410.845185)
			(xy 289.27298 -410.839158) (xy 289.256643 -410.810805) (xy 289.230924 -410.750632) (xy 289.213516 -410.687552)
			(xy 289.204734 -410.622705) (xy 282.775152 -410.622705) (xy 282.775152 -412.090108) (xy 287.004252 -412.090108)
			(xy 287.004757 -412.05831) (xy 287.013057 -411.995257) (xy 287.029516 -411.933827) (xy 287.053853 -411.875072)
			(xy 287.08565 -411.819995) (xy 287.124365 -411.76954) (xy 287.169334 -411.72457) (xy 287.219788 -411.685855)
			(xy 287.274864 -411.654056) (xy 287.33362 -411.629719) (xy 287.395049 -411.613259) (xy 287.458102 -411.604957)
			(xy 287.4899 -411.60446) (xy 287.521519 -411.604941) (xy 287.584222 -411.613149) (xy 287.645329 -411.629426)
			(xy 287.703806 -411.653496) (xy 287.758665 -411.684953) (xy 287.808977 -411.723264) (xy 287.85389 -411.76778)
			(xy 287.892646 -411.81775) (xy 287.924589 -411.872328) (xy 287.949177 -411.930589) (xy 287.965995 -411.991549)
			(xy 287.974759 -412.054177) (xy 287.975548 -412.08579) (xy 287.975548 -412.086044) (xy 287.976154 -412.095904)
			(xy 287.983857 -412.114071) (xy 287.990534 -412.12135) (xy 289.79622 -413.92729) (xy 289.80362 -413.93413)
			(xy 289.822219 -413.94185) (xy 289.832288 -413.942276) (xy 293.16553 -413.942276) (xy 293.191184 -413.925258)
			(xy 293.197026 -413.91078) (xy 293.200345 -413.901381) (xy 293.200356 -413.881473) (xy 293.192776 -413.863064)
			(xy 293.186104 -413.855662) (xy 291.921184 -412.590742) (xy 291.913903 -412.584069) (xy 291.895736 -412.576363)
			(xy 291.885878 -412.575756) (xy 291.885624 -412.575756) (xy 291.854011 -412.574993) (xy 291.791386 -412.566222)
			(xy 291.730429 -412.549397) (xy 291.672171 -412.524803) (xy 291.617597 -412.492857) (xy 291.567631 -412.454098)
			(xy 291.523117 -412.409183) (xy 291.484809 -412.35887) (xy 291.453355 -412.304011) (xy 291.429286 -412.245534)
			(xy 291.413011 -412.184428) (xy 291.404803 -412.121726) (xy 291.404294 -412.090108) (xy 291.404757 -412.058308)
			(xy 291.413058 -411.995252) (xy 291.429519 -411.933819) (xy 291.453858 -411.875061) (xy 291.485659 -411.819982)
			(xy 291.524378 -411.769526) (xy 291.569351 -411.724555) (xy 291.61981 -411.68584) (xy 291.674891 -411.654043)
			(xy 291.733651 -411.629708) (xy 291.795085 -411.613251) (xy 291.858142 -411.604955) (xy 291.889942 -411.60446)
			(xy 291.92156 -411.604995) (xy 291.98426 -411.613196) (xy 292.045366 -411.629466) (xy 292.103844 -411.65353)
			(xy 292.158702 -411.684981) (xy 292.209015 -411.723287) (xy 292.253929 -411.767799) (xy 292.292686 -411.817765)
			(xy 292.324629 -411.872338) (xy 292.349218 -411.930597) (xy 292.366037 -411.991554) (xy 292.374801 -412.054178)
			(xy 292.37559 -412.08579) (xy 292.37559 -412.086044) (xy 292.376211 -412.095901) (xy 292.383905 -412.114068)
			(xy 292.390576 -412.12135) (xy 293.67226 -413.403034) (xy 293.679676 -413.409854) (xy 293.698263 -413.417584)
			(xy 293.708328 -413.41802) (xy 297.041824 -413.41802) (xy 297.067224 -413.401002) (xy 297.073066 -413.386778)
			(xy 297.076482 -413.377337) (xy 297.076445 -413.357278) (xy 297.068713 -413.33877) (xy 297.06189 -413.331406)
			(xy 296.321226 -412.590742) (xy 296.31393 -412.584087) (xy 296.295775 -412.57637) (xy 296.28592 -412.575756)
			(xy 296.285666 -412.575756) (xy 296.254055 -412.574954) (xy 296.191431 -412.566188) (xy 296.130474 -412.549368)
			(xy 296.072216 -412.524779) (xy 296.017642 -412.492837) (xy 295.967676 -412.454082) (xy 295.923162 -412.40917)
			(xy 295.884853 -412.35886) (xy 295.853398 -412.304004) (xy 295.829329 -412.245529) (xy 295.813053 -412.184425)
			(xy 295.804845 -412.121725) (xy 295.804336 -412.090108) (xy 295.804879 -412.058312) (xy 295.813179 -411.995264)
			(xy 295.829636 -411.933838) (xy 295.853971 -411.875086) (xy 295.885766 -411.820013) (xy 295.924477 -411.769561)
			(xy 295.969442 -411.724593) (xy 296.019893 -411.685879) (xy 296.074964 -411.654082) (xy 296.133715 -411.629744)
			(xy 296.19514 -411.613283) (xy 296.258188 -411.604981) (xy 296.289984 -411.60446) (xy 296.321602 -411.604956)
			(xy 296.384305 -411.613162) (xy 296.445411 -411.629437) (xy 296.503889 -411.653505) (xy 296.558748 -411.68496)
			(xy 296.60906 -411.72327) (xy 296.653974 -411.767786) (xy 296.69273 -411.817754) (xy 296.724672 -411.872331)
			(xy 296.749261 -411.930591) (xy 296.766079 -411.991551) (xy 296.774843 -412.054177) (xy 296.775632 -412.08579)
			(xy 296.775632 -412.086044) (xy 296.776242 -412.095903) (xy 296.783943 -412.11407) (xy 296.790618 -412.12135)
			(xy 297.582082 -412.912814) (xy 297.589493 -412.91964) (xy 297.608084 -412.927368) (xy 297.61815 -412.9278)
			(xy 300.951392 -412.9278) (xy 300.976792 -412.910782) (xy 300.982634 -412.896558) (xy 300.98605 -412.887119)
			(xy 300.986006 -412.867061) (xy 300.978277 -412.848552) (xy 300.971458 -412.841186) (xy 300.721014 -412.590742)
			(xy 300.713722 -412.584082) (xy 300.695564 -412.576368) (xy 300.685708 -412.575756) (xy 300.685454 -412.575756)
			(xy 300.653842 -412.574966) (xy 300.591218 -412.566198) (xy 300.530261 -412.549376) (xy 300.472003 -412.524786)
			(xy 300.417429 -412.492843) (xy 300.367463 -412.454087) (xy 300.322949 -412.409173) (xy 300.284641 -412.358863)
			(xy 300.253186 -412.304006) (xy 300.229117 -412.24553) (xy 300.212841 -412.184426) (xy 300.204633 -412.121726)
			(xy 300.204124 -412.090108) (xy 300.204679 -412.058312) (xy 300.212978 -411.995265) (xy 300.229436 -411.93384)
			(xy 300.253769 -411.875089) (xy 300.285563 -411.820016) (xy 300.324273 -411.769565) (xy 300.369238 -411.724597)
			(xy 300.419686 -411.685883) (xy 300.474757 -411.654085) (xy 300.533506 -411.629747) (xy 300.59493 -411.613285)
			(xy 300.657976 -411.604982) (xy 300.689772 -411.60446) (xy 300.72139 -411.604967) (xy 300.784092 -411.613172)
			(xy 300.845199 -411.629445) (xy 300.903676 -411.653512) (xy 300.958535 -411.684966) (xy 301.008847 -411.723275)
			(xy 301.053761 -411.767789) (xy 301.092517 -411.817757) (xy 301.12446 -411.872333) (xy 301.149048 -411.930593)
			(xy 301.165867 -411.991552) (xy 301.174631 -412.054178) (xy 301.17542 -412.08579) (xy 301.17542 -412.086044)
			(xy 301.176033 -412.095903) (xy 301.183732 -412.11407) (xy 301.190406 -412.12135) (xy 301.51705 -412.447994)
			(xy 301.524474 -412.454804) (xy 301.543055 -412.462541) (xy 301.553118 -412.46298) (xy 304.569114 -412.46298)
			(xy 304.577772 -412.462585) (xy 304.594079 -412.456759) (xy 304.607501 -412.445815) (xy 304.612294 -412.438596)
			(xy 304.664618 -412.352998) (xy 304.66538 -412.326582) (xy 304.65903 -412.314644) (xy 304.645978 -412.288612)
			(xy 304.625464 -412.23411) (xy 304.611609 -412.177547) (xy 304.604613 -412.119733) (xy 304.604166 -412.090616)
			(xy 304.604166 -412.090108) (xy 304.604686 -412.058311) (xy 304.612987 -411.995261) (xy 304.629446 -411.933834)
			(xy 304.653782 -411.875081) (xy 304.685579 -411.820007) (xy 304.724293 -411.769555) (xy 304.769261 -411.724587)
			(xy 304.819713 -411.685873) (xy 304.874787 -411.654076) (xy 304.93354 -411.62974) (xy 304.994967 -411.613281)
			(xy 305.058017 -411.60498) (xy 305.121611 -411.60498) (xy 305.184661 -411.613281) (xy 305.246088 -411.62974)
			(xy 305.304841 -411.654076) (xy 305.359915 -411.685873) (xy 305.410367 -411.724587) (xy 305.455335 -411.769555)
			(xy 305.494049 -411.820007) (xy 305.525846 -411.875081) (xy 305.550182 -411.933834) (xy 305.566641 -411.995261)
			(xy 305.574942 -412.058311) (xy 305.575462 -412.090108) (xy 305.575462 -412.090616) (xy 305.575029 -412.119735)
			(xy 305.568045 -412.177552) (xy 305.554191 -412.234118) (xy 305.533666 -412.288619) (xy 305.520598 -412.314644)
			(xy 305.514248 -412.326582) (xy 305.51501 -412.352998) (xy 305.567334 -412.438596) (xy 305.572125 -412.445815)
			(xy 305.585557 -412.456744) (xy 305.601858 -412.46259) (xy 305.610514 -412.46298) (xy 307.396388 -412.46298)
			(xy 307.406457 -412.462554) (xy 307.425055 -412.454834) (xy 307.432456 -412.447994) (xy 310.540146 -409.340558)
			(xy 310.547003 -409.333172) (xy 310.554712 -409.314562) (xy 310.555132 -409.30449) (xy 310.555132 -393.505182)
			(xy 310.55566 -393.479158) (xy 310.563824 -393.427754) (xy 310.579917 -393.378256) (xy 310.603545 -393.33188)
			(xy 310.634127 -393.289764) (xy 310.65216 -393.270994) (xy 314.489084 -389.43407) (xy 314.507863 -389.415956)
			(xy 314.550063 -389.385275) (xy 314.596544 -389.361576) (xy 314.646162 -389.345444) (xy 314.697693 -389.337275)
			(xy 314.72378 -389.336788) (xy 315.708284 -389.336788) (xy 315.718353 -389.336357) (xy 315.736951 -389.328641)
			(xy 315.744352 -389.321802) (xy 317.096394 -387.96976) (xy 317.100511 -387.965367) (xy 317.106796 -387.955103)
			(xy 317.10884 -387.94944) (xy 317.10884 -387.948932) (xy 317.117301 -387.923393) (xy 317.140371 -387.87479)
			(xy 317.17004 -387.82991) (xy 317.205719 -387.789643) (xy 317.246701 -387.754787) (xy 317.292174 -387.726034)
			(xy 317.341234 -387.703955) (xy 317.39291 -387.688986) (xy 317.446176 -387.681424) (xy 317.473076 -387.680962)
			(xy 317.500325 -387.6815) (xy 317.554269 -387.689253) (xy 317.606561 -387.704604) (xy 317.656136 -387.72724)
			(xy 317.701985 -387.756701) (xy 317.743175 -387.792387) (xy 317.778867 -387.833571) (xy 317.808334 -387.879416)
			(xy 317.830978 -387.928988) (xy 317.846336 -387.981278) (xy 317.854096 -388.035221) (xy 317.854584 -388.06247)
			(xy 317.854158 -388.089382) (xy 317.846571 -388.142668) (xy 317.831573 -388.19436) (xy 317.809461 -388.243432)
			(xy 317.780672 -388.28891) (xy 317.74578 -388.329892) (xy 317.705475 -388.365565) (xy 317.660558 -388.395221)
			(xy 317.61192 -388.418272) (xy 317.58636 -388.426706) (xy 317.586106 -388.426706) (xy 317.580422 -388.428707)
			(xy 317.570142 -388.434989) (xy 317.565786 -388.439152) (xy 317.453518 -388.55142) (xy 317.447422 -388.581392)
			(xy 317.453518 -388.595616) (xy 317.457718 -388.604752) (xy 317.471902 -388.618985) (xy 317.490461 -388.626689)
			(xy 317.500508 -388.627112) (xy 318.384682 -388.627112) (xy 318.390832 -388.626919) (xy 318.402773 -388.623966)
			(xy 318.408304 -388.62127) (xy 318.435827 -388.607426) (xy 318.494246 -388.587865) (xy 318.555047 -388.577936)
			(xy 318.58585 -388.577328) (xy 318.613108 -388.577716) (xy 318.667069 -388.585467) (xy 318.719378 -388.600821)
			(xy 318.768969 -388.623462) (xy 318.814833 -388.652932) (xy 318.856036 -388.688629) (xy 318.891738 -388.729827)
			(xy 318.921214 -388.775687) (xy 318.943862 -388.825275) (xy 318.959222 -388.877582) (xy 318.966981 -388.931542)
			(xy 318.966981 -388.986058) (xy 318.959222 -389.040018) (xy 318.943862 -389.092325) (xy 318.921214 -389.141913)
			(xy 318.891738 -389.187773) (xy 318.856036 -389.228971) (xy 318.814833 -389.264668) (xy 318.768969 -389.294138)
			(xy 318.719378 -389.316779) (xy 318.667069 -389.332133) (xy 318.613108 -389.339884) (xy 318.58585 -389.340344)
			(xy 318.555046 -389.339754) (xy 318.494244 -389.329821) (xy 318.435831 -389.310239) (xy 318.408304 -389.296402)
			(xy 318.402779 -389.293689) (xy 318.390835 -389.290731) (xy 318.384682 -389.29056) (xy 317.405258 -389.29056)
			(xy 317.395184 -389.290948) (xy 317.376586 -389.298693) (xy 317.36919 -389.305546) (xy 317.118492 -389.556498)
			(xy 317.111825 -389.563907) (xy 317.10424 -389.582316) (xy 317.104229 -389.602226) (xy 317.10757 -389.611616)
			(xy 317.111805 -389.620733) (xy 317.125974 -389.634967) (xy 317.144518 -389.642681) (xy 317.15456 -389.643112)
			(xy 317.409068 -389.643112) (xy 317.415218 -389.642914) (xy 317.427159 -389.639964) (xy 317.43269 -389.63727)
			(xy 317.460215 -389.623431) (xy 317.518633 -389.603869) (xy 317.579433 -389.593937) (xy 317.610236 -389.593328)
			(xy 317.637488 -389.593744) (xy 317.691437 -389.601506) (xy 317.743732 -389.616865) (xy 317.79331 -389.639511)
			(xy 317.83916 -389.668981) (xy 317.88035 -389.704676) (xy 317.916041 -389.745869) (xy 317.945507 -389.791722)
			(xy 317.968147 -389.841301) (xy 317.983502 -389.893598) (xy 317.991258 -389.947548) (xy 317.991258 -390.002052)
			(xy 317.983502 -390.056002) (xy 317.968147 -390.108299) (xy 317.945507 -390.157878) (xy 317.916041 -390.203731)
			(xy 317.88035 -390.244924) (xy 317.83916 -390.280619) (xy 317.79331 -390.310089) (xy 317.743732 -390.332735)
			(xy 317.691437 -390.348094) (xy 317.637488 -390.355856) (xy 317.610236 -390.356344) (xy 317.579432 -390.355759)
			(xy 317.51863 -390.345825) (xy 317.460217 -390.32624) (xy 317.43269 -390.312402) (xy 317.427167 -390.309684)
			(xy 317.415221 -390.30673) (xy 317.409068 -390.30656) (xy 317.003684 -390.30656) (xy 316.993612 -390.306961)
			(xy 316.975013 -390.314697) (xy 316.967616 -390.321546) (xy 316.716918 -390.572498) (xy 316.710246 -390.579902)
			(xy 316.70267 -390.598314) (xy 316.702658 -390.618225) (xy 316.705996 -390.627616) (xy 316.710212 -390.636743)
			(xy 316.72439 -390.650977) (xy 316.742941 -390.658685) (xy 316.752986 -390.659112) (xy 318.384682 -390.659112)
			(xy 318.390832 -390.658919) (xy 318.402773 -390.655966) (xy 318.408304 -390.65327) (xy 318.435827 -390.639426)
			(xy 318.494246 -390.619865) (xy 318.555047 -390.609936) (xy 318.58585 -390.609328) (xy 318.613108 -390.609716)
			(xy 318.667069 -390.617467) (xy 318.719378 -390.632821) (xy 318.768969 -390.655462) (xy 318.814833 -390.684932)
			(xy 318.856036 -390.720629) (xy 318.891738 -390.761827) (xy 318.902939 -390.779254) (xy 319.428876 -390.779254)
			(xy 319.428876 -389.479282) (xy 319.42942 -389.453259) (xy 319.437582 -389.401856) (xy 319.453673 -389.35236)
			(xy 319.477296 -389.305983) (xy 319.507873 -389.263865) (xy 319.525904 -389.245094) (xy 320.42735 -388.343648)
			(xy 320.434155 -388.33622) (xy 320.441897 -388.317642) (xy 320.442336 -388.30758) (xy 320.442336 -388.1374)
			(xy 320.439796 -388.126224) (xy 320.437002 -388.12089) (xy 320.436494 -388.119874) (xy 320.422757 -388.092406)
			(xy 320.403309 -388.034155) (xy 320.393439 -387.973541) (xy 320.392806 -387.942836) (xy 320.393292 -387.915585)
			(xy 320.401048 -387.861637) (xy 320.416403 -387.809342) (xy 320.439045 -387.759765) (xy 320.468511 -387.713915)
			(xy 320.504202 -387.672724) (xy 320.545393 -387.637033) (xy 320.591243 -387.607567) (xy 320.64082 -387.584925)
			(xy 320.693115 -387.56957) (xy 320.747063 -387.561814) (xy 320.801565 -387.561814) (xy 320.855513 -387.56957)
			(xy 320.907808 -387.584925) (xy 320.957385 -387.607567) (xy 321.003235 -387.637033) (xy 321.044426 -387.672724)
			(xy 321.080117 -387.713915) (xy 321.109583 -387.759765) (xy 321.132225 -387.809342) (xy 321.14758 -387.861637)
			(xy 321.155336 -387.915585) (xy 321.155822 -387.942836) (xy 321.155218 -387.973639) (xy 321.14529 -388.03444)
			(xy 321.125714 -388.092854) (xy 321.11188 -388.120382) (xy 321.111626 -388.12089) (xy 321.109127 -388.126202)
			(xy 321.106439 -388.137627) (xy 321.106292 -388.143496) (xy 321.106292 -388.466076) (xy 321.106156 -388.477482)
			(xy 321.104501 -388.500235) (xy 321.10299 -388.511542) (xy 321.10299 -388.511796) (xy 321.102014 -388.522549)
			(xy 321.108219 -388.543212) (xy 321.114928 -388.551674) (xy 321.16522 -388.609586) (xy 321.172741 -388.617536)
			(xy 321.19264 -388.626603) (xy 321.203574 -388.627112) (xy 321.701414 -388.627112) (xy 321.707565 -388.62693)
			(xy 321.719506 -388.623969) (xy 321.725036 -388.62127) (xy 321.75257 -388.607451) (xy 321.810983 -388.587881)
			(xy 321.87178 -388.577941) (xy 321.902582 -388.577328) (xy 321.929838 -388.577718) (xy 321.983796 -388.585473)
			(xy 322.036101 -388.600829) (xy 322.085688 -388.623473) (xy 322.131548 -388.652943) (xy 322.172747 -388.68864)
			(xy 322.208446 -388.729837) (xy 322.237918 -388.775696) (xy 322.260564 -388.825282) (xy 322.275923 -388.877586)
			(xy 322.283681 -388.931544) (xy 322.283681 -388.986056) (xy 322.275923 -389.040014) (xy 322.260564 -389.092318)
			(xy 322.237918 -389.141904) (xy 322.208446 -389.187763) (xy 322.172747 -389.22896) (xy 322.131548 -389.264657)
			(xy 322.085688 -389.294127) (xy 322.036101 -389.316771) (xy 321.983796 -389.332127) (xy 321.929838 -389.339882)
			(xy 321.902582 -389.340344) (xy 321.871779 -389.339741) (xy 321.810977 -389.329814) (xy 321.752564 -389.310237)
			(xy 321.725036 -389.296402) (xy 321.719506 -389.293699) (xy 321.707566 -389.290735) (xy 321.701414 -389.29056)
			(xy 320.948558 -389.29056) (xy 320.938484 -389.290948) (xy 320.919886 -389.298693) (xy 320.91249 -389.305546)
			(xy 320.790062 -389.427974) (xy 320.783898 -389.434791) (xy 320.776405 -389.451556) (xy 320.775286 -389.469885)
			(xy 320.777616 -389.478774) (xy 320.804286 -389.56488) (xy 320.807447 -389.573562) (xy 320.818845 -389.588084)
			(xy 320.834648 -389.597625) (xy 320.843656 -389.599678) (xy 320.86963 -389.604899) (xy 320.919893 -389.621646)
			(xy 320.967355 -389.645187) (xy 321.011104 -389.675069) (xy 321.050298 -389.710716) (xy 321.084182 -389.751444)
			(xy 321.112105 -389.796468) (xy 321.133531 -389.844922) (xy 321.148045 -389.895875) (xy 321.155371 -389.948346)
			(xy 321.155822 -389.974836) (xy 321.155218 -390.005639) (xy 321.14529 -390.06644) (xy 321.125714 -390.124854)
			(xy 321.11188 -390.152382) (xy 321.111626 -390.15289) (xy 321.109127 -390.158202) (xy 321.106439 -390.169627)
			(xy 321.106292 -390.175496) (xy 321.106292 -390.488424) (xy 321.106681 -390.498498) (xy 321.114424 -390.517097)
			(xy 321.121278 -390.524492) (xy 321.391026 -390.79424) (xy 321.3994 -390.80182) (xy 321.420633 -390.809451)
			(xy 321.43192 -390.808972) (xy 321.521582 -390.800082) (xy 321.540886 -390.788398) (xy 321.547236 -390.779)
			(xy 321.562439 -390.756956) (xy 321.598107 -390.717014) (xy 321.639011 -390.682453) (xy 321.684348 -390.653955)
			(xy 321.733225 -390.632078) (xy 321.784682 -390.617255) (xy 321.837707 -390.609775) (xy 321.864482 -390.609328)
			(xy 321.895286 -390.609909) (xy 321.956088 -390.619846) (xy 322.014501 -390.639431) (xy 322.042028 -390.65327)
			(xy 322.047549 -390.655991) (xy 322.059497 -390.658944) (xy 322.06565 -390.659112) (xy 326.881744 -390.659112)
			(xy 326.907768 -390.659629) (xy 326.959172 -390.667796) (xy 327.00867 -390.683893) (xy 327.055046 -390.707523)
			(xy 327.097162 -390.738106) (xy 327.115932 -390.75614) (xy 329.851004 -393.491212) (xy 329.869011 -393.510006)
			(xy 329.899594 -393.552117) (xy 329.923226 -393.598487) (xy 329.939327 -393.647979) (xy 329.947501 -393.699378)
			(xy 329.948032 -393.7254) (xy 329.948032 -401.7228) (xy 331.005006 -401.7228) (xy 331.005009 -401.657362)
			(xy 331.013795 -401.592516) (xy 331.031207 -401.529437) (xy 331.056928 -401.469265) (xy 331.073252 -401.440904)
			(xy 331.076561 -401.434877) (xy 331.080171 -401.421615) (xy 331.080364 -401.414742) (xy 331.080364 -400.665442)
			(xy 331.08016 -400.65857) (xy 331.076561 -400.645307) (xy 331.073252 -400.63928) (xy 331.056934 -400.610916)
			(xy 331.031216 -400.550746) (xy 331.013807 -400.487668) (xy 331.005022 -400.422823) (xy 331.005021 -400.357387)
			(xy 331.013804 -400.292543) (xy 331.031212 -400.229464) (xy 331.05693 -400.169293) (xy 331.073252 -400.140932)
			(xy 331.076552 -400.1349) (xy 331.080167 -400.121642) (xy 331.080364 -400.11477) (xy 331.080364 -399.828766)
			(xy 331.080806 -399.818603) (xy 331.088597 -399.799828) (xy 331.102978 -399.785463) (xy 331.121762 -399.777694)
			(xy 331.131926 -399.777204) (xy 331.848206 -399.777204) (xy 331.85836 -399.777728) (xy 331.877123 -399.785498)
			(xy 331.891486 -399.799854) (xy 331.899267 -399.818612) (xy 331.899768 -399.828766) (xy 331.899768 -400.11477)
			(xy 331.899975 -400.121642) (xy 331.903573 -400.134905) (xy 331.90688 -400.140932) (xy 331.923207 -400.169291)
			(xy 331.948923 -400.229463) (xy 331.96633 -400.292542) (xy 331.975112 -400.357387) (xy 331.975112 -400.422824)
			(xy 331.966328 -400.487668) (xy 331.948919 -400.550747) (xy 331.923202 -400.610919) (xy 331.90688 -400.63928)
			(xy 331.903571 -400.645307) (xy 331.899962 -400.658569) (xy 331.899768 -400.665442) (xy 331.899768 -401.414742)
			(xy 331.899986 -401.421613) (xy 331.903577 -401.434876) (xy 331.90688 -401.440904) (xy 331.923183 -401.469276)
			(xy 331.948901 -401.529445) (xy 331.966311 -401.592521) (xy 331.975096 -401.657364) (xy 331.975099 -401.722799)
			(xy 331.966318 -401.787642) (xy 331.948914 -401.85072) (xy 331.9232 -401.910891) (xy 331.90688 -401.939252)
			(xy 331.903545 -401.945267) (xy 331.899953 -401.958538) (xy 331.899768 -401.965414) (xy 331.899768 -402.251418)
			(xy 331.899282 -402.261576) (xy 331.891502 -402.280345) (xy 331.877135 -402.294709) (xy 331.858364 -402.302484)
			(xy 331.848206 -402.30298) (xy 331.131926 -402.30298) (xy 331.121758 -402.302515) (xy 331.102968 -402.294742)
			(xy 331.088583 -402.280369) (xy 331.080794 -402.261585) (xy 331.080364 -402.251418) (xy 331.080364 -401.965414)
			(xy 331.080171 -401.958541) (xy 331.076564 -401.945278) (xy 331.073252 -401.939252) (xy 331.056911 -401.910901)
			(xy 331.031194 -401.850728) (xy 331.013788 -401.787647) (xy 331.005006 -401.7228) (xy 329.948032 -401.7228)
			(xy 329.948032 -402.790152) (xy 333.204312 -402.790152) (xy 333.204877 -402.757422) (xy 333.213733 -402.692564)
			(xy 333.231223 -402.629484) (xy 333.257031 -402.569326) (xy 333.2734 -402.540978) (xy 333.276723 -402.534957)
			(xy 333.280323 -402.52169) (xy 333.280512 -402.514816) (xy 333.280512 -401.765516) (xy 333.280313 -401.758643)
			(xy 333.276709 -401.745381) (xy 333.2734 -401.739354) (xy 333.257016 -401.711015) (xy 333.231219 -401.650852)
			(xy 333.213734 -401.587769) (xy 333.204879 -401.52291) (xy 333.204312 -401.49018) (xy 333.20489 -401.457451)
			(xy 333.213742 -401.392593) (xy 333.231228 -401.329513) (xy 333.257033 -401.269354) (xy 333.2734 -401.241006)
			(xy 333.276713 -401.23498) (xy 333.28032 -401.221717) (xy 333.280512 -401.214844) (xy 333.280512 -400.92884)
			(xy 333.280949 -400.918719) (xy 333.288686 -400.900014) (xy 333.302997 -400.885698) (xy 333.321699 -400.877953)
			(xy 333.33182 -400.877532) (xy 334.0481 -400.877532) (xy 334.058226 -400.877917) (xy 334.076936 -400.885671)
			(xy 334.091252 -400.899997) (xy 334.098991 -400.918713) (xy 334.099408 -400.92884) (xy 334.099408 -401.214844)
			(xy 334.09962 -401.221716) (xy 334.103215 -401.234979) (xy 334.10652 -401.241006) (xy 334.12289 -401.269353)
			(xy 334.14869 -401.329513) (xy 334.166179 -401.392594) (xy 334.175038 -401.457451) (xy 334.175608 -401.49018)
			(xy 334.175055 -401.52291) (xy 334.166195 -401.587769) (xy 334.148701 -401.650849) (xy 334.131869 -401.690078)
			(xy 335.40446 -401.690078) (xy 335.405043 -401.657349) (xy 335.413895 -401.592492) (xy 335.43138 -401.529412)
			(xy 335.457182 -401.469253) (xy 335.473548 -401.440904) (xy 335.476857 -401.434877) (xy 335.480467 -401.421615)
			(xy 335.48066 -401.414742) (xy 335.48066 -400.665442) (xy 335.480457 -400.65857) (xy 335.476857 -400.645307)
			(xy 335.473548 -400.63928) (xy 335.457179 -400.610933) (xy 335.431377 -400.550773) (xy 335.413888 -400.487693)
			(xy 335.405029 -400.422835) (xy 335.40446 -400.390106) (xy 335.405011 -400.357376) (xy 335.413872 -400.292517)
			(xy 335.431367 -400.229437) (xy 335.457178 -400.16928) (xy 335.473548 -400.140932) (xy 335.476847 -400.1349)
			(xy 335.480463 -400.121642) (xy 335.48066 -400.11477) (xy 335.48066 -399.828766) (xy 335.481099 -399.818635)
			(xy 335.488842 -399.799909) (xy 335.503143 -399.785553) (xy 335.521839 -399.777739) (xy 335.531968 -399.777204)
			(xy 336.248248 -399.777204) (xy 336.258406 -399.777583) (xy 336.27716 -399.785395) (xy 336.291482 -399.799804)
			(xy 336.299179 -399.818606) (xy 336.299556 -399.828766) (xy 336.299556 -400.11477) (xy 336.299752 -400.121643)
			(xy 336.303357 -400.134906) (xy 336.306668 -400.140932) (xy 336.323043 -400.169276) (xy 336.348843 -400.229437)
			(xy 336.366331 -400.292518) (xy 336.375188 -400.357377) (xy 336.375756 -400.390106) (xy 336.375163 -400.422834)
			(xy 336.366314 -400.487692) (xy 336.348832 -400.550772) (xy 336.323033 -400.610931) (xy 336.306668 -400.63928)
			(xy 336.303358 -400.645307) (xy 336.29975 -400.658569) (xy 336.299556 -400.665442) (xy 336.299556 -401.414742)
			(xy 336.299763 -401.421614) (xy 336.30336 -401.434877) (xy 336.306668 -401.440904) (xy 336.323032 -401.469254)
			(xy 336.348835 -401.529413) (xy 336.366325 -401.592492) (xy 336.375186 -401.657349) (xy 336.375756 -401.690078)
			(xy 336.375195 -401.722808) (xy 336.366337 -401.787666) (xy 336.348845 -401.850746) (xy 336.323037 -401.910904)
			(xy 336.306668 -401.939252) (xy 336.303333 -401.945266) (xy 336.299741 -401.958538) (xy 336.299556 -401.965414)
			(xy 336.299556 -402.251418) (xy 336.299088 -402.261546) (xy 336.291354 -402.280269) (xy 336.277062 -402.294625)
			(xy 336.258374 -402.302443) (xy 336.248248 -402.30298) (xy 335.531968 -402.30298) (xy 335.521809 -402.302604)
			(xy 335.503052 -402.294794) (xy 335.488729 -402.280384) (xy 335.481034 -402.261579) (xy 335.48066 -402.251418)
			(xy 335.48066 -401.965414) (xy 335.480468 -401.958541) (xy 335.47686 -401.945278) (xy 335.473548 -401.939252)
			(xy 335.457168 -401.910911) (xy 335.431368 -401.850749) (xy 335.413883 -401.787667) (xy 335.405027 -401.722808)
			(xy 335.40446 -401.690078) (xy 334.131869 -401.690078) (xy 334.12289 -401.711006) (xy 334.10652 -401.739354)
			(xy 334.103223 -401.745387) (xy 334.099606 -401.758644) (xy 334.099408 -401.765516) (xy 334.099408 -402.514816)
			(xy 334.099593 -402.52169) (xy 334.103206 -402.534953) (xy 334.10652 -402.540978) (xy 334.122879 -402.569331)
			(xy 334.148682 -402.629489) (xy 334.166173 -402.692568) (xy 334.175036 -402.757423) (xy 334.175608 -402.790152)
			(xy 334.175042 -402.822879) (xy 337.604936 -402.822879) (xy 337.604942 -402.757439) (xy 337.61373 -402.692593)
			(xy 337.631143 -402.629512) (xy 337.656864 -402.56934) (xy 337.673188 -402.540978) (xy 337.67651 -402.534957)
			(xy 337.680111 -402.52169) (xy 337.6803 -402.514816) (xy 337.6803 -401.765516) (xy 337.680102 -401.758643)
			(xy 337.676498 -401.74538) (xy 337.673188 -401.739354) (xy 337.65685 -401.711002) (xy 337.631137 -401.650828)
			(xy 337.613733 -401.587747) (xy 337.604952 -401.522902) (xy 337.604955 -401.457464) (xy 337.61374 -401.392619)
			(xy 337.631148 -401.32954) (xy 337.656866 -401.269368) (xy 337.673188 -401.241006) (xy 337.6765 -401.23498)
			(xy 337.680108 -401.221717) (xy 337.6803 -401.214844) (xy 337.6803 -400.92884) (xy 337.680755 -400.918688)
			(xy 337.688537 -400.899937) (xy 337.702924 -400.885612) (xy 337.721709 -400.877911) (xy 337.731862 -400.877532)
			(xy 338.448142 -400.877532) (xy 338.45827 -400.877992) (xy 338.476991 -400.885732) (xy 338.491346 -400.900026)
			(xy 338.499165 -400.918714) (xy 338.499704 -400.92884) (xy 338.499704 -401.214844) (xy 338.499917 -401.221716)
			(xy 338.503511 -401.234978) (xy 338.506816 -401.241006) (xy 338.523123 -401.269376) (xy 338.548844 -401.329545)
			(xy 338.566256 -401.392622) (xy 338.575042 -401.457465) (xy 338.575045 -401.522901) (xy 338.566263 -401.587745)
			(xy 338.548856 -401.650823) (xy 338.523138 -401.710993) (xy 338.516343 -401.7228) (xy 339.805092 -401.7228)
			(xy 339.805095 -401.657362) (xy 339.813881 -401.592516) (xy 339.831292 -401.529437) (xy 339.857012 -401.469265)
			(xy 339.873336 -401.440904) (xy 339.876644 -401.434876) (xy 339.880255 -401.421615) (xy 339.880448 -401.414742)
			(xy 339.880448 -400.665442) (xy 339.880247 -400.658569) (xy 339.876646 -400.645306) (xy 339.873336 -400.63928)
			(xy 339.857019 -400.610916) (xy 339.831301 -400.550745) (xy 339.813892 -400.487667) (xy 339.805108 -400.422823)
			(xy 339.805108 -400.357387) (xy 339.81389 -400.292543) (xy 339.831298 -400.229464) (xy 339.857014 -400.169293)
			(xy 339.873336 -400.140932) (xy 339.876634 -400.134899) (xy 339.880251 -400.121642) (xy 339.880448 -400.11477)
			(xy 339.880448 -399.828766) (xy 339.880906 -399.818605) (xy 339.888693 -399.799833) (xy 339.90307 -399.785469)
			(xy 339.921848 -399.777697) (xy 339.93201 -399.777204) (xy 340.64829 -399.777204) (xy 340.658443 -399.777741)
			(xy 340.677205 -399.785506) (xy 340.69157 -399.799858) (xy 340.699351 -399.818613) (xy 340.699852 -399.828766)
			(xy 340.699852 -400.11477) (xy 340.700049 -400.121643) (xy 340.703653 -400.134906) (xy 340.706964 -400.140932)
			(xy 340.723291 -400.16929) (xy 340.749008 -400.229462) (xy 340.766416 -400.292542) (xy 340.775198 -400.357387)
			(xy 340.775198 -400.422824) (xy 340.766414 -400.487669) (xy 340.749005 -400.550747) (xy 340.723287 -400.610919)
			(xy 340.706964 -400.63928) (xy 340.703661 -400.645311) (xy 340.700047 -400.65857) (xy 340.699852 -400.665442)
			(xy 340.699852 -401.414742) (xy 340.700059 -401.421614) (xy 340.703656 -401.434877) (xy 340.706964 -401.440904)
			(xy 340.723268 -401.469276) (xy 340.748987 -401.529444) (xy 340.766397 -401.592521) (xy 340.775183 -401.657364)
			(xy 340.775185 -401.722799) (xy 340.766404 -401.787642) (xy 340.748999 -401.85072) (xy 340.723285 -401.910891)
			(xy 340.706964 -401.939252) (xy 340.703636 -401.94527) (xy 340.700038 -401.958539) (xy 340.699852 -401.965414)
			(xy 340.699852 -402.251418) (xy 340.699381 -402.261578) (xy 340.691599 -402.28035) (xy 340.677226 -402.294715)
			(xy 340.65845 -402.302487) (xy 340.64829 -402.30298) (xy 339.93201 -402.30298) (xy 339.921855 -402.302459)
			(xy 339.90309 -402.294691) (xy 339.888725 -402.280334) (xy 339.880947 -402.261573) (xy 339.880448 -402.251418)
			(xy 339.880448 -401.965414) (xy 339.880257 -401.958541) (xy 339.876649 -401.945278) (xy 339.873336 -401.939252)
			(xy 339.856995 -401.910901) (xy 339.83128 -401.850727) (xy 339.813874 -401.787647) (xy 339.805092 -401.7228)
			(xy 338.516343 -401.7228) (xy 338.506816 -401.739354) (xy 338.503519 -401.745387) (xy 338.499902 -401.758644)
			(xy 338.499704 -401.765516) (xy 338.499704 -402.514816) (xy 338.499889 -402.52169) (xy 338.503502 -402.534953)
			(xy 338.506816 -402.540978) (xy 338.523099 -402.569361) (xy 338.548823 -402.629527) (xy 338.566237 -402.692601)
			(xy 338.575026 -402.757442) (xy 338.575029 -402.790152) (xy 342.004396 -402.790152) (xy 342.004963 -402.757423)
			(xy 342.013819 -402.692564) (xy 342.031309 -402.629484) (xy 342.057116 -402.569326) (xy 342.073484 -402.540978)
			(xy 342.076805 -402.534957) (xy 342.080407 -402.52169) (xy 342.080596 -402.514816) (xy 342.080596 -401.765516)
			(xy 342.080398 -401.758643) (xy 342.076794 -401.74538) (xy 342.073484 -401.739354) (xy 342.057099 -401.711016)
			(xy 342.031302 -401.650852) (xy 342.013818 -401.587769) (xy 342.004963 -401.52291) (xy 342.004396 -401.49018)
			(xy 342.004976 -401.457451) (xy 342.013828 -401.392593) (xy 342.031314 -401.329513) (xy 342.057117 -401.269355)
			(xy 342.073484 -401.241006) (xy 342.076795 -401.23498) (xy 342.080403 -401.221717) (xy 342.080596 -401.214844)
			(xy 342.080596 -400.92884) (xy 342.081049 -400.918721) (xy 342.088783 -400.900019) (xy 342.103088 -400.885703)
			(xy 342.121785 -400.877956) (xy 342.131904 -400.877532) (xy 342.848184 -400.877532) (xy 342.858309 -400.87793)
			(xy 342.877019 -400.885679) (xy 342.891335 -400.900001) (xy 342.899075 -400.918714) (xy 342.899492 -400.92884)
			(xy 342.899492 -401.214844) (xy 342.899707 -401.221716) (xy 342.9033 -401.234978) (xy 342.906604 -401.241006)
			(xy 342.922972 -401.269354) (xy 342.948773 -401.329514) (xy 342.966262 -401.392594) (xy 342.975122 -401.457451)
			(xy 342.975692 -401.49018) (xy 342.975141 -401.52291) (xy 342.966281 -401.587769) (xy 342.948786 -401.650849)
			(xy 342.922974 -401.711006) (xy 342.916163 -401.7228) (xy 344.204882 -401.7228) (xy 344.204885 -401.657362)
			(xy 344.213671 -401.592517) (xy 344.231081 -401.529437) (xy 344.256801 -401.469265) (xy 344.273124 -401.440904)
			(xy 344.276439 -401.43488) (xy 344.280044 -401.421616) (xy 344.280236 -401.414742) (xy 344.280236 -400.665442)
			(xy 344.280024 -400.65857) (xy 344.276429 -400.645308) (xy 344.273124 -400.63928) (xy 344.256807 -400.610916)
			(xy 344.23109 -400.550745) (xy 344.213682 -400.487667) (xy 344.204898 -400.422823) (xy 344.204897 -400.357387)
			(xy 344.21368 -400.292543) (xy 344.231087 -400.229465) (xy 344.256803 -400.169293) (xy 344.273124 -400.140932)
			(xy 344.276429 -400.134903) (xy 344.28004 -400.121643) (xy 344.280236 -400.11477) (xy 344.280236 -399.828766)
			(xy 344.280705 -399.818606) (xy 344.288491 -399.799837) (xy 344.302864 -399.785473) (xy 344.321638 -399.777699)
			(xy 344.331798 -399.777204) (xy 345.048078 -399.777204) (xy 345.05823 -399.77775) (xy 345.076992 -399.785511)
			(xy 345.091357 -399.799861) (xy 345.099139 -399.818614) (xy 345.09964 -399.828766) (xy 345.09964 -400.11477)
			(xy 345.099838 -400.121643) (xy 345.103442 -400.134906) (xy 345.106752 -400.140932) (xy 345.12308 -400.16929)
			(xy 345.148797 -400.229462) (xy 345.166205 -400.292541) (xy 345.174988 -400.357387) (xy 345.174987 -400.390106)
			(xy 348.603832 -400.390106) (xy 348.607823 -400.327939) (xy 348.619732 -400.266792) (xy 348.639361 -400.207671)
			(xy 348.66639 -400.151545) (xy 348.700374 -400.099336) (xy 348.740756 -400.051901) (xy 348.786872 -400.01002)
			(xy 348.837964 -399.97438) (xy 348.893195 -399.945566) (xy 348.951657 -399.924052) (xy 349.012391 -399.91019)
			(xy 349.074398 -399.904208) (xy 349.136661 -399.906204) (xy 349.198158 -399.916147) (xy 349.257879 -399.933871)
			(xy 349.314842 -399.959088) (xy 349.368113 -399.991381) (xy 349.416818 -400.030221) (xy 349.460155 -400.074971)
			(xy 349.497415 -400.124895) (xy 349.527984 -400.179174) (xy 349.551362 -400.236917) (xy 349.567163 -400.297175)
			(xy 349.575129 -400.358958) (xy 349.575628 -400.390106) (xy 349.575129 -400.421254) (xy 349.567163 -400.483037)
			(xy 349.551362 -400.543295) (xy 349.527984 -400.601038) (xy 349.497415 -400.655317) (xy 349.460155 -400.705241)
			(xy 349.416818 -400.749991) (xy 349.368113 -400.788831) (xy 349.314842 -400.821124) (xy 349.257879 -400.846341)
			(xy 349.198158 -400.864065) (xy 349.136661 -400.874008) (xy 349.074398 -400.876004) (xy 349.012391 -400.870022)
			(xy 348.951657 -400.85616) (xy 348.893195 -400.834646) (xy 348.837964 -400.805832) (xy 348.786872 -400.770192)
			(xy 348.740756 -400.728311) (xy 348.700374 -400.680876) (xy 348.66639 -400.628667) (xy 348.639361 -400.572541)
			(xy 348.619732 -400.51342) (xy 348.607823 -400.452273) (xy 348.603832 -400.390106) (xy 345.174987 -400.390106)
			(xy 345.174987 -400.422824) (xy 345.166203 -400.487669) (xy 345.148794 -400.550748) (xy 345.123075 -400.610919)
			(xy 345.106752 -400.63928) (xy 345.103449 -400.64531) (xy 345.099835 -400.65857) (xy 345.09964 -400.665442)
			(xy 345.09964 -401.414742) (xy 345.099849 -401.421614) (xy 345.103445 -401.434877) (xy 345.106752 -401.440904)
			(xy 345.123056 -401.469275) (xy 345.148776 -401.529444) (xy 345.166186 -401.592521) (xy 345.174972 -401.657363)
			(xy 345.174975 -401.722799) (xy 345.166194 -401.787642) (xy 345.148788 -401.85072) (xy 345.123073 -401.910891)
			(xy 345.106752 -401.939252) (xy 345.103423 -401.94527) (xy 345.099826 -401.958539) (xy 345.09964 -401.965414)
			(xy 345.09964 -402.251418) (xy 345.09925 -402.261593) (xy 345.091455 -402.280393) (xy 345.077059 -402.294778)
			(xy 345.058254 -402.302558) (xy 345.048078 -402.30298) (xy 344.331798 -402.30298) (xy 344.321642 -402.302469)
			(xy 344.302877 -402.294697) (xy 344.288512 -402.280337) (xy 344.280735 -402.261574) (xy 344.280236 -402.251418)
			(xy 344.280236 -401.965414) (xy 344.280034 -401.958542) (xy 344.276432 -401.945279) (xy 344.273124 -401.939252)
			(xy 344.256784 -401.910901) (xy 344.231069 -401.850727) (xy 344.213663 -401.787646) (xy 344.204882 -401.7228)
			(xy 342.916163 -401.7228) (xy 342.906604 -401.739354) (xy 342.903306 -401.745387) (xy 342.89969 -401.758644)
			(xy 342.899492 -401.765516) (xy 342.899492 -402.514816) (xy 342.899679 -402.52169) (xy 342.903291 -402.534952)
			(xy 342.906604 -402.540978) (xy 342.922961 -402.569332) (xy 342.948765 -402.62949) (xy 342.966257 -402.692568)
			(xy 342.97512 -402.757423) (xy 342.975692 -402.790152) (xy 342.975128 -402.822879) (xy 346.405009 -402.822879)
			(xy 346.405014 -402.757439) (xy 346.413804 -402.692591) (xy 346.43122 -402.629511) (xy 346.456946 -402.569339)
			(xy 346.473272 -402.540978) (xy 346.476593 -402.534956) (xy 346.480195 -402.52169) (xy 346.480384 -402.514816)
			(xy 346.480384 -401.765516) (xy 346.480188 -401.758643) (xy 346.476583 -401.74538) (xy 346.473272 -401.739354)
			(xy 346.456932 -401.711002) (xy 346.431214 -401.650829) (xy 346.413807 -401.587749) (xy 346.405025 -401.522902)
			(xy 346.405027 -401.457464) (xy 346.413813 -401.392618) (xy 346.431225 -401.329538) (xy 346.456947 -401.269367)
			(xy 346.473272 -401.241006) (xy 346.476583 -401.234979) (xy 346.480191 -401.221717) (xy 346.480384 -401.214844)
			(xy 346.480384 -400.92884) (xy 346.480854 -400.91869) (xy 346.488634 -400.899942) (xy 346.503015 -400.885618)
			(xy 346.521795 -400.877914) (xy 346.531946 -400.877532) (xy 347.248226 -400.877532) (xy 347.258353 -400.878005)
			(xy 347.277074 -400.88574) (xy 347.291429 -400.90003) (xy 347.299249 -400.918715) (xy 347.299788 -400.92884)
			(xy 347.299788 -401.214844) (xy 347.300003 -401.221716) (xy 347.303596 -401.234978) (xy 347.3069 -401.241006)
			(xy 347.323204 -401.269377) (xy 347.348921 -401.329546) (xy 347.36633 -401.392623) (xy 347.375115 -401.457465)
			(xy 347.375117 -401.5229) (xy 347.366337 -401.587743) (xy 347.348933 -401.650821) (xy 347.332157 -401.690078)
			(xy 348.603832 -401.690078) (xy 348.607823 -401.627911) (xy 348.619732 -401.566764) (xy 348.639361 -401.507643)
			(xy 348.66639 -401.451517) (xy 348.700374 -401.399308) (xy 348.740756 -401.351873) (xy 348.786872 -401.309992)
			(xy 348.837964 -401.274352) (xy 348.893195 -401.245538) (xy 348.951657 -401.224024) (xy 349.012391 -401.210162)
			(xy 349.074398 -401.20418) (xy 349.136661 -401.206176) (xy 349.198158 -401.216119) (xy 349.257879 -401.233843)
			(xy 349.314842 -401.25906) (xy 349.368113 -401.291353) (xy 349.416818 -401.330193) (xy 349.460155 -401.374943)
			(xy 349.497415 -401.424867) (xy 349.527984 -401.479146) (xy 349.532451 -401.49018) (xy 350.80398 -401.49018)
			(xy 350.807971 -401.428013) (xy 350.81988 -401.366866) (xy 350.839509 -401.307745) (xy 350.866538 -401.251619)
			(xy 350.900522 -401.19941) (xy 350.940904 -401.151975) (xy 350.98702 -401.110094) (xy 351.038112 -401.074454)
			(xy 351.093343 -401.04564) (xy 351.151805 -401.024126) (xy 351.212539 -401.010264) (xy 351.274546 -401.004282)
			(xy 351.336809 -401.006278) (xy 351.398306 -401.016221) (xy 351.458027 -401.033945) (xy 351.51499 -401.059162)
			(xy 351.568261 -401.091455) (xy 351.616966 -401.130295) (xy 351.660303 -401.175045) (xy 351.697563 -401.224969)
			(xy 351.728132 -401.279248) (xy 351.75151 -401.336991) (xy 351.767311 -401.397249) (xy 351.775277 -401.459032)
			(xy 351.775776 -401.49018) (xy 351.775277 -401.521328) (xy 351.767311 -401.583111) (xy 351.75151 -401.643369)
			(xy 351.728132 -401.701112) (xy 351.715918 -401.7228) (xy 375.004916 -401.7228) (xy 375.004919 -401.657362)
			(xy 375.013706 -401.592516) (xy 375.031118 -401.529436) (xy 375.05684 -401.469265) (xy 375.073164 -401.440904)
			(xy 375.076474 -401.434877) (xy 375.080083 -401.421615) (xy 375.080276 -401.414742) (xy 375.080276 -400.665442)
			(xy 375.080071 -400.65857) (xy 375.076472 -400.645307) (xy 375.073164 -400.63928) (xy 375.056846 -400.610916)
			(xy 375.031127 -400.550746) (xy 375.013717 -400.487668) (xy 375.004932 -400.422823) (xy 375.004932 -400.357387)
			(xy 375.013715 -400.292542) (xy 375.031123 -400.229464) (xy 375.056841 -400.169293) (xy 375.073164 -400.140932)
			(xy 375.076464 -400.1349) (xy 375.080079 -400.121642) (xy 375.080276 -400.11477) (xy 375.080276 -399.828766)
			(xy 375.080637 -399.818587) (xy 375.08844 -399.799785) (xy 375.102845 -399.7854) (xy 375.121659 -399.777623)
			(xy 375.131838 -399.777204) (xy 375.848118 -399.777204) (xy 375.858273 -399.777718) (xy 375.877036 -399.785492)
			(xy 375.891399 -399.799851) (xy 375.899179 -399.818611) (xy 375.89968 -399.828766) (xy 375.89968 -400.11477)
			(xy 375.899886 -400.121642) (xy 375.903485 -400.134905) (xy 375.906792 -400.140932) (xy 375.923118 -400.169291)
			(xy 375.948834 -400.229463) (xy 375.96624 -400.292542) (xy 375.975023 -400.357387) (xy 375.975022 -400.422824)
			(xy 375.966238 -400.487668) (xy 375.94883 -400.550747) (xy 375.923114 -400.610918) (xy 375.906792 -400.63928)
			(xy 375.903484 -400.645308) (xy 375.899874 -400.658569) (xy 375.89968 -400.665442) (xy 375.89968 -401.414742)
			(xy 375.899897 -401.421613) (xy 375.903489 -401.434876) (xy 375.906792 -401.440904) (xy 375.923095 -401.469276)
			(xy 375.948812 -401.529445) (xy 375.966221 -401.592521) (xy 375.975007 -401.657364) (xy 375.975009 -401.722799)
			(xy 375.966229 -401.787642) (xy 375.948825 -401.850719) (xy 375.923112 -401.91089) (xy 375.906792 -401.939252)
			(xy 375.903458 -401.945267) (xy 375.899865 -401.958538) (xy 375.89968 -401.965414) (xy 375.89968 -402.251418)
			(xy 375.899182 -402.261575) (xy 375.891405 -402.280341) (xy 375.877041 -402.294705) (xy 375.858275 -402.302482)
			(xy 375.848118 -402.30298) (xy 375.131838 -402.30298) (xy 375.121671 -402.302505) (xy 375.102881 -402.294736)
			(xy 375.088495 -402.280366) (xy 375.080706 -402.261584) (xy 375.080276 -402.251418) (xy 375.080276 -401.965414)
			(xy 375.080082 -401.958541) (xy 375.076475 -401.945278) (xy 375.073164 -401.939252) (xy 375.056822 -401.910901)
			(xy 375.031105 -401.850728) (xy 375.013698 -401.787647) (xy 375.004916 -401.7228) (xy 351.715918 -401.7228)
			(xy 351.697563 -401.755391) (xy 351.660303 -401.805315) (xy 351.616966 -401.850065) (xy 351.568261 -401.888905)
			(xy 351.51499 -401.921198) (xy 351.458027 -401.946415) (xy 351.398306 -401.964139) (xy 351.336809 -401.974082)
			(xy 351.274546 -401.976078) (xy 351.212539 -401.970096) (xy 351.151805 -401.956234) (xy 351.093343 -401.93472)
			(xy 351.038112 -401.905906) (xy 350.98702 -401.870266) (xy 350.940904 -401.828385) (xy 350.900522 -401.78095)
			(xy 350.866538 -401.728741) (xy 350.839509 -401.672615) (xy 350.81988 -401.613494) (xy 350.807971 -401.552347)
			(xy 350.80398 -401.49018) (xy 349.532451 -401.49018) (xy 349.551362 -401.536889) (xy 349.567163 -401.597147)
			(xy 349.575129 -401.65893) (xy 349.575628 -401.690078) (xy 349.575129 -401.721226) (xy 349.567163 -401.783009)
			(xy 349.551362 -401.843267) (xy 349.527984 -401.90101) (xy 349.497415 -401.955289) (xy 349.460155 -402.005213)
			(xy 349.416818 -402.049963) (xy 349.368113 -402.088803) (xy 349.314842 -402.121096) (xy 349.257879 -402.146313)
			(xy 349.198158 -402.164037) (xy 349.136661 -402.17398) (xy 349.074398 -402.175976) (xy 349.012391 -402.169994)
			(xy 348.951657 -402.156132) (xy 348.893195 -402.134618) (xy 348.837964 -402.105804) (xy 348.786872 -402.070164)
			(xy 348.740756 -402.028283) (xy 348.700374 -401.980848) (xy 348.66639 -401.928639) (xy 348.639361 -401.872513)
			(xy 348.619732 -401.813392) (xy 348.607823 -401.752245) (xy 348.603832 -401.690078) (xy 347.332157 -401.690078)
			(xy 347.32322 -401.710992) (xy 347.3069 -401.739354) (xy 347.303602 -401.745387) (xy 347.299986 -401.758644)
			(xy 347.299788 -401.765516) (xy 347.299788 -402.514816) (xy 347.299975 -402.52169) (xy 347.303587 -402.534952)
			(xy 347.3069 -402.540978) (xy 347.32318 -402.569362) (xy 347.3489 -402.629528) (xy 347.366311 -402.692602)
			(xy 347.375099 -402.757442) (xy 347.375101 -402.790152) (xy 350.80398 -402.790152) (xy 350.807971 -402.727985)
			(xy 350.81988 -402.666838) (xy 350.839509 -402.607717) (xy 350.866538 -402.551591) (xy 350.900522 -402.499382)
			(xy 350.940904 -402.451947) (xy 350.98702 -402.410066) (xy 351.038112 -402.374426) (xy 351.093343 -402.345612)
			(xy 351.151805 -402.324098) (xy 351.212539 -402.310236) (xy 351.274546 -402.304254) (xy 351.336809 -402.30625)
			(xy 351.398306 -402.316193) (xy 351.458027 -402.333917) (xy 351.51499 -402.359134) (xy 351.568261 -402.391427)
			(xy 351.616966 -402.430267) (xy 351.660303 -402.475017) (xy 351.697563 -402.524941) (xy 351.728132 -402.57922)
			(xy 351.75151 -402.636963) (xy 351.767311 -402.697221) (xy 351.775277 -402.759004) (xy 351.775776 -402.790152)
			(xy 377.204224 -402.790152) (xy 377.204787 -402.757422) (xy 377.213643 -402.692564) (xy 377.231134 -402.629484)
			(xy 377.256943 -402.569326) (xy 377.273312 -402.540978) (xy 377.276635 -402.534958) (xy 377.280235 -402.521691)
			(xy 377.280424 -402.514816) (xy 377.280424 -401.765516) (xy 377.280223 -401.758643) (xy 377.276621 -401.745381)
			(xy 377.273312 -401.739354) (xy 377.256929 -401.711014) (xy 377.231131 -401.650851) (xy 377.213646 -401.587769)
			(xy 377.204791 -401.52291) (xy 377.204224 -401.49018) (xy 377.2048 -401.457451) (xy 377.213652 -401.392593)
			(xy 377.231139 -401.329513) (xy 377.256945 -401.269354) (xy 377.273312 -401.241006) (xy 377.276625 -401.234981)
			(xy 377.280232 -401.221717) (xy 377.280424 -401.214844) (xy 377.280424 -400.92884) (xy 377.280849 -400.918717)
			(xy 377.288589 -400.90001) (xy 377.302903 -400.885693) (xy 377.321609 -400.877951) (xy 377.331732 -400.877532)
			(xy 378.048012 -400.877532) (xy 378.058139 -400.877907) (xy 378.076849 -400.885665) (xy 378.091164 -400.899994)
			(xy 378.098904 -400.918712) (xy 378.09932 -400.92884) (xy 378.09932 -401.214844) (xy 378.099531 -401.221716)
			(xy 378.103126 -401.234979) (xy 378.106432 -401.241006) (xy 378.122793 -401.269358) (xy 378.148598 -401.329516)
			(xy 378.166089 -401.392595) (xy 378.17495 -401.457451) (xy 378.17552 -401.49018) (xy 378.174965 -401.52291)
			(xy 378.166106 -401.587768) (xy 378.148612 -401.650849) (xy 378.131781 -401.690078) (xy 379.404372 -401.690078)
			(xy 379.404954 -401.657349) (xy 379.413806 -401.592492) (xy 379.431291 -401.529412) (xy 379.457094 -401.469253)
			(xy 379.47346 -401.440904) (xy 379.47677 -401.434877) (xy 379.480379 -401.421615) (xy 379.480572 -401.414742)
			(xy 379.480572 -400.665442) (xy 379.480367 -400.65857) (xy 379.476768 -400.645307) (xy 379.47346 -400.63928)
			(xy 379.457092 -400.610932) (xy 379.43129 -400.550772) (xy 379.4138 -400.487692) (xy 379.404941 -400.422835)
			(xy 379.404372 -400.390106) (xy 379.404922 -400.357376) (xy 379.413783 -400.292517) (xy 379.431278 -400.229437)
			(xy 379.457089 -400.16928) (xy 379.47346 -400.140932) (xy 379.47676 -400.1349) (xy 379.480375 -400.121642)
			(xy 379.480572 -400.11477) (xy 379.480572 -399.828766) (xy 379.481 -399.818633) (xy 379.488744 -399.799905)
			(xy 379.503049 -399.785549) (xy 379.521749 -399.777737) (xy 379.53188 -399.777204) (xy 380.24816 -399.777204)
			(xy 380.258312 -399.777655) (xy 380.277064 -399.785438) (xy 380.291389 -399.799826) (xy 380.29909 -399.818612)
			(xy 380.299468 -399.828766) (xy 380.299468 -400.11477) (xy 380.299675 -400.121642) (xy 380.303273 -400.134905)
			(xy 380.30658 -400.140932) (xy 380.322956 -400.169275) (xy 380.348756 -400.229437) (xy 380.366243 -400.292518)
			(xy 380.3751 -400.357376) (xy 380.375668 -400.390106) (xy 380.375073 -400.422834) (xy 380.366225 -400.487691)
			(xy 380.348743 -400.550771) (xy 380.322944 -400.610931) (xy 380.30658 -400.63928) (xy 380.303271 -400.645307)
			(xy 380.299662 -400.658569) (xy 380.299468 -400.665442) (xy 380.299468 -401.414742) (xy 380.299686 -401.421613)
			(xy 380.303277 -401.434876) (xy 380.30658 -401.440904) (xy 380.322945 -401.469253) (xy 380.348748 -401.529413)
			(xy 380.366237 -401.592492) (xy 380.375098 -401.657349) (xy 380.375668 -401.690078) (xy 380.375106 -401.722808)
			(xy 380.366247 -401.787666) (xy 380.348756 -401.850746) (xy 380.322948 -401.910904) (xy 380.30658 -401.939252)
			(xy 380.303245 -401.945267) (xy 380.299653 -401.958538) (xy 380.299468 -401.965414) (xy 380.299468 -402.251418)
			(xy 380.298989 -402.261545) (xy 380.291256 -402.280265) (xy 380.276968 -402.29462) (xy 380.258284 -402.30244)
			(xy 380.24816 -402.30298) (xy 379.53188 -402.30298) (xy 379.521722 -402.302595) (xy 379.502965 -402.294789)
			(xy 379.488642 -402.280381) (xy 379.480946 -402.261578) (xy 379.480572 -402.251418) (xy 379.480572 -401.965414)
			(xy 379.480378 -401.958541) (xy 379.476771 -401.945278) (xy 379.47346 -401.939252) (xy 379.457081 -401.91091)
			(xy 379.431281 -401.850748) (xy 379.413795 -401.787666) (xy 379.404939 -401.722808) (xy 379.404372 -401.690078)
			(xy 378.131781 -401.690078) (xy 378.122802 -401.711006) (xy 378.106432 -401.739354) (xy 378.103136 -401.745388)
			(xy 378.099518 -401.758644) (xy 378.09932 -401.765516) (xy 378.09932 -402.514816) (xy 378.099503 -402.52169)
			(xy 378.103117 -402.534953) (xy 378.106432 -402.540978) (xy 378.122782 -402.569336) (xy 378.148589 -402.629492)
			(xy 378.166084 -402.692569) (xy 378.174948 -402.757424) (xy 378.17552 -402.790152) (xy 378.174953 -402.822879)
			(xy 381.604847 -402.822879) (xy 381.604852 -402.757439) (xy 381.613641 -402.692592) (xy 381.631054 -402.629512)
			(xy 381.656776 -402.56934) (xy 381.6731 -402.540978) (xy 381.676423 -402.534957) (xy 381.680023 -402.52169)
			(xy 381.680212 -402.514816) (xy 381.680212 -401.765516) (xy 381.680013 -401.758643) (xy 381.676409 -401.745381)
			(xy 381.6731 -401.739354) (xy 381.656762 -401.711002) (xy 381.631048 -401.650828) (xy 381.613643 -401.587747)
			(xy 381.604863 -401.522902) (xy 381.604865 -401.457464) (xy 381.61365 -401.392619) (xy 381.631059 -401.32954)
			(xy 381.656778 -401.269368) (xy 381.6731 -401.241006) (xy 381.676413 -401.23498) (xy 381.68002 -401.221717)
			(xy 381.680212 -401.214844) (xy 381.680212 -400.92884) (xy 381.680655 -400.918687) (xy 381.688439 -400.899933)
			(xy 381.70283 -400.885608) (xy 381.721619 -400.877909) (xy 381.731774 -400.877532) (xy 382.448054 -400.877532)
			(xy 382.458177 -400.878064) (xy 382.476895 -400.885775) (xy 382.491253 -400.900048) (xy 382.499075 -400.91872)
			(xy 382.499616 -400.92884) (xy 382.499616 -401.214844) (xy 382.499827 -401.221716) (xy 382.503422 -401.234979)
			(xy 382.506728 -401.241006) (xy 382.523034 -401.269376) (xy 382.548755 -401.329545) (xy 382.566166 -401.392622)
			(xy 382.574953 -401.457465) (xy 382.574955 -401.522901) (xy 382.566173 -401.587745) (xy 382.548767 -401.650823)
			(xy 382.52305 -401.710993) (xy 382.516255 -401.7228) (xy 383.805003 -401.7228) (xy 383.805005 -401.657362)
			(xy 383.813792 -401.592516) (xy 383.831203 -401.529437) (xy 383.856924 -401.469265) (xy 383.873248 -401.440904)
			(xy 383.876557 -401.434877) (xy 383.880167 -401.421615) (xy 383.88036 -401.414742) (xy 383.88036 -400.665442)
			(xy 383.880157 -400.65857) (xy 383.876557 -400.645307) (xy 383.873248 -400.63928) (xy 383.856931 -400.610916)
			(xy 383.831212 -400.550746) (xy 383.813803 -400.487667) (xy 383.805019 -400.422823) (xy 383.805018 -400.357387)
			(xy 383.813801 -400.292543) (xy 383.831209 -400.229464) (xy 383.856926 -400.169293) (xy 383.873248 -400.140932)
			(xy 383.876547 -400.1349) (xy 383.880163 -400.121642) (xy 383.88036 -400.11477) (xy 383.88036 -399.828766)
			(xy 383.880806 -399.818603) (xy 383.888596 -399.799829) (xy 383.902976 -399.785464) (xy 383.921759 -399.777695)
			(xy 383.931922 -399.777204) (xy 384.648202 -399.777204) (xy 384.658356 -399.777731) (xy 384.677118 -399.7855)
			(xy 384.691482 -399.799855) (xy 384.699263 -399.818613) (xy 384.699764 -399.828766) (xy 384.699764 -400.11477)
			(xy 384.699972 -400.121642) (xy 384.70357 -400.134905) (xy 384.706876 -400.140932) (xy 384.723203 -400.169291)
			(xy 384.748919 -400.229463) (xy 384.766326 -400.292542) (xy 384.775109 -400.357387) (xy 384.775108 -400.422824)
			(xy 384.766324 -400.487668) (xy 384.748916 -400.550747) (xy 384.723198 -400.610919) (xy 384.706876 -400.63928)
			(xy 384.703567 -400.645307) (xy 384.699958 -400.658569) (xy 384.699764 -400.665442) (xy 384.699764 -401.414742)
			(xy 384.699982 -401.421613) (xy 384.703573 -401.434876) (xy 384.706876 -401.440904) (xy 384.723179 -401.469276)
			(xy 384.748898 -401.529445) (xy 384.766307 -401.592521) (xy 384.775093 -401.657364) (xy 384.775095 -401.722799)
			(xy 384.766315 -401.787642) (xy 384.74891 -401.85072) (xy 384.723196 -401.910891) (xy 384.706876 -401.939252)
			(xy 384.703541 -401.945267) (xy 384.699949 -401.958538) (xy 384.699764 -401.965414) (xy 384.699764 -402.251418)
			(xy 384.699282 -402.261577) (xy 384.691502 -402.280346) (xy 384.677133 -402.294711) (xy 384.658361 -402.302485)
			(xy 384.648202 -402.30298) (xy 383.931922 -402.30298) (xy 383.921754 -402.302518) (xy 383.902963 -402.294744)
			(xy 383.888578 -402.28037) (xy 383.88079 -402.261586) (xy 383.88036 -402.251418) (xy 383.88036 -401.965414)
			(xy 383.880168 -401.958541) (xy 383.87656 -401.945278) (xy 383.873248 -401.939252) (xy 383.856907 -401.910901)
			(xy 383.831191 -401.850728) (xy 383.813784 -401.787647) (xy 383.805003 -401.7228) (xy 382.516255 -401.7228)
			(xy 382.506728 -401.739354) (xy 382.503432 -401.745388) (xy 382.499814 -401.758644) (xy 382.499616 -401.765516)
			(xy 382.499616 -402.514816) (xy 382.4998 -402.52169) (xy 382.503413 -402.534953) (xy 382.506728 -402.540978)
			(xy 382.523011 -402.569361) (xy 382.548734 -402.629527) (xy 382.566148 -402.692601) (xy 382.574937 -402.757442)
			(xy 382.574939 -402.790152) (xy 386.004308 -402.790152) (xy 386.004874 -402.757422) (xy 386.013729 -402.692564)
			(xy 386.03122 -402.629484) (xy 386.057027 -402.569326) (xy 386.073396 -402.540978) (xy 386.076718 -402.534957)
			(xy 386.080319 -402.52169) (xy 386.080508 -402.514816) (xy 386.080508 -401.765516) (xy 386.080309 -401.758643)
			(xy 386.076706 -401.74538) (xy 386.073396 -401.739354) (xy 386.057012 -401.711015) (xy 386.031214 -401.650852)
			(xy 386.01373 -401.587769) (xy 386.004875 -401.52291) (xy 386.004308 -401.49018) (xy 386.004886 -401.457451)
			(xy 386.013738 -401.392593) (xy 386.031225 -401.329513) (xy 386.057029 -401.269354) (xy 386.073396 -401.241006)
			(xy 386.076708 -401.23498) (xy 386.080316 -401.221717) (xy 386.080508 -401.214844) (xy 386.080508 -400.92884)
			(xy 386.080949 -400.918719) (xy 386.088686 -400.900015) (xy 386.102995 -400.885699) (xy 386.121695 -400.877954)
			(xy 386.131816 -400.877532) (xy 386.848096 -400.877532) (xy 386.858222 -400.87792) (xy 386.876932 -400.885673)
			(xy 386.891247 -400.899998) (xy 386.898987 -400.918714) (xy 386.899404 -400.92884) (xy 386.899404 -401.214844)
			(xy 386.899617 -401.221716) (xy 386.903211 -401.234978) (xy 386.906516 -401.241006) (xy 386.922885 -401.269353)
			(xy 386.948686 -401.329513) (xy 386.966174 -401.392594) (xy 386.975034 -401.457451) (xy 386.975604 -401.49018)
			(xy 386.975051 -401.52291) (xy 386.966192 -401.587769) (xy 386.948698 -401.650849) (xy 386.922887 -401.711007)
			(xy 386.916076 -401.7228) (xy 388.204792 -401.7228) (xy 388.204795 -401.657362) (xy 388.213581 -401.592516)
			(xy 388.230992 -401.529437) (xy 388.256712 -401.469265) (xy 388.273036 -401.440904) (xy 388.276344 -401.434876)
			(xy 388.279955 -401.421615) (xy 388.280148 -401.414742) (xy 388.280148 -400.665442) (xy 388.279947 -400.658569)
			(xy 388.276346 -400.645306) (xy 388.273036 -400.63928) (xy 388.256719 -400.610916) (xy 388.231001 -400.550745)
			(xy 388.213592 -400.487667) (xy 388.204808 -400.422823) (xy 388.204808 -400.357387) (xy 388.21359 -400.292543)
			(xy 388.230998 -400.229464) (xy 388.256714 -400.169293) (xy 388.273036 -400.140932) (xy 388.276334 -400.134899)
			(xy 388.279951 -400.121642) (xy 388.280148 -400.11477) (xy 388.280148 -399.828766) (xy 388.280606 -399.818605)
			(xy 388.288393 -399.799833) (xy 388.30277 -399.785469) (xy 388.321548 -399.777697) (xy 388.33171 -399.777204)
			(xy 389.04799 -399.777204) (xy 389.058143 -399.777741) (xy 389.076905 -399.785506) (xy 389.09127 -399.799858)
			(xy 389.099051 -399.818613) (xy 389.099552 -399.828766) (xy 389.099552 -400.11477) (xy 389.099749 -400.121643)
			(xy 389.103353 -400.134906) (xy 389.106664 -400.140932) (xy 389.122991 -400.16929) (xy 389.148708 -400.229462)
			(xy 389.166116 -400.292542) (xy 389.174898 -400.357387) (xy 389.174898 -400.422824) (xy 389.166114 -400.487669)
			(xy 389.148705 -400.550747) (xy 389.122987 -400.610919) (xy 389.106664 -400.63928) (xy 389.103361 -400.645311)
			(xy 389.099747 -400.65857) (xy 389.099552 -400.665442) (xy 389.099552 -401.414742) (xy 389.099759 -401.421614)
			(xy 389.103356 -401.434877) (xy 389.106664 -401.440904) (xy 389.122968 -401.469276) (xy 389.148687 -401.529444)
			(xy 389.166097 -401.592521) (xy 389.174883 -401.657364) (xy 389.174885 -401.722799) (xy 389.166104 -401.787642)
			(xy 389.148699 -401.85072) (xy 389.122985 -401.910891) (xy 389.106664 -401.939252) (xy 389.103336 -401.94527)
			(xy 389.099738 -401.958539) (xy 389.099552 -401.965414) (xy 389.099552 -402.251418) (xy 389.099081 -402.261578)
			(xy 389.091299 -402.28035) (xy 389.076926 -402.294715) (xy 389.05815 -402.302487) (xy 389.04799 -402.30298)
			(xy 388.33171 -402.30298) (xy 388.321555 -402.302459) (xy 388.30279 -402.294691) (xy 388.288425 -402.280334)
			(xy 388.280647 -402.261573) (xy 388.280148 -402.251418) (xy 388.280148 -401.965414) (xy 388.279957 -401.958541)
			(xy 388.276349 -401.945278) (xy 388.273036 -401.939252) (xy 388.256695 -401.910901) (xy 388.23098 -401.850727)
			(xy 388.213574 -401.787647) (xy 388.204792 -401.7228) (xy 386.916076 -401.7228) (xy 386.906516 -401.739354)
			(xy 386.903219 -401.745387) (xy 386.899602 -401.758644) (xy 386.899404 -401.765516) (xy 386.899404 -402.514816)
			(xy 386.899589 -402.52169) (xy 386.903202 -402.534953) (xy 386.906516 -402.540978) (xy 386.922874 -402.569331)
			(xy 386.948678 -402.629489) (xy 386.966169 -402.692568) (xy 386.975032 -402.757423) (xy 386.975604 -402.790152)
			(xy 386.975038 -402.822879) (xy 390.404919 -402.822879) (xy 390.404924 -402.757439) (xy 390.413715 -402.692591)
			(xy 390.431131 -402.62951) (xy 390.456857 -402.569339) (xy 390.473184 -402.540978) (xy 390.476505 -402.534957)
			(xy 390.480107 -402.52169) (xy 390.480296 -402.514816) (xy 390.480296 -401.765516) (xy 390.480098 -401.758643)
			(xy 390.476494 -401.74538) (xy 390.473184 -401.739354) (xy 390.456843 -401.711003) (xy 390.431125 -401.65083)
			(xy 390.413717 -401.587749) (xy 390.404935 -401.522902) (xy 390.404937 -401.457464) (xy 390.413724 -401.392617)
			(xy 390.431136 -401.329538) (xy 390.456859 -401.269367) (xy 390.473184 -401.241006) (xy 390.476495 -401.23498)
			(xy 390.480103 -401.221717) (xy 390.480296 -401.214844) (xy 390.480296 -400.92884) (xy 390.480754 -400.918689)
			(xy 390.488536 -400.899938) (xy 390.502922 -400.885614) (xy 390.521705 -400.877912) (xy 390.531858 -400.877532)
			(xy 391.248138 -400.877532) (xy 391.258266 -400.877995) (xy 391.276987 -400.885734) (xy 391.291341 -400.900027)
			(xy 391.299161 -400.918714) (xy 391.2997 -400.92884) (xy 391.2997 -401.214844) (xy 391.299914 -401.221716)
			(xy 391.303507 -401.234978) (xy 391.306812 -401.241006) (xy 391.323116 -401.269377) (xy 391.348832 -401.329547)
			(xy 391.36624 -401.392623) (xy 391.375025 -401.457466) (xy 391.375027 -401.5229) (xy 391.366247 -401.587743)
			(xy 391.348844 -401.650821) (xy 391.323131 -401.710992) (xy 391.306812 -401.739354) (xy 391.303514 -401.745387)
			(xy 391.299898 -401.758644) (xy 391.2997 -401.765516) (xy 391.2997 -402.514816) (xy 391.299886 -402.52169)
			(xy 391.303498 -402.534953) (xy 391.306812 -402.540978) (xy 391.323092 -402.569362) (xy 391.348811 -402.629529)
			(xy 391.366221 -402.692602) (xy 391.375009 -402.757442) (xy 391.375015 -402.822875) (xy 391.366238 -402.887717)
			(xy 391.348838 -402.950794) (xy 391.323129 -403.010964) (xy 391.306812 -403.039326) (xy 391.303489 -403.045347)
			(xy 391.299888 -403.058613) (xy 391.2997 -403.065488) (xy 391.2997 -403.351492) (xy 391.299272 -403.361646)
			(xy 391.291479 -403.380398) (xy 391.277084 -403.394721) (xy 391.258294 -403.402421) (xy 391.248138 -403.4028)
			(xy 390.531858 -403.4028) (xy 390.521734 -403.402309) (xy 390.503019 -403.394575) (xy 390.488666 -403.380291)
			(xy 390.480841 -403.361614) (xy 390.480296 -403.351492) (xy 390.480296 -403.065488) (xy 390.480109 -403.058614)
			(xy 390.476498 -403.045352) (xy 390.473184 -403.039326) (xy 390.45682 -403.010988) (xy 390.431104 -402.950812)
			(xy 390.413698 -402.887728) (xy 390.404919 -402.822879) (xy 386.975038 -402.822879) (xy 386.975038 -402.822882)
			(xy 386.966182 -402.88774) (xy 386.948692 -402.95082) (xy 386.922884 -403.010978) (xy 386.906516 -403.039326)
			(xy 386.903193 -403.045347) (xy 386.899592 -403.058613) (xy 386.899404 -403.065488) (xy 386.899404 -403.351492)
			(xy 386.898978 -403.361613) (xy 386.891233 -403.380316) (xy 386.87692 -403.394631) (xy 386.858217 -403.402377)
			(xy 386.848096 -403.4028) (xy 386.131816 -403.4028) (xy 386.121695 -403.402371) (xy 386.102991 -403.394628)
			(xy 386.088676 -403.380315) (xy 386.080931 -403.361613) (xy 386.080508 -403.351492) (xy 386.080508 -403.065488)
			(xy 386.08032 -403.058615) (xy 386.076709 -403.045352) (xy 386.073396 -403.039326) (xy 386.05704 -403.010971)
			(xy 386.031236 -402.950814) (xy 386.013744 -402.887736) (xy 386.00488 -402.822881) (xy 386.004308 -402.790152)
			(xy 382.574939 -402.790152) (xy 382.574942 -402.822876) (xy 382.566164 -402.887718) (xy 382.548761 -402.950795)
			(xy 382.523048 -403.010965) (xy 382.506728 -403.039326) (xy 382.503406 -403.045347) (xy 382.499804 -403.058614)
			(xy 382.499616 -403.065488) (xy 382.499616 -403.351492) (xy 382.499172 -403.361644) (xy 382.491382 -403.380393)
			(xy 382.476993 -403.394716) (xy 382.458207 -403.402419) (xy 382.448054 -403.4028) (xy 381.731774 -403.4028)
			(xy 381.721651 -403.402296) (xy 381.702936 -403.394567) (xy 381.688582 -403.380287) (xy 381.680757 -403.361613)
			(xy 381.680212 -403.351492) (xy 381.680212 -403.065488) (xy 381.680023 -403.058615) (xy 381.676413 -403.045352)
			(xy 381.6731 -403.039326) (xy 381.656738 -403.010987) (xy 381.631027 -402.95081) (xy 381.613624 -402.887727)
			(xy 381.604847 -402.822879) (xy 378.174953 -402.822879) (xy 378.174953 -402.822881) (xy 378.166097 -402.88774)
			(xy 378.148607 -402.95082) (xy 378.1228 -403.010978) (xy 378.106432 -403.039326) (xy 378.103111 -403.045347)
			(xy 378.099509 -403.058614) (xy 378.09932 -403.065488) (xy 378.09932 -403.351492) (xy 378.098809 -403.361598)
			(xy 378.091078 -403.380272) (xy 378.076789 -403.394566) (xy 378.058118 -403.402305) (xy 378.048012 -403.4028)
			(xy 377.331732 -403.4028) (xy 377.321612 -403.402358) (xy 377.302909 -403.39462) (xy 377.288593 -403.380312)
			(xy 377.280847 -403.361612) (xy 377.280424 -403.351492) (xy 377.280424 -403.065488) (xy 377.280234 -403.058615)
			(xy 377.276624 -403.045352) (xy 377.273312 -403.039326) (xy 377.256958 -403.01097) (xy 377.231153 -402.950813)
			(xy 377.21366 -402.887736) (xy 377.204796 -402.82288) (xy 377.204224 -402.790152) (xy 351.775776 -402.790152)
			(xy 351.775277 -402.8213) (xy 351.767311 -402.883083) (xy 351.75151 -402.943341) (xy 351.728132 -403.001084)
			(xy 351.697563 -403.055363) (xy 351.660303 -403.105287) (xy 351.616966 -403.150037) (xy 351.568261 -403.188877)
			(xy 351.51499 -403.22117) (xy 351.458027 -403.246387) (xy 351.398306 -403.264111) (xy 351.336809 -403.274054)
			(xy 351.274546 -403.27605) (xy 351.212539 -403.270068) (xy 351.151805 -403.256206) (xy 351.093343 -403.234692)
			(xy 351.038112 -403.205878) (xy 350.98702 -403.170238) (xy 350.940904 -403.128357) (xy 350.900522 -403.080922)
			(xy 350.866538 -403.028713) (xy 350.839509 -402.972587) (xy 350.81988 -402.913466) (xy 350.807971 -402.852319)
			(xy 350.80398 -402.790152) (xy 347.375101 -402.790152) (xy 347.375104 -402.822875) (xy 347.366327 -402.887717)
			(xy 347.348927 -402.950794) (xy 347.323218 -403.010964) (xy 347.3069 -403.039326) (xy 347.303576 -403.045346)
			(xy 347.299976 -403.058613) (xy 347.299788 -403.065488) (xy 347.299788 -403.351492) (xy 347.299372 -403.361647)
			(xy 347.291576 -403.380402) (xy 347.277178 -403.394726) (xy 347.258383 -403.402424) (xy 347.248226 -403.4028)
			(xy 346.531946 -403.4028) (xy 346.521827 -403.402237) (xy 346.503115 -403.394532) (xy 346.488758 -403.380269)
			(xy 346.48093 -403.361607) (xy 346.480384 -403.351492) (xy 346.480384 -403.065488) (xy 346.480199 -403.058614)
			(xy 346.476586 -403.045351) (xy 346.473272 -403.039326) (xy 346.456908 -403.010988) (xy 346.431193 -402.950811)
			(xy 346.413788 -402.887728) (xy 346.405009 -402.822879) (xy 342.975128 -402.822879) (xy 342.975128 -402.822882)
			(xy 342.966272 -402.88774) (xy 342.948781 -402.95082) (xy 342.922973 -403.010978) (xy 342.906604 -403.039326)
			(xy 342.90328 -403.045346) (xy 342.89968 -403.058613) (xy 342.899492 -403.065488) (xy 342.899492 -403.351492)
			(xy 342.899077 -403.361615) (xy 342.89133 -403.38032) (xy 342.877013 -403.394635) (xy 342.858307 -403.402379)
			(xy 342.848184 -403.4028) (xy 342.131904 -403.4028) (xy 342.121782 -403.402381) (xy 342.103078 -403.394634)
			(xy 342.088764 -403.380318) (xy 342.081019 -403.361614) (xy 342.080596 -403.351492) (xy 342.080596 -403.065488)
			(xy 342.080409 -403.058614) (xy 342.076798 -403.045352) (xy 342.073484 -403.039326) (xy 342.057127 -403.010972)
			(xy 342.031324 -402.950814) (xy 342.013832 -402.887736) (xy 342.004968 -402.822881) (xy 342.004396 -402.790152)
			(xy 338.575029 -402.790152) (xy 338.575032 -402.822876) (xy 338.566254 -402.887718) (xy 338.54885 -402.950795)
			(xy 338.523136 -403.010965) (xy 338.506816 -403.039326) (xy 338.503493 -403.045347) (xy 338.499892 -403.058613)
			(xy 338.499704 -403.065488) (xy 338.499704 -403.351492) (xy 338.499272 -403.361645) (xy 338.49148 -403.380397)
			(xy 338.477086 -403.39472) (xy 338.458297 -403.402421) (xy 338.448142 -403.4028) (xy 337.731862 -403.4028)
			(xy 337.721738 -403.402306) (xy 337.703023 -403.394573) (xy 337.68867 -403.38029) (xy 337.680845 -403.361614)
			(xy 337.6803 -403.351492) (xy 337.6803 -403.065488) (xy 337.680113 -403.058614) (xy 337.676501 -403.045352)
			(xy 337.673188 -403.039326) (xy 337.656827 -403.010987) (xy 337.631116 -402.95081) (xy 337.613714 -402.887727)
			(xy 337.604936 -402.822879) (xy 334.175042 -402.822879) (xy 334.175042 -402.822881) (xy 334.166186 -402.88774)
			(xy 334.148696 -402.95082) (xy 334.122888 -403.010978) (xy 334.10652 -403.039326) (xy 334.103197 -403.045347)
			(xy 334.099596 -403.058613) (xy 334.099408 -403.065488) (xy 334.099408 -403.351492) (xy 334.098978 -403.361613)
			(xy 334.091234 -403.380315) (xy 334.076922 -403.394629) (xy 334.058221 -403.402376) (xy 334.0481 -403.4028)
			(xy 333.33182 -403.4028) (xy 333.321699 -403.402368) (xy 333.302996 -403.394626) (xy 333.288681 -403.380315)
			(xy 333.280935 -403.361613) (xy 333.280512 -403.351492) (xy 333.280512 -403.065488) (xy 333.280323 -403.058615)
			(xy 333.276713 -403.045352) (xy 333.2734 -403.039326) (xy 333.257045 -403.010971) (xy 333.23124 -402.950814)
			(xy 333.213748 -402.887736) (xy 333.204884 -402.822881) (xy 333.204312 -402.790152) (xy 329.948032 -402.790152)
			(xy 329.948032 -405.622714) (xy 331.005015 -405.622714) (xy 331.005016 -405.557276) (xy 331.013801 -405.492431)
			(xy 331.03121 -405.429352) (xy 331.056929 -405.369181) (xy 331.073252 -405.34082) (xy 331.076556 -405.33479)
			(xy 331.080169 -405.32153) (xy 331.080364 -405.314658) (xy 331.080364 -404.565358) (xy 331.080154 -404.558486)
			(xy 331.076559 -404.545223) (xy 331.073252 -404.539196) (xy 331.056948 -404.510825) (xy 331.031228 -404.450656)
			(xy 331.013817 -404.387579) (xy 331.005031 -404.322737) (xy 331.005029 -404.257301) (xy 331.01381 -404.192458)
			(xy 331.031215 -404.12938) (xy 331.056931 -404.069209) (xy 331.073252 -404.040848) (xy 331.076581 -404.03483)
			(xy 331.080178 -404.021561) (xy 331.080364 -404.014686) (xy 331.080364 -403.728682) (xy 331.08075 -403.718506)
			(xy 331.088546 -403.699706) (xy 331.102943 -403.685321) (xy 331.12175 -403.677541) (xy 331.131926 -403.67712)
			(xy 331.848206 -403.67712) (xy 331.858362 -403.677628) (xy 331.877128 -403.685401) (xy 331.891492 -403.699762)
			(xy 331.899269 -403.718526) (xy 331.899768 -403.728682) (xy 331.899768 -404.014686) (xy 331.899969 -404.021558)
			(xy 331.903572 -404.034821) (xy 331.90688 -404.040848) (xy 331.92322 -404.069199) (xy 331.948935 -404.129373)
			(xy 331.966341 -404.192454) (xy 331.975121 -404.2573) (xy 331.975119 -404.322738) (xy 331.966333 -404.387583)
			(xy 331.948923 -404.450663) (xy 331.923203 -404.510835) (xy 331.90688 -404.539196) (xy 331.903565 -404.545221)
			(xy 331.89996 -404.558484) (xy 331.899768 -404.565358) (xy 331.899768 -405.314658) (xy 331.89998 -405.32153)
			(xy 331.903575 -405.334792) (xy 331.90688 -405.34082) (xy 331.923197 -405.369184) (xy 331.948914 -405.429355)
			(xy 331.966322 -405.492433) (xy 331.975105 -405.557277) (xy 331.975106 -405.622713) (xy 331.966324 -405.687557)
			(xy 331.948917 -405.750635) (xy 331.923201 -405.810807) (xy 331.90688 -405.839168) (xy 331.903575 -405.845197)
			(xy 331.899964 -405.858458) (xy 331.899768 -405.86533) (xy 331.899768 -406.151334) (xy 331.899295 -406.161493)
			(xy 331.89151 -406.180262) (xy 331.877138 -406.194626) (xy 331.858365 -406.2024) (xy 331.848206 -406.202896)
			(xy 331.131926 -406.202896) (xy 331.121774 -406.202346) (xy 331.103012 -406.194587) (xy 331.088647 -406.180238)
			(xy 331.080865 -406.161485) (xy 331.080364 -406.151334) (xy 331.080364 -405.86533) (xy 331.080165 -405.858457)
			(xy 331.076562 -405.845194) (xy 331.073252 -405.839168) (xy 331.056924 -405.81081) (xy 331.031206 -405.750638)
			(xy 331.013798 -405.687559) (xy 331.005015 -405.622714) (xy 329.948032 -405.622714) (xy 329.948032 -406.690068)
			(xy 333.204312 -406.690068) (xy 333.204884 -406.657339) (xy 333.213738 -406.592481) (xy 333.231226 -406.5294)
			(xy 333.257032 -406.469242) (xy 333.2734 -406.440894) (xy 333.276717 -406.43487) (xy 333.280321 -406.421606)
			(xy 333.280512 -406.414732) (xy 333.280512 -405.665432) (xy 333.280307 -405.65856) (xy 333.276707 -405.645297)
			(xy 333.2734 -405.63927) (xy 333.257022 -405.610927) (xy 333.231224 -405.550765) (xy 333.213737 -405.487684)
			(xy 333.20488 -405.422826) (xy 333.204312 -405.390096) (xy 333.204852 -405.357366) (xy 333.213715 -405.292506)
			(xy 333.231213 -405.229426) (xy 333.257028 -405.169269) (xy 333.2734 -405.140922) (xy 333.276707 -405.134894)
			(xy 333.280317 -405.121633) (xy 333.280512 -405.11476) (xy 333.280512 -404.828756) (xy 333.280949 -404.818643)
			(xy 333.288704 -404.799961) (xy 333.303015 -404.785668) (xy 333.321706 -404.777937) (xy 333.33182 -404.777448)
			(xy 334.0481 -404.777448) (xy 334.058202 -404.777984) (xy 334.076871 -404.785712) (xy 334.091163 -404.799993)
			(xy 334.098907 -404.818654) (xy 334.099408 -404.828756) (xy 334.099408 -405.11476) (xy 334.099614 -405.121632)
			(xy 334.103213 -405.134895) (xy 334.10652 -405.140922) (xy 334.122896 -405.169265) (xy 334.148695 -405.229427)
			(xy 334.166182 -405.292508) (xy 334.175039 -405.357367) (xy 334.175608 -405.390096) (xy 334.175062 -405.422826)
			(xy 334.1662 -405.487685) (xy 334.148704 -405.550765) (xy 334.131871 -405.589994) (xy 335.40446 -405.589994)
			(xy 335.405051 -405.557265) (xy 335.4139 -405.492408) (xy 335.431383 -405.429328) (xy 335.457183 -405.369169)
			(xy 335.473548 -405.34082) (xy 335.476851 -405.33479) (xy 335.480465 -405.32153) (xy 335.48066 -405.314658)
			(xy 335.48066 -404.565358) (xy 335.480451 -404.558486) (xy 335.476855 -404.545223) (xy 335.473548 -404.539196)
			(xy 335.457185 -404.510845) (xy 335.431382 -404.450686) (xy 335.413891 -404.387607) (xy 335.40503 -404.322751)
			(xy 335.40446 -404.290022) (xy 335.405018 -404.257292) (xy 335.413877 -404.192434) (xy 335.43137 -404.129354)
			(xy 335.457179 -404.069196) (xy 335.473548 -404.040848) (xy 335.476877 -404.03483) (xy 335.480474 -404.021561)
			(xy 335.48066 -404.014686) (xy 335.48066 -403.728682) (xy 335.481112 -403.718552) (xy 335.48885 -403.699826)
			(xy 335.503147 -403.68547) (xy 335.52184 -403.677655) (xy 335.531968 -403.67712) (xy 336.248248 -403.67712)
			(xy 336.258408 -403.677483) (xy 336.277165 -403.685298) (xy 336.291487 -403.699713) (xy 336.299182 -403.71852)
			(xy 336.299556 -403.728682) (xy 336.299556 -404.014686) (xy 336.299746 -404.021559) (xy 336.303355 -404.034823)
			(xy 336.306668 -404.040848) (xy 336.32305 -404.069188) (xy 336.348848 -404.129351) (xy 336.366334 -404.192433)
			(xy 336.375189 -404.257292) (xy 336.375756 -404.290022) (xy 336.37517 -404.322751) (xy 336.366319 -404.387608)
			(xy 336.348835 -404.450688) (xy 336.323034 -404.510847) (xy 336.306668 -404.539196) (xy 336.303352 -404.54522)
			(xy 336.299748 -404.558484) (xy 336.299556 -404.565358) (xy 336.299556 -405.314658) (xy 336.299757 -405.321531)
			(xy 336.303358 -405.334794) (xy 336.306668 -405.34082) (xy 336.323038 -405.369167) (xy 336.34884 -405.429327)
			(xy 336.366328 -405.492407) (xy 336.375187 -405.557265) (xy 336.375756 -405.589994) (xy 336.375202 -405.622724)
			(xy 336.366342 -405.687582) (xy 336.348848 -405.750662) (xy 336.323038 -405.81082) (xy 336.306668 -405.839168)
			(xy 336.303362 -405.845197) (xy 336.299752 -405.858457) (xy 336.299556 -405.86533) (xy 336.299556 -406.151334)
			(xy 336.299101 -406.161463) (xy 336.291362 -406.180186) (xy 336.277066 -406.194541) (xy 336.258375 -406.202359)
			(xy 336.248248 -406.202896) (xy 335.531968 -406.202896) (xy 335.521811 -406.202505) (xy 335.503057 -406.194698)
			(xy 335.488735 -406.180292) (xy 335.481037 -406.161493) (xy 335.48066 -406.151334) (xy 335.48066 -405.86533)
			(xy 335.480462 -405.858457) (xy 335.476858 -405.845194) (xy 335.473548 -405.839168) (xy 335.457174 -405.810823)
			(xy 335.431373 -405.750662) (xy 335.413886 -405.687581) (xy 335.405028 -405.622723) (xy 335.40446 -405.589994)
			(xy 334.131871 -405.589994) (xy 334.122891 -405.610923) (xy 334.10652 -405.63927) (xy 334.103217 -405.645301)
			(xy 334.099604 -405.65856) (xy 334.099408 -405.665432) (xy 334.099408 -406.414732) (xy 334.099587 -406.421606)
			(xy 334.103204 -406.434869) (xy 334.10652 -406.440894) (xy 334.122885 -406.469243) (xy 334.148687 -406.529403)
			(xy 334.166176 -406.592482) (xy 334.175037 -406.657339) (xy 334.175608 -406.690068) (xy 334.175049 -406.722792)
			(xy 337.604945 -406.722792) (xy 337.604949 -406.657353) (xy 337.613736 -406.592508) (xy 337.631146 -406.529428)
			(xy 337.656865 -406.469256) (xy 337.673188 -406.440894) (xy 337.676504 -406.43487) (xy 337.680109 -406.421606)
			(xy 337.6803 -406.414732) (xy 337.6803 -405.665432) (xy 337.680096 -405.65856) (xy 337.676496 -405.645297)
			(xy 337.673188 -405.63927) (xy 337.656864 -405.61091) (xy 337.631149 -405.550738) (xy 337.613743 -405.487659)
			(xy 337.604961 -405.422815) (xy 337.604962 -405.357378) (xy 337.613745 -405.292534) (xy 337.631152 -405.229455)
			(xy 337.656867 -405.169284) (xy 337.673188 -405.140922) (xy 337.676494 -405.134893) (xy 337.680105 -405.121633)
			(xy 337.6803 -405.11476) (xy 337.6803 -404.828756) (xy 337.680686 -404.818599) (xy 337.688496 -404.799846)
			(xy 337.702903 -404.785524) (xy 337.721703 -404.777826) (xy 337.731862 -404.777448) (xy 338.448142 -404.777448)
			(xy 338.458272 -404.777892) (xy 338.476996 -404.785635) (xy 338.491351 -404.799934) (xy 338.499167 -404.818628)
			(xy 338.499704 -404.828756) (xy 338.499704 -405.11476) (xy 338.499911 -405.121632) (xy 338.503509 -405.134895)
			(xy 338.506816 -405.140922) (xy 338.523136 -405.169285) (xy 338.548857 -405.229455) (xy 338.566267 -405.292533)
			(xy 338.575051 -405.357378) (xy 338.575052 -405.422815) (xy 338.566268 -405.48766) (xy 338.548859 -405.550739)
			(xy 338.523139 -405.610909) (xy 338.516345 -405.622713) (xy 339.805102 -405.622713) (xy 339.805102 -405.557276)
			(xy 339.813886 -405.492431) (xy 339.831295 -405.429353) (xy 339.857013 -405.369181) (xy 339.873336 -405.34082)
			(xy 339.876639 -405.334789) (xy 339.880253 -405.32153) (xy 339.880448 -405.314658) (xy 339.880448 -404.565358)
			(xy 339.880241 -404.558486) (xy 339.876644 -404.545223) (xy 339.873336 -404.539196) (xy 339.857032 -404.510824)
			(xy 339.831313 -404.450656) (xy 339.813903 -404.387579) (xy 339.805117 -404.322736) (xy 339.805115 -404.257301)
			(xy 339.813896 -404.192458) (xy 339.831301 -404.12938) (xy 339.857015 -404.069209) (xy 339.873336 -404.040848)
			(xy 339.876664 -404.03483) (xy 339.880262 -404.021561) (xy 339.880448 -404.014686) (xy 339.880448 -403.728682)
			(xy 339.880919 -403.718522) (xy 339.888701 -403.69975) (xy 339.903074 -403.685385) (xy 339.92185 -403.677613)
			(xy 339.93201 -403.67712) (xy 340.64829 -403.67712) (xy 340.658445 -403.677641) (xy 340.67721 -403.685409)
			(xy 340.691575 -403.699766) (xy 340.699353 -403.718527) (xy 340.699852 -403.728682) (xy 340.699852 -404.014686)
			(xy 340.700043 -404.021559) (xy 340.703651 -404.034822) (xy 340.706964 -404.040848) (xy 340.723305 -404.069199)
			(xy 340.74902 -404.129373) (xy 340.766426 -404.192453) (xy 340.775208 -404.2573) (xy 340.775205 -404.322738)
			(xy 340.766419 -404.387584) (xy 340.749008 -404.450663) (xy 340.723288 -404.510835) (xy 340.706964 -404.539196)
			(xy 340.703656 -404.545224) (xy 340.700045 -404.558485) (xy 340.699852 -404.565358) (xy 340.699852 -405.314658)
			(xy 340.700053 -405.321531) (xy 340.703654 -405.334794) (xy 340.706964 -405.34082) (xy 340.723281 -405.369184)
			(xy 340.748999 -405.429355) (xy 340.766408 -405.492433) (xy 340.775192 -405.557277) (xy 340.775192 -405.622713)
			(xy 340.76641 -405.687557) (xy 340.749002 -405.750636) (xy 340.723286 -405.810807) (xy 340.706964 -405.839168)
			(xy 340.703666 -405.845201) (xy 340.700049 -405.858458) (xy 340.699852 -405.86533) (xy 340.699852 -406.151334)
			(xy 340.699394 -406.161495) (xy 340.691607 -406.180267) (xy 340.67723 -406.194631) (xy 340.658452 -406.202403)
			(xy 340.64829 -406.202896) (xy 339.93201 -406.202896) (xy 339.921857 -406.202359) (xy 339.903095 -406.194594)
			(xy 339.88873 -406.180242) (xy 339.880949 -406.161487) (xy 339.880448 -406.151334) (xy 339.880448 -405.86533)
			(xy 339.880251 -405.858457) (xy 339.876647 -405.845194) (xy 339.873336 -405.839168) (xy 339.857009 -405.81081)
			(xy 339.831292 -405.750638) (xy 339.813884 -405.687558) (xy 339.805102 -405.622713) (xy 338.516345 -405.622713)
			(xy 338.506816 -405.63927) (xy 338.503513 -405.6453) (xy 338.4999 -405.65856) (xy 338.499704 -405.665432)
			(xy 338.499704 -406.414732) (xy 338.499883 -406.421606) (xy 338.5035 -406.434869) (xy 338.506816 -406.440894)
			(xy 338.523113 -406.46927) (xy 338.548835 -406.529437) (xy 338.566248 -406.592513) (xy 338.575036 -406.657355)
			(xy 338.575037 -406.690068) (xy 342.004396 -406.690068) (xy 342.00497 -406.657339) (xy 342.013824 -406.592481)
			(xy 342.031312 -406.529401) (xy 342.057117 -406.469242) (xy 342.073484 -406.440894) (xy 342.0768 -406.43487)
			(xy 342.080405 -406.421606) (xy 342.080596 -406.414732) (xy 342.080596 -405.665432) (xy 342.080392 -405.65856)
			(xy 342.076792 -405.645297) (xy 342.073484 -405.63927) (xy 342.057105 -405.610928) (xy 342.031307 -405.550766)
			(xy 342.013821 -405.487684) (xy 342.004964 -405.422826) (xy 342.004396 -405.390096) (xy 342.004938 -405.357366)
			(xy 342.013801 -405.292506) (xy 342.031298 -405.229426) (xy 342.057112 -405.169269) (xy 342.073484 -405.140922)
			(xy 342.07679 -405.134893) (xy 342.080401 -405.121633) (xy 342.080596 -405.11476) (xy 342.080596 -404.828756)
			(xy 342.081049 -404.818645) (xy 342.0888 -404.799967) (xy 342.103107 -404.785673) (xy 342.121793 -404.77794)
			(xy 342.131904 -404.777448) (xy 342.848184 -404.777448) (xy 342.858285 -404.777997) (xy 342.876953 -404.78572)
			(xy 342.891247 -404.799996) (xy 342.898991 -404.818655) (xy 342.899492 -404.828756) (xy 342.899492 -405.11476)
			(xy 342.8997 -405.121632) (xy 342.903298 -405.134895) (xy 342.906604 -405.140922) (xy 342.922979 -405.169266)
			(xy 342.948778 -405.229428) (xy 342.966265 -405.292509) (xy 342.975123 -405.357367) (xy 342.975692 -405.390096)
			(xy 342.975148 -405.422826) (xy 342.966286 -405.487685) (xy 342.948789 -405.550765) (xy 342.922975 -405.610923)
			(xy 342.916166 -405.622713) (xy 344.204891 -405.622713) (xy 344.204892 -405.557276) (xy 344.213676 -405.492432)
			(xy 344.231084 -405.429353) (xy 344.256802 -405.369181) (xy 344.273124 -405.34082) (xy 344.276433 -405.334793)
			(xy 344.280042 -405.321531) (xy 344.280236 -405.314658) (xy 344.280236 -404.565358) (xy 344.280018 -404.558487)
			(xy 344.276427 -404.545224) (xy 344.273124 -404.539196) (xy 344.256821 -404.510824) (xy 344.231102 -404.450655)
			(xy 344.213693 -404.387579) (xy 344.204907 -404.322736) (xy 344.204905 -404.257301) (xy 344.213685 -404.192458)
			(xy 344.23109 -404.12938) (xy 344.256804 -404.069209) (xy 344.273124 -404.040848) (xy 344.276459 -404.034833)
			(xy 344.280051 -404.021562) (xy 344.280236 -404.014686) (xy 344.280236 -403.728682) (xy 344.280718 -403.718523)
			(xy 344.288498 -403.699754) (xy 344.302867 -403.685389) (xy 344.321639 -403.677615) (xy 344.331798 -403.67712)
			(xy 345.048078 -403.67712) (xy 345.058246 -403.677582) (xy 345.077037 -403.685356) (xy 345.091422 -403.69973)
			(xy 345.09921 -403.718514) (xy 345.09964 -403.728682) (xy 345.09964 -404.014686) (xy 345.099832 -404.021559)
			(xy 345.10344 -404.034822) (xy 345.106752 -404.040848) (xy 345.123093 -404.069199) (xy 345.148809 -404.129372)
			(xy 345.166216 -404.192453) (xy 345.174997 -404.2573) (xy 345.174996 -404.290022) (xy 348.603832 -404.290022)
			(xy 348.607823 -404.227855) (xy 348.619732 -404.166708) (xy 348.639361 -404.107587) (xy 348.66639 -404.051461)
			(xy 348.700374 -403.999252) (xy 348.740756 -403.951817) (xy 348.786872 -403.909936) (xy 348.837964 -403.874296)
			(xy 348.893195 -403.845482) (xy 348.951657 -403.823968) (xy 349.012391 -403.810106) (xy 349.074398 -403.804124)
			(xy 349.136661 -403.80612) (xy 349.198158 -403.816063) (xy 349.257879 -403.833787) (xy 349.314842 -403.859004)
			(xy 349.368113 -403.891297) (xy 349.416818 -403.930137) (xy 349.460155 -403.974887) (xy 349.497415 -404.024811)
			(xy 349.527984 -404.07909) (xy 349.551362 -404.136833) (xy 349.567163 -404.197091) (xy 349.575129 -404.258874)
			(xy 349.575628 -404.290022) (xy 349.575129 -404.32117) (xy 349.567163 -404.382953) (xy 349.551362 -404.443211)
			(xy 349.527984 -404.500954) (xy 349.497415 -404.555233) (xy 349.460155 -404.605157) (xy 349.416818 -404.649907)
			(xy 349.368113 -404.688747) (xy 349.314842 -404.72104) (xy 349.257879 -404.746257) (xy 349.198158 -404.763981)
			(xy 349.136661 -404.773924) (xy 349.074398 -404.77592) (xy 349.012391 -404.769938) (xy 348.951657 -404.756076)
			(xy 348.893195 -404.734562) (xy 348.837964 -404.705748) (xy 348.786872 -404.670108) (xy 348.740756 -404.628227)
			(xy 348.700374 -404.580792) (xy 348.66639 -404.528583) (xy 348.639361 -404.472457) (xy 348.619732 -404.413336)
			(xy 348.607823 -404.352189) (xy 348.603832 -404.290022) (xy 345.174996 -404.290022) (xy 345.174995 -404.322738)
			(xy 345.166208 -404.387584) (xy 345.148797 -404.450663) (xy 345.123076 -404.510835) (xy 345.106752 -404.539196)
			(xy 345.103443 -404.545223) (xy 345.099833 -404.558485) (xy 345.09964 -404.565358) (xy 345.09964 -405.314658)
			(xy 345.099843 -405.32153) (xy 345.103443 -405.334793) (xy 345.106752 -405.34082) (xy 345.123069 -405.369184)
			(xy 345.148788 -405.429354) (xy 345.166197 -405.492433) (xy 345.174981 -405.557277) (xy 345.174982 -405.622713)
			(xy 345.166199 -405.687557) (xy 345.148791 -405.750636) (xy 345.123074 -405.810807) (xy 345.106752 -405.839168)
			(xy 345.103453 -405.8452) (xy 345.099837 -405.858458) (xy 345.09964 -405.86533) (xy 345.09964 -406.151334)
			(xy 345.099194 -406.161497) (xy 345.091404 -406.180271) (xy 345.077024 -406.194636) (xy 345.058241 -406.202405)
			(xy 345.048078 -406.202896) (xy 344.331798 -406.202896) (xy 344.321644 -406.202369) (xy 344.302882 -406.1946)
			(xy 344.288518 -406.180245) (xy 344.280737 -406.161487) (xy 344.280236 -406.151334) (xy 344.280236 -405.86533)
			(xy 344.280028 -405.858458) (xy 344.27643 -405.845195) (xy 344.273124 -405.839168) (xy 344.256797 -405.810809)
			(xy 344.231081 -405.750637) (xy 344.213674 -405.687558) (xy 344.204891 -405.622713) (xy 342.916166 -405.622713)
			(xy 342.906604 -405.63927) (xy 342.9033 -405.6453) (xy 342.899688 -405.65856) (xy 342.899492 -405.665432)
			(xy 342.899492 -406.414732) (xy 342.899673 -406.421606) (xy 342.903289 -406.434869) (xy 342.906604 -406.440894)
			(xy 342.922968 -406.469244) (xy 342.94877 -406.529403) (xy 342.96626 -406.592483) (xy 342.975121 -406.657339)
			(xy 342.975692 -406.690068) (xy 342.975135 -406.722792) (xy 346.405018 -406.722792) (xy 346.405021 -406.657353)
			(xy 346.41381 -406.592506) (xy 346.431223 -406.529426) (xy 346.456947 -406.469255) (xy 346.473272 -406.440894)
			(xy 346.476587 -406.434869) (xy 346.480193 -406.421606) (xy 346.480384 -406.414732) (xy 346.480384 -405.665432)
			(xy 346.480182 -405.65856) (xy 346.476581 -405.645297) (xy 346.473272 -405.63927) (xy 346.456945 -405.610911)
			(xy 346.431226 -405.55074) (xy 346.413817 -405.48766) (xy 346.405034 -405.422815) (xy 346.405034 -405.357378)
			(xy 346.413819 -405.292533) (xy 346.431229 -405.229454) (xy 346.456948 -405.169283) (xy 346.473272 -405.140922)
			(xy 346.476577 -405.134893) (xy 346.480189 -405.121633) (xy 346.480384 -405.11476) (xy 346.480384 -404.828756)
			(xy 346.480785 -404.818601) (xy 346.488592 -404.799851) (xy 346.502995 -404.78553) (xy 346.521789 -404.777829)
			(xy 346.531946 -404.777448) (xy 347.248226 -404.777448) (xy 347.258355 -404.777905) (xy 347.277079 -404.785643)
			(xy 347.291434 -404.799938) (xy 347.299251 -404.818629) (xy 347.299788 -404.828756) (xy 347.299788 -405.11476)
			(xy 347.299997 -405.121632) (xy 347.303594 -405.134895) (xy 347.3069 -405.140922) (xy 347.323218 -405.169286)
			(xy 347.348933 -405.229457) (xy 347.366341 -405.292535) (xy 347.375124 -405.357379) (xy 347.375124 -405.422815)
			(xy 347.366342 -405.487658) (xy 347.348936 -405.550737) (xy 347.332159 -405.589994) (xy 348.603832 -405.589994)
			(xy 348.607823 -405.527827) (xy 348.619732 -405.46668) (xy 348.639361 -405.407559) (xy 348.66639 -405.351433)
			(xy 348.700374 -405.299224) (xy 348.740756 -405.251789) (xy 348.786872 -405.209908) (xy 348.837964 -405.174268)
			(xy 348.893195 -405.145454) (xy 348.951657 -405.12394) (xy 349.012391 -405.110078) (xy 349.074398 -405.104096)
			(xy 349.136661 -405.106092) (xy 349.198158 -405.116035) (xy 349.257879 -405.133759) (xy 349.314842 -405.158976)
			(xy 349.368113 -405.191269) (xy 349.416818 -405.230109) (xy 349.460155 -405.274859) (xy 349.497415 -405.324783)
			(xy 349.527984 -405.379062) (xy 349.532451 -405.390096) (xy 350.80398 -405.390096) (xy 350.807971 -405.327929)
			(xy 350.81988 -405.266782) (xy 350.839509 -405.207661) (xy 350.866538 -405.151535) (xy 350.900522 -405.099326)
			(xy 350.940904 -405.051891) (xy 350.98702 -405.01001) (xy 351.038112 -404.97437) (xy 351.093343 -404.945556)
			(xy 351.151805 -404.924042) (xy 351.212539 -404.91018) (xy 351.274546 -404.904198) (xy 351.336809 -404.906194)
			(xy 351.398306 -404.916137) (xy 351.458027 -404.933861) (xy 351.51499 -404.959078) (xy 351.568261 -404.991371)
			(xy 351.616966 -405.030211) (xy 351.660303 -405.074961) (xy 351.697563 -405.124885) (xy 351.728132 -405.179164)
			(xy 351.75151 -405.236907) (xy 351.767311 -405.297165) (xy 351.775277 -405.358948) (xy 351.775776 -405.390096)
			(xy 351.775277 -405.421244) (xy 351.767311 -405.483027) (xy 351.75151 -405.543285) (xy 351.728132 -405.601028)
			(xy 351.715919 -405.622714) (xy 375.004926 -405.622714) (xy 375.004926 -405.557276) (xy 375.013711 -405.492431)
			(xy 375.031121 -405.429352) (xy 375.056841 -405.369181) (xy 375.073164 -405.34082) (xy 375.076469 -405.33479)
			(xy 375.080081 -405.321531) (xy 375.080276 -405.314658) (xy 375.080276 -404.565358) (xy 375.080065 -404.558486)
			(xy 375.07647 -404.545223) (xy 375.073164 -404.539196) (xy 375.05686 -404.510825) (xy 375.031139 -404.450656)
			(xy 375.013728 -404.38758) (xy 375.004942 -404.322737) (xy 375.004939 -404.257301) (xy 375.01372 -404.192457)
			(xy 375.031126 -404.12938) (xy 375.056842 -404.069209) (xy 375.073164 -404.040848) (xy 375.076494 -404.034831)
			(xy 375.08009 -404.021561) (xy 375.080276 -404.014686) (xy 375.080276 -403.728682) (xy 375.08065 -403.718505)
			(xy 375.088448 -403.699702) (xy 375.102849 -403.685317) (xy 375.12166 -403.677539) (xy 375.131838 -403.67712)
			(xy 375.848118 -403.67712) (xy 375.858275 -403.677618) (xy 375.877041 -403.685395) (xy 375.891405 -403.699759)
			(xy 375.899182 -403.718525) (xy 375.89968 -403.728682) (xy 375.89968 -404.014686) (xy 375.89988 -404.021559)
			(xy 375.903483 -404.034821) (xy 375.906792 -404.040848) (xy 375.923132 -404.069199) (xy 375.948846 -404.129373)
			(xy 375.966251 -404.192454) (xy 375.975032 -404.2573) (xy 375.975029 -404.322738) (xy 375.966243 -404.387583)
			(xy 375.948834 -404.450663) (xy 375.923115 -404.510834) (xy 375.906792 -404.539196) (xy 375.903478 -404.545221)
			(xy 375.899872 -404.558484) (xy 375.89968 -404.565358) (xy 375.89968 -405.314658) (xy 375.89989 -405.32153)
			(xy 375.903486 -405.334793) (xy 375.906792 -405.34082) (xy 375.923108 -405.369184) (xy 375.948825 -405.429355)
			(xy 375.966232 -405.492433) (xy 375.975016 -405.557277) (xy 375.975016 -405.622713) (xy 375.966234 -405.687557)
			(xy 375.948828 -405.750635) (xy 375.923113 -405.810806) (xy 375.906792 -405.839168) (xy 375.903488 -405.845198)
			(xy 375.899876 -405.858458) (xy 375.89968 -405.86533) (xy 375.89968 -406.151334) (xy 375.899195 -406.161492)
			(xy 375.891413 -406.180258) (xy 375.877045 -406.194622) (xy 375.858276 -406.202398) (xy 375.848118 -406.202896)
			(xy 375.131838 -406.202896) (xy 375.121673 -406.202406) (xy 375.102886 -406.19464) (xy 375.088501 -406.180275)
			(xy 375.080708 -406.161498) (xy 375.080276 -406.151334) (xy 375.080276 -405.86533) (xy 375.080075 -405.858457)
			(xy 375.076473 -405.845194) (xy 375.073164 -405.839168) (xy 375.056836 -405.81081) (xy 375.031117 -405.750638)
			(xy 375.013709 -405.687559) (xy 375.004926 -405.622714) (xy 351.715919 -405.622714) (xy 351.697563 -405.655307)
			(xy 351.660303 -405.705231) (xy 351.616966 -405.749981) (xy 351.568261 -405.788821) (xy 351.51499 -405.821114)
			(xy 351.458027 -405.846331) (xy 351.398306 -405.864055) (xy 351.336809 -405.873998) (xy 351.274546 -405.875994)
			(xy 351.212539 -405.870012) (xy 351.151805 -405.85615) (xy 351.093343 -405.834636) (xy 351.038112 -405.805822)
			(xy 350.98702 -405.770182) (xy 350.940904 -405.728301) (xy 350.900522 -405.680866) (xy 350.866538 -405.628657)
			(xy 350.839509 -405.572531) (xy 350.81988 -405.51341) (xy 350.807971 -405.452263) (xy 350.80398 -405.390096)
			(xy 349.532451 -405.390096) (xy 349.551362 -405.436805) (xy 349.567163 -405.497063) (xy 349.575129 -405.558846)
			(xy 349.575628 -405.589994) (xy 349.575129 -405.621142) (xy 349.567163 -405.682925) (xy 349.551362 -405.743183)
			(xy 349.527984 -405.800926) (xy 349.497415 -405.855205) (xy 349.460155 -405.905129) (xy 349.416818 -405.949879)
			(xy 349.368113 -405.988719) (xy 349.314842 -406.021012) (xy 349.257879 -406.046229) (xy 349.198158 -406.063953)
			(xy 349.136661 -406.073896) (xy 349.074398 -406.075892) (xy 349.012391 -406.06991) (xy 348.951657 -406.056048)
			(xy 348.893195 -406.034534) (xy 348.837964 -406.00572) (xy 348.786872 -405.97008) (xy 348.740756 -405.928199)
			(xy 348.700374 -405.880764) (xy 348.66639 -405.828555) (xy 348.639361 -405.772429) (xy 348.619732 -405.713308)
			(xy 348.607823 -405.652161) (xy 348.603832 -405.589994) (xy 347.332159 -405.589994) (xy 347.323221 -405.610908)
			(xy 347.3069 -405.63927) (xy 347.303596 -405.6453) (xy 347.299984 -405.65856) (xy 347.299788 -405.665432)
			(xy 347.299788 -406.414732) (xy 347.299969 -406.421606) (xy 347.303585 -406.434869) (xy 347.3069 -406.440894)
			(xy 347.323194 -406.469271) (xy 347.348912 -406.529439) (xy 347.366322 -406.592514) (xy 347.375108 -406.657356)
			(xy 347.37511 -406.690068) (xy 350.80398 -406.690068) (xy 350.807971 -406.627901) (xy 350.81988 -406.566754)
			(xy 350.839509 -406.507633) (xy 350.866538 -406.451507) (xy 350.900522 -406.399298) (xy 350.940904 -406.351863)
			(xy 350.98702 -406.309982) (xy 351.038112 -406.274342) (xy 351.093343 -406.245528) (xy 351.151805 -406.224014)
			(xy 351.212539 -406.210152) (xy 351.274546 -406.20417) (xy 351.336809 -406.206166) (xy 351.398306 -406.216109)
			(xy 351.458027 -406.233833) (xy 351.51499 -406.25905) (xy 351.568261 -406.291343) (xy 351.616966 -406.330183)
			(xy 351.660303 -406.374933) (xy 351.697563 -406.424857) (xy 351.728132 -406.479136) (xy 351.75151 -406.536879)
			(xy 351.767311 -406.597137) (xy 351.775277 -406.65892) (xy 351.775776 -406.690068) (xy 377.204224 -406.690068)
			(xy 377.204795 -406.657339) (xy 377.213648 -406.59248) (xy 377.231137 -406.5294) (xy 377.256944 -406.469242)
			(xy 377.273312 -406.440894) (xy 377.27663 -406.434871) (xy 377.280233 -406.421606) (xy 377.280424 -406.414732)
			(xy 377.280424 -405.665432) (xy 377.280217 -405.65856) (xy 377.276619 -405.645297) (xy 377.273312 -405.63927)
			(xy 377.256936 -405.610927) (xy 377.231136 -405.550765) (xy 377.213649 -405.487684) (xy 377.204793 -405.422826)
			(xy 377.204224 -405.390096) (xy 377.204762 -405.357365) (xy 377.213626 -405.292506) (xy 377.231124 -405.229426)
			(xy 377.25694 -405.169269) (xy 377.273312 -405.140922) (xy 377.27662 -405.134894) (xy 377.28023 -405.121633)
			(xy 377.280424 -405.11476) (xy 377.280424 -404.828756) (xy 377.28085 -404.818641) (xy 377.288606 -404.799958)
			(xy 377.302922 -404.785664) (xy 377.321617 -404.777935) (xy 377.331732 -404.777448) (xy 378.048012 -404.777448)
			(xy 378.058115 -404.777974) (xy 378.076783 -404.785706) (xy 378.091076 -404.79999) (xy 378.098819 -404.818653)
			(xy 378.09932 -404.828756) (xy 378.09932 -405.11476) (xy 378.099525 -405.121632) (xy 378.103124 -405.134895)
			(xy 378.106432 -405.140922) (xy 378.1228 -405.16927) (xy 378.148603 -405.22943) (xy 378.166092 -405.292509)
			(xy 378.174951 -405.357367) (xy 378.17552 -405.390096) (xy 378.174972 -405.422826) (xy 378.166111 -405.487685)
			(xy 378.148615 -405.550765) (xy 378.131783 -405.589994) (xy 379.404372 -405.589994) (xy 379.404961 -405.557265)
			(xy 379.413811 -405.492408) (xy 379.431294 -405.429328) (xy 379.457095 -405.369169) (xy 379.47346 -405.34082)
			(xy 379.476764 -405.33479) (xy 379.480377 -405.321531) (xy 379.480572 -405.314658) (xy 379.480572 -404.565358)
			(xy 379.480361 -404.558486) (xy 379.476766 -404.545223) (xy 379.47346 -404.539196) (xy 379.457099 -404.510844)
			(xy 379.431294 -404.450686) (xy 379.413803 -404.387607) (xy 379.404942 -404.322751) (xy 379.404372 -404.290022)
			(xy 379.404929 -404.257292) (xy 379.413788 -404.192434) (xy 379.431281 -404.129354) (xy 379.45709 -404.069196)
			(xy 379.47346 -404.040848) (xy 379.47679 -404.034831) (xy 379.480386 -404.021561) (xy 379.480572 -404.014686)
			(xy 379.480572 -403.728682) (xy 379.481013 -403.71855) (xy 379.488752 -403.699822) (xy 379.503053 -403.685466)
			(xy 379.52175 -403.677653) (xy 379.53188 -403.67712) (xy 380.24816 -403.67712) (xy 380.258314 -403.677555)
			(xy 380.277069 -403.685341) (xy 380.291395 -403.699734) (xy 380.299092 -403.718526) (xy 380.299468 -403.728682)
			(xy 380.299468 -404.014686) (xy 380.299669 -404.021558) (xy 380.303272 -404.034821) (xy 380.30658 -404.040848)
			(xy 380.322963 -404.069188) (xy 380.348761 -404.129351) (xy 380.366246 -404.192433) (xy 380.375101 -404.257292)
			(xy 380.375668 -404.290022) (xy 380.375081 -404.322751) (xy 380.36623 -404.387608) (xy 380.348746 -404.450688)
			(xy 380.322945 -404.510847) (xy 380.30658 -404.539196) (xy 380.303265 -404.545221) (xy 380.29966 -404.558484)
			(xy 380.299468 -404.565358) (xy 380.299468 -405.314658) (xy 380.29968 -405.32153) (xy 380.303275 -405.334792)
			(xy 380.30658 -405.34082) (xy 380.322952 -405.369166) (xy 380.348752 -405.429327) (xy 380.36624 -405.492407)
			(xy 380.375099 -405.557265) (xy 380.375668 -405.589994) (xy 380.375113 -405.622724) (xy 380.366252 -405.687582)
			(xy 380.348759 -405.750662) (xy 380.322949 -405.81082) (xy 380.30658 -405.839168) (xy 380.303275 -405.845197)
			(xy 380.299664 -405.858458) (xy 380.299468 -405.86533) (xy 380.299468 -406.151334) (xy 380.299002 -406.161462)
			(xy 380.291264 -406.180182) (xy 380.276972 -406.194537) (xy 380.258286 -406.202357) (xy 380.24816 -406.202896)
			(xy 379.53188 -406.202896) (xy 379.521724 -406.202495) (xy 379.50297 -406.194692) (xy 379.488648 -406.180289)
			(xy 379.480949 -406.161492) (xy 379.480572 -406.151334) (xy 379.480572 -405.86533) (xy 379.480372 -405.858457)
			(xy 379.47677 -405.845194) (xy 379.47346 -405.839168) (xy 379.457087 -405.810823) (xy 379.431286 -405.750662)
			(xy 379.413798 -405.687581) (xy 379.40494 -405.622723) (xy 379.404372 -405.589994) (xy 378.131783 -405.589994)
			(xy 378.122803 -405.610923) (xy 378.106432 -405.63927) (xy 378.103131 -405.645301) (xy 378.099516 -405.65856)
			(xy 378.09932 -405.665432) (xy 378.09932 -406.414732) (xy 378.099497 -406.421606) (xy 378.103115 -406.434869)
			(xy 378.106432 -406.440894) (xy 378.122789 -406.469248) (xy 378.148594 -406.529405) (xy 378.166087 -406.592483)
			(xy 378.174949 -406.657339) (xy 378.17552 -406.690068) (xy 378.17496 -406.722792) (xy 381.604856 -406.722792)
			(xy 381.604859 -406.657353) (xy 381.613646 -406.592508) (xy 381.631057 -406.529428) (xy 381.656777 -406.469256)
			(xy 381.6731 -406.440894) (xy 381.676417 -406.43487) (xy 381.680021 -406.421606) (xy 381.680212 -406.414732)
			(xy 381.680212 -405.665432) (xy 381.680007 -405.65856) (xy 381.676407 -405.645297) (xy 381.6731 -405.63927)
			(xy 381.656776 -405.61091) (xy 381.63106 -405.550738) (xy 381.613654 -405.487659) (xy 381.604872 -405.422815)
			(xy 381.604872 -405.357378) (xy 381.613655 -405.292534) (xy 381.631063 -405.229455) (xy 381.656779 -405.169284)
			(xy 381.6731 -405.140922) (xy 381.676407 -405.134894) (xy 381.680017 -405.121633) (xy 381.680212 -405.11476)
			(xy 381.680212 -404.828756) (xy 381.680586 -404.818598) (xy 381.688398 -404.799842) (xy 381.702809 -404.78552)
			(xy 381.721613 -404.777824) (xy 381.731774 -404.777448) (xy 382.448054 -404.777448) (xy 382.458179 -404.777965)
			(xy 382.4769 -404.785679) (xy 382.491258 -404.799956) (xy 382.499078 -404.818634) (xy 382.499616 -404.828756)
			(xy 382.499616 -405.11476) (xy 382.499821 -405.121632) (xy 382.50342 -405.134895) (xy 382.506728 -405.140922)
			(xy 382.523048 -405.169285) (xy 382.548768 -405.229455) (xy 382.566177 -405.292534) (xy 382.574962 -405.357378)
			(xy 382.574962 -405.422815) (xy 382.566179 -405.48766) (xy 382.54877 -405.550738) (xy 382.523051 -405.610909)
			(xy 382.516257 -405.622713) (xy 383.805012 -405.622713) (xy 383.805013 -405.557276) (xy 383.813797 -405.492431)
			(xy 383.831206 -405.429352) (xy 383.856925 -405.369181) (xy 383.873248 -405.34082) (xy 383.876551 -405.33479)
			(xy 383.880165 -405.32153) (xy 383.88036 -405.314658) (xy 383.88036 -404.565358) (xy 383.880151 -404.558486)
			(xy 383.876555 -404.545223) (xy 383.873248 -404.539196) (xy 383.856944 -404.510825) (xy 383.831224 -404.450656)
			(xy 383.813814 -404.387579) (xy 383.805028 -404.322737) (xy 383.805025 -404.257301) (xy 383.813806 -404.192458)
			(xy 383.831212 -404.12938) (xy 383.856927 -404.069209) (xy 383.873248 -404.040848) (xy 383.876577 -404.03483)
			(xy 383.880174 -404.021561) (xy 383.88036 -404.014686) (xy 383.88036 -403.728682) (xy 383.88075 -403.718507)
			(xy 383.888545 -403.699707) (xy 383.902941 -403.685322) (xy 383.921746 -403.677542) (xy 383.931922 -403.67712)
			(xy 384.648202 -403.67712) (xy 384.658358 -403.677631) (xy 384.677123 -403.685403) (xy 384.691488 -403.699763)
			(xy 384.699265 -403.718526) (xy 384.699764 -403.728682) (xy 384.699764 -404.014686) (xy 384.699966 -404.021558)
			(xy 384.703568 -404.034821) (xy 384.706876 -404.040848) (xy 384.723216 -404.069199) (xy 384.748931 -404.129373)
			(xy 384.766337 -404.192454) (xy 384.775118 -404.2573) (xy 384.775115 -404.322738) (xy 384.766329 -404.387583)
			(xy 384.748919 -404.450663) (xy 384.723199 -404.510835) (xy 384.706876 -404.539196) (xy 384.703561 -404.54522)
			(xy 384.699956 -404.558484) (xy 384.699764 -404.565358) (xy 384.699764 -405.314658) (xy 384.699976 -405.32153)
			(xy 384.703571 -405.334792) (xy 384.706876 -405.34082) (xy 384.723193 -405.369184) (xy 384.74891 -405.429355)
			(xy 384.766318 -405.492433) (xy 384.775102 -405.557277) (xy 384.775103 -405.622713) (xy 384.76632 -405.687557)
			(xy 384.748913 -405.750635) (xy 384.723197 -405.810807) (xy 384.706876 -405.839168) (xy 384.703571 -405.845197)
			(xy 384.69996 -405.858457) (xy 384.699764 -405.86533) (xy 384.699764 -406.151334) (xy 384.699295 -406.161494)
			(xy 384.691509 -406.180263) (xy 384.677136 -406.194627) (xy 384.658362 -406.202401) (xy 384.648202 -406.202896)
			(xy 383.931922 -406.202896) (xy 383.92177 -406.20235) (xy 383.903008 -406.194589) (xy 383.888643 -406.180239)
			(xy 383.880861 -406.161486) (xy 383.88036 -406.151334) (xy 383.88036 -405.86533) (xy 383.880162 -405.858457)
			(xy 383.876558 -405.845194) (xy 383.873248 -405.839168) (xy 383.85692 -405.81081) (xy 383.831203 -405.750638)
			(xy 383.813795 -405.687559) (xy 383.805012 -405.622713) (xy 382.516257 -405.622713) (xy 382.506728 -405.63927)
			(xy 382.503426 -405.645301) (xy 382.499812 -405.65856) (xy 382.499616 -405.665432) (xy 382.499616 -406.414732)
			(xy 382.499794 -406.421606) (xy 382.503411 -406.434869) (xy 382.506728 -406.440894) (xy 382.523024 -406.46927)
			(xy 382.548746 -406.529437) (xy 382.566158 -406.592513) (xy 382.574946 -406.657355) (xy 382.574948 -406.690068)
			(xy 386.004308 -406.690068) (xy 386.004881 -406.657339) (xy 386.013734 -406.592481) (xy 386.031223 -406.5294)
			(xy 386.057028 -406.469242) (xy 386.073396 -406.440894) (xy 386.076713 -406.43487) (xy 386.080317 -406.421606)
			(xy 386.080508 -406.414732) (xy 386.080508 -405.665432) (xy 386.080303 -405.65856) (xy 386.076704 -405.645297)
			(xy 386.073396 -405.63927) (xy 386.057018 -405.610928) (xy 386.031219 -405.550766) (xy 386.013733 -405.487684)
			(xy 386.004876 -405.422826) (xy 386.004308 -405.390096) (xy 386.004848 -405.357366) (xy 386.013711 -405.292506)
			(xy 386.031209 -405.229426) (xy 386.057024 -405.169269) (xy 386.073396 -405.140922) (xy 386.076703 -405.134893)
			(xy 386.080313 -405.121633) (xy 386.080508 -405.11476) (xy 386.080508 -404.828756) (xy 386.080949 -404.818643)
			(xy 386.088703 -404.799963) (xy 386.103013 -404.785669) (xy 386.121703 -404.777938) (xy 386.131816 -404.777448)
			(xy 386.848096 -404.777448) (xy 386.858198 -404.777987) (xy 386.876866 -404.785714) (xy 386.891159 -404.799993)
			(xy 386.898903 -404.818654) (xy 386.899404 -404.828756) (xy 386.899404 -405.11476) (xy 386.899611 -405.121632)
			(xy 386.903209 -405.134895) (xy 386.906516 -405.140922) (xy 386.922892 -405.169266) (xy 386.948691 -405.229427)
			(xy 386.966178 -405.292508) (xy 386.975035 -405.357367) (xy 386.975604 -405.390096) (xy 386.975059 -405.422826)
			(xy 386.966197 -405.487685) (xy 386.948701 -405.550765) (xy 386.922888 -405.610923) (xy 386.916079 -405.622713)
			(xy 388.204802 -405.622713) (xy 388.204802 -405.557276) (xy 388.213586 -405.492431) (xy 388.230995 -405.429353)
			(xy 388.256713 -405.369181) (xy 388.273036 -405.34082) (xy 388.276339 -405.334789) (xy 388.279953 -405.32153)
			(xy 388.280148 -405.314658) (xy 388.280148 -404.565358) (xy 388.279941 -404.558486) (xy 388.276344 -404.545223)
			(xy 388.273036 -404.539196) (xy 388.256732 -404.510824) (xy 388.231013 -404.450656) (xy 388.213603 -404.387579)
			(xy 388.204817 -404.322736) (xy 388.204815 -404.257301) (xy 388.213596 -404.192458) (xy 388.231001 -404.12938)
			(xy 388.256715 -404.069209) (xy 388.273036 -404.040848) (xy 388.276364 -404.03483) (xy 388.279962 -404.021561)
			(xy 388.280148 -404.014686) (xy 388.280148 -403.728682) (xy 388.280619 -403.718522) (xy 388.288401 -403.69975)
			(xy 388.302774 -403.685385) (xy 388.32155 -403.677613) (xy 388.33171 -403.67712) (xy 389.04799 -403.67712)
			(xy 389.058145 -403.677641) (xy 389.07691 -403.685409) (xy 389.091275 -403.699766) (xy 389.099053 -403.718527)
			(xy 389.099552 -403.728682) (xy 389.099552 -404.014686) (xy 389.099743 -404.021559) (xy 389.103351 -404.034822)
			(xy 389.106664 -404.040848) (xy 389.123005 -404.069199) (xy 389.14872 -404.129373) (xy 389.166126 -404.192453)
			(xy 389.174908 -404.2573) (xy 389.174905 -404.322738) (xy 389.166119 -404.387584) (xy 389.148708 -404.450663)
			(xy 389.122988 -404.510835) (xy 389.106664 -404.539196) (xy 389.103356 -404.545224) (xy 389.099745 -404.558485)
			(xy 389.099552 -404.565358) (xy 389.099552 -405.314658) (xy 389.099753 -405.321531) (xy 389.103354 -405.334794)
			(xy 389.106664 -405.34082) (xy 389.122981 -405.369184) (xy 389.148699 -405.429355) (xy 389.166108 -405.492433)
			(xy 389.174892 -405.557277) (xy 389.174892 -405.622713) (xy 389.16611 -405.687557) (xy 389.148702 -405.750636)
			(xy 389.122986 -405.810807) (xy 389.106664 -405.839168) (xy 389.103366 -405.845201) (xy 389.099749 -405.858458)
			(xy 389.099552 -405.86533) (xy 389.099552 -406.151334) (xy 389.099094 -406.161495) (xy 389.091307 -406.180267)
			(xy 389.07693 -406.194631) (xy 389.058152 -406.202403) (xy 389.04799 -406.202896) (xy 388.33171 -406.202896)
			(xy 388.321557 -406.202359) (xy 388.302795 -406.194594) (xy 388.28843 -406.180242) (xy 388.280649 -406.161487)
			(xy 388.280148 -406.151334) (xy 388.280148 -405.86533) (xy 388.279951 -405.858457) (xy 388.276347 -405.845194)
			(xy 388.273036 -405.839168) (xy 388.256709 -405.81081) (xy 388.230992 -405.750638) (xy 388.213584 -405.687558)
			(xy 388.204802 -405.622713) (xy 386.916079 -405.622713) (xy 386.906516 -405.63927) (xy 386.903213 -405.6453)
			(xy 386.8996 -405.65856) (xy 386.899404 -405.665432) (xy 386.899404 -406.414732) (xy 386.899583 -406.421606)
			(xy 386.9032 -406.434869) (xy 386.906516 -406.440894) (xy 386.922881 -406.469244) (xy 386.948682 -406.529403)
			(xy 386.966172 -406.592482) (xy 386.975033 -406.657339) (xy 386.975604 -406.690068) (xy 386.975046 -406.722792)
			(xy 390.404928 -406.722792) (xy 390.404932 -406.657353) (xy 390.41372 -406.592506) (xy 390.431134 -406.529426)
			(xy 390.456858 -406.469255) (xy 390.473184 -406.440894) (xy 390.4765 -406.43487) (xy 390.480105 -406.421606)
			(xy 390.480296 -406.414732) (xy 390.480296 -405.665432) (xy 390.480092 -405.65856) (xy 390.476492 -405.645297)
			(xy 390.473184 -405.63927) (xy 390.456857 -405.610911) (xy 390.431137 -405.55074) (xy 390.413728 -405.487661)
			(xy 390.404944 -405.422815) (xy 390.404944 -405.357378) (xy 390.413729 -405.292533) (xy 390.43114 -405.229454)
			(xy 390.45686 -405.169283) (xy 390.473184 -405.140922) (xy 390.47649 -405.134893) (xy 390.480101 -405.121633)
			(xy 390.480296 -405.11476) (xy 390.480296 -404.828756) (xy 390.480686 -404.8186) (xy 390.488495 -404.799847)
			(xy 390.502901 -404.785525) (xy 390.521699 -404.777826) (xy 390.531858 -404.777448) (xy 391.248138 -404.777448)
			(xy 391.258268 -404.777896) (xy 391.276992 -404.785637) (xy 391.291347 -404.799935) (xy 391.299163 -404.818628)
			(xy 391.2997 -404.828756) (xy 391.2997 -405.11476) (xy 391.299907 -405.121632) (xy 391.303505 -405.134895)
			(xy 391.306812 -405.140922) (xy 391.323129 -405.169286) (xy 391.348844 -405.229457) (xy 391.366251 -405.292535)
			(xy 391.375034 -405.357379) (xy 391.375035 -405.422814) (xy 391.366252 -405.487658) (xy 391.348847 -405.550737)
			(xy 391.323132 -405.610908) (xy 391.306812 -405.63927) (xy 391.303509 -405.6453) (xy 391.299896 -405.65856)
			(xy 391.2997 -405.665432) (xy 391.2997 -406.414732) (xy 391.29988 -406.421606) (xy 391.303496 -406.434869)
			(xy 391.306812 -406.440894) (xy 391.323106 -406.469271) (xy 391.348823 -406.529439) (xy 391.366232 -406.592514)
			(xy 391.375018 -406.657356) (xy 391.375022 -406.722789) (xy 391.366243 -406.787632) (xy 391.348841 -406.850709)
			(xy 391.323131 -406.91088) (xy 391.306812 -406.939242) (xy 391.303483 -406.94526) (xy 391.299886 -406.958529)
			(xy 391.2997 -406.965404) (xy 391.2997 -407.251408) (xy 391.299285 -407.261563) (xy 391.291487 -407.280315)
			(xy 391.277088 -407.294638) (xy 391.258295 -407.302338) (xy 391.248138 -407.302716) (xy 390.531858 -407.302716)
			(xy 390.521723 -407.302307) (xy 390.502993 -407.294557) (xy 390.488636 -407.280247) (xy 390.480826 -407.261541)
			(xy 390.480296 -407.251408) (xy 390.480296 -406.965404) (xy 390.480103 -406.958531) (xy 390.476496 -406.945268)
			(xy 390.473184 -406.939242) (xy 390.456833 -406.910896) (xy 390.431116 -406.850722) (xy 390.413709 -406.78764)
			(xy 390.404928 -406.722792) (xy 386.975046 -406.722792) (xy 386.975046 -406.722798) (xy 386.966187 -406.787656)
			(xy 386.948695 -406.850736) (xy 386.922885 -406.910894) (xy 386.906516 -406.939242) (xy 386.903187 -406.94526)
			(xy 386.89959 -406.958529) (xy 386.899404 -406.965404) (xy 386.899404 -407.251408) (xy 386.898921 -407.261517)
			(xy 386.891182 -407.280194) (xy 386.876884 -407.294489) (xy 386.858205 -407.302224) (xy 386.848096 -407.302716)
			(xy 386.131816 -407.302716) (xy 386.121697 -407.302271) (xy 386.102996 -407.294531) (xy 386.088682 -407.280224)
			(xy 386.080933 -407.261527) (xy 386.080508 -407.251408) (xy 386.080508 -406.965404) (xy 386.080314 -406.958531)
			(xy 386.076707 -406.945268) (xy 386.073396 -406.939242) (xy 386.057047 -406.910884) (xy 386.031241 -406.850727)
			(xy 386.013747 -406.787651) (xy 386.004881 -406.722796) (xy 386.004308 -406.690068) (xy 382.574948 -406.690068)
			(xy 382.57495 -406.72279) (xy 382.566169 -406.787633) (xy 382.548764 -406.850711) (xy 382.523049 -406.910881)
			(xy 382.506728 -406.939242) (xy 382.5034 -406.94526) (xy 382.499802 -406.958529) (xy 382.499616 -406.965404)
			(xy 382.499616 -407.251408) (xy 382.499185 -407.261561) (xy 382.49139 -407.28031) (xy 382.476996 -407.294632)
			(xy 382.458209 -407.302335) (xy 382.448054 -407.302716) (xy 381.731774 -407.302716) (xy 381.72164 -407.302294)
			(xy 381.70291 -407.294549) (xy 381.688553 -407.280243) (xy 381.680743 -407.26154) (xy 381.680212 -407.251408)
			(xy 381.680212 -406.965404) (xy 381.680017 -406.958531) (xy 381.676411 -406.945268) (xy 381.6731 -406.939242)
			(xy 381.656752 -406.910895) (xy 381.631039 -406.85072) (xy 381.613635 -406.787639) (xy 381.604856 -406.722792)
			(xy 378.17496 -406.722792) (xy 378.17496 -406.722798) (xy 378.166102 -406.787656) (xy 378.14861 -406.850736)
			(xy 378.122801 -406.910894) (xy 378.106432 -406.939242) (xy 378.103105 -406.945261) (xy 378.099507 -406.958529)
			(xy 378.09932 -406.965404) (xy 378.09932 -407.251408) (xy 378.098822 -407.261515) (xy 378.091085 -407.280189)
			(xy 378.076793 -407.294483) (xy 378.058119 -407.302221) (xy 378.048012 -407.302716) (xy 377.331732 -407.302716)
			(xy 377.321614 -407.302258) (xy 377.302914 -407.294524) (xy 377.288599 -407.28022) (xy 377.280849 -407.261526)
			(xy 377.280424 -407.251408) (xy 377.280424 -406.965404) (xy 377.280228 -406.958531) (xy 377.276622 -406.945268)
			(xy 377.273312 -406.939242) (xy 377.256964 -406.910883) (xy 377.231158 -406.850727) (xy 377.213663 -406.787651)
			(xy 377.204797 -406.722796) (xy 377.204224 -406.690068) (xy 351.775776 -406.690068) (xy 351.775277 -406.721216)
			(xy 351.767311 -406.782999) (xy 351.75151 -406.843257) (xy 351.728132 -406.901) (xy 351.697563 -406.955279)
			(xy 351.660303 -407.005203) (xy 351.616966 -407.049953) (xy 351.568261 -407.088793) (xy 351.51499 -407.121086)
			(xy 351.458027 -407.146303) (xy 351.398306 -407.164027) (xy 351.336809 -407.17397) (xy 351.274546 -407.175966)
			(xy 351.212539 -407.169984) (xy 351.151805 -407.156122) (xy 351.093343 -407.134608) (xy 351.038112 -407.105794)
			(xy 350.98702 -407.070154) (xy 350.940904 -407.028273) (xy 350.900522 -406.980838) (xy 350.866538 -406.928629)
			(xy 350.839509 -406.872503) (xy 350.81988 -406.813382) (xy 350.807971 -406.752235) (xy 350.80398 -406.690068)
			(xy 347.37511 -406.690068) (xy 347.375112 -406.72279) (xy 347.366333 -406.787632) (xy 347.34893 -406.850709)
			(xy 347.323219 -406.91088) (xy 347.3069 -406.939242) (xy 347.30357 -406.945259) (xy 347.299974 -406.958529)
			(xy 347.299788 -406.965404) (xy 347.299788 -407.251408) (xy 347.299385 -407.261564) (xy 347.291584 -407.280319)
			(xy 347.277182 -407.294642) (xy 347.258384 -407.30234) (xy 347.248226 -407.302716) (xy 346.531946 -407.302716)
			(xy 346.521817 -407.302234) (xy 346.503088 -407.294514) (xy 346.488729 -407.280225) (xy 346.480916 -407.261535)
			(xy 346.480384 -407.251408) (xy 346.480384 -406.965404) (xy 346.480192 -406.958531) (xy 346.476584 -406.945268)
			(xy 346.473272 -406.939242) (xy 346.456922 -406.910896) (xy 346.431205 -406.850722) (xy 346.413798 -406.78764)
			(xy 346.405018 -406.722792) (xy 342.975135 -406.722792) (xy 342.975135 -406.722798) (xy 342.966277 -406.787656)
			(xy 342.948784 -406.850737) (xy 342.922974 -406.910894) (xy 342.906604 -406.939242) (xy 342.903275 -406.945259)
			(xy 342.899678 -406.958529) (xy 342.899492 -406.965404) (xy 342.899492 -407.251408) (xy 342.89909 -407.261532)
			(xy 342.891338 -407.280237) (xy 342.877017 -407.294551) (xy 342.858308 -407.302295) (xy 342.848184 -407.302716)
			(xy 342.131904 -407.302716) (xy 342.121798 -407.302212) (xy 342.103122 -407.294479) (xy 342.088828 -407.280188)
			(xy 342.08109 -407.261514) (xy 342.080596 -407.251408) (xy 342.080596 -406.965404) (xy 342.080403 -406.958531)
			(xy 342.076796 -406.945268) (xy 342.073484 -406.939242) (xy 342.057134 -406.910884) (xy 342.031328 -406.850728)
			(xy 342.013835 -406.787651) (xy 342.004969 -406.722796) (xy 342.004396 -406.690068) (xy 338.575037 -406.690068)
			(xy 338.575039 -406.72279) (xy 338.566259 -406.787633) (xy 338.548853 -406.850711) (xy 338.523137 -406.910881)
			(xy 338.506816 -406.939242) (xy 338.503487 -406.94526) (xy 338.49989 -406.958529) (xy 338.499704 -406.965404)
			(xy 338.499704 -407.251408) (xy 338.499285 -407.261562) (xy 338.491487 -407.280314) (xy 338.47709 -407.294637)
			(xy 338.458298 -407.302337) (xy 338.448142 -407.302716) (xy 337.731862 -407.302716) (xy 337.721727 -407.302303)
			(xy 337.702997 -407.294555) (xy 337.688641 -407.280246) (xy 337.68083 -407.261541) (xy 337.6803 -407.251408)
			(xy 337.6803 -406.965404) (xy 337.680107 -406.958531) (xy 337.6765 -406.945268) (xy 337.673188 -406.939242)
			(xy 337.65684 -406.910895) (xy 337.631128 -406.85072) (xy 337.613725 -406.787638) (xy 337.604945 -406.722792)
			(xy 334.175049 -406.722792) (xy 334.175049 -406.722798) (xy 334.166191 -406.787656) (xy 334.148699 -406.850736)
			(xy 334.122889 -406.910894) (xy 334.10652 -406.939242) (xy 334.103192 -406.94526) (xy 334.099594 -406.958529)
			(xy 334.099408 -406.965404) (xy 334.099408 -407.251408) (xy 334.098921 -407.261516) (xy 334.091183 -407.280193)
			(xy 334.076886 -407.294487) (xy 334.058208 -407.302223) (xy 334.0481 -407.302716) (xy 333.33182 -407.302716)
			(xy 333.321701 -407.302268) (xy 333.303001 -407.29453) (xy 333.288686 -407.280223) (xy 333.280937 -407.261527)
			(xy 333.280512 -407.251408) (xy 333.280512 -406.965404) (xy 333.280317 -406.958531) (xy 333.276711 -406.945268)
			(xy 333.2734 -406.939242) (xy 333.257051 -406.910884) (xy 333.231245 -406.850727) (xy 333.213751 -406.787651)
			(xy 333.204885 -406.722796) (xy 333.204312 -406.690068) (xy 329.948032 -406.690068) (xy 329.948032 -409.522889)
			(xy 331.004998 -409.522889) (xy 331.005002 -409.457449) (xy 331.013791 -409.392603) (xy 331.031204 -409.329523)
			(xy 331.056927 -409.269351) (xy 331.073252 -409.24099) (xy 331.076566 -409.234965) (xy 331.080173 -409.221702)
			(xy 331.080364 -409.214828) (xy 331.080364 -408.465528) (xy 331.080166 -408.458655) (xy 331.076562 -408.445392)
			(xy 331.073252 -408.439366) (xy 331.056923 -408.411009) (xy 331.031205 -408.350837) (xy 331.013797 -408.287757)
			(xy 331.005014 -408.222912) (xy 331.005015 -408.157474) (xy 331.0138 -408.092629) (xy 331.031209 -408.02955)
			(xy 331.056929 -407.969379) (xy 331.073252 -407.941018) (xy 331.076556 -407.934988) (xy 331.080169 -407.921729)
			(xy 331.080364 -407.914856) (xy 331.080364 -407.628852) (xy 331.080782 -407.618699) (xy 331.088586 -407.599953)
			(xy 331.102983 -407.585633) (xy 331.121771 -407.577928) (xy 331.131926 -407.577544) (xy 331.848206 -407.577544)
			(xy 331.858334 -407.578022) (xy 331.877056 -407.585752) (xy 331.891412 -407.600041) (xy 331.89923 -407.618727)
			(xy 331.899768 -407.628852) (xy 331.899768 -407.914856) (xy 331.899981 -407.921728) (xy 331.903575 -407.93499)
			(xy 331.90688 -407.941018) (xy 331.923195 -407.969383) (xy 331.948912 -408.029554) (xy 331.96632 -408.092632)
			(xy 331.975104 -408.157475) (xy 331.975105 -408.222911) (xy 331.966323 -408.287755) (xy 331.948917 -408.350833)
			(xy 331.923201 -408.411005) (xy 331.90688 -408.439366) (xy 331.903576 -408.445396) (xy 331.899964 -408.458656)
			(xy 331.899768 -408.465528) (xy 331.899768 -409.214828) (xy 331.899953 -409.221702) (xy 331.903567 -409.234964)
			(xy 331.90688 -409.24099) (xy 331.923171 -409.269368) (xy 331.948891 -409.329536) (xy 331.966301 -409.392611)
			(xy 331.975088 -409.457452) (xy 331.975093 -409.522886) (xy 331.966314 -409.587729) (xy 331.948911 -409.650806)
			(xy 331.923199 -409.710977) (xy 331.90688 -409.739338) (xy 331.90355 -409.745355) (xy 331.899954 -409.758625)
			(xy 331.899768 -409.7655) (xy 331.899768 -410.051504) (xy 331.899381 -410.061662) (xy 331.891578 -410.080421)
			(xy 331.87717 -410.094745) (xy 331.858367 -410.102439) (xy 331.848206 -410.102812) (xy 331.131926 -410.102812)
			(xy 331.121807 -410.102254) (xy 331.103097 -410.094544) (xy 331.088741 -410.08028) (xy 331.080912 -410.061619)
			(xy 331.080364 -410.051504) (xy 331.080364 -409.7655) (xy 331.080176 -409.758626) (xy 331.076566 -409.745363)
			(xy 331.073252 -409.739338) (xy 331.056899 -409.710994) (xy 331.031183 -409.650819) (xy 331.013778 -409.587736)
			(xy 331.004998 -409.522889) (xy 329.948032 -409.522889) (xy 329.948032 -410.057854) (xy 329.948473 -410.067922)
			(xy 329.956182 -410.08652) (xy 329.963018 -410.093922) (xy 330.459164 -410.589984) (xy 333.204312 -410.589984)
			(xy 333.204891 -410.557255) (xy 333.213743 -410.492397) (xy 333.231229 -410.429317) (xy 333.257033 -410.369158)
			(xy 333.2734 -410.34081) (xy 333.276711 -410.334784) (xy 333.280319 -410.321521) (xy 333.280512 -410.314648)
			(xy 333.280512 -409.565348) (xy 333.2803 -409.558476) (xy 333.276705 -409.545214) (xy 333.2734 -409.539186)
			(xy 333.257029 -409.51084) (xy 333.231228 -409.450679) (xy 333.21374 -409.387599) (xy 333.204882 -409.322741)
			(xy 333.204312 -409.290012) (xy 333.204859 -409.257282) (xy 333.21372 -409.192423) (xy 333.231216 -409.129343)
			(xy 333.257029 -409.069185) (xy 333.2734 -409.040838) (xy 333.276701 -409.034807) (xy 333.280315 -409.021548)
			(xy 333.280512 -409.014676) (xy 333.280512 -408.728672) (xy 333.280962 -408.71856) (xy 333.288711 -408.699879)
			(xy 333.303019 -408.685585) (xy 333.321708 -408.677853) (xy 333.33182 -408.677364) (xy 334.0481 -408.677364)
			(xy 334.058204 -408.677884) (xy 334.076876 -408.685615) (xy 334.091169 -408.699901) (xy 334.09891 -408.718568)
			(xy 334.099408 -408.728672) (xy 334.099408 -409.014676) (xy 334.099608 -409.021549) (xy 334.103211 -409.034811)
			(xy 334.10652 -409.040838) (xy 334.122903 -409.069178) (xy 334.1487 -409.129341) (xy 334.166185 -409.192423)
			(xy 334.17504 -409.257282) (xy 334.175608 -409.290012) (xy 334.175024 -409.322741) (xy 334.166173 -409.387598)
			(xy 334.148688 -409.450679) (xy 334.131753 -409.490164) (xy 335.40446 -409.490164) (xy 335.405037 -409.457435)
			(xy 335.41389 -409.392577) (xy 335.431377 -409.329497) (xy 335.457181 -409.269338) (xy 335.473548 -409.24099)
			(xy 335.476862 -409.234965) (xy 335.480469 -409.221702) (xy 335.48066 -409.214828) (xy 335.48066 -408.465528)
			(xy 335.480462 -408.458655) (xy 335.476859 -408.445392) (xy 335.473548 -408.439366) (xy 335.457173 -408.411022)
			(xy 335.431373 -408.350861) (xy 335.413885 -408.28778) (xy 335.405028 -408.222921) (xy 335.40446 -408.190192)
			(xy 335.40505 -408.157463) (xy 335.4139 -408.092606) (xy 335.431383 -408.029526) (xy 335.457183 -407.969367)
			(xy 335.473548 -407.941018) (xy 335.476852 -407.934988) (xy 335.480465 -407.921729) (xy 335.48066 -407.914856)
			(xy 335.48066 -407.628852) (xy 335.481145 -407.618745) (xy 335.488891 -407.600074) (xy 335.503187 -407.585782)
			(xy 335.521861 -407.578042) (xy 335.531968 -407.577544) (xy 336.248248 -407.577544) (xy 336.258353 -407.578045)
			(xy 336.277021 -407.585788) (xy 336.291312 -407.600079) (xy 336.299055 -407.618747) (xy 336.299556 -407.628852)
			(xy 336.299556 -407.914856) (xy 336.299758 -407.921729) (xy 336.303358 -407.934992) (xy 336.306668 -407.941018)
			(xy 336.323038 -407.969365) (xy 336.348839 -408.029525) (xy 336.366328 -408.092605) (xy 336.375187 -408.157463)
			(xy 336.375756 -408.190192) (xy 336.375202 -408.222922) (xy 336.366341 -408.28778) (xy 336.348847 -408.35086)
			(xy 336.323038 -408.411018) (xy 336.306668 -408.439366) (xy 336.303363 -408.445395) (xy 336.299752 -408.458656)
			(xy 336.299556 -408.465528) (xy 336.299556 -409.214828) (xy 336.29973 -409.221703) (xy 336.30335 -409.234966)
			(xy 336.306668 -409.24099) (xy 336.323027 -409.269343) (xy 336.348831 -409.329501) (xy 336.366323 -409.392579)
			(xy 336.375185 -409.457435) (xy 336.375756 -409.490164) (xy 336.375189 -409.522893) (xy 336.366332 -409.587751)
			(xy 336.348842 -409.650831) (xy 336.323036 -409.71099) (xy 336.306668 -409.739338) (xy 336.303338 -409.745355)
			(xy 336.299742 -409.758625) (xy 336.299556 -409.7655) (xy 336.299556 -410.051504) (xy 336.299019 -410.061606)
			(xy 336.291291 -410.080274) (xy 336.277011 -410.094566) (xy 336.25835 -410.102311) (xy 336.248248 -410.102812)
			(xy 335.531968 -410.102812) (xy 335.521859 -410.102341) (xy 335.503182 -410.094595) (xy 335.488889 -410.080294)
			(xy 335.481153 -410.061614) (xy 335.48066 -410.051504) (xy 335.48066 -409.7655) (xy 335.480473 -409.758626)
			(xy 335.476862 -409.745363) (xy 335.473548 -409.739338) (xy 335.457202 -409.710978) (xy 335.431394 -409.650823)
			(xy 335.413899 -409.587746) (xy 335.405033 -409.522892) (xy 335.40446 -409.490164) (xy 334.131753 -409.490164)
			(xy 334.122886 -409.510837) (xy 334.10652 -409.539186) (xy 334.103212 -409.545214) (xy 334.099602 -409.558475)
			(xy 334.099408 -409.565348) (xy 334.099408 -410.314648) (xy 334.099619 -410.32152) (xy 334.103214 -410.334783)
			(xy 334.10652 -410.34081) (xy 334.122891 -410.369156) (xy 334.148691 -410.429317) (xy 334.166179 -410.492397)
			(xy 334.175038 -410.557255) (xy 334.175608 -410.589984) (xy 334.175057 -410.622705) (xy 337.604954 -410.622705)
			(xy 337.604956 -410.557268) (xy 337.613741 -410.492423) (xy 337.631149 -410.429344) (xy 337.656866 -410.369172)
			(xy 337.673188 -410.34081) (xy 337.676498 -410.334783) (xy 337.680107 -410.321521) (xy 337.6803 -410.314648)
			(xy 337.6803 -409.565348) (xy 337.68009 -409.558476) (xy 337.676494 -409.545213) (xy 337.673188 -409.539186)
			(xy 337.656878 -409.510819) (xy 337.631162 -409.450648) (xy 337.613754 -409.387571) (xy 337.60497 -409.322728)
			(xy 337.604969 -409.257293) (xy 337.61375 -409.192449) (xy 337.631155 -409.129371) (xy 337.656868 -409.0692)
			(xy 337.673188 -409.040838) (xy 337.676488 -409.034806) (xy 337.680103 -409.021548) (xy 337.6803 -409.014676)
			(xy 337.6803 -408.728672) (xy 337.680699 -408.718516) (xy 337.688503 -408.699763) (xy 337.702907 -408.685441)
			(xy 337.721704 -408.677742) (xy 337.731862 -408.677364) (xy 338.448142 -408.677364) (xy 338.458274 -408.677793)
			(xy 338.477001 -408.685539) (xy 338.491357 -408.699843) (xy 338.49917 -408.718542) (xy 338.499704 -408.728672)
			(xy 338.499704 -409.014676) (xy 338.499905 -409.021549) (xy 338.503507 -409.034811) (xy 338.506816 -409.040838)
			(xy 338.52315 -409.069193) (xy 338.548869 -409.129365) (xy 338.566277 -409.192445) (xy 338.575061 -409.257291)
			(xy 338.575059 -409.322729) (xy 338.566273 -409.387575) (xy 338.548862 -409.450654) (xy 338.52314 -409.510825)
			(xy 338.516196 -409.522889) (xy 339.805084 -409.522889) (xy 339.805089 -409.45745) (xy 339.813877 -409.392603)
			(xy 339.831289 -409.329523) (xy 339.857011 -409.269351) (xy 339.873336 -409.24099) (xy 339.876649 -409.234965)
			(xy 339.880257 -409.221702) (xy 339.880448 -409.214828) (xy 339.880448 -408.465528) (xy 339.880252 -408.458655)
			(xy 339.876647 -408.445392) (xy 339.873336 -408.439366) (xy 339.857007 -408.411008) (xy 339.83129 -408.350836)
			(xy 339.813883 -408.287757) (xy 339.8051 -408.222912) (xy 339.805101 -408.157475) (xy 339.813886 -408.09263)
			(xy 339.831295 -408.029551) (xy 339.857013 -407.969379) (xy 339.873336 -407.941018) (xy 339.876639 -407.934988)
			(xy 339.880253 -407.921728) (xy 339.880448 -407.914856) (xy 339.880448 -407.628852) (xy 339.880881 -407.618701)
			(xy 339.888683 -407.599958) (xy 339.903075 -407.585638) (xy 339.921857 -407.577931) (xy 339.93201 -407.577544)
			(xy 340.64829 -407.577544) (xy 340.658417 -407.578035) (xy 340.677138 -407.58576) (xy 340.691495 -407.600045)
			(xy 340.699314 -407.618728) (xy 340.699852 -407.628852) (xy 340.699852 -407.914856) (xy 340.700054 -407.921729)
			(xy 340.703655 -407.934992) (xy 340.706964 -407.941018) (xy 340.723279 -407.969383) (xy 340.748997 -408.029553)
			(xy 340.766406 -408.092631) (xy 340.775191 -408.157475) (xy 340.775191 -408.222911) (xy 340.766409 -408.287755)
			(xy 340.749002 -408.350834) (xy 340.723286 -408.411005) (xy 340.706964 -408.439366) (xy 340.703666 -408.445399)
			(xy 340.700049 -408.458656) (xy 340.699852 -408.465528) (xy 340.699852 -409.214828) (xy 340.700027 -409.221703)
			(xy 340.703646 -409.234966) (xy 340.706964 -409.24099) (xy 340.723256 -409.269368) (xy 340.748976 -409.329535)
			(xy 340.766387 -409.392611) (xy 340.775175 -409.457452) (xy 340.775179 -409.522886) (xy 340.7664 -409.587729)
			(xy 340.748996 -409.650806) (xy 340.723284 -409.710977) (xy 340.706964 -409.739338) (xy 340.703641 -409.745359)
			(xy 340.70004 -409.758625) (xy 340.699852 -409.7655) (xy 340.699852 -410.051504) (xy 340.699383 -410.061652)
			(xy 340.691595 -410.080394) (xy 340.677214 -410.094716) (xy 340.65844 -410.102424) (xy 340.64829 -410.102812)
			(xy 339.93201 -410.102812) (xy 339.92189 -410.102267) (xy 339.903179 -410.094552) (xy 339.888824 -410.080284)
			(xy 339.880996 -410.061621) (xy 339.880448 -410.051504) (xy 339.880448 -409.7655) (xy 339.880263 -409.758626)
			(xy 339.876651 -409.745363) (xy 339.873336 -409.739338) (xy 339.856983 -409.710994) (xy 339.831269 -409.650818)
			(xy 339.813864 -409.587736) (xy 339.805084 -409.522889) (xy 338.516196 -409.522889) (xy 338.506816 -409.539186)
			(xy 338.503507 -409.545214) (xy 338.499898 -409.558475) (xy 338.499704 -409.565348) (xy 338.499704 -410.314648)
			(xy 338.499915 -410.32152) (xy 338.50351 -410.334783) (xy 338.506816 -410.34081) (xy 338.523126 -410.369178)
			(xy 338.548847 -410.429347) (xy 338.566259 -410.492425) (xy 338.575045 -410.557268) (xy 338.575045 -410.589984)
			(xy 342.004396 -410.589984) (xy 342.004978 -410.557255) (xy 342.013829 -410.492397) (xy 342.031315 -410.429317)
			(xy 342.057118 -410.369159) (xy 342.073484 -410.34081) (xy 342.076794 -410.334783) (xy 342.080403 -410.321521)
			(xy 342.080596 -410.314648) (xy 342.080596 -409.565348) (xy 342.080386 -409.558476) (xy 342.07679 -409.545213)
			(xy 342.073484 -409.539186) (xy 342.057111 -409.510841) (xy 342.031312 -409.45068) (xy 342.013824 -409.387599)
			(xy 342.004966 -409.322741) (xy 342.004396 -409.290012) (xy 342.004945 -409.257282) (xy 342.013806 -409.192423)
			(xy 342.031301 -409.129343) (xy 342.057113 -409.069185) (xy 342.073484 -409.040838) (xy 342.076784 -409.034806)
			(xy 342.080399 -409.021548) (xy 342.080596 -409.014676) (xy 342.080596 -408.728672) (xy 342.081062 -408.718562)
			(xy 342.088808 -408.699884) (xy 342.103111 -408.68559) (xy 342.121794 -408.677856) (xy 342.131904 -408.677364)
			(xy 342.848184 -408.677364) (xy 342.858287 -408.677897) (xy 342.876958 -408.685623) (xy 342.891252 -408.699905)
			(xy 342.898994 -408.718569) (xy 342.899492 -408.728672) (xy 342.899492 -409.014676) (xy 342.899694 -409.021548)
			(xy 342.903295 -409.034811) (xy 342.906604 -409.040838) (xy 342.922985 -409.069179) (xy 342.948783 -409.129341)
			(xy 342.966268 -409.192423) (xy 342.975124 -409.257282) (xy 342.975692 -409.290012) (xy 342.97511 -409.322741)
			(xy 342.966259 -409.387599) (xy 342.948774 -409.450679) (xy 342.92297 -409.510837) (xy 342.916012 -409.522889)
			(xy 344.204874 -409.522889) (xy 344.204878 -409.45745) (xy 344.213666 -409.392603) (xy 344.231078 -409.329523)
			(xy 344.2568 -409.269351) (xy 344.273124 -409.24099) (xy 344.276444 -409.234968) (xy 344.280046 -409.221702)
			(xy 344.280236 -409.214828) (xy 344.280236 -408.465528) (xy 344.280029 -408.458656) (xy 344.276431 -408.445393)
			(xy 344.273124 -408.439366) (xy 344.256795 -408.411008) (xy 344.231079 -408.350836) (xy 344.213672 -408.287757)
			(xy 344.20489 -408.222912) (xy 344.204891 -408.157475) (xy 344.213675 -408.09263) (xy 344.231084 -408.029551)
			(xy 344.256802 -407.969379) (xy 344.273124 -407.941018) (xy 344.276434 -407.934991) (xy 344.280042 -407.921729)
			(xy 344.280236 -407.914856) (xy 344.280236 -407.628852) (xy 344.280583 -407.61869) (xy 344.288401 -407.59993)
			(xy 344.302821 -407.585607) (xy 344.321634 -407.577916) (xy 344.331798 -407.577544) (xy 345.048078 -407.577544)
			(xy 345.058204 -407.578045) (xy 345.076925 -407.585766) (xy 345.091283 -407.600048) (xy 345.099102 -407.618729)
			(xy 345.09964 -407.628852) (xy 345.09964 -407.914856) (xy 345.099844 -407.921728) (xy 345.103443 -407.934991)
			(xy 345.106752 -407.941018) (xy 345.123068 -407.969383) (xy 345.148786 -408.029553) (xy 345.166196 -408.092631)
			(xy 345.17498 -408.157475) (xy 345.17498 -408.190192) (xy 348.603832 -408.190192) (xy 348.607823 -408.128025)
			(xy 348.619732 -408.066878) (xy 348.639361 -408.007757) (xy 348.66639 -407.951631) (xy 348.700374 -407.899422)
			(xy 348.740756 -407.851987) (xy 348.786872 -407.810106) (xy 348.837964 -407.774466) (xy 348.893195 -407.745652)
			(xy 348.951657 -407.724138) (xy 349.012391 -407.710276) (xy 349.074398 -407.704294) (xy 349.136661 -407.70629)
			(xy 349.198158 -407.716233) (xy 349.257879 -407.733957) (xy 349.314842 -407.759174) (xy 349.368113 -407.791467)
			(xy 349.416818 -407.830307) (xy 349.460155 -407.875057) (xy 349.497415 -407.924981) (xy 349.527984 -407.97926)
			(xy 349.551362 -408.037003) (xy 349.567163 -408.097261) (xy 349.575129 -408.159044) (xy 349.575628 -408.190192)
			(xy 349.575129 -408.22134) (xy 349.567163 -408.283123) (xy 349.551362 -408.343381) (xy 349.527984 -408.401124)
			(xy 349.497415 -408.455403) (xy 349.460155 -408.505327) (xy 349.416818 -408.550077) (xy 349.368113 -408.588917)
			(xy 349.314842 -408.62121) (xy 349.257879 -408.646427) (xy 349.198158 -408.664151) (xy 349.136661 -408.674094)
			(xy 349.074398 -408.67609) (xy 349.012391 -408.670108) (xy 348.951657 -408.656246) (xy 348.893195 -408.634732)
			(xy 348.837964 -408.605918) (xy 348.786872 -408.570278) (xy 348.740756 -408.528397) (xy 348.700374 -408.480962)
			(xy 348.66639 -408.428753) (xy 348.639361 -408.372627) (xy 348.619732 -408.313506) (xy 348.607823 -408.252359)
			(xy 348.603832 -408.190192) (xy 345.17498 -408.190192) (xy 345.174981 -408.222911) (xy 345.166198 -408.287755)
			(xy 345.148791 -408.350834) (xy 345.123074 -408.411005) (xy 345.106752 -408.439366) (xy 345.103453 -408.445399)
			(xy 345.099837 -408.458656) (xy 345.09964 -408.465528) (xy 345.09964 -409.214828) (xy 345.099816 -409.221702)
			(xy 345.103435 -409.234965) (xy 345.106752 -409.24099) (xy 345.123044 -409.269368) (xy 345.148765 -409.329535)
			(xy 345.166177 -409.39261) (xy 345.174964 -409.457452) (xy 345.174968 -409.522886) (xy 345.166189 -409.587729)
			(xy 345.148785 -409.650806) (xy 345.123072 -409.710977) (xy 345.106752 -409.739338) (xy 345.103428 -409.745358)
			(xy 345.099828 -409.758625) (xy 345.09964 -409.7655) (xy 345.09964 -410.051504) (xy 345.099182 -410.061653)
			(xy 345.091393 -410.080398) (xy 345.077008 -410.09472) (xy 345.058229 -410.102427) (xy 345.048078 -410.102812)
			(xy 344.331798 -410.102812) (xy 344.321678 -410.102277) (xy 344.302966 -410.094558) (xy 344.288612 -410.080287)
			(xy 344.280784 -410.061621) (xy 344.280236 -410.051504) (xy 344.280236 -409.7655) (xy 344.28004 -409.758627)
			(xy 344.276434 -409.745365) (xy 344.273124 -409.739338) (xy 344.256772 -409.710993) (xy 344.231058 -409.650818)
			(xy 344.213654 -409.587736) (xy 344.204874 -409.522889) (xy 342.916012 -409.522889) (xy 342.906604 -409.539186)
			(xy 342.903295 -409.545213) (xy 342.899685 -409.558475) (xy 342.899492 -409.565348) (xy 342.899492 -410.314648)
			(xy 342.899705 -410.32152) (xy 342.903299 -410.334782) (xy 342.906604 -410.34081) (xy 342.922974 -410.369157)
			(xy 342.948775 -410.429317) (xy 342.966263 -410.492397) (xy 342.975122 -410.557255) (xy 342.975692 -410.589984)
			(xy 342.975142 -410.622705) (xy 346.405027 -410.622705) (xy 346.405029 -410.557267) (xy 346.413815 -410.492421)
			(xy 346.431226 -410.429342) (xy 346.456948 -410.369171) (xy 346.473272 -410.34081) (xy 346.476581 -410.334783)
			(xy 346.480191 -410.321521) (xy 346.480384 -410.314648) (xy 346.480384 -409.565348) (xy 346.480176 -409.558476)
			(xy 346.476579 -409.545213) (xy 346.473272 -409.539186) (xy 346.456959 -409.510819) (xy 346.431239 -409.45065)
			(xy 346.413828 -409.387572) (xy 346.405043 -409.322728) (xy 346.405041 -409.257292) (xy 346.413824 -409.192448)
			(xy 346.431232 -409.12937) (xy 346.45695 -409.069199) (xy 346.473272 -409.040838) (xy 346.476571 -409.034806)
			(xy 346.480187 -409.021548) (xy 346.480384 -409.014676) (xy 346.480384 -408.728672) (xy 346.480798 -408.718518)
			(xy 346.4886 -408.699768) (xy 346.502999 -408.685446) (xy 346.52179 -408.677745) (xy 346.531946 -408.677364)
			(xy 347.248226 -408.677364) (xy 347.258357 -408.677806) (xy 347.277084 -408.685547) (xy 347.29144 -408.699847)
			(xy 347.299254 -408.718543) (xy 347.299788 -408.728672) (xy 347.299788 -409.014676) (xy 347.29999 -409.021548)
			(xy 347.303592 -409.034811) (xy 347.3069 -409.040838) (xy 347.323231 -409.069194) (xy 347.348946 -409.129367)
			(xy 347.366351 -409.192447) (xy 347.375133 -409.257292) (xy 347.375132 -409.322729) (xy 347.366347 -409.387574)
			(xy 347.348939 -409.450653) (xy 347.332052 -409.490164) (xy 348.603832 -409.490164) (xy 348.607823 -409.427997)
			(xy 348.619732 -409.36685) (xy 348.639361 -409.307729) (xy 348.66639 -409.251603) (xy 348.700374 -409.199394)
			(xy 348.740756 -409.151959) (xy 348.786872 -409.110078) (xy 348.837964 -409.074438) (xy 348.893195 -409.045624)
			(xy 348.951657 -409.02411) (xy 349.012391 -409.010248) (xy 349.074398 -409.004266) (xy 349.136661 -409.006262)
			(xy 349.198158 -409.016205) (xy 349.257879 -409.033929) (xy 349.314842 -409.059146) (xy 349.368113 -409.091439)
			(xy 349.416818 -409.130279) (xy 349.460155 -409.175029) (xy 349.497415 -409.224953) (xy 349.527984 -409.279232)
			(xy 349.532348 -409.290012) (xy 350.80398 -409.290012) (xy 350.807971 -409.227845) (xy 350.81988 -409.166698)
			(xy 350.839509 -409.107577) (xy 350.866538 -409.051451) (xy 350.900522 -408.999242) (xy 350.940904 -408.951807)
			(xy 350.98702 -408.909926) (xy 351.038112 -408.874286) (xy 351.093343 -408.845472) (xy 351.151805 -408.823958)
			(xy 351.212539 -408.810096) (xy 351.274546 -408.804114) (xy 351.336809 -408.80611) (xy 351.398306 -408.816053)
			(xy 351.458027 -408.833777) (xy 351.51499 -408.858994) (xy 351.568261 -408.891287) (xy 351.616966 -408.930127)
			(xy 351.660303 -408.974877) (xy 351.697563 -409.024801) (xy 351.728132 -409.07908) (xy 351.75151 -409.136823)
			(xy 351.767311 -409.197081) (xy 351.775277 -409.258864) (xy 351.775776 -409.290012) (xy 351.775277 -409.32116)
			(xy 351.767311 -409.382943) (xy 351.75151 -409.443201) (xy 351.728132 -409.500944) (xy 351.715773 -409.522889)
			(xy 375.004909 -409.522889) (xy 375.004913 -409.457449) (xy 375.013701 -409.392603) (xy 375.031115 -409.329523)
			(xy 375.056839 -409.269351) (xy 375.073164 -409.24099) (xy 375.076479 -409.234966) (xy 375.080085 -409.221702)
			(xy 375.080276 -409.214828) (xy 375.080276 -408.465528) (xy 375.080076 -408.458655) (xy 375.076474 -408.445392)
			(xy 375.073164 -408.439366) (xy 375.056834 -408.411009) (xy 375.031116 -408.350837) (xy 375.013708 -408.287757)
			(xy 375.004924 -408.222912) (xy 375.004925 -408.157474) (xy 375.01371 -408.092629) (xy 375.03112 -408.02955)
			(xy 375.05684 -407.969379) (xy 375.073164 -407.941018) (xy 375.076469 -407.934989) (xy 375.080081 -407.921729)
			(xy 375.080276 -407.914856) (xy 375.080276 -407.628852) (xy 375.080682 -407.618698) (xy 375.088489 -407.599949)
			(xy 375.10289 -407.585628) (xy 375.121682 -407.577926) (xy 375.131838 -407.577544) (xy 375.848118 -407.577544)
			(xy 375.858246 -407.578012) (xy 375.876969 -407.585746) (xy 375.891325 -407.600038) (xy 375.899143 -407.618726)
			(xy 375.89968 -407.628852) (xy 375.89968 -407.914856) (xy 375.899891 -407.921728) (xy 375.903486 -407.934991)
			(xy 375.906792 -407.941018) (xy 375.923106 -407.969383) (xy 375.948823 -408.029554) (xy 375.966231 -408.092632)
			(xy 375.975015 -408.157475) (xy 375.975016 -408.222911) (xy 375.966234 -408.287755) (xy 375.948828 -408.350833)
			(xy 375.923113 -408.411004) (xy 375.906792 -408.439366) (xy 375.903489 -408.445396) (xy 375.899876 -408.458656)
			(xy 375.89968 -408.465528) (xy 375.89968 -409.214828) (xy 375.899864 -409.221702) (xy 375.903478 -409.234964)
			(xy 375.906792 -409.24099) (xy 375.923083 -409.269368) (xy 375.948802 -409.329536) (xy 375.966212 -409.392611)
			(xy 375.974999 -409.457452) (xy 375.975003 -409.522886) (xy 375.966224 -409.587728) (xy 375.948822 -409.650806)
			(xy 375.923111 -409.710976) (xy 375.906792 -409.739338) (xy 375.903463 -409.745356) (xy 375.899867 -409.758625)
			(xy 375.89968 -409.7655) (xy 375.89968 -410.051504) (xy 375.899281 -410.061661) (xy 375.891481 -410.080417)
			(xy 375.877077 -410.094741) (xy 375.858277 -410.102437) (xy 375.848118 -410.102812) (xy 375.131838 -410.102812)
			(xy 375.12172 -410.102244) (xy 375.10301 -410.094538) (xy 375.088654 -410.080277) (xy 375.080824 -410.061618)
			(xy 375.080276 -410.051504) (xy 375.080276 -409.7655) (xy 375.080087 -409.758627) (xy 375.076477 -409.745364)
			(xy 375.073164 -409.739338) (xy 375.05681 -409.710994) (xy 375.031094 -409.650819) (xy 375.013689 -409.587737)
			(xy 375.004909 -409.522889) (xy 351.715773 -409.522889) (xy 351.697563 -409.555223) (xy 351.660303 -409.605147)
			(xy 351.616966 -409.649897) (xy 351.568261 -409.688737) (xy 351.51499 -409.72103) (xy 351.458027 -409.746247)
			(xy 351.398306 -409.763971) (xy 351.336809 -409.773914) (xy 351.274546 -409.77591) (xy 351.212539 -409.769928)
			(xy 351.151805 -409.756066) (xy 351.093343 -409.734552) (xy 351.038112 -409.705738) (xy 350.98702 -409.670098)
			(xy 350.940904 -409.628217) (xy 350.900522 -409.580782) (xy 350.866538 -409.528573) (xy 350.839509 -409.472447)
			(xy 350.81988 -409.413326) (xy 350.807971 -409.352179) (xy 350.80398 -409.290012) (xy 349.532348 -409.290012)
			(xy 349.551362 -409.336975) (xy 349.567163 -409.397233) (xy 349.575129 -409.459016) (xy 349.575628 -409.490164)
			(xy 349.575129 -409.521312) (xy 349.567163 -409.583095) (xy 349.551362 -409.643353) (xy 349.527984 -409.701096)
			(xy 349.497415 -409.755375) (xy 349.460155 -409.805299) (xy 349.416818 -409.850049) (xy 349.368113 -409.888889)
			(xy 349.314842 -409.921182) (xy 349.257879 -409.946399) (xy 349.198158 -409.964123) (xy 349.136661 -409.974066)
			(xy 349.074398 -409.976062) (xy 349.012391 -409.97008) (xy 348.951657 -409.956218) (xy 348.893195 -409.934704)
			(xy 348.837964 -409.90589) (xy 348.786872 -409.87025) (xy 348.740756 -409.828369) (xy 348.700374 -409.780934)
			(xy 348.66639 -409.728725) (xy 348.639361 -409.672599) (xy 348.619732 -409.613478) (xy 348.607823 -409.552331)
			(xy 348.603832 -409.490164) (xy 347.332052 -409.490164) (xy 347.323222 -409.510824) (xy 347.3069 -409.539186)
			(xy 347.30359 -409.545213) (xy 347.299981 -409.558475) (xy 347.299788 -409.565348) (xy 347.299788 -410.314648)
			(xy 347.300002 -410.32152) (xy 347.303595 -410.334782) (xy 347.3069 -410.34081) (xy 347.323207 -410.369179)
			(xy 347.348924 -410.429349) (xy 347.366332 -410.492426) (xy 347.375117 -410.557269) (xy 347.375118 -410.589984)
			(xy 350.80398 -410.589984) (xy 350.807971 -410.527817) (xy 350.81988 -410.46667) (xy 350.839509 -410.407549)
			(xy 350.866538 -410.351423) (xy 350.900522 -410.299214) (xy 350.940904 -410.251779) (xy 350.98702 -410.209898)
			(xy 351.038112 -410.174258) (xy 351.093343 -410.145444) (xy 351.151805 -410.12393) (xy 351.212539 -410.110068)
			(xy 351.274546 -410.104086) (xy 351.336809 -410.106082) (xy 351.398306 -410.116025) (xy 351.458027 -410.133749)
			(xy 351.51499 -410.158966) (xy 351.568261 -410.191259) (xy 351.616966 -410.230099) (xy 351.660303 -410.274849)
			(xy 351.697563 -410.324773) (xy 351.728132 -410.379052) (xy 351.75151 -410.436795) (xy 351.767311 -410.497053)
			(xy 351.775277 -410.558836) (xy 351.775776 -410.589984) (xy 377.204224 -410.589984) (xy 377.204802 -410.557255)
			(xy 377.213653 -410.492397) (xy 377.23114 -410.429317) (xy 377.256945 -410.369158) (xy 377.273312 -410.34081)
			(xy 377.276624 -410.334784) (xy 377.280231 -410.321521) (xy 377.280424 -410.314648) (xy 377.280424 -409.565348)
			(xy 377.280211 -409.558476) (xy 377.276617 -409.545214) (xy 377.273312 -409.539186) (xy 377.256942 -409.510839)
			(xy 377.231141 -409.450679) (xy 377.213653 -409.387599) (xy 377.204794 -409.322741) (xy 377.204224 -409.290012)
			(xy 377.20477 -409.257282) (xy 377.213631 -409.192423) (xy 377.231127 -409.129342) (xy 377.256941 -409.069185)
			(xy 377.273312 -409.040838) (xy 377.276614 -409.034807) (xy 377.280227 -409.021548) (xy 377.280424 -409.014676)
			(xy 377.280424 -408.728672) (xy 377.280794 -408.718545) (xy 377.288555 -408.699836) (xy 377.302886 -408.685522)
			(xy 377.321604 -408.677782) (xy 377.331732 -408.677364) (xy 378.048012 -408.677364) (xy 378.058117 -408.677875)
			(xy 378.076789 -408.685609) (xy 378.091082 -408.699898) (xy 378.098822 -408.718567) (xy 378.09932 -408.728672)
			(xy 378.09932 -409.014676) (xy 378.099519 -409.021549) (xy 378.103122 -409.034812) (xy 378.106432 -409.040838)
			(xy 378.122806 -409.069183) (xy 378.148607 -409.129343) (xy 378.166095 -409.192424) (xy 378.174952 -409.257283)
			(xy 378.17552 -409.290012) (xy 378.174934 -409.322741) (xy 378.166084 -409.387598) (xy 378.148599 -409.450678)
			(xy 378.131664 -409.490164) (xy 379.404372 -409.490164) (xy 379.404948 -409.457435) (xy 379.413801 -409.392577)
			(xy 379.431289 -409.329497) (xy 379.457093 -409.269339) (xy 379.47346 -409.24099) (xy 379.476775 -409.234965)
			(xy 379.480381 -409.221702) (xy 379.480572 -409.214828) (xy 379.480572 -408.465528) (xy 379.480373 -408.458655)
			(xy 379.47677 -408.445392) (xy 379.47346 -408.439366) (xy 379.457087 -408.411021) (xy 379.431285 -408.35086)
			(xy 379.413798 -408.287779) (xy 379.40494 -408.222921) (xy 379.404372 -408.190192) (xy 379.404961 -408.157463)
			(xy 379.41381 -408.092606) (xy 379.431294 -408.029526) (xy 379.457095 -407.969367) (xy 379.47346 -407.941018)
			(xy 379.476765 -407.934989) (xy 379.480377 -407.921729) (xy 379.480572 -407.914856) (xy 379.480572 -407.628852)
			(xy 379.481045 -407.618744) (xy 379.488793 -407.60007) (xy 379.503093 -407.585778) (xy 379.521771 -407.57804)
			(xy 379.53188 -407.577544) (xy 380.24816 -407.577544) (xy 380.258259 -407.578117) (xy 380.276926 -407.585831)
			(xy 380.29122 -407.6001) (xy 380.298966 -407.618754) (xy 380.299468 -407.628852) (xy 380.299468 -407.914856)
			(xy 380.299681 -407.921728) (xy 380.303275 -407.93499) (xy 380.30658 -407.941018) (xy 380.322951 -407.969364)
			(xy 380.348752 -408.029525) (xy 380.36624 -408.092605) (xy 380.375099 -408.157463) (xy 380.375668 -408.190192)
			(xy 380.375112 -408.222922) (xy 380.366252 -408.28778) (xy 380.348758 -408.35086) (xy 380.322949 -408.411018)
			(xy 380.30658 -408.439366) (xy 380.303276 -408.445396) (xy 380.299664 -408.458656) (xy 380.299468 -408.465528)
			(xy 380.299468 -409.214828) (xy 380.299653 -409.221702) (xy 380.303267 -409.234964) (xy 380.30658 -409.24099)
			(xy 380.32294 -409.269343) (xy 380.348743 -409.329501) (xy 380.366235 -409.392579) (xy 380.375097 -409.457435)
			(xy 380.375668 -409.490164) (xy 380.375099 -409.522893) (xy 380.366243 -409.587751) (xy 380.348753 -409.650831)
			(xy 380.322948 -409.71099) (xy 380.30658 -409.739338) (xy 380.30325 -409.745355) (xy 380.299654 -409.758625)
			(xy 380.299468 -409.7655) (xy 380.299468 -410.051504) (xy 380.299086 -410.061631) (xy 380.291331 -410.08034)
			(xy 380.277003 -410.094656) (xy 380.258287 -410.102395) (xy 380.24816 -410.102812) (xy 379.53188 -410.102812)
			(xy 379.521771 -410.102332) (xy 379.503095 -410.09459) (xy 379.488801 -410.080292) (xy 379.481065 -410.061613)
			(xy 379.480572 -410.051504) (xy 379.480572 -409.7655) (xy 379.480383 -409.758626) (xy 379.476773 -409.745364)
			(xy 379.47346 -409.739338) (xy 379.457115 -409.710977) (xy 379.431307 -409.650822) (xy 379.413811 -409.587746)
			(xy 379.404945 -409.522892) (xy 379.404372 -409.490164) (xy 378.131664 -409.490164) (xy 378.122798 -409.510837)
			(xy 378.106432 -409.539186) (xy 378.103125 -409.545214) (xy 378.099514 -409.558475) (xy 378.09932 -409.565348)
			(xy 378.09932 -410.314648) (xy 378.099529 -410.32152) (xy 378.103126 -410.334783) (xy 378.106432 -410.34081)
			(xy 378.122795 -410.369161) (xy 378.148599 -410.429319) (xy 378.16609 -410.492398) (xy 378.17495 -410.557255)
			(xy 378.17552 -410.589984) (xy 378.174967 -410.622705) (xy 381.604865 -410.622705) (xy 381.604867 -410.557268)
			(xy 381.613651 -410.492423) (xy 381.63106 -410.429343) (xy 381.656778 -410.369172) (xy 381.6731 -410.34081)
			(xy 381.676411 -410.334784) (xy 381.680019 -410.321521) (xy 381.680212 -410.314648) (xy 381.680212 -409.565348)
			(xy 381.68 -409.558476) (xy 381.676405 -409.545214) (xy 381.6731 -409.539186) (xy 381.656789 -409.510819)
			(xy 381.631073 -409.450649) (xy 381.613665 -409.387571) (xy 381.604881 -409.322728) (xy 381.604879 -409.257293)
			(xy 381.613661 -409.192449) (xy 381.631066 -409.129371) (xy 381.65678 -409.0692) (xy 381.6731 -409.040838)
			(xy 381.676401 -409.034807) (xy 381.680015 -409.021548) (xy 381.680212 -409.014676) (xy 381.680212 -408.728672)
			(xy 381.680599 -408.718515) (xy 381.688406 -408.699759) (xy 381.702813 -408.685436) (xy 381.721614 -408.67774)
			(xy 381.731774 -408.677364) (xy 382.448054 -408.677364) (xy 382.458181 -408.677865) (xy 382.476905 -408.685582)
			(xy 382.491264 -408.699865) (xy 382.499081 -408.718548) (xy 382.499616 -408.728672) (xy 382.499616 -409.014676)
			(xy 382.499815 -409.021549) (xy 382.503418 -409.034812) (xy 382.506728 -409.040838) (xy 382.523061 -409.069193)
			(xy 382.54878 -409.129365) (xy 382.566188 -409.192445) (xy 382.574971 -409.257291) (xy 382.57497 -409.322729)
			(xy 382.566184 -409.387575) (xy 382.548773 -409.450654) (xy 382.523052 -409.510825) (xy 382.516108 -409.522889)
			(xy 383.804995 -409.522889) (xy 383.804999 -409.457449) (xy 383.813787 -409.392603) (xy 383.8312 -409.329523)
			(xy 383.856923 -409.269351) (xy 383.873248 -409.24099) (xy 383.876562 -409.234965) (xy 383.880169 -409.221702)
			(xy 383.88036 -409.214828) (xy 383.88036 -408.465528) (xy 383.880162 -408.458655) (xy 383.876559 -408.445392)
			(xy 383.873248 -408.439366) (xy 383.856919 -408.411009) (xy 383.831201 -408.350837) (xy 383.813794 -408.287757)
			(xy 383.805011 -408.222912) (xy 383.805012 -408.157474) (xy 383.813796 -408.092629) (xy 383.831206 -408.02955)
			(xy 383.856925 -407.969379) (xy 383.873248 -407.941018) (xy 383.876552 -407.934988) (xy 383.880165 -407.921729)
			(xy 383.88036 -407.914856) (xy 383.88036 -407.628852) (xy 383.880782 -407.6187) (xy 383.888586 -407.599954)
			(xy 383.902981 -407.585634) (xy 383.921768 -407.577929) (xy 383.931922 -407.577544) (xy 384.648202 -407.577544)
			(xy 384.658329 -407.578025) (xy 384.677051 -407.585754) (xy 384.691408 -407.600042) (xy 384.699226 -407.618727)
			(xy 384.699764 -407.628852) (xy 384.699764 -407.914856) (xy 384.699977 -407.921728) (xy 384.703571 -407.93499)
			(xy 384.706876 -407.941018) (xy 384.723191 -407.969383) (xy 384.748908 -408.029554) (xy 384.766317 -408.092631)
			(xy 384.775101 -408.157475) (xy 384.775102 -408.222911) (xy 384.76632 -408.287755) (xy 384.748913 -408.350833)
			(xy 384.723197 -408.411005) (xy 384.706876 -408.439366) (xy 384.703572 -408.445396) (xy 384.69996 -408.458656)
			(xy 384.699764 -408.465528) (xy 384.699764 -409.214828) (xy 384.69995 -409.221702) (xy 384.703563 -409.234964)
			(xy 384.706876 -409.24099) (xy 384.723167 -409.269368) (xy 384.748887 -409.329536) (xy 384.766298 -409.392611)
			(xy 384.775085 -409.457452) (xy 384.775089 -409.522886) (xy 384.76631 -409.587729) (xy 384.748907 -409.650806)
			(xy 384.723195 -409.710977) (xy 384.706876 -409.739338) (xy 384.703546 -409.745355) (xy 384.69995 -409.758625)
			(xy 384.699764 -409.7655) (xy 384.699764 -410.051504) (xy 384.699381 -410.061663) (xy 384.691577 -410.080422)
			(xy 384.677168 -410.094747) (xy 384.658363 -410.10244) (xy 384.648202 -410.102812) (xy 383.931922 -410.102812)
			(xy 383.921803 -410.102257) (xy 383.903092 -410.094546) (xy 383.888737 -410.080281) (xy 383.880908 -410.06162)
			(xy 383.88036 -410.051504) (xy 383.88036 -409.7655) (xy 383.880173 -409.758626) (xy 383.876562 -409.745363)
			(xy 383.873248 -409.739338) (xy 383.856895 -409.710994) (xy 383.83118 -409.650819) (xy 383.813775 -409.587736)
			(xy 383.804995 -409.522889) (xy 382.516108 -409.522889) (xy 382.506728 -409.539186) (xy 382.50342 -409.545214)
			(xy 382.49981 -409.558475) (xy 382.499616 -409.565348) (xy 382.499616 -410.314648) (xy 382.499826 -410.32152)
			(xy 382.503422 -410.334783) (xy 382.506728 -410.34081) (xy 382.523038 -410.369178) (xy 382.548758 -410.429348)
			(xy 382.566169 -410.492425) (xy 382.574955 -410.557268) (xy 382.574956 -410.589984) (xy 386.004308 -410.589984)
			(xy 386.004888 -410.557255) (xy 386.013739 -410.492397) (xy 386.031225 -410.429317) (xy 386.057029 -410.369158)
			(xy 386.073396 -410.34081) (xy 386.076707 -410.334783) (xy 386.080315 -410.321521) (xy 386.080508 -410.314648)
			(xy 386.080508 -409.565348) (xy 386.080296 -409.558476) (xy 386.076701 -409.545214) (xy 386.073396 -409.539186)
			(xy 386.057024 -409.51084) (xy 386.031224 -409.450679) (xy 386.013736 -409.387599) (xy 386.004878 -409.322741)
			(xy 386.004308 -409.290012) (xy 386.004856 -409.257282) (xy 386.013717 -409.192423) (xy 386.031212 -409.129343)
			(xy 386.057025 -409.069185) (xy 386.073396 -409.040838) (xy 386.076697 -409.034807) (xy 386.080311 -409.021548)
			(xy 386.080508 -409.014676) (xy 386.080508 -408.728672) (xy 386.080962 -408.71856) (xy 386.088711 -408.69988)
			(xy 386.103017 -408.685586) (xy 386.121704 -408.677854) (xy 386.131816 -408.677364) (xy 386.848096 -408.677364)
			(xy 386.8582 -408.677888) (xy 386.876871 -408.685617) (xy 386.891165 -408.699902) (xy 386.898906 -408.718568)
			(xy 386.899404 -408.728672) (xy 386.899404 -409.014676) (xy 386.899605 -409.021549) (xy 386.903207 -409.034811)
			(xy 386.906516 -409.040838) (xy 386.922898 -409.069178) (xy 386.948696 -409.129341) (xy 386.966181 -409.192423)
			(xy 386.975036 -409.257282) (xy 386.975604 -409.290012) (xy 386.975021 -409.322741) (xy 386.96617 -409.387598)
			(xy 386.948685 -409.450679) (xy 386.922882 -409.510837) (xy 386.915924 -409.522889) (xy 388.204784 -409.522889)
			(xy 388.204789 -409.45745) (xy 388.213577 -409.392603) (xy 388.230989 -409.329523) (xy 388.256711 -409.269351)
			(xy 388.273036 -409.24099) (xy 388.276349 -409.234965) (xy 388.279957 -409.221702) (xy 388.280148 -409.214828)
			(xy 388.280148 -408.465528) (xy 388.279952 -408.458655) (xy 388.276347 -408.445392) (xy 388.273036 -408.439366)
			(xy 388.256707 -408.411008) (xy 388.23099 -408.350836) (xy 388.213583 -408.287757) (xy 388.2048 -408.222912)
			(xy 388.204801 -408.157475) (xy 388.213586 -408.09263) (xy 388.230995 -408.029551) (xy 388.256713 -407.969379)
			(xy 388.273036 -407.941018) (xy 388.276339 -407.934988) (xy 388.279953 -407.921728) (xy 388.280148 -407.914856)
			(xy 388.280148 -407.628852) (xy 388.280581 -407.618701) (xy 388.288383 -407.599958) (xy 388.302775 -407.585638)
			(xy 388.321557 -407.577931) (xy 388.33171 -407.577544) (xy 389.04799 -407.577544) (xy 389.058117 -407.578035)
			(xy 389.076838 -407.58576) (xy 389.091195 -407.600045) (xy 389.099014 -407.618728) (xy 389.099552 -407.628852)
			(xy 389.099552 -407.914856) (xy 389.099754 -407.921729) (xy 389.103355 -407.934992) (xy 389.106664 -407.941018)
			(xy 389.122979 -407.969383) (xy 389.148697 -408.029553) (xy 389.166106 -408.092631) (xy 389.174891 -408.157475)
			(xy 389.174891 -408.222911) (xy 389.166109 -408.287755) (xy 389.148702 -408.350834) (xy 389.122986 -408.411005)
			(xy 389.106664 -408.439366) (xy 389.103366 -408.445399) (xy 389.099749 -408.458656) (xy 389.099552 -408.465528)
			(xy 389.099552 -409.214828) (xy 389.099727 -409.221703) (xy 389.103346 -409.234966) (xy 389.106664 -409.24099)
			(xy 389.122956 -409.269368) (xy 389.148676 -409.329535) (xy 389.166087 -409.392611) (xy 389.174875 -409.457452)
			(xy 389.174879 -409.522886) (xy 389.1661 -409.587729) (xy 389.148696 -409.650806) (xy 389.122984 -409.710977)
			(xy 389.106664 -409.739338) (xy 389.103341 -409.745359) (xy 389.09974 -409.758625) (xy 389.099552 -409.7655)
			(xy 389.099552 -410.051504) (xy 389.099083 -410.061652) (xy 389.091295 -410.080394) (xy 389.076914 -410.094716)
			(xy 389.05814 -410.102424) (xy 389.04799 -410.102812) (xy 388.33171 -410.102812) (xy 388.32159 -410.102267)
			(xy 388.302879 -410.094552) (xy 388.288524 -410.080284) (xy 388.280696 -410.061621) (xy 388.280148 -410.051504)
			(xy 388.280148 -409.7655) (xy 388.279963 -409.758626) (xy 388.276351 -409.745363) (xy 388.273036 -409.739338)
			(xy 388.256683 -409.710994) (xy 388.230969 -409.650818) (xy 388.213564 -409.587736) (xy 388.204784 -409.522889)
			(xy 386.915924 -409.522889) (xy 386.906516 -409.539186) (xy 386.903207 -409.545214) (xy 386.899598 -409.558475)
			(xy 386.899404 -409.565348) (xy 386.899404 -410.314648) (xy 386.899615 -410.32152) (xy 386.90321 -410.334783)
			(xy 386.906516 -410.34081) (xy 386.922887 -410.369156) (xy 386.948687 -410.429317) (xy 386.966175 -410.492397)
			(xy 386.975034 -410.557255) (xy 386.975604 -410.589984) (xy 386.975053 -410.622705) (xy 390.404937 -410.622705)
			(xy 390.404939 -410.557267) (xy 390.413725 -410.492421) (xy 390.431137 -410.429342) (xy 390.456859 -410.369171)
			(xy 390.473184 -410.34081) (xy 390.476494 -410.334783) (xy 390.480103 -410.321521) (xy 390.480296 -410.314648)
			(xy 390.480296 -409.565348) (xy 390.480086 -409.558476) (xy 390.47649 -409.545213) (xy 390.473184 -409.539186)
			(xy 390.456871 -409.51082) (xy 390.43115 -409.45065) (xy 390.413739 -409.387572) (xy 390.404953 -409.322729)
			(xy 390.404952 -409.257292) (xy 390.413735 -409.192448) (xy 390.431143 -409.129369) (xy 390.456861 -409.069199)
			(xy 390.473184 -409.040838) (xy 390.476484 -409.034806) (xy 390.480099 -409.021548) (xy 390.480296 -409.014676)
			(xy 390.480296 -408.728672) (xy 390.480699 -408.718517) (xy 390.488503 -408.699764) (xy 390.502905 -408.685442)
			(xy 390.5217 -408.677743) (xy 390.531858 -408.677364) (xy 391.248138 -408.677364) (xy 391.25827 -408.677796)
			(xy 391.276997 -408.685541) (xy 391.291352 -408.699844) (xy 391.299166 -408.718542) (xy 391.2997 -408.728672)
			(xy 391.2997 -409.014676) (xy 391.299901 -409.021549) (xy 391.303503 -409.034811) (xy 391.306812 -409.040838)
			(xy 391.323143 -409.069194) (xy 391.348857 -409.129367) (xy 391.366262 -409.192447) (xy 391.375043 -409.257292)
			(xy 391.375042 -409.322729) (xy 391.366258 -409.387573) (xy 391.34885 -409.450652) (xy 391.323133 -409.510824)
			(xy 391.306812 -409.539186) (xy 391.303503 -409.545214) (xy 391.299894 -409.558475) (xy 391.2997 -409.565348)
			(xy 391.2997 -410.314648) (xy 391.299912 -410.32152) (xy 391.303507 -410.334782) (xy 391.306812 -410.34081)
			(xy 391.323119 -410.369179) (xy 391.348835 -410.429349) (xy 391.366243 -410.492426) (xy 391.375027 -410.557269)
			(xy 391.375029 -410.622704) (xy 391.366249 -410.687547) (xy 391.348844 -410.750625) (xy 391.323132 -410.810796)
			(xy 391.306812 -410.839158) (xy 391.303513 -410.84519) (xy 391.299897 -410.858448) (xy 391.2997 -410.86532)
			(xy 391.2997 -411.151324) (xy 391.299298 -411.16148) (xy 391.291495 -411.180233) (xy 391.277092 -411.194555)
			(xy 391.258296 -411.202254) (xy 391.248138 -411.202632) (xy 390.531858 -411.202632) (xy 390.521725 -411.202207)
			(xy 390.502998 -411.19446) (xy 390.488642 -411.180155) (xy 390.480829 -411.161455) (xy 390.480296 -411.151324)
			(xy 390.480296 -410.86532) (xy 390.480097 -410.858447) (xy 390.476493 -410.845185) (xy 390.473184 -410.839158)
			(xy 390.456847 -410.810805) (xy 390.431128 -410.750632) (xy 390.41372 -410.687552) (xy 390.404937 -410.622705)
			(xy 386.975053 -410.622705) (xy 386.975053 -410.622714) (xy 386.966193 -410.687573) (xy 386.948698 -410.750653)
			(xy 386.922887 -410.810811) (xy 386.906516 -410.839158) (xy 386.903217 -410.845191) (xy 386.899601 -410.858448)
			(xy 386.899404 -410.86532) (xy 386.899404 -411.151324) (xy 386.898935 -411.161434) (xy 386.89119 -411.180112)
			(xy 386.876888 -411.194406) (xy 386.858206 -411.20214) (xy 386.848096 -411.202632) (xy 386.131816 -411.202632)
			(xy 386.121712 -411.202103) (xy 386.10304 -411.194376) (xy 386.088746 -411.180093) (xy 386.081005 -411.161427)
			(xy 386.080508 -411.151324) (xy 386.080508 -410.86532) (xy 386.080308 -410.858447) (xy 386.076705 -410.845185)
			(xy 386.073396 -410.839158) (xy 386.057013 -410.810818) (xy 386.031216 -410.750655) (xy 386.013731 -410.687573)
			(xy 386.004876 -410.622714) (xy 386.004308 -410.589984) (xy 382.574956 -410.589984) (xy 382.574957 -410.622704)
			(xy 382.566175 -410.687548) (xy 382.548767 -410.750627) (xy 382.52305 -410.810797) (xy 382.506728 -410.839158)
			(xy 382.50343 -410.845191) (xy 382.499813 -410.858448) (xy 382.499616 -410.86532) (xy 382.499616 -411.151324)
			(xy 382.499198 -411.161478) (xy 382.491398 -411.180228) (xy 382.477 -411.19455) (xy 382.45821 -411.202251)
			(xy 382.448054 -411.202632) (xy 381.731774 -411.202632) (xy 381.721642 -411.202194) (xy 381.702915 -411.194453)
			(xy 381.688559 -411.180151) (xy 381.680745 -411.161454) (xy 381.680212 -411.151324) (xy 381.680212 -410.86532)
			(xy 381.680011 -410.858447) (xy 381.676409 -410.845185) (xy 381.6731 -410.839158) (xy 381.656765 -410.810804)
			(xy 381.631051 -410.750631) (xy 381.613646 -410.68755) (xy 381.604865 -410.622705) (xy 378.174967 -410.622705)
			(xy 378.174967 -410.622714) (xy 378.166107 -410.687573) (xy 378.148613 -410.750653) (xy 378.122802 -410.81081)
			(xy 378.106432 -410.839158) (xy 378.103135 -410.845191) (xy 378.099518 -410.858448) (xy 378.09932 -410.86532)
			(xy 378.09932 -411.151324) (xy 378.098835 -411.161432) (xy 378.091093 -411.180107) (xy 378.076797 -411.1944)
			(xy 378.05812 -411.202138) (xy 378.048012 -411.202632) (xy 377.331732 -411.202632) (xy 377.321615 -411.202159)
			(xy 377.302919 -411.194427) (xy 377.288604 -411.180128) (xy 377.280852 -411.16144) (xy 377.280424 -411.151324)
			(xy 377.280424 -410.86532) (xy 377.280221 -410.858448) (xy 377.27662 -410.845185) (xy 377.273312 -410.839158)
			(xy 377.256931 -410.810817) (xy 377.231132 -410.750655) (xy 377.213647 -410.687573) (xy 377.204792 -410.622714)
			(xy 377.204224 -410.589984) (xy 351.775776 -410.589984) (xy 351.775277 -410.621132) (xy 351.767311 -410.682915)
			(xy 351.75151 -410.743173) (xy 351.728132 -410.800916) (xy 351.697563 -410.855195) (xy 351.660303 -410.905119)
			(xy 351.616966 -410.949869) (xy 351.568261 -410.988709) (xy 351.51499 -411.021002) (xy 351.458027 -411.046219)
			(xy 351.398306 -411.063943) (xy 351.336809 -411.073886) (xy 351.274546 -411.075882) (xy 351.212539 -411.0699)
			(xy 351.151805 -411.056038) (xy 351.093343 -411.034524) (xy 351.038112 -411.00571) (xy 350.98702 -410.97007)
			(xy 350.940904 -410.928189) (xy 350.900522 -410.880754) (xy 350.866538 -410.828545) (xy 350.839509 -410.772419)
			(xy 350.81988 -410.713298) (xy 350.807971 -410.652151) (xy 350.80398 -410.589984) (xy 347.375118 -410.589984)
			(xy 347.375119 -410.622704) (xy 347.366338 -410.687547) (xy 347.348933 -410.750625) (xy 347.32322 -410.810796)
			(xy 347.3069 -410.839158) (xy 347.3036 -410.84519) (xy 347.299985 -410.858448) (xy 347.299788 -410.86532)
			(xy 347.299788 -411.151324) (xy 347.299398 -411.161481) (xy 347.291592 -411.180236) (xy 347.277186 -411.194559)
			(xy 347.258386 -411.202256) (xy 347.248226 -411.202632) (xy 346.531946 -411.202632) (xy 346.521819 -411.202135)
			(xy 346.503093 -411.194417) (xy 346.488735 -411.180133) (xy 346.480919 -411.161449) (xy 346.480384 -411.151324)
			(xy 346.480384 -410.86532) (xy 346.480186 -410.858447) (xy 346.476582 -410.845184) (xy 346.473272 -410.839158)
			(xy 346.456935 -410.810805) (xy 346.431217 -410.750632) (xy 346.413809 -410.687552) (xy 346.405027 -410.622705)
			(xy 342.975142 -410.622705) (xy 342.975142 -410.622714) (xy 342.966282 -410.687573) (xy 342.948787 -410.750653)
			(xy 342.922975 -410.81081) (xy 342.906604 -410.839158) (xy 342.903304 -410.84519) (xy 342.899689 -410.858448)
			(xy 342.899492 -410.86532) (xy 342.899492 -411.151324) (xy 342.899034 -411.161435) (xy 342.891287 -411.180116)
			(xy 342.876982 -411.19441) (xy 342.858296 -411.202142) (xy 342.848184 -411.202632) (xy 342.131904 -411.202632)
			(xy 342.121799 -411.202112) (xy 342.103128 -411.194382) (xy 342.088834 -411.180096) (xy 342.081093 -411.161428)
			(xy 342.080596 -411.151324) (xy 342.080596 -410.86532) (xy 342.080397 -410.858447) (xy 342.076793 -410.845185)
			(xy 342.073484 -410.839158) (xy 342.0571 -410.810819) (xy 342.031303 -410.750656) (xy 342.013819 -410.687573)
			(xy 342.004964 -410.622714) (xy 342.004396 -410.589984) (xy 338.575045 -410.589984) (xy 338.575046 -410.622704)
			(xy 338.566264 -410.687549) (xy 338.548856 -410.750627) (xy 338.523139 -410.810797) (xy 338.506816 -410.839158)
			(xy 338.503517 -410.845191) (xy 338.499901 -410.858448) (xy 338.499704 -410.86532) (xy 338.499704 -411.151324)
			(xy 338.499298 -411.161479) (xy 338.491495 -411.180231) (xy 338.477094 -411.194554) (xy 338.458299 -411.202253)
			(xy 338.448142 -411.202632) (xy 337.731862 -411.202632) (xy 337.721729 -411.202204) (xy 337.703002 -411.194458)
			(xy 337.688646 -411.180154) (xy 337.680833 -411.161455) (xy 337.6803 -411.151324) (xy 337.6803 -410.86532)
			(xy 337.6801 -410.858447) (xy 337.676497 -410.845185) (xy 337.673188 -410.839158) (xy 337.656854 -410.810804)
			(xy 337.63114 -410.75063) (xy 337.613735 -410.68755) (xy 337.604954 -410.622705) (xy 334.175057 -410.622705)
			(xy 334.175057 -410.622714) (xy 334.166196 -410.687573) (xy 334.148702 -410.750653) (xy 334.122891 -410.810811)
			(xy 334.10652 -410.839158) (xy 334.103222 -410.845191) (xy 334.099605 -410.858448) (xy 334.099408 -410.86532)
			(xy 334.099408 -411.151324) (xy 334.098935 -411.161433) (xy 334.091191 -411.180111) (xy 334.07689 -411.194404)
			(xy 334.05821 -411.20214) (xy 334.0481 -411.202632) (xy 333.33182 -411.202632) (xy 333.321716 -411.202099)
			(xy 333.303045 -411.194374) (xy 333.28875 -411.180092) (xy 333.281009 -411.161427) (xy 333.280512 -411.151324)
			(xy 333.280512 -410.86532) (xy 333.280311 -410.858447) (xy 333.276709 -410.845185) (xy 333.2734 -410.839158)
			(xy 333.257018 -410.810818) (xy 333.23122 -410.750655) (xy 333.213735 -410.687573) (xy 333.20488 -410.622714)
			(xy 333.204312 -410.589984) (xy 330.459164 -410.589984) (xy 331.458824 -411.589474) (xy 331.466101 -411.596153)
			(xy 331.484271 -411.603855) (xy 331.49413 -411.60446) (xy 331.494384 -411.60446) (xy 331.525998 -411.605199)
			(xy 331.588625 -411.613972) (xy 331.649583 -411.630799) (xy 331.707842 -411.655394) (xy 331.762417 -411.687343)
			(xy 331.812383 -411.726104) (xy 331.856897 -411.771022) (xy 331.895205 -411.821337) (xy 331.926658 -411.876198)
			(xy 331.950726 -411.934677) (xy 331.967 -411.995785) (xy 331.975206 -412.058489) (xy 331.975714 -412.090108)
			(xy 331.975714 -412.090616) (xy 331.975286 -412.119735) (xy 331.968301 -412.177553) (xy 331.954446 -412.234118)
			(xy 331.93392 -412.288619) (xy 331.92085 -412.314644) (xy 331.9145 -412.326582) (xy 331.915262 -412.352998)
			(xy 331.967586 -412.438596) (xy 331.972405 -412.445794) (xy 331.985825 -412.456727) (xy 332.002114 -412.462582)
			(xy 332.010766 -412.46298) (xy 335.026762 -412.46298) (xy 335.03683 -412.46254) (xy 335.055428 -412.45483)
			(xy 335.06283 -412.447994) (xy 335.389474 -412.12135) (xy 335.396121 -412.114048) (xy 335.403842 -412.095897)
			(xy 335.40446 -412.086044) (xy 335.40446 -412.08579) (xy 335.405268 -412.054179) (xy 335.414032 -411.991554)
			(xy 335.430849 -411.930597) (xy 335.455437 -411.872338) (xy 335.487378 -411.817763) (xy 335.526132 -411.767796)
			(xy 335.571044 -411.723281) (xy 335.621354 -411.684972) (xy 335.676211 -411.653518) (xy 335.734686 -411.629449)
			(xy 335.795791 -411.613174) (xy 335.858491 -411.604968) (xy 335.890108 -411.60446) (xy 335.921905 -411.604964)
			(xy 335.984956 -411.613266) (xy 336.046384 -411.629727) (xy 336.105138 -411.654065) (xy 336.160212 -411.685863)
			(xy 336.210665 -411.724578) (xy 336.255633 -411.769547) (xy 336.294346 -411.820001) (xy 336.326142 -411.875077)
			(xy 336.350478 -411.933831) (xy 336.366937 -411.995259) (xy 336.375237 -412.05831) (xy 336.375756 -412.090108)
			(xy 336.375267 -412.121726) (xy 336.367058 -412.184428) (xy 336.350781 -412.245534) (xy 336.326711 -412.304011)
			(xy 336.295255 -412.358869) (xy 336.256945 -412.40918) (xy 336.212429 -412.454093) (xy 336.16246 -412.492849)
			(xy 336.107884 -412.524792) (xy 336.049624 -412.549381) (xy 335.988665 -412.566201) (xy 335.926039 -412.574966)
			(xy 335.894426 -412.575756) (xy 335.894172 -412.575756) (xy 335.884313 -412.576368) (xy 335.866145 -412.584067)
			(xy 335.858866 -412.590742) (xy 335.521046 -412.928562) (xy 335.515204 -412.958534) (xy 335.521046 -412.972758)
			(xy 335.525349 -412.981796) (xy 335.539548 -412.995881) (xy 335.558037 -413.00351) (xy 335.568036 -413.004)
			(xy 338.885784 -413.004) (xy 338.895856 -413.003593) (xy 338.914455 -412.995862) (xy 338.921852 -412.989014)
			(xy 339.789516 -412.12135) (xy 339.796169 -412.114053) (xy 339.803885 -412.095898) (xy 339.804502 -412.086044)
			(xy 339.804502 -412.08579) (xy 339.805368 -412.054181) (xy 339.81413 -411.991562) (xy 339.830945 -411.930608)
			(xy 339.855529 -411.872353) (xy 339.887466 -411.817781) (xy 339.926215 -411.767816) (xy 339.971121 -411.723302)
			(xy 340.021424 -411.684993) (xy 340.076274 -411.653536) (xy 340.134742 -411.629464) (xy 340.195841 -411.613184)
			(xy 340.258535 -411.604971) (xy 340.29015 -411.60446) (xy 340.321948 -411.604996) (xy 340.385 -411.613291)
			(xy 340.446429 -411.629746) (xy 340.505185 -411.654078) (xy 340.560262 -411.685872) (xy 340.610718 -411.724584)
			(xy 340.655688 -411.769551) (xy 340.694404 -411.820003) (xy 340.726203 -411.875077) (xy 340.750541 -411.933831)
			(xy 340.767001 -411.995259) (xy 340.775301 -412.05831) (xy 340.775798 -412.090108) (xy 340.775366 -412.121729)
			(xy 340.767156 -412.184435) (xy 340.750877 -412.245545) (xy 340.726803 -412.304026) (xy 340.695342 -412.358886)
			(xy 340.657027 -412.409199) (xy 340.612505 -412.454114) (xy 340.56253 -412.492869) (xy 340.507947 -412.52481)
			(xy 340.44968 -412.549396) (xy 340.388715 -412.56621) (xy 340.326083 -412.57497) (xy 340.294468 -412.575756)
			(xy 340.294214 -412.575756) (xy 340.284351 -412.576338) (xy 340.266184 -412.584058) (xy 340.258908 -412.590742)
			(xy 339.491066 -413.358584) (xy 339.48497 -413.388556) (xy 339.491066 -413.40278) (xy 339.495319 -413.411888)
			(xy 339.509479 -413.426125) (xy 339.528016 -413.433843) (xy 339.538056 -413.434276) (xy 342.85555 -413.434276)
			(xy 342.865617 -413.433831) (xy 342.884215 -413.426125) (xy 342.891618 -413.41929) (xy 344.189304 -412.12135)
			(xy 344.195955 -412.114052) (xy 344.203673 -412.095898) (xy 344.20429 -412.086044) (xy 344.20429 -412.08579)
			(xy 344.205168 -412.054182) (xy 344.21393 -411.991563) (xy 344.230744 -411.930611) (xy 344.255327 -411.872356)
			(xy 344.287263 -411.817785) (xy 344.326011 -411.76782) (xy 344.370916 -411.723306) (xy 344.421218 -411.684997)
			(xy 344.476066 -411.65354) (xy 344.534533 -411.629467) (xy 344.59563 -411.613186) (xy 344.658324 -411.604972)
			(xy 344.689938 -411.60446) (xy 344.721736 -411.604936) (xy 344.784788 -411.613242) (xy 344.846216 -411.629706)
			(xy 344.90497 -411.654047) (xy 344.960044 -411.685849) (xy 345.010497 -411.724566) (xy 345.055464 -411.769538)
			(xy 345.094177 -411.819994) (xy 345.125973 -411.875071) (xy 345.150309 -411.933827) (xy 345.166767 -411.995257)
			(xy 345.175067 -412.05831) (xy 345.175586 -412.090108) (xy 348.603832 -412.090108) (xy 348.607823 -412.027941)
			(xy 348.619732 -411.966794) (xy 348.639361 -411.907673) (xy 348.66639 -411.851547) (xy 348.700374 -411.799338)
			(xy 348.740756 -411.751903) (xy 348.786872 -411.710022) (xy 348.837964 -411.674382) (xy 348.893195 -411.645568)
			(xy 348.951657 -411.624054) (xy 349.012391 -411.610192) (xy 349.074398 -411.60421) (xy 349.136661 -411.606206)
			(xy 349.198158 -411.616149) (xy 349.257879 -411.633873) (xy 349.314842 -411.65909) (xy 349.368113 -411.691383)
			(xy 349.416818 -411.730223) (xy 349.460155 -411.774973) (xy 349.497415 -411.824897) (xy 349.527984 -411.879176)
			(xy 349.551362 -411.936919) (xy 349.567163 -411.997177) (xy 349.575129 -412.05896) (xy 349.575628 -412.090108)
			(xy 375.00383 -412.090108) (xy 375.007821 -412.027941) (xy 375.01973 -411.966794) (xy 375.039359 -411.907673)
			(xy 375.066388 -411.851547) (xy 375.100372 -411.799338) (xy 375.140754 -411.751903) (xy 375.18687 -411.710022)
			(xy 375.237962 -411.674382) (xy 375.293193 -411.645568) (xy 375.351655 -411.624054) (xy 375.412389 -411.610192)
			(xy 375.474396 -411.60421) (xy 375.536659 -411.606206) (xy 375.598156 -411.616149) (xy 375.657877 -411.633873)
			(xy 375.71484 -411.65909) (xy 375.768111 -411.691383) (xy 375.816816 -411.730223) (xy 375.860153 -411.774973)
			(xy 375.897413 -411.824897) (xy 375.927982 -411.879176) (xy 375.95136 -411.936919) (xy 375.967161 -411.997177)
			(xy 375.975127 -412.05896) (xy 375.975626 -412.090108) (xy 375.975127 -412.121256) (xy 375.967161 -412.183039)
			(xy 375.95136 -412.243297) (xy 375.927982 -412.30104) (xy 375.897413 -412.355319) (xy 375.860153 -412.405243)
			(xy 375.816816 -412.449993) (xy 375.768111 -412.488833) (xy 375.71484 -412.521126) (xy 375.657877 -412.546343)
			(xy 375.598156 -412.564067) (xy 375.536659 -412.57401) (xy 375.474396 -412.576006) (xy 375.412389 -412.570024)
			(xy 375.351655 -412.556162) (xy 375.293193 -412.534648) (xy 375.237962 -412.505834) (xy 375.18687 -412.470194)
			(xy 375.140754 -412.428313) (xy 375.100372 -412.380878) (xy 375.066388 -412.328669) (xy 375.039359 -412.272543)
			(xy 375.01973 -412.213422) (xy 375.007821 -412.152275) (xy 375.00383 -412.090108) (xy 349.575628 -412.090108)
			(xy 349.575129 -412.121256) (xy 349.567163 -412.183039) (xy 349.551362 -412.243297) (xy 349.527984 -412.30104)
			(xy 349.497415 -412.355319) (xy 349.460155 -412.405243) (xy 349.416818 -412.449993) (xy 349.368113 -412.488833)
			(xy 349.314842 -412.521126) (xy 349.257879 -412.546343) (xy 349.198158 -412.564067) (xy 349.136661 -412.57401)
			(xy 349.074398 -412.576006) (xy 349.012391 -412.570024) (xy 348.951657 -412.556162) (xy 348.893195 -412.534648)
			(xy 348.837964 -412.505834) (xy 348.786872 -412.470194) (xy 348.740756 -412.428313) (xy 348.700374 -412.380878)
			(xy 348.66639 -412.328669) (xy 348.639361 -412.272543) (xy 348.619732 -412.213422) (xy 348.607823 -412.152275)
			(xy 348.603832 -412.090108) (xy 345.175586 -412.090108) (xy 345.175166 -412.121729) (xy 345.166956 -412.184437)
			(xy 345.150676 -412.245548) (xy 345.126601 -412.304029) (xy 345.09514 -412.35889) (xy 345.056823 -412.409204)
			(xy 345.0123 -412.454118) (xy 344.962323 -412.492873) (xy 344.907739 -412.524813) (xy 344.849471 -412.549399)
			(xy 344.788505 -412.566212) (xy 344.725872 -412.574971) (xy 344.694256 -412.575756) (xy 344.694002 -412.575756)
			(xy 344.684139 -412.576332) (xy 344.665972 -412.584056) (xy 344.658696 -412.590742) (xy 343.248742 -414.000696)
			(xy 343.229967 -414.018724) (xy 343.187851 -414.049305) (xy 343.141476 -414.072933) (xy 343.09198 -414.089028)
			(xy 343.040577 -414.097196) (xy 343.014554 -414.097724) (xy 330.910438 -414.097724) (xy 330.884414 -414.097208)
			(xy 330.83301 -414.089039) (xy 330.783513 -414.072942) (xy 330.737137 -414.049312) (xy 330.695021 -414.018729)
			(xy 330.67625 -414.000696) (xy 328.063352 -411.387798) (xy 328.045342 -411.369007) (xy 328.014761 -411.326894)
			(xy 327.99113 -411.280523) (xy 327.97503 -411.231031) (xy 327.966856 -411.179632) (xy 327.966324 -411.15361)
			(xy 327.966324 -394.750798) (xy 327.96592 -394.740726) (xy 327.958186 -394.722127) (xy 327.951338 -394.71473)
			(xy 326.295766 -393.059158) (xy 326.288377 -393.052305) (xy 326.269769 -393.044594) (xy 326.259698 -393.044172)
			(xy 321.693794 -393.044172) (xy 321.667771 -393.043636) (xy 321.616367 -393.035474) (xy 321.566869 -393.019382)
			(xy 321.520493 -392.995756) (xy 321.478376 -392.965176) (xy 321.459606 -392.947144) (xy 319.525904 -391.013442)
			(xy 319.507876 -390.994667) (xy 319.477295 -390.952551) (xy 319.453667 -390.906176) (xy 319.437572 -390.85668)
			(xy 319.429404 -390.805277) (xy 319.428876 -390.779254) (xy 318.902939 -390.779254) (xy 318.921214 -390.807687)
			(xy 318.943862 -390.857275) (xy 318.959222 -390.909582) (xy 318.966981 -390.963542) (xy 318.966981 -391.018058)
			(xy 318.959222 -391.072018) (xy 318.943862 -391.124325) (xy 318.921214 -391.173913) (xy 318.891738 -391.219773)
			(xy 318.856036 -391.260971) (xy 318.814833 -391.296668) (xy 318.768969 -391.326138) (xy 318.719378 -391.348779)
			(xy 318.667069 -391.364133) (xy 318.613108 -391.371884) (xy 318.58585 -391.372344) (xy 318.555046 -391.371754)
			(xy 318.494244 -391.361821) (xy 318.435831 -391.342239) (xy 318.408304 -391.328402) (xy 318.402779 -391.325689)
			(xy 318.390835 -391.322731) (xy 318.384682 -391.32256) (xy 315.66866 -391.32256) (xy 315.658586 -391.322949)
			(xy 315.639988 -391.330693) (xy 315.632592 -391.337546) (xy 312.575194 -394.395198) (xy 312.568362 -394.402604)
			(xy 312.560638 -394.421199) (xy 312.560208 -394.431266) (xy 312.560208 -410.24937) (xy 312.559714 -410.275457)
			(xy 312.551551 -410.326988) (xy 312.535421 -410.376606) (xy 312.511722 -410.423087) (xy 312.481038 -410.465285)
			(xy 312.462926 -410.484066) (xy 308.438296 -414.508696) (xy 308.419497 -414.526698) (xy 308.377388 -414.557282)
			(xy 308.331019 -414.580915) (xy 308.281528 -414.597017) (xy 308.23013 -414.605192) (xy 308.204108 -414.605724)
			(xy 289.673284 -414.605724) (xy 289.647261 -414.605179) (xy 289.595859 -414.597017) (xy 289.546362 -414.580927)
			(xy 289.499985 -414.557303) (xy 289.457868 -414.526726) (xy 289.439096 -414.508696) (xy 287.521142 -412.590742)
			(xy 287.513841 -412.584094) (xy 287.49569 -412.576373) (xy 287.485836 -412.575756) (xy 287.485582 -412.575756)
			(xy 287.453971 -412.57494) (xy 287.391348 -412.566175) (xy 287.330391 -412.549357) (xy 287.272133 -412.52477)
			(xy 287.217559 -412.492829) (xy 287.167593 -412.454076) (xy 287.123078 -412.409165) (xy 287.08477 -412.358856)
			(xy 287.053315 -412.304001) (xy 287.029245 -412.245527) (xy 287.012969 -412.184424) (xy 287.004761 -412.121725)
			(xy 287.004252 -412.090108) (xy 282.775152 -412.090108) (xy 282.775152 -415.98723) (xy 282.776168 -415.996628)
			(xy 282.776168 -415.997136) (xy 282.777878 -416.004292) (xy 282.784717 -416.017312) (xy 282.78963 -416.02279)
			(xy 283.261816 -416.494976) (xy 283.267248 -416.499954) (xy 283.280287 -416.506798) (xy 283.28747 -416.508438)
			(xy 283.287978 -416.508438) (xy 283.297376 -416.509454) (xy 307.686964 -416.509454)
		)
		(stroke
			(width 0)
			(type solid)
		)
		(fill yes)
		(layer "In9.Cu")
		(net "GND")
	)
	(gr_poly
		(pts
			(xy 92.982542 -333.186786) (xy 92.992609 -333.186355) (xy 93.011201 -333.178628) (xy 93.01861 -333.1718)
			(xy 93.025722 -333.164688) (xy 93.068394 -333.099156) (xy 93.073474 -333.08925) (xy 93.076268 -333.077566)
			(xy 93.076776 -333.071216) (xy 93.076776 -333.05623) (xy 93.073474 -333.040228) (xy 93.071442 -333.032862)
			(xy 93.070426 -333.030322) (xy 93.061817 -333.00774) (xy 93.049719 -332.960951) (xy 93.043625 -332.913008)
			(xy 93.043248 -332.888844) (xy 93.043709 -332.861552) (xy 93.051471 -332.807522) (xy 93.066843 -332.755148)
			(xy 93.089513 -332.705494) (xy 93.119018 -332.659571) (xy 93.154759 -332.618315) (xy 93.196007 -332.582566)
			(xy 93.241923 -332.553051) (xy 93.291572 -332.530371) (xy 93.343944 -332.514988) (xy 93.397972 -332.507214)
			(xy 93.425264 -332.506828) (xy 93.454592 -332.507361) (xy 93.512558 -332.516327) (xy 93.568471 -332.534054)
			(xy 93.621015 -332.560123) (xy 93.668953 -332.593923) (xy 93.711157 -332.634657) (xy 93.729302 -332.657704)
			(xy 93.734887 -332.664568) (xy 93.749713 -332.674208) (xy 93.758258 -332.6765) (xy 93.787976 -332.683358)
			(xy 93.796741 -332.685037) (xy 93.81444 -332.68283) (xy 93.82252 -332.67904) (xy 93.846832 -332.667049)
			(xy 93.897668 -332.648225) (xy 93.950371 -332.635532) (xy 94.004203 -332.629147) (xy 94.031308 -332.628748)
			(xy 94.060523 -332.629201) (xy 94.118483 -332.636592) (xy 94.146878 -332.64348) (xy 94.160086 -332.646782)
			(xy 94.185994 -332.639924) (xy 94.927928 -331.89799) (xy 94.934781 -331.890594) (xy 94.942523 -331.871996)
			(xy 94.942914 -331.861922) (xy 94.942914 -329.943206) (xy 94.943336 -329.933136) (xy 94.951051 -329.914531)
			(xy 94.9579 -329.907138) (xy 99.39274 -325.472298) (xy 99.400141 -325.465458) (xy 99.418739 -325.457739)
			(xy 99.428808 -325.457312) (xy 100.232972 -325.457312) (xy 100.244148 -325.455788) (xy 100.266246 -325.446136)
			(xy 100.269802 -325.44385) (xy 100.279708 -325.4375) (xy 100.284534 -325.433436) (xy 100.285296 -325.432674)
			(xy 100.306033 -325.415516) (xy 100.35142 -325.386588) (xy 100.400422 -325.364324) (xy 100.452065 -325.349166)
			(xy 100.505326 -325.341413) (xy 100.559148 -325.341221) (xy 100.612463 -325.348592) (xy 100.664214 -325.363381)
			(xy 100.713373 -325.385294) (xy 100.758967 -325.413896) (xy 100.779834 -325.430896) (xy 100.787962 -325.437754)
			(xy 100.797614 -325.44385) (xy 100.80117 -325.446136) (xy 100.816918 -325.452994) (xy 100.821758 -325.455)
			(xy 100.832001 -325.457183) (xy 100.837238 -325.457312) (xy 101.183694 -325.457312) (xy 101.200966 -325.45528)
			(xy 101.20376 -325.454518) (xy 101.21646 -325.452486) (xy 101.237288 -325.43369) (xy 101.2444 -325.429626)
			(xy 101.255576 -325.423784) (xy 101.283012 -325.410078) (xy 101.341174 -325.390638) (xy 101.401698 -325.380755)
			(xy 101.43236 -325.380096) (xy 101.433376 -325.380096) (xy 101.461391 -325.380608) (xy 101.516816 -325.388835)
			(xy 101.570443 -325.405073) (xy 101.621122 -325.428972) (xy 101.644704 -325.444104) (xy 101.6508 -325.448168)
			(xy 101.670866 -325.454772) (xy 101.6747 -325.455935) (xy 101.682609 -325.457214) (xy 101.686614 -325.457312)
			(xy 104.336596 -325.457312) (xy 104.342946 -325.455788) (xy 104.366346 -325.450095) (xy 104.414116 -325.443975)
			(xy 104.438196 -325.443596) (xy 104.462274 -325.443997) (xy 104.510043 -325.450111) (xy 104.533446 -325.455788)
			(xy 104.539796 -325.457312) (xy 115.458494 -325.457312) (xy 115.468565 -325.45689) (xy 115.487172 -325.449179)
			(xy 115.494562 -325.442326) (xy 116.221256 -324.715632) (xy 116.228097 -324.708232) (xy 116.235813 -324.689633)
			(xy 116.236242 -324.679564) (xy 116.236242 -323.807836) (xy 116.2304 -323.801994) (xy 116.2304 -320.726562)
			(xy 116.230535 -320.721671) (xy 116.232451 -320.712078) (xy 116.23421 -320.707512) (xy 116.24183 -320.68897)
			(xy 116.243533 -320.684395) (xy 116.245324 -320.674801) (xy 116.245386 -320.66992) (xy 116.245386 -308.935628)
			(xy 116.244949 -308.925564) (xy 116.237215 -308.90698) (xy 116.2304 -308.89956) (xy 115.799362 -308.468522)
			(xy 115.791963 -308.461679) (xy 115.773364 -308.453955) (xy 115.763294 -308.453536) (xy 103.191818 -308.453536)
			(xy 103.181756 -308.453096) (xy 103.163179 -308.445354) (xy 103.15575 -308.43855) (xy 98.899218 -304.182018)
			(xy 98.892383 -304.174616) (xy 98.884675 -304.156017) (xy 98.884232 -304.14595) (xy 98.884232 -298.169076)
			(xy 98.876612 -298.15028) (xy 98.869246 -298.143168) (xy 93.202506 -292.476174) (xy 93.195663 -292.468774)
			(xy 93.187937 -292.450176) (xy 93.18752 -292.440106) (xy 93.18752 -290.93922) (xy 93.187083 -290.929156)
			(xy 93.17935 -290.910571) (xy 93.172534 -290.903152) (xy 92.67444 -290.405058) (xy 92.667041 -290.398215)
			(xy 92.648442 -290.390493) (xy 92.638372 -290.390072) (xy 89.941908 -290.390072) (xy 89.935099 -290.390289)
			(xy 89.921966 -290.393894) (xy 89.916 -290.397184) (xy 89.896696 -290.408614) (xy 89.891108 -290.411916)
			(xy 89.881202 -290.421822) (xy 89.8779 -290.427664) (xy 89.869726 -290.441398) (xy 89.851413 -290.467593)
			(xy 89.841324 -290.479988) (xy 89.82391 -290.500449) (xy 89.784305 -290.536756) (xy 89.739999 -290.567151)
			(xy 89.691869 -290.591031) (xy 89.640865 -290.607925) (xy 89.587997 -290.617499) (xy 89.534307 -290.619564)
			(xy 89.480859 -290.614079) (xy 89.428709 -290.601153) (xy 89.378886 -290.58104) (xy 89.332377 -290.554139)
			(xy 89.310972 -290.5379) (xy 89.292628 -290.523102) (xy 89.259338 -290.489738) (xy 89.230392 -290.452542)
			(xy 89.218008 -290.43249) (xy 89.214706 -290.426902) (xy 89.19718 -290.409376) (xy 89.18829 -290.403788)
			(xy 89.177114 -290.397438) (xy 89.171018 -290.393882) (xy 89.161874 -290.391596) (xy 89.149428 -290.390072)
			(xy 86.09965 -290.390072) (xy 86.089494 -290.390521) (xy 86.070763 -290.39838) (xy 86.063328 -290.405312)
			(xy 86.012528 -290.457128) (xy 86.005944 -290.464509) (xy 85.998487 -290.482807) (xy 85.99805 -290.492688)
			(xy 85.99805 -290.501578) (xy 85.997566 -290.528831) (xy 85.989812 -290.582784) (xy 85.974459 -290.635084)
			(xy 85.95182 -290.684666) (xy 85.922355 -290.730522) (xy 85.886664 -290.771719) (xy 85.845474 -290.807416)
			(xy 85.799622 -290.836889) (xy 85.750044 -290.859537) (xy 85.697746 -290.874898) (xy 85.643795 -290.882661)
			(xy 85.616542 -290.883086) (xy 85.589618 -290.882628) (xy 85.536303 -290.875072) (xy 85.484578 -290.860103)
			(xy 85.435468 -290.838018) (xy 85.389946 -290.809255) (xy 85.369146 -290.792154) (xy 85.367622 -290.790884)
			(xy 85.357716 -290.783518) (xy 85.354668 -290.781994) (xy 85.329098 -290.76759) (xy 85.282324 -290.732149)
			(xy 85.241527 -290.689963) (xy 85.207672 -290.642028) (xy 85.181555 -290.589475) (xy 85.163794 -290.533542)
			(xy 85.154807 -290.475549) (xy 85.154262 -290.446206) (xy 85.154262 -290.440872) (xy 85.153837 -290.430857)
			(xy 85.146161 -290.412356) (xy 85.131988 -290.398202) (xy 85.113477 -290.39055) (xy 85.103462 -290.390072)
			(xy 83.316318 -290.390072) (xy 83.307711 -290.390415) (xy 83.291467 -290.396112) (xy 83.278006 -290.406842)
			(xy 83.273138 -290.413948) (xy 83.247738 -290.454334) (xy 83.227418 -290.486592) (xy 83.227418 -290.4871)
			(xy 83.22056 -290.498022) (xy 83.218782 -290.52393) (xy 83.22437 -290.535614) (xy 83.234155 -290.557506)
			(xy 83.248017 -290.603409) (xy 83.255109 -290.650832) (xy 83.255612 -290.674806) (xy 83.255102 -290.700793)
			(xy 83.246972 -290.752128) (xy 83.230911 -290.801558) (xy 83.207315 -290.847868) (xy 83.176765 -290.889916)
			(xy 83.140014 -290.926667) (xy 83.097966 -290.957217) (xy 83.051656 -290.980813) (xy 83.002226 -290.996874)
			(xy 82.950891 -291.005004) (xy 82.898917 -291.005004) (xy 82.847582 -290.996874) (xy 82.798152 -290.980813)
			(xy 82.751842 -290.957217) (xy 82.709794 -290.926667) (xy 82.673043 -290.889916) (xy 82.642493 -290.847868)
			(xy 82.618897 -290.801558) (xy 82.602836 -290.752128) (xy 82.594706 -290.700793) (xy 82.594196 -290.674806)
			(xy 82.594596 -290.651551) (xy 82.601116 -290.605499) (xy 82.614015 -290.560813) (xy 82.623152 -290.539424)
			(xy 82.625438 -290.534344) (xy 82.62747 -290.524184) (xy 82.63001 -290.514532) (xy 82.625946 -290.491926)
			(xy 82.620358 -290.48329) (xy 82.60207 -290.454588) (xy 82.60207 -290.45408) (xy 82.592418 -290.438586)
			(xy 82.58683 -290.426394) (xy 82.582004 -290.410138) (xy 82.555334 -290.390072) (xy 82.366358 -290.390072)
			(xy 82.357748 -290.390409) (xy 82.341494 -290.396097) (xy 82.328022 -290.406824) (xy 82.323178 -290.413948)
			(xy 82.297778 -290.454334) (xy 82.277458 -290.486592) (xy 82.277458 -290.4871) (xy 82.2706 -290.498022)
			(xy 82.268822 -290.52393) (xy 82.27441 -290.535614) (xy 82.284197 -290.557505) (xy 82.298061 -290.603408)
			(xy 82.305154 -290.650832) (xy 82.305652 -290.674806) (xy 82.305142 -290.700793) (xy 82.297012 -290.752128)
			(xy 82.280951 -290.801558) (xy 82.257355 -290.847868) (xy 82.226805 -290.889916) (xy 82.190054 -290.926667)
			(xy 82.148006 -290.957217) (xy 82.101696 -290.980813) (xy 82.052266 -290.996874) (xy 82.000931 -291.005004)
			(xy 81.948957 -291.005004) (xy 81.897622 -290.996874) (xy 81.848192 -290.980813) (xy 81.801882 -290.957217)
			(xy 81.759834 -290.926667) (xy 81.723083 -290.889916) (xy 81.692533 -290.847868) (xy 81.668937 -290.801558)
			(xy 81.652876 -290.752128) (xy 81.644746 -290.700793) (xy 81.644236 -290.674806) (xy 81.644636 -290.651551)
			(xy 81.651157 -290.6055) (xy 81.664057 -290.560814) (xy 81.673192 -290.539424) (xy 81.675478 -290.534344)
			(xy 81.67751 -290.524184) (xy 81.68005 -290.514532) (xy 81.675986 -290.491926) (xy 81.670398 -290.48329)
			(xy 81.65211 -290.454588) (xy 81.65211 -290.45408) (xy 81.642458 -290.438586) (xy 81.63687 -290.426394)
			(xy 81.632044 -290.410138) (xy 81.605374 -290.390072) (xy 81.416398 -290.390072) (xy 81.407793 -290.390418)
			(xy 81.391554 -290.39612) (xy 81.378098 -290.406851) (xy 81.373218 -290.413948) (xy 81.347818 -290.454334)
			(xy 81.327498 -290.486592) (xy 81.327498 -290.4871) (xy 81.32064 -290.498022) (xy 81.318862 -290.52393)
			(xy 81.32445 -290.535614) (xy 81.334236 -290.557506) (xy 81.348098 -290.603409) (xy 81.355191 -290.650832)
			(xy 81.355692 -290.674806) (xy 81.355182 -290.700793) (xy 81.347052 -290.752128) (xy 81.330991 -290.801558)
			(xy 81.307395 -290.847868) (xy 81.276845 -290.889916) (xy 81.240094 -290.926667) (xy 81.198046 -290.957217)
			(xy 81.151736 -290.980813) (xy 81.102306 -290.996874) (xy 81.050971 -291.005004) (xy 80.998997 -291.005004)
			(xy 80.947662 -290.996874) (xy 80.898232 -290.980813) (xy 80.851922 -290.957217) (xy 80.809874 -290.926667)
			(xy 80.773123 -290.889916) (xy 80.742573 -290.847868) (xy 80.718977 -290.801558) (xy 80.702916 -290.752128)
			(xy 80.694786 -290.700793) (xy 80.694276 -290.674806) (xy 80.694676 -290.651551) (xy 80.701196 -290.605499)
			(xy 80.714094 -290.560813) (xy 80.723232 -290.539424) (xy 80.725518 -290.534344) (xy 80.72755 -290.524184)
			(xy 80.73009 -290.514532) (xy 80.726026 -290.491926) (xy 80.720438 -290.48329) (xy 80.70215 -290.454588)
			(xy 80.70215 -290.45408) (xy 80.692498 -290.438586) (xy 80.68691 -290.426394) (xy 80.682084 -290.410138)
			(xy 80.655414 -290.390072) (xy 80.466184 -290.390072) (xy 80.45758 -290.390421) (xy 80.441344 -290.396125)
			(xy 80.427892 -290.406858) (xy 80.423004 -290.413948) (xy 80.397604 -290.454334) (xy 80.377284 -290.486592)
			(xy 80.377284 -290.4871) (xy 80.370426 -290.498022) (xy 80.368648 -290.52393) (xy 80.374236 -290.535614)
			(xy 80.384022 -290.557505) (xy 80.397885 -290.603409) (xy 80.404978 -290.650832) (xy 80.405478 -290.674806)
			(xy 80.404968 -290.700793) (xy 80.396838 -290.752128) (xy 80.380777 -290.801558) (xy 80.357181 -290.847868)
			(xy 80.326631 -290.889916) (xy 80.28988 -290.926667) (xy 80.247832 -290.957217) (xy 80.201522 -290.980813)
			(xy 80.152092 -290.996874) (xy 80.100757 -291.005004) (xy 80.048783 -291.005004) (xy 79.997448 -290.996874)
			(xy 79.948018 -290.980813) (xy 79.901708 -290.957217) (xy 79.85966 -290.926667) (xy 79.822909 -290.889916)
			(xy 79.792359 -290.847868) (xy 79.768763 -290.801558) (xy 79.752702 -290.752128) (xy 79.744572 -290.700793)
			(xy 79.744062 -290.674806) (xy 79.744462 -290.651551) (xy 79.750981 -290.605499) (xy 79.763879 -290.560812)
			(xy 79.773018 -290.539424) (xy 79.775304 -290.534344) (xy 79.777336 -290.524184) (xy 79.779876 -290.514532)
			(xy 79.775812 -290.491926) (xy 79.770224 -290.48329) (xy 79.751936 -290.454588) (xy 79.751936 -290.45408)
			(xy 79.742284 -290.438586) (xy 79.736696 -290.426394) (xy 79.73187 -290.410138) (xy 79.7052 -290.390072)
			(xy 79.516224 -290.390072) (xy 79.507617 -290.390414) (xy 79.491371 -290.39611) (xy 79.477908 -290.406839)
			(xy 79.473044 -290.413948) (xy 79.447644 -290.454334) (xy 79.427324 -290.486592) (xy 79.427324 -290.4871)
			(xy 79.420466 -290.498022) (xy 79.418688 -290.52393) (xy 79.424276 -290.535614) (xy 79.434061 -290.557506)
			(xy 79.447923 -290.603409) (xy 79.455014 -290.650832) (xy 79.455518 -290.674806) (xy 79.455008 -290.700793)
			(xy 79.446878 -290.752128) (xy 79.430817 -290.801558) (xy 79.407221 -290.847868) (xy 79.376671 -290.889916)
			(xy 79.33992 -290.926667) (xy 79.297872 -290.957217) (xy 79.251562 -290.980813) (xy 79.202132 -290.996874)
			(xy 79.150797 -291.005004) (xy 79.098823 -291.005004) (xy 79.047488 -290.996874) (xy 78.998058 -290.980813)
			(xy 78.951748 -290.957217) (xy 78.9097 -290.926667) (xy 78.872949 -290.889916) (xy 78.842399 -290.847868)
			(xy 78.818803 -290.801558) (xy 78.802742 -290.752128) (xy 78.794612 -290.700793) (xy 78.794102 -290.674806)
			(xy 78.794502 -290.651551) (xy 78.801022 -290.605499) (xy 78.813921 -290.560813) (xy 78.823058 -290.539424)
			(xy 78.825344 -290.534344) (xy 78.827376 -290.524184) (xy 78.829916 -290.514532) (xy 78.825852 -290.491926)
			(xy 78.820264 -290.48329) (xy 78.801976 -290.454588) (xy 78.801976 -290.45408) (xy 78.792324 -290.438586)
			(xy 78.786736 -290.426394) (xy 78.78191 -290.410138) (xy 78.75524 -290.390072) (xy 78.566264 -290.390072)
			(xy 78.557662 -290.390424) (xy 78.541431 -290.396132) (xy 78.527984 -290.406867) (xy 78.523084 -290.413948)
			(xy 78.497684 -290.454334) (xy 78.477364 -290.486592) (xy 78.477364 -290.4871) (xy 78.470506 -290.498022)
			(xy 78.468728 -290.52393) (xy 78.474316 -290.535614) (xy 78.484103 -290.557505) (xy 78.497967 -290.603408)
			(xy 78.50506 -290.650832) (xy 78.505558 -290.674806) (xy 78.505048 -290.700793) (xy 78.496918 -290.752128)
			(xy 78.480857 -290.801558) (xy 78.457261 -290.847868) (xy 78.426711 -290.889916) (xy 78.38996 -290.926667)
			(xy 78.347912 -290.957217) (xy 78.301602 -290.980813) (xy 78.252172 -290.996874) (xy 78.200837 -291.005004)
			(xy 78.148863 -291.005004) (xy 78.097528 -290.996874) (xy 78.048098 -290.980813) (xy 78.001788 -290.957217)
			(xy 77.95974 -290.926667) (xy 77.922989 -290.889916) (xy 77.892439 -290.847868) (xy 77.868843 -290.801558)
			(xy 77.852782 -290.752128) (xy 77.844652 -290.700793) (xy 77.844142 -290.674806) (xy 77.844542 -290.651551)
			(xy 77.851063 -290.6055) (xy 77.863964 -290.560814) (xy 77.873098 -290.539424) (xy 77.875384 -290.534344)
			(xy 77.877416 -290.524184) (xy 77.879956 -290.514532) (xy 77.875892 -290.491926) (xy 77.870304 -290.48329)
			(xy 77.852016 -290.454588) (xy 77.852016 -290.45408) (xy 77.842364 -290.438586) (xy 77.836776 -290.426394)
			(xy 77.83195 -290.410138) (xy 77.80528 -290.390072) (xy 77.616304 -290.390072) (xy 77.607699 -290.390417)
			(xy 77.591458 -290.396117) (xy 77.578 -290.406848) (xy 77.573124 -290.413948) (xy 77.547724 -290.454334)
			(xy 77.527404 -290.486592) (xy 77.527404 -290.4871) (xy 77.520546 -290.498022) (xy 77.518768 -290.52393)
			(xy 77.524356 -290.535614) (xy 77.534142 -290.557506) (xy 77.548004 -290.603409) (xy 77.555096 -290.650832)
			(xy 77.555598 -290.674806) (xy 77.555088 -290.700793) (xy 77.546958 -290.752128) (xy 77.530897 -290.801558)
			(xy 77.507301 -290.847868) (xy 77.476751 -290.889916) (xy 77.44 -290.926667) (xy 77.397952 -290.957217)
			(xy 77.351642 -290.980813) (xy 77.302212 -290.996874) (xy 77.250877 -291.005004) (xy 77.198903 -291.005004)
			(xy 77.147568 -290.996874) (xy 77.098138 -290.980813) (xy 77.051828 -290.957217) (xy 77.00978 -290.926667)
			(xy 76.973029 -290.889916) (xy 76.942479 -290.847868) (xy 76.918883 -290.801558) (xy 76.902822 -290.752128)
			(xy 76.894692 -290.700793) (xy 76.894182 -290.674806) (xy 76.894582 -290.651551) (xy 76.901102 -290.605499)
			(xy 76.914 -290.560813) (xy 76.923138 -290.539424) (xy 76.925424 -290.534344) (xy 76.927456 -290.524184)
			(xy 76.929996 -290.514532) (xy 76.925932 -290.491926) (xy 76.920344 -290.48329) (xy 76.902056 -290.454588)
			(xy 76.902056 -290.45408) (xy 76.892404 -290.438586) (xy 76.886816 -290.426394) (xy 76.88199 -290.410138)
			(xy 76.85532 -290.390072) (xy 76.666344 -290.390072) (xy 76.657735 -290.390411) (xy 76.641485 -290.396102)
			(xy 76.628017 -290.40683) (xy 76.623164 -290.413948) (xy 76.597764 -290.454334) (xy 76.577444 -290.486592)
			(xy 76.577444 -290.4871) (xy 76.570586 -290.498022) (xy 76.568808 -290.52393) (xy 76.574396 -290.535614)
			(xy 76.58418 -290.557506) (xy 76.598041 -290.603409) (xy 76.605132 -290.650832) (xy 76.605638 -290.674806)
			(xy 76.605128 -290.700793) (xy 76.596998 -290.752128) (xy 76.580937 -290.801558) (xy 76.557341 -290.847868)
			(xy 76.526791 -290.889916) (xy 76.49004 -290.926667) (xy 76.447992 -290.957217) (xy 76.401682 -290.980813)
			(xy 76.352252 -290.996874) (xy 76.300917 -291.005004) (xy 76.248943 -291.005004) (xy 76.197608 -290.996874)
			(xy 76.148178 -290.980813) (xy 76.101868 -290.957217) (xy 76.05982 -290.926667) (xy 76.023069 -290.889916)
			(xy 75.992519 -290.847868) (xy 75.968923 -290.801558) (xy 75.952862 -290.752128) (xy 75.944732 -290.700793)
			(xy 75.944222 -290.674806) (xy 75.944622 -290.651551) (xy 75.951143 -290.6055) (xy 75.964042 -290.560814)
			(xy 75.973178 -290.539424) (xy 75.975464 -290.534344) (xy 75.977496 -290.524184) (xy 75.980036 -290.514532)
			(xy 75.975972 -290.491926) (xy 75.970384 -290.48329) (xy 75.952096 -290.454588) (xy 75.952096 -290.45408)
			(xy 75.942444 -290.438586) (xy 75.936856 -290.426394) (xy 75.93203 -290.410138) (xy 75.90536 -290.390072)
			(xy 75.716384 -290.390072) (xy 75.70778 -290.390421) (xy 75.691544 -290.396125) (xy 75.678092 -290.406858)
			(xy 75.673204 -290.413948) (xy 75.647804 -290.454334) (xy 75.627484 -290.486592) (xy 75.627484 -290.4871)
			(xy 75.620626 -290.498022) (xy 75.618848 -290.52393) (xy 75.624436 -290.535614) (xy 75.634222 -290.557505)
			(xy 75.648085 -290.603409) (xy 75.655178 -290.650832) (xy 75.655678 -290.674806) (xy 75.655168 -290.700793)
			(xy 75.647038 -290.752128) (xy 75.630977 -290.801558) (xy 75.607381 -290.847868) (xy 75.576831 -290.889916)
			(xy 75.54008 -290.926667) (xy 75.498032 -290.957217) (xy 75.451722 -290.980813) (xy 75.402292 -290.996874)
			(xy 75.350957 -291.005004) (xy 75.298983 -291.005004) (xy 75.247648 -290.996874) (xy 75.198218 -290.980813)
			(xy 75.151908 -290.957217) (xy 75.10986 -290.926667) (xy 75.073109 -290.889916) (xy 75.042559 -290.847868)
			(xy 75.018963 -290.801558) (xy 75.002902 -290.752128) (xy 74.994772 -290.700793) (xy 74.994262 -290.674806)
			(xy 74.994662 -290.651551) (xy 75.001181 -290.605499) (xy 75.014079 -290.560812) (xy 75.023218 -290.539424)
			(xy 75.025504 -290.534344) (xy 75.027536 -290.524184) (xy 75.030076 -290.514532) (xy 75.026012 -290.491926)
			(xy 75.020424 -290.48329) (xy 75.002136 -290.454588) (xy 75.002136 -290.45408) (xy 74.992484 -290.438586)
			(xy 74.986896 -290.426394) (xy 74.98207 -290.410138) (xy 74.9554 -290.390072) (xy 74.76617 -290.390072)
			(xy 74.757567 -290.390423) (xy 74.741335 -290.39613) (xy 74.727886 -290.406864) (xy 74.72299 -290.413948)
			(xy 74.69759 -290.454334) (xy 74.67727 -290.486592) (xy 74.67727 -290.4871) (xy 74.670412 -290.498022)
			(xy 74.668634 -290.52393) (xy 74.674222 -290.535614) (xy 74.684009 -290.557505) (xy 74.697872 -290.603409)
			(xy 74.704965 -290.650832) (xy 74.705464 -290.674806) (xy 74.704954 -290.700793) (xy 74.696824 -290.752128)
			(xy 74.680763 -290.801558) (xy 74.657167 -290.847868) (xy 74.626617 -290.889916) (xy 74.589866 -290.926667)
			(xy 74.547818 -290.957217) (xy 74.501508 -290.980813) (xy 74.452078 -290.996874) (xy 74.400743 -291.005004)
			(xy 74.348769 -291.005004) (xy 74.297434 -290.996874) (xy 74.248004 -290.980813) (xy 74.201694 -290.957217)
			(xy 74.159646 -290.926667) (xy 74.122895 -290.889916) (xy 74.092345 -290.847868) (xy 74.068749 -290.801558)
			(xy 74.052688 -290.752128) (xy 74.044558 -290.700793) (xy 74.044048 -290.674806) (xy 74.044448 -290.651551)
			(xy 74.050969 -290.6055) (xy 74.06387 -290.560814) (xy 74.073004 -290.539424) (xy 74.07529 -290.534344)
			(xy 74.077322 -290.524184) (xy 74.079862 -290.514532) (xy 74.075798 -290.491926) (xy 74.07021 -290.48329)
			(xy 74.051922 -290.454588) (xy 74.051922 -290.45408) (xy 74.04227 -290.438586) (xy 74.036682 -290.426394)
			(xy 74.031856 -290.410138) (xy 74.005186 -290.390072) (xy 73.81621 -290.390072) (xy 73.807604 -290.390417)
			(xy 73.791362 -290.396115) (xy 73.777903 -290.406846) (xy 73.77303 -290.413948) (xy 73.74763 -290.454334)
			(xy 73.72731 -290.486592) (xy 73.72731 -290.4871) (xy 73.720452 -290.498022) (xy 73.718674 -290.52393)
			(xy 73.724262 -290.535614) (xy 73.734047 -290.557506) (xy 73.74791 -290.603409) (xy 73.755002 -290.650832)
			(xy 73.755504 -290.674806) (xy 73.754994 -290.700793) (xy 73.746864 -290.752128) (xy 73.730803 -290.801558)
			(xy 73.707207 -290.847868) (xy 73.676657 -290.889916) (xy 73.639906 -290.926667) (xy 73.597858 -290.957217)
			(xy 73.551548 -290.980813) (xy 73.502118 -290.996874) (xy 73.450783 -291.005004) (xy 73.398809 -291.005004)
			(xy 73.347474 -290.996874) (xy 73.298044 -290.980813) (xy 73.251734 -290.957217) (xy 73.209686 -290.926667)
			(xy 73.172935 -290.889916) (xy 73.142385 -290.847868) (xy 73.118789 -290.801558) (xy 73.102728 -290.752128)
			(xy 73.094598 -290.700793) (xy 73.094088 -290.674806) (xy 73.094488 -290.651551) (xy 73.101008 -290.605499)
			(xy 73.113906 -290.560813) (xy 73.123044 -290.539424) (xy 73.12533 -290.534344) (xy 73.127362 -290.524184)
			(xy 73.129902 -290.514532) (xy 73.125838 -290.491926) (xy 73.12025 -290.48329) (xy 73.101962 -290.454588)
			(xy 73.101962 -290.45408) (xy 73.09231 -290.438586) (xy 73.086722 -290.426394) (xy 73.081896 -290.410138)
			(xy 73.055226 -290.390072) (xy 72.86625 -290.390072) (xy 72.857641 -290.39041) (xy 72.841389 -290.3961)
			(xy 72.827919 -290.406827) (xy 72.82307 -290.413948) (xy 72.79767 -290.454334) (xy 72.77735 -290.486592)
			(xy 72.77735 -290.4871) (xy 72.770492 -290.498022) (xy 72.768714 -290.52393) (xy 72.774302 -290.535614)
			(xy 72.784089 -290.557505) (xy 72.797954 -290.603408) (xy 72.805047 -290.650832) (xy 72.805544 -290.674806)
			(xy 72.805034 -290.700793) (xy 72.796904 -290.752128) (xy 72.780843 -290.801558) (xy 72.757247 -290.847868)
			(xy 72.726697 -290.889916) (xy 72.689946 -290.926667) (xy 72.647898 -290.957217) (xy 72.601588 -290.980813)
			(xy 72.552158 -290.996874) (xy 72.500823 -291.005004) (xy 72.448849 -291.005004) (xy 72.397514 -290.996874)
			(xy 72.348084 -290.980813) (xy 72.301774 -290.957217) (xy 72.259726 -290.926667) (xy 72.222975 -290.889916)
			(xy 72.192425 -290.847868) (xy 72.168829 -290.801558) (xy 72.152768 -290.752128) (xy 72.144638 -290.700793)
			(xy 72.144128 -290.674806) (xy 72.144528 -290.651551) (xy 72.151049 -290.6055) (xy 72.163949 -290.560814)
			(xy 72.173084 -290.539424) (xy 72.17537 -290.534344) (xy 72.177402 -290.524184) (xy 72.179942 -290.514532)
			(xy 72.175878 -290.491926) (xy 72.17029 -290.48329) (xy 72.152002 -290.454588) (xy 72.152002 -290.45408)
			(xy 72.14235 -290.438586) (xy 72.136762 -290.426394) (xy 72.131936 -290.410138) (xy 72.105266 -290.390072)
			(xy 71.91629 -290.390072) (xy 71.907686 -290.39042) (xy 71.891448 -290.396122) (xy 71.877994 -290.406855)
			(xy 71.87311 -290.413948) (xy 71.84771 -290.454334) (xy 71.82739 -290.486592) (xy 71.82739 -290.4871)
			(xy 71.820532 -290.498022) (xy 71.818754 -290.52393) (xy 71.824342 -290.535614) (xy 71.834128 -290.557506)
			(xy 71.847991 -290.603409) (xy 71.855083 -290.650832) (xy 71.855584 -290.674806) (xy 71.855074 -290.700793)
			(xy 71.846944 -290.752128) (xy 71.830883 -290.801558) (xy 71.807287 -290.847868) (xy 71.776737 -290.889916)
			(xy 71.739986 -290.926667) (xy 71.697938 -290.957217) (xy 71.651628 -290.980813) (xy 71.602198 -290.996874)
			(xy 71.550863 -291.005004) (xy 71.498889 -291.005004) (xy 71.447554 -290.996874) (xy 71.398124 -290.980813)
			(xy 71.351814 -290.957217) (xy 71.309766 -290.926667) (xy 71.273015 -290.889916) (xy 71.242465 -290.847868)
			(xy 71.218869 -290.801558) (xy 71.202808 -290.752128) (xy 71.194678 -290.700793) (xy 71.194168 -290.674806)
			(xy 71.194568 -290.651551) (xy 71.201088 -290.605499) (xy 71.213985 -290.560812) (xy 71.223124 -290.539424)
			(xy 71.22541 -290.534344) (xy 71.227442 -290.524184) (xy 71.229982 -290.514532) (xy 71.225918 -290.491926)
			(xy 71.22033 -290.48329) (xy 71.202042 -290.454588) (xy 71.202042 -290.45408) (xy 71.19239 -290.438586)
			(xy 71.186802 -290.426394) (xy 71.181976 -290.410138) (xy 71.155306 -290.390072) (xy 70.96633 -290.390072)
			(xy 70.957722 -290.390413) (xy 70.941475 -290.396108) (xy 70.928011 -290.406836) (xy 70.92315 -290.413948)
			(xy 70.89775 -290.454334) (xy 70.87743 -290.486592) (xy 70.87743 -290.4871) (xy 70.870572 -290.498022)
			(xy 70.868794 -290.52393) (xy 70.874382 -290.535614) (xy 70.884167 -290.557506) (xy 70.898028 -290.603409)
			(xy 70.90512 -290.650832) (xy 70.905624 -290.674806) (xy 70.905114 -290.700793) (xy 70.896984 -290.752128)
			(xy 70.880923 -290.801558) (xy 70.857327 -290.847868) (xy 70.826777 -290.889916) (xy 70.790026 -290.926667)
			(xy 70.747978 -290.957217) (xy 70.701668 -290.980813) (xy 70.652238 -290.996874) (xy 70.600903 -291.005004)
			(xy 70.548929 -291.005004) (xy 70.497594 -290.996874) (xy 70.448164 -290.980813) (xy 70.401854 -290.957217)
			(xy 70.359806 -290.926667) (xy 70.323055 -290.889916) (xy 70.292505 -290.847868) (xy 70.268909 -290.801558)
			(xy 70.252848 -290.752128) (xy 70.244718 -290.700793) (xy 70.244208 -290.674806) (xy 70.244608 -290.651551)
			(xy 70.251128 -290.605499) (xy 70.264028 -290.560813) (xy 70.273164 -290.539424) (xy 70.27545 -290.534344)
			(xy 70.277482 -290.524184) (xy 70.280022 -290.514532) (xy 70.275958 -290.491926) (xy 70.27037 -290.48329)
			(xy 70.252082 -290.454588) (xy 70.252082 -290.45408) (xy 70.24243 -290.438586) (xy 70.236842 -290.426394)
			(xy 70.232016 -290.410138) (xy 70.205346 -290.390072) (xy 70.01637 -290.390072) (xy 70.007767 -290.390423)
			(xy 69.991535 -290.39613) (xy 69.978086 -290.406864) (xy 69.97319 -290.413948) (xy 69.94779 -290.454334)
			(xy 69.92747 -290.486592) (xy 69.92747 -290.4871) (xy 69.920612 -290.498022) (xy 69.918834 -290.52393)
			(xy 69.924422 -290.535614) (xy 69.934209 -290.557505) (xy 69.948072 -290.603409) (xy 69.955165 -290.650832)
			(xy 69.955664 -290.674806) (xy 69.955154 -290.700793) (xy 69.947024 -290.752128) (xy 69.930963 -290.801558)
			(xy 69.907367 -290.847868) (xy 69.876817 -290.889916) (xy 69.840066 -290.926667) (xy 69.798018 -290.957217)
			(xy 69.751708 -290.980813) (xy 69.702278 -290.996874) (xy 69.650943 -291.005004) (xy 69.598969 -291.005004)
			(xy 69.547634 -290.996874) (xy 69.498204 -290.980813) (xy 69.451894 -290.957217) (xy 69.409846 -290.926667)
			(xy 69.373095 -290.889916) (xy 69.342545 -290.847868) (xy 69.318949 -290.801558) (xy 69.302888 -290.752128)
			(xy 69.294758 -290.700793) (xy 69.294248 -290.674806) (xy 69.294648 -290.651551) (xy 69.301169 -290.6055)
			(xy 69.31407 -290.560814) (xy 69.323204 -290.539424) (xy 69.32549 -290.534344) (xy 69.327522 -290.524184)
			(xy 69.330062 -290.514532) (xy 69.325998 -290.491926) (xy 69.32041 -290.48329) (xy 69.302122 -290.454588)
			(xy 69.302122 -290.45408) (xy 69.29247 -290.438586) (xy 69.286882 -290.426394) (xy 69.282056 -290.410138)
			(xy 69.255386 -290.390072) (xy 69.066156 -290.390072) (xy 69.057546 -290.390409) (xy 69.041293 -290.396098)
			(xy 69.027822 -290.406825) (xy 69.022976 -290.413948) (xy 68.997576 -290.454334) (xy 68.977256 -290.486592)
			(xy 68.977256 -290.4871) (xy 68.970398 -290.498022) (xy 68.96862 -290.52393) (xy 68.974208 -290.535614)
			(xy 68.983995 -290.557505) (xy 68.997859 -290.603408) (xy 69.004952 -290.650832) (xy 69.00545 -290.674806)
			(xy 69.00494 -290.700793) (xy 68.99681 -290.752128) (xy 68.980749 -290.801558) (xy 68.957153 -290.847868)
			(xy 68.926603 -290.889916) (xy 68.889852 -290.926667) (xy 68.847804 -290.957217) (xy 68.801494 -290.980813)
			(xy 68.752064 -290.996874) (xy 68.700729 -291.005004) (xy 68.648755 -291.005004) (xy 68.59742 -290.996874)
			(xy 68.54799 -290.980813) (xy 68.50168 -290.957217) (xy 68.459632 -290.926667) (xy 68.422881 -290.889916)
			(xy 68.392331 -290.847868) (xy 68.368735 -290.801558) (xy 68.352674 -290.752128) (xy 68.344544 -290.700793)
			(xy 68.344034 -290.674806) (xy 68.344434 -290.651551) (xy 68.350955 -290.6055) (xy 68.363855 -290.560814)
			(xy 68.37299 -290.539424) (xy 68.375276 -290.534344) (xy 68.377308 -290.524184) (xy 68.379848 -290.514532)
			(xy 68.375784 -290.491926) (xy 68.370196 -290.48329) (xy 68.351908 -290.454588) (xy 68.351908 -290.45408)
			(xy 68.342256 -290.438586) (xy 68.336668 -290.426394) (xy 68.331842 -290.410138) (xy 68.305172 -290.390072)
			(xy 50.066194 -290.390072) (xy 50.057589 -290.390419) (xy 50.041351 -290.396121) (xy 50.027896 -290.406853)
			(xy 50.023014 -290.413948) (xy 49.997614 -290.454334) (xy 49.977294 -290.486592) (xy 49.977294 -290.4871)
			(xy 49.970436 -290.498022) (xy 49.968658 -290.52393) (xy 49.974246 -290.535614) (xy 49.984032 -290.557506)
			(xy 49.997895 -290.603409) (xy 50.004987 -290.650832) (xy 50.005488 -290.674806) (xy 50.004978 -290.700793)
			(xy 49.996848 -290.752128) (xy 49.980787 -290.801558) (xy 49.957191 -290.847868) (xy 49.926641 -290.889916)
			(xy 49.88989 -290.926667) (xy 49.847842 -290.957217) (xy 49.801532 -290.980813) (xy 49.752102 -290.996874)
			(xy 49.700767 -291.005004) (xy 49.648793 -291.005004) (xy 49.597458 -290.996874) (xy 49.548028 -290.980813)
			(xy 49.501718 -290.957217) (xy 49.45967 -290.926667) (xy 49.422919 -290.889916) (xy 49.392369 -290.847868)
			(xy 49.368773 -290.801558) (xy 49.352712 -290.752128) (xy 49.344582 -290.700793) (xy 49.344072 -290.674806)
			(xy 49.344472 -290.651551) (xy 49.350992 -290.605499) (xy 49.36389 -290.560813) (xy 49.373028 -290.539424)
			(xy 49.375314 -290.534344) (xy 49.377346 -290.524184) (xy 49.379886 -290.514532) (xy 49.375822 -290.491926)
			(xy 49.370234 -290.48329) (xy 49.351946 -290.454588) (xy 49.351946 -290.45408) (xy 49.342294 -290.438586)
			(xy 49.336706 -290.426394) (xy 49.33188 -290.410138) (xy 49.30521 -290.390072) (xy 49.141126 -290.390072)
			(xy 49.131075 -290.390577) (xy 49.112513 -290.398296) (xy 49.105058 -290.405058) (xy 49.034192 -290.475924)
			(xy 49.026536 -290.484553) (xy 49.018998 -290.506322) (xy 49.019714 -290.517834) (xy 49.02073 -290.526216)
			(xy 49.024286 -290.533836) (xy 49.034273 -290.55615) (xy 49.048286 -290.602985) (xy 49.055226 -290.651377)
			(xy 49.055528 -290.675822) (xy 49.055528 -290.679886) (xy 49.054543 -290.706914) (xy 49.044871 -290.760122)
			(xy 49.026679 -290.811051) (xy 49.000452 -290.858346) (xy 48.966887 -290.90075) (xy 48.926877 -290.937134)
			(xy 48.881485 -290.966533) (xy 48.831918 -290.988163) (xy 48.805846 -290.995354) (xy 48.80483 -290.995608)
			(xy 48.80229 -290.99637) (xy 48.796448 -290.998402) (xy 48.786694 -291.002345) (xy 48.771279 -291.01663)
			(xy 48.762889 -291.035899) (xy 48.762412 -291.046408) (xy 48.762412 -291.271452) (xy 48.784256 -291.298884)
			(xy 48.801528 -291.302948) (xy 48.826591 -291.309448) (xy 48.874461 -291.329171) (xy 48.918673 -291.356111)
			(xy 48.958149 -291.38961) (xy 48.991924 -291.428851) (xy 49.019173 -291.472873) (xy 49.039231 -291.520604)
			(xy 49.051608 -291.570877) (xy 49.056001 -291.622464) (xy 49.055836 -291.624766) (xy 49.368976 -291.624766)
			(xy 49.372936 -291.575712) (xy 49.384713 -291.527928) (xy 49.404004 -291.482652) (xy 49.430307 -291.441056)
			(xy 49.462942 -291.404219) (xy 49.501063 -291.373094) (xy 49.543684 -291.348487) (xy 49.5897 -291.331035)
			(xy 49.637919 -291.321191) (xy 49.687094 -291.31921) (xy 49.735949 -291.325142) (xy 49.78322 -291.338834)
			(xy 49.827682 -291.359932) (xy 49.868185 -291.387888) (xy 49.903678 -291.42198) (xy 49.933243 -291.461324)
			(xy 49.956114 -291.504901) (xy 49.971698 -291.551582) (xy 49.979593 -291.600159) (xy 49.980088 -291.624766)
			(xy 50.31919 -291.624766) (xy 50.32315 -291.575712) (xy 50.334927 -291.527928) (xy 50.354218 -291.482652)
			(xy 50.380521 -291.441056) (xy 50.413156 -291.404219) (xy 50.451277 -291.373094) (xy 50.493898 -291.348487)
			(xy 50.539914 -291.331035) (xy 50.588133 -291.321191) (xy 50.637308 -291.31921) (xy 50.686163 -291.325142)
			(xy 50.733434 -291.338834) (xy 50.777896 -291.359932) (xy 50.818399 -291.387888) (xy 50.853892 -291.42198)
			(xy 50.883457 -291.461324) (xy 50.906328 -291.504901) (xy 50.921912 -291.551582) (xy 50.929807 -291.600159)
			(xy 50.930302 -291.624766) (xy 51.26915 -291.624766) (xy 51.27311 -291.575712) (xy 51.284887 -291.527928)
			(xy 51.304178 -291.482652) (xy 51.330481 -291.441056) (xy 51.363116 -291.404219) (xy 51.401237 -291.373094)
			(xy 51.443858 -291.348487) (xy 51.489874 -291.331035) (xy 51.538093 -291.321191) (xy 51.587268 -291.31921)
			(xy 51.636123 -291.325142) (xy 51.683394 -291.338834) (xy 51.727856 -291.359932) (xy 51.768359 -291.387888)
			(xy 51.803852 -291.42198) (xy 51.833417 -291.461324) (xy 51.856288 -291.504901) (xy 51.871872 -291.551582)
			(xy 51.879767 -291.600159) (xy 51.880262 -291.624766) (xy 52.21911 -291.624766) (xy 52.22307 -291.575712)
			(xy 52.234847 -291.527928) (xy 52.254138 -291.482652) (xy 52.280441 -291.441056) (xy 52.313076 -291.404219)
			(xy 52.351197 -291.373094) (xy 52.393818 -291.348487) (xy 52.439834 -291.331035) (xy 52.488053 -291.321191)
			(xy 52.537228 -291.31921) (xy 52.586083 -291.325142) (xy 52.633354 -291.338834) (xy 52.677816 -291.359932)
			(xy 52.718319 -291.387888) (xy 52.753812 -291.42198) (xy 52.783377 -291.461324) (xy 52.806248 -291.504901)
			(xy 52.821832 -291.551582) (xy 52.829727 -291.600159) (xy 52.830222 -291.624766) (xy 53.16907 -291.624766)
			(xy 53.17303 -291.575712) (xy 53.184807 -291.527928) (xy 53.204098 -291.482652) (xy 53.230401 -291.441056)
			(xy 53.263036 -291.404219) (xy 53.301157 -291.373094) (xy 53.343778 -291.348487) (xy 53.389794 -291.331035)
			(xy 53.438013 -291.321191) (xy 53.487188 -291.31921) (xy 53.536043 -291.325142) (xy 53.583314 -291.338834)
			(xy 53.627776 -291.359932) (xy 53.668279 -291.387888) (xy 53.703772 -291.42198) (xy 53.733337 -291.461324)
			(xy 53.756208 -291.504901) (xy 53.771792 -291.551582) (xy 53.779687 -291.600159) (xy 53.780182 -291.624766)
			(xy 54.11903 -291.624766) (xy 54.12299 -291.575712) (xy 54.134767 -291.527928) (xy 54.154058 -291.482652)
			(xy 54.180361 -291.441056) (xy 54.212996 -291.404219) (xy 54.251117 -291.373094) (xy 54.293738 -291.348487)
			(xy 54.339754 -291.331035) (xy 54.387973 -291.321191) (xy 54.437148 -291.31921) (xy 54.486003 -291.325142)
			(xy 54.533274 -291.338834) (xy 54.577736 -291.359932) (xy 54.618239 -291.387888) (xy 54.653732 -291.42198)
			(xy 54.683297 -291.461324) (xy 54.706168 -291.504901) (xy 54.721752 -291.551582) (xy 54.729647 -291.600159)
			(xy 54.730142 -291.624766) (xy 55.06899 -291.624766) (xy 55.07295 -291.575712) (xy 55.084727 -291.527928)
			(xy 55.104018 -291.482652) (xy 55.130321 -291.441056) (xy 55.162956 -291.404219) (xy 55.201077 -291.373094)
			(xy 55.243698 -291.348487) (xy 55.289714 -291.331035) (xy 55.337933 -291.321191) (xy 55.387108 -291.31921)
			(xy 55.435963 -291.325142) (xy 55.483234 -291.338834) (xy 55.527696 -291.359932) (xy 55.568199 -291.387888)
			(xy 55.603692 -291.42198) (xy 55.633257 -291.461324) (xy 55.656128 -291.504901) (xy 55.671712 -291.551582)
			(xy 55.679607 -291.600159) (xy 55.680102 -291.624766) (xy 56.01895 -291.624766) (xy 56.02291 -291.575712)
			(xy 56.034687 -291.527928) (xy 56.053978 -291.482652) (xy 56.080281 -291.441056) (xy 56.112916 -291.404219)
			(xy 56.151037 -291.373094) (xy 56.193658 -291.348487) (xy 56.239674 -291.331035) (xy 56.287893 -291.321191)
			(xy 56.337068 -291.31921) (xy 56.385923 -291.325142) (xy 56.433194 -291.338834) (xy 56.477656 -291.359932)
			(xy 56.518159 -291.387888) (xy 56.553652 -291.42198) (xy 56.583217 -291.461324) (xy 56.606088 -291.504901)
			(xy 56.621672 -291.551582) (xy 56.629567 -291.600159) (xy 56.630062 -291.624766) (xy 56.969164 -291.624766)
			(xy 56.973124 -291.575712) (xy 56.984901 -291.527928) (xy 57.004192 -291.482652) (xy 57.030495 -291.441056)
			(xy 57.06313 -291.404219) (xy 57.101251 -291.373094) (xy 57.143872 -291.348487) (xy 57.189888 -291.331035)
			(xy 57.238107 -291.321191) (xy 57.287282 -291.31921) (xy 57.336137 -291.325142) (xy 57.383408 -291.338834)
			(xy 57.42787 -291.359932) (xy 57.468373 -291.387888) (xy 57.503866 -291.42198) (xy 57.533431 -291.461324)
			(xy 57.556302 -291.504901) (xy 57.571886 -291.551582) (xy 57.579781 -291.600159) (xy 57.580276 -291.624766)
			(xy 57.919124 -291.624766) (xy 57.923084 -291.575712) (xy 57.934861 -291.527928) (xy 57.954152 -291.482652)
			(xy 57.980455 -291.441056) (xy 58.01309 -291.404219) (xy 58.051211 -291.373094) (xy 58.093832 -291.348487)
			(xy 58.139848 -291.331035) (xy 58.188067 -291.321191) (xy 58.237242 -291.31921) (xy 58.286097 -291.325142)
			(xy 58.333368 -291.338834) (xy 58.37783 -291.359932) (xy 58.418333 -291.387888) (xy 58.453826 -291.42198)
			(xy 58.483391 -291.461324) (xy 58.506262 -291.504901) (xy 58.521846 -291.551582) (xy 58.529741 -291.600159)
			(xy 58.530236 -291.624766) (xy 59.819044 -291.624766) (xy 59.823004 -291.575712) (xy 59.834781 -291.527928)
			(xy 59.854072 -291.482652) (xy 59.880375 -291.441056) (xy 59.91301 -291.404219) (xy 59.951131 -291.373094)
			(xy 59.993752 -291.348487) (xy 60.039768 -291.331035) (xy 60.087987 -291.321191) (xy 60.137162 -291.31921)
			(xy 60.186017 -291.325142) (xy 60.233288 -291.338834) (xy 60.27775 -291.359932) (xy 60.318253 -291.387888)
			(xy 60.353746 -291.42198) (xy 60.383311 -291.461324) (xy 60.406182 -291.504901) (xy 60.421766 -291.551582)
			(xy 60.429661 -291.600159) (xy 60.430156 -291.624766) (xy 60.769004 -291.624766) (xy 60.772964 -291.575712)
			(xy 60.784741 -291.527928) (xy 60.804032 -291.482652) (xy 60.830335 -291.441056) (xy 60.86297 -291.404219)
			(xy 60.901091 -291.373094) (xy 60.943712 -291.348487) (xy 60.989728 -291.331035) (xy 61.037947 -291.321191)
			(xy 61.087122 -291.31921) (xy 61.135977 -291.325142) (xy 61.183248 -291.338834) (xy 61.22771 -291.359932)
			(xy 61.268213 -291.387888) (xy 61.303706 -291.42198) (xy 61.333271 -291.461324) (xy 61.356142 -291.504901)
			(xy 61.371726 -291.551582) (xy 61.379621 -291.600159) (xy 61.380116 -291.624766) (xy 61.718964 -291.624766)
			(xy 61.722924 -291.575712) (xy 61.734701 -291.527928) (xy 61.753992 -291.482652) (xy 61.780295 -291.441056)
			(xy 61.81293 -291.404219) (xy 61.851051 -291.373094) (xy 61.893672 -291.348487) (xy 61.939688 -291.331035)
			(xy 61.987907 -291.321191) (xy 62.037082 -291.31921) (xy 62.085937 -291.325142) (xy 62.133208 -291.338834)
			(xy 62.17767 -291.359932) (xy 62.218173 -291.387888) (xy 62.253666 -291.42198) (xy 62.283231 -291.461324)
			(xy 62.306102 -291.504901) (xy 62.321686 -291.551582) (xy 62.329581 -291.600159) (xy 62.330076 -291.624766)
			(xy 62.669178 -291.624766) (xy 62.673138 -291.575712) (xy 62.684915 -291.527928) (xy 62.704206 -291.482652)
			(xy 62.730509 -291.441056) (xy 62.763144 -291.404219) (xy 62.801265 -291.373094) (xy 62.843886 -291.348487)
			(xy 62.889902 -291.331035) (xy 62.938121 -291.321191) (xy 62.987296 -291.31921) (xy 63.036151 -291.325142)
			(xy 63.083422 -291.338834) (xy 63.127884 -291.359932) (xy 63.168387 -291.387888) (xy 63.20388 -291.42198)
			(xy 63.233445 -291.461324) (xy 63.256316 -291.504901) (xy 63.2719 -291.551582) (xy 63.279795 -291.600159)
			(xy 63.28029 -291.624766) (xy 63.619138 -291.624766) (xy 63.623098 -291.575712) (xy 63.634875 -291.527928)
			(xy 63.654166 -291.482652) (xy 63.680469 -291.441056) (xy 63.713104 -291.404219) (xy 63.751225 -291.373094)
			(xy 63.793846 -291.348487) (xy 63.839862 -291.331035) (xy 63.888081 -291.321191) (xy 63.937256 -291.31921)
			(xy 63.986111 -291.325142) (xy 64.033382 -291.338834) (xy 64.077844 -291.359932) (xy 64.118347 -291.387888)
			(xy 64.15384 -291.42198) (xy 64.183405 -291.461324) (xy 64.206276 -291.504901) (xy 64.22186 -291.551582)
			(xy 64.229755 -291.600159) (xy 64.23025 -291.624766) (xy 64.569098 -291.624766) (xy 64.573058 -291.575712)
			(xy 64.584835 -291.527928) (xy 64.604126 -291.482652) (xy 64.630429 -291.441056) (xy 64.663064 -291.404219)
			(xy 64.701185 -291.373094) (xy 64.743806 -291.348487) (xy 64.789822 -291.331035) (xy 64.838041 -291.321191)
			(xy 64.887216 -291.31921) (xy 64.936071 -291.325142) (xy 64.983342 -291.338834) (xy 65.027804 -291.359932)
			(xy 65.068307 -291.387888) (xy 65.1038 -291.42198) (xy 65.133365 -291.461324) (xy 65.156236 -291.504901)
			(xy 65.17182 -291.551582) (xy 65.179715 -291.600159) (xy 65.18021 -291.624766) (xy 65.519058 -291.624766)
			(xy 65.523018 -291.575712) (xy 65.534795 -291.527928) (xy 65.554086 -291.482652) (xy 65.580389 -291.441056)
			(xy 65.613024 -291.404219) (xy 65.651145 -291.373094) (xy 65.693766 -291.348487) (xy 65.739782 -291.331035)
			(xy 65.788001 -291.321191) (xy 65.837176 -291.31921) (xy 65.886031 -291.325142) (xy 65.933302 -291.338834)
			(xy 65.977764 -291.359932) (xy 66.018267 -291.387888) (xy 66.05376 -291.42198) (xy 66.083325 -291.461324)
			(xy 66.106196 -291.504901) (xy 66.12178 -291.551582) (xy 66.129675 -291.600159) (xy 66.13017 -291.624766)
			(xy 66.469018 -291.624766) (xy 66.472978 -291.575712) (xy 66.484755 -291.527928) (xy 66.504046 -291.482652)
			(xy 66.530349 -291.441056) (xy 66.562984 -291.404219) (xy 66.601105 -291.373094) (xy 66.643726 -291.348487)
			(xy 66.689742 -291.331035) (xy 66.737961 -291.321191) (xy 66.787136 -291.31921) (xy 66.835991 -291.325142)
			(xy 66.883262 -291.338834) (xy 66.927724 -291.359932) (xy 66.968227 -291.387888) (xy 67.00372 -291.42198)
			(xy 67.033285 -291.461324) (xy 67.056156 -291.504901) (xy 67.07174 -291.551582) (xy 67.079635 -291.600159)
			(xy 67.08013 -291.624766) (xy 67.418978 -291.624766) (xy 67.422938 -291.575712) (xy 67.434715 -291.527928)
			(xy 67.454006 -291.482652) (xy 67.480309 -291.441056) (xy 67.512944 -291.404219) (xy 67.551065 -291.373094)
			(xy 67.593686 -291.348487) (xy 67.639702 -291.331035) (xy 67.687921 -291.321191) (xy 67.737096 -291.31921)
			(xy 67.785951 -291.325142) (xy 67.833222 -291.338834) (xy 67.877684 -291.359932) (xy 67.918187 -291.387888)
			(xy 67.95368 -291.42198) (xy 67.983245 -291.461324) (xy 68.006116 -291.504901) (xy 68.0217 -291.551582)
			(xy 68.029595 -291.600159) (xy 68.03009 -291.624766) (xy 68.368938 -291.624766) (xy 68.372898 -291.575712)
			(xy 68.384675 -291.527928) (xy 68.403966 -291.482652) (xy 68.430269 -291.441056) (xy 68.462904 -291.404219)
			(xy 68.501025 -291.373094) (xy 68.543646 -291.348487) (xy 68.589662 -291.331035) (xy 68.637881 -291.321191)
			(xy 68.687056 -291.31921) (xy 68.735911 -291.325142) (xy 68.783182 -291.338834) (xy 68.827644 -291.359932)
			(xy 68.868147 -291.387888) (xy 68.90364 -291.42198) (xy 68.933205 -291.461324) (xy 68.956076 -291.504901)
			(xy 68.97166 -291.551582) (xy 68.979555 -291.600159) (xy 68.98005 -291.624766) (xy 69.319152 -291.624766)
			(xy 69.323112 -291.575712) (xy 69.334889 -291.527928) (xy 69.35418 -291.482652) (xy 69.380483 -291.441056)
			(xy 69.413118 -291.404219) (xy 69.451239 -291.373094) (xy 69.49386 -291.348487) (xy 69.539876 -291.331035)
			(xy 69.588095 -291.321191) (xy 69.63727 -291.31921) (xy 69.686125 -291.325142) (xy 69.733396 -291.338834)
			(xy 69.777858 -291.359932) (xy 69.818361 -291.387888) (xy 69.853854 -291.42198) (xy 69.883419 -291.461324)
			(xy 69.90629 -291.504901) (xy 69.921874 -291.551582) (xy 69.929769 -291.600159) (xy 69.930264 -291.624766)
			(xy 70.269112 -291.624766) (xy 70.273072 -291.575712) (xy 70.284849 -291.527928) (xy 70.30414 -291.482652)
			(xy 70.330443 -291.441056) (xy 70.363078 -291.404219) (xy 70.401199 -291.373094) (xy 70.44382 -291.348487)
			(xy 70.489836 -291.331035) (xy 70.538055 -291.321191) (xy 70.58723 -291.31921) (xy 70.636085 -291.325142)
			(xy 70.683356 -291.338834) (xy 70.727818 -291.359932) (xy 70.768321 -291.387888) (xy 70.803814 -291.42198)
			(xy 70.833379 -291.461324) (xy 70.85625 -291.504901) (xy 70.871834 -291.551582) (xy 70.879729 -291.600159)
			(xy 70.880224 -291.624766) (xy 71.219072 -291.624766) (xy 71.223032 -291.575712) (xy 71.234809 -291.527928)
			(xy 71.2541 -291.482652) (xy 71.280403 -291.441056) (xy 71.313038 -291.404219) (xy 71.351159 -291.373094)
			(xy 71.39378 -291.348487) (xy 71.439796 -291.331035) (xy 71.488015 -291.321191) (xy 71.53719 -291.31921)
			(xy 71.586045 -291.325142) (xy 71.633316 -291.338834) (xy 71.677778 -291.359932) (xy 71.718281 -291.387888)
			(xy 71.753774 -291.42198) (xy 71.783339 -291.461324) (xy 71.80621 -291.504901) (xy 71.821794 -291.551582)
			(xy 71.829689 -291.600159) (xy 71.830184 -291.624766) (xy 72.169032 -291.624766) (xy 72.172992 -291.575712)
			(xy 72.184769 -291.527928) (xy 72.20406 -291.482652) (xy 72.230363 -291.441056) (xy 72.262998 -291.404219)
			(xy 72.301119 -291.373094) (xy 72.34374 -291.348487) (xy 72.389756 -291.331035) (xy 72.437975 -291.321191)
			(xy 72.48715 -291.31921) (xy 72.536005 -291.325142) (xy 72.583276 -291.338834) (xy 72.627738 -291.359932)
			(xy 72.668241 -291.387888) (xy 72.703734 -291.42198) (xy 72.733299 -291.461324) (xy 72.75617 -291.504901)
			(xy 72.771754 -291.551582) (xy 72.779649 -291.600159) (xy 72.780144 -291.624766) (xy 73.118992 -291.624766)
			(xy 73.122952 -291.575712) (xy 73.134729 -291.527928) (xy 73.15402 -291.482652) (xy 73.180323 -291.441056)
			(xy 73.212958 -291.404219) (xy 73.251079 -291.373094) (xy 73.2937 -291.348487) (xy 73.339716 -291.331035)
			(xy 73.387935 -291.321191) (xy 73.43711 -291.31921) (xy 73.485965 -291.325142) (xy 73.533236 -291.338834)
			(xy 73.577698 -291.359932) (xy 73.618201 -291.387888) (xy 73.653694 -291.42198) (xy 73.683259 -291.461324)
			(xy 73.70613 -291.504901) (xy 73.721714 -291.551582) (xy 73.729609 -291.600159) (xy 73.730104 -291.624766)
			(xy 74.069206 -291.624766) (xy 74.073166 -291.575712) (xy 74.084943 -291.527928) (xy 74.104234 -291.482652)
			(xy 74.130537 -291.441056) (xy 74.163172 -291.404219) (xy 74.201293 -291.373094) (xy 74.243914 -291.348487)
			(xy 74.28993 -291.331035) (xy 74.338149 -291.321191) (xy 74.387324 -291.31921) (xy 74.436179 -291.325142)
			(xy 74.48345 -291.338834) (xy 74.527912 -291.359932) (xy 74.568415 -291.387888) (xy 74.603908 -291.42198)
			(xy 74.633473 -291.461324) (xy 74.656344 -291.504901) (xy 74.671928 -291.551582) (xy 74.679823 -291.600159)
			(xy 74.680318 -291.624766) (xy 75.969126 -291.624766) (xy 75.973086 -291.575712) (xy 75.984863 -291.527928)
			(xy 76.004154 -291.482652) (xy 76.030457 -291.441056) (xy 76.063092 -291.404219) (xy 76.101213 -291.373094)
			(xy 76.143834 -291.348487) (xy 76.18985 -291.331035) (xy 76.238069 -291.321191) (xy 76.287244 -291.31921)
			(xy 76.336099 -291.325142) (xy 76.38337 -291.338834) (xy 76.427832 -291.359932) (xy 76.468335 -291.387888)
			(xy 76.503828 -291.42198) (xy 76.533393 -291.461324) (xy 76.556264 -291.504901) (xy 76.571848 -291.551582)
			(xy 76.579743 -291.600159) (xy 76.580238 -291.624766) (xy 76.919086 -291.624766) (xy 76.923046 -291.575712)
			(xy 76.934823 -291.527928) (xy 76.954114 -291.482652) (xy 76.980417 -291.441056) (xy 77.013052 -291.404219)
			(xy 77.051173 -291.373094) (xy 77.093794 -291.348487) (xy 77.13981 -291.331035) (xy 77.188029 -291.321191)
			(xy 77.237204 -291.31921) (xy 77.286059 -291.325142) (xy 77.33333 -291.338834) (xy 77.377792 -291.359932)
			(xy 77.418295 -291.387888) (xy 77.453788 -291.42198) (xy 77.483353 -291.461324) (xy 77.506224 -291.504901)
			(xy 77.521808 -291.551582) (xy 77.529703 -291.600159) (xy 77.530198 -291.624766) (xy 77.869046 -291.624766)
			(xy 77.873006 -291.575712) (xy 77.884783 -291.527928) (xy 77.904074 -291.482652) (xy 77.930377 -291.441056)
			(xy 77.963012 -291.404219) (xy 78.001133 -291.373094) (xy 78.043754 -291.348487) (xy 78.08977 -291.331035)
			(xy 78.137989 -291.321191) (xy 78.187164 -291.31921) (xy 78.236019 -291.325142) (xy 78.28329 -291.338834)
			(xy 78.327752 -291.359932) (xy 78.368255 -291.387888) (xy 78.403748 -291.42198) (xy 78.433313 -291.461324)
			(xy 78.456184 -291.504901) (xy 78.471768 -291.551582) (xy 78.479663 -291.600159) (xy 78.480158 -291.624766)
			(xy 78.819006 -291.624766) (xy 78.822966 -291.575712) (xy 78.834743 -291.527928) (xy 78.854034 -291.482652)
			(xy 78.880337 -291.441056) (xy 78.912972 -291.404219) (xy 78.951093 -291.373094) (xy 78.993714 -291.348487)
			(xy 79.03973 -291.331035) (xy 79.087949 -291.321191) (xy 79.137124 -291.31921) (xy 79.185979 -291.325142)
			(xy 79.23325 -291.338834) (xy 79.277712 -291.359932) (xy 79.318215 -291.387888) (xy 79.353708 -291.42198)
			(xy 79.383273 -291.461324) (xy 79.406144 -291.504901) (xy 79.421728 -291.551582) (xy 79.429623 -291.600159)
			(xy 79.430118 -291.624766) (xy 79.768966 -291.624766) (xy 79.772926 -291.575712) (xy 79.784703 -291.527928)
			(xy 79.803994 -291.482652) (xy 79.830297 -291.441056) (xy 79.862932 -291.404219) (xy 79.901053 -291.373094)
			(xy 79.943674 -291.348487) (xy 79.98969 -291.331035) (xy 80.037909 -291.321191) (xy 80.087084 -291.31921)
			(xy 80.135939 -291.325142) (xy 80.18321 -291.338834) (xy 80.227672 -291.359932) (xy 80.268175 -291.387888)
			(xy 80.303668 -291.42198) (xy 80.333233 -291.461324) (xy 80.356104 -291.504901) (xy 80.371688 -291.551582)
			(xy 80.379583 -291.600159) (xy 80.380078 -291.624766) (xy 80.71918 -291.624766) (xy 80.72314 -291.575712)
			(xy 80.734917 -291.527928) (xy 80.754208 -291.482652) (xy 80.780511 -291.441056) (xy 80.813146 -291.404219)
			(xy 80.851267 -291.373094) (xy 80.893888 -291.348487) (xy 80.939904 -291.331035) (xy 80.988123 -291.321191)
			(xy 81.037298 -291.31921) (xy 81.086153 -291.325142) (xy 81.133424 -291.338834) (xy 81.177886 -291.359932)
			(xy 81.218389 -291.387888) (xy 81.253882 -291.42198) (xy 81.283447 -291.461324) (xy 81.306318 -291.504901)
			(xy 81.321902 -291.551582) (xy 81.329797 -291.600159) (xy 81.330292 -291.624766) (xy 81.66914 -291.624766)
			(xy 81.6731 -291.575712) (xy 81.684877 -291.527928) (xy 81.704168 -291.482652) (xy 81.730471 -291.441056)
			(xy 81.763106 -291.404219) (xy 81.801227 -291.373094) (xy 81.843848 -291.348487) (xy 81.889864 -291.331035)
			(xy 81.938083 -291.321191) (xy 81.987258 -291.31921) (xy 82.036113 -291.325142) (xy 82.083384 -291.338834)
			(xy 82.127846 -291.359932) (xy 82.168349 -291.387888) (xy 82.203842 -291.42198) (xy 82.233407 -291.461324)
			(xy 82.256278 -291.504901) (xy 82.271862 -291.551582) (xy 82.279757 -291.600159) (xy 82.280252 -291.624766)
			(xy 82.6191 -291.624766) (xy 82.62306 -291.575712) (xy 82.634837 -291.527928) (xy 82.654128 -291.482652)
			(xy 82.680431 -291.441056) (xy 82.713066 -291.404219) (xy 82.751187 -291.373094) (xy 82.793808 -291.348487)
			(xy 82.839824 -291.331035) (xy 82.888043 -291.321191) (xy 82.937218 -291.31921) (xy 82.986073 -291.325142)
			(xy 83.033344 -291.338834) (xy 83.077806 -291.359932) (xy 83.118309 -291.387888) (xy 83.153802 -291.42198)
			(xy 83.183367 -291.461324) (xy 83.185296 -291.465) (xy 86.104982 -291.465) (xy 86.109053 -291.409378)
			(xy 86.121179 -291.354941) (xy 86.141102 -291.30285) (xy 86.168398 -291.254215) (xy 86.202484 -291.210072)
			(xy 86.242633 -291.171363) (xy 86.287991 -291.138912) (xy 86.337591 -291.113411) (xy 86.390375 -291.095404)
			(xy 86.445218 -291.085274) (xy 86.500952 -291.083237) (xy 86.556389 -291.089337) (xy 86.610346 -291.103443)
			(xy 86.661675 -291.125255) (xy 86.709281 -291.154309) (xy 86.752149 -291.189984) (xy 86.789366 -291.231521)
			(xy 86.820139 -291.278034) (xy 86.843811 -291.328531) (xy 86.859879 -291.381938) (xy 86.867999 -291.437114)
			(xy 86.868508 -291.465) (xy 86.867999 -291.492886) (xy 86.859879 -291.548062) (xy 86.84666 -291.592)
			(xy 88.441782 -291.592) (xy 88.445853 -291.536378) (xy 88.457979 -291.481941) (xy 88.477902 -291.42985)
			(xy 88.505198 -291.381215) (xy 88.539284 -291.337072) (xy 88.579433 -291.298363) (xy 88.624791 -291.265912)
			(xy 88.674391 -291.240411) (xy 88.727175 -291.222404) (xy 88.782018 -291.212274) (xy 88.837752 -291.210237)
			(xy 88.893189 -291.216337) (xy 88.947146 -291.230443) (xy 88.998475 -291.252255) (xy 89.046081 -291.281309)
			(xy 89.088949 -291.316984) (xy 89.126166 -291.358521) (xy 89.156939 -291.405034) (xy 89.180611 -291.455531)
			(xy 89.196679 -291.508938) (xy 89.204799 -291.564114) (xy 89.205308 -291.592) (xy 89.204799 -291.619886)
			(xy 89.196679 -291.675062) (xy 89.180611 -291.728469) (xy 89.156939 -291.778966) (xy 89.126166 -291.825479)
			(xy 89.088949 -291.867016) (xy 89.046081 -291.902691) (xy 88.998475 -291.931745) (xy 88.947146 -291.953557)
			(xy 88.893189 -291.967663) (xy 88.837752 -291.973763) (xy 88.782018 -291.971726) (xy 88.727175 -291.961596)
			(xy 88.674391 -291.943589) (xy 88.624791 -291.918088) (xy 88.579433 -291.885637) (xy 88.539284 -291.846928)
			(xy 88.505198 -291.802785) (xy 88.477902 -291.75415) (xy 88.457979 -291.702059) (xy 88.445853 -291.647622)
			(xy 88.441782 -291.592) (xy 86.84666 -291.592) (xy 86.843811 -291.601469) (xy 86.820139 -291.651966)
			(xy 86.789366 -291.698479) (xy 86.752149 -291.740016) (xy 86.709281 -291.775691) (xy 86.661675 -291.804745)
			(xy 86.610346 -291.826557) (xy 86.556389 -291.840663) (xy 86.500952 -291.846763) (xy 86.445218 -291.844726)
			(xy 86.390375 -291.834596) (xy 86.337591 -291.816589) (xy 86.287991 -291.791088) (xy 86.242633 -291.758637)
			(xy 86.202484 -291.719928) (xy 86.168398 -291.675785) (xy 86.141102 -291.62715) (xy 86.121179 -291.575059)
			(xy 86.109053 -291.520622) (xy 86.104982 -291.465) (xy 83.185296 -291.465) (xy 83.206238 -291.504901)
			(xy 83.221822 -291.551582) (xy 83.229717 -291.600159) (xy 83.230212 -291.624766) (xy 83.229717 -291.649373)
			(xy 83.221822 -291.69795) (xy 83.206238 -291.744631) (xy 83.183367 -291.788208) (xy 83.153802 -291.827552)
			(xy 83.118309 -291.861644) (xy 83.077806 -291.8896) (xy 83.033344 -291.910698) (xy 82.986073 -291.92439)
			(xy 82.937218 -291.930322) (xy 82.888043 -291.928341) (xy 82.839824 -291.918497) (xy 82.793808 -291.901045)
			(xy 82.751187 -291.876438) (xy 82.713066 -291.845313) (xy 82.680431 -291.808476) (xy 82.654128 -291.76688)
			(xy 82.634837 -291.721604) (xy 82.62306 -291.67382) (xy 82.6191 -291.624766) (xy 82.280252 -291.624766)
			(xy 82.279757 -291.649373) (xy 82.271862 -291.69795) (xy 82.256278 -291.744631) (xy 82.233407 -291.788208)
			(xy 82.203842 -291.827552) (xy 82.168349 -291.861644) (xy 82.127846 -291.8896) (xy 82.083384 -291.910698)
			(xy 82.036113 -291.92439) (xy 81.987258 -291.930322) (xy 81.938083 -291.928341) (xy 81.889864 -291.918497)
			(xy 81.843848 -291.901045) (xy 81.801227 -291.876438) (xy 81.763106 -291.845313) (xy 81.730471 -291.808476)
			(xy 81.704168 -291.76688) (xy 81.684877 -291.721604) (xy 81.6731 -291.67382) (xy 81.66914 -291.624766)
			(xy 81.330292 -291.624766) (xy 81.329797 -291.649373) (xy 81.321902 -291.69795) (xy 81.306318 -291.744631)
			(xy 81.283447 -291.788208) (xy 81.253882 -291.827552) (xy 81.218389 -291.861644) (xy 81.177886 -291.8896)
			(xy 81.133424 -291.910698) (xy 81.086153 -291.92439) (xy 81.037298 -291.930322) (xy 80.988123 -291.928341)
			(xy 80.939904 -291.918497) (xy 80.893888 -291.901045) (xy 80.851267 -291.876438) (xy 80.813146 -291.845313)
			(xy 80.780511 -291.808476) (xy 80.754208 -291.76688) (xy 80.734917 -291.721604) (xy 80.72314 -291.67382)
			(xy 80.71918 -291.624766) (xy 80.380078 -291.624766) (xy 80.379583 -291.649373) (xy 80.371688 -291.69795)
			(xy 80.356104 -291.744631) (xy 80.333233 -291.788208) (xy 80.303668 -291.827552) (xy 80.268175 -291.861644)
			(xy 80.227672 -291.8896) (xy 80.18321 -291.910698) (xy 80.135939 -291.92439) (xy 80.087084 -291.930322)
			(xy 80.037909 -291.928341) (xy 79.98969 -291.918497) (xy 79.943674 -291.901045) (xy 79.901053 -291.876438)
			(xy 79.862932 -291.845313) (xy 79.830297 -291.808476) (xy 79.803994 -291.76688) (xy 79.784703 -291.721604)
			(xy 79.772926 -291.67382) (xy 79.768966 -291.624766) (xy 79.430118 -291.624766) (xy 79.429623 -291.649373)
			(xy 79.421728 -291.69795) (xy 79.406144 -291.744631) (xy 79.383273 -291.788208) (xy 79.353708 -291.827552)
			(xy 79.318215 -291.861644) (xy 79.277712 -291.8896) (xy 79.23325 -291.910698) (xy 79.185979 -291.92439)
			(xy 79.137124 -291.930322) (xy 79.087949 -291.928341) (xy 79.03973 -291.918497) (xy 78.993714 -291.901045)
			(xy 78.951093 -291.876438) (xy 78.912972 -291.845313) (xy 78.880337 -291.808476) (xy 78.854034 -291.76688)
			(xy 78.834743 -291.721604) (xy 78.822966 -291.67382) (xy 78.819006 -291.624766) (xy 78.480158 -291.624766)
			(xy 78.479663 -291.649373) (xy 78.471768 -291.69795) (xy 78.456184 -291.744631) (xy 78.433313 -291.788208)
			(xy 78.403748 -291.827552) (xy 78.368255 -291.861644) (xy 78.327752 -291.8896) (xy 78.28329 -291.910698)
			(xy 78.236019 -291.92439) (xy 78.187164 -291.930322) (xy 78.137989 -291.928341) (xy 78.08977 -291.918497)
			(xy 78.043754 -291.901045) (xy 78.001133 -291.876438) (xy 77.963012 -291.845313) (xy 77.930377 -291.808476)
			(xy 77.904074 -291.76688) (xy 77.884783 -291.721604) (xy 77.873006 -291.67382) (xy 77.869046 -291.624766)
			(xy 77.530198 -291.624766) (xy 77.529703 -291.649373) (xy 77.521808 -291.69795) (xy 77.506224 -291.744631)
			(xy 77.483353 -291.788208) (xy 77.453788 -291.827552) (xy 77.418295 -291.861644) (xy 77.377792 -291.8896)
			(xy 77.33333 -291.910698) (xy 77.286059 -291.92439) (xy 77.237204 -291.930322) (xy 77.188029 -291.928341)
			(xy 77.13981 -291.918497) (xy 77.093794 -291.901045) (xy 77.051173 -291.876438) (xy 77.013052 -291.845313)
			(xy 76.980417 -291.808476) (xy 76.954114 -291.76688) (xy 76.934823 -291.721604) (xy 76.923046 -291.67382)
			(xy 76.919086 -291.624766) (xy 76.580238 -291.624766) (xy 76.579743 -291.649373) (xy 76.571848 -291.69795)
			(xy 76.556264 -291.744631) (xy 76.533393 -291.788208) (xy 76.503828 -291.827552) (xy 76.468335 -291.861644)
			(xy 76.427832 -291.8896) (xy 76.38337 -291.910698) (xy 76.336099 -291.92439) (xy 76.287244 -291.930322)
			(xy 76.238069 -291.928341) (xy 76.18985 -291.918497) (xy 76.143834 -291.901045) (xy 76.101213 -291.876438)
			(xy 76.063092 -291.845313) (xy 76.030457 -291.808476) (xy 76.004154 -291.76688) (xy 75.984863 -291.721604)
			(xy 75.973086 -291.67382) (xy 75.969126 -291.624766) (xy 74.680318 -291.624766) (xy 74.679823 -291.649373)
			(xy 74.671928 -291.69795) (xy 74.656344 -291.744631) (xy 74.633473 -291.788208) (xy 74.603908 -291.827552)
			(xy 74.568415 -291.861644) (xy 74.527912 -291.8896) (xy 74.48345 -291.910698) (xy 74.436179 -291.92439)
			(xy 74.387324 -291.930322) (xy 74.338149 -291.928341) (xy 74.28993 -291.918497) (xy 74.243914 -291.901045)
			(xy 74.201293 -291.876438) (xy 74.163172 -291.845313) (xy 74.130537 -291.808476) (xy 74.104234 -291.76688)
			(xy 74.084943 -291.721604) (xy 74.073166 -291.67382) (xy 74.069206 -291.624766) (xy 73.730104 -291.624766)
			(xy 73.729609 -291.649373) (xy 73.721714 -291.69795) (xy 73.70613 -291.744631) (xy 73.683259 -291.788208)
			(xy 73.653694 -291.827552) (xy 73.618201 -291.861644) (xy 73.577698 -291.8896) (xy 73.533236 -291.910698)
			(xy 73.485965 -291.92439) (xy 73.43711 -291.930322) (xy 73.387935 -291.928341) (xy 73.339716 -291.918497)
			(xy 73.2937 -291.901045) (xy 73.251079 -291.876438) (xy 73.212958 -291.845313) (xy 73.180323 -291.808476)
			(xy 73.15402 -291.76688) (xy 73.134729 -291.721604) (xy 73.122952 -291.67382) (xy 73.118992 -291.624766)
			(xy 72.780144 -291.624766) (xy 72.779649 -291.649373) (xy 72.771754 -291.69795) (xy 72.75617 -291.744631)
			(xy 72.733299 -291.788208) (xy 72.703734 -291.827552) (xy 72.668241 -291.861644) (xy 72.627738 -291.8896)
			(xy 72.583276 -291.910698) (xy 72.536005 -291.92439) (xy 72.48715 -291.930322) (xy 72.437975 -291.928341)
			(xy 72.389756 -291.918497) (xy 72.34374 -291.901045) (xy 72.301119 -291.876438) (xy 72.262998 -291.845313)
			(xy 72.230363 -291.808476) (xy 72.20406 -291.76688) (xy 72.184769 -291.721604) (xy 72.172992 -291.67382)
			(xy 72.169032 -291.624766) (xy 71.830184 -291.624766) (xy 71.829689 -291.649373) (xy 71.821794 -291.69795)
			(xy 71.80621 -291.744631) (xy 71.783339 -291.788208) (xy 71.753774 -291.827552) (xy 71.718281 -291.861644)
			(xy 71.677778 -291.8896) (xy 71.633316 -291.910698) (xy 71.586045 -291.92439) (xy 71.53719 -291.930322)
			(xy 71.488015 -291.928341) (xy 71.439796 -291.918497) (xy 71.39378 -291.901045) (xy 71.351159 -291.876438)
			(xy 71.313038 -291.845313) (xy 71.280403 -291.808476) (xy 71.2541 -291.76688) (xy 71.234809 -291.721604)
			(xy 71.223032 -291.67382) (xy 71.219072 -291.624766) (xy 70.880224 -291.624766) (xy 70.879729 -291.649373)
			(xy 70.871834 -291.69795) (xy 70.85625 -291.744631) (xy 70.833379 -291.788208) (xy 70.803814 -291.827552)
			(xy 70.768321 -291.861644) (xy 70.727818 -291.8896) (xy 70.683356 -291.910698) (xy 70.636085 -291.92439)
			(xy 70.58723 -291.930322) (xy 70.538055 -291.928341) (xy 70.489836 -291.918497) (xy 70.44382 -291.901045)
			(xy 70.401199 -291.876438) (xy 70.363078 -291.845313) (xy 70.330443 -291.808476) (xy 70.30414 -291.76688)
			(xy 70.284849 -291.721604) (xy 70.273072 -291.67382) (xy 70.269112 -291.624766) (xy 69.930264 -291.624766)
			(xy 69.929769 -291.649373) (xy 69.921874 -291.69795) (xy 69.90629 -291.744631) (xy 69.883419 -291.788208)
			(xy 69.853854 -291.827552) (xy 69.818361 -291.861644) (xy 69.777858 -291.8896) (xy 69.733396 -291.910698)
			(xy 69.686125 -291.92439) (xy 69.63727 -291.930322) (xy 69.588095 -291.928341) (xy 69.539876 -291.918497)
			(xy 69.49386 -291.901045) (xy 69.451239 -291.876438) (xy 69.413118 -291.845313) (xy 69.380483 -291.808476)
			(xy 69.35418 -291.76688) (xy 69.334889 -291.721604) (xy 69.323112 -291.67382) (xy 69.319152 -291.624766)
			(xy 68.98005 -291.624766) (xy 68.979555 -291.649373) (xy 68.97166 -291.69795) (xy 68.956076 -291.744631)
			(xy 68.933205 -291.788208) (xy 68.90364 -291.827552) (xy 68.868147 -291.861644) (xy 68.827644 -291.8896)
			(xy 68.783182 -291.910698) (xy 68.735911 -291.92439) (xy 68.687056 -291.930322) (xy 68.637881 -291.928341)
			(xy 68.589662 -291.918497) (xy 68.543646 -291.901045) (xy 68.501025 -291.876438) (xy 68.462904 -291.845313)
			(xy 68.430269 -291.808476) (xy 68.403966 -291.76688) (xy 68.384675 -291.721604) (xy 68.372898 -291.67382)
			(xy 68.368938 -291.624766) (xy 68.03009 -291.624766) (xy 68.029595 -291.649373) (xy 68.0217 -291.69795)
			(xy 68.006116 -291.744631) (xy 67.983245 -291.788208) (xy 67.95368 -291.827552) (xy 67.918187 -291.861644)
			(xy 67.877684 -291.8896) (xy 67.833222 -291.910698) (xy 67.785951 -291.92439) (xy 67.737096 -291.930322)
			(xy 67.687921 -291.928341) (xy 67.639702 -291.918497) (xy 67.593686 -291.901045) (xy 67.551065 -291.876438)
			(xy 67.512944 -291.845313) (xy 67.480309 -291.808476) (xy 67.454006 -291.76688) (xy 67.434715 -291.721604)
			(xy 67.422938 -291.67382) (xy 67.418978 -291.624766) (xy 67.08013 -291.624766) (xy 67.079635 -291.649373)
			(xy 67.07174 -291.69795) (xy 67.056156 -291.744631) (xy 67.033285 -291.788208) (xy 67.00372 -291.827552)
			(xy 66.968227 -291.861644) (xy 66.927724 -291.8896) (xy 66.883262 -291.910698) (xy 66.835991 -291.92439)
			(xy 66.787136 -291.930322) (xy 66.737961 -291.928341) (xy 66.689742 -291.918497) (xy 66.643726 -291.901045)
			(xy 66.601105 -291.876438) (xy 66.562984 -291.845313) (xy 66.530349 -291.808476) (xy 66.504046 -291.76688)
			(xy 66.484755 -291.721604) (xy 66.472978 -291.67382) (xy 66.469018 -291.624766) (xy 66.13017 -291.624766)
			(xy 66.129675 -291.649373) (xy 66.12178 -291.69795) (xy 66.106196 -291.744631) (xy 66.083325 -291.788208)
			(xy 66.05376 -291.827552) (xy 66.018267 -291.861644) (xy 65.977764 -291.8896) (xy 65.933302 -291.910698)
			(xy 65.886031 -291.92439) (xy 65.837176 -291.930322) (xy 65.788001 -291.928341) (xy 65.739782 -291.918497)
			(xy 65.693766 -291.901045) (xy 65.651145 -291.876438) (xy 65.613024 -291.845313) (xy 65.580389 -291.808476)
			(xy 65.554086 -291.76688) (xy 65.534795 -291.721604) (xy 65.523018 -291.67382) (xy 65.519058 -291.624766)
			(xy 65.18021 -291.624766) (xy 65.179715 -291.649373) (xy 65.17182 -291.69795) (xy 65.156236 -291.744631)
			(xy 65.133365 -291.788208) (xy 65.1038 -291.827552) (xy 65.068307 -291.861644) (xy 65.027804 -291.8896)
			(xy 64.983342 -291.910698) (xy 64.936071 -291.92439) (xy 64.887216 -291.930322) (xy 64.838041 -291.928341)
			(xy 64.789822 -291.918497) (xy 64.743806 -291.901045) (xy 64.701185 -291.876438) (xy 64.663064 -291.845313)
			(xy 64.630429 -291.808476) (xy 64.604126 -291.76688) (xy 64.584835 -291.721604) (xy 64.573058 -291.67382)
			(xy 64.569098 -291.624766) (xy 64.23025 -291.624766) (xy 64.229755 -291.649373) (xy 64.22186 -291.69795)
			(xy 64.206276 -291.744631) (xy 64.183405 -291.788208) (xy 64.15384 -291.827552) (xy 64.118347 -291.861644)
			(xy 64.077844 -291.8896) (xy 64.033382 -291.910698) (xy 63.986111 -291.92439) (xy 63.937256 -291.930322)
			(xy 63.888081 -291.928341) (xy 63.839862 -291.918497) (xy 63.793846 -291.901045) (xy 63.751225 -291.876438)
			(xy 63.713104 -291.845313) (xy 63.680469 -291.808476) (xy 63.654166 -291.76688) (xy 63.634875 -291.721604)
			(xy 63.623098 -291.67382) (xy 63.619138 -291.624766) (xy 63.28029 -291.624766) (xy 63.279795 -291.649373)
			(xy 63.2719 -291.69795) (xy 63.256316 -291.744631) (xy 63.233445 -291.788208) (xy 63.20388 -291.827552)
			(xy 63.168387 -291.861644) (xy 63.127884 -291.8896) (xy 63.083422 -291.910698) (xy 63.036151 -291.92439)
			(xy 62.987296 -291.930322) (xy 62.938121 -291.928341) (xy 62.889902 -291.918497) (xy 62.843886 -291.901045)
			(xy 62.801265 -291.876438) (xy 62.763144 -291.845313) (xy 62.730509 -291.808476) (xy 62.704206 -291.76688)
			(xy 62.684915 -291.721604) (xy 62.673138 -291.67382) (xy 62.669178 -291.624766) (xy 62.330076 -291.624766)
			(xy 62.329581 -291.649373) (xy 62.321686 -291.69795) (xy 62.306102 -291.744631) (xy 62.283231 -291.788208)
			(xy 62.253666 -291.827552) (xy 62.218173 -291.861644) (xy 62.17767 -291.8896) (xy 62.133208 -291.910698)
			(xy 62.085937 -291.92439) (xy 62.037082 -291.930322) (xy 61.987907 -291.928341) (xy 61.939688 -291.918497)
			(xy 61.893672 -291.901045) (xy 61.851051 -291.876438) (xy 61.81293 -291.845313) (xy 61.780295 -291.808476)
			(xy 61.753992 -291.76688) (xy 61.734701 -291.721604) (xy 61.722924 -291.67382) (xy 61.718964 -291.624766)
			(xy 61.380116 -291.624766) (xy 61.379621 -291.649373) (xy 61.371726 -291.69795) (xy 61.356142 -291.744631)
			(xy 61.333271 -291.788208) (xy 61.303706 -291.827552) (xy 61.268213 -291.861644) (xy 61.22771 -291.8896)
			(xy 61.183248 -291.910698) (xy 61.135977 -291.92439) (xy 61.087122 -291.930322) (xy 61.037947 -291.928341)
			(xy 60.989728 -291.918497) (xy 60.943712 -291.901045) (xy 60.901091 -291.876438) (xy 60.86297 -291.845313)
			(xy 60.830335 -291.808476) (xy 60.804032 -291.76688) (xy 60.784741 -291.721604) (xy 60.772964 -291.67382)
			(xy 60.769004 -291.624766) (xy 60.430156 -291.624766) (xy 60.429661 -291.649373) (xy 60.421766 -291.69795)
			(xy 60.406182 -291.744631) (xy 60.383311 -291.788208) (xy 60.353746 -291.827552) (xy 60.318253 -291.861644)
			(xy 60.27775 -291.8896) (xy 60.233288 -291.910698) (xy 60.186017 -291.92439) (xy 60.137162 -291.930322)
			(xy 60.087987 -291.928341) (xy 60.039768 -291.918497) (xy 59.993752 -291.901045) (xy 59.951131 -291.876438)
			(xy 59.91301 -291.845313) (xy 59.880375 -291.808476) (xy 59.854072 -291.76688) (xy 59.834781 -291.721604)
			(xy 59.823004 -291.67382) (xy 59.819044 -291.624766) (xy 58.530236 -291.624766) (xy 58.529741 -291.649373)
			(xy 58.521846 -291.69795) (xy 58.506262 -291.744631) (xy 58.483391 -291.788208) (xy 58.453826 -291.827552)
			(xy 58.418333 -291.861644) (xy 58.37783 -291.8896) (xy 58.333368 -291.910698) (xy 58.286097 -291.92439)
			(xy 58.237242 -291.930322) (xy 58.188067 -291.928341) (xy 58.139848 -291.918497) (xy 58.093832 -291.901045)
			(xy 58.051211 -291.876438) (xy 58.01309 -291.845313) (xy 57.980455 -291.808476) (xy 57.954152 -291.76688)
			(xy 57.934861 -291.721604) (xy 57.923084 -291.67382) (xy 57.919124 -291.624766) (xy 57.580276 -291.624766)
			(xy 57.579781 -291.649373) (xy 57.571886 -291.69795) (xy 57.556302 -291.744631) (xy 57.533431 -291.788208)
			(xy 57.503866 -291.827552) (xy 57.468373 -291.861644) (xy 57.42787 -291.8896) (xy 57.383408 -291.910698)
			(xy 57.336137 -291.92439) (xy 57.287282 -291.930322) (xy 57.238107 -291.928341) (xy 57.189888 -291.918497)
			(xy 57.143872 -291.901045) (xy 57.101251 -291.876438) (xy 57.06313 -291.845313) (xy 57.030495 -291.808476)
			(xy 57.004192 -291.76688) (xy 56.984901 -291.721604) (xy 56.973124 -291.67382) (xy 56.969164 -291.624766)
			(xy 56.630062 -291.624766) (xy 56.629567 -291.649373) (xy 56.621672 -291.69795) (xy 56.606088 -291.744631)
			(xy 56.583217 -291.788208) (xy 56.553652 -291.827552) (xy 56.518159 -291.861644) (xy 56.477656 -291.8896)
			(xy 56.433194 -291.910698) (xy 56.385923 -291.92439) (xy 56.337068 -291.930322) (xy 56.287893 -291.928341)
			(xy 56.239674 -291.918497) (xy 56.193658 -291.901045) (xy 56.151037 -291.876438) (xy 56.112916 -291.845313)
			(xy 56.080281 -291.808476) (xy 56.053978 -291.76688) (xy 56.034687 -291.721604) (xy 56.02291 -291.67382)
			(xy 56.01895 -291.624766) (xy 55.680102 -291.624766) (xy 55.679607 -291.649373) (xy 55.671712 -291.69795)
			(xy 55.656128 -291.744631) (xy 55.633257 -291.788208) (xy 55.603692 -291.827552) (xy 55.568199 -291.861644)
			(xy 55.527696 -291.8896) (xy 55.483234 -291.910698) (xy 55.435963 -291.92439) (xy 55.387108 -291.930322)
			(xy 55.337933 -291.928341) (xy 55.289714 -291.918497) (xy 55.243698 -291.901045) (xy 55.201077 -291.876438)
			(xy 55.162956 -291.845313) (xy 55.130321 -291.808476) (xy 55.104018 -291.76688) (xy 55.084727 -291.721604)
			(xy 55.07295 -291.67382) (xy 55.06899 -291.624766) (xy 54.730142 -291.624766) (xy 54.729647 -291.649373)
			(xy 54.721752 -291.69795) (xy 54.706168 -291.744631) (xy 54.683297 -291.788208) (xy 54.653732 -291.827552)
			(xy 54.618239 -291.861644) (xy 54.577736 -291.8896) (xy 54.533274 -291.910698) (xy 54.486003 -291.92439)
			(xy 54.437148 -291.930322) (xy 54.387973 -291.928341) (xy 54.339754 -291.918497) (xy 54.293738 -291.901045)
			(xy 54.251117 -291.876438) (xy 54.212996 -291.845313) (xy 54.180361 -291.808476) (xy 54.154058 -291.76688)
			(xy 54.134767 -291.721604) (xy 54.12299 -291.67382) (xy 54.11903 -291.624766) (xy 53.780182 -291.624766)
			(xy 53.779687 -291.649373) (xy 53.771792 -291.69795) (xy 53.756208 -291.744631) (xy 53.733337 -291.788208)
			(xy 53.703772 -291.827552) (xy 53.668279 -291.861644) (xy 53.627776 -291.8896) (xy 53.583314 -291.910698)
			(xy 53.536043 -291.92439) (xy 53.487188 -291.930322) (xy 53.438013 -291.928341) (xy 53.389794 -291.918497)
			(xy 53.343778 -291.901045) (xy 53.301157 -291.876438) (xy 53.263036 -291.845313) (xy 53.230401 -291.808476)
			(xy 53.204098 -291.76688) (xy 53.184807 -291.721604) (xy 53.17303 -291.67382) (xy 53.16907 -291.624766)
			(xy 52.830222 -291.624766) (xy 52.829727 -291.649373) (xy 52.821832 -291.69795) (xy 52.806248 -291.744631)
			(xy 52.783377 -291.788208) (xy 52.753812 -291.827552) (xy 52.718319 -291.861644) (xy 52.677816 -291.8896)
			(xy 52.633354 -291.910698) (xy 52.586083 -291.92439) (xy 52.537228 -291.930322) (xy 52.488053 -291.928341)
			(xy 52.439834 -291.918497) (xy 52.393818 -291.901045) (xy 52.351197 -291.876438) (xy 52.313076 -291.845313)
			(xy 52.280441 -291.808476) (xy 52.254138 -291.76688) (xy 52.234847 -291.721604) (xy 52.22307 -291.67382)
			(xy 52.21911 -291.624766) (xy 51.880262 -291.624766) (xy 51.879767 -291.649373) (xy 51.871872 -291.69795)
			(xy 51.856288 -291.744631) (xy 51.833417 -291.788208) (xy 51.803852 -291.827552) (xy 51.768359 -291.861644)
			(xy 51.727856 -291.8896) (xy 51.683394 -291.910698) (xy 51.636123 -291.92439) (xy 51.587268 -291.930322)
			(xy 51.538093 -291.928341) (xy 51.489874 -291.918497) (xy 51.443858 -291.901045) (xy 51.401237 -291.876438)
			(xy 51.363116 -291.845313) (xy 51.330481 -291.808476) (xy 51.304178 -291.76688) (xy 51.284887 -291.721604)
			(xy 51.27311 -291.67382) (xy 51.26915 -291.624766) (xy 50.930302 -291.624766) (xy 50.929807 -291.649373)
			(xy 50.921912 -291.69795) (xy 50.906328 -291.744631) (xy 50.883457 -291.788208) (xy 50.853892 -291.827552)
			(xy 50.818399 -291.861644) (xy 50.777896 -291.8896) (xy 50.733434 -291.910698) (xy 50.686163 -291.92439)
			(xy 50.637308 -291.930322) (xy 50.588133 -291.928341) (xy 50.539914 -291.918497) (xy 50.493898 -291.901045)
			(xy 50.451277 -291.876438) (xy 50.413156 -291.845313) (xy 50.380521 -291.808476) (xy 50.354218 -291.76688)
			(xy 50.334927 -291.721604) (xy 50.32315 -291.67382) (xy 50.31919 -291.624766) (xy 49.980088 -291.624766)
			(xy 49.979593 -291.649373) (xy 49.971698 -291.69795) (xy 49.956114 -291.744631) (xy 49.933243 -291.788208)
			(xy 49.903678 -291.827552) (xy 49.868185 -291.861644) (xy 49.827682 -291.8896) (xy 49.78322 -291.910698)
			(xy 49.735949 -291.92439) (xy 49.687094 -291.930322) (xy 49.637919 -291.928341) (xy 49.5897 -291.918497)
			(xy 49.543684 -291.901045) (xy 49.501063 -291.876438) (xy 49.462942 -291.845313) (xy 49.430307 -291.808476)
			(xy 49.404004 -291.76688) (xy 49.384713 -291.721604) (xy 49.372936 -291.67382) (xy 49.368976 -291.624766)
			(xy 49.055836 -291.624766) (xy 49.052304 -291.674106) (xy 49.040607 -291.724541) (xy 49.021195 -291.772538)
			(xy 48.994543 -291.816925) (xy 48.961301 -291.856617) (xy 48.922281 -291.890646) (xy 48.878436 -291.91818)
			(xy 48.830837 -291.938548) (xy 48.805846 -291.945314) (xy 48.80483 -291.945568) (xy 48.80229 -291.94633)
			(xy 48.796448 -291.948362) (xy 48.78669 -291.952303) (xy 48.771263 -291.966586) (xy 48.762859 -291.985856)
			(xy 48.762412 -291.996368) (xy 48.762412 -292.221412) (xy 48.784256 -292.248844) (xy 48.801528 -292.252908)
			(xy 48.826586 -292.259408) (xy 48.874447 -292.279129) (xy 48.91865 -292.306067) (xy 48.958118 -292.339562)
			(xy 48.991885 -292.378796) (xy 49.019128 -292.422813) (xy 49.03918 -292.470536) (xy 49.051552 -292.5208)
			(xy 49.055943 -292.572379) (xy 49.055775 -292.574726) (xy 49.368976 -292.574726) (xy 49.372936 -292.525672)
			(xy 49.384713 -292.477888) (xy 49.404004 -292.432612) (xy 49.430307 -292.391016) (xy 49.462942 -292.354179)
			(xy 49.501063 -292.323054) (xy 49.543684 -292.298447) (xy 49.5897 -292.280995) (xy 49.637919 -292.271151)
			(xy 49.687094 -292.26917) (xy 49.735949 -292.275102) (xy 49.78322 -292.288794) (xy 49.827682 -292.309892)
			(xy 49.868185 -292.337848) (xy 49.903678 -292.37194) (xy 49.933243 -292.411284) (xy 49.956114 -292.454861)
			(xy 49.971698 -292.501542) (xy 49.979593 -292.550119) (xy 49.980088 -292.574726) (xy 68.368938 -292.574726)
			(xy 68.372898 -292.525672) (xy 68.384675 -292.477888) (xy 68.403966 -292.432612) (xy 68.430269 -292.391016)
			(xy 68.462904 -292.354179) (xy 68.501025 -292.323054) (xy 68.543646 -292.298447) (xy 68.589662 -292.280995)
			(xy 68.637881 -292.271151) (xy 68.687056 -292.26917) (xy 68.735911 -292.275102) (xy 68.783182 -292.288794)
			(xy 68.827644 -292.309892) (xy 68.868147 -292.337848) (xy 68.90364 -292.37194) (xy 68.933205 -292.411284)
			(xy 68.956076 -292.454861) (xy 68.97166 -292.501542) (xy 68.979555 -292.550119) (xy 68.98005 -292.574726)
			(xy 69.319152 -292.574726) (xy 69.323112 -292.525672) (xy 69.334889 -292.477888) (xy 69.35418 -292.432612)
			(xy 69.380483 -292.391016) (xy 69.413118 -292.354179) (xy 69.451239 -292.323054) (xy 69.49386 -292.298447)
			(xy 69.539876 -292.280995) (xy 69.588095 -292.271151) (xy 69.63727 -292.26917) (xy 69.686125 -292.275102)
			(xy 69.733396 -292.288794) (xy 69.777858 -292.309892) (xy 69.818361 -292.337848) (xy 69.853854 -292.37194)
			(xy 69.883419 -292.411284) (xy 69.90629 -292.454861) (xy 69.921874 -292.501542) (xy 69.929769 -292.550119)
			(xy 69.930264 -292.574726) (xy 69.930259 -292.57498) (xy 70.269112 -292.57498) (xy 70.273072 -292.525926)
			(xy 70.284849 -292.478142) (xy 70.30414 -292.432866) (xy 70.330443 -292.39127) (xy 70.363078 -292.354433)
			(xy 70.401199 -292.323308) (xy 70.44382 -292.298701) (xy 70.489836 -292.281249) (xy 70.538055 -292.271405)
			(xy 70.58723 -292.269424) (xy 70.636085 -292.275356) (xy 70.683356 -292.289048) (xy 70.727818 -292.310146)
			(xy 70.768321 -292.338102) (xy 70.803814 -292.372194) (xy 70.833379 -292.411538) (xy 70.85625 -292.455115)
			(xy 70.871834 -292.501796) (xy 70.879729 -292.550373) (xy 70.880219 -292.574726) (xy 71.219072 -292.574726)
			(xy 71.223032 -292.525672) (xy 71.234809 -292.477888) (xy 71.2541 -292.432612) (xy 71.280403 -292.391016)
			(xy 71.313038 -292.354179) (xy 71.351159 -292.323054) (xy 71.39378 -292.298447) (xy 71.439796 -292.280995)
			(xy 71.488015 -292.271151) (xy 71.53719 -292.26917) (xy 71.586045 -292.275102) (xy 71.633316 -292.288794)
			(xy 71.677778 -292.309892) (xy 71.718281 -292.337848) (xy 71.753774 -292.37194) (xy 71.783339 -292.411284)
			(xy 71.80621 -292.454861) (xy 71.821794 -292.501542) (xy 71.829689 -292.550119) (xy 71.830184 -292.574726)
			(xy 72.169032 -292.574726) (xy 72.172992 -292.525672) (xy 72.184769 -292.477888) (xy 72.20406 -292.432612)
			(xy 72.230363 -292.391016) (xy 72.262998 -292.354179) (xy 72.301119 -292.323054) (xy 72.34374 -292.298447)
			(xy 72.389756 -292.280995) (xy 72.437975 -292.271151) (xy 72.48715 -292.26917) (xy 72.536005 -292.275102)
			(xy 72.583276 -292.288794) (xy 72.627738 -292.309892) (xy 72.668241 -292.337848) (xy 72.703734 -292.37194)
			(xy 72.733299 -292.411284) (xy 72.75617 -292.454861) (xy 72.771754 -292.501542) (xy 72.779649 -292.550119)
			(xy 72.780144 -292.574726) (xy 73.118992 -292.574726) (xy 73.122952 -292.525672) (xy 73.134729 -292.477888)
			(xy 73.15402 -292.432612) (xy 73.180323 -292.391016) (xy 73.212958 -292.354179) (xy 73.251079 -292.323054)
			(xy 73.2937 -292.298447) (xy 73.339716 -292.280995) (xy 73.387935 -292.271151) (xy 73.43711 -292.26917)
			(xy 73.485965 -292.275102) (xy 73.533236 -292.288794) (xy 73.577698 -292.309892) (xy 73.618201 -292.337848)
			(xy 73.653694 -292.37194) (xy 73.683259 -292.411284) (xy 73.70613 -292.454861) (xy 73.721714 -292.501542)
			(xy 73.729609 -292.550119) (xy 73.730104 -292.574726) (xy 74.068952 -292.574726) (xy 74.072912 -292.525672)
			(xy 74.084689 -292.477888) (xy 74.10398 -292.432612) (xy 74.130283 -292.391016) (xy 74.162918 -292.354179)
			(xy 74.201039 -292.323054) (xy 74.24366 -292.298447) (xy 74.289676 -292.280995) (xy 74.337895 -292.271151)
			(xy 74.38707 -292.26917) (xy 74.435925 -292.275102) (xy 74.483196 -292.288794) (xy 74.527658 -292.309892)
			(xy 74.568161 -292.337848) (xy 74.603654 -292.37194) (xy 74.633219 -292.411284) (xy 74.65609 -292.454861)
			(xy 74.671674 -292.501542) (xy 74.679569 -292.550119) (xy 74.680064 -292.574726) (xy 75.019166 -292.574726)
			(xy 75.023126 -292.525672) (xy 75.034903 -292.477888) (xy 75.054194 -292.432612) (xy 75.080497 -292.391016)
			(xy 75.113132 -292.354179) (xy 75.151253 -292.323054) (xy 75.193874 -292.298447) (xy 75.23989 -292.280995)
			(xy 75.288109 -292.271151) (xy 75.337284 -292.26917) (xy 75.386139 -292.275102) (xy 75.43341 -292.288794)
			(xy 75.477872 -292.309892) (xy 75.518375 -292.337848) (xy 75.553868 -292.37194) (xy 75.583433 -292.411284)
			(xy 75.606304 -292.454861) (xy 75.621888 -292.501542) (xy 75.629783 -292.550119) (xy 75.630278 -292.574726)
			(xy 75.969126 -292.574726) (xy 75.973086 -292.525672) (xy 75.984863 -292.477888) (xy 76.004154 -292.432612)
			(xy 76.030457 -292.391016) (xy 76.063092 -292.354179) (xy 76.101213 -292.323054) (xy 76.143834 -292.298447)
			(xy 76.18985 -292.280995) (xy 76.238069 -292.271151) (xy 76.287244 -292.26917) (xy 76.336099 -292.275102)
			(xy 76.38337 -292.288794) (xy 76.427832 -292.309892) (xy 76.468335 -292.337848) (xy 76.503828 -292.37194)
			(xy 76.533393 -292.411284) (xy 76.556264 -292.454861) (xy 76.571848 -292.501542) (xy 76.579743 -292.550119)
			(xy 76.580238 -292.574726) (xy 76.919086 -292.574726) (xy 76.923046 -292.525672) (xy 76.934823 -292.477888)
			(xy 76.954114 -292.432612) (xy 76.980417 -292.391016) (xy 77.013052 -292.354179) (xy 77.051173 -292.323054)
			(xy 77.093794 -292.298447) (xy 77.13981 -292.280995) (xy 77.188029 -292.271151) (xy 77.237204 -292.26917)
			(xy 77.286059 -292.275102) (xy 77.33333 -292.288794) (xy 77.377792 -292.309892) (xy 77.418295 -292.337848)
			(xy 77.453788 -292.37194) (xy 77.483353 -292.411284) (xy 77.506224 -292.454861) (xy 77.521808 -292.501542)
			(xy 77.529703 -292.550119) (xy 77.530198 -292.574726) (xy 77.869046 -292.574726) (xy 77.873006 -292.525672)
			(xy 77.884783 -292.477888) (xy 77.904074 -292.432612) (xy 77.930377 -292.391016) (xy 77.963012 -292.354179)
			(xy 78.001133 -292.323054) (xy 78.043754 -292.298447) (xy 78.08977 -292.280995) (xy 78.137989 -292.271151)
			(xy 78.187164 -292.26917) (xy 78.236019 -292.275102) (xy 78.28329 -292.288794) (xy 78.327752 -292.309892)
			(xy 78.368255 -292.337848) (xy 78.403748 -292.37194) (xy 78.433313 -292.411284) (xy 78.456184 -292.454861)
			(xy 78.471768 -292.501542) (xy 78.479663 -292.550119) (xy 78.480158 -292.574726) (xy 78.819006 -292.574726)
			(xy 78.822966 -292.525672) (xy 78.834743 -292.477888) (xy 78.854034 -292.432612) (xy 78.880337 -292.391016)
			(xy 78.912972 -292.354179) (xy 78.951093 -292.323054) (xy 78.993714 -292.298447) (xy 79.03973 -292.280995)
			(xy 79.087949 -292.271151) (xy 79.137124 -292.26917) (xy 79.185979 -292.275102) (xy 79.23325 -292.288794)
			(xy 79.277712 -292.309892) (xy 79.318215 -292.337848) (xy 79.353708 -292.37194) (xy 79.383273 -292.411284)
			(xy 79.406144 -292.454861) (xy 79.421728 -292.501542) (xy 79.429623 -292.550119) (xy 79.430118 -292.574726)
			(xy 79.768966 -292.574726) (xy 79.772926 -292.525672) (xy 79.784703 -292.477888) (xy 79.803994 -292.432612)
			(xy 79.830297 -292.391016) (xy 79.862932 -292.354179) (xy 79.901053 -292.323054) (xy 79.943674 -292.298447)
			(xy 79.98969 -292.280995) (xy 80.037909 -292.271151) (xy 80.087084 -292.26917) (xy 80.135939 -292.275102)
			(xy 80.18321 -292.288794) (xy 80.227672 -292.309892) (xy 80.268175 -292.337848) (xy 80.303668 -292.37194)
			(xy 80.333233 -292.411284) (xy 80.356104 -292.454861) (xy 80.371688 -292.501542) (xy 80.379583 -292.550119)
			(xy 80.380078 -292.574726) (xy 80.71918 -292.574726) (xy 80.72314 -292.525672) (xy 80.734917 -292.477888)
			(xy 80.754208 -292.432612) (xy 80.780511 -292.391016) (xy 80.813146 -292.354179) (xy 80.851267 -292.323054)
			(xy 80.893888 -292.298447) (xy 80.939904 -292.280995) (xy 80.988123 -292.271151) (xy 81.037298 -292.26917)
			(xy 81.086153 -292.275102) (xy 81.133424 -292.288794) (xy 81.177886 -292.309892) (xy 81.218389 -292.337848)
			(xy 81.253882 -292.37194) (xy 81.283447 -292.411284) (xy 81.306318 -292.454861) (xy 81.321902 -292.501542)
			(xy 81.329797 -292.550119) (xy 81.330292 -292.574726) (xy 81.330287 -292.57498) (xy 81.66914 -292.57498)
			(xy 81.6731 -292.525926) (xy 81.684877 -292.478142) (xy 81.704168 -292.432866) (xy 81.730471 -292.39127)
			(xy 81.763106 -292.354433) (xy 81.801227 -292.323308) (xy 81.843848 -292.298701) (xy 81.889864 -292.281249)
			(xy 81.938083 -292.271405) (xy 81.987258 -292.269424) (xy 82.036113 -292.275356) (xy 82.083384 -292.289048)
			(xy 82.127846 -292.310146) (xy 82.168349 -292.338102) (xy 82.203842 -292.372194) (xy 82.233407 -292.411538)
			(xy 82.256278 -292.455115) (xy 82.271862 -292.501796) (xy 82.279757 -292.550373) (xy 82.280252 -292.57498)
			(xy 82.6191 -292.57498) (xy 82.62306 -292.525926) (xy 82.634837 -292.478142) (xy 82.654128 -292.432866)
			(xy 82.680431 -292.39127) (xy 82.713066 -292.354433) (xy 82.751187 -292.323308) (xy 82.793808 -292.298701)
			(xy 82.839824 -292.281249) (xy 82.888043 -292.271405) (xy 82.937218 -292.269424) (xy 82.986073 -292.275356)
			(xy 83.033344 -292.289048) (xy 83.077806 -292.310146) (xy 83.118309 -292.338102) (xy 83.153802 -292.372194)
			(xy 83.183367 -292.411538) (xy 83.206238 -292.455115) (xy 83.221822 -292.501796) (xy 83.229717 -292.550373)
			(xy 83.230212 -292.57498) (xy 83.229717 -292.599587) (xy 83.221822 -292.648164) (xy 83.206238 -292.694845)
			(xy 83.183367 -292.738422) (xy 83.153802 -292.777766) (xy 83.118309 -292.811858) (xy 83.077806 -292.839814)
			(xy 83.033344 -292.860912) (xy 82.986073 -292.874604) (xy 82.937218 -292.880536) (xy 82.888043 -292.878555)
			(xy 82.839824 -292.868711) (xy 82.793808 -292.851259) (xy 82.751187 -292.826652) (xy 82.713066 -292.795527)
			(xy 82.680431 -292.75869) (xy 82.654128 -292.717094) (xy 82.634837 -292.671818) (xy 82.62306 -292.624034)
			(xy 82.6191 -292.57498) (xy 82.280252 -292.57498) (xy 82.279757 -292.599587) (xy 82.271862 -292.648164)
			(xy 82.256278 -292.694845) (xy 82.233407 -292.738422) (xy 82.203842 -292.777766) (xy 82.168349 -292.811858)
			(xy 82.127846 -292.839814) (xy 82.083384 -292.860912) (xy 82.036113 -292.874604) (xy 81.987258 -292.880536)
			(xy 81.938083 -292.878555) (xy 81.889864 -292.868711) (xy 81.843848 -292.851259) (xy 81.801227 -292.826652)
			(xy 81.763106 -292.795527) (xy 81.730471 -292.75869) (xy 81.704168 -292.717094) (xy 81.684877 -292.671818)
			(xy 81.6731 -292.624034) (xy 81.66914 -292.57498) (xy 81.330287 -292.57498) (xy 81.329797 -292.599333)
			(xy 81.321902 -292.64791) (xy 81.306318 -292.694591) (xy 81.283447 -292.738168) (xy 81.253882 -292.777512)
			(xy 81.218389 -292.811604) (xy 81.177886 -292.83956) (xy 81.133424 -292.860658) (xy 81.086153 -292.87435)
			(xy 81.037298 -292.880282) (xy 80.988123 -292.878301) (xy 80.939904 -292.868457) (xy 80.893888 -292.851005)
			(xy 80.851267 -292.826398) (xy 80.813146 -292.795273) (xy 80.780511 -292.758436) (xy 80.754208 -292.71684)
			(xy 80.734917 -292.671564) (xy 80.72314 -292.62378) (xy 80.71918 -292.574726) (xy 80.380078 -292.574726)
			(xy 80.379583 -292.599333) (xy 80.371688 -292.64791) (xy 80.356104 -292.694591) (xy 80.333233 -292.738168)
			(xy 80.303668 -292.777512) (xy 80.268175 -292.811604) (xy 80.227672 -292.83956) (xy 80.18321 -292.860658)
			(xy 80.135939 -292.87435) (xy 80.087084 -292.880282) (xy 80.037909 -292.878301) (xy 79.98969 -292.868457)
			(xy 79.943674 -292.851005) (xy 79.901053 -292.826398) (xy 79.862932 -292.795273) (xy 79.830297 -292.758436)
			(xy 79.803994 -292.71684) (xy 79.784703 -292.671564) (xy 79.772926 -292.62378) (xy 79.768966 -292.574726)
			(xy 79.430118 -292.574726) (xy 79.429623 -292.599333) (xy 79.421728 -292.64791) (xy 79.406144 -292.694591)
			(xy 79.383273 -292.738168) (xy 79.353708 -292.777512) (xy 79.318215 -292.811604) (xy 79.277712 -292.83956)
			(xy 79.23325 -292.860658) (xy 79.185979 -292.87435) (xy 79.137124 -292.880282) (xy 79.087949 -292.878301)
			(xy 79.03973 -292.868457) (xy 78.993714 -292.851005) (xy 78.951093 -292.826398) (xy 78.912972 -292.795273)
			(xy 78.880337 -292.758436) (xy 78.854034 -292.71684) (xy 78.834743 -292.671564) (xy 78.822966 -292.62378)
			(xy 78.819006 -292.574726) (xy 78.480158 -292.574726) (xy 78.479663 -292.599333) (xy 78.471768 -292.64791)
			(xy 78.456184 -292.694591) (xy 78.433313 -292.738168) (xy 78.403748 -292.777512) (xy 78.368255 -292.811604)
			(xy 78.327752 -292.83956) (xy 78.28329 -292.860658) (xy 78.236019 -292.87435) (xy 78.187164 -292.880282)
			(xy 78.137989 -292.878301) (xy 78.08977 -292.868457) (xy 78.043754 -292.851005) (xy 78.001133 -292.826398)
			(xy 77.963012 -292.795273) (xy 77.930377 -292.758436) (xy 77.904074 -292.71684) (xy 77.884783 -292.671564)
			(xy 77.873006 -292.62378) (xy 77.869046 -292.574726) (xy 77.530198 -292.574726) (xy 77.529703 -292.599333)
			(xy 77.521808 -292.64791) (xy 77.506224 -292.694591) (xy 77.483353 -292.738168) (xy 77.453788 -292.777512)
			(xy 77.418295 -292.811604) (xy 77.377792 -292.83956) (xy 77.33333 -292.860658) (xy 77.286059 -292.87435)
			(xy 77.237204 -292.880282) (xy 77.188029 -292.878301) (xy 77.13981 -292.868457) (xy 77.093794 -292.851005)
			(xy 77.051173 -292.826398) (xy 77.013052 -292.795273) (xy 76.980417 -292.758436) (xy 76.954114 -292.71684)
			(xy 76.934823 -292.671564) (xy 76.923046 -292.62378) (xy 76.919086 -292.574726) (xy 76.580238 -292.574726)
			(xy 76.579743 -292.599333) (xy 76.571848 -292.64791) (xy 76.556264 -292.694591) (xy 76.533393 -292.738168)
			(xy 76.503828 -292.777512) (xy 76.468335 -292.811604) (xy 76.427832 -292.83956) (xy 76.38337 -292.860658)
			(xy 76.336099 -292.87435) (xy 76.287244 -292.880282) (xy 76.238069 -292.878301) (xy 76.18985 -292.868457)
			(xy 76.143834 -292.851005) (xy 76.101213 -292.826398) (xy 76.063092 -292.795273) (xy 76.030457 -292.758436)
			(xy 76.004154 -292.71684) (xy 75.984863 -292.671564) (xy 75.973086 -292.62378) (xy 75.969126 -292.574726)
			(xy 75.630278 -292.574726) (xy 75.629783 -292.599333) (xy 75.621888 -292.64791) (xy 75.606304 -292.694591)
			(xy 75.583433 -292.738168) (xy 75.553868 -292.777512) (xy 75.518375 -292.811604) (xy 75.477872 -292.83956)
			(xy 75.43341 -292.860658) (xy 75.386139 -292.87435) (xy 75.337284 -292.880282) (xy 75.288109 -292.878301)
			(xy 75.23989 -292.868457) (xy 75.193874 -292.851005) (xy 75.151253 -292.826398) (xy 75.113132 -292.795273)
			(xy 75.080497 -292.758436) (xy 75.054194 -292.71684) (xy 75.034903 -292.671564) (xy 75.023126 -292.62378)
			(xy 75.019166 -292.574726) (xy 74.680064 -292.574726) (xy 74.679569 -292.599333) (xy 74.671674 -292.64791)
			(xy 74.65609 -292.694591) (xy 74.633219 -292.738168) (xy 74.603654 -292.777512) (xy 74.568161 -292.811604)
			(xy 74.527658 -292.83956) (xy 74.483196 -292.860658) (xy 74.435925 -292.87435) (xy 74.38707 -292.880282)
			(xy 74.337895 -292.878301) (xy 74.289676 -292.868457) (xy 74.24366 -292.851005) (xy 74.201039 -292.826398)
			(xy 74.162918 -292.795273) (xy 74.130283 -292.758436) (xy 74.10398 -292.71684) (xy 74.084689 -292.671564)
			(xy 74.072912 -292.62378) (xy 74.068952 -292.574726) (xy 73.730104 -292.574726) (xy 73.729609 -292.599333)
			(xy 73.721714 -292.64791) (xy 73.70613 -292.694591) (xy 73.683259 -292.738168) (xy 73.653694 -292.777512)
			(xy 73.618201 -292.811604) (xy 73.577698 -292.83956) (xy 73.533236 -292.860658) (xy 73.485965 -292.87435)
			(xy 73.43711 -292.880282) (xy 73.387935 -292.878301) (xy 73.339716 -292.868457) (xy 73.2937 -292.851005)
			(xy 73.251079 -292.826398) (xy 73.212958 -292.795273) (xy 73.180323 -292.758436) (xy 73.15402 -292.71684)
			(xy 73.134729 -292.671564) (xy 73.122952 -292.62378) (xy 73.118992 -292.574726) (xy 72.780144 -292.574726)
			(xy 72.779649 -292.599333) (xy 72.771754 -292.64791) (xy 72.75617 -292.694591) (xy 72.733299 -292.738168)
			(xy 72.703734 -292.777512) (xy 72.668241 -292.811604) (xy 72.627738 -292.83956) (xy 72.583276 -292.860658)
			(xy 72.536005 -292.87435) (xy 72.48715 -292.880282) (xy 72.437975 -292.878301) (xy 72.389756 -292.868457)
			(xy 72.34374 -292.851005) (xy 72.301119 -292.826398) (xy 72.262998 -292.795273) (xy 72.230363 -292.758436)
			(xy 72.20406 -292.71684) (xy 72.184769 -292.671564) (xy 72.172992 -292.62378) (xy 72.169032 -292.574726)
			(xy 71.830184 -292.574726) (xy 71.829689 -292.599333) (xy 71.821794 -292.64791) (xy 71.80621 -292.694591)
			(xy 71.783339 -292.738168) (xy 71.753774 -292.777512) (xy 71.718281 -292.811604) (xy 71.677778 -292.83956)
			(xy 71.633316 -292.860658) (xy 71.586045 -292.87435) (xy 71.53719 -292.880282) (xy 71.488015 -292.878301)
			(xy 71.439796 -292.868457) (xy 71.39378 -292.851005) (xy 71.351159 -292.826398) (xy 71.313038 -292.795273)
			(xy 71.280403 -292.758436) (xy 71.2541 -292.71684) (xy 71.234809 -292.671564) (xy 71.223032 -292.62378)
			(xy 71.219072 -292.574726) (xy 70.880219 -292.574726) (xy 70.880224 -292.57498) (xy 70.879729 -292.599587)
			(xy 70.871834 -292.648164) (xy 70.85625 -292.694845) (xy 70.833379 -292.738422) (xy 70.803814 -292.777766)
			(xy 70.768321 -292.811858) (xy 70.727818 -292.839814) (xy 70.683356 -292.860912) (xy 70.636085 -292.874604)
			(xy 70.58723 -292.880536) (xy 70.538055 -292.878555) (xy 70.489836 -292.868711) (xy 70.44382 -292.851259)
			(xy 70.401199 -292.826652) (xy 70.363078 -292.795527) (xy 70.330443 -292.75869) (xy 70.30414 -292.717094)
			(xy 70.284849 -292.671818) (xy 70.273072 -292.624034) (xy 70.269112 -292.57498) (xy 69.930259 -292.57498)
			(xy 69.929769 -292.599333) (xy 69.921874 -292.64791) (xy 69.90629 -292.694591) (xy 69.883419 -292.738168)
			(xy 69.853854 -292.777512) (xy 69.818361 -292.811604) (xy 69.777858 -292.83956) (xy 69.733396 -292.860658)
			(xy 69.686125 -292.87435) (xy 69.63727 -292.880282) (xy 69.588095 -292.878301) (xy 69.539876 -292.868457)
			(xy 69.49386 -292.851005) (xy 69.451239 -292.826398) (xy 69.413118 -292.795273) (xy 69.380483 -292.758436)
			(xy 69.35418 -292.71684) (xy 69.334889 -292.671564) (xy 69.323112 -292.62378) (xy 69.319152 -292.574726)
			(xy 68.98005 -292.574726) (xy 68.979555 -292.599333) (xy 68.97166 -292.64791) (xy 68.956076 -292.694591)
			(xy 68.933205 -292.738168) (xy 68.90364 -292.777512) (xy 68.868147 -292.811604) (xy 68.827644 -292.83956)
			(xy 68.783182 -292.860658) (xy 68.735911 -292.87435) (xy 68.687056 -292.880282) (xy 68.637881 -292.878301)
			(xy 68.589662 -292.868457) (xy 68.543646 -292.851005) (xy 68.501025 -292.826398) (xy 68.462904 -292.795273)
			(xy 68.430269 -292.758436) (xy 68.403966 -292.71684) (xy 68.384675 -292.671564) (xy 68.372898 -292.62378)
			(xy 68.368938 -292.574726) (xy 49.980088 -292.574726) (xy 49.979593 -292.599333) (xy 49.971698 -292.64791)
			(xy 49.956114 -292.694591) (xy 49.933243 -292.738168) (xy 49.903678 -292.777512) (xy 49.868185 -292.811604)
			(xy 49.827682 -292.83956) (xy 49.78322 -292.860658) (xy 49.735949 -292.87435) (xy 49.687094 -292.880282)
			(xy 49.637919 -292.878301) (xy 49.5897 -292.868457) (xy 49.543684 -292.851005) (xy 49.501063 -292.826398)
			(xy 49.462942 -292.795273) (xy 49.430307 -292.758436) (xy 49.404004 -292.71684) (xy 49.384713 -292.671564)
			(xy 49.372936 -292.62378) (xy 49.368976 -292.574726) (xy 49.055775 -292.574726) (xy 49.052245 -292.624011)
			(xy 49.040547 -292.674437) (xy 49.021137 -292.722425) (xy 48.994487 -292.766802) (xy 48.961249 -292.806487)
			(xy 48.922235 -292.840508) (xy 48.878396 -292.868036) (xy 48.830804 -292.888397) (xy 48.805846 -292.895274)
			(xy 48.80483 -292.895528) (xy 48.80229 -292.89629) (xy 48.796448 -292.898322) (xy 48.786696 -292.902267)
			(xy 48.771287 -292.916552) (xy 48.762905 -292.93582) (xy 48.762412 -292.946328) (xy 48.762412 -293.171626)
			(xy 48.784256 -293.199058) (xy 48.801528 -293.203122) (xy 48.826585 -293.209622) (xy 48.874443 -293.229343)
			(xy 48.918645 -293.25628) (xy 48.958111 -293.289774) (xy 48.991876 -293.329007) (xy 49.019117 -293.373022)
			(xy 49.039168 -293.420743) (xy 49.05154 -293.471006) (xy 49.055929 -293.522582) (xy 49.05576 -293.52494)
			(xy 49.368976 -293.52494) (xy 49.372936 -293.475886) (xy 49.384713 -293.428102) (xy 49.404004 -293.382826)
			(xy 49.430307 -293.34123) (xy 49.462942 -293.304393) (xy 49.501063 -293.273268) (xy 49.543684 -293.248661)
			(xy 49.5897 -293.231209) (xy 49.637919 -293.221365) (xy 49.687094 -293.219384) (xy 49.735949 -293.225316)
			(xy 49.78322 -293.239008) (xy 49.827682 -293.260106) (xy 49.868185 -293.288062) (xy 49.903678 -293.322154)
			(xy 49.933243 -293.361498) (xy 49.956114 -293.405075) (xy 49.971698 -293.451756) (xy 49.979593 -293.500333)
			(xy 49.980088 -293.52494) (xy 50.31919 -293.52494) (xy 50.32315 -293.475886) (xy 50.334927 -293.428102)
			(xy 50.354218 -293.382826) (xy 50.380521 -293.34123) (xy 50.413156 -293.304393) (xy 50.451277 -293.273268)
			(xy 50.493898 -293.248661) (xy 50.539914 -293.231209) (xy 50.588133 -293.221365) (xy 50.637308 -293.219384)
			(xy 50.686163 -293.225316) (xy 50.733434 -293.239008) (xy 50.777896 -293.260106) (xy 50.818399 -293.288062)
			(xy 50.853892 -293.322154) (xy 50.883457 -293.361498) (xy 50.906328 -293.405075) (xy 50.921912 -293.451756)
			(xy 50.929807 -293.500333) (xy 50.930302 -293.52494) (xy 51.26915 -293.52494) (xy 51.27311 -293.475886)
			(xy 51.284887 -293.428102) (xy 51.304178 -293.382826) (xy 51.330481 -293.34123) (xy 51.363116 -293.304393)
			(xy 51.401237 -293.273268) (xy 51.443858 -293.248661) (xy 51.489874 -293.231209) (xy 51.538093 -293.221365)
			(xy 51.587268 -293.219384) (xy 51.636123 -293.225316) (xy 51.683394 -293.239008) (xy 51.727856 -293.260106)
			(xy 51.768359 -293.288062) (xy 51.803852 -293.322154) (xy 51.833417 -293.361498) (xy 51.856288 -293.405075)
			(xy 51.871872 -293.451756) (xy 51.879767 -293.500333) (xy 51.880262 -293.52494) (xy 52.21911 -293.52494)
			(xy 52.22307 -293.475886) (xy 52.234847 -293.428102) (xy 52.254138 -293.382826) (xy 52.280441 -293.34123)
			(xy 52.313076 -293.304393) (xy 52.351197 -293.273268) (xy 52.393818 -293.248661) (xy 52.439834 -293.231209)
			(xy 52.488053 -293.221365) (xy 52.537228 -293.219384) (xy 52.586083 -293.225316) (xy 52.633354 -293.239008)
			(xy 52.677816 -293.260106) (xy 52.718319 -293.288062) (xy 52.753812 -293.322154) (xy 52.783377 -293.361498)
			(xy 52.806248 -293.405075) (xy 52.821832 -293.451756) (xy 52.829727 -293.500333) (xy 52.830222 -293.52494)
			(xy 53.16907 -293.52494) (xy 53.17303 -293.475886) (xy 53.184807 -293.428102) (xy 53.204098 -293.382826)
			(xy 53.230401 -293.34123) (xy 53.263036 -293.304393) (xy 53.301157 -293.273268) (xy 53.343778 -293.248661)
			(xy 53.389794 -293.231209) (xy 53.438013 -293.221365) (xy 53.487188 -293.219384) (xy 53.536043 -293.225316)
			(xy 53.583314 -293.239008) (xy 53.627776 -293.260106) (xy 53.668279 -293.288062) (xy 53.703772 -293.322154)
			(xy 53.733337 -293.361498) (xy 53.756208 -293.405075) (xy 53.771792 -293.451756) (xy 53.779687 -293.500333)
			(xy 53.780182 -293.52494) (xy 54.11903 -293.52494) (xy 54.12299 -293.475886) (xy 54.134767 -293.428102)
			(xy 54.154058 -293.382826) (xy 54.180361 -293.34123) (xy 54.212996 -293.304393) (xy 54.251117 -293.273268)
			(xy 54.293738 -293.248661) (xy 54.339754 -293.231209) (xy 54.387973 -293.221365) (xy 54.437148 -293.219384)
			(xy 54.486003 -293.225316) (xy 54.533274 -293.239008) (xy 54.577736 -293.260106) (xy 54.618239 -293.288062)
			(xy 54.653732 -293.322154) (xy 54.683297 -293.361498) (xy 54.706168 -293.405075) (xy 54.721752 -293.451756)
			(xy 54.729647 -293.500333) (xy 54.730142 -293.52494) (xy 55.06899 -293.52494) (xy 55.07295 -293.475886)
			(xy 55.084727 -293.428102) (xy 55.104018 -293.382826) (xy 55.130321 -293.34123) (xy 55.162956 -293.304393)
			(xy 55.201077 -293.273268) (xy 55.243698 -293.248661) (xy 55.289714 -293.231209) (xy 55.337933 -293.221365)
			(xy 55.387108 -293.219384) (xy 55.435963 -293.225316) (xy 55.483234 -293.239008) (xy 55.527696 -293.260106)
			(xy 55.568199 -293.288062) (xy 55.603692 -293.322154) (xy 55.633257 -293.361498) (xy 55.656128 -293.405075)
			(xy 55.671712 -293.451756) (xy 55.679607 -293.500333) (xy 55.680102 -293.52494) (xy 56.01895 -293.52494)
			(xy 56.02291 -293.475886) (xy 56.034687 -293.428102) (xy 56.053978 -293.382826) (xy 56.080281 -293.34123)
			(xy 56.112916 -293.304393) (xy 56.151037 -293.273268) (xy 56.193658 -293.248661) (xy 56.239674 -293.231209)
			(xy 56.287893 -293.221365) (xy 56.337068 -293.219384) (xy 56.385923 -293.225316) (xy 56.433194 -293.239008)
			(xy 56.477656 -293.260106) (xy 56.518159 -293.288062) (xy 56.553652 -293.322154) (xy 56.583217 -293.361498)
			(xy 56.606088 -293.405075) (xy 56.621672 -293.451756) (xy 56.629567 -293.500333) (xy 56.630062 -293.52494)
			(xy 56.969164 -293.52494) (xy 56.973124 -293.475886) (xy 56.984901 -293.428102) (xy 57.004192 -293.382826)
			(xy 57.030495 -293.34123) (xy 57.06313 -293.304393) (xy 57.101251 -293.273268) (xy 57.143872 -293.248661)
			(xy 57.189888 -293.231209) (xy 57.238107 -293.221365) (xy 57.287282 -293.219384) (xy 57.336137 -293.225316)
			(xy 57.383408 -293.239008) (xy 57.42787 -293.260106) (xy 57.468373 -293.288062) (xy 57.503866 -293.322154)
			(xy 57.533431 -293.361498) (xy 57.556302 -293.405075) (xy 57.571886 -293.451756) (xy 57.579781 -293.500333)
			(xy 57.580276 -293.52494) (xy 57.919124 -293.52494) (xy 57.923084 -293.475886) (xy 57.934861 -293.428102)
			(xy 57.954152 -293.382826) (xy 57.980455 -293.34123) (xy 58.01309 -293.304393) (xy 58.051211 -293.273268)
			(xy 58.093832 -293.248661) (xy 58.139848 -293.231209) (xy 58.188067 -293.221365) (xy 58.237242 -293.219384)
			(xy 58.286097 -293.225316) (xy 58.333368 -293.239008) (xy 58.37783 -293.260106) (xy 58.418333 -293.288062)
			(xy 58.453826 -293.322154) (xy 58.483391 -293.361498) (xy 58.506262 -293.405075) (xy 58.521846 -293.451756)
			(xy 58.529741 -293.500333) (xy 58.530236 -293.52494) (xy 59.819044 -293.52494) (xy 59.823004 -293.475886)
			(xy 59.834781 -293.428102) (xy 59.854072 -293.382826) (xy 59.880375 -293.34123) (xy 59.91301 -293.304393)
			(xy 59.951131 -293.273268) (xy 59.993752 -293.248661) (xy 60.039768 -293.231209) (xy 60.087987 -293.221365)
			(xy 60.137162 -293.219384) (xy 60.186017 -293.225316) (xy 60.233288 -293.239008) (xy 60.27775 -293.260106)
			(xy 60.318253 -293.288062) (xy 60.353746 -293.322154) (xy 60.383311 -293.361498) (xy 60.406182 -293.405075)
			(xy 60.421766 -293.451756) (xy 60.429661 -293.500333) (xy 60.430156 -293.52494) (xy 60.769004 -293.52494)
			(xy 60.772964 -293.475886) (xy 60.784741 -293.428102) (xy 60.804032 -293.382826) (xy 60.830335 -293.34123)
			(xy 60.86297 -293.304393) (xy 60.901091 -293.273268) (xy 60.943712 -293.248661) (xy 60.989728 -293.231209)
			(xy 61.037947 -293.221365) (xy 61.087122 -293.219384) (xy 61.135977 -293.225316) (xy 61.183248 -293.239008)
			(xy 61.22771 -293.260106) (xy 61.268213 -293.288062) (xy 61.303706 -293.322154) (xy 61.333271 -293.361498)
			(xy 61.356142 -293.405075) (xy 61.371726 -293.451756) (xy 61.379621 -293.500333) (xy 61.380116 -293.52494)
			(xy 61.718964 -293.52494) (xy 61.722924 -293.475886) (xy 61.734701 -293.428102) (xy 61.753992 -293.382826)
			(xy 61.780295 -293.34123) (xy 61.81293 -293.304393) (xy 61.851051 -293.273268) (xy 61.893672 -293.248661)
			(xy 61.939688 -293.231209) (xy 61.987907 -293.221365) (xy 62.037082 -293.219384) (xy 62.085937 -293.225316)
			(xy 62.133208 -293.239008) (xy 62.17767 -293.260106) (xy 62.218173 -293.288062) (xy 62.253666 -293.322154)
			(xy 62.283231 -293.361498) (xy 62.306102 -293.405075) (xy 62.321686 -293.451756) (xy 62.329581 -293.500333)
			(xy 62.330076 -293.52494) (xy 62.669178 -293.52494) (xy 62.673138 -293.475886) (xy 62.684915 -293.428102)
			(xy 62.704206 -293.382826) (xy 62.730509 -293.34123) (xy 62.763144 -293.304393) (xy 62.801265 -293.273268)
			(xy 62.843886 -293.248661) (xy 62.889902 -293.231209) (xy 62.938121 -293.221365) (xy 62.987296 -293.219384)
			(xy 63.036151 -293.225316) (xy 63.083422 -293.239008) (xy 63.127884 -293.260106) (xy 63.168387 -293.288062)
			(xy 63.20388 -293.322154) (xy 63.233445 -293.361498) (xy 63.256316 -293.405075) (xy 63.2719 -293.451756)
			(xy 63.279795 -293.500333) (xy 63.28029 -293.52494) (xy 63.619138 -293.52494) (xy 63.623098 -293.475886)
			(xy 63.634875 -293.428102) (xy 63.654166 -293.382826) (xy 63.680469 -293.34123) (xy 63.713104 -293.304393)
			(xy 63.751225 -293.273268) (xy 63.793846 -293.248661) (xy 63.839862 -293.231209) (xy 63.888081 -293.221365)
			(xy 63.937256 -293.219384) (xy 63.986111 -293.225316) (xy 64.033382 -293.239008) (xy 64.077844 -293.260106)
			(xy 64.118347 -293.288062) (xy 64.15384 -293.322154) (xy 64.183405 -293.361498) (xy 64.206276 -293.405075)
			(xy 64.22186 -293.451756) (xy 64.229755 -293.500333) (xy 64.23025 -293.52494) (xy 64.569098 -293.52494)
			(xy 64.573058 -293.475886) (xy 64.584835 -293.428102) (xy 64.604126 -293.382826) (xy 64.630429 -293.34123)
			(xy 64.663064 -293.304393) (xy 64.701185 -293.273268) (xy 64.743806 -293.248661) (xy 64.789822 -293.231209)
			(xy 64.838041 -293.221365) (xy 64.887216 -293.219384) (xy 64.936071 -293.225316) (xy 64.983342 -293.239008)
			(xy 65.027804 -293.260106) (xy 65.068307 -293.288062) (xy 65.1038 -293.322154) (xy 65.133365 -293.361498)
			(xy 65.156236 -293.405075) (xy 65.17182 -293.451756) (xy 65.179715 -293.500333) (xy 65.18021 -293.52494)
			(xy 65.519058 -293.52494) (xy 65.523018 -293.475886) (xy 65.534795 -293.428102) (xy 65.554086 -293.382826)
			(xy 65.580389 -293.34123) (xy 65.613024 -293.304393) (xy 65.651145 -293.273268) (xy 65.693766 -293.248661)
			(xy 65.739782 -293.231209) (xy 65.788001 -293.221365) (xy 65.837176 -293.219384) (xy 65.886031 -293.225316)
			(xy 65.933302 -293.239008) (xy 65.977764 -293.260106) (xy 66.018267 -293.288062) (xy 66.05376 -293.322154)
			(xy 66.083325 -293.361498) (xy 66.106196 -293.405075) (xy 66.12178 -293.451756) (xy 66.129675 -293.500333)
			(xy 66.13017 -293.52494) (xy 66.469018 -293.52494) (xy 66.472978 -293.475886) (xy 66.484755 -293.428102)
			(xy 66.504046 -293.382826) (xy 66.530349 -293.34123) (xy 66.562984 -293.304393) (xy 66.601105 -293.273268)
			(xy 66.643726 -293.248661) (xy 66.689742 -293.231209) (xy 66.737961 -293.221365) (xy 66.787136 -293.219384)
			(xy 66.835991 -293.225316) (xy 66.883262 -293.239008) (xy 66.927724 -293.260106) (xy 66.968227 -293.288062)
			(xy 67.00372 -293.322154) (xy 67.033285 -293.361498) (xy 67.056156 -293.405075) (xy 67.07174 -293.451756)
			(xy 67.079635 -293.500333) (xy 67.08013 -293.52494) (xy 67.418978 -293.52494) (xy 67.422938 -293.475886)
			(xy 67.434715 -293.428102) (xy 67.454006 -293.382826) (xy 67.480309 -293.34123) (xy 67.512944 -293.304393)
			(xy 67.551065 -293.273268) (xy 67.593686 -293.248661) (xy 67.639702 -293.231209) (xy 67.687921 -293.221365)
			(xy 67.737096 -293.219384) (xy 67.785951 -293.225316) (xy 67.833222 -293.239008) (xy 67.877684 -293.260106)
			(xy 67.918187 -293.288062) (xy 67.95368 -293.322154) (xy 67.983245 -293.361498) (xy 68.006116 -293.405075)
			(xy 68.0217 -293.451756) (xy 68.029595 -293.500333) (xy 68.03009 -293.52494) (xy 68.368938 -293.52494)
			(xy 68.372898 -293.475886) (xy 68.384675 -293.428102) (xy 68.403966 -293.382826) (xy 68.430269 -293.34123)
			(xy 68.462904 -293.304393) (xy 68.501025 -293.273268) (xy 68.543646 -293.248661) (xy 68.589662 -293.231209)
			(xy 68.637881 -293.221365) (xy 68.687056 -293.219384) (xy 68.735911 -293.225316) (xy 68.783182 -293.239008)
			(xy 68.827644 -293.260106) (xy 68.868147 -293.288062) (xy 68.90364 -293.322154) (xy 68.933205 -293.361498)
			(xy 68.956076 -293.405075) (xy 68.97166 -293.451756) (xy 68.979555 -293.500333) (xy 68.98005 -293.52494)
			(xy 69.319152 -293.52494) (xy 69.323112 -293.475886) (xy 69.334889 -293.428102) (xy 69.35418 -293.382826)
			(xy 69.380483 -293.34123) (xy 69.413118 -293.304393) (xy 69.451239 -293.273268) (xy 69.49386 -293.248661)
			(xy 69.539876 -293.231209) (xy 69.588095 -293.221365) (xy 69.63727 -293.219384) (xy 69.686125 -293.225316)
			(xy 69.733396 -293.239008) (xy 69.777858 -293.260106) (xy 69.818361 -293.288062) (xy 69.853854 -293.322154)
			(xy 69.883419 -293.361498) (xy 69.90629 -293.405075) (xy 69.921874 -293.451756) (xy 69.929769 -293.500333)
			(xy 69.930264 -293.52494) (xy 70.269112 -293.52494) (xy 70.273072 -293.475886) (xy 70.284849 -293.428102)
			(xy 70.30414 -293.382826) (xy 70.330443 -293.34123) (xy 70.363078 -293.304393) (xy 70.401199 -293.273268)
			(xy 70.44382 -293.248661) (xy 70.489836 -293.231209) (xy 70.538055 -293.221365) (xy 70.58723 -293.219384)
			(xy 70.636085 -293.225316) (xy 70.683356 -293.239008) (xy 70.727818 -293.260106) (xy 70.768321 -293.288062)
			(xy 70.803814 -293.322154) (xy 70.833379 -293.361498) (xy 70.85625 -293.405075) (xy 70.871834 -293.451756)
			(xy 70.879729 -293.500333) (xy 70.880224 -293.52494) (xy 71.219072 -293.52494) (xy 71.223032 -293.475886)
			(xy 71.234809 -293.428102) (xy 71.2541 -293.382826) (xy 71.280403 -293.34123) (xy 71.313038 -293.304393)
			(xy 71.351159 -293.273268) (xy 71.39378 -293.248661) (xy 71.439796 -293.231209) (xy 71.488015 -293.221365)
			(xy 71.53719 -293.219384) (xy 71.586045 -293.225316) (xy 71.633316 -293.239008) (xy 71.677778 -293.260106)
			(xy 71.718281 -293.288062) (xy 71.753774 -293.322154) (xy 71.783339 -293.361498) (xy 71.80621 -293.405075)
			(xy 71.821794 -293.451756) (xy 71.829689 -293.500333) (xy 71.830184 -293.52494) (xy 72.169032 -293.52494)
			(xy 72.172992 -293.475886) (xy 72.184769 -293.428102) (xy 72.20406 -293.382826) (xy 72.230363 -293.34123)
			(xy 72.262998 -293.304393) (xy 72.301119 -293.273268) (xy 72.34374 -293.248661) (xy 72.389756 -293.231209)
			(xy 72.437975 -293.221365) (xy 72.48715 -293.219384) (xy 72.536005 -293.225316) (xy 72.583276 -293.239008)
			(xy 72.627738 -293.260106) (xy 72.668241 -293.288062) (xy 72.703734 -293.322154) (xy 72.733299 -293.361498)
			(xy 72.75617 -293.405075) (xy 72.771754 -293.451756) (xy 72.779649 -293.500333) (xy 72.780144 -293.52494)
			(xy 73.118992 -293.52494) (xy 73.122952 -293.475886) (xy 73.134729 -293.428102) (xy 73.15402 -293.382826)
			(xy 73.180323 -293.34123) (xy 73.212958 -293.304393) (xy 73.251079 -293.273268) (xy 73.2937 -293.248661)
			(xy 73.339716 -293.231209) (xy 73.387935 -293.221365) (xy 73.43711 -293.219384) (xy 73.485965 -293.225316)
			(xy 73.533236 -293.239008) (xy 73.577698 -293.260106) (xy 73.618201 -293.288062) (xy 73.653694 -293.322154)
			(xy 73.683259 -293.361498) (xy 73.70613 -293.405075) (xy 73.721714 -293.451756) (xy 73.729609 -293.500333)
			(xy 73.730104 -293.52494) (xy 74.069206 -293.52494) (xy 74.073166 -293.475886) (xy 74.084943 -293.428102)
			(xy 74.104234 -293.382826) (xy 74.130537 -293.34123) (xy 74.163172 -293.304393) (xy 74.201293 -293.273268)
			(xy 74.243914 -293.248661) (xy 74.28993 -293.231209) (xy 74.338149 -293.221365) (xy 74.387324 -293.219384)
			(xy 74.436179 -293.225316) (xy 74.48345 -293.239008) (xy 74.527912 -293.260106) (xy 74.568415 -293.288062)
			(xy 74.603908 -293.322154) (xy 74.633473 -293.361498) (xy 74.656344 -293.405075) (xy 74.671928 -293.451756)
			(xy 74.679823 -293.500333) (xy 74.680318 -293.52494) (xy 75.019166 -293.52494) (xy 75.023126 -293.475886)
			(xy 75.034903 -293.428102) (xy 75.054194 -293.382826) (xy 75.080497 -293.34123) (xy 75.113132 -293.304393)
			(xy 75.151253 -293.273268) (xy 75.193874 -293.248661) (xy 75.23989 -293.231209) (xy 75.288109 -293.221365)
			(xy 75.337284 -293.219384) (xy 75.386139 -293.225316) (xy 75.43341 -293.239008) (xy 75.477872 -293.260106)
			(xy 75.518375 -293.288062) (xy 75.553868 -293.322154) (xy 75.583433 -293.361498) (xy 75.606304 -293.405075)
			(xy 75.621888 -293.451756) (xy 75.629783 -293.500333) (xy 75.630278 -293.52494) (xy 75.969126 -293.52494)
			(xy 75.973086 -293.475886) (xy 75.984863 -293.428102) (xy 76.004154 -293.382826) (xy 76.030457 -293.34123)
			(xy 76.063092 -293.304393) (xy 76.101213 -293.273268) (xy 76.143834 -293.248661) (xy 76.18985 -293.231209)
			(xy 76.238069 -293.221365) (xy 76.287244 -293.219384) (xy 76.336099 -293.225316) (xy 76.38337 -293.239008)
			(xy 76.427832 -293.260106) (xy 76.468335 -293.288062) (xy 76.503828 -293.322154) (xy 76.533393 -293.361498)
			(xy 76.556264 -293.405075) (xy 76.571848 -293.451756) (xy 76.579743 -293.500333) (xy 76.580238 -293.52494)
			(xy 76.919086 -293.52494) (xy 76.923046 -293.475886) (xy 76.934823 -293.428102) (xy 76.954114 -293.382826)
			(xy 76.980417 -293.34123) (xy 77.013052 -293.304393) (xy 77.051173 -293.273268) (xy 77.093794 -293.248661)
			(xy 77.13981 -293.231209) (xy 77.188029 -293.221365) (xy 77.237204 -293.219384) (xy 77.286059 -293.225316)
			(xy 77.33333 -293.239008) (xy 77.377792 -293.260106) (xy 77.418295 -293.288062) (xy 77.453788 -293.322154)
			(xy 77.483353 -293.361498) (xy 77.506224 -293.405075) (xy 77.521808 -293.451756) (xy 77.529703 -293.500333)
			(xy 77.530198 -293.52494) (xy 77.869046 -293.52494) (xy 77.873006 -293.475886) (xy 77.884783 -293.428102)
			(xy 77.904074 -293.382826) (xy 77.930377 -293.34123) (xy 77.963012 -293.304393) (xy 78.001133 -293.273268)
			(xy 78.043754 -293.248661) (xy 78.08977 -293.231209) (xy 78.137989 -293.221365) (xy 78.187164 -293.219384)
			(xy 78.236019 -293.225316) (xy 78.28329 -293.239008) (xy 78.327752 -293.260106) (xy 78.368255 -293.288062)
			(xy 78.403748 -293.322154) (xy 78.433313 -293.361498) (xy 78.456184 -293.405075) (xy 78.471768 -293.451756)
			(xy 78.479663 -293.500333) (xy 78.480158 -293.52494) (xy 78.819006 -293.52494) (xy 78.822966 -293.475886)
			(xy 78.834743 -293.428102) (xy 78.854034 -293.382826) (xy 78.880337 -293.34123) (xy 78.912972 -293.304393)
			(xy 78.951093 -293.273268) (xy 78.993714 -293.248661) (xy 79.03973 -293.231209) (xy 79.087949 -293.221365)
			(xy 79.137124 -293.219384) (xy 79.185979 -293.225316) (xy 79.23325 -293.239008) (xy 79.277712 -293.260106)
			(xy 79.318215 -293.288062) (xy 79.353708 -293.322154) (xy 79.383273 -293.361498) (xy 79.406144 -293.405075)
			(xy 79.421728 -293.451756) (xy 79.429623 -293.500333) (xy 79.430118 -293.52494) (xy 79.768966 -293.52494)
			(xy 79.772926 -293.475886) (xy 79.784703 -293.428102) (xy 79.803994 -293.382826) (xy 79.830297 -293.34123)
			(xy 79.862932 -293.304393) (xy 79.901053 -293.273268) (xy 79.943674 -293.248661) (xy 79.98969 -293.231209)
			(xy 80.037909 -293.221365) (xy 80.087084 -293.219384) (xy 80.135939 -293.225316) (xy 80.18321 -293.239008)
			(xy 80.227672 -293.260106) (xy 80.268175 -293.288062) (xy 80.303668 -293.322154) (xy 80.333233 -293.361498)
			(xy 80.356104 -293.405075) (xy 80.371688 -293.451756) (xy 80.379583 -293.500333) (xy 80.380078 -293.52494)
			(xy 80.71918 -293.52494) (xy 80.72314 -293.475886) (xy 80.734917 -293.428102) (xy 80.754208 -293.382826)
			(xy 80.780511 -293.34123) (xy 80.813146 -293.304393) (xy 80.851267 -293.273268) (xy 80.893888 -293.248661)
			(xy 80.939904 -293.231209) (xy 80.988123 -293.221365) (xy 81.037298 -293.219384) (xy 81.086153 -293.225316)
			(xy 81.133424 -293.239008) (xy 81.177886 -293.260106) (xy 81.218389 -293.288062) (xy 81.253882 -293.322154)
			(xy 81.283447 -293.361498) (xy 81.306318 -293.405075) (xy 81.321902 -293.451756) (xy 81.329797 -293.500333)
			(xy 81.330292 -293.52494) (xy 81.66914 -293.52494) (xy 81.6731 -293.475886) (xy 81.684877 -293.428102)
			(xy 81.704168 -293.382826) (xy 81.730471 -293.34123) (xy 81.763106 -293.304393) (xy 81.801227 -293.273268)
			(xy 81.843848 -293.248661) (xy 81.889864 -293.231209) (xy 81.938083 -293.221365) (xy 81.987258 -293.219384)
			(xy 82.036113 -293.225316) (xy 82.083384 -293.239008) (xy 82.127846 -293.260106) (xy 82.168349 -293.288062)
			(xy 82.203842 -293.322154) (xy 82.233407 -293.361498) (xy 82.256278 -293.405075) (xy 82.271862 -293.451756)
			(xy 82.279757 -293.500333) (xy 82.280252 -293.52494) (xy 82.6191 -293.52494) (xy 82.62306 -293.475886)
			(xy 82.634837 -293.428102) (xy 82.654128 -293.382826) (xy 82.680431 -293.34123) (xy 82.713066 -293.304393)
			(xy 82.751187 -293.273268) (xy 82.793808 -293.248661) (xy 82.839824 -293.231209) (xy 82.888043 -293.221365)
			(xy 82.937218 -293.219384) (xy 82.986073 -293.225316) (xy 83.033344 -293.239008) (xy 83.077806 -293.260106)
			(xy 83.118309 -293.288062) (xy 83.153802 -293.322154) (xy 83.183367 -293.361498) (xy 83.206238 -293.405075)
			(xy 83.221822 -293.451756) (xy 83.229717 -293.500333) (xy 83.230212 -293.52494) (xy 83.229717 -293.549547)
			(xy 83.221822 -293.598124) (xy 83.206238 -293.644805) (xy 83.183367 -293.688382) (xy 83.153802 -293.727726)
			(xy 83.118309 -293.761818) (xy 83.077806 -293.789774) (xy 83.033344 -293.810872) (xy 82.986073 -293.824564)
			(xy 82.937218 -293.830496) (xy 82.888043 -293.828515) (xy 82.839824 -293.818671) (xy 82.793808 -293.801219)
			(xy 82.751187 -293.776612) (xy 82.713066 -293.745487) (xy 82.680431 -293.70865) (xy 82.654128 -293.667054)
			(xy 82.634837 -293.621778) (xy 82.62306 -293.573994) (xy 82.6191 -293.52494) (xy 82.280252 -293.52494)
			(xy 82.279757 -293.549547) (xy 82.271862 -293.598124) (xy 82.256278 -293.644805) (xy 82.233407 -293.688382)
			(xy 82.203842 -293.727726) (xy 82.168349 -293.761818) (xy 82.127846 -293.789774) (xy 82.083384 -293.810872)
			(xy 82.036113 -293.824564) (xy 81.987258 -293.830496) (xy 81.938083 -293.828515) (xy 81.889864 -293.818671)
			(xy 81.843848 -293.801219) (xy 81.801227 -293.776612) (xy 81.763106 -293.745487) (xy 81.730471 -293.70865)
			(xy 81.704168 -293.667054) (xy 81.684877 -293.621778) (xy 81.6731 -293.573994) (xy 81.66914 -293.52494)
			(xy 81.330292 -293.52494) (xy 81.329797 -293.549547) (xy 81.321902 -293.598124) (xy 81.306318 -293.644805)
			(xy 81.283447 -293.688382) (xy 81.253882 -293.727726) (xy 81.218389 -293.761818) (xy 81.177886 -293.789774)
			(xy 81.133424 -293.810872) (xy 81.086153 -293.824564) (xy 81.037298 -293.830496) (xy 80.988123 -293.828515)
			(xy 80.939904 -293.818671) (xy 80.893888 -293.801219) (xy 80.851267 -293.776612) (xy 80.813146 -293.745487)
			(xy 80.780511 -293.70865) (xy 80.754208 -293.667054) (xy 80.734917 -293.621778) (xy 80.72314 -293.573994)
			(xy 80.71918 -293.52494) (xy 80.380078 -293.52494) (xy 80.379583 -293.549547) (xy 80.371688 -293.598124)
			(xy 80.356104 -293.644805) (xy 80.333233 -293.688382) (xy 80.303668 -293.727726) (xy 80.268175 -293.761818)
			(xy 80.227672 -293.789774) (xy 80.18321 -293.810872) (xy 80.135939 -293.824564) (xy 80.087084 -293.830496)
			(xy 80.037909 -293.828515) (xy 79.98969 -293.818671) (xy 79.943674 -293.801219) (xy 79.901053 -293.776612)
			(xy 79.862932 -293.745487) (xy 79.830297 -293.70865) (xy 79.803994 -293.667054) (xy 79.784703 -293.621778)
			(xy 79.772926 -293.573994) (xy 79.768966 -293.52494) (xy 79.430118 -293.52494) (xy 79.429623 -293.549547)
			(xy 79.421728 -293.598124) (xy 79.406144 -293.644805) (xy 79.383273 -293.688382) (xy 79.353708 -293.727726)
			(xy 79.318215 -293.761818) (xy 79.277712 -293.789774) (xy 79.23325 -293.810872) (xy 79.185979 -293.824564)
			(xy 79.137124 -293.830496) (xy 79.087949 -293.828515) (xy 79.03973 -293.818671) (xy 78.993714 -293.801219)
			(xy 78.951093 -293.776612) (xy 78.912972 -293.745487) (xy 78.880337 -293.70865) (xy 78.854034 -293.667054)
			(xy 78.834743 -293.621778) (xy 78.822966 -293.573994) (xy 78.819006 -293.52494) (xy 78.480158 -293.52494)
			(xy 78.479663 -293.549547) (xy 78.471768 -293.598124) (xy 78.456184 -293.644805) (xy 78.433313 -293.688382)
			(xy 78.403748 -293.727726) (xy 78.368255 -293.761818) (xy 78.327752 -293.789774) (xy 78.28329 -293.810872)
			(xy 78.236019 -293.824564) (xy 78.187164 -293.830496) (xy 78.137989 -293.828515) (xy 78.08977 -293.818671)
			(xy 78.043754 -293.801219) (xy 78.001133 -293.776612) (xy 77.963012 -293.745487) (xy 77.930377 -293.70865)
			(xy 77.904074 -293.667054) (xy 77.884783 -293.621778) (xy 77.873006 -293.573994) (xy 77.869046 -293.52494)
			(xy 77.530198 -293.52494) (xy 77.529703 -293.549547) (xy 77.521808 -293.598124) (xy 77.506224 -293.644805)
			(xy 77.483353 -293.688382) (xy 77.453788 -293.727726) (xy 77.418295 -293.761818) (xy 77.377792 -293.789774)
			(xy 77.33333 -293.810872) (xy 77.286059 -293.824564) (xy 77.237204 -293.830496) (xy 77.188029 -293.828515)
			(xy 77.13981 -293.818671) (xy 77.093794 -293.801219) (xy 77.051173 -293.776612) (xy 77.013052 -293.745487)
			(xy 76.980417 -293.70865) (xy 76.954114 -293.667054) (xy 76.934823 -293.621778) (xy 76.923046 -293.573994)
			(xy 76.919086 -293.52494) (xy 76.580238 -293.52494) (xy 76.579743 -293.549547) (xy 76.571848 -293.598124)
			(xy 76.556264 -293.644805) (xy 76.533393 -293.688382) (xy 76.503828 -293.727726) (xy 76.468335 -293.761818)
			(xy 76.427832 -293.789774) (xy 76.38337 -293.810872) (xy 76.336099 -293.824564) (xy 76.287244 -293.830496)
			(xy 76.238069 -293.828515) (xy 76.18985 -293.818671) (xy 76.143834 -293.801219) (xy 76.101213 -293.776612)
			(xy 76.063092 -293.745487) (xy 76.030457 -293.70865) (xy 76.004154 -293.667054) (xy 75.984863 -293.621778)
			(xy 75.973086 -293.573994) (xy 75.969126 -293.52494) (xy 75.630278 -293.52494) (xy 75.629783 -293.549547)
			(xy 75.621888 -293.598124) (xy 75.606304 -293.644805) (xy 75.583433 -293.688382) (xy 75.553868 -293.727726)
			(xy 75.518375 -293.761818) (xy 75.477872 -293.789774) (xy 75.43341 -293.810872) (xy 75.386139 -293.824564)
			(xy 75.337284 -293.830496) (xy 75.288109 -293.828515) (xy 75.23989 -293.818671) (xy 75.193874 -293.801219)
			(xy 75.151253 -293.776612) (xy 75.113132 -293.745487) (xy 75.080497 -293.70865) (xy 75.054194 -293.667054)
			(xy 75.034903 -293.621778) (xy 75.023126 -293.573994) (xy 75.019166 -293.52494) (xy 74.680318 -293.52494)
			(xy 74.679823 -293.549547) (xy 74.671928 -293.598124) (xy 74.656344 -293.644805) (xy 74.633473 -293.688382)
			(xy 74.603908 -293.727726) (xy 74.568415 -293.761818) (xy 74.527912 -293.789774) (xy 74.48345 -293.810872)
			(xy 74.436179 -293.824564) (xy 74.387324 -293.830496) (xy 74.338149 -293.828515) (xy 74.28993 -293.818671)
			(xy 74.243914 -293.801219) (xy 74.201293 -293.776612) (xy 74.163172 -293.745487) (xy 74.130537 -293.70865)
			(xy 74.104234 -293.667054) (xy 74.084943 -293.621778) (xy 74.073166 -293.573994) (xy 74.069206 -293.52494)
			(xy 73.730104 -293.52494) (xy 73.729609 -293.549547) (xy 73.721714 -293.598124) (xy 73.70613 -293.644805)
			(xy 73.683259 -293.688382) (xy 73.653694 -293.727726) (xy 73.618201 -293.761818) (xy 73.577698 -293.789774)
			(xy 73.533236 -293.810872) (xy 73.485965 -293.824564) (xy 73.43711 -293.830496) (xy 73.387935 -293.828515)
			(xy 73.339716 -293.818671) (xy 73.2937 -293.801219) (xy 73.251079 -293.776612) (xy 73.212958 -293.745487)
			(xy 73.180323 -293.70865) (xy 73.15402 -293.667054) (xy 73.134729 -293.621778) (xy 73.122952 -293.573994)
			(xy 73.118992 -293.52494) (xy 72.780144 -293.52494) (xy 72.779649 -293.549547) (xy 72.771754 -293.598124)
			(xy 72.75617 -293.644805) (xy 72.733299 -293.688382) (xy 72.703734 -293.727726) (xy 72.668241 -293.761818)
			(xy 72.627738 -293.789774) (xy 72.583276 -293.810872) (xy 72.536005 -293.824564) (xy 72.48715 -293.830496)
			(xy 72.437975 -293.828515) (xy 72.389756 -293.818671) (xy 72.34374 -293.801219) (xy 72.301119 -293.776612)
			(xy 72.262998 -293.745487) (xy 72.230363 -293.70865) (xy 72.20406 -293.667054) (xy 72.184769 -293.621778)
			(xy 72.172992 -293.573994) (xy 72.169032 -293.52494) (xy 71.830184 -293.52494) (xy 71.829689 -293.549547)
			(xy 71.821794 -293.598124) (xy 71.80621 -293.644805) (xy 71.783339 -293.688382) (xy 71.753774 -293.727726)
			(xy 71.718281 -293.761818) (xy 71.677778 -293.789774) (xy 71.633316 -293.810872) (xy 71.586045 -293.824564)
			(xy 71.53719 -293.830496) (xy 71.488015 -293.828515) (xy 71.439796 -293.818671) (xy 71.39378 -293.801219)
			(xy 71.351159 -293.776612) (xy 71.313038 -293.745487) (xy 71.280403 -293.70865) (xy 71.2541 -293.667054)
			(xy 71.234809 -293.621778) (xy 71.223032 -293.573994) (xy 71.219072 -293.52494) (xy 70.880224 -293.52494)
			(xy 70.879729 -293.549547) (xy 70.871834 -293.598124) (xy 70.85625 -293.644805) (xy 70.833379 -293.688382)
			(xy 70.803814 -293.727726) (xy 70.768321 -293.761818) (xy 70.727818 -293.789774) (xy 70.683356 -293.810872)
			(xy 70.636085 -293.824564) (xy 70.58723 -293.830496) (xy 70.538055 -293.828515) (xy 70.489836 -293.818671)
			(xy 70.44382 -293.801219) (xy 70.401199 -293.776612) (xy 70.363078 -293.745487) (xy 70.330443 -293.70865)
			(xy 70.30414 -293.667054) (xy 70.284849 -293.621778) (xy 70.273072 -293.573994) (xy 70.269112 -293.52494)
			(xy 69.930264 -293.52494) (xy 69.929769 -293.549547) (xy 69.921874 -293.598124) (xy 69.90629 -293.644805)
			(xy 69.883419 -293.688382) (xy 69.853854 -293.727726) (xy 69.818361 -293.761818) (xy 69.777858 -293.789774)
			(xy 69.733396 -293.810872) (xy 69.686125 -293.824564) (xy 69.63727 -293.830496) (xy 69.588095 -293.828515)
			(xy 69.539876 -293.818671) (xy 69.49386 -293.801219) (xy 69.451239 -293.776612) (xy 69.413118 -293.745487)
			(xy 69.380483 -293.70865) (xy 69.35418 -293.667054) (xy 69.334889 -293.621778) (xy 69.323112 -293.573994)
			(xy 69.319152 -293.52494) (xy 68.98005 -293.52494) (xy 68.979555 -293.549547) (xy 68.97166 -293.598124)
			(xy 68.956076 -293.644805) (xy 68.933205 -293.688382) (xy 68.90364 -293.727726) (xy 68.868147 -293.761818)
			(xy 68.827644 -293.789774) (xy 68.783182 -293.810872) (xy 68.735911 -293.824564) (xy 68.687056 -293.830496)
			(xy 68.637881 -293.828515) (xy 68.589662 -293.818671) (xy 68.543646 -293.801219) (xy 68.501025 -293.776612)
			(xy 68.462904 -293.745487) (xy 68.430269 -293.70865) (xy 68.403966 -293.667054) (xy 68.384675 -293.621778)
			(xy 68.372898 -293.573994) (xy 68.368938 -293.52494) (xy 68.03009 -293.52494) (xy 68.029595 -293.549547)
			(xy 68.0217 -293.598124) (xy 68.006116 -293.644805) (xy 67.983245 -293.688382) (xy 67.95368 -293.727726)
			(xy 67.918187 -293.761818) (xy 67.877684 -293.789774) (xy 67.833222 -293.810872) (xy 67.785951 -293.824564)
			(xy 67.737096 -293.830496) (xy 67.687921 -293.828515) (xy 67.639702 -293.818671) (xy 67.593686 -293.801219)
			(xy 67.551065 -293.776612) (xy 67.512944 -293.745487) (xy 67.480309 -293.70865) (xy 67.454006 -293.667054)
			(xy 67.434715 -293.621778) (xy 67.422938 -293.573994) (xy 67.418978 -293.52494) (xy 67.08013 -293.52494)
			(xy 67.079635 -293.549547) (xy 67.07174 -293.598124) (xy 67.056156 -293.644805) (xy 67.033285 -293.688382)
			(xy 67.00372 -293.727726) (xy 66.968227 -293.761818) (xy 66.927724 -293.789774) (xy 66.883262 -293.810872)
			(xy 66.835991 -293.824564) (xy 66.787136 -293.830496) (xy 66.737961 -293.828515) (xy 66.689742 -293.818671)
			(xy 66.643726 -293.801219) (xy 66.601105 -293.776612) (xy 66.562984 -293.745487) (xy 66.530349 -293.70865)
			(xy 66.504046 -293.667054) (xy 66.484755 -293.621778) (xy 66.472978 -293.573994) (xy 66.469018 -293.52494)
			(xy 66.13017 -293.52494) (xy 66.129675 -293.549547) (xy 66.12178 -293.598124) (xy 66.106196 -293.644805)
			(xy 66.083325 -293.688382) (xy 66.05376 -293.727726) (xy 66.018267 -293.761818) (xy 65.977764 -293.789774)
			(xy 65.933302 -293.810872) (xy 65.886031 -293.824564) (xy 65.837176 -293.830496) (xy 65.788001 -293.828515)
			(xy 65.739782 -293.818671) (xy 65.693766 -293.801219) (xy 65.651145 -293.776612) (xy 65.613024 -293.745487)
			(xy 65.580389 -293.70865) (xy 65.554086 -293.667054) (xy 65.534795 -293.621778) (xy 65.523018 -293.573994)
			(xy 65.519058 -293.52494) (xy 65.18021 -293.52494) (xy 65.179715 -293.549547) (xy 65.17182 -293.598124)
			(xy 65.156236 -293.644805) (xy 65.133365 -293.688382) (xy 65.1038 -293.727726) (xy 65.068307 -293.761818)
			(xy 65.027804 -293.789774) (xy 64.983342 -293.810872) (xy 64.936071 -293.824564) (xy 64.887216 -293.830496)
			(xy 64.838041 -293.828515) (xy 64.789822 -293.818671) (xy 64.743806 -293.801219) (xy 64.701185 -293.776612)
			(xy 64.663064 -293.745487) (xy 64.630429 -293.70865) (xy 64.604126 -293.667054) (xy 64.584835 -293.621778)
			(xy 64.573058 -293.573994) (xy 64.569098 -293.52494) (xy 64.23025 -293.52494) (xy 64.229755 -293.549547)
			(xy 64.22186 -293.598124) (xy 64.206276 -293.644805) (xy 64.183405 -293.688382) (xy 64.15384 -293.727726)
			(xy 64.118347 -293.761818) (xy 64.077844 -293.789774) (xy 64.033382 -293.810872) (xy 63.986111 -293.824564)
			(xy 63.937256 -293.830496) (xy 63.888081 -293.828515) (xy 63.839862 -293.818671) (xy 63.793846 -293.801219)
			(xy 63.751225 -293.776612) (xy 63.713104 -293.745487) (xy 63.680469 -293.70865) (xy 63.654166 -293.667054)
			(xy 63.634875 -293.621778) (xy 63.623098 -293.573994) (xy 63.619138 -293.52494) (xy 63.28029 -293.52494)
			(xy 63.279795 -293.549547) (xy 63.2719 -293.598124) (xy 63.256316 -293.644805) (xy 63.233445 -293.688382)
			(xy 63.20388 -293.727726) (xy 63.168387 -293.761818) (xy 63.127884 -293.789774) (xy 63.083422 -293.810872)
			(xy 63.036151 -293.824564) (xy 62.987296 -293.830496) (xy 62.938121 -293.828515) (xy 62.889902 -293.818671)
			(xy 62.843886 -293.801219) (xy 62.801265 -293.776612) (xy 62.763144 -293.745487) (xy 62.730509 -293.70865)
			(xy 62.704206 -293.667054) (xy 62.684915 -293.621778) (xy 62.673138 -293.573994) (xy 62.669178 -293.52494)
			(xy 62.330076 -293.52494) (xy 62.329581 -293.549547) (xy 62.321686 -293.598124) (xy 62.306102 -293.644805)
			(xy 62.283231 -293.688382) (xy 62.253666 -293.727726) (xy 62.218173 -293.761818) (xy 62.17767 -293.789774)
			(xy 62.133208 -293.810872) (xy 62.085937 -293.824564) (xy 62.037082 -293.830496) (xy 61.987907 -293.828515)
			(xy 61.939688 -293.818671) (xy 61.893672 -293.801219) (xy 61.851051 -293.776612) (xy 61.81293 -293.745487)
			(xy 61.780295 -293.70865) (xy 61.753992 -293.667054) (xy 61.734701 -293.621778) (xy 61.722924 -293.573994)
			(xy 61.718964 -293.52494) (xy 61.380116 -293.52494) (xy 61.379621 -293.549547) (xy 61.371726 -293.598124)
			(xy 61.356142 -293.644805) (xy 61.333271 -293.688382) (xy 61.303706 -293.727726) (xy 61.268213 -293.761818)
			(xy 61.22771 -293.789774) (xy 61.183248 -293.810872) (xy 61.135977 -293.824564) (xy 61.087122 -293.830496)
			(xy 61.037947 -293.828515) (xy 60.989728 -293.818671) (xy 60.943712 -293.801219) (xy 60.901091 -293.776612)
			(xy 60.86297 -293.745487) (xy 60.830335 -293.70865) (xy 60.804032 -293.667054) (xy 60.784741 -293.621778)
			(xy 60.772964 -293.573994) (xy 60.769004 -293.52494) (xy 60.430156 -293.52494) (xy 60.429661 -293.549547)
			(xy 60.421766 -293.598124) (xy 60.406182 -293.644805) (xy 60.383311 -293.688382) (xy 60.353746 -293.727726)
			(xy 60.318253 -293.761818) (xy 60.27775 -293.789774) (xy 60.233288 -293.810872) (xy 60.186017 -293.824564)
			(xy 60.137162 -293.830496) (xy 60.087987 -293.828515) (xy 60.039768 -293.818671) (xy 59.993752 -293.801219)
			(xy 59.951131 -293.776612) (xy 59.91301 -293.745487) (xy 59.880375 -293.70865) (xy 59.854072 -293.667054)
			(xy 59.834781 -293.621778) (xy 59.823004 -293.573994) (xy 59.819044 -293.52494) (xy 58.530236 -293.52494)
			(xy 58.529741 -293.549547) (xy 58.521846 -293.598124) (xy 58.506262 -293.644805) (xy 58.483391 -293.688382)
			(xy 58.453826 -293.727726) (xy 58.418333 -293.761818) (xy 58.37783 -293.789774) (xy 58.333368 -293.810872)
			(xy 58.286097 -293.824564) (xy 58.237242 -293.830496) (xy 58.188067 -293.828515) (xy 58.139848 -293.818671)
			(xy 58.093832 -293.801219) (xy 58.051211 -293.776612) (xy 58.01309 -293.745487) (xy 57.980455 -293.70865)
			(xy 57.954152 -293.667054) (xy 57.934861 -293.621778) (xy 57.923084 -293.573994) (xy 57.919124 -293.52494)
			(xy 57.580276 -293.52494) (xy 57.579781 -293.549547) (xy 57.571886 -293.598124) (xy 57.556302 -293.644805)
			(xy 57.533431 -293.688382) (xy 57.503866 -293.727726) (xy 57.468373 -293.761818) (xy 57.42787 -293.789774)
			(xy 57.383408 -293.810872) (xy 57.336137 -293.824564) (xy 57.287282 -293.830496) (xy 57.238107 -293.828515)
			(xy 57.189888 -293.818671) (xy 57.143872 -293.801219) (xy 57.101251 -293.776612) (xy 57.06313 -293.745487)
			(xy 57.030495 -293.70865) (xy 57.004192 -293.667054) (xy 56.984901 -293.621778) (xy 56.973124 -293.573994)
			(xy 56.969164 -293.52494) (xy 56.630062 -293.52494) (xy 56.629567 -293.549547) (xy 56.621672 -293.598124)
			(xy 56.606088 -293.644805) (xy 56.583217 -293.688382) (xy 56.553652 -293.727726) (xy 56.518159 -293.761818)
			(xy 56.477656 -293.789774) (xy 56.433194 -293.810872) (xy 56.385923 -293.824564) (xy 56.337068 -293.830496)
			(xy 56.287893 -293.828515) (xy 56.239674 -293.818671) (xy 56.193658 -293.801219) (xy 56.151037 -293.776612)
			(xy 56.112916 -293.745487) (xy 56.080281 -293.70865) (xy 56.053978 -293.667054) (xy 56.034687 -293.621778)
			(xy 56.02291 -293.573994) (xy 56.01895 -293.52494) (xy 55.680102 -293.52494) (xy 55.679607 -293.549547)
			(xy 55.671712 -293.598124) (xy 55.656128 -293.644805) (xy 55.633257 -293.688382) (xy 55.603692 -293.727726)
			(xy 55.568199 -293.761818) (xy 55.527696 -293.789774) (xy 55.483234 -293.810872) (xy 55.435963 -293.824564)
			(xy 55.387108 -293.830496) (xy 55.337933 -293.828515) (xy 55.289714 -293.818671) (xy 55.243698 -293.801219)
			(xy 55.201077 -293.776612) (xy 55.162956 -293.745487) (xy 55.130321 -293.70865) (xy 55.104018 -293.667054)
			(xy 55.084727 -293.621778) (xy 55.07295 -293.573994) (xy 55.06899 -293.52494) (xy 54.730142 -293.52494)
			(xy 54.729647 -293.549547) (xy 54.721752 -293.598124) (xy 54.706168 -293.644805) (xy 54.683297 -293.688382)
			(xy 54.653732 -293.727726) (xy 54.618239 -293.761818) (xy 54.577736 -293.789774) (xy 54.533274 -293.810872)
			(xy 54.486003 -293.824564) (xy 54.437148 -293.830496) (xy 54.387973 -293.828515) (xy 54.339754 -293.818671)
			(xy 54.293738 -293.801219) (xy 54.251117 -293.776612) (xy 54.212996 -293.745487) (xy 54.180361 -293.70865)
			(xy 54.154058 -293.667054) (xy 54.134767 -293.621778) (xy 54.12299 -293.573994) (xy 54.11903 -293.52494)
			(xy 53.780182 -293.52494) (xy 53.779687 -293.549547) (xy 53.771792 -293.598124) (xy 53.756208 -293.644805)
			(xy 53.733337 -293.688382) (xy 53.703772 -293.727726) (xy 53.668279 -293.761818) (xy 53.627776 -293.789774)
			(xy 53.583314 -293.810872) (xy 53.536043 -293.824564) (xy 53.487188 -293.830496) (xy 53.438013 -293.828515)
			(xy 53.389794 -293.818671) (xy 53.343778 -293.801219) (xy 53.301157 -293.776612) (xy 53.263036 -293.745487)
			(xy 53.230401 -293.70865) (xy 53.204098 -293.667054) (xy 53.184807 -293.621778) (xy 53.17303 -293.573994)
			(xy 53.16907 -293.52494) (xy 52.830222 -293.52494) (xy 52.829727 -293.549547) (xy 52.821832 -293.598124)
			(xy 52.806248 -293.644805) (xy 52.783377 -293.688382) (xy 52.753812 -293.727726) (xy 52.718319 -293.761818)
			(xy 52.677816 -293.789774) (xy 52.633354 -293.810872) (xy 52.586083 -293.824564) (xy 52.537228 -293.830496)
			(xy 52.488053 -293.828515) (xy 52.439834 -293.818671) (xy 52.393818 -293.801219) (xy 52.351197 -293.776612)
			(xy 52.313076 -293.745487) (xy 52.280441 -293.70865) (xy 52.254138 -293.667054) (xy 52.234847 -293.621778)
			(xy 52.22307 -293.573994) (xy 52.21911 -293.52494) (xy 51.880262 -293.52494) (xy 51.879767 -293.549547)
			(xy 51.871872 -293.598124) (xy 51.856288 -293.644805) (xy 51.833417 -293.688382) (xy 51.803852 -293.727726)
			(xy 51.768359 -293.761818) (xy 51.727856 -293.789774) (xy 51.683394 -293.810872) (xy 51.636123 -293.824564)
			(xy 51.587268 -293.830496) (xy 51.538093 -293.828515) (xy 51.489874 -293.818671) (xy 51.443858 -293.801219)
			(xy 51.401237 -293.776612) (xy 51.363116 -293.745487) (xy 51.330481 -293.70865) (xy 51.304178 -293.667054)
			(xy 51.284887 -293.621778) (xy 51.27311 -293.573994) (xy 51.26915 -293.52494) (xy 50.930302 -293.52494)
			(xy 50.929807 -293.549547) (xy 50.921912 -293.598124) (xy 50.906328 -293.644805) (xy 50.883457 -293.688382)
			(xy 50.853892 -293.727726) (xy 50.818399 -293.761818) (xy 50.777896 -293.789774) (xy 50.733434 -293.810872)
			(xy 50.686163 -293.824564) (xy 50.637308 -293.830496) (xy 50.588133 -293.828515) (xy 50.539914 -293.818671)
			(xy 50.493898 -293.801219) (xy 50.451277 -293.776612) (xy 50.413156 -293.745487) (xy 50.380521 -293.70865)
			(xy 50.354218 -293.667054) (xy 50.334927 -293.621778) (xy 50.32315 -293.573994) (xy 50.31919 -293.52494)
			(xy 49.980088 -293.52494) (xy 49.979593 -293.549547) (xy 49.971698 -293.598124) (xy 49.956114 -293.644805)
			(xy 49.933243 -293.688382) (xy 49.903678 -293.727726) (xy 49.868185 -293.761818) (xy 49.827682 -293.789774)
			(xy 49.78322 -293.810872) (xy 49.735949 -293.824564) (xy 49.687094 -293.830496) (xy 49.637919 -293.828515)
			(xy 49.5897 -293.818671) (xy 49.543684 -293.801219) (xy 49.501063 -293.776612) (xy 49.462942 -293.745487)
			(xy 49.430307 -293.70865) (xy 49.404004 -293.667054) (xy 49.384713 -293.621778) (xy 49.372936 -293.573994)
			(xy 49.368976 -293.52494) (xy 49.05576 -293.52494) (xy 49.052231 -293.574212) (xy 49.040533 -293.624636)
			(xy 49.021123 -293.672622) (xy 48.994474 -293.716997) (xy 48.961237 -293.756679) (xy 48.922224 -293.790699)
			(xy 48.878387 -293.818225) (xy 48.830796 -293.838586) (xy 48.805846 -293.845488) (xy 48.80483 -293.845742)
			(xy 48.80229 -293.846504) (xy 48.796448 -293.848536) (xy 48.786698 -293.852481) (xy 48.771293 -293.866768)
			(xy 48.762915 -293.886035) (xy 48.762412 -293.896542) (xy 48.762412 -294.121586) (xy 48.784256 -294.149018)
			(xy 48.801528 -294.153082) (xy 48.826588 -294.159582) (xy 48.874453 -294.179304) (xy 48.91866 -294.206243)
			(xy 48.958131 -294.239739) (xy 48.991902 -294.278977) (xy 49.019147 -294.322996) (xy 49.039202 -294.370722)
			(xy 49.051576 -294.42099) (xy 49.055968 -294.472572) (xy 49.055801 -294.4749) (xy 49.368976 -294.4749)
			(xy 49.372936 -294.425846) (xy 49.384713 -294.378062) (xy 49.404004 -294.332786) (xy 49.430307 -294.29119)
			(xy 49.462942 -294.254353) (xy 49.501063 -294.223228) (xy 49.543684 -294.198621) (xy 49.5897 -294.181169)
			(xy 49.637919 -294.171325) (xy 49.687094 -294.169344) (xy 49.735949 -294.175276) (xy 49.78322 -294.188968)
			(xy 49.827682 -294.210066) (xy 49.868185 -294.238022) (xy 49.903678 -294.272114) (xy 49.933243 -294.311458)
			(xy 49.956114 -294.355035) (xy 49.971698 -294.401716) (xy 49.979593 -294.450293) (xy 49.980088 -294.4749)
			(xy 50.31919 -294.4749) (xy 50.32315 -294.425846) (xy 50.334927 -294.378062) (xy 50.354218 -294.332786)
			(xy 50.380521 -294.29119) (xy 50.413156 -294.254353) (xy 50.451277 -294.223228) (xy 50.493898 -294.198621)
			(xy 50.539914 -294.181169) (xy 50.588133 -294.171325) (xy 50.637308 -294.169344) (xy 50.686163 -294.175276)
			(xy 50.733434 -294.188968) (xy 50.777896 -294.210066) (xy 50.818399 -294.238022) (xy 50.853892 -294.272114)
			(xy 50.883457 -294.311458) (xy 50.906328 -294.355035) (xy 50.921912 -294.401716) (xy 50.929807 -294.450293)
			(xy 50.930302 -294.4749) (xy 51.26915 -294.4749) (xy 51.27311 -294.425846) (xy 51.284887 -294.378062)
			(xy 51.304178 -294.332786) (xy 51.330481 -294.29119) (xy 51.363116 -294.254353) (xy 51.401237 -294.223228)
			(xy 51.443858 -294.198621) (xy 51.489874 -294.181169) (xy 51.538093 -294.171325) (xy 51.587268 -294.169344)
			(xy 51.636123 -294.175276) (xy 51.683394 -294.188968) (xy 51.727856 -294.210066) (xy 51.768359 -294.238022)
			(xy 51.803852 -294.272114) (xy 51.833417 -294.311458) (xy 51.856288 -294.355035) (xy 51.871872 -294.401716)
			(xy 51.879767 -294.450293) (xy 51.880262 -294.4749) (xy 52.21911 -294.4749) (xy 52.22307 -294.425846)
			(xy 52.234847 -294.378062) (xy 52.254138 -294.332786) (xy 52.280441 -294.29119) (xy 52.313076 -294.254353)
			(xy 52.351197 -294.223228) (xy 52.393818 -294.198621) (xy 52.439834 -294.181169) (xy 52.488053 -294.171325)
			(xy 52.537228 -294.169344) (xy 52.586083 -294.175276) (xy 52.633354 -294.188968) (xy 52.677816 -294.210066)
			(xy 52.718319 -294.238022) (xy 52.753812 -294.272114) (xy 52.783377 -294.311458) (xy 52.806248 -294.355035)
			(xy 52.821832 -294.401716) (xy 52.829727 -294.450293) (xy 52.830222 -294.4749) (xy 53.16907 -294.4749)
			(xy 53.17303 -294.425846) (xy 53.184807 -294.378062) (xy 53.204098 -294.332786) (xy 53.230401 -294.29119)
			(xy 53.263036 -294.254353) (xy 53.301157 -294.223228) (xy 53.343778 -294.198621) (xy 53.389794 -294.181169)
			(xy 53.438013 -294.171325) (xy 53.487188 -294.169344) (xy 53.536043 -294.175276) (xy 53.583314 -294.188968)
			(xy 53.627776 -294.210066) (xy 53.668279 -294.238022) (xy 53.703772 -294.272114) (xy 53.733337 -294.311458)
			(xy 53.756208 -294.355035) (xy 53.771792 -294.401716) (xy 53.779687 -294.450293) (xy 53.780182 -294.4749)
			(xy 54.11903 -294.4749) (xy 54.12299 -294.425846) (xy 54.134767 -294.378062) (xy 54.154058 -294.332786)
			(xy 54.180361 -294.29119) (xy 54.212996 -294.254353) (xy 54.251117 -294.223228) (xy 54.293738 -294.198621)
			(xy 54.339754 -294.181169) (xy 54.387973 -294.171325) (xy 54.437148 -294.169344) (xy 54.486003 -294.175276)
			(xy 54.533274 -294.188968) (xy 54.577736 -294.210066) (xy 54.618239 -294.238022) (xy 54.653732 -294.272114)
			(xy 54.683297 -294.311458) (xy 54.706168 -294.355035) (xy 54.721752 -294.401716) (xy 54.729647 -294.450293)
			(xy 54.730142 -294.4749) (xy 55.06899 -294.4749) (xy 55.07295 -294.425846) (xy 55.084727 -294.378062)
			(xy 55.104018 -294.332786) (xy 55.130321 -294.29119) (xy 55.162956 -294.254353) (xy 55.201077 -294.223228)
			(xy 55.243698 -294.198621) (xy 55.289714 -294.181169) (xy 55.337933 -294.171325) (xy 55.387108 -294.169344)
			(xy 55.435963 -294.175276) (xy 55.483234 -294.188968) (xy 55.527696 -294.210066) (xy 55.568199 -294.238022)
			(xy 55.603692 -294.272114) (xy 55.633257 -294.311458) (xy 55.656128 -294.355035) (xy 55.671712 -294.401716)
			(xy 55.679607 -294.450293) (xy 55.680102 -294.4749) (xy 56.01895 -294.4749) (xy 56.02291 -294.425846)
			(xy 56.034687 -294.378062) (xy 56.053978 -294.332786) (xy 56.080281 -294.29119) (xy 56.112916 -294.254353)
			(xy 56.151037 -294.223228) (xy 56.193658 -294.198621) (xy 56.239674 -294.181169) (xy 56.287893 -294.171325)
			(xy 56.337068 -294.169344) (xy 56.385923 -294.175276) (xy 56.433194 -294.188968) (xy 56.477656 -294.210066)
			(xy 56.518159 -294.238022) (xy 56.553652 -294.272114) (xy 56.583217 -294.311458) (xy 56.606088 -294.355035)
			(xy 56.621672 -294.401716) (xy 56.629567 -294.450293) (xy 56.630062 -294.4749) (xy 56.969164 -294.4749)
			(xy 56.973124 -294.425846) (xy 56.984901 -294.378062) (xy 57.004192 -294.332786) (xy 57.030495 -294.29119)
			(xy 57.06313 -294.254353) (xy 57.101251 -294.223228) (xy 57.143872 -294.198621) (xy 57.189888 -294.181169)
			(xy 57.238107 -294.171325) (xy 57.287282 -294.169344) (xy 57.336137 -294.175276) (xy 57.383408 -294.188968)
			(xy 57.42787 -294.210066) (xy 57.468373 -294.238022) (xy 57.503866 -294.272114) (xy 57.533431 -294.311458)
			(xy 57.556302 -294.355035) (xy 57.571886 -294.401716) (xy 57.579781 -294.450293) (xy 57.580276 -294.4749)
			(xy 57.919124 -294.4749) (xy 57.923084 -294.425846) (xy 57.934861 -294.378062) (xy 57.954152 -294.332786)
			(xy 57.980455 -294.29119) (xy 58.01309 -294.254353) (xy 58.051211 -294.223228) (xy 58.093832 -294.198621)
			(xy 58.139848 -294.181169) (xy 58.188067 -294.171325) (xy 58.237242 -294.169344) (xy 58.286097 -294.175276)
			(xy 58.333368 -294.188968) (xy 58.37783 -294.210066) (xy 58.418333 -294.238022) (xy 58.453826 -294.272114)
			(xy 58.483391 -294.311458) (xy 58.506262 -294.355035) (xy 58.521846 -294.401716) (xy 58.529741 -294.450293)
			(xy 58.530236 -294.4749) (xy 59.819044 -294.4749) (xy 59.823004 -294.425846) (xy 59.834781 -294.378062)
			(xy 59.854072 -294.332786) (xy 59.880375 -294.29119) (xy 59.91301 -294.254353) (xy 59.951131 -294.223228)
			(xy 59.993752 -294.198621) (xy 60.039768 -294.181169) (xy 60.087987 -294.171325) (xy 60.137162 -294.169344)
			(xy 60.186017 -294.175276) (xy 60.233288 -294.188968) (xy 60.27775 -294.210066) (xy 60.318253 -294.238022)
			(xy 60.353746 -294.272114) (xy 60.383311 -294.311458) (xy 60.406182 -294.355035) (xy 60.421766 -294.401716)
			(xy 60.429661 -294.450293) (xy 60.430156 -294.4749) (xy 60.769004 -294.4749) (xy 60.772964 -294.425846)
			(xy 60.784741 -294.378062) (xy 60.804032 -294.332786) (xy 60.830335 -294.29119) (xy 60.86297 -294.254353)
			(xy 60.901091 -294.223228) (xy 60.943712 -294.198621) (xy 60.989728 -294.181169) (xy 61.037947 -294.171325)
			(xy 61.087122 -294.169344) (xy 61.135977 -294.175276) (xy 61.183248 -294.188968) (xy 61.22771 -294.210066)
			(xy 61.268213 -294.238022) (xy 61.303706 -294.272114) (xy 61.333271 -294.311458) (xy 61.356142 -294.355035)
			(xy 61.371726 -294.401716) (xy 61.379621 -294.450293) (xy 61.380116 -294.4749) (xy 61.718964 -294.4749)
			(xy 61.722924 -294.425846) (xy 61.734701 -294.378062) (xy 61.753992 -294.332786) (xy 61.780295 -294.29119)
			(xy 61.81293 -294.254353) (xy 61.851051 -294.223228) (xy 61.893672 -294.198621) (xy 61.939688 -294.181169)
			(xy 61.987907 -294.171325) (xy 62.037082 -294.169344) (xy 62.085937 -294.175276) (xy 62.133208 -294.188968)
			(xy 62.17767 -294.210066) (xy 62.218173 -294.238022) (xy 62.253666 -294.272114) (xy 62.283231 -294.311458)
			(xy 62.306102 -294.355035) (xy 62.321686 -294.401716) (xy 62.329581 -294.450293) (xy 62.330076 -294.4749)
			(xy 62.669178 -294.4749) (xy 62.673138 -294.425846) (xy 62.684915 -294.378062) (xy 62.704206 -294.332786)
			(xy 62.730509 -294.29119) (xy 62.763144 -294.254353) (xy 62.801265 -294.223228) (xy 62.843886 -294.198621)
			(xy 62.889902 -294.181169) (xy 62.938121 -294.171325) (xy 62.987296 -294.169344) (xy 63.036151 -294.175276)
			(xy 63.083422 -294.188968) (xy 63.127884 -294.210066) (xy 63.168387 -294.238022) (xy 63.20388 -294.272114)
			(xy 63.233445 -294.311458) (xy 63.256316 -294.355035) (xy 63.2719 -294.401716) (xy 63.279795 -294.450293)
			(xy 63.28029 -294.4749) (xy 63.619138 -294.4749) (xy 63.623098 -294.425846) (xy 63.634875 -294.378062)
			(xy 63.654166 -294.332786) (xy 63.680469 -294.29119) (xy 63.713104 -294.254353) (xy 63.751225 -294.223228)
			(xy 63.793846 -294.198621) (xy 63.839862 -294.181169) (xy 63.888081 -294.171325) (xy 63.937256 -294.169344)
			(xy 63.986111 -294.175276) (xy 64.033382 -294.188968) (xy 64.077844 -294.210066) (xy 64.118347 -294.238022)
			(xy 64.15384 -294.272114) (xy 64.183405 -294.311458) (xy 64.206276 -294.355035) (xy 64.22186 -294.401716)
			(xy 64.229755 -294.450293) (xy 64.23025 -294.4749) (xy 64.569098 -294.4749) (xy 64.573058 -294.425846)
			(xy 64.584835 -294.378062) (xy 64.604126 -294.332786) (xy 64.630429 -294.29119) (xy 64.663064 -294.254353)
			(xy 64.701185 -294.223228) (xy 64.743806 -294.198621) (xy 64.789822 -294.181169) (xy 64.838041 -294.171325)
			(xy 64.887216 -294.169344) (xy 64.936071 -294.175276) (xy 64.983342 -294.188968) (xy 65.027804 -294.210066)
			(xy 65.068307 -294.238022) (xy 65.1038 -294.272114) (xy 65.133365 -294.311458) (xy 65.156236 -294.355035)
			(xy 65.17182 -294.401716) (xy 65.179715 -294.450293) (xy 65.18021 -294.4749) (xy 65.519058 -294.4749)
			(xy 65.523018 -294.425846) (xy 65.534795 -294.378062) (xy 65.554086 -294.332786) (xy 65.580389 -294.29119)
			(xy 65.613024 -294.254353) (xy 65.651145 -294.223228) (xy 65.693766 -294.198621) (xy 65.739782 -294.181169)
			(xy 65.788001 -294.171325) (xy 65.837176 -294.169344) (xy 65.886031 -294.175276) (xy 65.933302 -294.188968)
			(xy 65.977764 -294.210066) (xy 66.018267 -294.238022) (xy 66.05376 -294.272114) (xy 66.083325 -294.311458)
			(xy 66.106196 -294.355035) (xy 66.12178 -294.401716) (xy 66.129675 -294.450293) (xy 66.13017 -294.4749)
			(xy 69.319152 -294.4749) (xy 69.323112 -294.425846) (xy 69.334889 -294.378062) (xy 69.35418 -294.332786)
			(xy 69.380483 -294.29119) (xy 69.413118 -294.254353) (xy 69.451239 -294.223228) (xy 69.49386 -294.198621)
			(xy 69.539876 -294.181169) (xy 69.588095 -294.171325) (xy 69.63727 -294.169344) (xy 69.686125 -294.175276)
			(xy 69.733396 -294.188968) (xy 69.777858 -294.210066) (xy 69.818361 -294.238022) (xy 69.853854 -294.272114)
			(xy 69.883419 -294.311458) (xy 69.90629 -294.355035) (xy 69.921874 -294.401716) (xy 69.929769 -294.450293)
			(xy 69.930264 -294.4749) (xy 70.269112 -294.4749) (xy 70.273072 -294.425846) (xy 70.284849 -294.378062)
			(xy 70.30414 -294.332786) (xy 70.330443 -294.29119) (xy 70.363078 -294.254353) (xy 70.401199 -294.223228)
			(xy 70.44382 -294.198621) (xy 70.489836 -294.181169) (xy 70.538055 -294.171325) (xy 70.58723 -294.169344)
			(xy 70.636085 -294.175276) (xy 70.683356 -294.188968) (xy 70.727818 -294.210066) (xy 70.768321 -294.238022)
			(xy 70.803814 -294.272114) (xy 70.833379 -294.311458) (xy 70.85625 -294.355035) (xy 70.871834 -294.401716)
			(xy 70.879729 -294.450293) (xy 70.880224 -294.4749) (xy 71.219072 -294.4749) (xy 71.223032 -294.425846)
			(xy 71.234809 -294.378062) (xy 71.2541 -294.332786) (xy 71.280403 -294.29119) (xy 71.313038 -294.254353)
			(xy 71.351159 -294.223228) (xy 71.39378 -294.198621) (xy 71.439796 -294.181169) (xy 71.488015 -294.171325)
			(xy 71.53719 -294.169344) (xy 71.586045 -294.175276) (xy 71.633316 -294.188968) (xy 71.677778 -294.210066)
			(xy 71.718281 -294.238022) (xy 71.753774 -294.272114) (xy 71.783339 -294.311458) (xy 71.80621 -294.355035)
			(xy 71.821794 -294.401716) (xy 71.829689 -294.450293) (xy 71.830184 -294.4749) (xy 72.169032 -294.4749)
			(xy 72.172992 -294.425846) (xy 72.184769 -294.378062) (xy 72.20406 -294.332786) (xy 72.230363 -294.29119)
			(xy 72.262998 -294.254353) (xy 72.301119 -294.223228) (xy 72.34374 -294.198621) (xy 72.389756 -294.181169)
			(xy 72.437975 -294.171325) (xy 72.48715 -294.169344) (xy 72.536005 -294.175276) (xy 72.583276 -294.188968)
			(xy 72.627738 -294.210066) (xy 72.668241 -294.238022) (xy 72.703734 -294.272114) (xy 72.733299 -294.311458)
			(xy 72.75617 -294.355035) (xy 72.771754 -294.401716) (xy 72.779649 -294.450293) (xy 72.780144 -294.4749)
			(xy 73.118992 -294.4749) (xy 73.122952 -294.425846) (xy 73.134729 -294.378062) (xy 73.15402 -294.332786)
			(xy 73.180323 -294.29119) (xy 73.212958 -294.254353) (xy 73.251079 -294.223228) (xy 73.2937 -294.198621)
			(xy 73.339716 -294.181169) (xy 73.387935 -294.171325) (xy 73.43711 -294.169344) (xy 73.485965 -294.175276)
			(xy 73.533236 -294.188968) (xy 73.577698 -294.210066) (xy 73.618201 -294.238022) (xy 73.653694 -294.272114)
			(xy 73.683259 -294.311458) (xy 73.70613 -294.355035) (xy 73.721714 -294.401716) (xy 73.729609 -294.450293)
			(xy 73.730104 -294.4749) (xy 74.068952 -294.4749) (xy 74.072912 -294.425846) (xy 74.084689 -294.378062)
			(xy 74.10398 -294.332786) (xy 74.130283 -294.29119) (xy 74.162918 -294.254353) (xy 74.201039 -294.223228)
			(xy 74.24366 -294.198621) (xy 74.289676 -294.181169) (xy 74.337895 -294.171325) (xy 74.38707 -294.169344)
			(xy 74.435925 -294.175276) (xy 74.483196 -294.188968) (xy 74.527658 -294.210066) (xy 74.568161 -294.238022)
			(xy 74.603654 -294.272114) (xy 74.633219 -294.311458) (xy 74.65609 -294.355035) (xy 74.671674 -294.401716)
			(xy 74.679569 -294.450293) (xy 74.680064 -294.4749) (xy 75.019166 -294.4749) (xy 75.023126 -294.425846)
			(xy 75.034903 -294.378062) (xy 75.054194 -294.332786) (xy 75.080497 -294.29119) (xy 75.113132 -294.254353)
			(xy 75.151253 -294.223228) (xy 75.193874 -294.198621) (xy 75.23989 -294.181169) (xy 75.288109 -294.171325)
			(xy 75.337284 -294.169344) (xy 75.386139 -294.175276) (xy 75.43341 -294.188968) (xy 75.477872 -294.210066)
			(xy 75.518375 -294.238022) (xy 75.553868 -294.272114) (xy 75.583433 -294.311458) (xy 75.606304 -294.355035)
			(xy 75.621888 -294.401716) (xy 75.629783 -294.450293) (xy 75.630278 -294.4749) (xy 75.969126 -294.4749)
			(xy 75.973086 -294.425846) (xy 75.984863 -294.378062) (xy 76.004154 -294.332786) (xy 76.030457 -294.29119)
			(xy 76.063092 -294.254353) (xy 76.101213 -294.223228) (xy 76.143834 -294.198621) (xy 76.18985 -294.181169)
			(xy 76.238069 -294.171325) (xy 76.287244 -294.169344) (xy 76.336099 -294.175276) (xy 76.38337 -294.188968)
			(xy 76.427832 -294.210066) (xy 76.468335 -294.238022) (xy 76.503828 -294.272114) (xy 76.533393 -294.311458)
			(xy 76.556264 -294.355035) (xy 76.571848 -294.401716) (xy 76.579743 -294.450293) (xy 76.580238 -294.4749)
			(xy 76.919086 -294.4749) (xy 76.923046 -294.425846) (xy 76.934823 -294.378062) (xy 76.954114 -294.332786)
			(xy 76.980417 -294.29119) (xy 77.013052 -294.254353) (xy 77.051173 -294.223228) (xy 77.093794 -294.198621)
			(xy 77.13981 -294.181169) (xy 77.188029 -294.171325) (xy 77.237204 -294.169344) (xy 77.286059 -294.175276)
			(xy 77.33333 -294.188968) (xy 77.377792 -294.210066) (xy 77.418295 -294.238022) (xy 77.453788 -294.272114)
			(xy 77.483353 -294.311458) (xy 77.506224 -294.355035) (xy 77.521808 -294.401716) (xy 77.529703 -294.450293)
			(xy 77.530198 -294.4749) (xy 77.869046 -294.4749) (xy 77.873006 -294.425846) (xy 77.884783 -294.378062)
			(xy 77.904074 -294.332786) (xy 77.930377 -294.29119) (xy 77.963012 -294.254353) (xy 78.001133 -294.223228)
			(xy 78.043754 -294.198621) (xy 78.08977 -294.181169) (xy 78.137989 -294.171325) (xy 78.187164 -294.169344)
			(xy 78.236019 -294.175276) (xy 78.28329 -294.188968) (xy 78.327752 -294.210066) (xy 78.368255 -294.238022)
			(xy 78.403748 -294.272114) (xy 78.433313 -294.311458) (xy 78.456184 -294.355035) (xy 78.471768 -294.401716)
			(xy 78.479663 -294.450293) (xy 78.480158 -294.4749) (xy 78.819006 -294.4749) (xy 78.822966 -294.425846)
			(xy 78.834743 -294.378062) (xy 78.854034 -294.332786) (xy 78.880337 -294.29119) (xy 78.912972 -294.254353)
			(xy 78.951093 -294.223228) (xy 78.993714 -294.198621) (xy 79.03973 -294.181169) (xy 79.087949 -294.171325)
			(xy 79.137124 -294.169344) (xy 79.185979 -294.175276) (xy 79.23325 -294.188968) (xy 79.277712 -294.210066)
			(xy 79.318215 -294.238022) (xy 79.353708 -294.272114) (xy 79.383273 -294.311458) (xy 79.406144 -294.355035)
			(xy 79.421728 -294.401716) (xy 79.429623 -294.450293) (xy 79.430118 -294.4749) (xy 79.768966 -294.4749)
			(xy 79.772926 -294.425846) (xy 79.784703 -294.378062) (xy 79.803994 -294.332786) (xy 79.830297 -294.29119)
			(xy 79.862932 -294.254353) (xy 79.901053 -294.223228) (xy 79.943674 -294.198621) (xy 79.98969 -294.181169)
			(xy 80.037909 -294.171325) (xy 80.087084 -294.169344) (xy 80.135939 -294.175276) (xy 80.18321 -294.188968)
			(xy 80.227672 -294.210066) (xy 80.268175 -294.238022) (xy 80.303668 -294.272114) (xy 80.333233 -294.311458)
			(xy 80.356104 -294.355035) (xy 80.371688 -294.401716) (xy 80.379583 -294.450293) (xy 80.380078 -294.4749)
			(xy 80.71918 -294.4749) (xy 80.72314 -294.425846) (xy 80.734917 -294.378062) (xy 80.754208 -294.332786)
			(xy 80.780511 -294.29119) (xy 80.813146 -294.254353) (xy 80.851267 -294.223228) (xy 80.893888 -294.198621)
			(xy 80.939904 -294.181169) (xy 80.988123 -294.171325) (xy 81.037298 -294.169344) (xy 81.086153 -294.175276)
			(xy 81.133424 -294.188968) (xy 81.177886 -294.210066) (xy 81.218389 -294.238022) (xy 81.253882 -294.272114)
			(xy 81.283447 -294.311458) (xy 81.306318 -294.355035) (xy 81.321902 -294.401716) (xy 81.329797 -294.450293)
			(xy 81.330292 -294.4749) (xy 81.66914 -294.4749) (xy 81.6731 -294.425846) (xy 81.684877 -294.378062)
			(xy 81.704168 -294.332786) (xy 81.730471 -294.29119) (xy 81.763106 -294.254353) (xy 81.801227 -294.223228)
			(xy 81.843848 -294.198621) (xy 81.889864 -294.181169) (xy 81.938083 -294.171325) (xy 81.987258 -294.169344)
			(xy 82.036113 -294.175276) (xy 82.083384 -294.188968) (xy 82.127846 -294.210066) (xy 82.168349 -294.238022)
			(xy 82.203842 -294.272114) (xy 82.233407 -294.311458) (xy 82.256278 -294.355035) (xy 82.271862 -294.401716)
			(xy 82.279757 -294.450293) (xy 82.280252 -294.4749) (xy 82.6191 -294.4749) (xy 82.62306 -294.425846)
			(xy 82.634837 -294.378062) (xy 82.654128 -294.332786) (xy 82.680431 -294.29119) (xy 82.713066 -294.254353)
			(xy 82.751187 -294.223228) (xy 82.793808 -294.198621) (xy 82.839824 -294.181169) (xy 82.888043 -294.171325)
			(xy 82.937218 -294.169344) (xy 82.986073 -294.175276) (xy 83.033344 -294.188968) (xy 83.077806 -294.210066)
			(xy 83.118309 -294.238022) (xy 83.153802 -294.272114) (xy 83.183367 -294.311458) (xy 83.206238 -294.355035)
			(xy 83.221822 -294.401716) (xy 83.229717 -294.450293) (xy 83.230212 -294.4749) (xy 83.229717 -294.499507)
			(xy 83.221822 -294.548084) (xy 83.206238 -294.594765) (xy 83.183367 -294.638342) (xy 83.153802 -294.677686)
			(xy 83.120227 -294.709936) (xy 89.163026 -294.709936) (xy 89.163028 -294.655424) (xy 89.170789 -294.601467)
			(xy 89.186151 -294.549165) (xy 89.208799 -294.49958) (xy 89.238274 -294.453724) (xy 89.273975 -294.41253)
			(xy 89.315175 -294.376836) (xy 89.361037 -294.347368) (xy 89.410625 -294.324728) (xy 89.46293 -294.309376)
			(xy 89.516888 -294.301624) (xy 89.544144 -294.301164) (xy 89.569544 -294.301926) (xy 89.584276 -294.302414)
			(xy 89.613006 -294.295872) (xy 89.638673 -294.281399) (xy 89.65914 -294.260202) (xy 89.672703 -294.234044)
			(xy 89.678235 -294.205102) (xy 89.675274 -294.175786) (xy 89.670128 -294.161972) (xy 89.660964 -294.13877)
			(xy 89.648075 -294.090579) (xy 89.641576 -294.041119) (xy 89.641172 -294.016176) (xy 89.641704 -293.988927)
			(xy 89.649463 -293.934983) (xy 89.664821 -293.882693) (xy 89.687463 -293.83312) (xy 89.716931 -293.787275)
			(xy 89.752622 -293.746089) (xy 89.793812 -293.710403) (xy 89.839661 -293.680941) (xy 89.889236 -293.658304)
			(xy 89.941529 -293.642953) (xy 89.995473 -293.635201) (xy 90.049972 -293.635204) (xy 90.103916 -293.642963)
			(xy 90.156206 -293.65832) (xy 90.205779 -293.680963) (xy 90.251624 -293.71043) (xy 90.29281 -293.746121)
			(xy 90.328497 -293.787311) (xy 90.357958 -293.83316) (xy 90.380595 -293.882735) (xy 90.395946 -293.935027)
			(xy 90.402498 -293.980616) (xy 91.28074 -293.980616) (xy 91.284811 -293.924994) (xy 91.296937 -293.870557)
			(xy 91.31686 -293.818466) (xy 91.344156 -293.769831) (xy 91.378242 -293.725688) (xy 91.418391 -293.686979)
			(xy 91.463749 -293.654528) (xy 91.513349 -293.629027) (xy 91.566133 -293.61102) (xy 91.620976 -293.60089)
			(xy 91.67671 -293.598853) (xy 91.732147 -293.604953) (xy 91.786104 -293.619059) (xy 91.837433 -293.640871)
			(xy 91.885039 -293.669925) (xy 91.927907 -293.7056) (xy 91.965124 -293.747137) (xy 91.995897 -293.79365)
			(xy 92.019569 -293.844147) (xy 92.035637 -293.897554) (xy 92.043757 -293.95273) (xy 92.044266 -293.980616)
			(xy 92.043757 -294.008502) (xy 92.035637 -294.063678) (xy 92.019569 -294.117085) (xy 91.995897 -294.167582)
			(xy 91.965124 -294.214095) (xy 91.927907 -294.255632) (xy 91.885039 -294.291307) (xy 91.837433 -294.320361)
			(xy 91.786104 -294.342173) (xy 91.732147 -294.356279) (xy 91.67671 -294.362379) (xy 91.620976 -294.360342)
			(xy 91.566133 -294.350212) (xy 91.513349 -294.332205) (xy 91.463749 -294.306704) (xy 91.418391 -294.274253)
			(xy 91.378242 -294.235544) (xy 91.344156 -294.191401) (xy 91.31686 -294.142766) (xy 91.296937 -294.090675)
			(xy 91.284811 -294.036238) (xy 91.28074 -293.980616) (xy 90.402498 -293.980616) (xy 90.403699 -293.988972)
			(xy 90.403696 -294.043471) (xy 90.395937 -294.097414) (xy 90.38058 -294.149705) (xy 90.357938 -294.199278)
			(xy 90.328471 -294.245123) (xy 90.29278 -294.286309) (xy 90.25159 -294.321996) (xy 90.205741 -294.351458)
			(xy 90.156166 -294.374095) (xy 90.103874 -294.389446) (xy 90.049929 -294.397199) (xy 90.02268 -294.397684)
			(xy 89.99728 -294.396922) (xy 89.982549 -294.396526) (xy 89.953832 -294.403059) (xy 89.928174 -294.417517)
			(xy 89.907712 -294.438698) (xy 89.894147 -294.464839) (xy 89.888608 -294.493765) (xy 89.889394 -294.50157)
			(xy 90.53652 -294.50157) (xy 90.540591 -294.445948) (xy 90.552717 -294.391511) (xy 90.57264 -294.33942)
			(xy 90.599936 -294.290785) (xy 90.634022 -294.246642) (xy 90.674171 -294.207933) (xy 90.719529 -294.175482)
			(xy 90.769129 -294.149981) (xy 90.821913 -294.131974) (xy 90.876756 -294.121844) (xy 90.93249 -294.119807)
			(xy 90.987927 -294.125907) (xy 91.041884 -294.140013) (xy 91.093213 -294.161825) (xy 91.140819 -294.190879)
			(xy 91.183687 -294.226554) (xy 91.220904 -294.268091) (xy 91.251677 -294.314604) (xy 91.275349 -294.365101)
			(xy 91.291417 -294.418508) (xy 91.299537 -294.473684) (xy 91.300046 -294.50157) (xy 91.299537 -294.529456)
			(xy 91.291417 -294.584632) (xy 91.275349 -294.638039) (xy 91.251677 -294.688536) (xy 91.220904 -294.735049)
			(xy 91.183687 -294.776586) (xy 91.140819 -294.812261) (xy 91.093213 -294.841315) (xy 91.041884 -294.863127)
			(xy 90.987927 -294.877233) (xy 90.93249 -294.883333) (xy 90.876756 -294.881296) (xy 90.821913 -294.871166)
			(xy 90.769129 -294.853159) (xy 90.719529 -294.827658) (xy 90.674171 -294.795207) (xy 90.634022 -294.756498)
			(xy 90.599936 -294.712355) (xy 90.57264 -294.66372) (xy 90.552717 -294.611629) (xy 90.540591 -294.557192)
			(xy 90.53652 -294.50157) (xy 89.889394 -294.50157) (xy 89.891557 -294.523067) (xy 89.896696 -294.536876)
			(xy 89.905845 -294.560083) (xy 89.91874 -294.608272) (xy 89.925244 -294.65773) (xy 89.925652 -294.682672)
			(xy 89.925175 -294.709928) (xy 89.917421 -294.763886) (xy 89.902066 -294.81619) (xy 89.879424 -294.865778)
			(xy 89.849955 -294.911637) (xy 89.814259 -294.952836) (xy 89.773063 -294.988536) (xy 89.727206 -295.018009)
			(xy 89.67762 -295.040655) (xy 89.625317 -295.056014) (xy 89.57136 -295.063773) (xy 89.516848 -295.063773)
			(xy 89.462891 -295.056016) (xy 89.410587 -295.040658) (xy 89.361001 -295.018012) (xy 89.315143 -294.98854)
			(xy 89.273947 -294.952842) (xy 89.23825 -294.911644) (xy 89.20878 -294.865785) (xy 89.186137 -294.816198)
			(xy 89.170781 -294.763893) (xy 89.163026 -294.709936) (xy 83.120227 -294.709936) (xy 83.118309 -294.711778)
			(xy 83.077806 -294.739734) (xy 83.033344 -294.760832) (xy 82.986073 -294.774524) (xy 82.937218 -294.780456)
			(xy 82.888043 -294.778475) (xy 82.839824 -294.768631) (xy 82.793808 -294.751179) (xy 82.751187 -294.726572)
			(xy 82.713066 -294.695447) (xy 82.680431 -294.65861) (xy 82.654128 -294.617014) (xy 82.634837 -294.571738)
			(xy 82.62306 -294.523954) (xy 82.6191 -294.4749) (xy 82.280252 -294.4749) (xy 82.279757 -294.499507)
			(xy 82.271862 -294.548084) (xy 82.256278 -294.594765) (xy 82.233407 -294.638342) (xy 82.203842 -294.677686)
			(xy 82.168349 -294.711778) (xy 82.127846 -294.739734) (xy 82.083384 -294.760832) (xy 82.036113 -294.774524)
			(xy 81.987258 -294.780456) (xy 81.938083 -294.778475) (xy 81.889864 -294.768631) (xy 81.843848 -294.751179)
			(xy 81.801227 -294.726572) (xy 81.763106 -294.695447) (xy 81.730471 -294.65861) (xy 81.704168 -294.617014)
			(xy 81.684877 -294.571738) (xy 81.6731 -294.523954) (xy 81.66914 -294.4749) (xy 81.330292 -294.4749)
			(xy 81.329797 -294.499507) (xy 81.321902 -294.548084) (xy 81.306318 -294.594765) (xy 81.283447 -294.638342)
			(xy 81.253882 -294.677686) (xy 81.218389 -294.711778) (xy 81.177886 -294.739734) (xy 81.133424 -294.760832)
			(xy 81.086153 -294.774524) (xy 81.037298 -294.780456) (xy 80.988123 -294.778475) (xy 80.939904 -294.768631)
			(xy 80.893888 -294.751179) (xy 80.851267 -294.726572) (xy 80.813146 -294.695447) (xy 80.780511 -294.65861)
			(xy 80.754208 -294.617014) (xy 80.734917 -294.571738) (xy 80.72314 -294.523954) (xy 80.71918 -294.4749)
			(xy 80.380078 -294.4749) (xy 80.379583 -294.499507) (xy 80.371688 -294.548084) (xy 80.356104 -294.594765)
			(xy 80.333233 -294.638342) (xy 80.303668 -294.677686) (xy 80.268175 -294.711778) (xy 80.227672 -294.739734)
			(xy 80.18321 -294.760832) (xy 80.135939 -294.774524) (xy 80.087084 -294.780456) (xy 80.037909 -294.778475)
			(xy 79.98969 -294.768631) (xy 79.943674 -294.751179) (xy 79.901053 -294.726572) (xy 79.862932 -294.695447)
			(xy 79.830297 -294.65861) (xy 79.803994 -294.617014) (xy 79.784703 -294.571738) (xy 79.772926 -294.523954)
			(xy 79.768966 -294.4749) (xy 79.430118 -294.4749) (xy 79.429623 -294.499507) (xy 79.421728 -294.548084)
			(xy 79.406144 -294.594765) (xy 79.383273 -294.638342) (xy 79.353708 -294.677686) (xy 79.318215 -294.711778)
			(xy 79.277712 -294.739734) (xy 79.23325 -294.760832) (xy 79.185979 -294.774524) (xy 79.137124 -294.780456)
			(xy 79.087949 -294.778475) (xy 79.03973 -294.768631) (xy 78.993714 -294.751179) (xy 78.951093 -294.726572)
			(xy 78.912972 -294.695447) (xy 78.880337 -294.65861) (xy 78.854034 -294.617014) (xy 78.834743 -294.571738)
			(xy 78.822966 -294.523954) (xy 78.819006 -294.4749) (xy 78.480158 -294.4749) (xy 78.479663 -294.499507)
			(xy 78.471768 -294.548084) (xy 78.456184 -294.594765) (xy 78.433313 -294.638342) (xy 78.403748 -294.677686)
			(xy 78.368255 -294.711778) (xy 78.327752 -294.739734) (xy 78.28329 -294.760832) (xy 78.236019 -294.774524)
			(xy 78.187164 -294.780456) (xy 78.137989 -294.778475) (xy 78.08977 -294.768631) (xy 78.043754 -294.751179)
			(xy 78.001133 -294.726572) (xy 77.963012 -294.695447) (xy 77.930377 -294.65861) (xy 77.904074 -294.617014)
			(xy 77.884783 -294.571738) (xy 77.873006 -294.523954) (xy 77.869046 -294.4749) (xy 77.530198 -294.4749)
			(xy 77.529703 -294.499507) (xy 77.521808 -294.548084) (xy 77.506224 -294.594765) (xy 77.483353 -294.638342)
			(xy 77.453788 -294.677686) (xy 77.418295 -294.711778) (xy 77.377792 -294.739734) (xy 77.33333 -294.760832)
			(xy 77.286059 -294.774524) (xy 77.237204 -294.780456) (xy 77.188029 -294.778475) (xy 77.13981 -294.768631)
			(xy 77.093794 -294.751179) (xy 77.051173 -294.726572) (xy 77.013052 -294.695447) (xy 76.980417 -294.65861)
			(xy 76.954114 -294.617014) (xy 76.934823 -294.571738) (xy 76.923046 -294.523954) (xy 76.919086 -294.4749)
			(xy 76.580238 -294.4749) (xy 76.579743 -294.499507) (xy 76.571848 -294.548084) (xy 76.556264 -294.594765)
			(xy 76.533393 -294.638342) (xy 76.503828 -294.677686) (xy 76.468335 -294.711778) (xy 76.427832 -294.739734)
			(xy 76.38337 -294.760832) (xy 76.336099 -294.774524) (xy 76.287244 -294.780456) (xy 76.238069 -294.778475)
			(xy 76.18985 -294.768631) (xy 76.143834 -294.751179) (xy 76.101213 -294.726572) (xy 76.063092 -294.695447)
			(xy 76.030457 -294.65861) (xy 76.004154 -294.617014) (xy 75.984863 -294.571738) (xy 75.973086 -294.523954)
			(xy 75.969126 -294.4749) (xy 75.630278 -294.4749) (xy 75.629783 -294.499507) (xy 75.621888 -294.548084)
			(xy 75.606304 -294.594765) (xy 75.583433 -294.638342) (xy 75.553868 -294.677686) (xy 75.518375 -294.711778)
			(xy 75.477872 -294.739734) (xy 75.43341 -294.760832) (xy 75.386139 -294.774524) (xy 75.337284 -294.780456)
			(xy 75.288109 -294.778475) (xy 75.23989 -294.768631) (xy 75.193874 -294.751179) (xy 75.151253 -294.726572)
			(xy 75.113132 -294.695447) (xy 75.080497 -294.65861) (xy 75.054194 -294.617014) (xy 75.034903 -294.571738)
			(xy 75.023126 -294.523954) (xy 75.019166 -294.4749) (xy 74.680064 -294.4749) (xy 74.679569 -294.499507)
			(xy 74.671674 -294.548084) (xy 74.65609 -294.594765) (xy 74.633219 -294.638342) (xy 74.603654 -294.677686)
			(xy 74.568161 -294.711778) (xy 74.527658 -294.739734) (xy 74.483196 -294.760832) (xy 74.435925 -294.774524)
			(xy 74.38707 -294.780456) (xy 74.337895 -294.778475) (xy 74.289676 -294.768631) (xy 74.24366 -294.751179)
			(xy 74.201039 -294.726572) (xy 74.162918 -294.695447) (xy 74.130283 -294.65861) (xy 74.10398 -294.617014)
			(xy 74.084689 -294.571738) (xy 74.072912 -294.523954) (xy 74.068952 -294.4749) (xy 73.730104 -294.4749)
			(xy 73.729609 -294.499507) (xy 73.721714 -294.548084) (xy 73.70613 -294.594765) (xy 73.683259 -294.638342)
			(xy 73.653694 -294.677686) (xy 73.618201 -294.711778) (xy 73.577698 -294.739734) (xy 73.533236 -294.760832)
			(xy 73.485965 -294.774524) (xy 73.43711 -294.780456) (xy 73.387935 -294.778475) (xy 73.339716 -294.768631)
			(xy 73.2937 -294.751179) (xy 73.251079 -294.726572) (xy 73.212958 -294.695447) (xy 73.180323 -294.65861)
			(xy 73.15402 -294.617014) (xy 73.134729 -294.571738) (xy 73.122952 -294.523954) (xy 73.118992 -294.4749)
			(xy 72.780144 -294.4749) (xy 72.779649 -294.499507) (xy 72.771754 -294.548084) (xy 72.75617 -294.594765)
			(xy 72.733299 -294.638342) (xy 72.703734 -294.677686) (xy 72.668241 -294.711778) (xy 72.627738 -294.739734)
			(xy 72.583276 -294.760832) (xy 72.536005 -294.774524) (xy 72.48715 -294.780456) (xy 72.437975 -294.778475)
			(xy 72.389756 -294.768631) (xy 72.34374 -294.751179) (xy 72.301119 -294.726572) (xy 72.262998 -294.695447)
			(xy 72.230363 -294.65861) (xy 72.20406 -294.617014) (xy 72.184769 -294.571738) (xy 72.172992 -294.523954)
			(xy 72.169032 -294.4749) (xy 71.830184 -294.4749) (xy 71.829689 -294.499507) (xy 71.821794 -294.548084)
			(xy 71.80621 -294.594765) (xy 71.783339 -294.638342) (xy 71.753774 -294.677686) (xy 71.718281 -294.711778)
			(xy 71.677778 -294.739734) (xy 71.633316 -294.760832) (xy 71.586045 -294.774524) (xy 71.53719 -294.780456)
			(xy 71.488015 -294.778475) (xy 71.439796 -294.768631) (xy 71.39378 -294.751179) (xy 71.351159 -294.726572)
			(xy 71.313038 -294.695447) (xy 71.280403 -294.65861) (xy 71.2541 -294.617014) (xy 71.234809 -294.571738)
			(xy 71.223032 -294.523954) (xy 71.219072 -294.4749) (xy 70.880224 -294.4749) (xy 70.879729 -294.499507)
			(xy 70.871834 -294.548084) (xy 70.85625 -294.594765) (xy 70.833379 -294.638342) (xy 70.803814 -294.677686)
			(xy 70.768321 -294.711778) (xy 70.727818 -294.739734) (xy 70.683356 -294.760832) (xy 70.636085 -294.774524)
			(xy 70.58723 -294.780456) (xy 70.538055 -294.778475) (xy 70.489836 -294.768631) (xy 70.44382 -294.751179)
			(xy 70.401199 -294.726572) (xy 70.363078 -294.695447) (xy 70.330443 -294.65861) (xy 70.30414 -294.617014)
			(xy 70.284849 -294.571738) (xy 70.273072 -294.523954) (xy 70.269112 -294.4749) (xy 69.930264 -294.4749)
			(xy 69.929769 -294.499507) (xy 69.921874 -294.548084) (xy 69.90629 -294.594765) (xy 69.883419 -294.638342)
			(xy 69.853854 -294.677686) (xy 69.818361 -294.711778) (xy 69.777858 -294.739734) (xy 69.733396 -294.760832)
			(xy 69.686125 -294.774524) (xy 69.63727 -294.780456) (xy 69.588095 -294.778475) (xy 69.539876 -294.768631)
			(xy 69.49386 -294.751179) (xy 69.451239 -294.726572) (xy 69.413118 -294.695447) (xy 69.380483 -294.65861)
			(xy 69.35418 -294.617014) (xy 69.334889 -294.571738) (xy 69.323112 -294.523954) (xy 69.319152 -294.4749)
			(xy 66.13017 -294.4749) (xy 66.129675 -294.499507) (xy 66.12178 -294.548084) (xy 66.106196 -294.594765)
			(xy 66.083325 -294.638342) (xy 66.05376 -294.677686) (xy 66.018267 -294.711778) (xy 65.977764 -294.739734)
			(xy 65.933302 -294.760832) (xy 65.886031 -294.774524) (xy 65.837176 -294.780456) (xy 65.788001 -294.778475)
			(xy 65.739782 -294.768631) (xy 65.693766 -294.751179) (xy 65.651145 -294.726572) (xy 65.613024 -294.695447)
			(xy 65.580389 -294.65861) (xy 65.554086 -294.617014) (xy 65.534795 -294.571738) (xy 65.523018 -294.523954)
			(xy 65.519058 -294.4749) (xy 65.18021 -294.4749) (xy 65.179715 -294.499507) (xy 65.17182 -294.548084)
			(xy 65.156236 -294.594765) (xy 65.133365 -294.638342) (xy 65.1038 -294.677686) (xy 65.068307 -294.711778)
			(xy 65.027804 -294.739734) (xy 64.983342 -294.760832) (xy 64.936071 -294.774524) (xy 64.887216 -294.780456)
			(xy 64.838041 -294.778475) (xy 64.789822 -294.768631) (xy 64.743806 -294.751179) (xy 64.701185 -294.726572)
			(xy 64.663064 -294.695447) (xy 64.630429 -294.65861) (xy 64.604126 -294.617014) (xy 64.584835 -294.571738)
			(xy 64.573058 -294.523954) (xy 64.569098 -294.4749) (xy 64.23025 -294.4749) (xy 64.229755 -294.499507)
			(xy 64.22186 -294.548084) (xy 64.206276 -294.594765) (xy 64.183405 -294.638342) (xy 64.15384 -294.677686)
			(xy 64.118347 -294.711778) (xy 64.077844 -294.739734) (xy 64.033382 -294.760832) (xy 63.986111 -294.774524)
			(xy 63.937256 -294.780456) (xy 63.888081 -294.778475) (xy 63.839862 -294.768631) (xy 63.793846 -294.751179)
			(xy 63.751225 -294.726572) (xy 63.713104 -294.695447) (xy 63.680469 -294.65861) (xy 63.654166 -294.617014)
			(xy 63.634875 -294.571738) (xy 63.623098 -294.523954) (xy 63.619138 -294.4749) (xy 63.28029 -294.4749)
			(xy 63.279795 -294.499507) (xy 63.2719 -294.548084) (xy 63.256316 -294.594765) (xy 63.233445 -294.638342)
			(xy 63.20388 -294.677686) (xy 63.168387 -294.711778) (xy 63.127884 -294.739734) (xy 63.083422 -294.760832)
			(xy 63.036151 -294.774524) (xy 62.987296 -294.780456) (xy 62.938121 -294.778475) (xy 62.889902 -294.768631)
			(xy 62.843886 -294.751179) (xy 62.801265 -294.726572) (xy 62.763144 -294.695447) (xy 62.730509 -294.65861)
			(xy 62.704206 -294.617014) (xy 62.684915 -294.571738) (xy 62.673138 -294.523954) (xy 62.669178 -294.4749)
			(xy 62.330076 -294.4749) (xy 62.329581 -294.499507) (xy 62.321686 -294.548084) (xy 62.306102 -294.594765)
			(xy 62.283231 -294.638342) (xy 62.253666 -294.677686) (xy 62.218173 -294.711778) (xy 62.17767 -294.739734)
			(xy 62.133208 -294.760832) (xy 62.085937 -294.774524) (xy 62.037082 -294.780456) (xy 61.987907 -294.778475)
			(xy 61.939688 -294.768631) (xy 61.893672 -294.751179) (xy 61.851051 -294.726572) (xy 61.81293 -294.695447)
			(xy 61.780295 -294.65861) (xy 61.753992 -294.617014) (xy 61.734701 -294.571738) (xy 61.722924 -294.523954)
			(xy 61.718964 -294.4749) (xy 61.380116 -294.4749) (xy 61.379621 -294.499507) (xy 61.371726 -294.548084)
			(xy 61.356142 -294.594765) (xy 61.333271 -294.638342) (xy 61.303706 -294.677686) (xy 61.268213 -294.711778)
			(xy 61.22771 -294.739734) (xy 61.183248 -294.760832) (xy 61.135977 -294.774524) (xy 61.087122 -294.780456)
			(xy 61.037947 -294.778475) (xy 60.989728 -294.768631) (xy 60.943712 -294.751179) (xy 60.901091 -294.726572)
			(xy 60.86297 -294.695447) (xy 60.830335 -294.65861) (xy 60.804032 -294.617014) (xy 60.784741 -294.571738)
			(xy 60.772964 -294.523954) (xy 60.769004 -294.4749) (xy 60.430156 -294.4749) (xy 60.429661 -294.499507)
			(xy 60.421766 -294.548084) (xy 60.406182 -294.594765) (xy 60.383311 -294.638342) (xy 60.353746 -294.677686)
			(xy 60.318253 -294.711778) (xy 60.27775 -294.739734) (xy 60.233288 -294.760832) (xy 60.186017 -294.774524)
			(xy 60.137162 -294.780456) (xy 60.087987 -294.778475) (xy 60.039768 -294.768631) (xy 59.993752 -294.751179)
			(xy 59.951131 -294.726572) (xy 59.91301 -294.695447) (xy 59.880375 -294.65861) (xy 59.854072 -294.617014)
			(xy 59.834781 -294.571738) (xy 59.823004 -294.523954) (xy 59.819044 -294.4749) (xy 58.530236 -294.4749)
			(xy 58.529741 -294.499507) (xy 58.521846 -294.548084) (xy 58.506262 -294.594765) (xy 58.483391 -294.638342)
			(xy 58.453826 -294.677686) (xy 58.418333 -294.711778) (xy 58.37783 -294.739734) (xy 58.333368 -294.760832)
			(xy 58.286097 -294.774524) (xy 58.237242 -294.780456) (xy 58.188067 -294.778475) (xy 58.139848 -294.768631)
			(xy 58.093832 -294.751179) (xy 58.051211 -294.726572) (xy 58.01309 -294.695447) (xy 57.980455 -294.65861)
			(xy 57.954152 -294.617014) (xy 57.934861 -294.571738) (xy 57.923084 -294.523954) (xy 57.919124 -294.4749)
			(xy 57.580276 -294.4749) (xy 57.579781 -294.499507) (xy 57.571886 -294.548084) (xy 57.556302 -294.594765)
			(xy 57.533431 -294.638342) (xy 57.503866 -294.677686) (xy 57.468373 -294.711778) (xy 57.42787 -294.739734)
			(xy 57.383408 -294.760832) (xy 57.336137 -294.774524) (xy 57.287282 -294.780456) (xy 57.238107 -294.778475)
			(xy 57.189888 -294.768631) (xy 57.143872 -294.751179) (xy 57.101251 -294.726572) (xy 57.06313 -294.695447)
			(xy 57.030495 -294.65861) (xy 57.004192 -294.617014) (xy 56.984901 -294.571738) (xy 56.973124 -294.523954)
			(xy 56.969164 -294.4749) (xy 56.630062 -294.4749) (xy 56.629567 -294.499507) (xy 56.621672 -294.548084)
			(xy 56.606088 -294.594765) (xy 56.583217 -294.638342) (xy 56.553652 -294.677686) (xy 56.518159 -294.711778)
			(xy 56.477656 -294.739734) (xy 56.433194 -294.760832) (xy 56.385923 -294.774524) (xy 56.337068 -294.780456)
			(xy 56.287893 -294.778475) (xy 56.239674 -294.768631) (xy 56.193658 -294.751179) (xy 56.151037 -294.726572)
			(xy 56.112916 -294.695447) (xy 56.080281 -294.65861) (xy 56.053978 -294.617014) (xy 56.034687 -294.571738)
			(xy 56.02291 -294.523954) (xy 56.01895 -294.4749) (xy 55.680102 -294.4749) (xy 55.679607 -294.499507)
			(xy 55.671712 -294.548084) (xy 55.656128 -294.594765) (xy 55.633257 -294.638342) (xy 55.603692 -294.677686)
			(xy 55.568199 -294.711778) (xy 55.527696 -294.739734) (xy 55.483234 -294.760832) (xy 55.435963 -294.774524)
			(xy 55.387108 -294.780456) (xy 55.337933 -294.778475) (xy 55.289714 -294.768631) (xy 55.243698 -294.751179)
			(xy 55.201077 -294.726572) (xy 55.162956 -294.695447) (xy 55.130321 -294.65861) (xy 55.104018 -294.617014)
			(xy 55.084727 -294.571738) (xy 55.07295 -294.523954) (xy 55.06899 -294.4749) (xy 54.730142 -294.4749)
			(xy 54.729647 -294.499507) (xy 54.721752 -294.548084) (xy 54.706168 -294.594765) (xy 54.683297 -294.638342)
			(xy 54.653732 -294.677686) (xy 54.618239 -294.711778) (xy 54.577736 -294.739734) (xy 54.533274 -294.760832)
			(xy 54.486003 -294.774524) (xy 54.437148 -294.780456) (xy 54.387973 -294.778475) (xy 54.339754 -294.768631)
			(xy 54.293738 -294.751179) (xy 54.251117 -294.726572) (xy 54.212996 -294.695447) (xy 54.180361 -294.65861)
			(xy 54.154058 -294.617014) (xy 54.134767 -294.571738) (xy 54.12299 -294.523954) (xy 54.11903 -294.4749)
			(xy 53.780182 -294.4749) (xy 53.779687 -294.499507) (xy 53.771792 -294.548084) (xy 53.756208 -294.594765)
			(xy 53.733337 -294.638342) (xy 53.703772 -294.677686) (xy 53.668279 -294.711778) (xy 53.627776 -294.739734)
			(xy 53.583314 -294.760832) (xy 53.536043 -294.774524) (xy 53.487188 -294.780456) (xy 53.438013 -294.778475)
			(xy 53.389794 -294.768631) (xy 53.343778 -294.751179) (xy 53.301157 -294.726572) (xy 53.263036 -294.695447)
			(xy 53.230401 -294.65861) (xy 53.204098 -294.617014) (xy 53.184807 -294.571738) (xy 53.17303 -294.523954)
			(xy 53.16907 -294.4749) (xy 52.830222 -294.4749) (xy 52.829727 -294.499507) (xy 52.821832 -294.548084)
			(xy 52.806248 -294.594765) (xy 52.783377 -294.638342) (xy 52.753812 -294.677686) (xy 52.718319 -294.711778)
			(xy 52.677816 -294.739734) (xy 52.633354 -294.760832) (xy 52.586083 -294.774524) (xy 52.537228 -294.780456)
			(xy 52.488053 -294.778475) (xy 52.439834 -294.768631) (xy 52.393818 -294.751179) (xy 52.351197 -294.726572)
			(xy 52.313076 -294.695447) (xy 52.280441 -294.65861) (xy 52.254138 -294.617014) (xy 52.234847 -294.571738)
			(xy 52.22307 -294.523954) (xy 52.21911 -294.4749) (xy 51.880262 -294.4749) (xy 51.879767 -294.499507)
			(xy 51.871872 -294.548084) (xy 51.856288 -294.594765) (xy 51.833417 -294.638342) (xy 51.803852 -294.677686)
			(xy 51.768359 -294.711778) (xy 51.727856 -294.739734) (xy 51.683394 -294.760832) (xy 51.636123 -294.774524)
			(xy 51.587268 -294.780456) (xy 51.538093 -294.778475) (xy 51.489874 -294.768631) (xy 51.443858 -294.751179)
			(xy 51.401237 -294.726572) (xy 51.363116 -294.695447) (xy 51.330481 -294.65861) (xy 51.304178 -294.617014)
			(xy 51.284887 -294.571738) (xy 51.27311 -294.523954) (xy 51.26915 -294.4749) (xy 50.930302 -294.4749)
			(xy 50.929807 -294.499507) (xy 50.921912 -294.548084) (xy 50.906328 -294.594765) (xy 50.883457 -294.638342)
			(xy 50.853892 -294.677686) (xy 50.818399 -294.711778) (xy 50.777896 -294.739734) (xy 50.733434 -294.760832)
			(xy 50.686163 -294.774524) (xy 50.637308 -294.780456) (xy 50.588133 -294.778475) (xy 50.539914 -294.768631)
			(xy 50.493898 -294.751179) (xy 50.451277 -294.726572) (xy 50.413156 -294.695447) (xy 50.380521 -294.65861)
			(xy 50.354218 -294.617014) (xy 50.334927 -294.571738) (xy 50.32315 -294.523954) (xy 50.31919 -294.4749)
			(xy 49.980088 -294.4749) (xy 49.979593 -294.499507) (xy 49.971698 -294.548084) (xy 49.956114 -294.594765)
			(xy 49.933243 -294.638342) (xy 49.903678 -294.677686) (xy 49.868185 -294.711778) (xy 49.827682 -294.739734)
			(xy 49.78322 -294.760832) (xy 49.735949 -294.774524) (xy 49.687094 -294.780456) (xy 49.637919 -294.778475)
			(xy 49.5897 -294.768631) (xy 49.543684 -294.751179) (xy 49.501063 -294.726572) (xy 49.462942 -294.695447)
			(xy 49.430307 -294.65861) (xy 49.404004 -294.617014) (xy 49.384713 -294.571738) (xy 49.372936 -294.523954)
			(xy 49.368976 -294.4749) (xy 49.055801 -294.4749) (xy 49.05227 -294.524209) (xy 49.040573 -294.574639)
			(xy 49.021162 -294.62263) (xy 48.994511 -294.667012) (xy 48.961272 -294.7067) (xy 48.922255 -294.740724)
			(xy 48.878413 -294.768255) (xy 48.830818 -294.788619) (xy 48.805846 -294.795448) (xy 48.80483 -294.795702)
			(xy 48.80229 -294.796464) (xy 48.796448 -294.798496) (xy 48.786693 -294.802439) (xy 48.771277 -294.816724)
			(xy 48.762885 -294.835993) (xy 48.762412 -294.846502) (xy 48.762412 -294.950896) (xy 48.762831 -294.960917)
			(xy 48.770501 -294.979433) (xy 48.784673 -294.993604) (xy 48.803191 -295.001271) (xy 48.813212 -295.001696)
			(xy 58.547254 -295.001696) (xy 58.57722 -295.002271) (xy 58.636419 -295.011618) (xy 58.693429 -295.030104)
			(xy 58.746849 -295.057275) (xy 58.795364 -295.092463) (xy 58.817002 -295.113202) (xy 59.059249 -295.355518)
			(xy 92.615764 -295.355518) (xy 92.619835 -295.299896) (xy 92.631961 -295.245459) (xy 92.651884 -295.193368)
			(xy 92.67918 -295.144733) (xy 92.713266 -295.10059) (xy 92.753415 -295.061881) (xy 92.798773 -295.02943)
			(xy 92.848373 -295.003929) (xy 92.901157 -294.985922) (xy 92.956 -294.975792) (xy 93.011734 -294.973755)
			(xy 93.067171 -294.979855) (xy 93.121128 -294.993961) (xy 93.172457 -295.015773) (xy 93.220063 -295.044827)
			(xy 93.262931 -295.080502) (xy 93.300148 -295.122039) (xy 93.330921 -295.168552) (xy 93.354593 -295.219049)
			(xy 93.370661 -295.272456) (xy 93.378781 -295.327632) (xy 93.37929 -295.355518) (xy 93.378781 -295.383404)
			(xy 93.370661 -295.43858) (xy 93.354593 -295.491987) (xy 93.330921 -295.542484) (xy 93.300148 -295.588997)
			(xy 93.262931 -295.630534) (xy 93.220063 -295.666209) (xy 93.172457 -295.695263) (xy 93.121128 -295.717075)
			(xy 93.067171 -295.731181) (xy 93.011734 -295.737281) (xy 92.956 -295.735244) (xy 92.901157 -295.725114)
			(xy 92.848373 -295.707107) (xy 92.798773 -295.681606) (xy 92.753415 -295.649155) (xy 92.713266 -295.610446)
			(xy 92.67918 -295.566303) (xy 92.651884 -295.517668) (xy 92.631961 -295.465577) (xy 92.619835 -295.41114)
			(xy 92.615764 -295.355518) (xy 59.059249 -295.355518) (xy 59.705748 -296.002202) (xy 59.722934 -296.019935)
			(xy 59.753062 -296.059064) (xy 59.77789 -296.101753) (xy 59.78779 -296.124376) (xy 59.793378 -296.137584)
			(xy 59.81573 -296.154094) (xy 59.868308 -296.15892) (xy 59.868816 -296.15892) (xy 59.877452 -296.159682)
			(xy 59.88558 -296.160444) (xy 59.895486 -296.158412) (xy 59.900223 -296.157277) (xy 59.909175 -296.153437)
			(xy 59.913266 -296.150792) (xy 59.920378 -296.14622) (xy 59.922664 -296.144188) (xy 59.943783 -296.126423)
			(xy 59.991093 -296.098019) (xy 60.042722 -296.078539) (xy 60.097004 -296.068612) (xy 60.124594 -296.067988)
			(xy 60.124848 -296.067988) (xy 60.148956 -296.068464) (xy 60.196577 -296.076014) (xy 60.242431 -296.09092)
			(xy 60.285389 -296.112815) (xy 60.324394 -296.141161) (xy 60.358484 -296.175258) (xy 60.38682 -296.214269)
			(xy 60.408706 -296.257232) (xy 60.423602 -296.303089) (xy 60.431141 -296.350712) (xy 60.43168 -296.37482)
			(xy 60.769004 -296.37482) (xy 60.772964 -296.325766) (xy 60.784741 -296.277982) (xy 60.804032 -296.232706)
			(xy 60.830335 -296.19111) (xy 60.86297 -296.154273) (xy 60.901091 -296.123148) (xy 60.943712 -296.098541)
			(xy 60.989728 -296.081089) (xy 61.037947 -296.071245) (xy 61.087122 -296.069264) (xy 61.135977 -296.075196)
			(xy 61.183248 -296.088888) (xy 61.22771 -296.109986) (xy 61.268213 -296.137942) (xy 61.303706 -296.172034)
			(xy 61.333271 -296.211378) (xy 61.356142 -296.254955) (xy 61.371726 -296.301636) (xy 61.379621 -296.350213)
			(xy 61.380116 -296.37482) (xy 61.718964 -296.37482) (xy 61.722924 -296.325766) (xy 61.734701 -296.277982)
			(xy 61.753992 -296.232706) (xy 61.780295 -296.19111) (xy 61.81293 -296.154273) (xy 61.851051 -296.123148)
			(xy 61.893672 -296.098541) (xy 61.939688 -296.081089) (xy 61.987907 -296.071245) (xy 62.037082 -296.069264)
			(xy 62.085937 -296.075196) (xy 62.133208 -296.088888) (xy 62.17767 -296.109986) (xy 62.218173 -296.137942)
			(xy 62.253666 -296.172034) (xy 62.283231 -296.211378) (xy 62.306102 -296.254955) (xy 62.321686 -296.301636)
			(xy 62.329581 -296.350213) (xy 62.330076 -296.37482) (xy 62.669178 -296.37482) (xy 62.673138 -296.325766)
			(xy 62.684915 -296.277982) (xy 62.704206 -296.232706) (xy 62.730509 -296.19111) (xy 62.763144 -296.154273)
			(xy 62.801265 -296.123148) (xy 62.843886 -296.098541) (xy 62.889902 -296.081089) (xy 62.938121 -296.071245)
			(xy 62.987296 -296.069264) (xy 63.036151 -296.075196) (xy 63.083422 -296.088888) (xy 63.127884 -296.109986)
			(xy 63.168387 -296.137942) (xy 63.20388 -296.172034) (xy 63.233445 -296.211378) (xy 63.256316 -296.254955)
			(xy 63.2719 -296.301636) (xy 63.279795 -296.350213) (xy 63.28029 -296.37482) (xy 63.619138 -296.37482)
			(xy 63.623098 -296.325766) (xy 63.634875 -296.277982) (xy 63.654166 -296.232706) (xy 63.680469 -296.19111)
			(xy 63.713104 -296.154273) (xy 63.751225 -296.123148) (xy 63.793846 -296.098541) (xy 63.839862 -296.081089)
			(xy 63.888081 -296.071245) (xy 63.937256 -296.069264) (xy 63.986111 -296.075196) (xy 64.033382 -296.088888)
			(xy 64.077844 -296.109986) (xy 64.118347 -296.137942) (xy 64.15384 -296.172034) (xy 64.183405 -296.211378)
			(xy 64.206276 -296.254955) (xy 64.22186 -296.301636) (xy 64.229755 -296.350213) (xy 64.23025 -296.37482)
			(xy 64.569098 -296.37482) (xy 64.573058 -296.325766) (xy 64.584835 -296.277982) (xy 64.604126 -296.232706)
			(xy 64.630429 -296.19111) (xy 64.663064 -296.154273) (xy 64.701185 -296.123148) (xy 64.743806 -296.098541)
			(xy 64.789822 -296.081089) (xy 64.838041 -296.071245) (xy 64.887216 -296.069264) (xy 64.936071 -296.075196)
			(xy 64.983342 -296.088888) (xy 65.027804 -296.109986) (xy 65.068307 -296.137942) (xy 65.1038 -296.172034)
			(xy 65.133365 -296.211378) (xy 65.156236 -296.254955) (xy 65.17182 -296.301636) (xy 65.179715 -296.350213)
			(xy 65.18021 -296.37482) (xy 65.519058 -296.37482) (xy 65.523018 -296.325766) (xy 65.534795 -296.277982)
			(xy 65.554086 -296.232706) (xy 65.580389 -296.19111) (xy 65.613024 -296.154273) (xy 65.651145 -296.123148)
			(xy 65.693766 -296.098541) (xy 65.739782 -296.081089) (xy 65.788001 -296.071245) (xy 65.837176 -296.069264)
			(xy 65.886031 -296.075196) (xy 65.933302 -296.088888) (xy 65.977764 -296.109986) (xy 66.018267 -296.137942)
			(xy 66.05376 -296.172034) (xy 66.083325 -296.211378) (xy 66.106196 -296.254955) (xy 66.12178 -296.301636)
			(xy 66.129675 -296.350213) (xy 66.13017 -296.37482) (xy 66.469018 -296.37482) (xy 66.472978 -296.325766)
			(xy 66.484755 -296.277982) (xy 66.504046 -296.232706) (xy 66.530349 -296.19111) (xy 66.562984 -296.154273)
			(xy 66.601105 -296.123148) (xy 66.643726 -296.098541) (xy 66.689742 -296.081089) (xy 66.737961 -296.071245)
			(xy 66.787136 -296.069264) (xy 66.835991 -296.075196) (xy 66.883262 -296.088888) (xy 66.927724 -296.109986)
			(xy 66.968227 -296.137942) (xy 67.00372 -296.172034) (xy 67.033285 -296.211378) (xy 67.056156 -296.254955)
			(xy 67.07174 -296.301636) (xy 67.079635 -296.350213) (xy 67.08013 -296.37482) (xy 69.319152 -296.37482)
			(xy 69.323112 -296.325766) (xy 69.334889 -296.277982) (xy 69.35418 -296.232706) (xy 69.380483 -296.19111)
			(xy 69.413118 -296.154273) (xy 69.451239 -296.123148) (xy 69.49386 -296.098541) (xy 69.539876 -296.081089)
			(xy 69.588095 -296.071245) (xy 69.63727 -296.069264) (xy 69.686125 -296.075196) (xy 69.733396 -296.088888)
			(xy 69.777858 -296.109986) (xy 69.818361 -296.137942) (xy 69.853854 -296.172034) (xy 69.883419 -296.211378)
			(xy 69.90629 -296.254955) (xy 69.921874 -296.301636) (xy 69.929769 -296.350213) (xy 69.930264 -296.37482)
			(xy 70.269112 -296.37482) (xy 70.273072 -296.325766) (xy 70.284849 -296.277982) (xy 70.30414 -296.232706)
			(xy 70.330443 -296.19111) (xy 70.363078 -296.154273) (xy 70.401199 -296.123148) (xy 70.44382 -296.098541)
			(xy 70.489836 -296.081089) (xy 70.538055 -296.071245) (xy 70.58723 -296.069264) (xy 70.636085 -296.075196)
			(xy 70.683356 -296.088888) (xy 70.727818 -296.109986) (xy 70.768321 -296.137942) (xy 70.803814 -296.172034)
			(xy 70.833379 -296.211378) (xy 70.85625 -296.254955) (xy 70.871834 -296.301636) (xy 70.879729 -296.350213)
			(xy 70.880224 -296.37482) (xy 71.219072 -296.37482) (xy 71.223032 -296.325766) (xy 71.234809 -296.277982)
			(xy 71.2541 -296.232706) (xy 71.280403 -296.19111) (xy 71.313038 -296.154273) (xy 71.351159 -296.123148)
			(xy 71.39378 -296.098541) (xy 71.439796 -296.081089) (xy 71.488015 -296.071245) (xy 71.53719 -296.069264)
			(xy 71.586045 -296.075196) (xy 71.633316 -296.088888) (xy 71.677778 -296.109986) (xy 71.718281 -296.137942)
			(xy 71.753774 -296.172034) (xy 71.783339 -296.211378) (xy 71.80621 -296.254955) (xy 71.821794 -296.301636)
			(xy 71.829689 -296.350213) (xy 71.830184 -296.37482) (xy 72.169032 -296.37482) (xy 72.172992 -296.325766)
			(xy 72.184769 -296.277982) (xy 72.20406 -296.232706) (xy 72.230363 -296.19111) (xy 72.262998 -296.154273)
			(xy 72.301119 -296.123148) (xy 72.34374 -296.098541) (xy 72.389756 -296.081089) (xy 72.437975 -296.071245)
			(xy 72.48715 -296.069264) (xy 72.536005 -296.075196) (xy 72.583276 -296.088888) (xy 72.627738 -296.109986)
			(xy 72.668241 -296.137942) (xy 72.703734 -296.172034) (xy 72.733299 -296.211378) (xy 72.75617 -296.254955)
			(xy 72.771754 -296.301636) (xy 72.779649 -296.350213) (xy 72.780144 -296.37482) (xy 73.118992 -296.37482)
			(xy 73.122952 -296.325766) (xy 73.134729 -296.277982) (xy 73.15402 -296.232706) (xy 73.180323 -296.19111)
			(xy 73.212958 -296.154273) (xy 73.251079 -296.123148) (xy 73.2937 -296.098541) (xy 73.339716 -296.081089)
			(xy 73.387935 -296.071245) (xy 73.43711 -296.069264) (xy 73.485965 -296.075196) (xy 73.533236 -296.088888)
			(xy 73.577698 -296.109986) (xy 73.618201 -296.137942) (xy 73.653694 -296.172034) (xy 73.683259 -296.211378)
			(xy 73.70613 -296.254955) (xy 73.721714 -296.301636) (xy 73.729609 -296.350213) (xy 73.730104 -296.37482)
			(xy 74.068952 -296.37482) (xy 74.072912 -296.325766) (xy 74.084689 -296.277982) (xy 74.10398 -296.232706)
			(xy 74.130283 -296.19111) (xy 74.162918 -296.154273) (xy 74.201039 -296.123148) (xy 74.24366 -296.098541)
			(xy 74.289676 -296.081089) (xy 74.337895 -296.071245) (xy 74.38707 -296.069264) (xy 74.435925 -296.075196)
			(xy 74.483196 -296.088888) (xy 74.527658 -296.109986) (xy 74.568161 -296.137942) (xy 74.603654 -296.172034)
			(xy 74.633219 -296.211378) (xy 74.65609 -296.254955) (xy 74.671674 -296.301636) (xy 74.679569 -296.350213)
			(xy 74.680064 -296.37482) (xy 75.019166 -296.37482) (xy 75.023126 -296.325766) (xy 75.034903 -296.277982)
			(xy 75.054194 -296.232706) (xy 75.080497 -296.19111) (xy 75.113132 -296.154273) (xy 75.151253 -296.123148)
			(xy 75.193874 -296.098541) (xy 75.23989 -296.081089) (xy 75.288109 -296.071245) (xy 75.337284 -296.069264)
			(xy 75.386139 -296.075196) (xy 75.43341 -296.088888) (xy 75.477872 -296.109986) (xy 75.518375 -296.137942)
			(xy 75.553868 -296.172034) (xy 75.583433 -296.211378) (xy 75.606304 -296.254955) (xy 75.621888 -296.301636)
			(xy 75.629783 -296.350213) (xy 75.630278 -296.37482) (xy 75.969126 -296.37482) (xy 75.973086 -296.325766)
			(xy 75.984863 -296.277982) (xy 76.004154 -296.232706) (xy 76.030457 -296.19111) (xy 76.063092 -296.154273)
			(xy 76.101213 -296.123148) (xy 76.143834 -296.098541) (xy 76.18985 -296.081089) (xy 76.238069 -296.071245)
			(xy 76.287244 -296.069264) (xy 76.336099 -296.075196) (xy 76.38337 -296.088888) (xy 76.427832 -296.109986)
			(xy 76.468335 -296.137942) (xy 76.503828 -296.172034) (xy 76.533393 -296.211378) (xy 76.556264 -296.254955)
			(xy 76.571848 -296.301636) (xy 76.579743 -296.350213) (xy 76.580238 -296.37482) (xy 76.919086 -296.37482)
			(xy 76.923046 -296.325766) (xy 76.934823 -296.277982) (xy 76.954114 -296.232706) (xy 76.980417 -296.19111)
			(xy 77.013052 -296.154273) (xy 77.051173 -296.123148) (xy 77.093794 -296.098541) (xy 77.13981 -296.081089)
			(xy 77.188029 -296.071245) (xy 77.237204 -296.069264) (xy 77.286059 -296.075196) (xy 77.33333 -296.088888)
			(xy 77.377792 -296.109986) (xy 77.418295 -296.137942) (xy 77.453788 -296.172034) (xy 77.483353 -296.211378)
			(xy 77.506224 -296.254955) (xy 77.521808 -296.301636) (xy 77.529703 -296.350213) (xy 77.530198 -296.37482)
			(xy 77.869046 -296.37482) (xy 77.873006 -296.325766) (xy 77.884783 -296.277982) (xy 77.904074 -296.232706)
			(xy 77.930377 -296.19111) (xy 77.963012 -296.154273) (xy 78.001133 -296.123148) (xy 78.043754 -296.098541)
			(xy 78.08977 -296.081089) (xy 78.137989 -296.071245) (xy 78.187164 -296.069264) (xy 78.236019 -296.075196)
			(xy 78.28329 -296.088888) (xy 78.327752 -296.109986) (xy 78.368255 -296.137942) (xy 78.403748 -296.172034)
			(xy 78.433313 -296.211378) (xy 78.456184 -296.254955) (xy 78.471768 -296.301636) (xy 78.479663 -296.350213)
			(xy 78.480158 -296.37482) (xy 78.819006 -296.37482) (xy 78.822966 -296.325766) (xy 78.834743 -296.277982)
			(xy 78.854034 -296.232706) (xy 78.880337 -296.19111) (xy 78.912972 -296.154273) (xy 78.951093 -296.123148)
			(xy 78.993714 -296.098541) (xy 79.03973 -296.081089) (xy 79.087949 -296.071245) (xy 79.137124 -296.069264)
			(xy 79.185979 -296.075196) (xy 79.23325 -296.088888) (xy 79.277712 -296.109986) (xy 79.318215 -296.137942)
			(xy 79.353708 -296.172034) (xy 79.383273 -296.211378) (xy 79.406144 -296.254955) (xy 79.421728 -296.301636)
			(xy 79.429623 -296.350213) (xy 79.430118 -296.37482) (xy 79.768966 -296.37482) (xy 79.772926 -296.325766)
			(xy 79.784703 -296.277982) (xy 79.803994 -296.232706) (xy 79.830297 -296.19111) (xy 79.862932 -296.154273)
			(xy 79.901053 -296.123148) (xy 79.943674 -296.098541) (xy 79.98969 -296.081089) (xy 80.037909 -296.071245)
			(xy 80.087084 -296.069264) (xy 80.135939 -296.075196) (xy 80.18321 -296.088888) (xy 80.227672 -296.109986)
			(xy 80.268175 -296.137942) (xy 80.303668 -296.172034) (xy 80.333233 -296.211378) (xy 80.356104 -296.254955)
			(xy 80.371688 -296.301636) (xy 80.379583 -296.350213) (xy 80.380078 -296.37482) (xy 80.71918 -296.37482)
			(xy 80.72314 -296.325766) (xy 80.734917 -296.277982) (xy 80.754208 -296.232706) (xy 80.780511 -296.19111)
			(xy 80.813146 -296.154273) (xy 80.851267 -296.123148) (xy 80.893888 -296.098541) (xy 80.939904 -296.081089)
			(xy 80.988123 -296.071245) (xy 81.037298 -296.069264) (xy 81.086153 -296.075196) (xy 81.133424 -296.088888)
			(xy 81.177886 -296.109986) (xy 81.218389 -296.137942) (xy 81.253882 -296.172034) (xy 81.283447 -296.211378)
			(xy 81.306318 -296.254955) (xy 81.321902 -296.301636) (xy 81.329797 -296.350213) (xy 81.330292 -296.37482)
			(xy 81.66914 -296.37482) (xy 81.6731 -296.325766) (xy 81.684877 -296.277982) (xy 81.704168 -296.232706)
			(xy 81.730471 -296.19111) (xy 81.763106 -296.154273) (xy 81.801227 -296.123148) (xy 81.843848 -296.098541)
			(xy 81.889864 -296.081089) (xy 81.938083 -296.071245) (xy 81.987258 -296.069264) (xy 82.036113 -296.075196)
			(xy 82.083384 -296.088888) (xy 82.127846 -296.109986) (xy 82.168349 -296.137942) (xy 82.203842 -296.172034)
			(xy 82.233407 -296.211378) (xy 82.256278 -296.254955) (xy 82.271862 -296.301636) (xy 82.279757 -296.350213)
			(xy 82.280252 -296.37482) (xy 82.6191 -296.37482) (xy 82.62306 -296.325766) (xy 82.634837 -296.277982)
			(xy 82.654128 -296.232706) (xy 82.680431 -296.19111) (xy 82.713066 -296.154273) (xy 82.751187 -296.123148)
			(xy 82.793808 -296.098541) (xy 82.839824 -296.081089) (xy 82.888043 -296.071245) (xy 82.937218 -296.069264)
			(xy 82.986073 -296.075196) (xy 83.033344 -296.088888) (xy 83.077806 -296.109986) (xy 83.118309 -296.137942)
			(xy 83.153802 -296.172034) (xy 83.183367 -296.211378) (xy 83.206238 -296.254955) (xy 83.221822 -296.301636)
			(xy 83.229717 -296.350213) (xy 83.230212 -296.37482) (xy 83.229717 -296.399427) (xy 83.221822 -296.448004)
			(xy 83.206238 -296.494685) (xy 83.183367 -296.538262) (xy 83.153802 -296.577606) (xy 83.118309 -296.611698)
			(xy 83.116318 -296.613072) (xy 89.262456 -296.613072) (xy 89.266527 -296.55745) (xy 89.278653 -296.503013)
			(xy 89.298576 -296.450922) (xy 89.325872 -296.402287) (xy 89.359958 -296.358144) (xy 89.400107 -296.319435)
			(xy 89.445465 -296.286984) (xy 89.495065 -296.261483) (xy 89.547849 -296.243476) (xy 89.602692 -296.233346)
			(xy 89.658426 -296.231309) (xy 89.713863 -296.237409) (xy 89.76782 -296.251515) (xy 89.819149 -296.273327)
			(xy 89.866755 -296.302381) (xy 89.909623 -296.338056) (xy 89.94684 -296.379593) (xy 89.977613 -296.426106)
			(xy 90.001285 -296.476603) (xy 90.017353 -296.53001) (xy 90.025473 -296.585186) (xy 90.025982 -296.613072)
			(xy 90.537282 -296.613072) (xy 90.541353 -296.55745) (xy 90.553479 -296.503013) (xy 90.573402 -296.450922)
			(xy 90.600698 -296.402287) (xy 90.634784 -296.358144) (xy 90.674933 -296.319435) (xy 90.720291 -296.286984)
			(xy 90.769891 -296.261483) (xy 90.822675 -296.243476) (xy 90.877518 -296.233346) (xy 90.933252 -296.231309)
			(xy 90.988689 -296.237409) (xy 91.042646 -296.251515) (xy 91.093975 -296.273327) (xy 91.141581 -296.302381)
			(xy 91.184449 -296.338056) (xy 91.221666 -296.379593) (xy 91.252439 -296.426106) (xy 91.276111 -296.476603)
			(xy 91.292179 -296.53001) (xy 91.300299 -296.585186) (xy 91.300808 -296.613072) (xy 91.300299 -296.640958)
			(xy 91.292179 -296.696134) (xy 91.276111 -296.749541) (xy 91.252439 -296.800038) (xy 91.221666 -296.846551)
			(xy 91.184449 -296.888088) (xy 91.141581 -296.923763) (xy 91.093975 -296.952817) (xy 91.042646 -296.974629)
			(xy 90.988689 -296.988735) (xy 90.933252 -296.994835) (xy 90.877518 -296.992798) (xy 90.822675 -296.982668)
			(xy 90.769891 -296.964661) (xy 90.720291 -296.93916) (xy 90.674933 -296.906709) (xy 90.634784 -296.868)
			(xy 90.600698 -296.823857) (xy 90.573402 -296.775222) (xy 90.553479 -296.723131) (xy 90.541353 -296.668694)
			(xy 90.537282 -296.613072) (xy 90.025982 -296.613072) (xy 90.025473 -296.640958) (xy 90.017353 -296.696134)
			(xy 90.001285 -296.749541) (xy 89.977613 -296.800038) (xy 89.94684 -296.846551) (xy 89.909623 -296.888088)
			(xy 89.866755 -296.923763) (xy 89.819149 -296.952817) (xy 89.76782 -296.974629) (xy 89.713863 -296.988735)
			(xy 89.658426 -296.994835) (xy 89.602692 -296.992798) (xy 89.547849 -296.982668) (xy 89.495065 -296.964661)
			(xy 89.445465 -296.93916) (xy 89.400107 -296.906709) (xy 89.359958 -296.868) (xy 89.325872 -296.823857)
			(xy 89.298576 -296.775222) (xy 89.278653 -296.723131) (xy 89.266527 -296.668694) (xy 89.262456 -296.613072)
			(xy 83.116318 -296.613072) (xy 83.077806 -296.639654) (xy 83.033344 -296.660752) (xy 82.986073 -296.674444)
			(xy 82.937218 -296.680376) (xy 82.888043 -296.678395) (xy 82.839824 -296.668551) (xy 82.793808 -296.651099)
			(xy 82.751187 -296.626492) (xy 82.713066 -296.595367) (xy 82.680431 -296.55853) (xy 82.654128 -296.516934)
			(xy 82.634837 -296.471658) (xy 82.62306 -296.423874) (xy 82.6191 -296.37482) (xy 82.280252 -296.37482)
			(xy 82.279757 -296.399427) (xy 82.271862 -296.448004) (xy 82.256278 -296.494685) (xy 82.233407 -296.538262)
			(xy 82.203842 -296.577606) (xy 82.168349 -296.611698) (xy 82.127846 -296.639654) (xy 82.083384 -296.660752)
			(xy 82.036113 -296.674444) (xy 81.987258 -296.680376) (xy 81.938083 -296.678395) (xy 81.889864 -296.668551)
			(xy 81.843848 -296.651099) (xy 81.801227 -296.626492) (xy 81.763106 -296.595367) (xy 81.730471 -296.55853)
			(xy 81.704168 -296.516934) (xy 81.684877 -296.471658) (xy 81.6731 -296.423874) (xy 81.66914 -296.37482)
			(xy 81.330292 -296.37482) (xy 81.329797 -296.399427) (xy 81.321902 -296.448004) (xy 81.306318 -296.494685)
			(xy 81.283447 -296.538262) (xy 81.253882 -296.577606) (xy 81.218389 -296.611698) (xy 81.177886 -296.639654)
			(xy 81.133424 -296.660752) (xy 81.086153 -296.674444) (xy 81.037298 -296.680376) (xy 80.988123 -296.678395)
			(xy 80.939904 -296.668551) (xy 80.893888 -296.651099) (xy 80.851267 -296.626492) (xy 80.813146 -296.595367)
			(xy 80.780511 -296.55853) (xy 80.754208 -296.516934) (xy 80.734917 -296.471658) (xy 80.72314 -296.423874)
			(xy 80.71918 -296.37482) (xy 80.380078 -296.37482) (xy 80.379583 -296.399427) (xy 80.371688 -296.448004)
			(xy 80.356104 -296.494685) (xy 80.333233 -296.538262) (xy 80.303668 -296.577606) (xy 80.268175 -296.611698)
			(xy 80.227672 -296.639654) (xy 80.18321 -296.660752) (xy 80.135939 -296.674444) (xy 80.087084 -296.680376)
			(xy 80.037909 -296.678395) (xy 79.98969 -296.668551) (xy 79.943674 -296.651099) (xy 79.901053 -296.626492)
			(xy 79.862932 -296.595367) (xy 79.830297 -296.55853) (xy 79.803994 -296.516934) (xy 79.784703 -296.471658)
			(xy 79.772926 -296.423874) (xy 79.768966 -296.37482) (xy 79.430118 -296.37482) (xy 79.429623 -296.399427)
			(xy 79.421728 -296.448004) (xy 79.406144 -296.494685) (xy 79.383273 -296.538262) (xy 79.353708 -296.577606)
			(xy 79.318215 -296.611698) (xy 79.277712 -296.639654) (xy 79.23325 -296.660752) (xy 79.185979 -296.674444)
			(xy 79.137124 -296.680376) (xy 79.087949 -296.678395) (xy 79.03973 -296.668551) (xy 78.993714 -296.651099)
			(xy 78.951093 -296.626492) (xy 78.912972 -296.595367) (xy 78.880337 -296.55853) (xy 78.854034 -296.516934)
			(xy 78.834743 -296.471658) (xy 78.822966 -296.423874) (xy 78.819006 -296.37482) (xy 78.480158 -296.37482)
			(xy 78.479663 -296.399427) (xy 78.471768 -296.448004) (xy 78.456184 -296.494685) (xy 78.433313 -296.538262)
			(xy 78.403748 -296.577606) (xy 78.368255 -296.611698) (xy 78.327752 -296.639654) (xy 78.28329 -296.660752)
			(xy 78.236019 -296.674444) (xy 78.187164 -296.680376) (xy 78.137989 -296.678395) (xy 78.08977 -296.668551)
			(xy 78.043754 -296.651099) (xy 78.001133 -296.626492) (xy 77.963012 -296.595367) (xy 77.930377 -296.55853)
			(xy 77.904074 -296.516934) (xy 77.884783 -296.471658) (xy 77.873006 -296.423874) (xy 77.869046 -296.37482)
			(xy 77.530198 -296.37482) (xy 77.529703 -296.399427) (xy 77.521808 -296.448004) (xy 77.506224 -296.494685)
			(xy 77.483353 -296.538262) (xy 77.453788 -296.577606) (xy 77.418295 -296.611698) (xy 77.377792 -296.639654)
			(xy 77.33333 -296.660752) (xy 77.286059 -296.674444) (xy 77.237204 -296.680376) (xy 77.188029 -296.678395)
			(xy 77.13981 -296.668551) (xy 77.093794 -296.651099) (xy 77.051173 -296.626492) (xy 77.013052 -296.595367)
			(xy 76.980417 -296.55853) (xy 76.954114 -296.516934) (xy 76.934823 -296.471658) (xy 76.923046 -296.423874)
			(xy 76.919086 -296.37482) (xy 76.580238 -296.37482) (xy 76.579743 -296.399427) (xy 76.571848 -296.448004)
			(xy 76.556264 -296.494685) (xy 76.533393 -296.538262) (xy 76.503828 -296.577606) (xy 76.468335 -296.611698)
			(xy 76.427832 -296.639654) (xy 76.38337 -296.660752) (xy 76.336099 -296.674444) (xy 76.287244 -296.680376)
			(xy 76.238069 -296.678395) (xy 76.18985 -296.668551) (xy 76.143834 -296.651099) (xy 76.101213 -296.626492)
			(xy 76.063092 -296.595367) (xy 76.030457 -296.55853) (xy 76.004154 -296.516934) (xy 75.984863 -296.471658)
			(xy 75.973086 -296.423874) (xy 75.969126 -296.37482) (xy 75.630278 -296.37482) (xy 75.629783 -296.399427)
			(xy 75.621888 -296.448004) (xy 75.606304 -296.494685) (xy 75.583433 -296.538262) (xy 75.553868 -296.577606)
			(xy 75.518375 -296.611698) (xy 75.477872 -296.639654) (xy 75.43341 -296.660752) (xy 75.386139 -296.674444)
			(xy 75.337284 -296.680376) (xy 75.288109 -296.678395) (xy 75.23989 -296.668551) (xy 75.193874 -296.651099)
			(xy 75.151253 -296.626492) (xy 75.113132 -296.595367) (xy 75.080497 -296.55853) (xy 75.054194 -296.516934)
			(xy 75.034903 -296.471658) (xy 75.023126 -296.423874) (xy 75.019166 -296.37482) (xy 74.680064 -296.37482)
			(xy 74.679569 -296.399427) (xy 74.671674 -296.448004) (xy 74.65609 -296.494685) (xy 74.633219 -296.538262)
			(xy 74.603654 -296.577606) (xy 74.568161 -296.611698) (xy 74.527658 -296.639654) (xy 74.483196 -296.660752)
			(xy 74.435925 -296.674444) (xy 74.38707 -296.680376) (xy 74.337895 -296.678395) (xy 74.289676 -296.668551)
			(xy 74.24366 -296.651099) (xy 74.201039 -296.626492) (xy 74.162918 -296.595367) (xy 74.130283 -296.55853)
			(xy 74.10398 -296.516934) (xy 74.084689 -296.471658) (xy 74.072912 -296.423874) (xy 74.068952 -296.37482)
			(xy 73.730104 -296.37482) (xy 73.729609 -296.399427) (xy 73.721714 -296.448004) (xy 73.70613 -296.494685)
			(xy 73.683259 -296.538262) (xy 73.653694 -296.577606) (xy 73.618201 -296.611698) (xy 73.577698 -296.639654)
			(xy 73.533236 -296.660752) (xy 73.485965 -296.674444) (xy 73.43711 -296.680376) (xy 73.387935 -296.678395)
			(xy 73.339716 -296.668551) (xy 73.2937 -296.651099) (xy 73.251079 -296.626492) (xy 73.212958 -296.595367)
			(xy 73.180323 -296.55853) (xy 73.15402 -296.516934) (xy 73.134729 -296.471658) (xy 73.122952 -296.423874)
			(xy 73.118992 -296.37482) (xy 72.780144 -296.37482) (xy 72.779649 -296.399427) (xy 72.771754 -296.448004)
			(xy 72.75617 -296.494685) (xy 72.733299 -296.538262) (xy 72.703734 -296.577606) (xy 72.668241 -296.611698)
			(xy 72.627738 -296.639654) (xy 72.583276 -296.660752) (xy 72.536005 -296.674444) (xy 72.48715 -296.680376)
			(xy 72.437975 -296.678395) (xy 72.389756 -296.668551) (xy 72.34374 -296.651099) (xy 72.301119 -296.626492)
			(xy 72.262998 -296.595367) (xy 72.230363 -296.55853) (xy 72.20406 -296.516934) (xy 72.184769 -296.471658)
			(xy 72.172992 -296.423874) (xy 72.169032 -296.37482) (xy 71.830184 -296.37482) (xy 71.829689 -296.399427)
			(xy 71.821794 -296.448004) (xy 71.80621 -296.494685) (xy 71.783339 -296.538262) (xy 71.753774 -296.577606)
			(xy 71.718281 -296.611698) (xy 71.677778 -296.639654) (xy 71.633316 -296.660752) (xy 71.586045 -296.674444)
			(xy 71.53719 -296.680376) (xy 71.488015 -296.678395) (xy 71.439796 -296.668551) (xy 71.39378 -296.651099)
			(xy 71.351159 -296.626492) (xy 71.313038 -296.595367) (xy 71.280403 -296.55853) (xy 71.2541 -296.516934)
			(xy 71.234809 -296.471658) (xy 71.223032 -296.423874) (xy 71.219072 -296.37482) (xy 70.880224 -296.37482)
			(xy 70.879729 -296.399427) (xy 70.871834 -296.448004) (xy 70.85625 -296.494685) (xy 70.833379 -296.538262)
			(xy 70.803814 -296.577606) (xy 70.768321 -296.611698) (xy 70.727818 -296.639654) (xy 70.683356 -296.660752)
			(xy 70.636085 -296.674444) (xy 70.58723 -296.680376) (xy 70.538055 -296.678395) (xy 70.489836 -296.668551)
			(xy 70.44382 -296.651099) (xy 70.401199 -296.626492) (xy 70.363078 -296.595367) (xy 70.330443 -296.55853)
			(xy 70.30414 -296.516934) (xy 70.284849 -296.471658) (xy 70.273072 -296.423874) (xy 70.269112 -296.37482)
			(xy 69.930264 -296.37482) (xy 69.929769 -296.399427) (xy 69.921874 -296.448004) (xy 69.90629 -296.494685)
			(xy 69.883419 -296.538262) (xy 69.853854 -296.577606) (xy 69.818361 -296.611698) (xy 69.777858 -296.639654)
			(xy 69.733396 -296.660752) (xy 69.686125 -296.674444) (xy 69.63727 -296.680376) (xy 69.588095 -296.678395)
			(xy 69.539876 -296.668551) (xy 69.49386 -296.651099) (xy 69.451239 -296.626492) (xy 69.413118 -296.595367)
			(xy 69.380483 -296.55853) (xy 69.35418 -296.516934) (xy 69.334889 -296.471658) (xy 69.323112 -296.423874)
			(xy 69.319152 -296.37482) (xy 67.08013 -296.37482) (xy 67.079635 -296.399427) (xy 67.07174 -296.448004)
			(xy 67.056156 -296.494685) (xy 67.033285 -296.538262) (xy 67.00372 -296.577606) (xy 66.968227 -296.611698)
			(xy 66.927724 -296.639654) (xy 66.883262 -296.660752) (xy 66.835991 -296.674444) (xy 66.787136 -296.680376)
			(xy 66.737961 -296.678395) (xy 66.689742 -296.668551) (xy 66.643726 -296.651099) (xy 66.601105 -296.626492)
			(xy 66.562984 -296.595367) (xy 66.530349 -296.55853) (xy 66.504046 -296.516934) (xy 66.484755 -296.471658)
			(xy 66.472978 -296.423874) (xy 66.469018 -296.37482) (xy 66.13017 -296.37482) (xy 66.129675 -296.399427)
			(xy 66.12178 -296.448004) (xy 66.106196 -296.494685) (xy 66.083325 -296.538262) (xy 66.05376 -296.577606)
			(xy 66.018267 -296.611698) (xy 65.977764 -296.639654) (xy 65.933302 -296.660752) (xy 65.886031 -296.674444)
			(xy 65.837176 -296.680376) (xy 65.788001 -296.678395) (xy 65.739782 -296.668551) (xy 65.693766 -296.651099)
			(xy 65.651145 -296.626492) (xy 65.613024 -296.595367) (xy 65.580389 -296.55853) (xy 65.554086 -296.516934)
			(xy 65.534795 -296.471658) (xy 65.523018 -296.423874) (xy 65.519058 -296.37482) (xy 65.18021 -296.37482)
			(xy 65.179715 -296.399427) (xy 65.17182 -296.448004) (xy 65.156236 -296.494685) (xy 65.133365 -296.538262)
			(xy 65.1038 -296.577606) (xy 65.068307 -296.611698) (xy 65.027804 -296.639654) (xy 64.983342 -296.660752)
			(xy 64.936071 -296.674444) (xy 64.887216 -296.680376) (xy 64.838041 -296.678395) (xy 64.789822 -296.668551)
			(xy 64.743806 -296.651099) (xy 64.701185 -296.626492) (xy 64.663064 -296.595367) (xy 64.630429 -296.55853)
			(xy 64.604126 -296.516934) (xy 64.584835 -296.471658) (xy 64.573058 -296.423874) (xy 64.569098 -296.37482)
			(xy 64.23025 -296.37482) (xy 64.229755 -296.399427) (xy 64.22186 -296.448004) (xy 64.206276 -296.494685)
			(xy 64.183405 -296.538262) (xy 64.15384 -296.577606) (xy 64.118347 -296.611698) (xy 64.077844 -296.639654)
			(xy 64.033382 -296.660752) (xy 63.986111 -296.674444) (xy 63.937256 -296.680376) (xy 63.888081 -296.678395)
			(xy 63.839862 -296.668551) (xy 63.793846 -296.651099) (xy 63.751225 -296.626492) (xy 63.713104 -296.595367)
			(xy 63.680469 -296.55853) (xy 63.654166 -296.516934) (xy 63.634875 -296.471658) (xy 63.623098 -296.423874)
			(xy 63.619138 -296.37482) (xy 63.28029 -296.37482) (xy 63.279795 -296.399427) (xy 63.2719 -296.448004)
			(xy 63.256316 -296.494685) (xy 63.233445 -296.538262) (xy 63.20388 -296.577606) (xy 63.168387 -296.611698)
			(xy 63.127884 -296.639654) (xy 63.083422 -296.660752) (xy 63.036151 -296.674444) (xy 62.987296 -296.680376)
			(xy 62.938121 -296.678395) (xy 62.889902 -296.668551) (xy 62.843886 -296.651099) (xy 62.801265 -296.626492)
			(xy 62.763144 -296.595367) (xy 62.730509 -296.55853) (xy 62.704206 -296.516934) (xy 62.684915 -296.471658)
			(xy 62.673138 -296.423874) (xy 62.669178 -296.37482) (xy 62.330076 -296.37482) (xy 62.329581 -296.399427)
			(xy 62.321686 -296.448004) (xy 62.306102 -296.494685) (xy 62.283231 -296.538262) (xy 62.253666 -296.577606)
			(xy 62.218173 -296.611698) (xy 62.17767 -296.639654) (xy 62.133208 -296.660752) (xy 62.085937 -296.674444)
			(xy 62.037082 -296.680376) (xy 61.987907 -296.678395) (xy 61.939688 -296.668551) (xy 61.893672 -296.651099)
			(xy 61.851051 -296.626492) (xy 61.81293 -296.595367) (xy 61.780295 -296.55853) (xy 61.753992 -296.516934)
			(xy 61.734701 -296.471658) (xy 61.722924 -296.423874) (xy 61.718964 -296.37482) (xy 61.380116 -296.37482)
			(xy 61.379621 -296.399427) (xy 61.371726 -296.448004) (xy 61.356142 -296.494685) (xy 61.333271 -296.538262)
			(xy 61.303706 -296.577606) (xy 61.268213 -296.611698) (xy 61.22771 -296.639654) (xy 61.183248 -296.660752)
			(xy 61.135977 -296.674444) (xy 61.087122 -296.680376) (xy 61.037947 -296.678395) (xy 60.989728 -296.668551)
			(xy 60.943712 -296.651099) (xy 60.901091 -296.626492) (xy 60.86297 -296.595367) (xy 60.830335 -296.55853)
			(xy 60.804032 -296.516934) (xy 60.784741 -296.471658) (xy 60.772964 -296.423874) (xy 60.769004 -296.37482)
			(xy 60.43168 -296.37482) (xy 60.431207 -296.398919) (xy 60.423669 -296.446523) (xy 60.408782 -296.492363)
			(xy 60.386911 -296.535313) (xy 60.358595 -296.574316) (xy 60.32453 -296.608412) (xy 60.285554 -296.636764)
			(xy 60.242624 -296.658674) (xy 60.196798 -296.673603) (xy 60.1492 -296.681184) (xy 60.125102 -296.681652)
			(xy 60.124848 -296.681652) (xy 60.094186 -296.680657) (xy 60.034169 -296.667992) (xy 60.005722 -296.656506)
			(xy 59.99607 -296.652188) (xy 59.965844 -296.652188) (xy 59.958598 -296.652407) (xy 59.944669 -296.656402)
			(xy 59.938412 -296.660062) (xy 59.87415 -296.70121) (xy 59.867191 -296.706065) (xy 59.856702 -296.719391)
			(xy 59.851117 -296.735404) (xy 59.850782 -296.743882) (xy 59.850782 -296.955972) (xy 59.851218 -296.966037)
			(xy 59.858948 -296.984624) (xy 59.865768 -296.99204) (xy 59.868054 -296.994326) (xy 59.872626 -296.997882)
			(xy 59.906408 -297.019726) (xy 59.906916 -297.019726) (xy 59.937396 -297.039792) (xy 59.943725 -297.043661)
			(xy 59.957923 -297.047928) (xy 59.965336 -297.048174) (xy 59.985402 -297.048174) (xy 59.99734 -297.045634)
			(xy 60.00242 -297.043602) (xy 60.003182 -297.043348) (xy 60.022464 -297.035366) (xy 60.062646 -297.024094)
			(xy 60.103983 -297.018361) (xy 60.124848 -297.017948) (xy 60.148957 -297.018424) (xy 60.196581 -297.025974)
			(xy 60.242437 -297.040879) (xy 60.285398 -297.062774) (xy 60.324406 -297.091118) (xy 60.3585 -297.125215)
			(xy 60.386841 -297.164226) (xy 60.408732 -297.207188) (xy 60.423633 -297.253047) (xy 60.431178 -297.300671)
			(xy 60.43168 -297.32478) (xy 60.769004 -297.32478) (xy 60.772964 -297.275726) (xy 60.784741 -297.227942)
			(xy 60.804032 -297.182666) (xy 60.830335 -297.14107) (xy 60.86297 -297.104233) (xy 60.901091 -297.073108)
			(xy 60.943712 -297.048501) (xy 60.989728 -297.031049) (xy 61.037947 -297.021205) (xy 61.087122 -297.019224)
			(xy 61.135977 -297.025156) (xy 61.183248 -297.038848) (xy 61.22771 -297.059946) (xy 61.268213 -297.087902)
			(xy 61.303706 -297.121994) (xy 61.333271 -297.161338) (xy 61.356142 -297.204915) (xy 61.371726 -297.251596)
			(xy 61.379621 -297.300173) (xy 61.380116 -297.32478) (xy 61.718964 -297.32478) (xy 61.722924 -297.275726)
			(xy 61.734701 -297.227942) (xy 61.753992 -297.182666) (xy 61.780295 -297.14107) (xy 61.81293 -297.104233)
			(xy 61.851051 -297.073108) (xy 61.893672 -297.048501) (xy 61.939688 -297.031049) (xy 61.987907 -297.021205)
			(xy 62.037082 -297.019224) (xy 62.085937 -297.025156) (xy 62.133208 -297.038848) (xy 62.17767 -297.059946)
			(xy 62.218173 -297.087902) (xy 62.253666 -297.121994) (xy 62.283231 -297.161338) (xy 62.306102 -297.204915)
			(xy 62.321686 -297.251596) (xy 62.329581 -297.300173) (xy 62.330076 -297.32478) (xy 62.669178 -297.32478)
			(xy 62.673138 -297.275726) (xy 62.684915 -297.227942) (xy 62.704206 -297.182666) (xy 62.730509 -297.14107)
			(xy 62.763144 -297.104233) (xy 62.801265 -297.073108) (xy 62.843886 -297.048501) (xy 62.889902 -297.031049)
			(xy 62.938121 -297.021205) (xy 62.987296 -297.019224) (xy 63.036151 -297.025156) (xy 63.083422 -297.038848)
			(xy 63.127884 -297.059946) (xy 63.168387 -297.087902) (xy 63.20388 -297.121994) (xy 63.233445 -297.161338)
			(xy 63.256316 -297.204915) (xy 63.2719 -297.251596) (xy 63.279795 -297.300173) (xy 63.28029 -297.32478)
			(xy 63.619138 -297.32478) (xy 63.623098 -297.275726) (xy 63.634875 -297.227942) (xy 63.654166 -297.182666)
			(xy 63.680469 -297.14107) (xy 63.713104 -297.104233) (xy 63.751225 -297.073108) (xy 63.793846 -297.048501)
			(xy 63.839862 -297.031049) (xy 63.888081 -297.021205) (xy 63.937256 -297.019224) (xy 63.986111 -297.025156)
			(xy 64.033382 -297.038848) (xy 64.077844 -297.059946) (xy 64.118347 -297.087902) (xy 64.15384 -297.121994)
			(xy 64.183405 -297.161338) (xy 64.206276 -297.204915) (xy 64.22186 -297.251596) (xy 64.229755 -297.300173)
			(xy 64.23025 -297.32478) (xy 64.569098 -297.32478) (xy 64.573058 -297.275726) (xy 64.584835 -297.227942)
			(xy 64.604126 -297.182666) (xy 64.630429 -297.14107) (xy 64.663064 -297.104233) (xy 64.701185 -297.073108)
			(xy 64.743806 -297.048501) (xy 64.789822 -297.031049) (xy 64.838041 -297.021205) (xy 64.887216 -297.019224)
			(xy 64.936071 -297.025156) (xy 64.983342 -297.038848) (xy 65.027804 -297.059946) (xy 65.068307 -297.087902)
			(xy 65.1038 -297.121994) (xy 65.133365 -297.161338) (xy 65.156236 -297.204915) (xy 65.17182 -297.251596)
			(xy 65.179715 -297.300173) (xy 65.18021 -297.32478) (xy 65.519058 -297.32478) (xy 65.523018 -297.275726)
			(xy 65.534795 -297.227942) (xy 65.554086 -297.182666) (xy 65.580389 -297.14107) (xy 65.613024 -297.104233)
			(xy 65.651145 -297.073108) (xy 65.693766 -297.048501) (xy 65.739782 -297.031049) (xy 65.788001 -297.021205)
			(xy 65.837176 -297.019224) (xy 65.886031 -297.025156) (xy 65.933302 -297.038848) (xy 65.977764 -297.059946)
			(xy 66.018267 -297.087902) (xy 66.05376 -297.121994) (xy 66.083325 -297.161338) (xy 66.106196 -297.204915)
			(xy 66.12178 -297.251596) (xy 66.129675 -297.300173) (xy 66.13017 -297.32478) (xy 69.319152 -297.32478)
			(xy 69.323112 -297.275726) (xy 69.334889 -297.227942) (xy 69.35418 -297.182666) (xy 69.380483 -297.14107)
			(xy 69.413118 -297.104233) (xy 69.451239 -297.073108) (xy 69.49386 -297.048501) (xy 69.539876 -297.031049)
			(xy 69.588095 -297.021205) (xy 69.63727 -297.019224) (xy 69.686125 -297.025156) (xy 69.733396 -297.038848)
			(xy 69.777858 -297.059946) (xy 69.818361 -297.087902) (xy 69.853854 -297.121994) (xy 69.883419 -297.161338)
			(xy 69.90629 -297.204915) (xy 69.921874 -297.251596) (xy 69.929769 -297.300173) (xy 69.930264 -297.32478)
			(xy 70.269112 -297.32478) (xy 70.273072 -297.275726) (xy 70.284849 -297.227942) (xy 70.30414 -297.182666)
			(xy 70.330443 -297.14107) (xy 70.363078 -297.104233) (xy 70.401199 -297.073108) (xy 70.44382 -297.048501)
			(xy 70.489836 -297.031049) (xy 70.538055 -297.021205) (xy 70.58723 -297.019224) (xy 70.636085 -297.025156)
			(xy 70.683356 -297.038848) (xy 70.727818 -297.059946) (xy 70.768321 -297.087902) (xy 70.803814 -297.121994)
			(xy 70.833379 -297.161338) (xy 70.85625 -297.204915) (xy 70.871834 -297.251596) (xy 70.879729 -297.300173)
			(xy 70.880224 -297.32478) (xy 71.219072 -297.32478) (xy 71.223032 -297.275726) (xy 71.234809 -297.227942)
			(xy 71.2541 -297.182666) (xy 71.280403 -297.14107) (xy 71.313038 -297.104233) (xy 71.351159 -297.073108)
			(xy 71.39378 -297.048501) (xy 71.439796 -297.031049) (xy 71.488015 -297.021205) (xy 71.53719 -297.019224)
			(xy 71.586045 -297.025156) (xy 71.633316 -297.038848) (xy 71.677778 -297.059946) (xy 71.718281 -297.087902)
			(xy 71.753774 -297.121994) (xy 71.783339 -297.161338) (xy 71.80621 -297.204915) (xy 71.821794 -297.251596)
			(xy 71.829689 -297.300173) (xy 71.830184 -297.32478) (xy 72.169032 -297.32478) (xy 72.172992 -297.275726)
			(xy 72.184769 -297.227942) (xy 72.20406 -297.182666) (xy 72.230363 -297.14107) (xy 72.262998 -297.104233)
			(xy 72.301119 -297.073108) (xy 72.34374 -297.048501) (xy 72.389756 -297.031049) (xy 72.437975 -297.021205)
			(xy 72.48715 -297.019224) (xy 72.536005 -297.025156) (xy 72.583276 -297.038848) (xy 72.627738 -297.059946)
			(xy 72.668241 -297.087902) (xy 72.703734 -297.121994) (xy 72.733299 -297.161338) (xy 72.75617 -297.204915)
			(xy 72.771754 -297.251596) (xy 72.779649 -297.300173) (xy 72.780144 -297.32478) (xy 73.118992 -297.32478)
			(xy 73.122952 -297.275726) (xy 73.134729 -297.227942) (xy 73.15402 -297.182666) (xy 73.180323 -297.14107)
			(xy 73.212958 -297.104233) (xy 73.251079 -297.073108) (xy 73.2937 -297.048501) (xy 73.339716 -297.031049)
			(xy 73.387935 -297.021205) (xy 73.43711 -297.019224) (xy 73.485965 -297.025156) (xy 73.533236 -297.038848)
			(xy 73.577698 -297.059946) (xy 73.618201 -297.087902) (xy 73.653694 -297.121994) (xy 73.683259 -297.161338)
			(xy 73.70613 -297.204915) (xy 73.721714 -297.251596) (xy 73.729609 -297.300173) (xy 73.730104 -297.32478)
			(xy 74.069206 -297.32478) (xy 74.073166 -297.275726) (xy 74.084943 -297.227942) (xy 74.104234 -297.182666)
			(xy 74.130537 -297.14107) (xy 74.163172 -297.104233) (xy 74.201293 -297.073108) (xy 74.243914 -297.048501)
			(xy 74.28993 -297.031049) (xy 74.338149 -297.021205) (xy 74.387324 -297.019224) (xy 74.436179 -297.025156)
			(xy 74.48345 -297.038848) (xy 74.527912 -297.059946) (xy 74.568415 -297.087902) (xy 74.603908 -297.121994)
			(xy 74.633473 -297.161338) (xy 74.656344 -297.204915) (xy 74.671928 -297.251596) (xy 74.679823 -297.300173)
			(xy 74.680318 -297.32478) (xy 75.019166 -297.32478) (xy 75.023126 -297.275726) (xy 75.034903 -297.227942)
			(xy 75.054194 -297.182666) (xy 75.080497 -297.14107) (xy 75.113132 -297.104233) (xy 75.151253 -297.073108)
			(xy 75.193874 -297.048501) (xy 75.23989 -297.031049) (xy 75.288109 -297.021205) (xy 75.337284 -297.019224)
			(xy 75.386139 -297.025156) (xy 75.43341 -297.038848) (xy 75.477872 -297.059946) (xy 75.518375 -297.087902)
			(xy 75.553868 -297.121994) (xy 75.583433 -297.161338) (xy 75.606304 -297.204915) (xy 75.621888 -297.251596)
			(xy 75.629783 -297.300173) (xy 75.630278 -297.32478) (xy 75.969126 -297.32478) (xy 75.973086 -297.275726)
			(xy 75.984863 -297.227942) (xy 76.004154 -297.182666) (xy 76.030457 -297.14107) (xy 76.063092 -297.104233)
			(xy 76.101213 -297.073108) (xy 76.143834 -297.048501) (xy 76.18985 -297.031049) (xy 76.238069 -297.021205)
			(xy 76.287244 -297.019224) (xy 76.336099 -297.025156) (xy 76.38337 -297.038848) (xy 76.427832 -297.059946)
			(xy 76.468335 -297.087902) (xy 76.503828 -297.121994) (xy 76.533393 -297.161338) (xy 76.556264 -297.204915)
			(xy 76.571848 -297.251596) (xy 76.579743 -297.300173) (xy 76.580238 -297.32478) (xy 76.919086 -297.32478)
			(xy 76.923046 -297.275726) (xy 76.934823 -297.227942) (xy 76.954114 -297.182666) (xy 76.980417 -297.14107)
			(xy 77.013052 -297.104233) (xy 77.051173 -297.073108) (xy 77.093794 -297.048501) (xy 77.13981 -297.031049)
			(xy 77.188029 -297.021205) (xy 77.237204 -297.019224) (xy 77.286059 -297.025156) (xy 77.33333 -297.038848)
			(xy 77.377792 -297.059946) (xy 77.418295 -297.087902) (xy 77.453788 -297.121994) (xy 77.483353 -297.161338)
			(xy 77.506224 -297.204915) (xy 77.521808 -297.251596) (xy 77.529703 -297.300173) (xy 77.530198 -297.32478)
			(xy 77.869046 -297.32478) (xy 77.873006 -297.275726) (xy 77.884783 -297.227942) (xy 77.904074 -297.182666)
			(xy 77.930377 -297.14107) (xy 77.963012 -297.104233) (xy 78.001133 -297.073108) (xy 78.043754 -297.048501)
			(xy 78.08977 -297.031049) (xy 78.137989 -297.021205) (xy 78.187164 -297.019224) (xy 78.236019 -297.025156)
			(xy 78.28329 -297.038848) (xy 78.327752 -297.059946) (xy 78.368255 -297.087902) (xy 78.403748 -297.121994)
			(xy 78.433313 -297.161338) (xy 78.456184 -297.204915) (xy 78.471768 -297.251596) (xy 78.479663 -297.300173)
			(xy 78.480158 -297.32478) (xy 78.819006 -297.32478) (xy 78.822966 -297.275726) (xy 78.834743 -297.227942)
			(xy 78.854034 -297.182666) (xy 78.880337 -297.14107) (xy 78.912972 -297.104233) (xy 78.951093 -297.073108)
			(xy 78.993714 -297.048501) (xy 79.03973 -297.031049) (xy 79.087949 -297.021205) (xy 79.137124 -297.019224)
			(xy 79.185979 -297.025156) (xy 79.23325 -297.038848) (xy 79.277712 -297.059946) (xy 79.318215 -297.087902)
			(xy 79.353708 -297.121994) (xy 79.383273 -297.161338) (xy 79.406144 -297.204915) (xy 79.421728 -297.251596)
			(xy 79.429623 -297.300173) (xy 79.430118 -297.32478) (xy 79.768966 -297.32478) (xy 79.772926 -297.275726)
			(xy 79.784703 -297.227942) (xy 79.803994 -297.182666) (xy 79.830297 -297.14107) (xy 79.862932 -297.104233)
			(xy 79.901053 -297.073108) (xy 79.943674 -297.048501) (xy 79.98969 -297.031049) (xy 80.037909 -297.021205)
			(xy 80.087084 -297.019224) (xy 80.135939 -297.025156) (xy 80.18321 -297.038848) (xy 80.227672 -297.059946)
			(xy 80.268175 -297.087902) (xy 80.303668 -297.121994) (xy 80.333233 -297.161338) (xy 80.356104 -297.204915)
			(xy 80.371688 -297.251596) (xy 80.379583 -297.300173) (xy 80.380078 -297.32478) (xy 80.71918 -297.32478)
			(xy 80.72314 -297.275726) (xy 80.734917 -297.227942) (xy 80.754208 -297.182666) (xy 80.780511 -297.14107)
			(xy 80.813146 -297.104233) (xy 80.851267 -297.073108) (xy 80.893888 -297.048501) (xy 80.939904 -297.031049)
			(xy 80.988123 -297.021205) (xy 81.037298 -297.019224) (xy 81.086153 -297.025156) (xy 81.133424 -297.038848)
			(xy 81.177886 -297.059946) (xy 81.218389 -297.087902) (xy 81.253882 -297.121994) (xy 81.283447 -297.161338)
			(xy 81.306318 -297.204915) (xy 81.321902 -297.251596) (xy 81.329797 -297.300173) (xy 81.330292 -297.32478)
			(xy 81.66914 -297.32478) (xy 81.6731 -297.275726) (xy 81.684877 -297.227942) (xy 81.704168 -297.182666)
			(xy 81.730471 -297.14107) (xy 81.763106 -297.104233) (xy 81.801227 -297.073108) (xy 81.843848 -297.048501)
			(xy 81.889864 -297.031049) (xy 81.938083 -297.021205) (xy 81.987258 -297.019224) (xy 82.036113 -297.025156)
			(xy 82.083384 -297.038848) (xy 82.127846 -297.059946) (xy 82.168349 -297.087902) (xy 82.203842 -297.121994)
			(xy 82.233407 -297.161338) (xy 82.256278 -297.204915) (xy 82.271862 -297.251596) (xy 82.279757 -297.300173)
			(xy 82.280252 -297.32478) (xy 82.6191 -297.32478) (xy 82.62306 -297.275726) (xy 82.634837 -297.227942)
			(xy 82.654128 -297.182666) (xy 82.680431 -297.14107) (xy 82.713066 -297.104233) (xy 82.751187 -297.073108)
			(xy 82.793808 -297.048501) (xy 82.839824 -297.031049) (xy 82.888043 -297.021205) (xy 82.937218 -297.019224)
			(xy 82.986073 -297.025156) (xy 83.033344 -297.038848) (xy 83.077806 -297.059946) (xy 83.118309 -297.087902)
			(xy 83.153802 -297.121994) (xy 83.183367 -297.161338) (xy 83.206238 -297.204915) (xy 83.221822 -297.251596)
			(xy 83.229717 -297.300173) (xy 83.230212 -297.32478) (xy 83.229717 -297.349387) (xy 83.221822 -297.397964)
			(xy 83.206238 -297.444645) (xy 83.183367 -297.488222) (xy 83.153802 -297.527566) (xy 83.118309 -297.561658)
			(xy 83.077806 -297.589614) (xy 83.033344 -297.610712) (xy 82.986073 -297.624404) (xy 82.937218 -297.630336)
			(xy 82.888043 -297.628355) (xy 82.839824 -297.618511) (xy 82.793808 -297.601059) (xy 82.751187 -297.576452)
			(xy 82.713066 -297.545327) (xy 82.680431 -297.50849) (xy 82.654128 -297.466894) (xy 82.634837 -297.421618)
			(xy 82.62306 -297.373834) (xy 82.6191 -297.32478) (xy 82.280252 -297.32478) (xy 82.279757 -297.349387)
			(xy 82.271862 -297.397964) (xy 82.256278 -297.444645) (xy 82.233407 -297.488222) (xy 82.203842 -297.527566)
			(xy 82.168349 -297.561658) (xy 82.127846 -297.589614) (xy 82.083384 -297.610712) (xy 82.036113 -297.624404)
			(xy 81.987258 -297.630336) (xy 81.938083 -297.628355) (xy 81.889864 -297.618511) (xy 81.843848 -297.601059)
			(xy 81.801227 -297.576452) (xy 81.763106 -297.545327) (xy 81.730471 -297.50849) (xy 81.704168 -297.466894)
			(xy 81.684877 -297.421618) (xy 81.6731 -297.373834) (xy 81.66914 -297.32478) (xy 81.330292 -297.32478)
			(xy 81.329797 -297.349387) (xy 81.321902 -297.397964) (xy 81.306318 -297.444645) (xy 81.283447 -297.488222)
			(xy 81.253882 -297.527566) (xy 81.218389 -297.561658) (xy 81.177886 -297.589614) (xy 81.133424 -297.610712)
			(xy 81.086153 -297.624404) (xy 81.037298 -297.630336) (xy 80.988123 -297.628355) (xy 80.939904 -297.618511)
			(xy 80.893888 -297.601059) (xy 80.851267 -297.576452) (xy 80.813146 -297.545327) (xy 80.780511 -297.50849)
			(xy 80.754208 -297.466894) (xy 80.734917 -297.421618) (xy 80.72314 -297.373834) (xy 80.71918 -297.32478)
			(xy 80.380078 -297.32478) (xy 80.379583 -297.349387) (xy 80.371688 -297.397964) (xy 80.356104 -297.444645)
			(xy 80.333233 -297.488222) (xy 80.303668 -297.527566) (xy 80.268175 -297.561658) (xy 80.227672 -297.589614)
			(xy 80.18321 -297.610712) (xy 80.135939 -297.624404) (xy 80.087084 -297.630336) (xy 80.037909 -297.628355)
			(xy 79.98969 -297.618511) (xy 79.943674 -297.601059) (xy 79.901053 -297.576452) (xy 79.862932 -297.545327)
			(xy 79.830297 -297.50849) (xy 79.803994 -297.466894) (xy 79.784703 -297.421618) (xy 79.772926 -297.373834)
			(xy 79.768966 -297.32478) (xy 79.430118 -297.32478) (xy 79.429623 -297.349387) (xy 79.421728 -297.397964)
			(xy 79.406144 -297.444645) (xy 79.383273 -297.488222) (xy 79.353708 -297.527566) (xy 79.318215 -297.561658)
			(xy 79.277712 -297.589614) (xy 79.23325 -297.610712) (xy 79.185979 -297.624404) (xy 79.137124 -297.630336)
			(xy 79.087949 -297.628355) (xy 79.03973 -297.618511) (xy 78.993714 -297.601059) (xy 78.951093 -297.576452)
			(xy 78.912972 -297.545327) (xy 78.880337 -297.50849) (xy 78.854034 -297.466894) (xy 78.834743 -297.421618)
			(xy 78.822966 -297.373834) (xy 78.819006 -297.32478) (xy 78.480158 -297.32478) (xy 78.479663 -297.349387)
			(xy 78.471768 -297.397964) (xy 78.456184 -297.444645) (xy 78.433313 -297.488222) (xy 78.403748 -297.527566)
			(xy 78.368255 -297.561658) (xy 78.327752 -297.589614) (xy 78.28329 -297.610712) (xy 78.236019 -297.624404)
			(xy 78.187164 -297.630336) (xy 78.137989 -297.628355) (xy 78.08977 -297.618511) (xy 78.043754 -297.601059)
			(xy 78.001133 -297.576452) (xy 77.963012 -297.545327) (xy 77.930377 -297.50849) (xy 77.904074 -297.466894)
			(xy 77.884783 -297.421618) (xy 77.873006 -297.373834) (xy 77.869046 -297.32478) (xy 77.530198 -297.32478)
			(xy 77.529703 -297.349387) (xy 77.521808 -297.397964) (xy 77.506224 -297.444645) (xy 77.483353 -297.488222)
			(xy 77.453788 -297.527566) (xy 77.418295 -297.561658) (xy 77.377792 -297.589614) (xy 77.33333 -297.610712)
			(xy 77.286059 -297.624404) (xy 77.237204 -297.630336) (xy 77.188029 -297.628355) (xy 77.13981 -297.618511)
			(xy 77.093794 -297.601059) (xy 77.051173 -297.576452) (xy 77.013052 -297.545327) (xy 76.980417 -297.50849)
			(xy 76.954114 -297.466894) (xy 76.934823 -297.421618) (xy 76.923046 -297.373834) (xy 76.919086 -297.32478)
			(xy 76.580238 -297.32478) (xy 76.579743 -297.349387) (xy 76.571848 -297.397964) (xy 76.556264 -297.444645)
			(xy 76.533393 -297.488222) (xy 76.503828 -297.527566) (xy 76.468335 -297.561658) (xy 76.427832 -297.589614)
			(xy 76.38337 -297.610712) (xy 76.336099 -297.624404) (xy 76.287244 -297.630336) (xy 76.238069 -297.628355)
			(xy 76.18985 -297.618511) (xy 76.143834 -297.601059) (xy 76.101213 -297.576452) (xy 76.063092 -297.545327)
			(xy 76.030457 -297.50849) (xy 76.004154 -297.466894) (xy 75.984863 -297.421618) (xy 75.973086 -297.373834)
			(xy 75.969126 -297.32478) (xy 75.630278 -297.32478) (xy 75.629783 -297.349387) (xy 75.621888 -297.397964)
			(xy 75.606304 -297.444645) (xy 75.583433 -297.488222) (xy 75.553868 -297.527566) (xy 75.518375 -297.561658)
			(xy 75.477872 -297.589614) (xy 75.43341 -297.610712) (xy 75.386139 -297.624404) (xy 75.337284 -297.630336)
			(xy 75.288109 -297.628355) (xy 75.23989 -297.618511) (xy 75.193874 -297.601059) (xy 75.151253 -297.576452)
			(xy 75.113132 -297.545327) (xy 75.080497 -297.50849) (xy 75.054194 -297.466894) (xy 75.034903 -297.421618)
			(xy 75.023126 -297.373834) (xy 75.019166 -297.32478) (xy 74.680318 -297.32478) (xy 74.679823 -297.349387)
			(xy 74.671928 -297.397964) (xy 74.656344 -297.444645) (xy 74.633473 -297.488222) (xy 74.603908 -297.527566)
			(xy 74.568415 -297.561658) (xy 74.527912 -297.589614) (xy 74.48345 -297.610712) (xy 74.436179 -297.624404)
			(xy 74.387324 -297.630336) (xy 74.338149 -297.628355) (xy 74.28993 -297.618511) (xy 74.243914 -297.601059)
			(xy 74.201293 -297.576452) (xy 74.163172 -297.545327) (xy 74.130537 -297.50849) (xy 74.104234 -297.466894)
			(xy 74.084943 -297.421618) (xy 74.073166 -297.373834) (xy 74.069206 -297.32478) (xy 73.730104 -297.32478)
			(xy 73.729609 -297.349387) (xy 73.721714 -297.397964) (xy 73.70613 -297.444645) (xy 73.683259 -297.488222)
			(xy 73.653694 -297.527566) (xy 73.618201 -297.561658) (xy 73.577698 -297.589614) (xy 73.533236 -297.610712)
			(xy 73.485965 -297.624404) (xy 73.43711 -297.630336) (xy 73.387935 -297.628355) (xy 73.339716 -297.618511)
			(xy 73.2937 -297.601059) (xy 73.251079 -297.576452) (xy 73.212958 -297.545327) (xy 73.180323 -297.50849)
			(xy 73.15402 -297.466894) (xy 73.134729 -297.421618) (xy 73.122952 -297.373834) (xy 73.118992 -297.32478)
			(xy 72.780144 -297.32478) (xy 72.779649 -297.349387) (xy 72.771754 -297.397964) (xy 72.75617 -297.444645)
			(xy 72.733299 -297.488222) (xy 72.703734 -297.527566) (xy 72.668241 -297.561658) (xy 72.627738 -297.589614)
			(xy 72.583276 -297.610712) (xy 72.536005 -297.624404) (xy 72.48715 -297.630336) (xy 72.437975 -297.628355)
			(xy 72.389756 -297.618511) (xy 72.34374 -297.601059) (xy 72.301119 -297.576452) (xy 72.262998 -297.545327)
			(xy 72.230363 -297.50849) (xy 72.20406 -297.466894) (xy 72.184769 -297.421618) (xy 72.172992 -297.373834)
			(xy 72.169032 -297.32478) (xy 71.830184 -297.32478) (xy 71.829689 -297.349387) (xy 71.821794 -297.397964)
			(xy 71.80621 -297.444645) (xy 71.783339 -297.488222) (xy 71.753774 -297.527566) (xy 71.718281 -297.561658)
			(xy 71.677778 -297.589614) (xy 71.633316 -297.610712) (xy 71.586045 -297.624404) (xy 71.53719 -297.630336)
			(xy 71.488015 -297.628355) (xy 71.439796 -297.618511) (xy 71.39378 -297.601059) (xy 71.351159 -297.576452)
			(xy 71.313038 -297.545327) (xy 71.280403 -297.50849) (xy 71.2541 -297.466894) (xy 71.234809 -297.421618)
			(xy 71.223032 -297.373834) (xy 71.219072 -297.32478) (xy 70.880224 -297.32478) (xy 70.879729 -297.349387)
			(xy 70.871834 -297.397964) (xy 70.85625 -297.444645) (xy 70.833379 -297.488222) (xy 70.803814 -297.527566)
			(xy 70.768321 -297.561658) (xy 70.727818 -297.589614) (xy 70.683356 -297.610712) (xy 70.636085 -297.624404)
			(xy 70.58723 -297.630336) (xy 70.538055 -297.628355) (xy 70.489836 -297.618511) (xy 70.44382 -297.601059)
			(xy 70.401199 -297.576452) (xy 70.363078 -297.545327) (xy 70.330443 -297.50849) (xy 70.30414 -297.466894)
			(xy 70.284849 -297.421618) (xy 70.273072 -297.373834) (xy 70.269112 -297.32478) (xy 69.930264 -297.32478)
			(xy 69.929769 -297.349387) (xy 69.921874 -297.397964) (xy 69.90629 -297.444645) (xy 69.883419 -297.488222)
			(xy 69.853854 -297.527566) (xy 69.818361 -297.561658) (xy 69.777858 -297.589614) (xy 69.733396 -297.610712)
			(xy 69.686125 -297.624404) (xy 69.63727 -297.630336) (xy 69.588095 -297.628355) (xy 69.539876 -297.618511)
			(xy 69.49386 -297.601059) (xy 69.451239 -297.576452) (xy 69.413118 -297.545327) (xy 69.380483 -297.50849)
			(xy 69.35418 -297.466894) (xy 69.334889 -297.421618) (xy 69.323112 -297.373834) (xy 69.319152 -297.32478)
			(xy 66.13017 -297.32478) (xy 66.129675 -297.349387) (xy 66.12178 -297.397964) (xy 66.106196 -297.444645)
			(xy 66.083325 -297.488222) (xy 66.05376 -297.527566) (xy 66.018267 -297.561658) (xy 65.977764 -297.589614)
			(xy 65.933302 -297.610712) (xy 65.886031 -297.624404) (xy 65.837176 -297.630336) (xy 65.788001 -297.628355)
			(xy 65.739782 -297.618511) (xy 65.693766 -297.601059) (xy 65.651145 -297.576452) (xy 65.613024 -297.545327)
			(xy 65.580389 -297.50849) (xy 65.554086 -297.466894) (xy 65.534795 -297.421618) (xy 65.523018 -297.373834)
			(xy 65.519058 -297.32478) (xy 65.18021 -297.32478) (xy 65.179715 -297.349387) (xy 65.17182 -297.397964)
			(xy 65.156236 -297.444645) (xy 65.133365 -297.488222) (xy 65.1038 -297.527566) (xy 65.068307 -297.561658)
			(xy 65.027804 -297.589614) (xy 64.983342 -297.610712) (xy 64.936071 -297.624404) (xy 64.887216 -297.630336)
			(xy 64.838041 -297.628355) (xy 64.789822 -297.618511) (xy 64.743806 -297.601059) (xy 64.701185 -297.576452)
			(xy 64.663064 -297.545327) (xy 64.630429 -297.50849) (xy 64.604126 -297.466894) (xy 64.584835 -297.421618)
			(xy 64.573058 -297.373834) (xy 64.569098 -297.32478) (xy 64.23025 -297.32478) (xy 64.229755 -297.349387)
			(xy 64.22186 -297.397964) (xy 64.206276 -297.444645) (xy 64.183405 -297.488222) (xy 64.15384 -297.527566)
			(xy 64.118347 -297.561658) (xy 64.077844 -297.589614) (xy 64.033382 -297.610712) (xy 63.986111 -297.624404)
			(xy 63.937256 -297.630336) (xy 63.888081 -297.628355) (xy 63.839862 -297.618511) (xy 63.793846 -297.601059)
			(xy 63.751225 -297.576452) (xy 63.713104 -297.545327) (xy 63.680469 -297.50849) (xy 63.654166 -297.466894)
			(xy 63.634875 -297.421618) (xy 63.623098 -297.373834) (xy 63.619138 -297.32478) (xy 63.28029 -297.32478)
			(xy 63.279795 -297.349387) (xy 63.2719 -297.397964) (xy 63.256316 -297.444645) (xy 63.233445 -297.488222)
			(xy 63.20388 -297.527566) (xy 63.168387 -297.561658) (xy 63.127884 -297.589614) (xy 63.083422 -297.610712)
			(xy 63.036151 -297.624404) (xy 62.987296 -297.630336) (xy 62.938121 -297.628355) (xy 62.889902 -297.618511)
			(xy 62.843886 -297.601059) (xy 62.801265 -297.576452) (xy 62.763144 -297.545327) (xy 62.730509 -297.50849)
			(xy 62.704206 -297.466894) (xy 62.684915 -297.421618) (xy 62.673138 -297.373834) (xy 62.669178 -297.32478)
			(xy 62.330076 -297.32478) (xy 62.329581 -297.349387) (xy 62.321686 -297.397964) (xy 62.306102 -297.444645)
			(xy 62.283231 -297.488222) (xy 62.253666 -297.527566) (xy 62.218173 -297.561658) (xy 62.17767 -297.589614)
			(xy 62.133208 -297.610712) (xy 62.085937 -297.624404) (xy 62.037082 -297.630336) (xy 61.987907 -297.628355)
			(xy 61.939688 -297.618511) (xy 61.893672 -297.601059) (xy 61.851051 -297.576452) (xy 61.81293 -297.545327)
			(xy 61.780295 -297.50849) (xy 61.753992 -297.466894) (xy 61.734701 -297.421618) (xy 61.722924 -297.373834)
			(xy 61.718964 -297.32478) (xy 61.380116 -297.32478) (xy 61.379621 -297.349387) (xy 61.371726 -297.397964)
			(xy 61.356142 -297.444645) (xy 61.333271 -297.488222) (xy 61.303706 -297.527566) (xy 61.268213 -297.561658)
			(xy 61.22771 -297.589614) (xy 61.183248 -297.610712) (xy 61.135977 -297.624404) (xy 61.087122 -297.630336)
			(xy 61.037947 -297.628355) (xy 60.989728 -297.618511) (xy 60.943712 -297.601059) (xy 60.901091 -297.576452)
			(xy 60.86297 -297.545327) (xy 60.830335 -297.50849) (xy 60.804032 -297.466894) (xy 60.784741 -297.421618)
			(xy 60.772964 -297.373834) (xy 60.769004 -297.32478) (xy 60.43168 -297.32478) (xy 60.43121 -297.348881)
			(xy 60.423677 -297.39649) (xy 60.408793 -297.442336) (xy 60.386925 -297.485291) (xy 60.35861 -297.524299)
			(xy 60.324544 -297.5584) (xy 60.285566 -297.586756) (xy 60.242634 -297.60867) (xy 60.196803 -297.623601)
			(xy 60.149202 -297.631184) (xy 60.125102 -297.631612) (xy 60.124848 -297.631612) (xy 60.094186 -297.630617)
			(xy 60.034168 -297.617955) (xy 60.005722 -297.606466) (xy 59.99607 -297.602148) (xy 59.965844 -297.602148)
			(xy 59.958598 -297.602368) (xy 59.944672 -297.606367) (xy 59.938412 -297.610022) (xy 59.87415 -297.65117)
			(xy 59.867198 -297.656028) (xy 59.856724 -297.669356) (xy 59.851158 -297.685368) (xy 59.850782 -297.693842)
			(xy 59.850782 -297.905932) (xy 59.85121 -297.916) (xy 59.858931 -297.934598) (xy 59.865768 -297.942)
			(xy 59.868054 -297.944286) (xy 59.872626 -297.947842) (xy 59.889124 -297.95851) (xy 84.756242 -297.95851)
			(xy 84.760313 -297.902888) (xy 84.772439 -297.848451) (xy 84.792362 -297.79636) (xy 84.819658 -297.747725)
			(xy 84.853744 -297.703582) (xy 84.893893 -297.664873) (xy 84.939251 -297.632422) (xy 84.988851 -297.606921)
			(xy 85.041635 -297.588914) (xy 85.096478 -297.578784) (xy 85.152212 -297.576747) (xy 85.207649 -297.582847)
			(xy 85.261606 -297.596953) (xy 85.312935 -297.618765) (xy 85.360541 -297.647819) (xy 85.395394 -297.676824)
			(xy 86.299546 -297.676824) (xy 86.303617 -297.621202) (xy 86.315743 -297.566765) (xy 86.335666 -297.514674)
			(xy 86.362962 -297.466039) (xy 86.397048 -297.421896) (xy 86.437197 -297.383187) (xy 86.482555 -297.350736)
			(xy 86.532155 -297.325235) (xy 86.584939 -297.307228) (xy 86.639782 -297.297098) (xy 86.695516 -297.295061)
			(xy 86.750953 -297.301161) (xy 86.80491 -297.315267) (xy 86.856239 -297.337079) (xy 86.903845 -297.366133)
			(xy 86.914281 -297.374818) (xy 92.615764 -297.374818) (xy 92.619835 -297.319196) (xy 92.631961 -297.264759)
			(xy 92.651884 -297.212668) (xy 92.67918 -297.164033) (xy 92.713266 -297.11989) (xy 92.753415 -297.081181)
			(xy 92.798773 -297.04873) (xy 92.848373 -297.023229) (xy 92.901157 -297.005222) (xy 92.956 -296.995092)
			(xy 93.011734 -296.993055) (xy 93.067171 -296.999155) (xy 93.121128 -297.013261) (xy 93.172457 -297.035073)
			(xy 93.220063 -297.064127) (xy 93.262931 -297.099802) (xy 93.300148 -297.141339) (xy 93.330921 -297.187852)
			(xy 93.354593 -297.238349) (xy 93.370661 -297.291756) (xy 93.378781 -297.346932) (xy 93.37929 -297.374818)
			(xy 93.378781 -297.402704) (xy 93.370661 -297.45788) (xy 93.354593 -297.511287) (xy 93.330921 -297.561784)
			(xy 93.300148 -297.608297) (xy 93.262931 -297.649834) (xy 93.220063 -297.685509) (xy 93.172457 -297.714563)
			(xy 93.121128 -297.736375) (xy 93.067171 -297.750481) (xy 93.011734 -297.756581) (xy 92.956 -297.754544)
			(xy 92.901157 -297.744414) (xy 92.848373 -297.726407) (xy 92.798773 -297.700906) (xy 92.753415 -297.668455)
			(xy 92.713266 -297.629746) (xy 92.67918 -297.585603) (xy 92.651884 -297.536968) (xy 92.631961 -297.484877)
			(xy 92.619835 -297.43044) (xy 92.615764 -297.374818) (xy 86.914281 -297.374818) (xy 86.946713 -297.401808)
			(xy 86.98393 -297.443345) (xy 87.014703 -297.489858) (xy 87.038375 -297.540355) (xy 87.054443 -297.593762)
			(xy 87.062563 -297.648938) (xy 87.063072 -297.676824) (xy 87.062563 -297.70471) (xy 87.054443 -297.759886)
			(xy 87.038375 -297.813293) (xy 87.014703 -297.86379) (xy 86.98393 -297.910303) (xy 86.946713 -297.95184)
			(xy 86.903845 -297.987515) (xy 86.856239 -298.016569) (xy 86.80491 -298.038381) (xy 86.750953 -298.052487)
			(xy 86.695516 -298.058587) (xy 86.639782 -298.05655) (xy 86.584939 -298.04642) (xy 86.532155 -298.028413)
			(xy 86.482555 -298.002912) (xy 86.437197 -297.970461) (xy 86.397048 -297.931752) (xy 86.362962 -297.887609)
			(xy 86.335666 -297.838974) (xy 86.315743 -297.786883) (xy 86.303617 -297.732446) (xy 86.299546 -297.676824)
			(xy 85.395394 -297.676824) (xy 85.403409 -297.683494) (xy 85.440626 -297.725031) (xy 85.471399 -297.771544)
			(xy 85.495071 -297.822041) (xy 85.511139 -297.875448) (xy 85.519259 -297.930624) (xy 85.519768 -297.95851)
			(xy 85.519259 -297.986396) (xy 85.511139 -298.041572) (xy 85.495071 -298.094979) (xy 85.471399 -298.145476)
			(xy 85.440626 -298.191989) (xy 85.403409 -298.233526) (xy 85.360541 -298.269201) (xy 85.312935 -298.298255)
			(xy 85.261606 -298.320067) (xy 85.207649 -298.334173) (xy 85.152212 -298.340273) (xy 85.096478 -298.338236)
			(xy 85.041635 -298.328106) (xy 84.988851 -298.310099) (xy 84.939251 -298.284598) (xy 84.893893 -298.252147)
			(xy 84.853744 -298.213438) (xy 84.819658 -298.169295) (xy 84.792362 -298.12066) (xy 84.772439 -298.068569)
			(xy 84.760313 -298.014132) (xy 84.756242 -297.95851) (xy 59.889124 -297.95851) (xy 59.906408 -297.969686)
			(xy 59.906916 -297.969686) (xy 59.937396 -297.989752) (xy 59.943724 -297.993623) (xy 59.957923 -297.997894)
			(xy 59.965336 -297.998134) (xy 59.985402 -297.998134) (xy 59.99734 -297.995594) (xy 60.00242 -297.993562)
			(xy 60.003182 -297.993308) (xy 60.022465 -297.985327) (xy 60.062646 -297.974057) (xy 60.103983 -297.968324)
			(xy 60.124848 -297.967908) (xy 60.148955 -297.968384) (xy 60.196576 -297.975934) (xy 60.242428 -297.99084)
			(xy 60.285385 -298.012736) (xy 60.324387 -298.041082) (xy 60.358476 -298.07518) (xy 60.38681 -298.11419)
			(xy 60.408693 -298.157153) (xy 60.423586 -298.20301) (xy 60.431122 -298.250632) (xy 60.43168 -298.27474)
			(xy 60.769004 -298.27474) (xy 60.772964 -298.225686) (xy 60.784741 -298.177902) (xy 60.804032 -298.132626)
			(xy 60.830335 -298.09103) (xy 60.86297 -298.054193) (xy 60.901091 -298.023068) (xy 60.943712 -297.998461)
			(xy 60.989728 -297.981009) (xy 61.037947 -297.971165) (xy 61.087122 -297.969184) (xy 61.135977 -297.975116)
			(xy 61.183248 -297.988808) (xy 61.22771 -298.009906) (xy 61.268213 -298.037862) (xy 61.303706 -298.071954)
			(xy 61.333271 -298.111298) (xy 61.356142 -298.154875) (xy 61.371726 -298.201556) (xy 61.379621 -298.250133)
			(xy 61.380116 -298.27474) (xy 61.718964 -298.27474) (xy 61.722924 -298.225686) (xy 61.734701 -298.177902)
			(xy 61.753992 -298.132626) (xy 61.780295 -298.09103) (xy 61.81293 -298.054193) (xy 61.851051 -298.023068)
			(xy 61.893672 -297.998461) (xy 61.939688 -297.981009) (xy 61.987907 -297.971165) (xy 62.037082 -297.969184)
			(xy 62.085937 -297.975116) (xy 62.133208 -297.988808) (xy 62.17767 -298.009906) (xy 62.218173 -298.037862)
			(xy 62.253666 -298.071954) (xy 62.283231 -298.111298) (xy 62.306102 -298.154875) (xy 62.321686 -298.201556)
			(xy 62.329581 -298.250133) (xy 62.330076 -298.27474) (xy 62.669178 -298.27474) (xy 62.673138 -298.225686)
			(xy 62.684915 -298.177902) (xy 62.704206 -298.132626) (xy 62.730509 -298.09103) (xy 62.763144 -298.054193)
			(xy 62.801265 -298.023068) (xy 62.843886 -297.998461) (xy 62.889902 -297.981009) (xy 62.938121 -297.971165)
			(xy 62.987296 -297.969184) (xy 63.036151 -297.975116) (xy 63.083422 -297.988808) (xy 63.127884 -298.009906)
			(xy 63.168387 -298.037862) (xy 63.20388 -298.071954) (xy 63.233445 -298.111298) (xy 63.256316 -298.154875)
			(xy 63.2719 -298.201556) (xy 63.279795 -298.250133) (xy 63.28029 -298.27474) (xy 63.619138 -298.27474)
			(xy 63.623098 -298.225686) (xy 63.634875 -298.177902) (xy 63.654166 -298.132626) (xy 63.680469 -298.09103)
			(xy 63.713104 -298.054193) (xy 63.751225 -298.023068) (xy 63.793846 -297.998461) (xy 63.839862 -297.981009)
			(xy 63.888081 -297.971165) (xy 63.937256 -297.969184) (xy 63.986111 -297.975116) (xy 64.033382 -297.988808)
			(xy 64.077844 -298.009906) (xy 64.118347 -298.037862) (xy 64.15384 -298.071954) (xy 64.183405 -298.111298)
			(xy 64.206276 -298.154875) (xy 64.22186 -298.201556) (xy 64.229755 -298.250133) (xy 64.23025 -298.27474)
			(xy 64.569098 -298.27474) (xy 64.573058 -298.225686) (xy 64.584835 -298.177902) (xy 64.604126 -298.132626)
			(xy 64.630429 -298.09103) (xy 64.663064 -298.054193) (xy 64.701185 -298.023068) (xy 64.743806 -297.998461)
			(xy 64.789822 -297.981009) (xy 64.838041 -297.971165) (xy 64.887216 -297.969184) (xy 64.936071 -297.975116)
			(xy 64.983342 -297.988808) (xy 65.027804 -298.009906) (xy 65.068307 -298.037862) (xy 65.1038 -298.071954)
			(xy 65.133365 -298.111298) (xy 65.156236 -298.154875) (xy 65.17182 -298.201556) (xy 65.179715 -298.250133)
			(xy 65.18021 -298.27474) (xy 65.519058 -298.27474) (xy 65.523018 -298.225686) (xy 65.534795 -298.177902)
			(xy 65.554086 -298.132626) (xy 65.580389 -298.09103) (xy 65.613024 -298.054193) (xy 65.651145 -298.023068)
			(xy 65.693766 -297.998461) (xy 65.739782 -297.981009) (xy 65.788001 -297.971165) (xy 65.837176 -297.969184)
			(xy 65.886031 -297.975116) (xy 65.933302 -297.988808) (xy 65.977764 -298.009906) (xy 66.018267 -298.037862)
			(xy 66.05376 -298.071954) (xy 66.083325 -298.111298) (xy 66.106196 -298.154875) (xy 66.12178 -298.201556)
			(xy 66.129675 -298.250133) (xy 66.13017 -298.27474) (xy 66.469018 -298.27474) (xy 66.472978 -298.225686)
			(xy 66.484755 -298.177902) (xy 66.504046 -298.132626) (xy 66.530349 -298.09103) (xy 66.562984 -298.054193)
			(xy 66.601105 -298.023068) (xy 66.643726 -297.998461) (xy 66.689742 -297.981009) (xy 66.737961 -297.971165)
			(xy 66.787136 -297.969184) (xy 66.835991 -297.975116) (xy 66.883262 -297.988808) (xy 66.927724 -298.009906)
			(xy 66.968227 -298.037862) (xy 67.00372 -298.071954) (xy 67.033285 -298.111298) (xy 67.056156 -298.154875)
			(xy 67.07174 -298.201556) (xy 67.079635 -298.250133) (xy 67.08013 -298.27474) (xy 67.418978 -298.27474)
			(xy 67.422938 -298.225686) (xy 67.434715 -298.177902) (xy 67.454006 -298.132626) (xy 67.480309 -298.09103)
			(xy 67.512944 -298.054193) (xy 67.551065 -298.023068) (xy 67.593686 -297.998461) (xy 67.639702 -297.981009)
			(xy 67.687921 -297.971165) (xy 67.737096 -297.969184) (xy 67.785951 -297.975116) (xy 67.833222 -297.988808)
			(xy 67.877684 -298.009906) (xy 67.918187 -298.037862) (xy 67.95368 -298.071954) (xy 67.983245 -298.111298)
			(xy 68.006116 -298.154875) (xy 68.0217 -298.201556) (xy 68.029595 -298.250133) (xy 68.03009 -298.27474)
			(xy 68.368938 -298.27474) (xy 68.372898 -298.225686) (xy 68.384675 -298.177902) (xy 68.403966 -298.132626)
			(xy 68.430269 -298.09103) (xy 68.462904 -298.054193) (xy 68.501025 -298.023068) (xy 68.543646 -297.998461)
			(xy 68.589662 -297.981009) (xy 68.637881 -297.971165) (xy 68.687056 -297.969184) (xy 68.735911 -297.975116)
			(xy 68.783182 -297.988808) (xy 68.827644 -298.009906) (xy 68.868147 -298.037862) (xy 68.90364 -298.071954)
			(xy 68.933205 -298.111298) (xy 68.956076 -298.154875) (xy 68.97166 -298.201556) (xy 68.979555 -298.250133)
			(xy 68.98005 -298.27474) (xy 69.319152 -298.27474) (xy 69.323112 -298.225686) (xy 69.334889 -298.177902)
			(xy 69.35418 -298.132626) (xy 69.380483 -298.09103) (xy 69.413118 -298.054193) (xy 69.451239 -298.023068)
			(xy 69.49386 -297.998461) (xy 69.539876 -297.981009) (xy 69.588095 -297.971165) (xy 69.63727 -297.969184)
			(xy 69.686125 -297.975116) (xy 69.733396 -297.988808) (xy 69.777858 -298.009906) (xy 69.818361 -298.037862)
			(xy 69.853854 -298.071954) (xy 69.883419 -298.111298) (xy 69.90629 -298.154875) (xy 69.921874 -298.201556)
			(xy 69.929769 -298.250133) (xy 69.930264 -298.27474) (xy 70.269112 -298.27474) (xy 70.273072 -298.225686)
			(xy 70.284849 -298.177902) (xy 70.30414 -298.132626) (xy 70.330443 -298.09103) (xy 70.363078 -298.054193)
			(xy 70.401199 -298.023068) (xy 70.44382 -297.998461) (xy 70.489836 -297.981009) (xy 70.538055 -297.971165)
			(xy 70.58723 -297.969184) (xy 70.636085 -297.975116) (xy 70.683356 -297.988808) (xy 70.727818 -298.009906)
			(xy 70.768321 -298.037862) (xy 70.803814 -298.071954) (xy 70.833379 -298.111298) (xy 70.85625 -298.154875)
			(xy 70.871834 -298.201556) (xy 70.879729 -298.250133) (xy 70.880224 -298.27474) (xy 71.219072 -298.27474)
			(xy 71.223032 -298.225686) (xy 71.234809 -298.177902) (xy 71.2541 -298.132626) (xy 71.280403 -298.09103)
			(xy 71.313038 -298.054193) (xy 71.351159 -298.023068) (xy 71.39378 -297.998461) (xy 71.439796 -297.981009)
			(xy 71.488015 -297.971165) (xy 71.53719 -297.969184) (xy 71.586045 -297.975116) (xy 71.633316 -297.988808)
			(xy 71.677778 -298.009906) (xy 71.718281 -298.037862) (xy 71.753774 -298.071954) (xy 71.783339 -298.111298)
			(xy 71.80621 -298.154875) (xy 71.821794 -298.201556) (xy 71.829689 -298.250133) (xy 71.830184 -298.27474)
			(xy 72.169032 -298.27474) (xy 72.172992 -298.225686) (xy 72.184769 -298.177902) (xy 72.20406 -298.132626)
			(xy 72.230363 -298.09103) (xy 72.262998 -298.054193) (xy 72.301119 -298.023068) (xy 72.34374 -297.998461)
			(xy 72.389756 -297.981009) (xy 72.437975 -297.971165) (xy 72.48715 -297.969184) (xy 72.536005 -297.975116)
			(xy 72.583276 -297.988808) (xy 72.627738 -298.009906) (xy 72.668241 -298.037862) (xy 72.703734 -298.071954)
			(xy 72.733299 -298.111298) (xy 72.75617 -298.154875) (xy 72.771754 -298.201556) (xy 72.779649 -298.250133)
			(xy 72.780144 -298.27474) (xy 73.118992 -298.27474) (xy 73.122952 -298.225686) (xy 73.134729 -298.177902)
			(xy 73.15402 -298.132626) (xy 73.180323 -298.09103) (xy 73.212958 -298.054193) (xy 73.251079 -298.023068)
			(xy 73.2937 -297.998461) (xy 73.339716 -297.981009) (xy 73.387935 -297.971165) (xy 73.43711 -297.969184)
			(xy 73.485965 -297.975116) (xy 73.533236 -297.988808) (xy 73.577698 -298.009906) (xy 73.618201 -298.037862)
			(xy 73.653694 -298.071954) (xy 73.683259 -298.111298) (xy 73.70613 -298.154875) (xy 73.721714 -298.201556)
			(xy 73.729609 -298.250133) (xy 73.730104 -298.27474) (xy 74.068952 -298.27474) (xy 74.072912 -298.225686)
			(xy 74.084689 -298.177902) (xy 74.10398 -298.132626) (xy 74.130283 -298.09103) (xy 74.162918 -298.054193)
			(xy 74.201039 -298.023068) (xy 74.24366 -297.998461) (xy 74.289676 -297.981009) (xy 74.337895 -297.971165)
			(xy 74.38707 -297.969184) (xy 74.435925 -297.975116) (xy 74.483196 -297.988808) (xy 74.527658 -298.009906)
			(xy 74.568161 -298.037862) (xy 74.603654 -298.071954) (xy 74.633219 -298.111298) (xy 74.65609 -298.154875)
			(xy 74.671674 -298.201556) (xy 74.679569 -298.250133) (xy 74.680064 -298.27474) (xy 75.019166 -298.27474)
			(xy 75.023126 -298.225686) (xy 75.034903 -298.177902) (xy 75.054194 -298.132626) (xy 75.080497 -298.09103)
			(xy 75.113132 -298.054193) (xy 75.151253 -298.023068) (xy 75.193874 -297.998461) (xy 75.23989 -297.981009)
			(xy 75.288109 -297.971165) (xy 75.337284 -297.969184) (xy 75.386139 -297.975116) (xy 75.43341 -297.988808)
			(xy 75.477872 -298.009906) (xy 75.518375 -298.037862) (xy 75.553868 -298.071954) (xy 75.583433 -298.111298)
			(xy 75.606304 -298.154875) (xy 75.621888 -298.201556) (xy 75.629783 -298.250133) (xy 75.630278 -298.27474)
			(xy 75.969126 -298.27474) (xy 75.973086 -298.225686) (xy 75.984863 -298.177902) (xy 76.004154 -298.132626)
			(xy 76.030457 -298.09103) (xy 76.063092 -298.054193) (xy 76.101213 -298.023068) (xy 76.143834 -297.998461)
			(xy 76.18985 -297.981009) (xy 76.238069 -297.971165) (xy 76.287244 -297.969184) (xy 76.336099 -297.975116)
			(xy 76.38337 -297.988808) (xy 76.427832 -298.009906) (xy 76.468335 -298.037862) (xy 76.503828 -298.071954)
			(xy 76.533393 -298.111298) (xy 76.556264 -298.154875) (xy 76.571848 -298.201556) (xy 76.579743 -298.250133)
			(xy 76.580238 -298.27474) (xy 76.919086 -298.27474) (xy 76.923046 -298.225686) (xy 76.934823 -298.177902)
			(xy 76.954114 -298.132626) (xy 76.980417 -298.09103) (xy 77.013052 -298.054193) (xy 77.051173 -298.023068)
			(xy 77.093794 -297.998461) (xy 77.13981 -297.981009) (xy 77.188029 -297.971165) (xy 77.237204 -297.969184)
			(xy 77.286059 -297.975116) (xy 77.33333 -297.988808) (xy 77.377792 -298.009906) (xy 77.418295 -298.037862)
			(xy 77.453788 -298.071954) (xy 77.483353 -298.111298) (xy 77.506224 -298.154875) (xy 77.521808 -298.201556)
			(xy 77.529703 -298.250133) (xy 77.530198 -298.27474) (xy 77.869046 -298.27474) (xy 77.873006 -298.225686)
			(xy 77.884783 -298.177902) (xy 77.904074 -298.132626) (xy 77.930377 -298.09103) (xy 77.963012 -298.054193)
			(xy 78.001133 -298.023068) (xy 78.043754 -297.998461) (xy 78.08977 -297.981009) (xy 78.137989 -297.971165)
			(xy 78.187164 -297.969184) (xy 78.236019 -297.975116) (xy 78.28329 -297.988808) (xy 78.327752 -298.009906)
			(xy 78.368255 -298.037862) (xy 78.403748 -298.071954) (xy 78.433313 -298.111298) (xy 78.456184 -298.154875)
			(xy 78.471768 -298.201556) (xy 78.479663 -298.250133) (xy 78.480158 -298.27474) (xy 78.819006 -298.27474)
			(xy 78.822966 -298.225686) (xy 78.834743 -298.177902) (xy 78.854034 -298.132626) (xy 78.880337 -298.09103)
			(xy 78.912972 -298.054193) (xy 78.951093 -298.023068) (xy 78.993714 -297.998461) (xy 79.03973 -297.981009)
			(xy 79.087949 -297.971165) (xy 79.137124 -297.969184) (xy 79.185979 -297.975116) (xy 79.23325 -297.988808)
			(xy 79.277712 -298.009906) (xy 79.318215 -298.037862) (xy 79.353708 -298.071954) (xy 79.383273 -298.111298)
			(xy 79.406144 -298.154875) (xy 79.421728 -298.201556) (xy 79.429623 -298.250133) (xy 79.430118 -298.27474)
			(xy 79.768966 -298.27474) (xy 79.772926 -298.225686) (xy 79.784703 -298.177902) (xy 79.803994 -298.132626)
			(xy 79.830297 -298.09103) (xy 79.862932 -298.054193) (xy 79.901053 -298.023068) (xy 79.943674 -297.998461)
			(xy 79.98969 -297.981009) (xy 80.037909 -297.971165) (xy 80.087084 -297.969184) (xy 80.135939 -297.975116)
			(xy 80.18321 -297.988808) (xy 80.227672 -298.009906) (xy 80.268175 -298.037862) (xy 80.303668 -298.071954)
			(xy 80.333233 -298.111298) (xy 80.356104 -298.154875) (xy 80.371688 -298.201556) (xy 80.379583 -298.250133)
			(xy 80.380078 -298.27474) (xy 80.71918 -298.27474) (xy 80.72314 -298.225686) (xy 80.734917 -298.177902)
			(xy 80.754208 -298.132626) (xy 80.780511 -298.09103) (xy 80.813146 -298.054193) (xy 80.851267 -298.023068)
			(xy 80.893888 -297.998461) (xy 80.939904 -297.981009) (xy 80.988123 -297.971165) (xy 81.037298 -297.969184)
			(xy 81.086153 -297.975116) (xy 81.133424 -297.988808) (xy 81.177886 -298.009906) (xy 81.218389 -298.037862)
			(xy 81.253882 -298.071954) (xy 81.283447 -298.111298) (xy 81.306318 -298.154875) (xy 81.321902 -298.201556)
			(xy 81.329797 -298.250133) (xy 81.330292 -298.27474) (xy 81.66914 -298.27474) (xy 81.6731 -298.225686)
			(xy 81.684877 -298.177902) (xy 81.704168 -298.132626) (xy 81.730471 -298.09103) (xy 81.763106 -298.054193)
			(xy 81.801227 -298.023068) (xy 81.843848 -297.998461) (xy 81.889864 -297.981009) (xy 81.938083 -297.971165)
			(xy 81.987258 -297.969184) (xy 82.036113 -297.975116) (xy 82.083384 -297.988808) (xy 82.127846 -298.009906)
			(xy 82.168349 -298.037862) (xy 82.203842 -298.071954) (xy 82.233407 -298.111298) (xy 82.256278 -298.154875)
			(xy 82.271862 -298.201556) (xy 82.279757 -298.250133) (xy 82.280252 -298.27474) (xy 82.6191 -298.27474)
			(xy 82.62306 -298.225686) (xy 82.634837 -298.177902) (xy 82.654128 -298.132626) (xy 82.680431 -298.09103)
			(xy 82.713066 -298.054193) (xy 82.751187 -298.023068) (xy 82.793808 -297.998461) (xy 82.839824 -297.981009)
			(xy 82.888043 -297.971165) (xy 82.937218 -297.969184) (xy 82.986073 -297.975116) (xy 83.033344 -297.988808)
			(xy 83.077806 -298.009906) (xy 83.118309 -298.037862) (xy 83.153802 -298.071954) (xy 83.183367 -298.111298)
			(xy 83.206238 -298.154875) (xy 83.221822 -298.201556) (xy 83.229717 -298.250133) (xy 83.230212 -298.27474)
			(xy 83.229717 -298.299347) (xy 83.221822 -298.347924) (xy 83.221246 -298.349649) (xy 83.66759 -298.349649)
			(xy 83.66759 -298.296351) (xy 83.675533 -298.243647) (xy 83.691243 -298.192717) (xy 83.714369 -298.144696)
			(xy 83.744393 -298.100659) (xy 83.780645 -298.061588) (xy 83.822316 -298.028357) (xy 83.868474 -298.001708)
			(xy 83.918088 -297.982236) (xy 83.97005 -297.970376) (xy 84.0232 -297.966393) (xy 84.07635 -297.970376)
			(xy 84.128312 -297.982236) (xy 84.177926 -298.001708) (xy 84.224084 -298.028357) (xy 84.265755 -298.061588)
			(xy 84.302007 -298.100659) (xy 84.332031 -298.144696) (xy 84.355157 -298.192717) (xy 84.370867 -298.243647)
			(xy 84.37881 -298.296351) (xy 84.379308 -298.323) (xy 84.37881 -298.349649) (xy 84.370867 -298.402353)
			(xy 84.355157 -298.453283) (xy 84.332031 -298.501304) (xy 84.302007 -298.545341) (xy 84.265755 -298.584412)
			(xy 84.224084 -298.617643) (xy 84.177926 -298.644292) (xy 84.128312 -298.663764) (xy 84.07635 -298.675624)
			(xy 84.0232 -298.679608) (xy 83.97005 -298.675624) (xy 83.918088 -298.663764) (xy 83.868474 -298.644292)
			(xy 83.822316 -298.617643) (xy 83.780645 -298.584412) (xy 83.744393 -298.545341) (xy 83.714369 -298.501304)
			(xy 83.691243 -298.453283) (xy 83.675533 -298.402353) (xy 83.66759 -298.349649) (xy 83.221246 -298.349649)
			(xy 83.206238 -298.394605) (xy 83.183367 -298.438182) (xy 83.153802 -298.477526) (xy 83.118309 -298.511618)
			(xy 83.077806 -298.539574) (xy 83.033344 -298.560672) (xy 82.986073 -298.574364) (xy 82.937218 -298.580296)
			(xy 82.888043 -298.578315) (xy 82.839824 -298.568471) (xy 82.793808 -298.551019) (xy 82.751187 -298.526412)
			(xy 82.713066 -298.495287) (xy 82.680431 -298.45845) (xy 82.654128 -298.416854) (xy 82.634837 -298.371578)
			(xy 82.62306 -298.323794) (xy 82.6191 -298.27474) (xy 82.280252 -298.27474) (xy 82.279757 -298.299347)
			(xy 82.271862 -298.347924) (xy 82.256278 -298.394605) (xy 82.233407 -298.438182) (xy 82.203842 -298.477526)
			(xy 82.168349 -298.511618) (xy 82.127846 -298.539574) (xy 82.083384 -298.560672) (xy 82.036113 -298.574364)
			(xy 81.987258 -298.580296) (xy 81.938083 -298.578315) (xy 81.889864 -298.568471) (xy 81.843848 -298.551019)
			(xy 81.801227 -298.526412) (xy 81.763106 -298.495287) (xy 81.730471 -298.45845) (xy 81.704168 -298.416854)
			(xy 81.684877 -298.371578) (xy 81.6731 -298.323794) (xy 81.66914 -298.27474) (xy 81.330292 -298.27474)
			(xy 81.329797 -298.299347) (xy 81.321902 -298.347924) (xy 81.306318 -298.394605) (xy 81.283447 -298.438182)
			(xy 81.253882 -298.477526) (xy 81.218389 -298.511618) (xy 81.177886 -298.539574) (xy 81.133424 -298.560672)
			(xy 81.086153 -298.574364) (xy 81.037298 -298.580296) (xy 80.988123 -298.578315) (xy 80.939904 -298.568471)
			(xy 80.893888 -298.551019) (xy 80.851267 -298.526412) (xy 80.813146 -298.495287) (xy 80.780511 -298.45845)
			(xy 80.754208 -298.416854) (xy 80.734917 -298.371578) (xy 80.72314 -298.323794) (xy 80.71918 -298.27474)
			(xy 80.380078 -298.27474) (xy 80.379583 -298.299347) (xy 80.371688 -298.347924) (xy 80.356104 -298.394605)
			(xy 80.333233 -298.438182) (xy 80.303668 -298.477526) (xy 80.268175 -298.511618) (xy 80.227672 -298.539574)
			(xy 80.18321 -298.560672) (xy 80.135939 -298.574364) (xy 80.087084 -298.580296) (xy 80.037909 -298.578315)
			(xy 79.98969 -298.568471) (xy 79.943674 -298.551019) (xy 79.901053 -298.526412) (xy 79.862932 -298.495287)
			(xy 79.830297 -298.45845) (xy 79.803994 -298.416854) (xy 79.784703 -298.371578) (xy 79.772926 -298.323794)
			(xy 79.768966 -298.27474) (xy 79.430118 -298.27474) (xy 79.429623 -298.299347) (xy 79.421728 -298.347924)
			(xy 79.406144 -298.394605) (xy 79.383273 -298.438182) (xy 79.353708 -298.477526) (xy 79.318215 -298.511618)
			(xy 79.277712 -298.539574) (xy 79.23325 -298.560672) (xy 79.185979 -298.574364) (xy 79.137124 -298.580296)
			(xy 79.087949 -298.578315) (xy 79.03973 -298.568471) (xy 78.993714 -298.551019) (xy 78.951093 -298.526412)
			(xy 78.912972 -298.495287) (xy 78.880337 -298.45845) (xy 78.854034 -298.416854) (xy 78.834743 -298.371578)
			(xy 78.822966 -298.323794) (xy 78.819006 -298.27474) (xy 78.480158 -298.27474) (xy 78.479663 -298.299347)
			(xy 78.471768 -298.347924) (xy 78.456184 -298.394605) (xy 78.433313 -298.438182) (xy 78.403748 -298.477526)
			(xy 78.368255 -298.511618) (xy 78.327752 -298.539574) (xy 78.28329 -298.560672) (xy 78.236019 -298.574364)
			(xy 78.187164 -298.580296) (xy 78.137989 -298.578315) (xy 78.08977 -298.568471) (xy 78.043754 -298.551019)
			(xy 78.001133 -298.526412) (xy 77.963012 -298.495287) (xy 77.930377 -298.45845) (xy 77.904074 -298.416854)
			(xy 77.884783 -298.371578) (xy 77.873006 -298.323794) (xy 77.869046 -298.27474) (xy 77.530198 -298.27474)
			(xy 77.529703 -298.299347) (xy 77.521808 -298.347924) (xy 77.506224 -298.394605) (xy 77.483353 -298.438182)
			(xy 77.453788 -298.477526) (xy 77.418295 -298.511618) (xy 77.377792 -298.539574) (xy 77.33333 -298.560672)
			(xy 77.286059 -298.574364) (xy 77.237204 -298.580296) (xy 77.188029 -298.578315) (xy 77.13981 -298.568471)
			(xy 77.093794 -298.551019) (xy 77.051173 -298.526412) (xy 77.013052 -298.495287) (xy 76.980417 -298.45845)
			(xy 76.954114 -298.416854) (xy 76.934823 -298.371578) (xy 76.923046 -298.323794) (xy 76.919086 -298.27474)
			(xy 76.580238 -298.27474) (xy 76.579743 -298.299347) (xy 76.571848 -298.347924) (xy 76.556264 -298.394605)
			(xy 76.533393 -298.438182) (xy 76.503828 -298.477526) (xy 76.468335 -298.511618) (xy 76.427832 -298.539574)
			(xy 76.38337 -298.560672) (xy 76.336099 -298.574364) (xy 76.287244 -298.580296) (xy 76.238069 -298.578315)
			(xy 76.18985 -298.568471) (xy 76.143834 -298.551019) (xy 76.101213 -298.526412) (xy 76.063092 -298.495287)
			(xy 76.030457 -298.45845) (xy 76.004154 -298.416854) (xy 75.984863 -298.371578) (xy 75.973086 -298.323794)
			(xy 75.969126 -298.27474) (xy 75.630278 -298.27474) (xy 75.629783 -298.299347) (xy 75.621888 -298.347924)
			(xy 75.606304 -298.394605) (xy 75.583433 -298.438182) (xy 75.553868 -298.477526) (xy 75.518375 -298.511618)
			(xy 75.477872 -298.539574) (xy 75.43341 -298.560672) (xy 75.386139 -298.574364) (xy 75.337284 -298.580296)
			(xy 75.288109 -298.578315) (xy 75.23989 -298.568471) (xy 75.193874 -298.551019) (xy 75.151253 -298.526412)
			(xy 75.113132 -298.495287) (xy 75.080497 -298.45845) (xy 75.054194 -298.416854) (xy 75.034903 -298.371578)
			(xy 75.023126 -298.323794) (xy 75.019166 -298.27474) (xy 74.680064 -298.27474) (xy 74.679569 -298.299347)
			(xy 74.671674 -298.347924) (xy 74.65609 -298.394605) (xy 74.633219 -298.438182) (xy 74.603654 -298.477526)
			(xy 74.568161 -298.511618) (xy 74.527658 -298.539574) (xy 74.483196 -298.560672) (xy 74.435925 -298.574364)
			(xy 74.38707 -298.580296) (xy 74.337895 -298.578315) (xy 74.289676 -298.568471) (xy 74.24366 -298.551019)
			(xy 74.201039 -298.526412) (xy 74.162918 -298.495287) (xy 74.130283 -298.45845) (xy 74.10398 -298.416854)
			(xy 74.084689 -298.371578) (xy 74.072912 -298.323794) (xy 74.068952 -298.27474) (xy 73.730104 -298.27474)
			(xy 73.729609 -298.299347) (xy 73.721714 -298.347924) (xy 73.70613 -298.394605) (xy 73.683259 -298.438182)
			(xy 73.653694 -298.477526) (xy 73.618201 -298.511618) (xy 73.577698 -298.539574) (xy 73.533236 -298.560672)
			(xy 73.485965 -298.574364) (xy 73.43711 -298.580296) (xy 73.387935 -298.578315) (xy 73.339716 -298.568471)
			(xy 73.2937 -298.551019) (xy 73.251079 -298.526412) (xy 73.212958 -298.495287) (xy 73.180323 -298.45845)
			(xy 73.15402 -298.416854) (xy 73.134729 -298.371578) (xy 73.122952 -298.323794) (xy 73.118992 -298.27474)
			(xy 72.780144 -298.27474) (xy 72.779649 -298.299347) (xy 72.771754 -298.347924) (xy 72.75617 -298.394605)
			(xy 72.733299 -298.438182) (xy 72.703734 -298.477526) (xy 72.668241 -298.511618) (xy 72.627738 -298.539574)
			(xy 72.583276 -298.560672) (xy 72.536005 -298.574364) (xy 72.48715 -298.580296) (xy 72.437975 -298.578315)
			(xy 72.389756 -298.568471) (xy 72.34374 -298.551019) (xy 72.301119 -298.526412) (xy 72.262998 -298.495287)
			(xy 72.230363 -298.45845) (xy 72.20406 -298.416854) (xy 72.184769 -298.371578) (xy 72.172992 -298.323794)
			(xy 72.169032 -298.27474) (xy 71.830184 -298.27474) (xy 71.829689 -298.299347) (xy 71.821794 -298.347924)
			(xy 71.80621 -298.394605) (xy 71.783339 -298.438182) (xy 71.753774 -298.477526) (xy 71.718281 -298.511618)
			(xy 71.677778 -298.539574) (xy 71.633316 -298.560672) (xy 71.586045 -298.574364) (xy 71.53719 -298.580296)
			(xy 71.488015 -298.578315) (xy 71.439796 -298.568471) (xy 71.39378 -298.551019) (xy 71.351159 -298.526412)
			(xy 71.313038 -298.495287) (xy 71.280403 -298.45845) (xy 71.2541 -298.416854) (xy 71.234809 -298.371578)
			(xy 71.223032 -298.323794) (xy 71.219072 -298.27474) (xy 70.880224 -298.27474) (xy 70.879729 -298.299347)
			(xy 70.871834 -298.347924) (xy 70.85625 -298.394605) (xy 70.833379 -298.438182) (xy 70.803814 -298.477526)
			(xy 70.768321 -298.511618) (xy 70.727818 -298.539574) (xy 70.683356 -298.560672) (xy 70.636085 -298.574364)
			(xy 70.58723 -298.580296) (xy 70.538055 -298.578315) (xy 70.489836 -298.568471) (xy 70.44382 -298.551019)
			(xy 70.401199 -298.526412) (xy 70.363078 -298.495287) (xy 70.330443 -298.45845) (xy 70.30414 -298.416854)
			(xy 70.284849 -298.371578) (xy 70.273072 -298.323794) (xy 70.269112 -298.27474) (xy 69.930264 -298.27474)
			(xy 69.929769 -298.299347) (xy 69.921874 -298.347924) (xy 69.90629 -298.394605) (xy 69.883419 -298.438182)
			(xy 69.853854 -298.477526) (xy 69.818361 -298.511618) (xy 69.777858 -298.539574) (xy 69.733396 -298.560672)
			(xy 69.686125 -298.574364) (xy 69.63727 -298.580296) (xy 69.588095 -298.578315) (xy 69.539876 -298.568471)
			(xy 69.49386 -298.551019) (xy 69.451239 -298.526412) (xy 69.413118 -298.495287) (xy 69.380483 -298.45845)
			(xy 69.35418 -298.416854) (xy 69.334889 -298.371578) (xy 69.323112 -298.323794) (xy 69.319152 -298.27474)
			(xy 68.98005 -298.27474) (xy 68.979555 -298.299347) (xy 68.97166 -298.347924) (xy 68.956076 -298.394605)
			(xy 68.933205 -298.438182) (xy 68.90364 -298.477526) (xy 68.868147 -298.511618) (xy 68.827644 -298.539574)
			(xy 68.783182 -298.560672) (xy 68.735911 -298.574364) (xy 68.687056 -298.580296) (xy 68.637881 -298.578315)
			(xy 68.589662 -298.568471) (xy 68.543646 -298.551019) (xy 68.501025 -298.526412) (xy 68.462904 -298.495287)
			(xy 68.430269 -298.45845) (xy 68.403966 -298.416854) (xy 68.384675 -298.371578) (xy 68.372898 -298.323794)
			(xy 68.368938 -298.27474) (xy 68.03009 -298.27474) (xy 68.029595 -298.299347) (xy 68.0217 -298.347924)
			(xy 68.006116 -298.394605) (xy 67.983245 -298.438182) (xy 67.95368 -298.477526) (xy 67.918187 -298.511618)
			(xy 67.877684 -298.539574) (xy 67.833222 -298.560672) (xy 67.785951 -298.574364) (xy 67.737096 -298.580296)
			(xy 67.687921 -298.578315) (xy 67.639702 -298.568471) (xy 67.593686 -298.551019) (xy 67.551065 -298.526412)
			(xy 67.512944 -298.495287) (xy 67.480309 -298.45845) (xy 67.454006 -298.416854) (xy 67.434715 -298.371578)
			(xy 67.422938 -298.323794) (xy 67.418978 -298.27474) (xy 67.08013 -298.27474) (xy 67.079635 -298.299347)
			(xy 67.07174 -298.347924) (xy 67.056156 -298.394605) (xy 67.033285 -298.438182) (xy 67.00372 -298.477526)
			(xy 66.968227 -298.511618) (xy 66.927724 -298.539574) (xy 66.883262 -298.560672) (xy 66.835991 -298.574364)
			(xy 66.787136 -298.580296) (xy 66.737961 -298.578315) (xy 66.689742 -298.568471) (xy 66.643726 -298.551019)
			(xy 66.601105 -298.526412) (xy 66.562984 -298.495287) (xy 66.530349 -298.45845) (xy 66.504046 -298.416854)
			(xy 66.484755 -298.371578) (xy 66.472978 -298.323794) (xy 66.469018 -298.27474) (xy 66.13017 -298.27474)
			(xy 66.129675 -298.299347) (xy 66.12178 -298.347924) (xy 66.106196 -298.394605) (xy 66.083325 -298.438182)
			(xy 66.05376 -298.477526) (xy 66.018267 -298.511618) (xy 65.977764 -298.539574) (xy 65.933302 -298.560672)
			(xy 65.886031 -298.574364) (xy 65.837176 -298.580296) (xy 65.788001 -298.578315) (xy 65.739782 -298.568471)
			(xy 65.693766 -298.551019) (xy 65.651145 -298.526412) (xy 65.613024 -298.495287) (xy 65.580389 -298.45845)
			(xy 65.554086 -298.416854) (xy 65.534795 -298.371578) (xy 65.523018 -298.323794) (xy 65.519058 -298.27474)
			(xy 65.18021 -298.27474) (xy 65.179715 -298.299347) (xy 65.17182 -298.347924) (xy 65.156236 -298.394605)
			(xy 65.133365 -298.438182) (xy 65.1038 -298.477526) (xy 65.068307 -298.511618) (xy 65.027804 -298.539574)
			(xy 64.983342 -298.560672) (xy 64.936071 -298.574364) (xy 64.887216 -298.580296) (xy 64.838041 -298.578315)
			(xy 64.789822 -298.568471) (xy 64.743806 -298.551019) (xy 64.701185 -298.526412) (xy 64.663064 -298.495287)
			(xy 64.630429 -298.45845) (xy 64.604126 -298.416854) (xy 64.584835 -298.371578) (xy 64.573058 -298.323794)
			(xy 64.569098 -298.27474) (xy 64.23025 -298.27474) (xy 64.229755 -298.299347) (xy 64.22186 -298.347924)
			(xy 64.206276 -298.394605) (xy 64.183405 -298.438182) (xy 64.15384 -298.477526) (xy 64.118347 -298.511618)
			(xy 64.077844 -298.539574) (xy 64.033382 -298.560672) (xy 63.986111 -298.574364) (xy 63.937256 -298.580296)
			(xy 63.888081 -298.578315) (xy 63.839862 -298.568471) (xy 63.793846 -298.551019) (xy 63.751225 -298.526412)
			(xy 63.713104 -298.495287) (xy 63.680469 -298.45845) (xy 63.654166 -298.416854) (xy 63.634875 -298.371578)
			(xy 63.623098 -298.323794) (xy 63.619138 -298.27474) (xy 63.28029 -298.27474) (xy 63.279795 -298.299347)
			(xy 63.2719 -298.347924) (xy 63.256316 -298.394605) (xy 63.233445 -298.438182) (xy 63.20388 -298.477526)
			(xy 63.168387 -298.511618) (xy 63.127884 -298.539574) (xy 63.083422 -298.560672) (xy 63.036151 -298.574364)
			(xy 62.987296 -298.580296) (xy 62.938121 -298.578315) (xy 62.889902 -298.568471) (xy 62.843886 -298.551019)
			(xy 62.801265 -298.526412) (xy 62.763144 -298.495287) (xy 62.730509 -298.45845) (xy 62.704206 -298.416854)
			(xy 62.684915 -298.371578) (xy 62.673138 -298.323794) (xy 62.669178 -298.27474) (xy 62.330076 -298.27474)
			(xy 62.329581 -298.299347) (xy 62.321686 -298.347924) (xy 62.306102 -298.394605) (xy 62.283231 -298.438182)
			(xy 62.253666 -298.477526) (xy 62.218173 -298.511618) (xy 62.17767 -298.539574) (xy 62.133208 -298.560672)
			(xy 62.085937 -298.574364) (xy 62.037082 -298.580296) (xy 61.987907 -298.578315) (xy 61.939688 -298.568471)
			(xy 61.893672 -298.551019) (xy 61.851051 -298.526412) (xy 61.81293 -298.495287) (xy 61.780295 -298.45845)
			(xy 61.753992 -298.416854) (xy 61.734701 -298.371578) (xy 61.722924 -298.323794) (xy 61.718964 -298.27474)
			(xy 61.380116 -298.27474) (xy 61.379621 -298.299347) (xy 61.371726 -298.347924) (xy 61.356142 -298.394605)
			(xy 61.333271 -298.438182) (xy 61.303706 -298.477526) (xy 61.268213 -298.511618) (xy 61.22771 -298.539574)
			(xy 61.183248 -298.560672) (xy 61.135977 -298.574364) (xy 61.087122 -298.580296) (xy 61.037947 -298.578315)
			(xy 60.989728 -298.568471) (xy 60.943712 -298.551019) (xy 60.901091 -298.526412) (xy 60.86297 -298.495287)
			(xy 60.830335 -298.45845) (xy 60.804032 -298.416854) (xy 60.784741 -298.371578) (xy 60.772964 -298.323794)
			(xy 60.769004 -298.27474) (xy 60.43168 -298.27474) (xy 60.431205 -298.298838) (xy 60.423665 -298.346439)
			(xy 60.408776 -298.392277) (xy 60.386904 -298.435224) (xy 60.358588 -298.474224) (xy 60.324524 -298.508318)
			(xy 60.285548 -298.536667) (xy 60.24262 -298.558575) (xy 60.196795 -298.573504) (xy 60.149199 -298.581085)
			(xy 60.125102 -298.581572) (xy 60.124848 -298.581572) (xy 60.094186 -298.580577) (xy 60.034168 -298.567913)
			(xy 60.005722 -298.556426) (xy 59.99607 -298.552108) (xy 59.965844 -298.552108) (xy 59.958598 -298.552327)
			(xy 59.94467 -298.556324) (xy 59.938412 -298.559982) (xy 59.87415 -298.60113) (xy 59.867193 -298.605986)
			(xy 59.856709 -298.619313) (xy 59.85113 -298.635325) (xy 59.850782 -298.643802) (xy 59.850782 -298.7294)
			(xy 86.488268 -298.7294) (xy 86.492339 -298.673778) (xy 86.504465 -298.619341) (xy 86.524388 -298.56725)
			(xy 86.551684 -298.518615) (xy 86.58577 -298.474472) (xy 86.625919 -298.435763) (xy 86.671277 -298.403312)
			(xy 86.720877 -298.377811) (xy 86.773661 -298.359804) (xy 86.828504 -298.349674) (xy 86.884238 -298.347637)
			(xy 86.939675 -298.353737) (xy 86.993632 -298.367843) (xy 87.044961 -298.389655) (xy 87.092567 -298.418709)
			(xy 87.135435 -298.454384) (xy 87.172652 -298.495921) (xy 87.203425 -298.542434) (xy 87.227097 -298.592931)
			(xy 87.243165 -298.646338) (xy 87.251285 -298.701514) (xy 87.251794 -298.7294) (xy 87.251285 -298.757286)
			(xy 87.243165 -298.812462) (xy 87.227097 -298.865869) (xy 87.203425 -298.916366) (xy 87.172652 -298.962879)
			(xy 87.135435 -299.004416) (xy 87.092567 -299.040091) (xy 87.044961 -299.069145) (xy 86.993632 -299.090957)
			(xy 86.939675 -299.105063) (xy 86.884238 -299.111163) (xy 86.828504 -299.109126) (xy 86.773661 -299.098996)
			(xy 86.720877 -299.080989) (xy 86.671277 -299.055488) (xy 86.625919 -299.023037) (xy 86.58577 -298.984328)
			(xy 86.551684 -298.940185) (xy 86.524388 -298.89155) (xy 86.504465 -298.839459) (xy 86.492339 -298.785022)
			(xy 86.488268 -298.7294) (xy 59.850782 -298.7294) (xy 59.850782 -299.224954) (xy 68.368938 -299.224954)
			(xy 68.372898 -299.1759) (xy 68.384675 -299.128116) (xy 68.403966 -299.08284) (xy 68.430269 -299.041244)
			(xy 68.462904 -299.004407) (xy 68.501025 -298.973282) (xy 68.543646 -298.948675) (xy 68.589662 -298.931223)
			(xy 68.637881 -298.921379) (xy 68.687056 -298.919398) (xy 68.735911 -298.92533) (xy 68.783182 -298.939022)
			(xy 68.827644 -298.96012) (xy 68.868147 -298.988076) (xy 68.90364 -299.022168) (xy 68.933205 -299.061512)
			(xy 68.956076 -299.105089) (xy 68.97166 -299.15177) (xy 68.979555 -299.200347) (xy 68.98005 -299.224954)
			(xy 69.319152 -299.224954) (xy 69.323112 -299.1759) (xy 69.334889 -299.128116) (xy 69.35418 -299.08284)
			(xy 69.380483 -299.041244) (xy 69.413118 -299.004407) (xy 69.451239 -298.973282) (xy 69.49386 -298.948675)
			(xy 69.539876 -298.931223) (xy 69.588095 -298.921379) (xy 69.63727 -298.919398) (xy 69.686125 -298.92533)
			(xy 69.733396 -298.939022) (xy 69.777858 -298.96012) (xy 69.818361 -298.988076) (xy 69.853854 -299.022168)
			(xy 69.883419 -299.061512) (xy 69.90629 -299.105089) (xy 69.921874 -299.15177) (xy 69.929769 -299.200347)
			(xy 69.930264 -299.224954) (xy 70.269112 -299.224954) (xy 70.273072 -299.1759) (xy 70.284849 -299.128116)
			(xy 70.30414 -299.08284) (xy 70.330443 -299.041244) (xy 70.363078 -299.004407) (xy 70.401199 -298.973282)
			(xy 70.44382 -298.948675) (xy 70.489836 -298.931223) (xy 70.538055 -298.921379) (xy 70.58723 -298.919398)
			(xy 70.636085 -298.92533) (xy 70.683356 -298.939022) (xy 70.727818 -298.96012) (xy 70.768321 -298.988076)
			(xy 70.803814 -299.022168) (xy 70.833379 -299.061512) (xy 70.85625 -299.105089) (xy 70.871834 -299.15177)
			(xy 70.879729 -299.200347) (xy 70.880224 -299.224954) (xy 71.219072 -299.224954) (xy 71.223032 -299.1759)
			(xy 71.234809 -299.128116) (xy 71.2541 -299.08284) (xy 71.280403 -299.041244) (xy 71.313038 -299.004407)
			(xy 71.351159 -298.973282) (xy 71.39378 -298.948675) (xy 71.439796 -298.931223) (xy 71.488015 -298.921379)
			(xy 71.53719 -298.919398) (xy 71.586045 -298.92533) (xy 71.633316 -298.939022) (xy 71.677778 -298.96012)
			(xy 71.718281 -298.988076) (xy 71.753774 -299.022168) (xy 71.783339 -299.061512) (xy 71.80621 -299.105089)
			(xy 71.821794 -299.15177) (xy 71.829689 -299.200347) (xy 71.830184 -299.224954) (xy 72.169032 -299.224954)
			(xy 72.172992 -299.1759) (xy 72.184769 -299.128116) (xy 72.20406 -299.08284) (xy 72.230363 -299.041244)
			(xy 72.262998 -299.004407) (xy 72.301119 -298.973282) (xy 72.34374 -298.948675) (xy 72.389756 -298.931223)
			(xy 72.437975 -298.921379) (xy 72.48715 -298.919398) (xy 72.536005 -298.92533) (xy 72.583276 -298.939022)
			(xy 72.627738 -298.96012) (xy 72.668241 -298.988076) (xy 72.703734 -299.022168) (xy 72.733299 -299.061512)
			(xy 72.75617 -299.105089) (xy 72.771754 -299.15177) (xy 72.779649 -299.200347) (xy 72.780144 -299.224954)
			(xy 73.118992 -299.224954) (xy 73.122952 -299.1759) (xy 73.134729 -299.128116) (xy 73.15402 -299.08284)
			(xy 73.180323 -299.041244) (xy 73.212958 -299.004407) (xy 73.251079 -298.973282) (xy 73.2937 -298.948675)
			(xy 73.339716 -298.931223) (xy 73.387935 -298.921379) (xy 73.43711 -298.919398) (xy 73.485965 -298.92533)
			(xy 73.533236 -298.939022) (xy 73.577698 -298.96012) (xy 73.618201 -298.988076) (xy 73.653694 -299.022168)
			(xy 73.683259 -299.061512) (xy 73.70613 -299.105089) (xy 73.721714 -299.15177) (xy 73.729609 -299.200347)
			(xy 73.730104 -299.224954) (xy 75.969126 -299.224954) (xy 75.973086 -299.1759) (xy 75.984863 -299.128116)
			(xy 76.004154 -299.08284) (xy 76.030457 -299.041244) (xy 76.063092 -299.004407) (xy 76.101213 -298.973282)
			(xy 76.143834 -298.948675) (xy 76.18985 -298.931223) (xy 76.238069 -298.921379) (xy 76.287244 -298.919398)
			(xy 76.336099 -298.92533) (xy 76.38337 -298.939022) (xy 76.427832 -298.96012) (xy 76.468335 -298.988076)
			(xy 76.503828 -299.022168) (xy 76.533393 -299.061512) (xy 76.556264 -299.105089) (xy 76.571848 -299.15177)
			(xy 76.579743 -299.200347) (xy 76.580238 -299.224954) (xy 76.919086 -299.224954) (xy 76.923046 -299.1759)
			(xy 76.934823 -299.128116) (xy 76.954114 -299.08284) (xy 76.980417 -299.041244) (xy 77.013052 -299.004407)
			(xy 77.051173 -298.973282) (xy 77.093794 -298.948675) (xy 77.13981 -298.931223) (xy 77.188029 -298.921379)
			(xy 77.237204 -298.919398) (xy 77.286059 -298.92533) (xy 77.33333 -298.939022) (xy 77.377792 -298.96012)
			(xy 77.418295 -298.988076) (xy 77.453788 -299.022168) (xy 77.483353 -299.061512) (xy 77.506224 -299.105089)
			(xy 77.521808 -299.15177) (xy 77.529703 -299.200347) (xy 77.530198 -299.224954) (xy 77.869046 -299.224954)
			(xy 77.873006 -299.1759) (xy 77.884783 -299.128116) (xy 77.904074 -299.08284) (xy 77.930377 -299.041244)
			(xy 77.963012 -299.004407) (xy 78.001133 -298.973282) (xy 78.043754 -298.948675) (xy 78.08977 -298.931223)
			(xy 78.137989 -298.921379) (xy 78.187164 -298.919398) (xy 78.236019 -298.92533) (xy 78.28329 -298.939022)
			(xy 78.327752 -298.96012) (xy 78.368255 -298.988076) (xy 78.403748 -299.022168) (xy 78.433313 -299.061512)
			(xy 78.456184 -299.105089) (xy 78.471768 -299.15177) (xy 78.479663 -299.200347) (xy 78.480158 -299.224954)
			(xy 78.819006 -299.224954) (xy 78.822966 -299.1759) (xy 78.834743 -299.128116) (xy 78.854034 -299.08284)
			(xy 78.880337 -299.041244) (xy 78.912972 -299.004407) (xy 78.951093 -298.973282) (xy 78.993714 -298.948675)
			(xy 79.03973 -298.931223) (xy 79.087949 -298.921379) (xy 79.137124 -298.919398) (xy 79.185979 -298.92533)
			(xy 79.23325 -298.939022) (xy 79.277712 -298.96012) (xy 79.318215 -298.988076) (xy 79.353708 -299.022168)
			(xy 79.383273 -299.061512) (xy 79.406144 -299.105089) (xy 79.421728 -299.15177) (xy 79.429623 -299.200347)
			(xy 79.430118 -299.224954) (xy 79.768966 -299.224954) (xy 79.772926 -299.1759) (xy 79.784703 -299.128116)
			(xy 79.803994 -299.08284) (xy 79.830297 -299.041244) (xy 79.862932 -299.004407) (xy 79.901053 -298.973282)
			(xy 79.943674 -298.948675) (xy 79.98969 -298.931223) (xy 80.037909 -298.921379) (xy 80.087084 -298.919398)
			(xy 80.135939 -298.92533) (xy 80.18321 -298.939022) (xy 80.227672 -298.96012) (xy 80.268175 -298.988076)
			(xy 80.303668 -299.022168) (xy 80.333233 -299.061512) (xy 80.356104 -299.105089) (xy 80.371688 -299.15177)
			(xy 80.379583 -299.200347) (xy 80.380078 -299.224954) (xy 80.71918 -299.224954) (xy 80.72314 -299.1759)
			(xy 80.734917 -299.128116) (xy 80.754208 -299.08284) (xy 80.780511 -299.041244) (xy 80.813146 -299.004407)
			(xy 80.851267 -298.973282) (xy 80.893888 -298.948675) (xy 80.939904 -298.931223) (xy 80.988123 -298.921379)
			(xy 81.037298 -298.919398) (xy 81.086153 -298.92533) (xy 81.133424 -298.939022) (xy 81.177886 -298.96012)
			(xy 81.218389 -298.988076) (xy 81.253882 -299.022168) (xy 81.283447 -299.061512) (xy 81.306318 -299.105089)
			(xy 81.321902 -299.15177) (xy 81.329797 -299.200347) (xy 81.330292 -299.224954) (xy 81.66914 -299.224954)
			(xy 81.6731 -299.1759) (xy 81.684877 -299.128116) (xy 81.704168 -299.08284) (xy 81.730471 -299.041244)
			(xy 81.763106 -299.004407) (xy 81.801227 -298.973282) (xy 81.843848 -298.948675) (xy 81.889864 -298.931223)
			(xy 81.938083 -298.921379) (xy 81.987258 -298.919398) (xy 82.036113 -298.92533) (xy 82.083384 -298.939022)
			(xy 82.127846 -298.96012) (xy 82.168349 -298.988076) (xy 82.203842 -299.022168) (xy 82.233407 -299.061512)
			(xy 82.256278 -299.105089) (xy 82.271862 -299.15177) (xy 82.279757 -299.200347) (xy 82.280252 -299.224954)
			(xy 82.6191 -299.224954) (xy 82.62306 -299.1759) (xy 82.634837 -299.128116) (xy 82.654128 -299.08284)
			(xy 82.680431 -299.041244) (xy 82.713066 -299.004407) (xy 82.751187 -298.973282) (xy 82.793808 -298.948675)
			(xy 82.839824 -298.931223) (xy 82.888043 -298.921379) (xy 82.937218 -298.919398) (xy 82.986073 -298.92533)
			(xy 83.033344 -298.939022) (xy 83.077806 -298.96012) (xy 83.118309 -298.988076) (xy 83.153802 -299.022168)
			(xy 83.183367 -299.061512) (xy 83.206238 -299.105089) (xy 83.221822 -299.15177) (xy 83.229717 -299.200347)
			(xy 83.230212 -299.224954) (xy 83.229717 -299.249561) (xy 83.221822 -299.298138) (xy 83.206238 -299.344819)
			(xy 83.183367 -299.388396) (xy 83.153802 -299.42774) (xy 83.118309 -299.461832) (xy 83.077806 -299.489788)
			(xy 83.033344 -299.510886) (xy 82.986073 -299.524578) (xy 82.937218 -299.53051) (xy 82.888043 -299.528529)
			(xy 82.839824 -299.518685) (xy 82.793808 -299.501233) (xy 82.751187 -299.476626) (xy 82.713066 -299.445501)
			(xy 82.680431 -299.408664) (xy 82.654128 -299.367068) (xy 82.634837 -299.321792) (xy 82.62306 -299.274008)
			(xy 82.6191 -299.224954) (xy 82.280252 -299.224954) (xy 82.279757 -299.249561) (xy 82.271862 -299.298138)
			(xy 82.256278 -299.344819) (xy 82.233407 -299.388396) (xy 82.203842 -299.42774) (xy 82.168349 -299.461832)
			(xy 82.127846 -299.489788) (xy 82.083384 -299.510886) (xy 82.036113 -299.524578) (xy 81.987258 -299.53051)
			(xy 81.938083 -299.528529) (xy 81.889864 -299.518685) (xy 81.843848 -299.501233) (xy 81.801227 -299.476626)
			(xy 81.763106 -299.445501) (xy 81.730471 -299.408664) (xy 81.704168 -299.367068) (xy 81.684877 -299.321792)
			(xy 81.6731 -299.274008) (xy 81.66914 -299.224954) (xy 81.330292 -299.224954) (xy 81.329797 -299.249561)
			(xy 81.321902 -299.298138) (xy 81.306318 -299.344819) (xy 81.283447 -299.388396) (xy 81.253882 -299.42774)
			(xy 81.218389 -299.461832) (xy 81.177886 -299.489788) (xy 81.133424 -299.510886) (xy 81.086153 -299.524578)
			(xy 81.037298 -299.53051) (xy 80.988123 -299.528529) (xy 80.939904 -299.518685) (xy 80.893888 -299.501233)
			(xy 80.851267 -299.476626) (xy 80.813146 -299.445501) (xy 80.780511 -299.408664) (xy 80.754208 -299.367068)
			(xy 80.734917 -299.321792) (xy 80.72314 -299.274008) (xy 80.71918 -299.224954) (xy 80.380078 -299.224954)
			(xy 80.379583 -299.249561) (xy 80.371688 -299.298138) (xy 80.356104 -299.344819) (xy 80.333233 -299.388396)
			(xy 80.303668 -299.42774) (xy 80.268175 -299.461832) (xy 80.227672 -299.489788) (xy 80.18321 -299.510886)
			(xy 80.135939 -299.524578) (xy 80.087084 -299.53051) (xy 80.037909 -299.528529) (xy 79.98969 -299.518685)
			(xy 79.943674 -299.501233) (xy 79.901053 -299.476626) (xy 79.862932 -299.445501) (xy 79.830297 -299.408664)
			(xy 79.803994 -299.367068) (xy 79.784703 -299.321792) (xy 79.772926 -299.274008) (xy 79.768966 -299.224954)
			(xy 79.430118 -299.224954) (xy 79.429623 -299.249561) (xy 79.421728 -299.298138) (xy 79.406144 -299.344819)
			(xy 79.383273 -299.388396) (xy 79.353708 -299.42774) (xy 79.318215 -299.461832) (xy 79.277712 -299.489788)
			(xy 79.23325 -299.510886) (xy 79.185979 -299.524578) (xy 79.137124 -299.53051) (xy 79.087949 -299.528529)
			(xy 79.03973 -299.518685) (xy 78.993714 -299.501233) (xy 78.951093 -299.476626) (xy 78.912972 -299.445501)
			(xy 78.880337 -299.408664) (xy 78.854034 -299.367068) (xy 78.834743 -299.321792) (xy 78.822966 -299.274008)
			(xy 78.819006 -299.224954) (xy 78.480158 -299.224954) (xy 78.479663 -299.249561) (xy 78.471768 -299.298138)
			(xy 78.456184 -299.344819) (xy 78.433313 -299.388396) (xy 78.403748 -299.42774) (xy 78.368255 -299.461832)
			(xy 78.327752 -299.489788) (xy 78.28329 -299.510886) (xy 78.236019 -299.524578) (xy 78.187164 -299.53051)
			(xy 78.137989 -299.528529) (xy 78.08977 -299.518685) (xy 78.043754 -299.501233) (xy 78.001133 -299.476626)
			(xy 77.963012 -299.445501) (xy 77.930377 -299.408664) (xy 77.904074 -299.367068) (xy 77.884783 -299.321792)
			(xy 77.873006 -299.274008) (xy 77.869046 -299.224954) (xy 77.530198 -299.224954) (xy 77.529703 -299.249561)
			(xy 77.521808 -299.298138) (xy 77.506224 -299.344819) (xy 77.483353 -299.388396) (xy 77.453788 -299.42774)
			(xy 77.418295 -299.461832) (xy 77.377792 -299.489788) (xy 77.33333 -299.510886) (xy 77.286059 -299.524578)
			(xy 77.237204 -299.53051) (xy 77.188029 -299.528529) (xy 77.13981 -299.518685) (xy 77.093794 -299.501233)
			(xy 77.051173 -299.476626) (xy 77.013052 -299.445501) (xy 76.980417 -299.408664) (xy 76.954114 -299.367068)
			(xy 76.934823 -299.321792) (xy 76.923046 -299.274008) (xy 76.919086 -299.224954) (xy 76.580238 -299.224954)
			(xy 76.579743 -299.249561) (xy 76.571848 -299.298138) (xy 76.556264 -299.344819) (xy 76.533393 -299.388396)
			(xy 76.503828 -299.42774) (xy 76.468335 -299.461832) (xy 76.427832 -299.489788) (xy 76.38337 -299.510886)
			(xy 76.336099 -299.524578) (xy 76.287244 -299.53051) (xy 76.238069 -299.528529) (xy 76.18985 -299.518685)
			(xy 76.143834 -299.501233) (xy 76.101213 -299.476626) (xy 76.063092 -299.445501) (xy 76.030457 -299.408664)
			(xy 76.004154 -299.367068) (xy 75.984863 -299.321792) (xy 75.973086 -299.274008) (xy 75.969126 -299.224954)
			(xy 73.730104 -299.224954) (xy 73.729609 -299.249561) (xy 73.721714 -299.298138) (xy 73.70613 -299.344819)
			(xy 73.683259 -299.388396) (xy 73.653694 -299.42774) (xy 73.618201 -299.461832) (xy 73.577698 -299.489788)
			(xy 73.533236 -299.510886) (xy 73.485965 -299.524578) (xy 73.43711 -299.53051) (xy 73.387935 -299.528529)
			(xy 73.339716 -299.518685) (xy 73.2937 -299.501233) (xy 73.251079 -299.476626) (xy 73.212958 -299.445501)
			(xy 73.180323 -299.408664) (xy 73.15402 -299.367068) (xy 73.134729 -299.321792) (xy 73.122952 -299.274008)
			(xy 73.118992 -299.224954) (xy 72.780144 -299.224954) (xy 72.779649 -299.249561) (xy 72.771754 -299.298138)
			(xy 72.75617 -299.344819) (xy 72.733299 -299.388396) (xy 72.703734 -299.42774) (xy 72.668241 -299.461832)
			(xy 72.627738 -299.489788) (xy 72.583276 -299.510886) (xy 72.536005 -299.524578) (xy 72.48715 -299.53051)
			(xy 72.437975 -299.528529) (xy 72.389756 -299.518685) (xy 72.34374 -299.501233) (xy 72.301119 -299.476626)
			(xy 72.262998 -299.445501) (xy 72.230363 -299.408664) (xy 72.20406 -299.367068) (xy 72.184769 -299.321792)
			(xy 72.172992 -299.274008) (xy 72.169032 -299.224954) (xy 71.830184 -299.224954) (xy 71.829689 -299.249561)
			(xy 71.821794 -299.298138) (xy 71.80621 -299.344819) (xy 71.783339 -299.388396) (xy 71.753774 -299.42774)
			(xy 71.718281 -299.461832) (xy 71.677778 -299.489788) (xy 71.633316 -299.510886) (xy 71.586045 -299.524578)
			(xy 71.53719 -299.53051) (xy 71.488015 -299.528529) (xy 71.439796 -299.518685) (xy 71.39378 -299.501233)
			(xy 71.351159 -299.476626) (xy 71.313038 -299.445501) (xy 71.280403 -299.408664) (xy 71.2541 -299.367068)
			(xy 71.234809 -299.321792) (xy 71.223032 -299.274008) (xy 71.219072 -299.224954) (xy 70.880224 -299.224954)
			(xy 70.879729 -299.249561) (xy 70.871834 -299.298138) (xy 70.85625 -299.344819) (xy 70.833379 -299.388396)
			(xy 70.803814 -299.42774) (xy 70.768321 -299.461832) (xy 70.727818 -299.489788) (xy 70.683356 -299.510886)
			(xy 70.636085 -299.524578) (xy 70.58723 -299.53051) (xy 70.538055 -299.528529) (xy 70.489836 -299.518685)
			(xy 70.44382 -299.501233) (xy 70.401199 -299.476626) (xy 70.363078 -299.445501) (xy 70.330443 -299.408664)
			(xy 70.30414 -299.367068) (xy 70.284849 -299.321792) (xy 70.273072 -299.274008) (xy 70.269112 -299.224954)
			(xy 69.930264 -299.224954) (xy 69.929769 -299.249561) (xy 69.921874 -299.298138) (xy 69.90629 -299.344819)
			(xy 69.883419 -299.388396) (xy 69.853854 -299.42774) (xy 69.818361 -299.461832) (xy 69.777858 -299.489788)
			(xy 69.733396 -299.510886) (xy 69.686125 -299.524578) (xy 69.63727 -299.53051) (xy 69.588095 -299.528529)
			(xy 69.539876 -299.518685) (xy 69.49386 -299.501233) (xy 69.451239 -299.476626) (xy 69.413118 -299.445501)
			(xy 69.380483 -299.408664) (xy 69.35418 -299.367068) (xy 69.334889 -299.321792) (xy 69.323112 -299.274008)
			(xy 69.319152 -299.224954) (xy 68.98005 -299.224954) (xy 68.979555 -299.249561) (xy 68.97166 -299.298138)
			(xy 68.956076 -299.344819) (xy 68.933205 -299.388396) (xy 68.90364 -299.42774) (xy 68.868147 -299.461832)
			(xy 68.827644 -299.489788) (xy 68.783182 -299.510886) (xy 68.735911 -299.524578) (xy 68.687056 -299.53051)
			(xy 68.637881 -299.528529) (xy 68.589662 -299.518685) (xy 68.543646 -299.501233) (xy 68.501025 -299.476626)
			(xy 68.462904 -299.445501) (xy 68.430269 -299.408664) (xy 68.403966 -299.367068) (xy 68.384675 -299.321792)
			(xy 68.372898 -299.274008) (xy 68.368938 -299.224954) (xy 59.850782 -299.224954) (xy 59.850782 -299.76445)
			(xy 88.041732 -299.76445) (xy 88.045803 -299.708828) (xy 88.057929 -299.654391) (xy 88.077852 -299.6023)
			(xy 88.105148 -299.553665) (xy 88.139234 -299.509522) (xy 88.179383 -299.470813) (xy 88.224741 -299.438362)
			(xy 88.274341 -299.412861) (xy 88.327125 -299.394854) (xy 88.381968 -299.384724) (xy 88.437702 -299.382687)
			(xy 88.493139 -299.388787) (xy 88.547096 -299.402893) (xy 88.598425 -299.424705) (xy 88.646031 -299.453759)
			(xy 88.688899 -299.489434) (xy 88.726116 -299.530971) (xy 88.756889 -299.577484) (xy 88.769164 -299.603668)
			(xy 90.31046 -299.603668) (xy 90.314531 -299.548046) (xy 90.326657 -299.493609) (xy 90.34658 -299.441518)
			(xy 90.373876 -299.392883) (xy 90.407962 -299.34874) (xy 90.448111 -299.310031) (xy 90.493469 -299.27758)
			(xy 90.543069 -299.252079) (xy 90.595853 -299.234072) (xy 90.650696 -299.223942) (xy 90.70643 -299.221905)
			(xy 90.761867 -299.228005) (xy 90.815824 -299.242111) (xy 90.867153 -299.263923) (xy 90.914759 -299.292977)
			(xy 90.957627 -299.328652) (xy 90.994844 -299.370189) (xy 91.025617 -299.416702) (xy 91.049289 -299.467199)
			(xy 91.065357 -299.520606) (xy 91.073477 -299.575782) (xy 91.073986 -299.603668) (xy 91.073477 -299.631554)
			(xy 91.065357 -299.68673) (xy 91.049289 -299.740137) (xy 91.030747 -299.77969) (xy 92.63837 -299.77969)
			(xy 92.642441 -299.724068) (xy 92.654567 -299.669631) (xy 92.67449 -299.61754) (xy 92.701786 -299.568905)
			(xy 92.735872 -299.524762) (xy 92.776021 -299.486053) (xy 92.821379 -299.453602) (xy 92.870979 -299.428101)
			(xy 92.923763 -299.410094) (xy 92.978606 -299.399964) (xy 93.03434 -299.397927) (xy 93.089777 -299.404027)
			(xy 93.143734 -299.418133) (xy 93.195063 -299.439945) (xy 93.242669 -299.468999) (xy 93.285537 -299.504674)
			(xy 93.322754 -299.546211) (xy 93.353527 -299.592724) (xy 93.377199 -299.643221) (xy 93.393267 -299.696628)
			(xy 93.401387 -299.751804) (xy 93.401896 -299.77969) (xy 93.401387 -299.807576) (xy 93.393267 -299.862752)
			(xy 93.377199 -299.916159) (xy 93.353527 -299.966656) (xy 93.322754 -300.013169) (xy 93.285537 -300.054706)
			(xy 93.242669 -300.090381) (xy 93.195063 -300.119435) (xy 93.143734 -300.141247) (xy 93.089777 -300.155353)
			(xy 93.03434 -300.161453) (xy 92.978606 -300.159416) (xy 92.923763 -300.149286) (xy 92.870979 -300.131279)
			(xy 92.821379 -300.105778) (xy 92.776021 -300.073327) (xy 92.735872 -300.034618) (xy 92.701786 -299.990475)
			(xy 92.67449 -299.94184) (xy 92.654567 -299.889749) (xy 92.642441 -299.835312) (xy 92.63837 -299.77969)
			(xy 91.030747 -299.77969) (xy 91.025617 -299.790634) (xy 90.994844 -299.837147) (xy 90.957627 -299.878684)
			(xy 90.914759 -299.914359) (xy 90.867153 -299.943413) (xy 90.815824 -299.965225) (xy 90.761867 -299.979331)
			(xy 90.70643 -299.985431) (xy 90.650696 -299.983394) (xy 90.595853 -299.973264) (xy 90.543069 -299.955257)
			(xy 90.493469 -299.929756) (xy 90.448111 -299.897305) (xy 90.407962 -299.858596) (xy 90.373876 -299.814453)
			(xy 90.34658 -299.765818) (xy 90.326657 -299.713727) (xy 90.314531 -299.65929) (xy 90.31046 -299.603668)
			(xy 88.769164 -299.603668) (xy 88.780561 -299.627981) (xy 88.796629 -299.681388) (xy 88.804749 -299.736564)
			(xy 88.805258 -299.76445) (xy 88.804749 -299.792336) (xy 88.796629 -299.847512) (xy 88.780561 -299.900919)
			(xy 88.756889 -299.951416) (xy 88.726116 -299.997929) (xy 88.688899 -300.039466) (xy 88.646031 -300.075141)
			(xy 88.598425 -300.104195) (xy 88.547096 -300.126007) (xy 88.493139 -300.140113) (xy 88.437702 -300.146213)
			(xy 88.381968 -300.144176) (xy 88.327125 -300.134046) (xy 88.274341 -300.116039) (xy 88.224741 -300.090538)
			(xy 88.179383 -300.058087) (xy 88.139234 -300.019378) (xy 88.105148 -299.975235) (xy 88.077852 -299.9266)
			(xy 88.057929 -299.874509) (xy 88.045803 -299.820072) (xy 88.041732 -299.76445) (xy 59.850782 -299.76445)
			(xy 59.850782 -299.806106) (xy 59.851206 -299.816176) (xy 59.85892 -299.834781) (xy 59.865768 -299.842174)
			(xy 59.868054 -299.84446) (xy 59.872626 -299.848016) (xy 59.906408 -299.86986) (xy 59.906916 -299.86986)
			(xy 59.937396 -299.889926) (xy 59.943725 -299.893792) (xy 59.957924 -299.898057) (xy 59.965336 -299.898308)
			(xy 59.985402 -299.898308) (xy 59.99734 -299.895768) (xy 60.00242 -299.893736) (xy 60.003182 -299.893482)
			(xy 60.022464 -299.885499) (xy 60.062645 -299.874226) (xy 60.103982 -299.868492) (xy 60.124848 -299.868082)
			(xy 60.148956 -299.868558) (xy 60.196578 -299.876108) (xy 60.242432 -299.891014) (xy 60.285391 -299.912909)
			(xy 60.324395 -299.941254) (xy 60.358486 -299.975352) (xy 60.386823 -300.014362) (xy 60.40871 -300.057325)
			(xy 60.423606 -300.103183) (xy 60.431146 -300.150806) (xy 60.43168 -300.174914) (xy 60.769004 -300.174914)
			(xy 60.772964 -300.12586) (xy 60.784741 -300.078076) (xy 60.804032 -300.0328) (xy 60.830335 -299.991204)
			(xy 60.86297 -299.954367) (xy 60.901091 -299.923242) (xy 60.943712 -299.898635) (xy 60.989728 -299.881183)
			(xy 61.037947 -299.871339) (xy 61.087122 -299.869358) (xy 61.135977 -299.87529) (xy 61.183248 -299.888982)
			(xy 61.22771 -299.91008) (xy 61.268213 -299.938036) (xy 61.303706 -299.972128) (xy 61.333271 -300.011472)
			(xy 61.356142 -300.055049) (xy 61.371726 -300.10173) (xy 61.379621 -300.150307) (xy 61.380116 -300.174914)
			(xy 61.718964 -300.174914) (xy 61.722924 -300.12586) (xy 61.734701 -300.078076) (xy 61.753992 -300.0328)
			(xy 61.780295 -299.991204) (xy 61.81293 -299.954367) (xy 61.851051 -299.923242) (xy 61.893672 -299.898635)
			(xy 61.939688 -299.881183) (xy 61.987907 -299.871339) (xy 62.037082 -299.869358) (xy 62.085937 -299.87529)
			(xy 62.133208 -299.888982) (xy 62.17767 -299.91008) (xy 62.218173 -299.938036) (xy 62.253666 -299.972128)
			(xy 62.283231 -300.011472) (xy 62.306102 -300.055049) (xy 62.321686 -300.10173) (xy 62.329581 -300.150307)
			(xy 62.330076 -300.174914) (xy 62.669178 -300.174914) (xy 62.673138 -300.12586) (xy 62.684915 -300.078076)
			(xy 62.704206 -300.0328) (xy 62.730509 -299.991204) (xy 62.763144 -299.954367) (xy 62.801265 -299.923242)
			(xy 62.843886 -299.898635) (xy 62.889902 -299.881183) (xy 62.938121 -299.871339) (xy 62.987296 -299.869358)
			(xy 63.036151 -299.87529) (xy 63.083422 -299.888982) (xy 63.127884 -299.91008) (xy 63.168387 -299.938036)
			(xy 63.20388 -299.972128) (xy 63.233445 -300.011472) (xy 63.256316 -300.055049) (xy 63.2719 -300.10173)
			(xy 63.279795 -300.150307) (xy 63.28029 -300.174914) (xy 63.619138 -300.174914) (xy 63.623098 -300.12586)
			(xy 63.634875 -300.078076) (xy 63.654166 -300.0328) (xy 63.680469 -299.991204) (xy 63.713104 -299.954367)
			(xy 63.751225 -299.923242) (xy 63.793846 -299.898635) (xy 63.839862 -299.881183) (xy 63.888081 -299.871339)
			(xy 63.937256 -299.869358) (xy 63.986111 -299.87529) (xy 64.033382 -299.888982) (xy 64.077844 -299.91008)
			(xy 64.118347 -299.938036) (xy 64.15384 -299.972128) (xy 64.183405 -300.011472) (xy 64.206276 -300.055049)
			(xy 64.22186 -300.10173) (xy 64.229755 -300.150307) (xy 64.23025 -300.174914) (xy 64.569098 -300.174914)
			(xy 64.573058 -300.12586) (xy 64.584835 -300.078076) (xy 64.604126 -300.0328) (xy 64.630429 -299.991204)
			(xy 64.663064 -299.954367) (xy 64.701185 -299.923242) (xy 64.743806 -299.898635) (xy 64.789822 -299.881183)
			(xy 64.838041 -299.871339) (xy 64.887216 -299.869358) (xy 64.936071 -299.87529) (xy 64.983342 -299.888982)
			(xy 65.027804 -299.91008) (xy 65.068307 -299.938036) (xy 65.1038 -299.972128) (xy 65.133365 -300.011472)
			(xy 65.156236 -300.055049) (xy 65.17182 -300.10173) (xy 65.179715 -300.150307) (xy 65.18021 -300.174914)
			(xy 65.519058 -300.174914) (xy 65.523018 -300.12586) (xy 65.534795 -300.078076) (xy 65.554086 -300.0328)
			(xy 65.580389 -299.991204) (xy 65.613024 -299.954367) (xy 65.651145 -299.923242) (xy 65.693766 -299.898635)
			(xy 65.739782 -299.881183) (xy 65.788001 -299.871339) (xy 65.837176 -299.869358) (xy 65.886031 -299.87529)
			(xy 65.933302 -299.888982) (xy 65.977764 -299.91008) (xy 66.018267 -299.938036) (xy 66.05376 -299.972128)
			(xy 66.083325 -300.011472) (xy 66.106196 -300.055049) (xy 66.12178 -300.10173) (xy 66.129675 -300.150307)
			(xy 66.13017 -300.174914) (xy 66.469018 -300.174914) (xy 66.472978 -300.12586) (xy 66.484755 -300.078076)
			(xy 66.504046 -300.0328) (xy 66.530349 -299.991204) (xy 66.562984 -299.954367) (xy 66.601105 -299.923242)
			(xy 66.643726 -299.898635) (xy 66.689742 -299.881183) (xy 66.737961 -299.871339) (xy 66.787136 -299.869358)
			(xy 66.835991 -299.87529) (xy 66.883262 -299.888982) (xy 66.927724 -299.91008) (xy 66.968227 -299.938036)
			(xy 67.00372 -299.972128) (xy 67.033285 -300.011472) (xy 67.056156 -300.055049) (xy 67.07174 -300.10173)
			(xy 67.079635 -300.150307) (xy 67.08013 -300.174914) (xy 67.418978 -300.174914) (xy 67.422938 -300.12586)
			(xy 67.434715 -300.078076) (xy 67.454006 -300.0328) (xy 67.480309 -299.991204) (xy 67.512944 -299.954367)
			(xy 67.551065 -299.923242) (xy 67.593686 -299.898635) (xy 67.639702 -299.881183) (xy 67.687921 -299.871339)
			(xy 67.737096 -299.869358) (xy 67.785951 -299.87529) (xy 67.833222 -299.888982) (xy 67.877684 -299.91008)
			(xy 67.918187 -299.938036) (xy 67.95368 -299.972128) (xy 67.983245 -300.011472) (xy 68.006116 -300.055049)
			(xy 68.0217 -300.10173) (xy 68.029595 -300.150307) (xy 68.03009 -300.174914) (xy 68.368938 -300.174914)
			(xy 68.372898 -300.12586) (xy 68.384675 -300.078076) (xy 68.403966 -300.0328) (xy 68.430269 -299.991204)
			(xy 68.462904 -299.954367) (xy 68.501025 -299.923242) (xy 68.543646 -299.898635) (xy 68.589662 -299.881183)
			(xy 68.637881 -299.871339) (xy 68.687056 -299.869358) (xy 68.735911 -299.87529) (xy 68.783182 -299.888982)
			(xy 68.827644 -299.91008) (xy 68.868147 -299.938036) (xy 68.90364 -299.972128) (xy 68.933205 -300.011472)
			(xy 68.956076 -300.055049) (xy 68.97166 -300.10173) (xy 68.979555 -300.150307) (xy 68.98005 -300.174914)
			(xy 69.319152 -300.174914) (xy 69.323112 -300.12586) (xy 69.334889 -300.078076) (xy 69.35418 -300.0328)
			(xy 69.380483 -299.991204) (xy 69.413118 -299.954367) (xy 69.451239 -299.923242) (xy 69.49386 -299.898635)
			(xy 69.539876 -299.881183) (xy 69.588095 -299.871339) (xy 69.63727 -299.869358) (xy 69.686125 -299.87529)
			(xy 69.733396 -299.888982) (xy 69.777858 -299.91008) (xy 69.818361 -299.938036) (xy 69.853854 -299.972128)
			(xy 69.883419 -300.011472) (xy 69.90629 -300.055049) (xy 69.921874 -300.10173) (xy 69.929769 -300.150307)
			(xy 69.930264 -300.174914) (xy 70.269112 -300.174914) (xy 70.273072 -300.12586) (xy 70.284849 -300.078076)
			(xy 70.30414 -300.0328) (xy 70.330443 -299.991204) (xy 70.363078 -299.954367) (xy 70.401199 -299.923242)
			(xy 70.44382 -299.898635) (xy 70.489836 -299.881183) (xy 70.538055 -299.871339) (xy 70.58723 -299.869358)
			(xy 70.636085 -299.87529) (xy 70.683356 -299.888982) (xy 70.727818 -299.91008) (xy 70.768321 -299.938036)
			(xy 70.803814 -299.972128) (xy 70.833379 -300.011472) (xy 70.85625 -300.055049) (xy 70.871834 -300.10173)
			(xy 70.879729 -300.150307) (xy 70.880224 -300.174914) (xy 71.219072 -300.174914) (xy 71.223032 -300.12586)
			(xy 71.234809 -300.078076) (xy 71.2541 -300.0328) (xy 71.280403 -299.991204) (xy 71.313038 -299.954367)
			(xy 71.351159 -299.923242) (xy 71.39378 -299.898635) (xy 71.439796 -299.881183) (xy 71.488015 -299.871339)
			(xy 71.53719 -299.869358) (xy 71.586045 -299.87529) (xy 71.633316 -299.888982) (xy 71.677778 -299.91008)
			(xy 71.718281 -299.938036) (xy 71.753774 -299.972128) (xy 71.783339 -300.011472) (xy 71.80621 -300.055049)
			(xy 71.821794 -300.10173) (xy 71.829689 -300.150307) (xy 71.830184 -300.174914) (xy 72.169032 -300.174914)
			(xy 72.172992 -300.12586) (xy 72.184769 -300.078076) (xy 72.20406 -300.0328) (xy 72.230363 -299.991204)
			(xy 72.262998 -299.954367) (xy 72.301119 -299.923242) (xy 72.34374 -299.898635) (xy 72.389756 -299.881183)
			(xy 72.437975 -299.871339) (xy 72.48715 -299.869358) (xy 72.536005 -299.87529) (xy 72.583276 -299.888982)
			(xy 72.627738 -299.91008) (xy 72.668241 -299.938036) (xy 72.703734 -299.972128) (xy 72.733299 -300.011472)
			(xy 72.75617 -300.055049) (xy 72.771754 -300.10173) (xy 72.779649 -300.150307) (xy 72.780144 -300.174914)
			(xy 73.118992 -300.174914) (xy 73.122952 -300.12586) (xy 73.134729 -300.078076) (xy 73.15402 -300.0328)
			(xy 73.180323 -299.991204) (xy 73.212958 -299.954367) (xy 73.251079 -299.923242) (xy 73.2937 -299.898635)
			(xy 73.339716 -299.881183) (xy 73.387935 -299.871339) (xy 73.43711 -299.869358) (xy 73.485965 -299.87529)
			(xy 73.533236 -299.888982) (xy 73.577698 -299.91008) (xy 73.618201 -299.938036) (xy 73.653694 -299.972128)
			(xy 73.683259 -300.011472) (xy 73.70613 -300.055049) (xy 73.721714 -300.10173) (xy 73.729609 -300.150307)
			(xy 73.730104 -300.174914) (xy 74.068952 -300.174914) (xy 74.072912 -300.12586) (xy 74.084689 -300.078076)
			(xy 74.10398 -300.0328) (xy 74.130283 -299.991204) (xy 74.162918 -299.954367) (xy 74.201039 -299.923242)
			(xy 74.24366 -299.898635) (xy 74.289676 -299.881183) (xy 74.337895 -299.871339) (xy 74.38707 -299.869358)
			(xy 74.435925 -299.87529) (xy 74.483196 -299.888982) (xy 74.527658 -299.91008) (xy 74.568161 -299.938036)
			(xy 74.603654 -299.972128) (xy 74.633219 -300.011472) (xy 74.65609 -300.055049) (xy 74.671674 -300.10173)
			(xy 74.679569 -300.150307) (xy 74.680064 -300.174914) (xy 75.969126 -300.174914) (xy 75.973086 -300.12586)
			(xy 75.984863 -300.078076) (xy 76.004154 -300.0328) (xy 76.030457 -299.991204) (xy 76.063092 -299.954367)
			(xy 76.101213 -299.923242) (xy 76.143834 -299.898635) (xy 76.18985 -299.881183) (xy 76.238069 -299.871339)
			(xy 76.287244 -299.869358) (xy 76.336099 -299.87529) (xy 76.38337 -299.888982) (xy 76.427832 -299.91008)
			(xy 76.468335 -299.938036) (xy 76.503828 -299.972128) (xy 76.533393 -300.011472) (xy 76.556264 -300.055049)
			(xy 76.571848 -300.10173) (xy 76.579743 -300.150307) (xy 76.580238 -300.174914) (xy 76.919086 -300.174914)
			(xy 76.923046 -300.12586) (xy 76.934823 -300.078076) (xy 76.954114 -300.0328) (xy 76.980417 -299.991204)
			(xy 77.013052 -299.954367) (xy 77.051173 -299.923242) (xy 77.093794 -299.898635) (xy 77.13981 -299.881183)
			(xy 77.188029 -299.871339) (xy 77.237204 -299.869358) (xy 77.286059 -299.87529) (xy 77.33333 -299.888982)
			(xy 77.377792 -299.91008) (xy 77.418295 -299.938036) (xy 77.453788 -299.972128) (xy 77.483353 -300.011472)
			(xy 77.506224 -300.055049) (xy 77.521808 -300.10173) (xy 77.529703 -300.150307) (xy 77.530198 -300.174914)
			(xy 77.869046 -300.174914) (xy 77.873006 -300.12586) (xy 77.884783 -300.078076) (xy 77.904074 -300.0328)
			(xy 77.930377 -299.991204) (xy 77.963012 -299.954367) (xy 78.001133 -299.923242) (xy 78.043754 -299.898635)
			(xy 78.08977 -299.881183) (xy 78.137989 -299.871339) (xy 78.187164 -299.869358) (xy 78.236019 -299.87529)
			(xy 78.28329 -299.888982) (xy 78.327752 -299.91008) (xy 78.368255 -299.938036) (xy 78.403748 -299.972128)
			(xy 78.433313 -300.011472) (xy 78.456184 -300.055049) (xy 78.471768 -300.10173) (xy 78.479663 -300.150307)
			(xy 78.480158 -300.174914) (xy 78.819006 -300.174914) (xy 78.822966 -300.12586) (xy 78.834743 -300.078076)
			(xy 78.854034 -300.0328) (xy 78.880337 -299.991204) (xy 78.912972 -299.954367) (xy 78.951093 -299.923242)
			(xy 78.993714 -299.898635) (xy 79.03973 -299.881183) (xy 79.087949 -299.871339) (xy 79.137124 -299.869358)
			(xy 79.185979 -299.87529) (xy 79.23325 -299.888982) (xy 79.277712 -299.91008) (xy 79.318215 -299.938036)
			(xy 79.353708 -299.972128) (xy 79.383273 -300.011472) (xy 79.406144 -300.055049) (xy 79.421728 -300.10173)
			(xy 79.429623 -300.150307) (xy 79.430118 -300.174914) (xy 79.768966 -300.174914) (xy 79.772926 -300.12586)
			(xy 79.784703 -300.078076) (xy 79.803994 -300.0328) (xy 79.830297 -299.991204) (xy 79.862932 -299.954367)
			(xy 79.901053 -299.923242) (xy 79.943674 -299.898635) (xy 79.98969 -299.881183) (xy 80.037909 -299.871339)
			(xy 80.087084 -299.869358) (xy 80.135939 -299.87529) (xy 80.18321 -299.888982) (xy 80.227672 -299.91008)
			(xy 80.268175 -299.938036) (xy 80.303668 -299.972128) (xy 80.333233 -300.011472) (xy 80.356104 -300.055049)
			(xy 80.371688 -300.10173) (xy 80.379583 -300.150307) (xy 80.380078 -300.174914) (xy 80.71918 -300.174914)
			(xy 80.72314 -300.12586) (xy 80.734917 -300.078076) (xy 80.754208 -300.0328) (xy 80.780511 -299.991204)
			(xy 80.813146 -299.954367) (xy 80.851267 -299.923242) (xy 80.893888 -299.898635) (xy 80.939904 -299.881183)
			(xy 80.988123 -299.871339) (xy 81.037298 -299.869358) (xy 81.086153 -299.87529) (xy 81.133424 -299.888982)
			(xy 81.177886 -299.91008) (xy 81.218389 -299.938036) (xy 81.253882 -299.972128) (xy 81.283447 -300.011472)
			(xy 81.306318 -300.055049) (xy 81.321902 -300.10173) (xy 81.329797 -300.150307) (xy 81.330292 -300.174914)
			(xy 81.66914 -300.174914) (xy 81.6731 -300.12586) (xy 81.684877 -300.078076) (xy 81.704168 -300.0328)
			(xy 81.730471 -299.991204) (xy 81.763106 -299.954367) (xy 81.801227 -299.923242) (xy 81.843848 -299.898635)
			(xy 81.889864 -299.881183) (xy 81.938083 -299.871339) (xy 81.987258 -299.869358) (xy 82.036113 -299.87529)
			(xy 82.083384 -299.888982) (xy 82.127846 -299.91008) (xy 82.168349 -299.938036) (xy 82.203842 -299.972128)
			(xy 82.233407 -300.011472) (xy 82.256278 -300.055049) (xy 82.271862 -300.10173) (xy 82.279757 -300.150307)
			(xy 82.280252 -300.174914) (xy 82.6191 -300.174914) (xy 82.62306 -300.12586) (xy 82.634837 -300.078076)
			(xy 82.654128 -300.0328) (xy 82.680431 -299.991204) (xy 82.713066 -299.954367) (xy 82.751187 -299.923242)
			(xy 82.793808 -299.898635) (xy 82.839824 -299.881183) (xy 82.888043 -299.871339) (xy 82.937218 -299.869358)
			(xy 82.986073 -299.87529) (xy 83.033344 -299.888982) (xy 83.077806 -299.91008) (xy 83.118309 -299.938036)
			(xy 83.153802 -299.972128) (xy 83.183367 -300.011472) (xy 83.206238 -300.055049) (xy 83.221822 -300.10173)
			(xy 83.229717 -300.150307) (xy 83.230212 -300.174914) (xy 83.229717 -300.199521) (xy 83.221822 -300.248098)
			(xy 83.206238 -300.294779) (xy 83.183367 -300.338356) (xy 83.153802 -300.3777) (xy 83.138034 -300.392846)
			(xy 93.257876 -300.392846) (xy 93.261947 -300.337224) (xy 93.274073 -300.282787) (xy 93.293996 -300.230696)
			(xy 93.321292 -300.182061) (xy 93.355378 -300.137918) (xy 93.395527 -300.099209) (xy 93.440885 -300.066758)
			(xy 93.490485 -300.041257) (xy 93.543269 -300.02325) (xy 93.598112 -300.01312) (xy 93.653846 -300.011083)
			(xy 93.709283 -300.017183) (xy 93.76324 -300.031289) (xy 93.814569 -300.053101) (xy 93.862175 -300.082155)
			(xy 93.905043 -300.11783) (xy 93.94226 -300.159367) (xy 93.973033 -300.20588) (xy 93.996705 -300.256377)
			(xy 94.012773 -300.309784) (xy 94.020893 -300.36496) (xy 94.021402 -300.392846) (xy 94.020893 -300.420732)
			(xy 94.012773 -300.475908) (xy 93.996705 -300.529315) (xy 93.973033 -300.579812) (xy 93.94226 -300.626325)
			(xy 93.905043 -300.667862) (xy 93.862175 -300.703537) (xy 93.814569 -300.732591) (xy 93.76324 -300.754403)
			(xy 93.709283 -300.768509) (xy 93.653846 -300.774609) (xy 93.598112 -300.772572) (xy 93.543269 -300.762442)
			(xy 93.490485 -300.744435) (xy 93.440885 -300.718934) (xy 93.395527 -300.686483) (xy 93.355378 -300.647774)
			(xy 93.321292 -300.603631) (xy 93.293996 -300.554996) (xy 93.274073 -300.502905) (xy 93.261947 -300.448468)
			(xy 93.257876 -300.392846) (xy 83.138034 -300.392846) (xy 83.118309 -300.411792) (xy 83.077806 -300.439748)
			(xy 83.033344 -300.460846) (xy 82.986073 -300.474538) (xy 82.937218 -300.48047) (xy 82.888043 -300.478489)
			(xy 82.839824 -300.468645) (xy 82.793808 -300.451193) (xy 82.751187 -300.426586) (xy 82.713066 -300.395461)
			(xy 82.680431 -300.358624) (xy 82.654128 -300.317028) (xy 82.634837 -300.271752) (xy 82.62306 -300.223968)
			(xy 82.6191 -300.174914) (xy 82.280252 -300.174914) (xy 82.279757 -300.199521) (xy 82.271862 -300.248098)
			(xy 82.256278 -300.294779) (xy 82.233407 -300.338356) (xy 82.203842 -300.3777) (xy 82.168349 -300.411792)
			(xy 82.127846 -300.439748) (xy 82.083384 -300.460846) (xy 82.036113 -300.474538) (xy 81.987258 -300.48047)
			(xy 81.938083 -300.478489) (xy 81.889864 -300.468645) (xy 81.843848 -300.451193) (xy 81.801227 -300.426586)
			(xy 81.763106 -300.395461) (xy 81.730471 -300.358624) (xy 81.704168 -300.317028) (xy 81.684877 -300.271752)
			(xy 81.6731 -300.223968) (xy 81.66914 -300.174914) (xy 81.330292 -300.174914) (xy 81.329797 -300.199521)
			(xy 81.321902 -300.248098) (xy 81.306318 -300.294779) (xy 81.283447 -300.338356) (xy 81.253882 -300.3777)
			(xy 81.218389 -300.411792) (xy 81.177886 -300.439748) (xy 81.133424 -300.460846) (xy 81.086153 -300.474538)
			(xy 81.037298 -300.48047) (xy 80.988123 -300.478489) (xy 80.939904 -300.468645) (xy 80.893888 -300.451193)
			(xy 80.851267 -300.426586) (xy 80.813146 -300.395461) (xy 80.780511 -300.358624) (xy 80.754208 -300.317028)
			(xy 80.734917 -300.271752) (xy 80.72314 -300.223968) (xy 80.71918 -300.174914) (xy 80.380078 -300.174914)
			(xy 80.379583 -300.199521) (xy 80.371688 -300.248098) (xy 80.356104 -300.294779) (xy 80.333233 -300.338356)
			(xy 80.303668 -300.3777) (xy 80.268175 -300.411792) (xy 80.227672 -300.439748) (xy 80.18321 -300.460846)
			(xy 80.135939 -300.474538) (xy 80.087084 -300.48047) (xy 80.037909 -300.478489) (xy 79.98969 -300.468645)
			(xy 79.943674 -300.451193) (xy 79.901053 -300.426586) (xy 79.862932 -300.395461) (xy 79.830297 -300.358624)
			(xy 79.803994 -300.317028) (xy 79.784703 -300.271752) (xy 79.772926 -300.223968) (xy 79.768966 -300.174914)
			(xy 79.430118 -300.174914) (xy 79.429623 -300.199521) (xy 79.421728 -300.248098) (xy 79.406144 -300.294779)
			(xy 79.383273 -300.338356) (xy 79.353708 -300.3777) (xy 79.318215 -300.411792) (xy 79.277712 -300.439748)
			(xy 79.23325 -300.460846) (xy 79.185979 -300.474538) (xy 79.137124 -300.48047) (xy 79.087949 -300.478489)
			(xy 79.03973 -300.468645) (xy 78.993714 -300.451193) (xy 78.951093 -300.426586) (xy 78.912972 -300.395461)
			(xy 78.880337 -300.358624) (xy 78.854034 -300.317028) (xy 78.834743 -300.271752) (xy 78.822966 -300.223968)
			(xy 78.819006 -300.174914) (xy 78.480158 -300.174914) (xy 78.479663 -300.199521) (xy 78.471768 -300.248098)
			(xy 78.456184 -300.294779) (xy 78.433313 -300.338356) (xy 78.403748 -300.3777) (xy 78.368255 -300.411792)
			(xy 78.327752 -300.439748) (xy 78.28329 -300.460846) (xy 78.236019 -300.474538) (xy 78.187164 -300.48047)
			(xy 78.137989 -300.478489) (xy 78.08977 -300.468645) (xy 78.043754 -300.451193) (xy 78.001133 -300.426586)
			(xy 77.963012 -300.395461) (xy 77.930377 -300.358624) (xy 77.904074 -300.317028) (xy 77.884783 -300.271752)
			(xy 77.873006 -300.223968) (xy 77.869046 -300.174914) (xy 77.530198 -300.174914) (xy 77.529703 -300.199521)
			(xy 77.521808 -300.248098) (xy 77.506224 -300.294779) (xy 77.483353 -300.338356) (xy 77.453788 -300.3777)
			(xy 77.418295 -300.411792) (xy 77.377792 -300.439748) (xy 77.33333 -300.460846) (xy 77.286059 -300.474538)
			(xy 77.237204 -300.48047) (xy 77.188029 -300.478489) (xy 77.13981 -300.468645) (xy 77.093794 -300.451193)
			(xy 77.051173 -300.426586) (xy 77.013052 -300.395461) (xy 76.980417 -300.358624) (xy 76.954114 -300.317028)
			(xy 76.934823 -300.271752) (xy 76.923046 -300.223968) (xy 76.919086 -300.174914) (xy 76.580238 -300.174914)
			(xy 76.579743 -300.199521) (xy 76.571848 -300.248098) (xy 76.556264 -300.294779) (xy 76.533393 -300.338356)
			(xy 76.503828 -300.3777) (xy 76.468335 -300.411792) (xy 76.427832 -300.439748) (xy 76.38337 -300.460846)
			(xy 76.336099 -300.474538) (xy 76.287244 -300.48047) (xy 76.238069 -300.478489) (xy 76.18985 -300.468645)
			(xy 76.143834 -300.451193) (xy 76.101213 -300.426586) (xy 76.063092 -300.395461) (xy 76.030457 -300.358624)
			(xy 76.004154 -300.317028) (xy 75.984863 -300.271752) (xy 75.973086 -300.223968) (xy 75.969126 -300.174914)
			(xy 74.680064 -300.174914) (xy 74.679569 -300.199521) (xy 74.671674 -300.248098) (xy 74.65609 -300.294779)
			(xy 74.633219 -300.338356) (xy 74.603654 -300.3777) (xy 74.568161 -300.411792) (xy 74.527658 -300.439748)
			(xy 74.483196 -300.460846) (xy 74.435925 -300.474538) (xy 74.38707 -300.48047) (xy 74.337895 -300.478489)
			(xy 74.289676 -300.468645) (xy 74.24366 -300.451193) (xy 74.201039 -300.426586) (xy 74.162918 -300.395461)
			(xy 74.130283 -300.358624) (xy 74.10398 -300.317028) (xy 74.084689 -300.271752) (xy 74.072912 -300.223968)
			(xy 74.068952 -300.174914) (xy 73.730104 -300.174914) (xy 73.729609 -300.199521) (xy 73.721714 -300.248098)
			(xy 73.70613 -300.294779) (xy 73.683259 -300.338356) (xy 73.653694 -300.3777) (xy 73.618201 -300.411792)
			(xy 73.577698 -300.439748) (xy 73.533236 -300.460846) (xy 73.485965 -300.474538) (xy 73.43711 -300.48047)
			(xy 73.387935 -300.478489) (xy 73.339716 -300.468645) (xy 73.2937 -300.451193) (xy 73.251079 -300.426586)
			(xy 73.212958 -300.395461) (xy 73.180323 -300.358624) (xy 73.15402 -300.317028) (xy 73.134729 -300.271752)
			(xy 73.122952 -300.223968) (xy 73.118992 -300.174914) (xy 72.780144 -300.174914) (xy 72.779649 -300.199521)
			(xy 72.771754 -300.248098) (xy 72.75617 -300.294779) (xy 72.733299 -300.338356) (xy 72.703734 -300.3777)
			(xy 72.668241 -300.411792) (xy 72.627738 -300.439748) (xy 72.583276 -300.460846) (xy 72.536005 -300.474538)
			(xy 72.48715 -300.48047) (xy 72.437975 -300.478489) (xy 72.389756 -300.468645) (xy 72.34374 -300.451193)
			(xy 72.301119 -300.426586) (xy 72.262998 -300.395461) (xy 72.230363 -300.358624) (xy 72.20406 -300.317028)
			(xy 72.184769 -300.271752) (xy 72.172992 -300.223968) (xy 72.169032 -300.174914) (xy 71.830184 -300.174914)
			(xy 71.829689 -300.199521) (xy 71.821794 -300.248098) (xy 71.80621 -300.294779) (xy 71.783339 -300.338356)
			(xy 71.753774 -300.3777) (xy 71.718281 -300.411792) (xy 71.677778 -300.439748) (xy 71.633316 -300.460846)
			(xy 71.586045 -300.474538) (xy 71.53719 -300.48047) (xy 71.488015 -300.478489) (xy 71.439796 -300.468645)
			(xy 71.39378 -300.451193) (xy 71.351159 -300.426586) (xy 71.313038 -300.395461) (xy 71.280403 -300.358624)
			(xy 71.2541 -300.317028) (xy 71.234809 -300.271752) (xy 71.223032 -300.223968) (xy 71.219072 -300.174914)
			(xy 70.880224 -300.174914) (xy 70.879729 -300.199521) (xy 70.871834 -300.248098) (xy 70.85625 -300.294779)
			(xy 70.833379 -300.338356) (xy 70.803814 -300.3777) (xy 70.768321 -300.411792) (xy 70.727818 -300.439748)
			(xy 70.683356 -300.460846) (xy 70.636085 -300.474538) (xy 70.58723 -300.48047) (xy 70.538055 -300.478489)
			(xy 70.489836 -300.468645) (xy 70.44382 -300.451193) (xy 70.401199 -300.426586) (xy 70.363078 -300.395461)
			(xy 70.330443 -300.358624) (xy 70.30414 -300.317028) (xy 70.284849 -300.271752) (xy 70.273072 -300.223968)
			(xy 70.269112 -300.174914) (xy 69.930264 -300.174914) (xy 69.929769 -300.199521) (xy 69.921874 -300.248098)
			(xy 69.90629 -300.294779) (xy 69.883419 -300.338356) (xy 69.853854 -300.3777) (xy 69.818361 -300.411792)
			(xy 69.777858 -300.439748) (xy 69.733396 -300.460846) (xy 69.686125 -300.474538) (xy 69.63727 -300.48047)
			(xy 69.588095 -300.478489) (xy 69.539876 -300.468645) (xy 69.49386 -300.451193) (xy 69.451239 -300.426586)
			(xy 69.413118 -300.395461) (xy 69.380483 -300.358624) (xy 69.35418 -300.317028) (xy 69.334889 -300.271752)
			(xy 69.323112 -300.223968) (xy 69.319152 -300.174914) (xy 68.98005 -300.174914) (xy 68.979555 -300.199521)
			(xy 68.97166 -300.248098) (xy 68.956076 -300.294779) (xy 68.933205 -300.338356) (xy 68.90364 -300.3777)
			(xy 68.868147 -300.411792) (xy 68.827644 -300.439748) (xy 68.783182 -300.460846) (xy 68.735911 -300.474538)
			(xy 68.687056 -300.48047) (xy 68.637881 -300.478489) (xy 68.589662 -300.468645) (xy 68.543646 -300.451193)
			(xy 68.501025 -300.426586) (xy 68.462904 -300.395461) (xy 68.430269 -300.358624) (xy 68.403966 -300.317028)
			(xy 68.384675 -300.271752) (xy 68.372898 -300.223968) (xy 68.368938 -300.174914) (xy 68.03009 -300.174914)
			(xy 68.029595 -300.199521) (xy 68.0217 -300.248098) (xy 68.006116 -300.294779) (xy 67.983245 -300.338356)
			(xy 67.95368 -300.3777) (xy 67.918187 -300.411792) (xy 67.877684 -300.439748) (xy 67.833222 -300.460846)
			(xy 67.785951 -300.474538) (xy 67.737096 -300.48047) (xy 67.687921 -300.478489) (xy 67.639702 -300.468645)
			(xy 67.593686 -300.451193) (xy 67.551065 -300.426586) (xy 67.512944 -300.395461) (xy 67.480309 -300.358624)
			(xy 67.454006 -300.317028) (xy 67.434715 -300.271752) (xy 67.422938 -300.223968) (xy 67.418978 -300.174914)
			(xy 67.08013 -300.174914) (xy 67.079635 -300.199521) (xy 67.07174 -300.248098) (xy 67.056156 -300.294779)
			(xy 67.033285 -300.338356) (xy 67.00372 -300.3777) (xy 66.968227 -300.411792) (xy 66.927724 -300.439748)
			(xy 66.883262 -300.460846) (xy 66.835991 -300.474538) (xy 66.787136 -300.48047) (xy 66.737961 -300.478489)
			(xy 66.689742 -300.468645) (xy 66.643726 -300.451193) (xy 66.601105 -300.426586) (xy 66.562984 -300.395461)
			(xy 66.530349 -300.358624) (xy 66.504046 -300.317028) (xy 66.484755 -300.271752) (xy 66.472978 -300.223968)
			(xy 66.469018 -300.174914) (xy 66.13017 -300.174914) (xy 66.129675 -300.199521) (xy 66.12178 -300.248098)
			(xy 66.106196 -300.294779) (xy 66.083325 -300.338356) (xy 66.05376 -300.3777) (xy 66.018267 -300.411792)
			(xy 65.977764 -300.439748) (xy 65.933302 -300.460846) (xy 65.886031 -300.474538) (xy 65.837176 -300.48047)
			(xy 65.788001 -300.478489) (xy 65.739782 -300.468645) (xy 65.693766 -300.451193) (xy 65.651145 -300.426586)
			(xy 65.613024 -300.395461) (xy 65.580389 -300.358624) (xy 65.554086 -300.317028) (xy 65.534795 -300.271752)
			(xy 65.523018 -300.223968) (xy 65.519058 -300.174914) (xy 65.18021 -300.174914) (xy 65.179715 -300.199521)
			(xy 65.17182 -300.248098) (xy 65.156236 -300.294779) (xy 65.133365 -300.338356) (xy 65.1038 -300.3777)
			(xy 65.068307 -300.411792) (xy 65.027804 -300.439748) (xy 64.983342 -300.460846) (xy 64.936071 -300.474538)
			(xy 64.887216 -300.48047) (xy 64.838041 -300.478489) (xy 64.789822 -300.468645) (xy 64.743806 -300.451193)
			(xy 64.701185 -300.426586) (xy 64.663064 -300.395461) (xy 64.630429 -300.358624) (xy 64.604126 -300.317028)
			(xy 64.584835 -300.271752) (xy 64.573058 -300.223968) (xy 64.569098 -300.174914) (xy 64.23025 -300.174914)
			(xy 64.229755 -300.199521) (xy 64.22186 -300.248098) (xy 64.206276 -300.294779) (xy 64.183405 -300.338356)
			(xy 64.15384 -300.3777) (xy 64.118347 -300.411792) (xy 64.077844 -300.439748) (xy 64.033382 -300.460846)
			(xy 63.986111 -300.474538) (xy 63.937256 -300.48047) (xy 63.888081 -300.478489) (xy 63.839862 -300.468645)
			(xy 63.793846 -300.451193) (xy 63.751225 -300.426586) (xy 63.713104 -300.395461) (xy 63.680469 -300.358624)
			(xy 63.654166 -300.317028) (xy 63.634875 -300.271752) (xy 63.623098 -300.223968) (xy 63.619138 -300.174914)
			(xy 63.28029 -300.174914) (xy 63.279795 -300.199521) (xy 63.2719 -300.248098) (xy 63.256316 -300.294779)
			(xy 63.233445 -300.338356) (xy 63.20388 -300.3777) (xy 63.168387 -300.411792) (xy 63.127884 -300.439748)
			(xy 63.083422 -300.460846) (xy 63.036151 -300.474538) (xy 62.987296 -300.48047) (xy 62.938121 -300.478489)
			(xy 62.889902 -300.468645) (xy 62.843886 -300.451193) (xy 62.801265 -300.426586) (xy 62.763144 -300.395461)
			(xy 62.730509 -300.358624) (xy 62.704206 -300.317028) (xy 62.684915 -300.271752) (xy 62.673138 -300.223968)
			(xy 62.669178 -300.174914) (xy 62.330076 -300.174914) (xy 62.329581 -300.199521) (xy 62.321686 -300.248098)
			(xy 62.306102 -300.294779) (xy 62.283231 -300.338356) (xy 62.253666 -300.3777) (xy 62.218173 -300.411792)
			(xy 62.17767 -300.439748) (xy 62.133208 -300.460846) (xy 62.085937 -300.474538) (xy 62.037082 -300.48047)
			(xy 61.987907 -300.478489) (xy 61.939688 -300.468645) (xy 61.893672 -300.451193) (xy 61.851051 -300.426586)
			(xy 61.81293 -300.395461) (xy 61.780295 -300.358624) (xy 61.753992 -300.317028) (xy 61.734701 -300.271752)
			(xy 61.722924 -300.223968) (xy 61.718964 -300.174914) (xy 61.380116 -300.174914) (xy 61.379621 -300.199521)
			(xy 61.371726 -300.248098) (xy 61.356142 -300.294779) (xy 61.333271 -300.338356) (xy 61.303706 -300.3777)
			(xy 61.268213 -300.411792) (xy 61.22771 -300.439748) (xy 61.183248 -300.460846) (xy 61.135977 -300.474538)
			(xy 61.087122 -300.48047) (xy 61.037947 -300.478489) (xy 60.989728 -300.468645) (xy 60.943712 -300.451193)
			(xy 60.901091 -300.426586) (xy 60.86297 -300.395461) (xy 60.830335 -300.358624) (xy 60.804032 -300.317028)
			(xy 60.784741 -300.271752) (xy 60.772964 -300.223968) (xy 60.769004 -300.174914) (xy 60.43168 -300.174914)
			(xy 60.431207 -300.199013) (xy 60.42367 -300.246618) (xy 60.408783 -300.292459) (xy 60.386913 -300.33541)
			(xy 60.358598 -300.374413) (xy 60.324532 -300.40851) (xy 60.285556 -300.436863) (xy 60.242626 -300.458773)
			(xy 60.196798 -300.473703) (xy 60.149201 -300.481284) (xy 60.125102 -300.481746) (xy 60.124848 -300.481746)
			(xy 60.094186 -300.480751) (xy 60.034169 -300.468086) (xy 60.005722 -300.4566) (xy 59.99607 -300.452282)
			(xy 59.965844 -300.452282) (xy 59.958598 -300.452501) (xy 59.944669 -300.456495) (xy 59.938412 -300.460156)
			(xy 59.87415 -300.501304) (xy 59.867191 -300.506159) (xy 59.8567 -300.519484) (xy 59.851113 -300.535498)
			(xy 59.850782 -300.543976) (xy 59.850782 -301.124874) (xy 68.368938 -301.124874) (xy 68.372898 -301.07582)
			(xy 68.384675 -301.028036) (xy 68.403966 -300.98276) (xy 68.430269 -300.941164) (xy 68.462904 -300.904327)
			(xy 68.501025 -300.873202) (xy 68.543646 -300.848595) (xy 68.589662 -300.831143) (xy 68.637881 -300.821299)
			(xy 68.687056 -300.819318) (xy 68.735911 -300.82525) (xy 68.783182 -300.838942) (xy 68.827644 -300.86004)
			(xy 68.868147 -300.887996) (xy 68.90364 -300.922088) (xy 68.933205 -300.961432) (xy 68.956076 -301.005009)
			(xy 68.97166 -301.05169) (xy 68.979555 -301.100267) (xy 68.98005 -301.124874) (xy 69.319152 -301.124874)
			(xy 69.323112 -301.07582) (xy 69.334889 -301.028036) (xy 69.35418 -300.98276) (xy 69.380483 -300.941164)
			(xy 69.413118 -300.904327) (xy 69.451239 -300.873202) (xy 69.49386 -300.848595) (xy 69.539876 -300.831143)
			(xy 69.588095 -300.821299) (xy 69.63727 -300.819318) (xy 69.686125 -300.82525) (xy 69.733396 -300.838942)
			(xy 69.777858 -300.86004) (xy 69.818361 -300.887996) (xy 69.853854 -300.922088) (xy 69.883419 -300.961432)
			(xy 69.90629 -301.005009) (xy 69.921874 -301.05169) (xy 69.929769 -301.100267) (xy 69.930264 -301.124874)
			(xy 70.269112 -301.124874) (xy 70.273072 -301.07582) (xy 70.284849 -301.028036) (xy 70.30414 -300.98276)
			(xy 70.330443 -300.941164) (xy 70.363078 -300.904327) (xy 70.401199 -300.873202) (xy 70.44382 -300.848595)
			(xy 70.489836 -300.831143) (xy 70.538055 -300.821299) (xy 70.58723 -300.819318) (xy 70.636085 -300.82525)
			(xy 70.683356 -300.838942) (xy 70.727818 -300.86004) (xy 70.768321 -300.887996) (xy 70.803814 -300.922088)
			(xy 70.833379 -300.961432) (xy 70.85625 -301.005009) (xy 70.871834 -301.05169) (xy 70.879729 -301.100267)
			(xy 70.880224 -301.124874) (xy 71.219072 -301.124874) (xy 71.223032 -301.07582) (xy 71.234809 -301.028036)
			(xy 71.2541 -300.98276) (xy 71.280403 -300.941164) (xy 71.313038 -300.904327) (xy 71.351159 -300.873202)
			(xy 71.39378 -300.848595) (xy 71.439796 -300.831143) (xy 71.488015 -300.821299) (xy 71.53719 -300.819318)
			(xy 71.586045 -300.82525) (xy 71.633316 -300.838942) (xy 71.677778 -300.86004) (xy 71.718281 -300.887996)
			(xy 71.753774 -300.922088) (xy 71.783339 -300.961432) (xy 71.80621 -301.005009) (xy 71.821794 -301.05169)
			(xy 71.829689 -301.100267) (xy 71.830184 -301.124874) (xy 72.169032 -301.124874) (xy 72.172992 -301.07582)
			(xy 72.184769 -301.028036) (xy 72.20406 -300.98276) (xy 72.230363 -300.941164) (xy 72.262998 -300.904327)
			(xy 72.301119 -300.873202) (xy 72.34374 -300.848595) (xy 72.389756 -300.831143) (xy 72.437975 -300.821299)
			(xy 72.48715 -300.819318) (xy 72.536005 -300.82525) (xy 72.583276 -300.838942) (xy 72.627738 -300.86004)
			(xy 72.668241 -300.887996) (xy 72.703734 -300.922088) (xy 72.733299 -300.961432) (xy 72.75617 -301.005009)
			(xy 72.771754 -301.05169) (xy 72.779649 -301.100267) (xy 72.780144 -301.124874) (xy 73.118992 -301.124874)
			(xy 73.122952 -301.07582) (xy 73.134729 -301.028036) (xy 73.15402 -300.98276) (xy 73.180323 -300.941164)
			(xy 73.212958 -300.904327) (xy 73.251079 -300.873202) (xy 73.2937 -300.848595) (xy 73.339716 -300.831143)
			(xy 73.387935 -300.821299) (xy 73.43711 -300.819318) (xy 73.485965 -300.82525) (xy 73.533236 -300.838942)
			(xy 73.577698 -300.86004) (xy 73.618201 -300.887996) (xy 73.653694 -300.922088) (xy 73.683259 -300.961432)
			(xy 73.70613 -301.005009) (xy 73.721714 -301.05169) (xy 73.729609 -301.100267) (xy 73.730104 -301.124874)
			(xy 73.729609 -301.149481) (xy 73.721714 -301.198058) (xy 73.70613 -301.244739) (xy 73.683259 -301.288316)
			(xy 73.653694 -301.32766) (xy 73.618201 -301.361752) (xy 73.577698 -301.389708) (xy 73.533236 -301.410806)
			(xy 73.485965 -301.424498) (xy 73.43711 -301.43043) (xy 73.387935 -301.428449) (xy 73.339716 -301.418605)
			(xy 73.2937 -301.401153) (xy 73.251079 -301.376546) (xy 73.212958 -301.345421) (xy 73.180323 -301.308584)
			(xy 73.15402 -301.266988) (xy 73.134729 -301.221712) (xy 73.122952 -301.173928) (xy 73.118992 -301.124874)
			(xy 72.780144 -301.124874) (xy 72.779649 -301.149481) (xy 72.771754 -301.198058) (xy 72.75617 -301.244739)
			(xy 72.733299 -301.288316) (xy 72.703734 -301.32766) (xy 72.668241 -301.361752) (xy 72.627738 -301.389708)
			(xy 72.583276 -301.410806) (xy 72.536005 -301.424498) (xy 72.48715 -301.43043) (xy 72.437975 -301.428449)
			(xy 72.389756 -301.418605) (xy 72.34374 -301.401153) (xy 72.301119 -301.376546) (xy 72.262998 -301.345421)
			(xy 72.230363 -301.308584) (xy 72.20406 -301.266988) (xy 72.184769 -301.221712) (xy 72.172992 -301.173928)
			(xy 72.169032 -301.124874) (xy 71.830184 -301.124874) (xy 71.829689 -301.149481) (xy 71.821794 -301.198058)
			(xy 71.80621 -301.244739) (xy 71.783339 -301.288316) (xy 71.753774 -301.32766) (xy 71.718281 -301.361752)
			(xy 71.677778 -301.389708) (xy 71.633316 -301.410806) (xy 71.586045 -301.424498) (xy 71.53719 -301.43043)
			(xy 71.488015 -301.428449) (xy 71.439796 -301.418605) (xy 71.39378 -301.401153) (xy 71.351159 -301.376546)
			(xy 71.313038 -301.345421) (xy 71.280403 -301.308584) (xy 71.2541 -301.266988) (xy 71.234809 -301.221712)
			(xy 71.223032 -301.173928) (xy 71.219072 -301.124874) (xy 70.880224 -301.124874) (xy 70.879729 -301.149481)
			(xy 70.871834 -301.198058) (xy 70.85625 -301.244739) (xy 70.833379 -301.288316) (xy 70.803814 -301.32766)
			(xy 70.768321 -301.361752) (xy 70.727818 -301.389708) (xy 70.683356 -301.410806) (xy 70.636085 -301.424498)
			(xy 70.58723 -301.43043) (xy 70.538055 -301.428449) (xy 70.489836 -301.418605) (xy 70.44382 -301.401153)
			(xy 70.401199 -301.376546) (xy 70.363078 -301.345421) (xy 70.330443 -301.308584) (xy 70.30414 -301.266988)
			(xy 70.284849 -301.221712) (xy 70.273072 -301.173928) (xy 70.269112 -301.124874) (xy 69.930264 -301.124874)
			(xy 69.929769 -301.149481) (xy 69.921874 -301.198058) (xy 69.90629 -301.244739) (xy 69.883419 -301.288316)
			(xy 69.853854 -301.32766) (xy 69.818361 -301.361752) (xy 69.777858 -301.389708) (xy 69.733396 -301.410806)
			(xy 69.686125 -301.424498) (xy 69.63727 -301.43043) (xy 69.588095 -301.428449) (xy 69.539876 -301.418605)
			(xy 69.49386 -301.401153) (xy 69.451239 -301.376546) (xy 69.413118 -301.345421) (xy 69.380483 -301.308584)
			(xy 69.35418 -301.266988) (xy 69.334889 -301.221712) (xy 69.323112 -301.173928) (xy 69.319152 -301.124874)
			(xy 68.98005 -301.124874) (xy 68.979555 -301.149481) (xy 68.97166 -301.198058) (xy 68.956076 -301.244739)
			(xy 68.933205 -301.288316) (xy 68.90364 -301.32766) (xy 68.868147 -301.361752) (xy 68.827644 -301.389708)
			(xy 68.783182 -301.410806) (xy 68.735911 -301.424498) (xy 68.687056 -301.43043) (xy 68.637881 -301.428449)
			(xy 68.589662 -301.418605) (xy 68.543646 -301.401153) (xy 68.501025 -301.376546) (xy 68.462904 -301.345421)
			(xy 68.430269 -301.308584) (xy 68.403966 -301.266988) (xy 68.384675 -301.221712) (xy 68.372898 -301.173928)
			(xy 68.368938 -301.124874) (xy 59.850782 -301.124874) (xy 59.850782 -301.5999) (xy 75.494122 -301.5999)
			(xy 75.498293 -301.549559) (xy 75.510692 -301.500592) (xy 75.530981 -301.454332) (xy 75.558607 -301.412043)
			(xy 75.592815 -301.374876) (xy 75.632674 -301.343847) (xy 75.677097 -301.3198) (xy 75.724871 -301.303393)
			(xy 75.774694 -301.295071) (xy 75.79995 -301.294546) (xy 75.814133 -301.29473) (xy 75.842373 -301.297397)
			(xy 75.856338 -301.29988) (xy 75.868784 -301.302166) (xy 75.892406 -301.2948) (xy 75.969876 -301.21733)
			(xy 75.977242 -301.193708) (xy 75.974956 -301.181262) (xy 75.972479 -301.167296) (xy 75.969807 -301.139057)
			(xy 75.969622 -301.124874) (xy 75.970106 -301.100056) (xy 75.97814 -301.051075) (xy 75.993992 -301.004039)
			(xy 76.017245 -300.960187) (xy 76.047285 -300.920674) (xy 76.083322 -300.886542) (xy 76.124406 -300.858689)
			(xy 76.169455 -300.837849) (xy 76.217282 -300.824572) (xy 76.266627 -300.819207) (xy 76.316189 -300.821895)
			(xy 76.364664 -300.832566) (xy 76.410774 -300.850939) (xy 76.453305 -300.876529) (xy 76.491135 -300.908662)
			(xy 76.523269 -300.946492) (xy 76.54886 -300.989022) (xy 76.567233 -301.035132) (xy 76.577904 -301.083607)
			(xy 76.580143 -301.124874) (xy 76.919086 -301.124874) (xy 76.923046 -301.07582) (xy 76.934823 -301.028036)
			(xy 76.954114 -300.98276) (xy 76.980417 -300.941164) (xy 77.013052 -300.904327) (xy 77.051173 -300.873202)
			(xy 77.093794 -300.848595) (xy 77.13981 -300.831143) (xy 77.188029 -300.821299) (xy 77.237204 -300.819318)
			(xy 77.286059 -300.82525) (xy 77.33333 -300.838942) (xy 77.377792 -300.86004) (xy 77.418295 -300.887996)
			(xy 77.453788 -300.922088) (xy 77.483353 -300.961432) (xy 77.506224 -301.005009) (xy 77.521808 -301.05169)
			(xy 77.529703 -301.100267) (xy 77.530198 -301.124874) (xy 77.869046 -301.124874) (xy 77.873006 -301.07582)
			(xy 77.884783 -301.028036) (xy 77.904074 -300.98276) (xy 77.930377 -300.941164) (xy 77.963012 -300.904327)
			(xy 78.001133 -300.873202) (xy 78.043754 -300.848595) (xy 78.08977 -300.831143) (xy 78.137989 -300.821299)
			(xy 78.187164 -300.819318) (xy 78.236019 -300.82525) (xy 78.28329 -300.838942) (xy 78.327752 -300.86004)
			(xy 78.368255 -300.887996) (xy 78.403748 -300.922088) (xy 78.433313 -300.961432) (xy 78.456184 -301.005009)
			(xy 78.471768 -301.05169) (xy 78.479663 -301.100267) (xy 78.480158 -301.124874) (xy 78.819006 -301.124874)
			(xy 78.822966 -301.07582) (xy 78.834743 -301.028036) (xy 78.854034 -300.98276) (xy 78.880337 -300.941164)
			(xy 78.912972 -300.904327) (xy 78.951093 -300.873202) (xy 78.993714 -300.848595) (xy 79.03973 -300.831143)
			(xy 79.087949 -300.821299) (xy 79.137124 -300.819318) (xy 79.185979 -300.82525) (xy 79.23325 -300.838942)
			(xy 79.277712 -300.86004) (xy 79.318215 -300.887996) (xy 79.353708 -300.922088) (xy 79.383273 -300.961432)
			(xy 79.406144 -301.005009) (xy 79.421728 -301.05169) (xy 79.429623 -301.100267) (xy 79.430118 -301.124874)
			(xy 79.768966 -301.124874) (xy 79.772926 -301.07582) (xy 79.784703 -301.028036) (xy 79.803994 -300.98276)
			(xy 79.830297 -300.941164) (xy 79.862932 -300.904327) (xy 79.901053 -300.873202) (xy 79.943674 -300.848595)
			(xy 79.98969 -300.831143) (xy 80.037909 -300.821299) (xy 80.087084 -300.819318) (xy 80.135939 -300.82525)
			(xy 80.18321 -300.838942) (xy 80.227672 -300.86004) (xy 80.268175 -300.887996) (xy 80.303668 -300.922088)
			(xy 80.333233 -300.961432) (xy 80.356104 -301.005009) (xy 80.371688 -301.05169) (xy 80.379583 -301.100267)
			(xy 80.380078 -301.124874) (xy 80.71918 -301.124874) (xy 80.72314 -301.07582) (xy 80.734917 -301.028036)
			(xy 80.754208 -300.98276) (xy 80.780511 -300.941164) (xy 80.813146 -300.904327) (xy 80.851267 -300.873202)
			(xy 80.893888 -300.848595) (xy 80.939904 -300.831143) (xy 80.988123 -300.821299) (xy 81.037298 -300.819318)
			(xy 81.086153 -300.82525) (xy 81.133424 -300.838942) (xy 81.177886 -300.86004) (xy 81.218389 -300.887996)
			(xy 81.253882 -300.922088) (xy 81.283447 -300.961432) (xy 81.306318 -301.005009) (xy 81.321902 -301.05169)
			(xy 81.329797 -301.100267) (xy 81.330292 -301.124874) (xy 81.66914 -301.124874) (xy 81.6731 -301.07582)
			(xy 81.684877 -301.028036) (xy 81.704168 -300.98276) (xy 81.730471 -300.941164) (xy 81.763106 -300.904327)
			(xy 81.801227 -300.873202) (xy 81.843848 -300.848595) (xy 81.889864 -300.831143) (xy 81.938083 -300.821299)
			(xy 81.987258 -300.819318) (xy 82.036113 -300.82525) (xy 82.083384 -300.838942) (xy 82.127846 -300.86004)
			(xy 82.168349 -300.887996) (xy 82.203842 -300.922088) (xy 82.233407 -300.961432) (xy 82.256278 -301.005009)
			(xy 82.271862 -301.05169) (xy 82.279757 -301.100267) (xy 82.280252 -301.124874) (xy 82.6191 -301.124874)
			(xy 82.62306 -301.07582) (xy 82.634837 -301.028036) (xy 82.654128 -300.98276) (xy 82.680431 -300.941164)
			(xy 82.713066 -300.904327) (xy 82.751187 -300.873202) (xy 82.793808 -300.848595) (xy 82.839824 -300.831143)
			(xy 82.888043 -300.821299) (xy 82.937218 -300.819318) (xy 82.986073 -300.82525) (xy 83.033344 -300.838942)
			(xy 83.077806 -300.86004) (xy 83.118309 -300.887996) (xy 83.153802 -300.922088) (xy 83.183367 -300.961432)
			(xy 83.206238 -301.005009) (xy 83.221822 -301.05169) (xy 83.229717 -301.100267) (xy 83.230212 -301.124874)
			(xy 83.229717 -301.149481) (xy 83.221822 -301.198058) (xy 83.206238 -301.244739) (xy 83.183367 -301.288316)
			(xy 83.153802 -301.32766) (xy 83.118309 -301.361752) (xy 83.077806 -301.389708) (xy 83.033344 -301.410806)
			(xy 82.986073 -301.424498) (xy 82.937218 -301.43043) (xy 82.888043 -301.428449) (xy 82.839824 -301.418605)
			(xy 82.793808 -301.401153) (xy 82.751187 -301.376546) (xy 82.713066 -301.345421) (xy 82.680431 -301.308584)
			(xy 82.654128 -301.266988) (xy 82.634837 -301.221712) (xy 82.62306 -301.173928) (xy 82.6191 -301.124874)
			(xy 82.280252 -301.124874) (xy 82.279757 -301.149481) (xy 82.271862 -301.198058) (xy 82.256278 -301.244739)
			(xy 82.233407 -301.288316) (xy 82.203842 -301.32766) (xy 82.168349 -301.361752) (xy 82.127846 -301.389708)
			(xy 82.083384 -301.410806) (xy 82.036113 -301.424498) (xy 81.987258 -301.43043) (xy 81.938083 -301.428449)
			(xy 81.889864 -301.418605) (xy 81.843848 -301.401153) (xy 81.801227 -301.376546) (xy 81.763106 -301.345421)
			(xy 81.730471 -301.308584) (xy 81.704168 -301.266988) (xy 81.684877 -301.221712) (xy 81.6731 -301.173928)
			(xy 81.66914 -301.124874) (xy 81.330292 -301.124874) (xy 81.329797 -301.149481) (xy 81.321902 -301.198058)
			(xy 81.306318 -301.244739) (xy 81.283447 -301.288316) (xy 81.253882 -301.32766) (xy 81.218389 -301.361752)
			(xy 81.177886 -301.389708) (xy 81.133424 -301.410806) (xy 81.086153 -301.424498) (xy 81.037298 -301.43043)
			(xy 80.988123 -301.428449) (xy 80.939904 -301.418605) (xy 80.893888 -301.401153) (xy 80.851267 -301.376546)
			(xy 80.813146 -301.345421) (xy 80.780511 -301.308584) (xy 80.754208 -301.266988) (xy 80.734917 -301.221712)
			(xy 80.72314 -301.173928) (xy 80.71918 -301.124874) (xy 80.380078 -301.124874) (xy 80.379583 -301.149481)
			(xy 80.371688 -301.198058) (xy 80.356104 -301.244739) (xy 80.333233 -301.288316) (xy 80.303668 -301.32766)
			(xy 80.268175 -301.361752) (xy 80.227672 -301.389708) (xy 80.18321 -301.410806) (xy 80.135939 -301.424498)
			(xy 80.087084 -301.43043) (xy 80.037909 -301.428449) (xy 79.98969 -301.418605) (xy 79.943674 -301.401153)
			(xy 79.901053 -301.376546) (xy 79.862932 -301.345421) (xy 79.830297 -301.308584) (xy 79.803994 -301.266988)
			(xy 79.784703 -301.221712) (xy 79.772926 -301.173928) (xy 79.768966 -301.124874) (xy 79.430118 -301.124874)
			(xy 79.429623 -301.149481) (xy 79.421728 -301.198058) (xy 79.406144 -301.244739) (xy 79.383273 -301.288316)
			(xy 79.353708 -301.32766) (xy 79.318215 -301.361752) (xy 79.277712 -301.389708) (xy 79.23325 -301.410806)
			(xy 79.185979 -301.424498) (xy 79.137124 -301.43043) (xy 79.087949 -301.428449) (xy 79.03973 -301.418605)
			(xy 78.993714 -301.401153) (xy 78.951093 -301.376546) (xy 78.912972 -301.345421) (xy 78.880337 -301.308584)
			(xy 78.854034 -301.266988) (xy 78.834743 -301.221712) (xy 78.822966 -301.173928) (xy 78.819006 -301.124874)
			(xy 78.480158 -301.124874) (xy 78.479663 -301.149481) (xy 78.471768 -301.198058) (xy 78.456184 -301.244739)
			(xy 78.433313 -301.288316) (xy 78.403748 -301.32766) (xy 78.368255 -301.361752) (xy 78.327752 -301.389708)
			(xy 78.28329 -301.410806) (xy 78.236019 -301.424498) (xy 78.187164 -301.43043) (xy 78.137989 -301.428449)
			(xy 78.08977 -301.418605) (xy 78.043754 -301.401153) (xy 78.001133 -301.376546) (xy 77.963012 -301.345421)
			(xy 77.930377 -301.308584) (xy 77.904074 -301.266988) (xy 77.884783 -301.221712) (xy 77.873006 -301.173928)
			(xy 77.869046 -301.124874) (xy 77.530198 -301.124874) (xy 77.529703 -301.149481) (xy 77.521808 -301.198058)
			(xy 77.506224 -301.244739) (xy 77.483353 -301.288316) (xy 77.453788 -301.32766) (xy 77.418295 -301.361752)
			(xy 77.377792 -301.389708) (xy 77.33333 -301.410806) (xy 77.286059 -301.424498) (xy 77.237204 -301.43043)
			(xy 77.188029 -301.428449) (xy 77.13981 -301.418605) (xy 77.093794 -301.401153) (xy 77.051173 -301.376546)
			(xy 77.013052 -301.345421) (xy 76.980417 -301.308584) (xy 76.954114 -301.266988) (xy 76.934823 -301.221712)
			(xy 76.923046 -301.173928) (xy 76.919086 -301.124874) (xy 76.580143 -301.124874) (xy 76.580593 -301.133169)
			(xy 76.575229 -301.182514) (xy 76.561952 -301.230341) (xy 76.541113 -301.27539) (xy 76.513261 -301.316475)
			(xy 76.479129 -301.352512) (xy 76.439616 -301.382553) (xy 76.395765 -301.405806) (xy 76.348729 -301.421659)
			(xy 76.299748 -301.429694) (xy 76.27493 -301.430182) (xy 76.260747 -301.430002) (xy 76.232507 -301.427332)
			(xy 76.218542 -301.424848) (xy 76.206096 -301.422562) (xy 76.182474 -301.429928) (xy 76.105004 -301.507398)
			(xy 76.097638 -301.53102) (xy 76.099924 -301.543466) (xy 76.102406 -301.557431) (xy 76.105074 -301.585671)
			(xy 76.105258 -301.599854) (xy 76.105076 -301.614037) (xy 76.102408 -301.642277) (xy 76.099924 -301.656242)
			(xy 76.097638 -301.668688) (xy 76.105004 -301.69231) (xy 76.182474 -301.76978) (xy 76.206096 -301.777146)
			(xy 76.218542 -301.77486) (xy 76.232508 -301.772382) (xy 76.260747 -301.769711) (xy 76.27493 -301.769526)
			(xy 76.299747 -301.77001) (xy 76.348727 -301.778045) (xy 76.395762 -301.793897) (xy 76.439613 -301.81715)
			(xy 76.479125 -301.84719) (xy 76.513257 -301.883227) (xy 76.541109 -301.92431) (xy 76.561948 -301.969358)
			(xy 76.575224 -302.017184) (xy 76.580589 -302.066528) (xy 76.580139 -302.074834) (xy 76.919086 -302.074834)
			(xy 76.923046 -302.02578) (xy 76.934823 -301.977996) (xy 76.954114 -301.93272) (xy 76.980417 -301.891124)
			(xy 77.013052 -301.854287) (xy 77.051173 -301.823162) (xy 77.093794 -301.798555) (xy 77.13981 -301.781103)
			(xy 77.188029 -301.771259) (xy 77.237204 -301.769278) (xy 77.286059 -301.77521) (xy 77.33333 -301.788902)
			(xy 77.377792 -301.81) (xy 77.418295 -301.837956) (xy 77.453788 -301.872048) (xy 77.483353 -301.911392)
			(xy 77.506224 -301.954969) (xy 77.521808 -302.00165) (xy 77.529703 -302.050227) (xy 77.530198 -302.074834)
			(xy 77.869046 -302.074834) (xy 77.873006 -302.02578) (xy 77.884783 -301.977996) (xy 77.904074 -301.93272)
			(xy 77.930377 -301.891124) (xy 77.963012 -301.854287) (xy 78.001133 -301.823162) (xy 78.043754 -301.798555)
			(xy 78.08977 -301.781103) (xy 78.137989 -301.771259) (xy 78.187164 -301.769278) (xy 78.236019 -301.77521)
			(xy 78.28329 -301.788902) (xy 78.327752 -301.81) (xy 78.368255 -301.837956) (xy 78.403748 -301.872048)
			(xy 78.433313 -301.911392) (xy 78.456184 -301.954969) (xy 78.471768 -302.00165) (xy 78.479663 -302.050227)
			(xy 78.480158 -302.074834) (xy 78.819006 -302.074834) (xy 78.822966 -302.02578) (xy 78.834743 -301.977996)
			(xy 78.854034 -301.93272) (xy 78.880337 -301.891124) (xy 78.912972 -301.854287) (xy 78.951093 -301.823162)
			(xy 78.993714 -301.798555) (xy 79.03973 -301.781103) (xy 79.087949 -301.771259) (xy 79.137124 -301.769278)
			(xy 79.185979 -301.77521) (xy 79.23325 -301.788902) (xy 79.277712 -301.81) (xy 79.318215 -301.837956)
			(xy 79.353708 -301.872048) (xy 79.383273 -301.911392) (xy 79.406144 -301.954969) (xy 79.421728 -302.00165)
			(xy 79.429623 -302.050227) (xy 79.430118 -302.074834) (xy 79.768966 -302.074834) (xy 79.772926 -302.02578)
			(xy 79.784703 -301.977996) (xy 79.803994 -301.93272) (xy 79.830297 -301.891124) (xy 79.862932 -301.854287)
			(xy 79.901053 -301.823162) (xy 79.943674 -301.798555) (xy 79.98969 -301.781103) (xy 80.037909 -301.771259)
			(xy 80.087084 -301.769278) (xy 80.135939 -301.77521) (xy 80.18321 -301.788902) (xy 80.227672 -301.81)
			(xy 80.268175 -301.837956) (xy 80.303668 -301.872048) (xy 80.333233 -301.911392) (xy 80.356104 -301.954969)
			(xy 80.371688 -302.00165) (xy 80.379583 -302.050227) (xy 80.380078 -302.074834) (xy 80.71918 -302.074834)
			(xy 80.72314 -302.02578) (xy 80.734917 -301.977996) (xy 80.754208 -301.93272) (xy 80.780511 -301.891124)
			(xy 80.813146 -301.854287) (xy 80.851267 -301.823162) (xy 80.893888 -301.798555) (xy 80.939904 -301.781103)
			(xy 80.988123 -301.771259) (xy 81.037298 -301.769278) (xy 81.086153 -301.77521) (xy 81.133424 -301.788902)
			(xy 81.177886 -301.81) (xy 81.218389 -301.837956) (xy 81.253882 -301.872048) (xy 81.283447 -301.911392)
			(xy 81.306318 -301.954969) (xy 81.321902 -302.00165) (xy 81.329797 -302.050227) (xy 81.330292 -302.074834)
			(xy 81.66914 -302.074834) (xy 81.6731 -302.02578) (xy 81.684877 -301.977996) (xy 81.704168 -301.93272)
			(xy 81.730471 -301.891124) (xy 81.763106 -301.854287) (xy 81.801227 -301.823162) (xy 81.843848 -301.798555)
			(xy 81.889864 -301.781103) (xy 81.938083 -301.771259) (xy 81.987258 -301.769278) (xy 82.036113 -301.77521)
			(xy 82.083384 -301.788902) (xy 82.127846 -301.81) (xy 82.168349 -301.837956) (xy 82.203842 -301.872048)
			(xy 82.233407 -301.911392) (xy 82.256278 -301.954969) (xy 82.271862 -302.00165) (xy 82.279757 -302.050227)
			(xy 82.280252 -302.074834) (xy 82.6191 -302.074834) (xy 82.62306 -302.02578) (xy 82.634837 -301.977996)
			(xy 82.654128 -301.93272) (xy 82.680431 -301.891124) (xy 82.713066 -301.854287) (xy 82.751187 -301.823162)
			(xy 82.793808 -301.798555) (xy 82.839824 -301.781103) (xy 82.888043 -301.771259) (xy 82.937218 -301.769278)
			(xy 82.986073 -301.77521) (xy 83.033344 -301.788902) (xy 83.077806 -301.81) (xy 83.114972 -301.835653)
			(xy 84.836443 -301.835653) (xy 84.836443 -301.781145) (xy 84.844201 -301.727191) (xy 84.859558 -301.674891)
			(xy 84.882202 -301.625309) (xy 84.911671 -301.579454) (xy 84.947367 -301.53826) (xy 84.988562 -301.502566)
			(xy 85.034417 -301.473097) (xy 85.084 -301.450454) (xy 85.136301 -301.435099) (xy 85.190254 -301.427342)
			(xy 85.217508 -301.42688) (xy 85.229734 -301.426948) (xy 85.254137 -301.428473) (xy 85.266276 -301.429928)
			(xy 85.278214 -301.431452) (xy 85.300566 -301.423832) (xy 85.374226 -301.34941) (xy 85.381592 -301.327058)
			(xy 85.380068 -301.31512) (xy 85.378309 -301.301918) (xy 85.376401 -301.275351) (xy 85.376258 -301.262034)
			(xy 85.376787 -301.234759) (xy 85.384553 -301.180764) (xy 85.39993 -301.128426) (xy 85.422606 -301.078812)
			(xy 85.452118 -301.032934) (xy 85.487863 -300.991728) (xy 85.529114 -300.956033) (xy 85.575029 -300.926579)
			(xy 85.624671 -300.903964) (xy 85.677028 -300.888652) (xy 85.731032 -300.880954) (xy 85.785582 -300.881026)
			(xy 85.839566 -300.888868) (xy 85.891882 -300.90432) (xy 85.941464 -300.927066) (xy 85.9873 -300.956643)
			(xy 86.028456 -300.992448) (xy 86.064091 -301.033749) (xy 86.069412 -301.04207) (xy 90.317574 -301.04207)
			(xy 90.31806 -301.014819) (xy 90.325816 -300.960871) (xy 90.341171 -300.908576) (xy 90.363813 -300.858999)
			(xy 90.393279 -300.813149) (xy 90.42897 -300.771958) (xy 90.470161 -300.736267) (xy 90.516011 -300.706801)
			(xy 90.565588 -300.684159) (xy 90.617883 -300.668804) (xy 90.671831 -300.661048) (xy 90.726333 -300.661048)
			(xy 90.780281 -300.668804) (xy 90.832576 -300.684159) (xy 90.882153 -300.706801) (xy 90.928003 -300.736267)
			(xy 90.969194 -300.771958) (xy 91.004885 -300.813149) (xy 91.034351 -300.858999) (xy 91.056993 -300.908576)
			(xy 91.072348 -300.960871) (xy 91.080104 -301.014819) (xy 91.08059 -301.04207) (xy 91.08043 -301.050452)
			(xy 92.690948 -301.050452) (xy 92.695019 -300.99483) (xy 92.707145 -300.940393) (xy 92.727068 -300.888302)
			(xy 92.754364 -300.839667) (xy 92.78845 -300.795524) (xy 92.828599 -300.756815) (xy 92.873957 -300.724364)
			(xy 92.923557 -300.698863) (xy 92.976341 -300.680856) (xy 93.031184 -300.670726) (xy 93.086918 -300.668689)
			(xy 93.142355 -300.674789) (xy 93.196312 -300.688895) (xy 93.247641 -300.710707) (xy 93.295247 -300.739761)
			(xy 93.338115 -300.775436) (xy 93.375332 -300.816973) (xy 93.406105 -300.863486) (xy 93.429777 -300.913983)
			(xy 93.445845 -300.96739) (xy 93.453965 -301.022566) (xy 93.454474 -301.050452) (xy 93.453965 -301.078338)
			(xy 93.445845 -301.133514) (xy 93.429777 -301.186921) (xy 93.406105 -301.237418) (xy 93.375332 -301.283931)
			(xy 93.338115 -301.325468) (xy 93.295247 -301.361143) (xy 93.247641 -301.390197) (xy 93.196312 -301.412009)
			(xy 93.142355 -301.426115) (xy 93.086918 -301.432215) (xy 93.031184 -301.430178) (xy 92.976341 -301.420048)
			(xy 92.923557 -301.402041) (xy 92.873957 -301.37654) (xy 92.828599 -301.344089) (xy 92.78845 -301.30538)
			(xy 92.754364 -301.261237) (xy 92.727068 -301.212602) (xy 92.707145 -301.160511) (xy 92.695019 -301.106074)
			(xy 92.690948 -301.050452) (xy 91.08043 -301.050452) (xy 91.080008 -301.072563) (xy 91.070321 -301.132774)
			(xy 91.051188 -301.19068) (xy 91.023096 -301.24481) (xy 91.005406 -301.269654) (xy 90.998548 -301.278798)
			(xy 90.993976 -301.300896) (xy 91.018614 -301.399448) (xy 91.033092 -301.416974) (xy 91.043506 -301.4218)
			(xy 91.067638 -301.433754) (xy 91.112573 -301.463433) (xy 91.15289 -301.499133) (xy 91.18779 -301.540146)
			(xy 91.210938 -301.57674) (xy 91.51315 -301.57674) (xy 91.517221 -301.521118) (xy 91.529347 -301.466681)
			(xy 91.54927 -301.41459) (xy 91.576566 -301.365955) (xy 91.610652 -301.321812) (xy 91.650801 -301.283103)
			(xy 91.696159 -301.250652) (xy 91.745759 -301.225151) (xy 91.798543 -301.207144) (xy 91.853386 -301.197014)
			(xy 91.90912 -301.194977) (xy 91.964557 -301.201077) (xy 92.018514 -301.215183) (xy 92.069843 -301.236995)
			(xy 92.117449 -301.266049) (xy 92.160317 -301.301724) (xy 92.197534 -301.343261) (xy 92.228307 -301.389774)
			(xy 92.251979 -301.440271) (xy 92.268047 -301.493678) (xy 92.276167 -301.548854) (xy 92.276676 -301.57674)
			(xy 92.276167 -301.604626) (xy 92.268047 -301.659802) (xy 92.251979 -301.713209) (xy 92.228307 -301.763706)
			(xy 92.197534 -301.810219) (xy 92.160317 -301.851756) (xy 92.117449 -301.887431) (xy 92.069843 -301.916485)
			(xy 92.018514 -301.938297) (xy 91.964557 -301.952403) (xy 91.90912 -301.958503) (xy 91.853386 -301.956466)
			(xy 91.798543 -301.946336) (xy 91.745759 -301.928329) (xy 91.696159 -301.902828) (xy 91.650801 -301.870377)
			(xy 91.610652 -301.831668) (xy 91.576566 -301.787525) (xy 91.54927 -301.73889) (xy 91.529347 -301.686799)
			(xy 91.517221 -301.632362) (xy 91.51315 -301.57674) (xy 91.210938 -301.57674) (xy 91.216578 -301.585657)
			(xy 91.238683 -301.634763) (xy 91.253667 -301.686488) (xy 91.261232 -301.739806) (xy 91.261692 -301.766732)
			(xy 91.261206 -301.793983) (xy 91.25345 -301.847931) (xy 91.238095 -301.900226) (xy 91.215453 -301.949803)
			(xy 91.185987 -301.995653) (xy 91.150296 -302.036844) (xy 91.109105 -302.072535) (xy 91.063255 -302.102001)
			(xy 91.013678 -302.124643) (xy 90.961383 -302.139998) (xy 90.907435 -302.147754) (xy 90.852933 -302.147754)
			(xy 90.798985 -302.139998) (xy 90.74669 -302.124643) (xy 90.697113 -302.102001) (xy 90.651263 -302.072535)
			(xy 90.610072 -302.036844) (xy 90.574381 -301.995653) (xy 90.544915 -301.949803) (xy 90.522273 -301.900226)
			(xy 90.506918 -301.847931) (xy 90.499162 -301.793983) (xy 90.498676 -301.766732) (xy 90.499265 -301.73624)
			(xy 90.508951 -301.676029) (xy 90.528082 -301.618123) (xy 90.556171 -301.563992) (xy 90.57386 -301.539148)
			(xy 90.580718 -301.530004) (xy 90.58529 -301.507906) (xy 90.560652 -301.409354) (xy 90.546174 -301.391828)
			(xy 90.53576 -301.387002) (xy 90.511621 -301.375062) (xy 90.466688 -301.34538) (xy 90.426371 -301.309676)
			(xy 90.391474 -301.268661) (xy 90.362687 -301.223148) (xy 90.340582 -301.174041) (xy 90.325599 -301.122315)
			(xy 90.318034 -301.068996) (xy 90.317574 -301.04207) (xy 86.069412 -301.04207) (xy 86.093481 -301.079706)
			(xy 86.116024 -301.12938) (xy 86.131262 -301.181758) (xy 86.138884 -301.235774) (xy 86.139274 -301.26305)
			(xy 86.139274 -301.274226) (xy 86.148164 -301.294038) (xy 86.222078 -301.359062) (xy 86.242906 -301.365412)
			(xy 86.253828 -301.364142) (xy 86.26609 -301.362615) (xy 86.290748 -301.360962) (xy 86.303104 -301.36084)
			(xy 86.332328 -301.361372) (xy 86.390089 -301.370301) (xy 86.445814 -301.387933) (xy 86.498197 -301.413857)
			(xy 86.546015 -301.447466) (xy 86.588149 -301.487974) (xy 86.623612 -301.534433) (xy 86.651576 -301.585757)
			(xy 86.662006 -301.613062) (xy 86.666832 -301.626524) (xy 86.68893 -301.644304) (xy 86.806532 -301.660052)
			(xy 86.83244 -301.648876) (xy 86.840822 -301.637192) (xy 86.856173 -301.616072) (xy 86.891738 -301.577846)
			(xy 86.932188 -301.544832) (xy 86.976765 -301.517648) (xy 87.024636 -301.496804) (xy 87.074904 -301.482688)
			(xy 87.126628 -301.475566) (xy 87.152734 -301.47514) (xy 87.179987 -301.475532) (xy 87.233938 -301.483294)
			(xy 87.286235 -301.498654) (xy 87.335814 -301.5213) (xy 87.381666 -301.55077) (xy 87.383789 -301.55261)
			(xy 88.11971 -301.55261) (xy 88.123781 -301.496988) (xy 88.135907 -301.442551) (xy 88.15583 -301.39046)
			(xy 88.183126 -301.341825) (xy 88.217212 -301.297682) (xy 88.257361 -301.258973) (xy 88.302719 -301.226522)
			(xy 88.352319 -301.201021) (xy 88.405103 -301.183014) (xy 88.459946 -301.172884) (xy 88.51568 -301.170847)
			(xy 88.571117 -301.176947) (xy 88.625074 -301.191053) (xy 88.676403 -301.212865) (xy 88.724009 -301.241919)
			(xy 88.766877 -301.277594) (xy 88.804094 -301.319131) (xy 88.834867 -301.365644) (xy 88.858539 -301.416141)
			(xy 88.874607 -301.469548) (xy 88.882727 -301.524724) (xy 88.883236 -301.55261) (xy 88.882727 -301.580496)
			(xy 88.874607 -301.635672) (xy 88.858539 -301.689079) (xy 88.834867 -301.739576) (xy 88.804094 -301.786089)
			(xy 88.766877 -301.827626) (xy 88.724009 -301.863301) (xy 88.676403 -301.892355) (xy 88.625074 -301.914167)
			(xy 88.571117 -301.928273) (xy 88.51568 -301.934373) (xy 88.459946 -301.932336) (xy 88.405103 -301.922206)
			(xy 88.352319 -301.904199) (xy 88.302719 -301.878698) (xy 88.257361 -301.846247) (xy 88.217212 -301.807538)
			(xy 88.183126 -301.763395) (xy 88.15583 -301.71476) (xy 88.135907 -301.662669) (xy 88.123781 -301.608232)
			(xy 88.11971 -301.55261) (xy 87.383789 -301.55261) (xy 87.422858 -301.586466) (xy 87.45855 -301.627661)
			(xy 87.488017 -301.673516) (xy 87.510658 -301.723097) (xy 87.526014 -301.775395) (xy 87.53377 -301.829347)
			(xy 87.53377 -301.883853) (xy 87.526014 -301.937805) (xy 87.510658 -301.990103) (xy 87.488017 -302.039684)
			(xy 87.45855 -302.085539) (xy 87.422858 -302.126734) (xy 87.381666 -302.16243) (xy 87.335814 -302.1919)
			(xy 87.286235 -302.214546) (xy 87.233938 -302.229906) (xy 87.179987 -302.237668) (xy 87.152734 -302.238156)
			(xy 87.123511 -302.237594) (xy 87.065751 -302.228671) (xy 87.010027 -302.211043) (xy 86.957643 -302.185124)
			(xy 86.909825 -302.151519) (xy 86.867691 -302.111015) (xy 86.832227 -302.064559) (xy 86.804262 -302.013238)
			(xy 86.793832 -301.985934) (xy 86.789006 -301.972472) (xy 86.766908 -301.954692) (xy 86.649306 -301.938944)
			(xy 86.623398 -301.95012) (xy 86.615016 -301.961804) (xy 86.599641 -301.982905) (xy 86.56408 -302.021132)
			(xy 86.523634 -302.054148) (xy 86.479061 -302.081334) (xy 86.431194 -302.102181) (xy 86.38093 -302.116301)
			(xy 86.329209 -302.123427) (xy 86.303104 -302.123856) (xy 86.275807 -302.123339) (xy 86.221771 -302.115558)
			(xy 86.169396 -302.100153) (xy 86.119751 -302.07744) (xy 86.073851 -302.047883) (xy 86.032633 -302.012084)
			(xy 85.996939 -301.970776) (xy 85.967498 -301.924801) (xy 85.94491 -301.875099) (xy 85.929638 -301.822686)
			(xy 85.921993 -301.76863) (xy 85.921596 -301.741332) (xy 85.921596 -301.730156) (xy 85.912706 -301.710344)
			(xy 85.838792 -301.64532) (xy 85.817964 -301.63897) (xy 85.807042 -301.64024) (xy 85.79478 -301.64177)
			(xy 85.770122 -301.643421) (xy 85.757766 -301.643542) (xy 85.74554 -301.643474) (xy 85.721137 -301.641947)
			(xy 85.708998 -301.640494) (xy 85.69706 -301.63897) (xy 85.674708 -301.64659) (xy 85.601048 -301.721012)
			(xy 85.593682 -301.743364) (xy 85.595206 -301.755302) (xy 85.596967 -301.768503) (xy 85.598873 -301.795071)
			(xy 85.599016 -301.808388) (xy 85.598558 -301.835642) (xy 85.590802 -301.889596) (xy 85.575447 -301.941896)
			(xy 85.552805 -301.991479) (xy 85.523337 -302.037335) (xy 85.487642 -302.07853) (xy 85.446449 -302.114226)
			(xy 85.400594 -302.143697) (xy 85.351012 -302.166341) (xy 85.298713 -302.181699) (xy 85.244759 -302.189457)
			(xy 85.190251 -302.189457) (xy 85.136298 -302.181701) (xy 85.083998 -302.166345) (xy 85.034415 -302.143702)
			(xy 84.98856 -302.114233) (xy 84.947365 -302.078538) (xy 84.91167 -302.037343) (xy 84.8822 -301.991488)
			(xy 84.859557 -301.941906) (xy 84.8442 -301.889606) (xy 84.836443 -301.835653) (xy 83.114972 -301.835653)
			(xy 83.118309 -301.837956) (xy 83.153802 -301.872048) (xy 83.183367 -301.911392) (xy 83.206238 -301.954969)
			(xy 83.221822 -302.00165) (xy 83.229717 -302.050227) (xy 83.230212 -302.074834) (xy 83.229717 -302.099441)
			(xy 83.221822 -302.148018) (xy 83.206238 -302.194699) (xy 83.183367 -302.238276) (xy 83.153802 -302.27762)
			(xy 83.118309 -302.311712) (xy 83.077806 -302.339668) (xy 83.033344 -302.360766) (xy 82.986073 -302.374458)
			(xy 82.937218 -302.38039) (xy 82.888043 -302.378409) (xy 82.839824 -302.368565) (xy 82.793808 -302.351113)
			(xy 82.751187 -302.326506) (xy 82.713066 -302.295381) (xy 82.680431 -302.258544) (xy 82.654128 -302.216948)
			(xy 82.634837 -302.171672) (xy 82.62306 -302.123888) (xy 82.6191 -302.074834) (xy 82.280252 -302.074834)
			(xy 82.279757 -302.099441) (xy 82.271862 -302.148018) (xy 82.256278 -302.194699) (xy 82.233407 -302.238276)
			(xy 82.203842 -302.27762) (xy 82.168349 -302.311712) (xy 82.127846 -302.339668) (xy 82.083384 -302.360766)
			(xy 82.036113 -302.374458) (xy 81.987258 -302.38039) (xy 81.938083 -302.378409) (xy 81.889864 -302.368565)
			(xy 81.843848 -302.351113) (xy 81.801227 -302.326506) (xy 81.763106 -302.295381) (xy 81.730471 -302.258544)
			(xy 81.704168 -302.216948) (xy 81.684877 -302.171672) (xy 81.6731 -302.123888) (xy 81.66914 -302.074834)
			(xy 81.330292 -302.074834) (xy 81.329797 -302.099441) (xy 81.321902 -302.148018) (xy 81.306318 -302.194699)
			(xy 81.283447 -302.238276) (xy 81.253882 -302.27762) (xy 81.218389 -302.311712) (xy 81.177886 -302.339668)
			(xy 81.133424 -302.360766) (xy 81.086153 -302.374458) (xy 81.037298 -302.38039) (xy 80.988123 -302.378409)
			(xy 80.939904 -302.368565) (xy 80.893888 -302.351113) (xy 80.851267 -302.326506) (xy 80.813146 -302.295381)
			(xy 80.780511 -302.258544) (xy 80.754208 -302.216948) (xy 80.734917 -302.171672) (xy 80.72314 -302.123888)
			(xy 80.71918 -302.074834) (xy 80.380078 -302.074834) (xy 80.379583 -302.099441) (xy 80.371688 -302.148018)
			(xy 80.356104 -302.194699) (xy 80.333233 -302.238276) (xy 80.303668 -302.27762) (xy 80.268175 -302.311712)
			(xy 80.227672 -302.339668) (xy 80.18321 -302.360766) (xy 80.135939 -302.374458) (xy 80.087084 -302.38039)
			(xy 80.037909 -302.378409) (xy 79.98969 -302.368565) (xy 79.943674 -302.351113) (xy 79.901053 -302.326506)
			(xy 79.862932 -302.295381) (xy 79.830297 -302.258544) (xy 79.803994 -302.216948) (xy 79.784703 -302.171672)
			(xy 79.772926 -302.123888) (xy 79.768966 -302.074834) (xy 79.430118 -302.074834) (xy 79.429623 -302.099441)
			(xy 79.421728 -302.148018) (xy 79.406144 -302.194699) (xy 79.383273 -302.238276) (xy 79.353708 -302.27762)
			(xy 79.318215 -302.311712) (xy 79.277712 -302.339668) (xy 79.23325 -302.360766) (xy 79.185979 -302.374458)
			(xy 79.137124 -302.38039) (xy 79.087949 -302.378409) (xy 79.03973 -302.368565) (xy 78.993714 -302.351113)
			(xy 78.951093 -302.326506) (xy 78.912972 -302.295381) (xy 78.880337 -302.258544) (xy 78.854034 -302.216948)
			(xy 78.834743 -302.171672) (xy 78.822966 -302.123888) (xy 78.819006 -302.074834) (xy 78.480158 -302.074834)
			(xy 78.479663 -302.099441) (xy 78.471768 -302.148018) (xy 78.456184 -302.194699) (xy 78.433313 -302.238276)
			(xy 78.403748 -302.27762) (xy 78.368255 -302.311712) (xy 78.327752 -302.339668) (xy 78.28329 -302.360766)
			(xy 78.236019 -302.374458) (xy 78.187164 -302.38039) (xy 78.137989 -302.378409) (xy 78.08977 -302.368565)
			(xy 78.043754 -302.351113) (xy 78.001133 -302.326506) (xy 77.963012 -302.295381) (xy 77.930377 -302.258544)
			(xy 77.904074 -302.216948) (xy 77.884783 -302.171672) (xy 77.873006 -302.123888) (xy 77.869046 -302.074834)
			(xy 77.530198 -302.074834) (xy 77.529703 -302.099441) (xy 77.521808 -302.148018) (xy 77.506224 -302.194699)
			(xy 77.483353 -302.238276) (xy 77.453788 -302.27762) (xy 77.418295 -302.311712) (xy 77.377792 -302.339668)
			(xy 77.33333 -302.360766) (xy 77.286059 -302.374458) (xy 77.237204 -302.38039) (xy 77.188029 -302.378409)
			(xy 77.13981 -302.368565) (xy 77.093794 -302.351113) (xy 77.051173 -302.326506) (xy 77.013052 -302.295381)
			(xy 76.980417 -302.258544) (xy 76.954114 -302.216948) (xy 76.934823 -302.171672) (xy 76.923046 -302.123888)
			(xy 76.919086 -302.074834) (xy 76.580139 -302.074834) (xy 76.577901 -302.11609) (xy 76.56723 -302.164564)
			(xy 76.548858 -302.210673) (xy 76.523268 -302.253203) (xy 76.491135 -302.291033) (xy 76.453306 -302.323166)
			(xy 76.410777 -302.348756) (xy 76.364668 -302.367129) (xy 76.316194 -302.3778) (xy 76.266632 -302.380489)
			(xy 76.217288 -302.375125) (xy 76.169462 -302.361849) (xy 76.124414 -302.341011) (xy 76.08333 -302.313159)
			(xy 76.047293 -302.279028) (xy 76.017252 -302.239517) (xy 75.993999 -302.195666) (xy 75.978146 -302.148631)
			(xy 75.97011 -302.099651) (xy 75.969622 -302.074834) (xy 75.969803 -302.060651) (xy 75.972472 -302.032411)
			(xy 75.974956 -302.018446) (xy 75.977242 -302.006) (xy 75.969876 -301.982378) (xy 75.892406 -301.904908)
			(xy 75.868784 -301.897542) (xy 75.856338 -301.899828) (xy 75.842373 -301.902309) (xy 75.814133 -301.904978)
			(xy 75.79995 -301.905162) (xy 75.774694 -301.904729) (xy 75.724871 -301.896407) (xy 75.677097 -301.88)
			(xy 75.632674 -301.855953) (xy 75.592815 -301.824924) (xy 75.558607 -301.787757) (xy 75.530981 -301.745468)
			(xy 75.510692 -301.699208) (xy 75.498293 -301.650241) (xy 75.494122 -301.5999) (xy 59.850782 -301.5999)
			(xy 59.850782 -301.64278) (xy 59.851198 -301.652805) (xy 59.858864 -301.671332) (xy 59.873036 -301.685515)
			(xy 59.891557 -301.693195) (xy 59.901582 -301.69358) (xy 60.124848 -301.69358) (xy 60.134754 -301.69358)
			(xy 60.161386 -301.694747) (xy 60.213959 -301.703553) (xy 60.264796 -301.71959) (xy 60.312906 -301.742545)
			(xy 60.357354 -301.771972) (xy 60.397274 -301.807298) (xy 60.43189 -301.847836) (xy 60.460527 -301.892797)
			(xy 60.482629 -301.941305) (xy 60.497766 -301.992417) (xy 60.505642 -302.045138) (xy 60.506356 -302.071786)
			(xy 60.506102 -302.073056) (xy 60.506102 -302.074326) (xy 60.506095 -302.074834) (xy 60.769004 -302.074834)
			(xy 60.772964 -302.02578) (xy 60.784741 -301.977996) (xy 60.804032 -301.93272) (xy 60.830335 -301.891124)
			(xy 60.86297 -301.854287) (xy 60.901091 -301.823162) (xy 60.943712 -301.798555) (xy 60.989728 -301.781103)
			(xy 61.037947 -301.771259) (xy 61.087122 -301.769278) (xy 61.135977 -301.77521) (xy 61.183248 -301.788902)
			(xy 61.22771 -301.81) (xy 61.268213 -301.837956) (xy 61.303706 -301.872048) (xy 61.333271 -301.911392)
			(xy 61.356142 -301.954969) (xy 61.371726 -302.00165) (xy 61.379621 -302.050227) (xy 61.380116 -302.074834)
			(xy 61.718964 -302.074834) (xy 61.722924 -302.02578) (xy 61.734701 -301.977996) (xy 61.753992 -301.93272)
			(xy 61.780295 -301.891124) (xy 61.81293 -301.854287) (xy 61.851051 -301.823162) (xy 61.893672 -301.798555)
			(xy 61.939688 -301.781103) (xy 61.987907 -301.771259) (xy 62.037082 -301.769278) (xy 62.085937 -301.77521)
			(xy 62.133208 -301.788902) (xy 62.17767 -301.81) (xy 62.218173 -301.837956) (xy 62.253666 -301.872048)
			(xy 62.283231 -301.911392) (xy 62.306102 -301.954969) (xy 62.321686 -302.00165) (xy 62.329581 -302.050227)
			(xy 62.330076 -302.074834) (xy 62.669178 -302.074834) (xy 62.673138 -302.02578) (xy 62.684915 -301.977996)
			(xy 62.704206 -301.93272) (xy 62.730509 -301.891124) (xy 62.763144 -301.854287) (xy 62.801265 -301.823162)
			(xy 62.843886 -301.798555) (xy 62.889902 -301.781103) (xy 62.938121 -301.771259) (xy 62.987296 -301.769278)
			(xy 63.036151 -301.77521) (xy 63.083422 -301.788902) (xy 63.127884 -301.81) (xy 63.168387 -301.837956)
			(xy 63.20388 -301.872048) (xy 63.233445 -301.911392) (xy 63.256316 -301.954969) (xy 63.2719 -302.00165)
			(xy 63.279795 -302.050227) (xy 63.28029 -302.074834) (xy 63.619138 -302.074834) (xy 63.623098 -302.02578)
			(xy 63.634875 -301.977996) (xy 63.654166 -301.93272) (xy 63.680469 -301.891124) (xy 63.713104 -301.854287)
			(xy 63.751225 -301.823162) (xy 63.793846 -301.798555) (xy 63.839862 -301.781103) (xy 63.888081 -301.771259)
			(xy 63.937256 -301.769278) (xy 63.986111 -301.77521) (xy 64.033382 -301.788902) (xy 64.077844 -301.81)
			(xy 64.118347 -301.837956) (xy 64.15384 -301.872048) (xy 64.183405 -301.911392) (xy 64.206276 -301.954969)
			(xy 64.22186 -302.00165) (xy 64.229755 -302.050227) (xy 64.23025 -302.074834) (xy 64.569098 -302.074834)
			(xy 64.573058 -302.02578) (xy 64.584835 -301.977996) (xy 64.604126 -301.93272) (xy 64.630429 -301.891124)
			(xy 64.663064 -301.854287) (xy 64.701185 -301.823162) (xy 64.743806 -301.798555) (xy 64.789822 -301.781103)
			(xy 64.838041 -301.771259) (xy 64.887216 -301.769278) (xy 64.936071 -301.77521) (xy 64.983342 -301.788902)
			(xy 65.027804 -301.81) (xy 65.068307 -301.837956) (xy 65.1038 -301.872048) (xy 65.133365 -301.911392)
			(xy 65.156236 -301.954969) (xy 65.17182 -302.00165) (xy 65.179715 -302.050227) (xy 65.18021 -302.074834)
			(xy 65.519058 -302.074834) (xy 65.523018 -302.02578) (xy 65.534795 -301.977996) (xy 65.554086 -301.93272)
			(xy 65.580389 -301.891124) (xy 65.613024 -301.854287) (xy 65.651145 -301.823162) (xy 65.693766 -301.798555)
			(xy 65.739782 -301.781103) (xy 65.788001 -301.771259) (xy 65.837176 -301.769278) (xy 65.886031 -301.77521)
			(xy 65.933302 -301.788902) (xy 65.977764 -301.81) (xy 66.018267 -301.837956) (xy 66.05376 -301.872048)
			(xy 66.083325 -301.911392) (xy 66.106196 -301.954969) (xy 66.12178 -302.00165) (xy 66.129675 -302.050227)
			(xy 66.13017 -302.074834) (xy 66.469018 -302.074834) (xy 66.472978 -302.02578) (xy 66.484755 -301.977996)
			(xy 66.504046 -301.93272) (xy 66.530349 -301.891124) (xy 66.562984 -301.854287) (xy 66.601105 -301.823162)
			(xy 66.643726 -301.798555) (xy 66.689742 -301.781103) (xy 66.737961 -301.771259) (xy 66.787136 -301.769278)
			(xy 66.835991 -301.77521) (xy 66.883262 -301.788902) (xy 66.927724 -301.81) (xy 66.968227 -301.837956)
			(xy 67.00372 -301.872048) (xy 67.033285 -301.911392) (xy 67.056156 -301.954969) (xy 67.07174 -302.00165)
			(xy 67.079635 -302.050227) (xy 67.08013 -302.074834) (xy 67.418978 -302.074834) (xy 67.422938 -302.02578)
			(xy 67.434715 -301.977996) (xy 67.454006 -301.93272) (xy 67.480309 -301.891124) (xy 67.512944 -301.854287)
			(xy 67.551065 -301.823162) (xy 67.593686 -301.798555) (xy 67.639702 -301.781103) (xy 67.687921 -301.771259)
			(xy 67.737096 -301.769278) (xy 67.785951 -301.77521) (xy 67.833222 -301.788902) (xy 67.877684 -301.81)
			(xy 67.918187 -301.837956) (xy 67.95368 -301.872048) (xy 67.983245 -301.911392) (xy 68.006116 -301.954969)
			(xy 68.0217 -302.00165) (xy 68.029595 -302.050227) (xy 68.03009 -302.074834) (xy 68.368938 -302.074834)
			(xy 68.372898 -302.02578) (xy 68.384675 -301.977996) (xy 68.403966 -301.93272) (xy 68.430269 -301.891124)
			(xy 68.462904 -301.854287) (xy 68.501025 -301.823162) (xy 68.543646 -301.798555) (xy 68.589662 -301.781103)
			(xy 68.637881 -301.771259) (xy 68.687056 -301.769278) (xy 68.735911 -301.77521) (xy 68.783182 -301.788902)
			(xy 68.827644 -301.81) (xy 68.868147 -301.837956) (xy 68.90364 -301.872048) (xy 68.933205 -301.911392)
			(xy 68.956076 -301.954969) (xy 68.97166 -302.00165) (xy 68.979555 -302.050227) (xy 68.98005 -302.074834)
			(xy 69.319152 -302.074834) (xy 69.323112 -302.02578) (xy 69.334889 -301.977996) (xy 69.35418 -301.93272)
			(xy 69.380483 -301.891124) (xy 69.413118 -301.854287) (xy 69.451239 -301.823162) (xy 69.49386 -301.798555)
			(xy 69.539876 -301.781103) (xy 69.588095 -301.771259) (xy 69.63727 -301.769278) (xy 69.686125 -301.77521)
			(xy 69.733396 -301.788902) (xy 69.777858 -301.81) (xy 69.818361 -301.837956) (xy 69.853854 -301.872048)
			(xy 69.883419 -301.911392) (xy 69.90629 -301.954969) (xy 69.921874 -302.00165) (xy 69.929769 -302.050227)
			(xy 69.930264 -302.074834) (xy 70.269112 -302.074834) (xy 70.273072 -302.02578) (xy 70.284849 -301.977996)
			(xy 70.30414 -301.93272) (xy 70.330443 -301.891124) (xy 70.363078 -301.854287) (xy 70.401199 -301.823162)
			(xy 70.44382 -301.798555) (xy 70.489836 -301.781103) (xy 70.538055 -301.771259) (xy 70.58723 -301.769278)
			(xy 70.636085 -301.77521) (xy 70.683356 -301.788902) (xy 70.727818 -301.81) (xy 70.768321 -301.837956)
			(xy 70.803814 -301.872048) (xy 70.833379 -301.911392) (xy 70.85625 -301.954969) (xy 70.871834 -302.00165)
			(xy 70.879729 -302.050227) (xy 70.880224 -302.074834) (xy 71.219072 -302.074834) (xy 71.223032 -302.02578)
			(xy 71.234809 -301.977996) (xy 71.2541 -301.93272) (xy 71.280403 -301.891124) (xy 71.313038 -301.854287)
			(xy 71.351159 -301.823162) (xy 71.39378 -301.798555) (xy 71.439796 -301.781103) (xy 71.488015 -301.771259)
			(xy 71.53719 -301.769278) (xy 71.586045 -301.77521) (xy 71.633316 -301.788902) (xy 71.677778 -301.81)
			(xy 71.718281 -301.837956) (xy 71.753774 -301.872048) (xy 71.783339 -301.911392) (xy 71.80621 -301.954969)
			(xy 71.821794 -302.00165) (xy 71.829689 -302.050227) (xy 71.830184 -302.074834) (xy 72.169032 -302.074834)
			(xy 72.172992 -302.02578) (xy 72.184769 -301.977996) (xy 72.20406 -301.93272) (xy 72.230363 -301.891124)
			(xy 72.262998 -301.854287) (xy 72.301119 -301.823162) (xy 72.34374 -301.798555) (xy 72.389756 -301.781103)
			(xy 72.437975 -301.771259) (xy 72.48715 -301.769278) (xy 72.536005 -301.77521) (xy 72.583276 -301.788902)
			(xy 72.627738 -301.81) (xy 72.668241 -301.837956) (xy 72.703734 -301.872048) (xy 72.733299 -301.911392)
			(xy 72.75617 -301.954969) (xy 72.771754 -302.00165) (xy 72.779649 -302.050227) (xy 72.780144 -302.074834)
			(xy 72.779978 -302.083068) (xy 73.119085 -302.083068) (xy 73.121775 -302.033499) (xy 73.132449 -301.985018)
			(xy 73.150826 -301.938902) (xy 73.176421 -301.896368) (xy 73.208561 -301.858534) (xy 73.246398 -301.826399)
			(xy 73.288936 -301.800809) (xy 73.335054 -301.782438) (xy 73.383536 -301.77177) (xy 73.433106 -301.769086)
			(xy 73.482456 -301.774457) (xy 73.530288 -301.787742) (xy 73.57534 -301.80859) (xy 73.616426 -301.836452)
			(xy 73.652462 -301.870594) (xy 73.682501 -301.910117) (xy 73.705749 -301.953979) (xy 73.721595 -302.001024)
			(xy 73.729621 -302.050013) (xy 73.730104 -302.074834) (xy 73.729932 -302.089017) (xy 73.727257 -302.117257)
			(xy 73.72477 -302.131222) (xy 73.722484 -302.143668) (xy 73.72985 -302.16729) (xy 73.80732 -302.24476)
			(xy 73.830942 -302.252126) (xy 73.843388 -302.24984) (xy 73.857355 -302.247369) (xy 73.885594 -302.244694)
			(xy 73.899776 -302.244506) (xy 73.913959 -302.244686) (xy 73.942199 -302.247356) (xy 73.956164 -302.24984)
			(xy 73.96861 -302.252126) (xy 73.992232 -302.24476) (xy 74.069702 -302.16729) (xy 74.077068 -302.143668)
			(xy 74.074782 -302.131222) (xy 74.072299 -302.117257) (xy 74.069631 -302.089017) (xy 74.069448 -302.074834)
			(xy 74.069941 -302.050009) (xy 74.077969 -302.001012) (xy 74.093818 -301.95396) (xy 74.11707 -301.910092)
			(xy 74.147114 -301.870563) (xy 74.183158 -301.836417) (xy 74.224251 -301.808551) (xy 74.269311 -301.787702)
			(xy 74.31715 -301.774417) (xy 74.366509 -301.769047) (xy 74.416086 -301.771734) (xy 74.464575 -301.782407)
			(xy 74.510699 -301.800784) (xy 74.553242 -301.826381) (xy 74.591083 -301.858524) (xy 74.623225 -301.896366)
			(xy 74.648821 -301.93891) (xy 74.667196 -301.985034) (xy 74.677867 -302.033524) (xy 74.680552 -302.083101)
			(xy 74.675181 -302.13246) (xy 74.661895 -302.180299) (xy 74.641044 -302.225358) (xy 74.613177 -302.26645)
			(xy 74.579029 -302.302492) (xy 74.5395 -302.332535) (xy 74.495631 -302.355786) (xy 74.448578 -302.371634)
			(xy 74.399581 -302.379659) (xy 74.374756 -302.380142) (xy 74.360573 -302.379957) (xy 74.332333 -302.37729)
			(xy 74.318368 -302.374808) (xy 74.305922 -302.372522) (xy 74.2823 -302.379888) (xy 74.20483 -302.457358)
			(xy 74.197464 -302.48098) (xy 74.19975 -302.493426) (xy 74.202226 -302.507392) (xy 74.204898 -302.535632)
			(xy 74.205084 -302.549814) (xy 74.204562 -302.575069) (xy 74.196249 -302.624891) (xy 74.179848 -302.672665)
			(xy 74.155807 -302.717088) (xy 74.124783 -302.756948) (xy 74.087621 -302.791158) (xy 74.045335 -302.818784)
			(xy 73.999079 -302.839074) (xy 73.950114 -302.851474) (xy 73.899776 -302.855645) (xy 73.849438 -302.851474)
			(xy 73.800473 -302.839074) (xy 73.754217 -302.818784) (xy 73.711931 -302.791158) (xy 73.674769 -302.756948)
			(xy 73.643745 -302.717088) (xy 73.619704 -302.672665) (xy 73.603303 -302.624891) (xy 73.59499 -302.575069)
			(xy 73.594468 -302.549814) (xy 73.594647 -302.535631) (xy 73.597318 -302.507391) (xy 73.599802 -302.493426)
			(xy 73.602088 -302.48098) (xy 73.594722 -302.457358) (xy 73.517252 -302.379888) (xy 73.49363 -302.372522)
			(xy 73.481184 -302.374808) (xy 73.467218 -302.377283) (xy 73.438978 -302.379956) (xy 73.424796 -302.380142)
			(xy 73.399975 -302.379618) (xy 73.350987 -302.371586) (xy 73.303944 -302.355734) (xy 73.260085 -302.33248)
			(xy 73.220566 -302.302437) (xy 73.186428 -302.266396) (xy 73.158571 -302.225307) (xy 73.137729 -302.180252)
			(xy 73.12445 -302.132419) (xy 73.119085 -302.083068) (xy 72.779978 -302.083068) (xy 72.779649 -302.099441)
			(xy 72.771754 -302.148018) (xy 72.75617 -302.194699) (xy 72.733299 -302.238276) (xy 72.703734 -302.27762)
			(xy 72.668241 -302.311712) (xy 72.627738 -302.339668) (xy 72.583276 -302.360766) (xy 72.536005 -302.374458)
			(xy 72.48715 -302.38039) (xy 72.437975 -302.378409) (xy 72.389756 -302.368565) (xy 72.34374 -302.351113)
			(xy 72.301119 -302.326506) (xy 72.262998 -302.295381) (xy 72.230363 -302.258544) (xy 72.20406 -302.216948)
			(xy 72.184769 -302.171672) (xy 72.172992 -302.123888) (xy 72.169032 -302.074834) (xy 71.830184 -302.074834)
			(xy 71.829689 -302.099441) (xy 71.821794 -302.148018) (xy 71.80621 -302.194699) (xy 71.783339 -302.238276)
			(xy 71.753774 -302.27762) (xy 71.718281 -302.311712) (xy 71.677778 -302.339668) (xy 71.633316 -302.360766)
			(xy 71.586045 -302.374458) (xy 71.53719 -302.38039) (xy 71.488015 -302.378409) (xy 71.439796 -302.368565)
			(xy 71.39378 -302.351113) (xy 71.351159 -302.326506) (xy 71.313038 -302.295381) (xy 71.280403 -302.258544)
			(xy 71.2541 -302.216948) (xy 71.234809 -302.171672) (xy 71.223032 -302.123888) (xy 71.219072 -302.074834)
			(xy 70.880224 -302.074834) (xy 70.879729 -302.099441) (xy 70.871834 -302.148018) (xy 70.85625 -302.194699)
			(xy 70.833379 -302.238276) (xy 70.803814 -302.27762) (xy 70.768321 -302.311712) (xy 70.727818 -302.339668)
			(xy 70.683356 -302.360766) (xy 70.636085 -302.374458) (xy 70.58723 -302.38039) (xy 70.538055 -302.378409)
			(xy 70.489836 -302.368565) (xy 70.44382 -302.351113) (xy 70.401199 -302.326506) (xy 70.363078 -302.295381)
			(xy 70.330443 -302.258544) (xy 70.30414 -302.216948) (xy 70.284849 -302.171672) (xy 70.273072 -302.123888)
			(xy 70.269112 -302.074834) (xy 69.930264 -302.074834) (xy 69.929769 -302.099441) (xy 69.921874 -302.148018)
			(xy 69.90629 -302.194699) (xy 69.883419 -302.238276) (xy 69.853854 -302.27762) (xy 69.818361 -302.311712)
			(xy 69.777858 -302.339668) (xy 69.733396 -302.360766) (xy 69.686125 -302.374458) (xy 69.63727 -302.38039)
			(xy 69.588095 -302.378409) (xy 69.539876 -302.368565) (xy 69.49386 -302.351113) (xy 69.451239 -302.326506)
			(xy 69.413118 -302.295381) (xy 69.380483 -302.258544) (xy 69.35418 -302.216948) (xy 69.334889 -302.171672)
			(xy 69.323112 -302.123888) (xy 69.319152 -302.074834) (xy 68.98005 -302.074834) (xy 68.979555 -302.099441)
			(xy 68.97166 -302.148018) (xy 68.956076 -302.194699) (xy 68.933205 -302.238276) (xy 68.90364 -302.27762)
			(xy 68.868147 -302.311712) (xy 68.827644 -302.339668) (xy 68.783182 -302.360766) (xy 68.735911 -302.374458)
			(xy 68.687056 -302.38039) (xy 68.637881 -302.378409) (xy 68.589662 -302.368565) (xy 68.543646 -302.351113)
			(xy 68.501025 -302.326506) (xy 68.462904 -302.295381) (xy 68.430269 -302.258544) (xy 68.403966 -302.216948)
			(xy 68.384675 -302.171672) (xy 68.372898 -302.123888) (xy 68.368938 -302.074834) (xy 68.03009 -302.074834)
			(xy 68.029595 -302.099441) (xy 68.0217 -302.148018) (xy 68.006116 -302.194699) (xy 67.983245 -302.238276)
			(xy 67.95368 -302.27762) (xy 67.918187 -302.311712) (xy 67.877684 -302.339668) (xy 67.833222 -302.360766)
			(xy 67.785951 -302.374458) (xy 67.737096 -302.38039) (xy 67.687921 -302.378409) (xy 67.639702 -302.368565)
			(xy 67.593686 -302.351113) (xy 67.551065 -302.326506) (xy 67.512944 -302.295381) (xy 67.480309 -302.258544)
			(xy 67.454006 -302.216948) (xy 67.434715 -302.171672) (xy 67.422938 -302.123888) (xy 67.418978 -302.074834)
			(xy 67.08013 -302.074834) (xy 67.079635 -302.099441) (xy 67.07174 -302.148018) (xy 67.056156 -302.194699)
			(xy 67.033285 -302.238276) (xy 67.00372 -302.27762) (xy 66.968227 -302.311712) (xy 66.927724 -302.339668)
			(xy 66.883262 -302.360766) (xy 66.835991 -302.374458) (xy 66.787136 -302.38039) (xy 66.737961 -302.378409)
			(xy 66.689742 -302.368565) (xy 66.643726 -302.351113) (xy 66.601105 -302.326506) (xy 66.562984 -302.295381)
			(xy 66.530349 -302.258544) (xy 66.504046 -302.216948) (xy 66.484755 -302.171672) (xy 66.472978 -302.123888)
			(xy 66.469018 -302.074834) (xy 66.13017 -302.074834) (xy 66.129675 -302.099441) (xy 66.12178 -302.148018)
			(xy 66.106196 -302.194699) (xy 66.083325 -302.238276) (xy 66.05376 -302.27762) (xy 66.018267 -302.311712)
			(xy 65.977764 -302.339668) (xy 65.933302 -302.360766) (xy 65.886031 -302.374458) (xy 65.837176 -302.38039)
			(xy 65.788001 -302.378409) (xy 65.739782 -302.368565) (xy 65.693766 -302.351113) (xy 65.651145 -302.326506)
			(xy 65.613024 -302.295381) (xy 65.580389 -302.258544) (xy 65.554086 -302.216948) (xy 65.534795 -302.171672)
			(xy 65.523018 -302.123888) (xy 65.519058 -302.074834) (xy 65.18021 -302.074834) (xy 65.179715 -302.099441)
			(xy 65.17182 -302.148018) (xy 65.156236 -302.194699) (xy 65.133365 -302.238276) (xy 65.1038 -302.27762)
			(xy 65.068307 -302.311712) (xy 65.027804 -302.339668) (xy 64.983342 -302.360766) (xy 64.936071 -302.374458)
			(xy 64.887216 -302.38039) (xy 64.838041 -302.378409) (xy 64.789822 -302.368565) (xy 64.743806 -302.351113)
			(xy 64.701185 -302.326506) (xy 64.663064 -302.295381) (xy 64.630429 -302.258544) (xy 64.604126 -302.216948)
			(xy 64.584835 -302.171672) (xy 64.573058 -302.123888) (xy 64.569098 -302.074834) (xy 64.23025 -302.074834)
			(xy 64.229755 -302.099441) (xy 64.22186 -302.148018) (xy 64.206276 -302.194699) (xy 64.183405 -302.238276)
			(xy 64.15384 -302.27762) (xy 64.118347 -302.311712) (xy 64.077844 -302.339668) (xy 64.033382 -302.360766)
			(xy 63.986111 -302.374458) (xy 63.937256 -302.38039) (xy 63.888081 -302.378409) (xy 63.839862 -302.368565)
			(xy 63.793846 -302.351113) (xy 63.751225 -302.326506) (xy 63.713104 -302.295381) (xy 63.680469 -302.258544)
			(xy 63.654166 -302.216948) (xy 63.634875 -302.171672) (xy 63.623098 -302.123888) (xy 63.619138 -302.074834)
			(xy 63.28029 -302.074834) (xy 63.279795 -302.099441) (xy 63.2719 -302.148018) (xy 63.256316 -302.194699)
			(xy 63.233445 -302.238276) (xy 63.20388 -302.27762) (xy 63.168387 -302.311712) (xy 63.127884 -302.339668)
			(xy 63.083422 -302.360766) (xy 63.036151 -302.374458) (xy 62.987296 -302.38039) (xy 62.938121 -302.378409)
			(xy 62.889902 -302.368565) (xy 62.843886 -302.351113) (xy 62.801265 -302.326506) (xy 62.763144 -302.295381)
			(xy 62.730509 -302.258544) (xy 62.704206 -302.216948) (xy 62.684915 -302.171672) (xy 62.673138 -302.123888)
			(xy 62.669178 -302.074834) (xy 62.330076 -302.074834) (xy 62.329581 -302.099441) (xy 62.321686 -302.148018)
			(xy 62.306102 -302.194699) (xy 62.283231 -302.238276) (xy 62.253666 -302.27762) (xy 62.218173 -302.311712)
			(xy 62.17767 -302.339668) (xy 62.133208 -302.360766) (xy 62.085937 -302.374458) (xy 62.037082 -302.38039)
			(xy 61.987907 -302.378409) (xy 61.939688 -302.368565) (xy 61.893672 -302.351113) (xy 61.851051 -302.326506)
			(xy 61.81293 -302.295381) (xy 61.780295 -302.258544) (xy 61.753992 -302.216948) (xy 61.734701 -302.171672)
			(xy 61.722924 -302.123888) (xy 61.718964 -302.074834) (xy 61.380116 -302.074834) (xy 61.379621 -302.099441)
			(xy 61.371726 -302.148018) (xy 61.356142 -302.194699) (xy 61.333271 -302.238276) (xy 61.303706 -302.27762)
			(xy 61.268213 -302.311712) (xy 61.22771 -302.339668) (xy 61.183248 -302.360766) (xy 61.135977 -302.374458)
			(xy 61.087122 -302.38039) (xy 61.037947 -302.378409) (xy 60.989728 -302.368565) (xy 60.943712 -302.351113)
			(xy 60.901091 -302.326506) (xy 60.86297 -302.295381) (xy 60.830335 -302.258544) (xy 60.804032 -302.216948)
			(xy 60.784741 -302.171672) (xy 60.772964 -302.123888) (xy 60.769004 -302.074834) (xy 60.506095 -302.074834)
			(xy 60.505722 -302.10058) (xy 60.498628 -302.152604) (xy 60.484454 -302.20316) (xy 60.463468 -302.25129)
			(xy 60.436069 -302.29608) (xy 60.419742 -302.316642) (xy 60.414916 -302.322484) (xy 60.396684 -302.343097)
			(xy 60.35531 -302.379382) (xy 60.309153 -302.409348) (xy 60.28436 -302.42129) (xy 60.284106 -302.421544)
			(xy 60.279788 -302.423322) (xy 60.278518 -302.42383) (xy 60.272676 -302.42637) (xy 60.263278 -302.433736)
			(xy 60.245752 -302.455326) (xy 60.240926 -302.461168) (xy 60.235084 -302.47463) (xy 60.234068 -302.479964)
			(xy 60.22975 -302.500538) (xy 60.228734 -302.510952) (xy 60.228734 -302.568102) (xy 60.22919 -302.577982)
			(xy 60.236622 -302.59629) (xy 60.243212 -302.603662) (xy 60.243466 -302.603916) (xy 60.394596 -302.755046)
			(xy 60.412308 -302.773374) (xy 60.443209 -302.813908) (xy 60.468435 -302.858197) (xy 60.487538 -302.905451)
			(xy 60.500176 -302.954828) (xy 60.503562 -302.98009) (xy 60.504578 -302.988218) (xy 60.506732 -303.015474)
			(xy 60.506292 -303.024794) (xy 60.769004 -303.024794) (xy 60.772964 -302.97574) (xy 60.784741 -302.927956)
			(xy 60.804032 -302.88268) (xy 60.830335 -302.841084) (xy 60.86297 -302.804247) (xy 60.901091 -302.773122)
			(xy 60.943712 -302.748515) (xy 60.989728 -302.731063) (xy 61.037947 -302.721219) (xy 61.087122 -302.719238)
			(xy 61.135977 -302.72517) (xy 61.183248 -302.738862) (xy 61.22771 -302.75996) (xy 61.268213 -302.787916)
			(xy 61.303706 -302.822008) (xy 61.333271 -302.861352) (xy 61.356142 -302.904929) (xy 61.371726 -302.95161)
			(xy 61.379621 -303.000187) (xy 61.380116 -303.024794) (xy 61.718964 -303.024794) (xy 61.722924 -302.97574)
			(xy 61.734701 -302.927956) (xy 61.753992 -302.88268) (xy 61.780295 -302.841084) (xy 61.81293 -302.804247)
			(xy 61.851051 -302.773122) (xy 61.893672 -302.748515) (xy 61.939688 -302.731063) (xy 61.987907 -302.721219)
			(xy 62.037082 -302.719238) (xy 62.085937 -302.72517) (xy 62.133208 -302.738862) (xy 62.17767 -302.75996)
			(xy 62.218173 -302.787916) (xy 62.253666 -302.822008) (xy 62.283231 -302.861352) (xy 62.306102 -302.904929)
			(xy 62.321686 -302.95161) (xy 62.329581 -303.000187) (xy 62.330076 -303.024794) (xy 62.669178 -303.024794)
			(xy 62.673138 -302.97574) (xy 62.684915 -302.927956) (xy 62.704206 -302.88268) (xy 62.730509 -302.841084)
			(xy 62.763144 -302.804247) (xy 62.801265 -302.773122) (xy 62.843886 -302.748515) (xy 62.889902 -302.731063)
			(xy 62.938121 -302.721219) (xy 62.987296 -302.719238) (xy 63.036151 -302.72517) (xy 63.083422 -302.738862)
			(xy 63.127884 -302.75996) (xy 63.168387 -302.787916) (xy 63.20388 -302.822008) (xy 63.233445 -302.861352)
			(xy 63.256316 -302.904929) (xy 63.2719 -302.95161) (xy 63.279795 -303.000187) (xy 63.28029 -303.024794)
			(xy 63.619138 -303.024794) (xy 63.623098 -302.97574) (xy 63.634875 -302.927956) (xy 63.654166 -302.88268)
			(xy 63.680469 -302.841084) (xy 63.713104 -302.804247) (xy 63.751225 -302.773122) (xy 63.793846 -302.748515)
			(xy 63.839862 -302.731063) (xy 63.888081 -302.721219) (xy 63.937256 -302.719238) (xy 63.986111 -302.72517)
			(xy 64.033382 -302.738862) (xy 64.077844 -302.75996) (xy 64.118347 -302.787916) (xy 64.15384 -302.822008)
			(xy 64.183405 -302.861352) (xy 64.206276 -302.904929) (xy 64.22186 -302.95161) (xy 64.229755 -303.000187)
			(xy 64.23025 -303.024794) (xy 64.569098 -303.024794) (xy 64.573058 -302.97574) (xy 64.584835 -302.927956)
			(xy 64.604126 -302.88268) (xy 64.630429 -302.841084) (xy 64.663064 -302.804247) (xy 64.701185 -302.773122)
			(xy 64.743806 -302.748515) (xy 64.789822 -302.731063) (xy 64.838041 -302.721219) (xy 64.887216 -302.719238)
			(xy 64.936071 -302.72517) (xy 64.983342 -302.738862) (xy 65.027804 -302.75996) (xy 65.068307 -302.787916)
			(xy 65.1038 -302.822008) (xy 65.133365 -302.861352) (xy 65.156236 -302.904929) (xy 65.17182 -302.95161)
			(xy 65.179715 -303.000187) (xy 65.18021 -303.024794) (xy 65.519058 -303.024794) (xy 65.523018 -302.97574)
			(xy 65.534795 -302.927956) (xy 65.554086 -302.88268) (xy 65.580389 -302.841084) (xy 65.613024 -302.804247)
			(xy 65.651145 -302.773122) (xy 65.693766 -302.748515) (xy 65.739782 -302.731063) (xy 65.788001 -302.721219)
			(xy 65.837176 -302.719238) (xy 65.886031 -302.72517) (xy 65.933302 -302.738862) (xy 65.977764 -302.75996)
			(xy 66.018267 -302.787916) (xy 66.05376 -302.822008) (xy 66.083325 -302.861352) (xy 66.106196 -302.904929)
			(xy 66.12178 -302.95161) (xy 66.129675 -303.000187) (xy 66.13017 -303.024794) (xy 66.469018 -303.024794)
			(xy 66.472978 -302.97574) (xy 66.484755 -302.927956) (xy 66.504046 -302.88268) (xy 66.530349 -302.841084)
			(xy 66.562984 -302.804247) (xy 66.601105 -302.773122) (xy 66.643726 -302.748515) (xy 66.689742 -302.731063)
			(xy 66.737961 -302.721219) (xy 66.787136 -302.719238) (xy 66.835991 -302.72517) (xy 66.883262 -302.738862)
			(xy 66.927724 -302.75996) (xy 66.968227 -302.787916) (xy 67.00372 -302.822008) (xy 67.033285 -302.861352)
			(xy 67.056156 -302.904929) (xy 67.07174 -302.95161) (xy 67.079635 -303.000187) (xy 67.08013 -303.024794)
			(xy 67.418978 -303.024794) (xy 67.422938 -302.97574) (xy 67.434715 -302.927956) (xy 67.454006 -302.88268)
			(xy 67.480309 -302.841084) (xy 67.512944 -302.804247) (xy 67.551065 -302.773122) (xy 67.593686 -302.748515)
			(xy 67.639702 -302.731063) (xy 67.687921 -302.721219) (xy 67.737096 -302.719238) (xy 67.785951 -302.72517)
			(xy 67.833222 -302.738862) (xy 67.877684 -302.75996) (xy 67.918187 -302.787916) (xy 67.95368 -302.822008)
			(xy 67.983245 -302.861352) (xy 68.006116 -302.904929) (xy 68.0217 -302.95161) (xy 68.029595 -303.000187)
			(xy 68.03009 -303.024794) (xy 68.368938 -303.024794) (xy 68.372898 -302.97574) (xy 68.384675 -302.927956)
			(xy 68.403966 -302.88268) (xy 68.430269 -302.841084) (xy 68.462904 -302.804247) (xy 68.501025 -302.773122)
			(xy 68.543646 -302.748515) (xy 68.589662 -302.731063) (xy 68.637881 -302.721219) (xy 68.687056 -302.719238)
			(xy 68.735911 -302.72517) (xy 68.783182 -302.738862) (xy 68.827644 -302.75996) (xy 68.868147 -302.787916)
			(xy 68.90364 -302.822008) (xy 68.933205 -302.861352) (xy 68.956076 -302.904929) (xy 68.97166 -302.95161)
			(xy 68.979555 -303.000187) (xy 68.98005 -303.024794) (xy 69.319152 -303.024794) (xy 69.323112 -302.97574)
			(xy 69.334889 -302.927956) (xy 69.35418 -302.88268) (xy 69.380483 -302.841084) (xy 69.413118 -302.804247)
			(xy 69.451239 -302.773122) (xy 69.49386 -302.748515) (xy 69.539876 -302.731063) (xy 69.588095 -302.721219)
			(xy 69.63727 -302.719238) (xy 69.686125 -302.72517) (xy 69.733396 -302.738862) (xy 69.777858 -302.75996)
			(xy 69.818361 -302.787916) (xy 69.853854 -302.822008) (xy 69.883419 -302.861352) (xy 69.90629 -302.904929)
			(xy 69.921874 -302.95161) (xy 69.929769 -303.000187) (xy 69.930264 -303.024794) (xy 70.269112 -303.024794)
			(xy 70.273072 -302.97574) (xy 70.284849 -302.927956) (xy 70.30414 -302.88268) (xy 70.330443 -302.841084)
			(xy 70.363078 -302.804247) (xy 70.401199 -302.773122) (xy 70.44382 -302.748515) (xy 70.489836 -302.731063)
			(xy 70.538055 -302.721219) (xy 70.58723 -302.719238) (xy 70.636085 -302.72517) (xy 70.683356 -302.738862)
			(xy 70.727818 -302.75996) (xy 70.768321 -302.787916) (xy 70.803814 -302.822008) (xy 70.833379 -302.861352)
			(xy 70.85625 -302.904929) (xy 70.871834 -302.95161) (xy 70.879729 -303.000187) (xy 70.880224 -303.024794)
			(xy 71.219072 -303.024794) (xy 71.223032 -302.97574) (xy 71.234809 -302.927956) (xy 71.2541 -302.88268)
			(xy 71.280403 -302.841084) (xy 71.313038 -302.804247) (xy 71.351159 -302.773122) (xy 71.39378 -302.748515)
			(xy 71.439796 -302.731063) (xy 71.488015 -302.721219) (xy 71.53719 -302.719238) (xy 71.586045 -302.72517)
			(xy 71.633316 -302.738862) (xy 71.677778 -302.75996) (xy 71.718281 -302.787916) (xy 71.753774 -302.822008)
			(xy 71.783339 -302.861352) (xy 71.80621 -302.904929) (xy 71.821794 -302.95161) (xy 71.829689 -303.000187)
			(xy 71.830184 -303.024794) (xy 72.169032 -303.024794) (xy 72.172992 -302.97574) (xy 72.184769 -302.927956)
			(xy 72.20406 -302.88268) (xy 72.230363 -302.841084) (xy 72.262998 -302.804247) (xy 72.301119 -302.773122)
			(xy 72.34374 -302.748515) (xy 72.389756 -302.731063) (xy 72.437975 -302.721219) (xy 72.48715 -302.719238)
			(xy 72.536005 -302.72517) (xy 72.583276 -302.738862) (xy 72.627738 -302.75996) (xy 72.668241 -302.787916)
			(xy 72.703734 -302.822008) (xy 72.733299 -302.861352) (xy 72.75617 -302.904929) (xy 72.771754 -302.95161)
			(xy 72.779649 -303.000187) (xy 72.780144 -303.024794) (xy 76.919086 -303.024794) (xy 76.923046 -302.97574)
			(xy 76.934823 -302.927956) (xy 76.954114 -302.88268) (xy 76.980417 -302.841084) (xy 77.013052 -302.804247)
			(xy 77.051173 -302.773122) (xy 77.093794 -302.748515) (xy 77.13981 -302.731063) (xy 77.188029 -302.721219)
			(xy 77.237204 -302.719238) (xy 77.286059 -302.72517) (xy 77.33333 -302.738862) (xy 77.377792 -302.75996)
			(xy 77.418295 -302.787916) (xy 77.453788 -302.822008) (xy 77.483353 -302.861352) (xy 77.506224 -302.904929)
			(xy 77.521808 -302.95161) (xy 77.529703 -303.000187) (xy 77.530198 -303.024794) (xy 77.869046 -303.024794)
			(xy 77.873006 -302.97574) (xy 77.884783 -302.927956) (xy 77.904074 -302.88268) (xy 77.930377 -302.841084)
			(xy 77.963012 -302.804247) (xy 78.001133 -302.773122) (xy 78.043754 -302.748515) (xy 78.08977 -302.731063)
			(xy 78.137989 -302.721219) (xy 78.187164 -302.719238) (xy 78.236019 -302.72517) (xy 78.28329 -302.738862)
			(xy 78.327752 -302.75996) (xy 78.368255 -302.787916) (xy 78.403748 -302.822008) (xy 78.433313 -302.861352)
			(xy 78.456184 -302.904929) (xy 78.471768 -302.95161) (xy 78.479663 -303.000187) (xy 78.480158 -303.024794)
			(xy 78.819006 -303.024794) (xy 78.822966 -302.97574) (xy 78.834743 -302.927956) (xy 78.854034 -302.88268)
			(xy 78.880337 -302.841084) (xy 78.912972 -302.804247) (xy 78.951093 -302.773122) (xy 78.993714 -302.748515)
			(xy 79.03973 -302.731063) (xy 79.087949 -302.721219) (xy 79.137124 -302.719238) (xy 79.185979 -302.72517)
			(xy 79.23325 -302.738862) (xy 79.277712 -302.75996) (xy 79.318215 -302.787916) (xy 79.353708 -302.822008)
			(xy 79.383273 -302.861352) (xy 79.406144 -302.904929) (xy 79.421728 -302.95161) (xy 79.429623 -303.000187)
			(xy 79.430118 -303.024794) (xy 79.768966 -303.024794) (xy 79.772926 -302.97574) (xy 79.784703 -302.927956)
			(xy 79.803994 -302.88268) (xy 79.830297 -302.841084) (xy 79.862932 -302.804247) (xy 79.901053 -302.773122)
			(xy 79.943674 -302.748515) (xy 79.98969 -302.731063) (xy 80.037909 -302.721219) (xy 80.087084 -302.719238)
			(xy 80.135939 -302.72517) (xy 80.18321 -302.738862) (xy 80.227672 -302.75996) (xy 80.268175 -302.787916)
			(xy 80.303668 -302.822008) (xy 80.333233 -302.861352) (xy 80.356104 -302.904929) (xy 80.371688 -302.95161)
			(xy 80.379583 -303.000187) (xy 80.380078 -303.024794) (xy 80.71918 -303.024794) (xy 80.72314 -302.97574)
			(xy 80.734917 -302.927956) (xy 80.754208 -302.88268) (xy 80.780511 -302.841084) (xy 80.813146 -302.804247)
			(xy 80.851267 -302.773122) (xy 80.893888 -302.748515) (xy 80.939904 -302.731063) (xy 80.988123 -302.721219)
			(xy 81.037298 -302.719238) (xy 81.086153 -302.72517) (xy 81.133424 -302.738862) (xy 81.177886 -302.75996)
			(xy 81.218389 -302.787916) (xy 81.253882 -302.822008) (xy 81.283447 -302.861352) (xy 81.306318 -302.904929)
			(xy 81.321902 -302.95161) (xy 81.329797 -303.000187) (xy 81.330292 -303.024794) (xy 81.66914 -303.024794)
			(xy 81.6731 -302.97574) (xy 81.684877 -302.927956) (xy 81.704168 -302.88268) (xy 81.730471 -302.841084)
			(xy 81.763106 -302.804247) (xy 81.801227 -302.773122) (xy 81.843848 -302.748515) (xy 81.889864 -302.731063)
			(xy 81.938083 -302.721219) (xy 81.987258 -302.719238) (xy 82.036113 -302.72517) (xy 82.083384 -302.738862)
			(xy 82.127846 -302.75996) (xy 82.168349 -302.787916) (xy 82.203842 -302.822008) (xy 82.233407 -302.861352)
			(xy 82.256278 -302.904929) (xy 82.271862 -302.95161) (xy 82.279757 -303.000187) (xy 82.280252 -303.024794)
			(xy 82.60386 -303.024794) (xy 82.60782 -302.97574) (xy 82.619597 -302.927956) (xy 82.638888 -302.88268)
			(xy 82.665191 -302.841084) (xy 82.697826 -302.804247) (xy 82.735947 -302.773122) (xy 82.778568 -302.748515)
			(xy 82.824584 -302.731063) (xy 82.872803 -302.721219) (xy 82.921978 -302.719238) (xy 82.970833 -302.72517)
			(xy 83.018104 -302.738862) (xy 83.062566 -302.75996) (xy 83.103069 -302.787916) (xy 83.138562 -302.822008)
			(xy 83.168127 -302.861352) (xy 83.190998 -302.904929) (xy 83.206582 -302.95161) (xy 83.210441 -302.975356)
			(xy 90.372341 -302.975356) (xy 90.372341 -302.920844) (xy 90.380099 -302.866888) (xy 90.395458 -302.814585)
			(xy 90.418104 -302.765001) (xy 90.447577 -302.719144) (xy 90.483276 -302.677949) (xy 90.524474 -302.642254)
			(xy 90.570334 -302.612786) (xy 90.619921 -302.590144) (xy 90.672225 -302.574791) (xy 90.726182 -302.567038)
			(xy 90.753438 -302.566578) (xy 90.781901 -302.567128) (xy 90.838198 -302.575574) (xy 90.892616 -302.592287)
			(xy 90.943949 -302.616897) (xy 90.991056 -302.648858) (xy 91.032895 -302.687461) (xy 91.051126 -302.709326)
			(xy 91.060886 -302.72061) (xy 91.08546 -302.737501) (xy 91.113865 -302.746574) (xy 91.143679 -302.747054)
			(xy 91.172362 -302.738902) (xy 91.197467 -302.722812) (xy 91.216854 -302.700155) (xy 91.223338 -302.68672)
			(xy 91.234826 -302.661582) (xy 91.264054 -302.614673) (xy 91.299745 -302.572473) (xy 91.341152 -302.535864)
			(xy 91.387408 -302.505615) (xy 91.437546 -302.482357) (xy 91.490515 -302.466578) (xy 91.545207 -302.458608)
			(xy 91.572842 -302.45812) (xy 91.600093 -302.458553) (xy 91.65404 -302.466315) (xy 91.706334 -302.481675)
			(xy 91.75591 -302.50432) (xy 91.801758 -302.533789) (xy 91.842946 -302.569483) (xy 91.878636 -302.610676)
			(xy 91.9081 -302.656527) (xy 91.93074 -302.706105) (xy 91.946094 -302.758401) (xy 91.95385 -302.812349)
			(xy 91.95385 -302.866851) (xy 91.946094 -302.920799) (xy 91.93074 -302.973095) (xy 91.9081 -303.022673)
			(xy 91.878636 -303.068524) (xy 91.842946 -303.109717) (xy 91.801758 -303.145411) (xy 91.75591 -303.17488)
			(xy 91.706334 -303.197525) (xy 91.65404 -303.212885) (xy 91.600093 -303.220647) (xy 91.572842 -303.221136)
			(xy 91.544378 -303.220595) (xy 91.488081 -303.212146) (xy 91.433663 -303.195431) (xy 91.382331 -303.170819)
			(xy 91.335224 -303.138857) (xy 91.293385 -303.100253) (xy 91.275154 -303.078388) (xy 91.26542 -303.067078)
			(xy 91.240841 -303.050185) (xy 91.212429 -303.041113) (xy 91.182608 -303.040635) (xy 91.15392 -303.048793)
			(xy 91.128812 -303.06489) (xy 91.109425 -303.087554) (xy 91.102942 -303.100994) (xy 91.091476 -303.126143)
			(xy 91.062245 -303.173052) (xy 91.026551 -303.215252) (xy 90.985141 -303.251859) (xy 90.938881 -303.282108)
			(xy 90.88874 -303.305364) (xy 90.835768 -303.32114) (xy 90.781074 -303.329108) (xy 90.753438 -303.329594)
			(xy 90.726182 -303.329162) (xy 90.672225 -303.321409) (xy 90.619921 -303.306056) (xy 90.570334 -303.283414)
			(xy 90.524474 -303.253946) (xy 90.483276 -303.218251) (xy 90.447577 -303.177056) (xy 90.418104 -303.131199)
			(xy 90.395458 -303.081615) (xy 90.380099 -303.029312) (xy 90.372341 -302.975356) (xy 83.210441 -302.975356)
			(xy 83.214477 -303.000187) (xy 83.214972 -303.024794) (xy 83.214477 -303.049401) (xy 83.206582 -303.097978)
			(xy 83.190998 -303.144659) (xy 83.168127 -303.188236) (xy 83.138562 -303.22758) (xy 83.103069 -303.261672)
			(xy 83.062566 -303.289628) (xy 83.018104 -303.310726) (xy 82.970833 -303.324418) (xy 82.921978 -303.33035)
			(xy 82.872803 -303.328369) (xy 82.824584 -303.318525) (xy 82.778568 -303.301073) (xy 82.735947 -303.276466)
			(xy 82.697826 -303.245341) (xy 82.665191 -303.208504) (xy 82.638888 -303.166908) (xy 82.619597 -303.121632)
			(xy 82.60782 -303.073848) (xy 82.60386 -303.024794) (xy 82.280252 -303.024794) (xy 82.279757 -303.049401)
			(xy 82.271862 -303.097978) (xy 82.256278 -303.144659) (xy 82.233407 -303.188236) (xy 82.203842 -303.22758)
			(xy 82.168349 -303.261672) (xy 82.127846 -303.289628) (xy 82.083384 -303.310726) (xy 82.036113 -303.324418)
			(xy 81.987258 -303.33035) (xy 81.938083 -303.328369) (xy 81.889864 -303.318525) (xy 81.843848 -303.301073)
			(xy 81.801227 -303.276466) (xy 81.763106 -303.245341) (xy 81.730471 -303.208504) (xy 81.704168 -303.166908)
			(xy 81.684877 -303.121632) (xy 81.6731 -303.073848) (xy 81.66914 -303.024794) (xy 81.330292 -303.024794)
			(xy 81.329797 -303.049401) (xy 81.321902 -303.097978) (xy 81.306318 -303.144659) (xy 81.283447 -303.188236)
			(xy 81.253882 -303.22758) (xy 81.218389 -303.261672) (xy 81.177886 -303.289628) (xy 81.133424 -303.310726)
			(xy 81.086153 -303.324418) (xy 81.037298 -303.33035) (xy 80.988123 -303.328369) (xy 80.939904 -303.318525)
			(xy 80.893888 -303.301073) (xy 80.851267 -303.276466) (xy 80.813146 -303.245341) (xy 80.780511 -303.208504)
			(xy 80.754208 -303.166908) (xy 80.734917 -303.121632) (xy 80.72314 -303.073848) (xy 80.71918 -303.024794)
			(xy 80.380078 -303.024794) (xy 80.379583 -303.049401) (xy 80.371688 -303.097978) (xy 80.356104 -303.144659)
			(xy 80.333233 -303.188236) (xy 80.303668 -303.22758) (xy 80.268175 -303.261672) (xy 80.227672 -303.289628)
			(xy 80.18321 -303.310726) (xy 80.135939 -303.324418) (xy 80.087084 -303.33035) (xy 80.037909 -303.328369)
			(xy 79.98969 -303.318525) (xy 79.943674 -303.301073) (xy 79.901053 -303.276466) (xy 79.862932 -303.245341)
			(xy 79.830297 -303.208504) (xy 79.803994 -303.166908) (xy 79.784703 -303.121632) (xy 79.772926 -303.073848)
			(xy 79.768966 -303.024794) (xy 79.430118 -303.024794) (xy 79.429623 -303.049401) (xy 79.421728 -303.097978)
			(xy 79.406144 -303.144659) (xy 79.383273 -303.188236) (xy 79.353708 -303.22758) (xy 79.318215 -303.261672)
			(xy 79.277712 -303.289628) (xy 79.23325 -303.310726) (xy 79.185979 -303.324418) (xy 79.137124 -303.33035)
			(xy 79.087949 -303.328369) (xy 79.03973 -303.318525) (xy 78.993714 -303.301073) (xy 78.951093 -303.276466)
			(xy 78.912972 -303.245341) (xy 78.880337 -303.208504) (xy 78.854034 -303.166908) (xy 78.834743 -303.121632)
			(xy 78.822966 -303.073848) (xy 78.819006 -303.024794) (xy 78.480158 -303.024794) (xy 78.479663 -303.049401)
			(xy 78.471768 -303.097978) (xy 78.456184 -303.144659) (xy 78.433313 -303.188236) (xy 78.403748 -303.22758)
			(xy 78.368255 -303.261672) (xy 78.327752 -303.289628) (xy 78.28329 -303.310726) (xy 78.236019 -303.324418)
			(xy 78.187164 -303.33035) (xy 78.137989 -303.328369) (xy 78.08977 -303.318525) (xy 78.043754 -303.301073)
			(xy 78.001133 -303.276466) (xy 77.963012 -303.245341) (xy 77.930377 -303.208504) (xy 77.904074 -303.166908)
			(xy 77.884783 -303.121632) (xy 77.873006 -303.073848) (xy 77.869046 -303.024794) (xy 77.530198 -303.024794)
			(xy 77.529703 -303.049401) (xy 77.521808 -303.097978) (xy 77.506224 -303.144659) (xy 77.483353 -303.188236)
			(xy 77.453788 -303.22758) (xy 77.418295 -303.261672) (xy 77.377792 -303.289628) (xy 77.33333 -303.310726)
			(xy 77.286059 -303.324418) (xy 77.237204 -303.33035) (xy 77.188029 -303.328369) (xy 77.13981 -303.318525)
			(xy 77.093794 -303.301073) (xy 77.051173 -303.276466) (xy 77.013052 -303.245341) (xy 76.980417 -303.208504)
			(xy 76.954114 -303.166908) (xy 76.934823 -303.121632) (xy 76.923046 -303.073848) (xy 76.919086 -303.024794)
			(xy 72.780144 -303.024794) (xy 72.779649 -303.049401) (xy 72.771754 -303.097978) (xy 72.75617 -303.144659)
			(xy 72.733299 -303.188236) (xy 72.703734 -303.22758) (xy 72.668241 -303.261672) (xy 72.627738 -303.289628)
			(xy 72.583276 -303.310726) (xy 72.536005 -303.324418) (xy 72.48715 -303.33035) (xy 72.437975 -303.328369)
			(xy 72.389756 -303.318525) (xy 72.34374 -303.301073) (xy 72.301119 -303.276466) (xy 72.262998 -303.245341)
			(xy 72.230363 -303.208504) (xy 72.20406 -303.166908) (xy 72.184769 -303.121632) (xy 72.172992 -303.073848)
			(xy 72.169032 -303.024794) (xy 71.830184 -303.024794) (xy 71.829689 -303.049401) (xy 71.821794 -303.097978)
			(xy 71.80621 -303.144659) (xy 71.783339 -303.188236) (xy 71.753774 -303.22758) (xy 71.718281 -303.261672)
			(xy 71.677778 -303.289628) (xy 71.633316 -303.310726) (xy 71.586045 -303.324418) (xy 71.53719 -303.33035)
			(xy 71.488015 -303.328369) (xy 71.439796 -303.318525) (xy 71.39378 -303.301073) (xy 71.351159 -303.276466)
			(xy 71.313038 -303.245341) (xy 71.280403 -303.208504) (xy 71.2541 -303.166908) (xy 71.234809 -303.121632)
			(xy 71.223032 -303.073848) (xy 71.219072 -303.024794) (xy 70.880224 -303.024794) (xy 70.879729 -303.049401)
			(xy 70.871834 -303.097978) (xy 70.85625 -303.144659) (xy 70.833379 -303.188236) (xy 70.803814 -303.22758)
			(xy 70.768321 -303.261672) (xy 70.727818 -303.289628) (xy 70.683356 -303.310726) (xy 70.636085 -303.324418)
			(xy 70.58723 -303.33035) (xy 70.538055 -303.328369) (xy 70.489836 -303.318525) (xy 70.44382 -303.301073)
			(xy 70.401199 -303.276466) (xy 70.363078 -303.245341) (xy 70.330443 -303.208504) (xy 70.30414 -303.166908)
			(xy 70.284849 -303.121632) (xy 70.273072 -303.073848) (xy 70.269112 -303.024794) (xy 69.930264 -303.024794)
			(xy 69.929769 -303.049401) (xy 69.921874 -303.097978) (xy 69.90629 -303.144659) (xy 69.883419 -303.188236)
			(xy 69.853854 -303.22758) (xy 69.818361 -303.261672) (xy 69.777858 -303.289628) (xy 69.733396 -303.310726)
			(xy 69.686125 -303.324418) (xy 69.63727 -303.33035) (xy 69.588095 -303.328369) (xy 69.539876 -303.318525)
			(xy 69.49386 -303.301073) (xy 69.451239 -303.276466) (xy 69.413118 -303.245341) (xy 69.380483 -303.208504)
			(xy 69.35418 -303.166908) (xy 69.334889 -303.121632) (xy 69.323112 -303.073848) (xy 69.319152 -303.024794)
			(xy 68.98005 -303.024794) (xy 68.979555 -303.049401) (xy 68.97166 -303.097978) (xy 68.956076 -303.144659)
			(xy 68.933205 -303.188236) (xy 68.90364 -303.22758) (xy 68.868147 -303.261672) (xy 68.827644 -303.289628)
			(xy 68.783182 -303.310726) (xy 68.735911 -303.324418) (xy 68.687056 -303.33035) (xy 68.637881 -303.328369)
			(xy 68.589662 -303.318525) (xy 68.543646 -303.301073) (xy 68.501025 -303.276466) (xy 68.462904 -303.245341)
			(xy 68.430269 -303.208504) (xy 68.403966 -303.166908) (xy 68.384675 -303.121632) (xy 68.372898 -303.073848)
			(xy 68.368938 -303.024794) (xy 68.03009 -303.024794) (xy 68.029595 -303.049401) (xy 68.0217 -303.097978)
			(xy 68.006116 -303.144659) (xy 67.983245 -303.188236) (xy 67.95368 -303.22758) (xy 67.918187 -303.261672)
			(xy 67.877684 -303.289628) (xy 67.833222 -303.310726) (xy 67.785951 -303.324418) (xy 67.737096 -303.33035)
			(xy 67.687921 -303.328369) (xy 67.639702 -303.318525) (xy 67.593686 -303.301073) (xy 67.551065 -303.276466)
			(xy 67.512944 -303.245341) (xy 67.480309 -303.208504) (xy 67.454006 -303.166908) (xy 67.434715 -303.121632)
			(xy 67.422938 -303.073848) (xy 67.418978 -303.024794) (xy 67.08013 -303.024794) (xy 67.079635 -303.049401)
			(xy 67.07174 -303.097978) (xy 67.056156 -303.144659) (xy 67.033285 -303.188236) (xy 67.00372 -303.22758)
			(xy 66.968227 -303.261672) (xy 66.927724 -303.289628) (xy 66.883262 -303.310726) (xy 66.835991 -303.324418)
			(xy 66.787136 -303.33035) (xy 66.737961 -303.328369) (xy 66.689742 -303.318525) (xy 66.643726 -303.301073)
			(xy 66.601105 -303.276466) (xy 66.562984 -303.245341) (xy 66.530349 -303.208504) (xy 66.504046 -303.166908)
			(xy 66.484755 -303.121632) (xy 66.472978 -303.073848) (xy 66.469018 -303.024794) (xy 66.13017 -303.024794)
			(xy 66.129675 -303.049401) (xy 66.12178 -303.097978) (xy 66.106196 -303.144659) (xy 66.083325 -303.188236)
			(xy 66.05376 -303.22758) (xy 66.018267 -303.261672) (xy 65.977764 -303.289628) (xy 65.933302 -303.310726)
			(xy 65.886031 -303.324418) (xy 65.837176 -303.33035) (xy 65.788001 -303.328369) (xy 65.739782 -303.318525)
			(xy 65.693766 -303.301073) (xy 65.651145 -303.276466) (xy 65.613024 -303.245341) (xy 65.580389 -303.208504)
			(xy 65.554086 -303.166908) (xy 65.534795 -303.121632) (xy 65.523018 -303.073848) (xy 65.519058 -303.024794)
			(xy 65.18021 -303.024794) (xy 65.179715 -303.049401) (xy 65.17182 -303.097978) (xy 65.156236 -303.144659)
			(xy 65.133365 -303.188236) (xy 65.1038 -303.22758) (xy 65.068307 -303.261672) (xy 65.027804 -303.289628)
			(xy 64.983342 -303.310726) (xy 64.936071 -303.324418) (xy 64.887216 -303.33035) (xy 64.838041 -303.328369)
			(xy 64.789822 -303.318525) (xy 64.743806 -303.301073) (xy 64.701185 -303.276466) (xy 64.663064 -303.245341)
			(xy 64.630429 -303.208504) (xy 64.604126 -303.166908) (xy 64.584835 -303.121632) (xy 64.573058 -303.073848)
			(xy 64.569098 -303.024794) (xy 64.23025 -303.024794) (xy 64.229755 -303.049401) (xy 64.22186 -303.097978)
			(xy 64.206276 -303.144659) (xy 64.183405 -303.188236) (xy 64.15384 -303.22758) (xy 64.118347 -303.261672)
			(xy 64.077844 -303.289628) (xy 64.033382 -303.310726) (xy 63.986111 -303.324418) (xy 63.937256 -303.33035)
			(xy 63.888081 -303.328369) (xy 63.839862 -303.318525) (xy 63.793846 -303.301073) (xy 63.751225 -303.276466)
			(xy 63.713104 -303.245341) (xy 63.680469 -303.208504) (xy 63.654166 -303.166908) (xy 63.634875 -303.121632)
			(xy 63.623098 -303.073848) (xy 63.619138 -303.024794) (xy 63.28029 -303.024794) (xy 63.279795 -303.049401)
			(xy 63.2719 -303.097978) (xy 63.256316 -303.144659) (xy 63.233445 -303.188236) (xy 63.20388 -303.22758)
			(xy 63.168387 -303.261672) (xy 63.127884 -303.289628) (xy 63.083422 -303.310726) (xy 63.036151 -303.324418)
			(xy 62.987296 -303.33035) (xy 62.938121 -303.328369) (xy 62.889902 -303.318525) (xy 62.843886 -303.301073)
			(xy 62.801265 -303.276466) (xy 62.763144 -303.245341) (xy 62.730509 -303.208504) (xy 62.704206 -303.166908)
			(xy 62.684915 -303.121632) (xy 62.673138 -303.073848) (xy 62.669178 -303.024794) (xy 62.330076 -303.024794)
			(xy 62.329581 -303.049401) (xy 62.321686 -303.097978) (xy 62.306102 -303.144659) (xy 62.283231 -303.188236)
			(xy 62.253666 -303.22758) (xy 62.218173 -303.261672) (xy 62.17767 -303.289628) (xy 62.133208 -303.310726)
			(xy 62.085937 -303.324418) (xy 62.037082 -303.33035) (xy 61.987907 -303.328369) (xy 61.939688 -303.318525)
			(xy 61.893672 -303.301073) (xy 61.851051 -303.276466) (xy 61.81293 -303.245341) (xy 61.780295 -303.208504)
			(xy 61.753992 -303.166908) (xy 61.734701 -303.121632) (xy 61.722924 -303.073848) (xy 61.718964 -303.024794)
			(xy 61.380116 -303.024794) (xy 61.379621 -303.049401) (xy 61.371726 -303.097978) (xy 61.356142 -303.144659)
			(xy 61.333271 -303.188236) (xy 61.303706 -303.22758) (xy 61.268213 -303.261672) (xy 61.22771 -303.289628)
			(xy 61.183248 -303.310726) (xy 61.135977 -303.324418) (xy 61.087122 -303.33035) (xy 61.037947 -303.328369)
			(xy 60.989728 -303.318525) (xy 60.943712 -303.301073) (xy 60.901091 -303.276466) (xy 60.86297 -303.245341)
			(xy 60.830335 -303.208504) (xy 60.804032 -303.166908) (xy 60.784741 -303.121632) (xy 60.772964 -303.073848)
			(xy 60.769004 -303.024794) (xy 60.506292 -303.024794) (xy 60.504153 -303.070087) (xy 60.493807 -303.123773)
			(xy 60.475905 -303.175434) (xy 60.450814 -303.224011) (xy 60.419048 -303.26851) (xy 60.381257 -303.30802)
			(xy 60.338215 -303.341734) (xy 60.290801 -303.36896) (xy 60.239988 -303.389141) (xy 60.213494 -303.395888)
			(xy 60.206636 -303.397412) (xy 60.195206 -303.403762) (xy 60.180474 -303.417986) (xy 60.1735 -303.425334)
			(xy 60.165522 -303.443937) (xy 60.16498 -303.454054) (xy 60.16498 -303.464214) (xy 60.1726 -303.48301)
			(xy 60.189364 -303.499774) (xy 73.593972 -303.499774) (xy 73.597932 -303.45072) (xy 73.609709 -303.402936)
			(xy 73.629 -303.35766) (xy 73.655303 -303.316064) (xy 73.687938 -303.279227) (xy 73.726059 -303.248102)
			(xy 73.76868 -303.223495) (xy 73.814696 -303.206043) (xy 73.862915 -303.196199) (xy 73.91209 -303.194218)
			(xy 73.960945 -303.20015) (xy 74.008216 -303.213842) (xy 74.052678 -303.23494) (xy 74.093181 -303.262896)
			(xy 74.128674 -303.296988) (xy 74.158239 -303.336332) (xy 74.18111 -303.379909) (xy 74.196694 -303.42659)
			(xy 74.204589 -303.475167) (xy 74.205084 -303.499774) (xy 74.544186 -303.499774) (xy 74.548146 -303.45072)
			(xy 74.559923 -303.402936) (xy 74.579214 -303.35766) (xy 74.605517 -303.316064) (xy 74.638152 -303.279227)
			(xy 74.676273 -303.248102) (xy 74.718894 -303.223495) (xy 74.76491 -303.206043) (xy 74.813129 -303.196199)
			(xy 74.862304 -303.194218) (xy 74.911159 -303.20015) (xy 74.95843 -303.213842) (xy 75.002892 -303.23494)
			(xy 75.043395 -303.262896) (xy 75.078888 -303.296988) (xy 75.108453 -303.336332) (xy 75.131324 -303.379909)
			(xy 75.146908 -303.42659) (xy 75.154803 -303.475167) (xy 75.155298 -303.499774) (xy 75.494146 -303.499774)
			(xy 75.498106 -303.45072) (xy 75.509883 -303.402936) (xy 75.529174 -303.35766) (xy 75.555477 -303.316064)
			(xy 75.588112 -303.279227) (xy 75.626233 -303.248102) (xy 75.668854 -303.223495) (xy 75.71487 -303.206043)
			(xy 75.763089 -303.196199) (xy 75.812264 -303.194218) (xy 75.861119 -303.20015) (xy 75.90839 -303.213842)
			(xy 75.952852 -303.23494) (xy 75.993355 -303.262896) (xy 76.028848 -303.296988) (xy 76.058413 -303.336332)
			(xy 76.081284 -303.379909) (xy 76.096868 -303.42659) (xy 76.104763 -303.475167) (xy 76.105258 -303.499774)
			(xy 76.104763 -303.524381) (xy 76.096868 -303.572958) (xy 76.081284 -303.619639) (xy 76.058413 -303.663216)
			(xy 76.028848 -303.70256) (xy 75.993355 -303.736652) (xy 75.952852 -303.764608) (xy 75.90839 -303.785706)
			(xy 75.861119 -303.799398) (xy 75.812264 -303.80533) (xy 75.763089 -303.803349) (xy 75.71487 -303.793505)
			(xy 75.668854 -303.776053) (xy 75.626233 -303.751446) (xy 75.588112 -303.720321) (xy 75.555477 -303.683484)
			(xy 75.529174 -303.641888) (xy 75.509883 -303.596612) (xy 75.498106 -303.548828) (xy 75.494146 -303.499774)
			(xy 75.155298 -303.499774) (xy 75.154803 -303.524381) (xy 75.146908 -303.572958) (xy 75.131324 -303.619639)
			(xy 75.108453 -303.663216) (xy 75.078888 -303.70256) (xy 75.043395 -303.736652) (xy 75.002892 -303.764608)
			(xy 74.95843 -303.785706) (xy 74.911159 -303.799398) (xy 74.862304 -303.80533) (xy 74.813129 -303.803349)
			(xy 74.76491 -303.793505) (xy 74.718894 -303.776053) (xy 74.676273 -303.751446) (xy 74.638152 -303.720321)
			(xy 74.605517 -303.683484) (xy 74.579214 -303.641888) (xy 74.559923 -303.596612) (xy 74.548146 -303.548828)
			(xy 74.544186 -303.499774) (xy 74.205084 -303.499774) (xy 74.204589 -303.524381) (xy 74.196694 -303.572958)
			(xy 74.18111 -303.619639) (xy 74.158239 -303.663216) (xy 74.128674 -303.70256) (xy 74.093181 -303.736652)
			(xy 74.052678 -303.764608) (xy 74.008216 -303.785706) (xy 73.960945 -303.799398) (xy 73.91209 -303.80533)
			(xy 73.862915 -303.803349) (xy 73.814696 -303.793505) (xy 73.76868 -303.776053) (xy 73.726059 -303.751446)
			(xy 73.687938 -303.720321) (xy 73.655303 -303.683484) (xy 73.629 -303.641888) (xy 73.609709 -303.596612)
			(xy 73.597932 -303.548828) (xy 73.593972 -303.499774) (xy 60.189364 -303.499774) (xy 60.394596 -303.705006)
			(xy 60.415329 -303.726583) (xy 60.450487 -303.775001) (xy 60.477643 -303.82832) (xy 60.496129 -303.885229)
			(xy 60.505492 -303.944328) (xy 60.506102 -303.974246) (xy 60.506102 -303.974754) (xy 60.769004 -303.974754)
			(xy 60.772964 -303.9257) (xy 60.784741 -303.877916) (xy 60.804032 -303.83264) (xy 60.830335 -303.791044)
			(xy 60.86297 -303.754207) (xy 60.901091 -303.723082) (xy 60.943712 -303.698475) (xy 60.989728 -303.681023)
			(xy 61.037947 -303.671179) (xy 61.087122 -303.669198) (xy 61.135977 -303.67513) (xy 61.183248 -303.688822)
			(xy 61.22771 -303.70992) (xy 61.268213 -303.737876) (xy 61.303706 -303.771968) (xy 61.333271 -303.811312)
			(xy 61.356142 -303.854889) (xy 61.371726 -303.90157) (xy 61.379621 -303.950147) (xy 61.380116 -303.974754)
			(xy 61.718964 -303.974754) (xy 61.722924 -303.9257) (xy 61.734701 -303.877916) (xy 61.753992 -303.83264)
			(xy 61.780295 -303.791044) (xy 61.81293 -303.754207) (xy 61.851051 -303.723082) (xy 61.893672 -303.698475)
			(xy 61.939688 -303.681023) (xy 61.987907 -303.671179) (xy 62.037082 -303.669198) (xy 62.085937 -303.67513)
			(xy 62.133208 -303.688822) (xy 62.17767 -303.70992) (xy 62.218173 -303.737876) (xy 62.253666 -303.771968)
			(xy 62.283231 -303.811312) (xy 62.306102 -303.854889) (xy 62.321686 -303.90157) (xy 62.329581 -303.950147)
			(xy 62.330076 -303.974754) (xy 62.669178 -303.974754) (xy 62.673138 -303.9257) (xy 62.684915 -303.877916)
			(xy 62.704206 -303.83264) (xy 62.730509 -303.791044) (xy 62.763144 -303.754207) (xy 62.801265 -303.723082)
			(xy 62.843886 -303.698475) (xy 62.889902 -303.681023) (xy 62.938121 -303.671179) (xy 62.987296 -303.669198)
			(xy 63.036151 -303.67513) (xy 63.083422 -303.688822) (xy 63.127884 -303.70992) (xy 63.168387 -303.737876)
			(xy 63.20388 -303.771968) (xy 63.233445 -303.811312) (xy 63.256316 -303.854889) (xy 63.2719 -303.90157)
			(xy 63.279795 -303.950147) (xy 63.28029 -303.974754) (xy 63.619138 -303.974754) (xy 63.623098 -303.9257)
			(xy 63.634875 -303.877916) (xy 63.654166 -303.83264) (xy 63.680469 -303.791044) (xy 63.713104 -303.754207)
			(xy 63.751225 -303.723082) (xy 63.793846 -303.698475) (xy 63.839862 -303.681023) (xy 63.888081 -303.671179)
			(xy 63.937256 -303.669198) (xy 63.986111 -303.67513) (xy 64.033382 -303.688822) (xy 64.077844 -303.70992)
			(xy 64.118347 -303.737876) (xy 64.15384 -303.771968) (xy 64.183405 -303.811312) (xy 64.206276 -303.854889)
			(xy 64.22186 -303.90157) (xy 64.229755 -303.950147) (xy 64.23025 -303.974754) (xy 64.569098 -303.974754)
			(xy 64.573058 -303.9257) (xy 64.584835 -303.877916) (xy 64.604126 -303.83264) (xy 64.630429 -303.791044)
			(xy 64.663064 -303.754207) (xy 64.701185 -303.723082) (xy 64.743806 -303.698475) (xy 64.789822 -303.681023)
			(xy 64.838041 -303.671179) (xy 64.887216 -303.669198) (xy 64.936071 -303.67513) (xy 64.983342 -303.688822)
			(xy 65.027804 -303.70992) (xy 65.068307 -303.737876) (xy 65.1038 -303.771968) (xy 65.133365 -303.811312)
			(xy 65.156236 -303.854889) (xy 65.17182 -303.90157) (xy 65.179715 -303.950147) (xy 65.18021 -303.974754)
			(xy 65.519058 -303.974754) (xy 65.523018 -303.9257) (xy 65.534795 -303.877916) (xy 65.554086 -303.83264)
			(xy 65.580389 -303.791044) (xy 65.613024 -303.754207) (xy 65.651145 -303.723082) (xy 65.693766 -303.698475)
			(xy 65.739782 -303.681023) (xy 65.788001 -303.671179) (xy 65.837176 -303.669198) (xy 65.886031 -303.67513)
			(xy 65.933302 -303.688822) (xy 65.977764 -303.70992) (xy 66.018267 -303.737876) (xy 66.05376 -303.771968)
			(xy 66.083325 -303.811312) (xy 66.106196 -303.854889) (xy 66.12178 -303.90157) (xy 66.129675 -303.950147)
			(xy 66.13017 -303.974754) (xy 66.469018 -303.974754) (xy 66.472978 -303.9257) (xy 66.484755 -303.877916)
			(xy 66.504046 -303.83264) (xy 66.530349 -303.791044) (xy 66.562984 -303.754207) (xy 66.601105 -303.723082)
			(xy 66.643726 -303.698475) (xy 66.689742 -303.681023) (xy 66.737961 -303.671179) (xy 66.787136 -303.669198)
			(xy 66.835991 -303.67513) (xy 66.883262 -303.688822) (xy 66.927724 -303.70992) (xy 66.968227 -303.737876)
			(xy 67.00372 -303.771968) (xy 67.033285 -303.811312) (xy 67.056156 -303.854889) (xy 67.07174 -303.90157)
			(xy 67.079635 -303.950147) (xy 67.08013 -303.974754) (xy 67.418978 -303.974754) (xy 67.422938 -303.9257)
			(xy 67.434715 -303.877916) (xy 67.454006 -303.83264) (xy 67.480309 -303.791044) (xy 67.512944 -303.754207)
			(xy 67.551065 -303.723082) (xy 67.593686 -303.698475) (xy 67.639702 -303.681023) (xy 67.687921 -303.671179)
			(xy 67.737096 -303.669198) (xy 67.785951 -303.67513) (xy 67.833222 -303.688822) (xy 67.877684 -303.70992)
			(xy 67.918187 -303.737876) (xy 67.95368 -303.771968) (xy 67.983245 -303.811312) (xy 68.006116 -303.854889)
			(xy 68.0217 -303.90157) (xy 68.029595 -303.950147) (xy 68.029993 -303.969928) (xy 68.374018 -303.969928)
			(xy 68.377978 -303.920874) (xy 68.389755 -303.87309) (xy 68.409046 -303.827814) (xy 68.435349 -303.786218)
			(xy 68.467984 -303.749381) (xy 68.506105 -303.718256) (xy 68.548726 -303.693649) (xy 68.594742 -303.676197)
			(xy 68.642961 -303.666353) (xy 68.692136 -303.664372) (xy 68.740991 -303.670304) (xy 68.788262 -303.683996)
			(xy 68.832724 -303.705094) (xy 68.873227 -303.73305) (xy 68.90872 -303.767142) (xy 68.938285 -303.806486)
			(xy 68.961156 -303.850063) (xy 68.97674 -303.896744) (xy 68.984635 -303.945321) (xy 68.98513 -303.969928)
			(xy 68.985033 -303.974754) (xy 69.319152 -303.974754) (xy 69.323112 -303.9257) (xy 69.334889 -303.877916)
			(xy 69.35418 -303.83264) (xy 69.380483 -303.791044) (xy 69.413118 -303.754207) (xy 69.451239 -303.723082)
			(xy 69.49386 -303.698475) (xy 69.539876 -303.681023) (xy 69.588095 -303.671179) (xy 69.63727 -303.669198)
			(xy 69.686125 -303.67513) (xy 69.733396 -303.688822) (xy 69.777858 -303.70992) (xy 69.818361 -303.737876)
			(xy 69.853854 -303.771968) (xy 69.883419 -303.811312) (xy 69.90629 -303.854889) (xy 69.921874 -303.90157)
			(xy 69.929769 -303.950147) (xy 69.930264 -303.974754) (xy 70.269112 -303.974754) (xy 70.273072 -303.9257)
			(xy 70.284849 -303.877916) (xy 70.30414 -303.83264) (xy 70.330443 -303.791044) (xy 70.363078 -303.754207)
			(xy 70.401199 -303.723082) (xy 70.44382 -303.698475) (xy 70.489836 -303.681023) (xy 70.538055 -303.671179)
			(xy 70.58723 -303.669198) (xy 70.636085 -303.67513) (xy 70.683356 -303.688822) (xy 70.727818 -303.70992)
			(xy 70.768321 -303.737876) (xy 70.803814 -303.771968) (xy 70.833379 -303.811312) (xy 70.85625 -303.854889)
			(xy 70.871834 -303.90157) (xy 70.879729 -303.950147) (xy 70.880224 -303.974754) (xy 71.219072 -303.974754)
			(xy 71.223032 -303.9257) (xy 71.234809 -303.877916) (xy 71.2541 -303.83264) (xy 71.280403 -303.791044)
			(xy 71.313038 -303.754207) (xy 71.351159 -303.723082) (xy 71.39378 -303.698475) (xy 71.439796 -303.681023)
			(xy 71.488015 -303.671179) (xy 71.53719 -303.669198) (xy 71.586045 -303.67513) (xy 71.633316 -303.688822)
			(xy 71.677778 -303.70992) (xy 71.718281 -303.737876) (xy 71.753774 -303.771968) (xy 71.783339 -303.811312)
			(xy 71.80621 -303.854889) (xy 71.821794 -303.90157) (xy 71.829689 -303.950147) (xy 71.830184 -303.974754)
			(xy 72.169032 -303.974754) (xy 72.172992 -303.9257) (xy 72.184769 -303.877916) (xy 72.20406 -303.83264)
			(xy 72.230363 -303.791044) (xy 72.262998 -303.754207) (xy 72.301119 -303.723082) (xy 72.34374 -303.698475)
			(xy 72.389756 -303.681023) (xy 72.437975 -303.671179) (xy 72.48715 -303.669198) (xy 72.536005 -303.67513)
			(xy 72.583276 -303.688822) (xy 72.627738 -303.70992) (xy 72.668241 -303.737876) (xy 72.703734 -303.771968)
			(xy 72.733299 -303.811312) (xy 72.75617 -303.854889) (xy 72.771754 -303.90157) (xy 72.779649 -303.950147)
			(xy 72.780144 -303.974754) (xy 72.779649 -303.999361) (xy 72.771754 -304.047938) (xy 72.75617 -304.094619)
			(xy 72.733299 -304.138196) (xy 72.703734 -304.17754) (xy 72.668241 -304.211632) (xy 72.627738 -304.239588)
			(xy 72.583276 -304.260686) (xy 72.536005 -304.274378) (xy 72.48715 -304.28031) (xy 72.437975 -304.278329)
			(xy 72.389756 -304.268485) (xy 72.34374 -304.251033) (xy 72.301119 -304.226426) (xy 72.262998 -304.195301)
			(xy 72.230363 -304.158464) (xy 72.20406 -304.116868) (xy 72.184769 -304.071592) (xy 72.172992 -304.023808)
			(xy 72.169032 -303.974754) (xy 71.830184 -303.974754) (xy 71.829689 -303.999361) (xy 71.821794 -304.047938)
			(xy 71.80621 -304.094619) (xy 71.783339 -304.138196) (xy 71.753774 -304.17754) (xy 71.718281 -304.211632)
			(xy 71.677778 -304.239588) (xy 71.633316 -304.260686) (xy 71.586045 -304.274378) (xy 71.53719 -304.28031)
			(xy 71.488015 -304.278329) (xy 71.439796 -304.268485) (xy 71.39378 -304.251033) (xy 71.351159 -304.226426)
			(xy 71.313038 -304.195301) (xy 71.280403 -304.158464) (xy 71.2541 -304.116868) (xy 71.234809 -304.071592)
			(xy 71.223032 -304.023808) (xy 71.219072 -303.974754) (xy 70.880224 -303.974754) (xy 70.879729 -303.999361)
			(xy 70.871834 -304.047938) (xy 70.85625 -304.094619) (xy 70.833379 -304.138196) (xy 70.803814 -304.17754)
			(xy 70.768321 -304.211632) (xy 70.727818 -304.239588) (xy 70.683356 -304.260686) (xy 70.636085 -304.274378)
			(xy 70.58723 -304.28031) (xy 70.538055 -304.278329) (xy 70.489836 -304.268485) (xy 70.44382 -304.251033)
			(xy 70.401199 -304.226426) (xy 70.363078 -304.195301) (xy 70.330443 -304.158464) (xy 70.30414 -304.116868)
			(xy 70.284849 -304.071592) (xy 70.273072 -304.023808) (xy 70.269112 -303.974754) (xy 69.930264 -303.974754)
			(xy 69.929769 -303.999361) (xy 69.921874 -304.047938) (xy 69.90629 -304.094619) (xy 69.883419 -304.138196)
			(xy 69.853854 -304.17754) (xy 69.818361 -304.211632) (xy 69.777858 -304.239588) (xy 69.733396 -304.260686)
			(xy 69.686125 -304.274378) (xy 69.63727 -304.28031) (xy 69.588095 -304.278329) (xy 69.539876 -304.268485)
			(xy 69.49386 -304.251033) (xy 69.451239 -304.226426) (xy 69.413118 -304.195301) (xy 69.380483 -304.158464)
			(xy 69.35418 -304.116868) (xy 69.334889 -304.071592) (xy 69.323112 -304.023808) (xy 69.319152 -303.974754)
			(xy 68.985033 -303.974754) (xy 68.984635 -303.994535) (xy 68.97674 -304.043112) (xy 68.961156 -304.089793)
			(xy 68.938285 -304.13337) (xy 68.90872 -304.172714) (xy 68.873227 -304.206806) (xy 68.832724 -304.234762)
			(xy 68.788262 -304.25586) (xy 68.740991 -304.269552) (xy 68.692136 -304.275484) (xy 68.642961 -304.273503)
			(xy 68.594742 -304.263659) (xy 68.548726 -304.246207) (xy 68.506105 -304.2216) (xy 68.467984 -304.190475)
			(xy 68.435349 -304.153638) (xy 68.409046 -304.112042) (xy 68.389755 -304.066766) (xy 68.377978 -304.018982)
			(xy 68.374018 -303.969928) (xy 68.029993 -303.969928) (xy 68.03009 -303.974754) (xy 68.029595 -303.999361)
			(xy 68.0217 -304.047938) (xy 68.006116 -304.094619) (xy 67.983245 -304.138196) (xy 67.95368 -304.17754)
			(xy 67.918187 -304.211632) (xy 67.877684 -304.239588) (xy 67.833222 -304.260686) (xy 67.785951 -304.274378)
			(xy 67.737096 -304.28031) (xy 67.687921 -304.278329) (xy 67.639702 -304.268485) (xy 67.593686 -304.251033)
			(xy 67.551065 -304.226426) (xy 67.512944 -304.195301) (xy 67.480309 -304.158464) (xy 67.454006 -304.116868)
			(xy 67.434715 -304.071592) (xy 67.422938 -304.023808) (xy 67.418978 -303.974754) (xy 67.08013 -303.974754)
			(xy 67.079635 -303.999361) (xy 67.07174 -304.047938) (xy 67.056156 -304.094619) (xy 67.033285 -304.138196)
			(xy 67.00372 -304.17754) (xy 66.968227 -304.211632) (xy 66.927724 -304.239588) (xy 66.883262 -304.260686)
			(xy 66.835991 -304.274378) (xy 66.787136 -304.28031) (xy 66.737961 -304.278329) (xy 66.689742 -304.268485)
			(xy 66.643726 -304.251033) (xy 66.601105 -304.226426) (xy 66.562984 -304.195301) (xy 66.530349 -304.158464)
			(xy 66.504046 -304.116868) (xy 66.484755 -304.071592) (xy 66.472978 -304.023808) (xy 66.469018 -303.974754)
			(xy 66.13017 -303.974754) (xy 66.129675 -303.999361) (xy 66.12178 -304.047938) (xy 66.106196 -304.094619)
			(xy 66.083325 -304.138196) (xy 66.05376 -304.17754) (xy 66.018267 -304.211632) (xy 65.977764 -304.239588)
			(xy 65.933302 -304.260686) (xy 65.886031 -304.274378) (xy 65.837176 -304.28031) (xy 65.788001 -304.278329)
			(xy 65.739782 -304.268485) (xy 65.693766 -304.251033) (xy 65.651145 -304.226426) (xy 65.613024 -304.195301)
			(xy 65.580389 -304.158464) (xy 65.554086 -304.116868) (xy 65.534795 -304.071592) (xy 65.523018 -304.023808)
			(xy 65.519058 -303.974754) (xy 65.18021 -303.974754) (xy 65.179715 -303.999361) (xy 65.17182 -304.047938)
			(xy 65.156236 -304.094619) (xy 65.133365 -304.138196) (xy 65.1038 -304.17754) (xy 65.068307 -304.211632)
			(xy 65.027804 -304.239588) (xy 64.983342 -304.260686) (xy 64.936071 -304.274378) (xy 64.887216 -304.28031)
			(xy 64.838041 -304.278329) (xy 64.789822 -304.268485) (xy 64.743806 -304.251033) (xy 64.701185 -304.226426)
			(xy 64.663064 -304.195301) (xy 64.630429 -304.158464) (xy 64.604126 -304.116868) (xy 64.584835 -304.071592)
			(xy 64.573058 -304.023808) (xy 64.569098 -303.974754) (xy 64.23025 -303.974754) (xy 64.229755 -303.999361)
			(xy 64.22186 -304.047938) (xy 64.206276 -304.094619) (xy 64.183405 -304.138196) (xy 64.15384 -304.17754)
			(xy 64.118347 -304.211632) (xy 64.077844 -304.239588) (xy 64.033382 -304.260686) (xy 63.986111 -304.274378)
			(xy 63.937256 -304.28031) (xy 63.888081 -304.278329) (xy 63.839862 -304.268485) (xy 63.793846 -304.251033)
			(xy 63.751225 -304.226426) (xy 63.713104 -304.195301) (xy 63.680469 -304.158464) (xy 63.654166 -304.116868)
			(xy 63.634875 -304.071592) (xy 63.623098 -304.023808) (xy 63.619138 -303.974754) (xy 63.28029 -303.974754)
			(xy 63.279795 -303.999361) (xy 63.2719 -304.047938) (xy 63.256316 -304.094619) (xy 63.233445 -304.138196)
			(xy 63.20388 -304.17754) (xy 63.168387 -304.211632) (xy 63.127884 -304.239588) (xy 63.083422 -304.260686)
			(xy 63.036151 -304.274378) (xy 62.987296 -304.28031) (xy 62.938121 -304.278329) (xy 62.889902 -304.268485)
			(xy 62.843886 -304.251033) (xy 62.801265 -304.226426) (xy 62.763144 -304.195301) (xy 62.730509 -304.158464)
			(xy 62.704206 -304.116868) (xy 62.684915 -304.071592) (xy 62.673138 -304.023808) (xy 62.669178 -303.974754)
			(xy 62.330076 -303.974754) (xy 62.329581 -303.999361) (xy 62.321686 -304.047938) (xy 62.306102 -304.094619)
			(xy 62.283231 -304.138196) (xy 62.253666 -304.17754) (xy 62.218173 -304.211632) (xy 62.17767 -304.239588)
			(xy 62.133208 -304.260686) (xy 62.085937 -304.274378) (xy 62.037082 -304.28031) (xy 61.987907 -304.278329)
			(xy 61.939688 -304.268485) (xy 61.893672 -304.251033) (xy 61.851051 -304.226426) (xy 61.81293 -304.195301)
			(xy 61.780295 -304.158464) (xy 61.753992 -304.116868) (xy 61.734701 -304.071592) (xy 61.722924 -304.023808)
			(xy 61.718964 -303.974754) (xy 61.380116 -303.974754) (xy 61.379621 -303.999361) (xy 61.371726 -304.047938)
			(xy 61.356142 -304.094619) (xy 61.333271 -304.138196) (xy 61.303706 -304.17754) (xy 61.268213 -304.211632)
			(xy 61.22771 -304.239588) (xy 61.183248 -304.260686) (xy 61.135977 -304.274378) (xy 61.087122 -304.28031)
			(xy 61.037947 -304.278329) (xy 60.989728 -304.268485) (xy 60.943712 -304.251033) (xy 60.901091 -304.226426)
			(xy 60.86297 -304.195301) (xy 60.830335 -304.158464) (xy 60.804032 -304.116868) (xy 60.784741 -304.071592)
			(xy 60.772964 -304.023808) (xy 60.769004 -303.974754) (xy 60.506102 -303.974754) (xy 60.50562 -304.00199)
			(xy 60.497874 -304.05591) (xy 60.482533 -304.108178) (xy 60.459911 -304.157731) (xy 60.430466 -304.20356)
			(xy 60.394799 -304.244732) (xy 60.353635 -304.28041) (xy 60.307814 -304.309865) (xy 60.258266 -304.3325)
			(xy 60.206002 -304.347854) (xy 60.152084 -304.355613) (xy 60.124848 -304.356008) (xy 60.12434 -304.356008)
			(xy 60.094425 -304.355397) (xy 60.035336 -304.346004) (xy 59.978437 -304.327504) (xy 59.925122 -304.300351)
			(xy 59.876698 -304.26521) (xy 59.8551 -304.244502) (xy 59.19978 -303.589182) (xy 59.179049 -303.567604)
			(xy 59.143895 -303.519185) (xy 59.116742 -303.465866) (xy 59.098259 -303.408957) (xy 59.088898 -303.349859)
			(xy 59.088274 -303.319942) (xy 59.088274 -303.290224) (xy 59.08802 -303.286668) (xy 59.08802 -303.284382)
			(xy 59.086905 -303.274716) (xy 59.078399 -303.257236) (xy 59.063973 -303.244204) (xy 59.055 -303.24044)
			(xy 59.04103 -303.235106) (xy 59.012074 -303.241456) (xy 58.986166 -303.267364) (xy 58.985912 -303.267364)
			(xy 58.958988 -303.294542) (xy 58.937412 -303.315277) (xy 58.888995 -303.350439) (xy 58.835677 -303.377598)
			(xy 58.778767 -303.396087) (xy 58.719667 -303.40545) (xy 58.689748 -303.406048) (xy 58.224928 -303.406048)
			(xy 58.197692 -303.405587) (xy 58.143775 -303.397839) (xy 58.09151 -303.382496) (xy 58.04196 -303.35987)
			(xy 57.996134 -303.330423) (xy 57.954966 -303.294754) (xy 57.919294 -303.253588) (xy 57.889843 -303.207765)
			(xy 57.867214 -303.158217) (xy 57.851867 -303.105952) (xy 57.844115 -303.052036) (xy 57.844115 -302.997564)
			(xy 57.851867 -302.943648) (xy 57.867214 -302.891383) (xy 57.889843 -302.841835) (xy 57.919294 -302.796012)
			(xy 57.954966 -302.754846) (xy 57.996134 -302.719177) (xy 58.04196 -302.68973) (xy 58.09151 -302.667104)
			(xy 58.143775 -302.651761) (xy 58.197692 -302.644013) (xy 58.224928 -302.64354) (xy 58.51525 -302.64354)
			(xy 58.522919 -302.642382) (xy 58.537127 -302.636185) (xy 58.54319 -302.631348) (xy 58.618882 -302.555656)
			(xy 58.623791 -302.549636) (xy 58.630007 -302.53541) (xy 58.631074 -302.527716) (xy 58.631074 -302.344836)
			(xy 58.63061 -302.334561) (xy 58.622565 -302.315653) (xy 58.60775 -302.301414) (xy 58.598308 -302.297338)
			(xy 58.509408 -302.263556) (xy 58.499669 -302.260348) (xy 58.479198 -302.261153) (xy 58.460687 -302.269929)
			(xy 58.453528 -302.277272) (xy 58.453274 -302.277526) (xy 58.435737 -302.296471) (xy 58.395462 -302.328763)
			(xy 58.35033 -302.353819) (xy 58.301626 -302.370927) (xy 58.250739 -302.379598) (xy 58.224928 -302.380142)
			(xy 58.199666 -302.379651) (xy 58.14983 -302.37134) (xy 58.102043 -302.354938) (xy 58.057607 -302.330894)
			(xy 58.017734 -302.299864) (xy 57.983514 -302.262693) (xy 57.955878 -302.220397) (xy 57.935582 -302.174129)
			(xy 57.923178 -302.125151) (xy 57.919006 -302.0748) (xy 57.923178 -302.024449) (xy 57.935582 -301.975471)
			(xy 57.955878 -301.929203) (xy 57.983514 -301.886907) (xy 58.017734 -301.849736) (xy 58.057607 -301.818706)
			(xy 58.102043 -301.794662) (xy 58.14983 -301.77826) (xy 58.199666 -301.769949) (xy 58.224928 -301.769526)
			(xy 58.225436 -301.769526) (xy 58.250297 -301.770008) (xy 58.299365 -301.778045) (xy 58.346486 -301.793918)
			(xy 58.390416 -301.817208) (xy 58.429997 -301.847301) (xy 58.447432 -301.86503) (xy 58.45429 -301.872396)
			(xy 58.47588 -301.882302) (xy 58.476388 -301.882302) (xy 58.485532 -301.88662) (xy 58.506106 -301.887382)
			(xy 58.572908 -301.861728) (xy 58.573416 -301.861728) (xy 58.598054 -301.85233) (xy 58.600848 -301.85106)
			(xy 58.609538 -301.846652) (xy 58.623023 -301.832609) (xy 58.630332 -301.814564) (xy 58.63082 -301.804832)
			(xy 58.63082 -300.444916) (xy 58.630353 -300.434642) (xy 58.622308 -300.415733) (xy 58.607498 -300.401489)
			(xy 58.598054 -300.397418) (xy 58.494422 -300.358048) (xy 58.463942 -300.365414) (xy 58.453274 -300.377606)
			(xy 58.435737 -300.396552) (xy 58.395464 -300.428846) (xy 58.350332 -300.453904) (xy 58.301627 -300.471013)
			(xy 58.250739 -300.479685) (xy 58.224928 -300.480222) (xy 58.199668 -300.479731) (xy 58.149835 -300.47142)
			(xy 58.102051 -300.45502) (xy 58.057618 -300.430977) (xy 58.017748 -300.399949) (xy 57.98353 -300.362781)
			(xy 57.955896 -300.320488) (xy 57.935601 -300.274223) (xy 57.923198 -300.225248) (xy 57.919026 -300.1749)
			(xy 57.923198 -300.124552) (xy 57.935601 -300.075577) (xy 57.955896 -300.029312) (xy 57.98353 -299.987019)
			(xy 58.017748 -299.949851) (xy 58.057618 -299.918823) (xy 58.102051 -299.89478) (xy 58.149835 -299.87838)
			(xy 58.199668 -299.870069) (xy 58.224928 -299.869606) (xy 58.225436 -299.869606) (xy 58.250297 -299.870088)
			(xy 58.299366 -299.878124) (xy 58.346487 -299.893997) (xy 58.390418 -299.917285) (xy 58.430001 -299.947377)
			(xy 58.447432 -299.96511) (xy 58.45429 -299.972476) (xy 58.47588 -299.982382) (xy 58.476388 -299.982382)
			(xy 58.485532 -299.9867) (xy 58.506106 -299.987462) (xy 58.572908 -299.961808) (xy 58.573416 -299.961808)
			(xy 58.598054 -299.95241) (xy 58.600848 -299.95114) (xy 58.609536 -299.946732) (xy 58.623015 -299.932688)
			(xy 58.630317 -299.914643) (xy 58.63082 -299.904912) (xy 58.63082 -298.544742) (xy 58.630358 -298.534465)
			(xy 58.622318 -298.515548) (xy 58.607508 -298.501295) (xy 58.598054 -298.497244) (xy 58.494422 -298.457874)
			(xy 58.463942 -298.46524) (xy 58.453274 -298.477432) (xy 58.435736 -298.496377) (xy 58.395462 -298.528668)
			(xy 58.35033 -298.553724) (xy 58.301626 -298.570831) (xy 58.250739 -298.579502) (xy 58.224928 -298.580048)
			(xy 58.199665 -298.579557) (xy 58.149829 -298.571245) (xy 58.10204 -298.554843) (xy 58.057603 -298.530799)
			(xy 58.01773 -298.499768) (xy 57.983509 -298.462597) (xy 57.955873 -298.4203) (xy 57.935576 -298.374031)
			(xy 57.923173 -298.325052) (xy 57.919 -298.2747) (xy 57.923173 -298.224348) (xy 57.935576 -298.175369)
			(xy 57.955873 -298.1291) (xy 57.983509 -298.086803) (xy 58.01773 -298.049632) (xy 58.057603 -298.018601)
			(xy 58.10204 -297.994557) (xy 58.149829 -297.978155) (xy 58.199665 -297.969843) (xy 58.224928 -297.969432)
			(xy 58.225436 -297.969432) (xy 58.250298 -297.969913) (xy 58.299368 -297.977949) (xy 58.346491 -297.993818)
			(xy 58.390426 -298.017103) (xy 58.430014 -298.04719) (xy 58.447432 -298.064936) (xy 58.45429 -298.072302)
			(xy 58.47588 -298.082208) (xy 58.476388 -298.082208) (xy 58.485532 -298.086526) (xy 58.506106 -298.087288)
			(xy 58.572908 -298.061634) (xy 58.573416 -298.061634) (xy 58.598054 -298.052236) (xy 58.600848 -298.050966)
			(xy 58.609539 -298.046559) (xy 58.623025 -298.032516) (xy 58.630336 -298.014471) (xy 58.63082 -298.004738)
			(xy 58.63082 -297.594782) (xy 58.630347 -297.584511) (xy 58.622295 -297.565614) (xy 58.607485 -297.55138)
			(xy 58.598054 -297.547284) (xy 58.494422 -297.507914) (xy 58.463942 -297.51528) (xy 58.453274 -297.527472)
			(xy 58.435738 -297.54642) (xy 58.395466 -297.578717) (xy 58.350334 -297.603778) (xy 58.301629 -297.620889)
			(xy 58.25074 -297.629562) (xy 58.224928 -297.630088) (xy 58.19967 -297.629598) (xy 58.149844 -297.621287)
			(xy 58.102064 -297.604888) (xy 58.057636 -297.580849) (xy 58.017771 -297.549824) (xy 57.983557 -297.51266)
			(xy 57.955926 -297.470372) (xy 57.935633 -297.424112) (xy 57.923232 -297.375143) (xy 57.91906 -297.3248)
			(xy 57.923232 -297.274457) (xy 57.935633 -297.225488) (xy 57.955926 -297.179228) (xy 57.983557 -297.13694)
			(xy 58.017771 -297.099776) (xy 58.057636 -297.068751) (xy 58.102064 -297.044712) (xy 58.149844 -297.028313)
			(xy 58.19967 -297.020002) (xy 58.224928 -297.019472) (xy 58.225436 -297.019472) (xy 58.250298 -297.019954)
			(xy 58.299367 -297.02799) (xy 58.346489 -297.04386) (xy 58.390422 -297.067148) (xy 58.430007 -297.097237)
			(xy 58.447432 -297.114976) (xy 58.45429 -297.122342) (xy 58.47588 -297.132248) (xy 58.476388 -297.132248)
			(xy 58.485532 -297.136566) (xy 58.506106 -297.137328) (xy 58.572908 -297.111674) (xy 58.573416 -297.111674)
			(xy 58.598054 -297.102276) (xy 58.600848 -297.101006) (xy 58.609543 -297.096601) (xy 58.623041 -297.08256)
			(xy 58.630365 -297.064514) (xy 58.63082 -297.054778) (xy 58.63082 -296.733722) (xy 58.630332 -296.72376)
			(xy 58.622744 -296.705337) (xy 58.616088 -296.697908) (xy 58.591196 -296.672762) (xy 58.52541 -296.60723)
			(xy 58.518003 -296.600541) (xy 58.499566 -296.59295) (xy 58.489596 -296.592498) (xy 58.458862 -296.592498)
			(xy 58.449848 -296.592864) (xy 58.43294 -296.59912) (xy 58.425842 -296.60469) (xy 58.425588 -296.604944)
			(xy 58.404545 -296.622481) (xy 58.357503 -296.650537) (xy 58.306211 -296.669752) (xy 58.252314 -296.679509)
			(xy 58.224928 -296.680128) (xy 58.200933 -296.679684) (xy 58.153533 -296.672181) (xy 58.10789 -296.657355)
			(xy 58.065129 -296.635571) (xy 58.026301 -296.607367) (xy 57.992365 -296.573435) (xy 57.964154 -296.534612)
			(xy 57.942363 -296.491854) (xy 57.92753 -296.446214) (xy 57.92002 -296.398815) (xy 57.91962 -296.37482)
			(xy 57.919723 -296.36514) (xy 57.920996 -296.345822) (xy 57.92216 -296.336212) (xy 57.92343 -296.32529)
			(xy 57.91708 -296.304462) (xy 57.859168 -296.238676) (xy 57.851635 -296.230873) (xy 57.831901 -296.221922)
			(xy 57.821068 -296.221404) (xy 57.678574 -296.221404) (xy 57.668589 -296.221946) (xy 57.650164 -296.229667)
			(xy 57.64276 -296.23639) (xy 57.64022 -296.23893) (xy 57.590944 -296.295064) (xy 57.584594 -296.302176)
			(xy 57.581292 -296.311066) (xy 57.579744 -296.315413) (xy 57.578073 -296.324487) (xy 57.57799 -296.3291)
			(xy 57.57799 -296.337482) (xy 57.578244 -296.340276) (xy 57.580276 -296.373804) (xy 57.580276 -296.374058)
			(xy 57.580276 -296.37482) (xy 57.579754 -296.400075) (xy 57.571441 -296.449897) (xy 57.55504 -296.497671)
			(xy 57.530999 -296.542094) (xy 57.499975 -296.581954) (xy 57.462813 -296.616164) (xy 57.420527 -296.64379)
			(xy 57.374271 -296.66408) (xy 57.325306 -296.67648) (xy 57.274968 -296.680651) (xy 57.22463 -296.67648)
			(xy 57.175665 -296.66408) (xy 57.129409 -296.64379) (xy 57.087123 -296.616164) (xy 57.049961 -296.581954)
			(xy 57.018937 -296.542094) (xy 56.994896 -296.497671) (xy 56.978495 -296.449897) (xy 56.970182 -296.400075)
			(xy 56.96966 -296.37482) (xy 56.96966 -296.374058) (xy 56.971438 -296.341546) (xy 56.971692 -296.340276)
			(xy 56.9722 -296.333672) (xy 56.972428 -296.323229) (xy 56.965473 -296.303557) (xy 56.958738 -296.295572)
			(xy 56.958992 -296.295318) (xy 56.90997 -296.239184) (xy 56.908192 -296.23766) (xy 56.906922 -296.23639)
			(xy 56.899572 -296.229593) (xy 56.881109 -296.22189) (xy 56.871108 -296.221404) (xy 56.728614 -296.221404)
			(xy 56.718625 -296.221939) (xy 56.70019 -296.229649) (xy 56.6928 -296.23639) (xy 56.69026 -296.23893)
			(xy 56.640984 -296.295064) (xy 56.634634 -296.302176) (xy 56.631332 -296.311066) (xy 56.629785 -296.315413)
			(xy 56.628117 -296.324487) (xy 56.62803 -296.3291) (xy 56.62803 -296.337482) (xy 56.628284 -296.340276)
			(xy 56.630316 -296.373804) (xy 56.630316 -296.374058) (xy 56.630316 -296.37482) (xy 56.629794 -296.400075)
			(xy 56.621481 -296.449897) (xy 56.60508 -296.497671) (xy 56.581039 -296.542094) (xy 56.550015 -296.581954)
			(xy 56.512853 -296.616164) (xy 56.470567 -296.64379) (xy 56.424311 -296.66408) (xy 56.375346 -296.67648)
			(xy 56.325008 -296.680651) (xy 56.27467 -296.67648) (xy 56.225705 -296.66408) (xy 56.179449 -296.64379)
			(xy 56.137163 -296.616164) (xy 56.100001 -296.581954) (xy 56.068977 -296.542094) (xy 56.044936 -296.497671)
			(xy 56.028535 -296.449897) (xy 56.020222 -296.400075) (xy 56.0197 -296.37482) (xy 56.0197 -296.374058)
			(xy 56.021478 -296.341546) (xy 56.021732 -296.340276) (xy 56.02224 -296.333672) (xy 56.022468 -296.32323)
			(xy 56.015506 -296.303563) (xy 56.008778 -296.295572) (xy 56.009032 -296.295318) (xy 55.96001 -296.239184)
			(xy 55.958232 -296.23766) (xy 55.956962 -296.23639) (xy 55.949614 -296.229587) (xy 55.931152 -296.22187)
			(xy 55.921148 -296.221404) (xy 55.7784 -296.221404) (xy 55.768413 -296.221942) (xy 55.749981 -296.229655)
			(xy 55.742586 -296.23639) (xy 55.740046 -296.23893) (xy 55.69077 -296.295064) (xy 55.68442 -296.302176)
			(xy 55.681118 -296.311066) (xy 55.679572 -296.315413) (xy 55.677903 -296.324487) (xy 55.677816 -296.3291)
			(xy 55.677816 -296.337482) (xy 55.67807 -296.340276) (xy 55.680102 -296.373804) (xy 55.680102 -296.374058)
			(xy 55.680102 -296.37482) (xy 55.67958 -296.400075) (xy 55.671267 -296.449897) (xy 55.654866 -296.497671)
			(xy 55.630825 -296.542094) (xy 55.599801 -296.581954) (xy 55.562639 -296.616164) (xy 55.520353 -296.64379)
			(xy 55.474097 -296.66408) (xy 55.425132 -296.67648) (xy 55.374794 -296.680651) (xy 55.324456 -296.67648)
			(xy 55.275491 -296.66408) (xy 55.229235 -296.64379) (xy 55.186949 -296.616164) (xy 55.149787 -296.581954)
			(xy 55.118763 -296.542094) (xy 55.094722 -296.497671) (xy 55.078321 -296.449897) (xy 55.070008 -296.400075)
			(xy 55.069486 -296.37482) (xy 55.069486 -296.374058) (xy 55.071264 -296.341546) (xy 55.071518 -296.340276)
			(xy 55.072026 -296.333672) (xy 55.072253 -296.323231) (xy 55.06529 -296.303564) (xy 55.058564 -296.295572)
			(xy 55.058818 -296.295318) (xy 55.009796 -296.239184) (xy 55.008018 -296.23766) (xy 55.006748 -296.23639)
			(xy 54.999399 -296.229589) (xy 54.980937 -296.221877) (xy 54.970934 -296.221404) (xy 54.82844 -296.221404)
			(xy 54.818449 -296.221934) (xy 54.800007 -296.229638) (xy 54.792626 -296.23639) (xy 54.790086 -296.23893)
			(xy 54.74081 -296.295064) (xy 54.73446 -296.302176) (xy 54.731158 -296.311066) (xy 54.729611 -296.315413)
			(xy 54.727941 -296.324487) (xy 54.727856 -296.3291) (xy 54.727856 -296.337482) (xy 54.72811 -296.340276)
			(xy 54.730142 -296.373804) (xy 54.730142 -296.374058) (xy 54.730142 -296.37482) (xy 54.72962 -296.400075)
			(xy 54.721307 -296.449897) (xy 54.704906 -296.497671) (xy 54.680865 -296.542094) (xy 54.649841 -296.581954)
			(xy 54.612679 -296.616164) (xy 54.570393 -296.64379) (xy 54.524137 -296.66408) (xy 54.475172 -296.67648)
			(xy 54.424834 -296.680651) (xy 54.374496 -296.67648) (xy 54.325531 -296.66408) (xy 54.279275 -296.64379)
			(xy 54.236989 -296.616164) (xy 54.199827 -296.581954) (xy 54.168803 -296.542094) (xy 54.144762 -296.497671)
			(xy 54.128361 -296.449897) (xy 54.120048 -296.400075) (xy 54.119526 -296.37482) (xy 54.119526 -296.374058)
			(xy 54.121304 -296.341546) (xy 54.121558 -296.340276) (xy 54.122066 -296.333672) (xy 54.122294 -296.32323)
			(xy 54.115334 -296.30356) (xy 54.108604 -296.295572) (xy 54.108858 -296.295318) (xy 54.059836 -296.239184)
			(xy 54.058058 -296.23766) (xy 54.056788 -296.23639) (xy 54.049442 -296.229582) (xy 54.030979 -296.221856)
			(xy 54.020974 -296.221404) (xy 53.87848 -296.221404) (xy 53.868494 -296.221945) (xy 53.850068 -296.229664)
			(xy 53.842666 -296.23639) (xy 53.840126 -296.23893) (xy 53.79085 -296.295064) (xy 53.7845 -296.302176)
			(xy 53.781198 -296.311066) (xy 53.77965 -296.315413) (xy 53.777979 -296.324487) (xy 53.777896 -296.3291)
			(xy 53.777896 -296.337482) (xy 53.77815 -296.340276) (xy 53.780182 -296.373804) (xy 53.780182 -296.374058)
			(xy 53.780182 -296.37482) (xy 53.77966 -296.400075) (xy 53.771347 -296.449897) (xy 53.754946 -296.497671)
			(xy 53.730905 -296.542094) (xy 53.699881 -296.581954) (xy 53.662719 -296.616164) (xy 53.620433 -296.64379)
			(xy 53.574177 -296.66408) (xy 53.525212 -296.67648) (xy 53.474874 -296.680651) (xy 53.424536 -296.67648)
			(xy 53.375571 -296.66408) (xy 53.329315 -296.64379) (xy 53.287029 -296.616164) (xy 53.249867 -296.581954)
			(xy 53.218843 -296.542094) (xy 53.194802 -296.497671) (xy 53.178401 -296.449897) (xy 53.170088 -296.400075)
			(xy 53.169566 -296.37482) (xy 53.169566 -296.374058) (xy 53.171344 -296.341546) (xy 53.171598 -296.340276)
			(xy 53.172106 -296.333672) (xy 53.172333 -296.323231) (xy 53.165367 -296.303566) (xy 53.158644 -296.295572)
			(xy 53.158898 -296.295318) (xy 53.109876 -296.239184) (xy 53.108098 -296.23766) (xy 53.106828 -296.23639)
			(xy 53.099478 -296.229592) (xy 53.081016 -296.221887) (xy 53.071014 -296.221404) (xy 52.92852 -296.221404)
			(xy 52.918531 -296.221938) (xy 52.900094 -296.229647) (xy 52.892706 -296.23639) (xy 52.890166 -296.23893)
			(xy 52.84089 -296.295064) (xy 52.83454 -296.302176) (xy 52.831238 -296.311066) (xy 52.829691 -296.315413)
			(xy 52.828022 -296.324487) (xy 52.827936 -296.3291) (xy 52.827936 -296.337482) (xy 52.82819 -296.340276)
			(xy 52.830222 -296.373804) (xy 52.830222 -296.374058) (xy 52.830222 -296.37482) (xy 52.8297 -296.400075)
			(xy 52.821387 -296.449897) (xy 52.804986 -296.497671) (xy 52.780945 -296.542094) (xy 52.749921 -296.581954)
			(xy 52.712759 -296.616164) (xy 52.670473 -296.64379) (xy 52.624217 -296.66408) (xy 52.575252 -296.67648)
			(xy 52.524914 -296.680651) (xy 52.474576 -296.67648) (xy 52.425611 -296.66408) (xy 52.379355 -296.64379)
			(xy 52.337069 -296.616164) (xy 52.299907 -296.581954) (xy 52.268883 -296.542094) (xy 52.244842 -296.497671)
			(xy 52.228441 -296.449897) (xy 52.220128 -296.400075) (xy 52.219606 -296.37482) (xy 52.219606 -296.374058)
			(xy 52.221384 -296.341546) (xy 52.221638 -296.340276) (xy 52.222146 -296.333672) (xy 52.222374 -296.32323)
			(xy 52.215412 -296.303562) (xy 52.208684 -296.295572) (xy 52.208938 -296.295318) (xy 52.159916 -296.239184)
			(xy 52.158138 -296.23766) (xy 52.156868 -296.23639) (xy 52.14952 -296.229586) (xy 52.131058 -296.221866)
			(xy 52.121054 -296.221404) (xy 51.97856 -296.221404) (xy 51.968576 -296.221949) (xy 51.950155 -296.229673)
			(xy 51.942746 -296.23639) (xy 51.940206 -296.23893) (xy 51.89093 -296.295064) (xy 51.88458 -296.302176)
			(xy 51.881278 -296.311066) (xy 51.87973 -296.315413) (xy 51.87806 -296.324487) (xy 51.877976 -296.3291)
			(xy 51.877976 -296.337482) (xy 51.87823 -296.340276) (xy 51.880262 -296.373804) (xy 51.880262 -296.374058)
			(xy 51.880262 -296.37482) (xy 51.87974 -296.400075) (xy 51.871427 -296.449897) (xy 51.855026 -296.497671)
			(xy 51.830985 -296.542094) (xy 51.799961 -296.581954) (xy 51.762799 -296.616164) (xy 51.720513 -296.64379)
			(xy 51.674257 -296.66408) (xy 51.625292 -296.67648) (xy 51.574954 -296.680651) (xy 51.524616 -296.67648)
			(xy 51.475651 -296.66408) (xy 51.429395 -296.64379) (xy 51.387109 -296.616164) (xy 51.349947 -296.581954)
			(xy 51.318923 -296.542094) (xy 51.294882 -296.497671) (xy 51.278481 -296.449897) (xy 51.270168 -296.400075)
			(xy 51.269646 -296.37482) (xy 51.269646 -296.374058) (xy 51.271424 -296.341546) (xy 51.271678 -296.340276)
			(xy 51.272186 -296.333672) (xy 51.272414 -296.323229) (xy 51.265457 -296.303558) (xy 51.258724 -296.295572)
			(xy 51.258978 -296.295318) (xy 51.209956 -296.239184) (xy 51.208178 -296.23766) (xy 51.206908 -296.23639)
			(xy 51.199563 -296.229579) (xy 51.181101 -296.221846) (xy 51.171094 -296.221404) (xy 51.0286 -296.221404)
			(xy 51.018613 -296.221942) (xy 51.000181 -296.229655) (xy 50.992786 -296.23639) (xy 50.990246 -296.23893)
			(xy 50.94097 -296.295064) (xy 50.93462 -296.302176) (xy 50.931318 -296.311066) (xy 50.929772 -296.315413)
			(xy 50.928103 -296.324487) (xy 50.928016 -296.3291) (xy 50.928016 -296.337482) (xy 50.92827 -296.340276)
			(xy 50.930302 -296.373804) (xy 50.930302 -296.374058) (xy 50.930302 -296.37482) (xy 50.92978 -296.400075)
			(xy 50.921467 -296.449897) (xy 50.905066 -296.497671) (xy 50.881025 -296.542094) (xy 50.850001 -296.581954)
			(xy 50.812839 -296.616164) (xy 50.770553 -296.64379) (xy 50.724297 -296.66408) (xy 50.675332 -296.67648)
			(xy 50.624994 -296.680651) (xy 50.574656 -296.67648) (xy 50.525691 -296.66408) (xy 50.479435 -296.64379)
			(xy 50.437149 -296.616164) (xy 50.399987 -296.581954) (xy 50.368963 -296.542094) (xy 50.344922 -296.497671)
			(xy 50.328521 -296.449897) (xy 50.320208 -296.400075) (xy 50.319686 -296.37482) (xy 50.319686 -296.374058)
			(xy 50.321464 -296.341546) (xy 50.321718 -296.340276) (xy 50.322226 -296.333672) (xy 50.322453 -296.323231)
			(xy 50.31549 -296.303564) (xy 50.308764 -296.295572) (xy 50.309018 -296.295318) (xy 50.259996 -296.239184)
			(xy 50.258218 -296.23766) (xy 50.256948 -296.23639) (xy 50.249599 -296.229589) (xy 50.231137 -296.221877)
			(xy 50.221134 -296.221404) (xy 50.205894 -296.221404) (xy 50.196385 -296.222526) (xy 50.179148 -296.230833)
			(xy 50.166119 -296.244845) (xy 50.159084 -296.262639) (xy 50.15865 -296.272204) (xy 50.15865 -297.32478)
			(xy 50.31919 -297.32478) (xy 50.32315 -297.275726) (xy 50.334927 -297.227942) (xy 50.354218 -297.182666)
			(xy 50.380521 -297.14107) (xy 50.413156 -297.104233) (xy 50.451277 -297.073108) (xy 50.493898 -297.048501)
			(xy 50.539914 -297.031049) (xy 50.588133 -297.021205) (xy 50.637308 -297.019224) (xy 50.686163 -297.025156)
			(xy 50.733434 -297.038848) (xy 50.777896 -297.059946) (xy 50.818399 -297.087902) (xy 50.853892 -297.121994)
			(xy 50.883457 -297.161338) (xy 50.906328 -297.204915) (xy 50.921912 -297.251596) (xy 50.929807 -297.300173)
			(xy 50.930302 -297.32478) (xy 51.26915 -297.32478) (xy 51.27311 -297.275726) (xy 51.284887 -297.227942)
			(xy 51.304178 -297.182666) (xy 51.330481 -297.14107) (xy 51.363116 -297.104233) (xy 51.401237 -297.073108)
			(xy 51.443858 -297.048501) (xy 51.489874 -297.031049) (xy 51.538093 -297.021205) (xy 51.587268 -297.019224)
			(xy 51.636123 -297.025156) (xy 51.683394 -297.038848) (xy 51.727856 -297.059946) (xy 51.768359 -297.087902)
			(xy 51.803852 -297.121994) (xy 51.833417 -297.161338) (xy 51.856288 -297.204915) (xy 51.871872 -297.251596)
			(xy 51.879767 -297.300173) (xy 51.880262 -297.32478) (xy 52.21911 -297.32478) (xy 52.22307 -297.275726)
			(xy 52.234847 -297.227942) (xy 52.254138 -297.182666) (xy 52.280441 -297.14107) (xy 52.313076 -297.104233)
			(xy 52.351197 -297.073108) (xy 52.393818 -297.048501) (xy 52.439834 -297.031049) (xy 52.488053 -297.021205)
			(xy 52.537228 -297.019224) (xy 52.586083 -297.025156) (xy 52.633354 -297.038848) (xy 52.677816 -297.059946)
			(xy 52.718319 -297.087902) (xy 52.753812 -297.121994) (xy 52.783377 -297.161338) (xy 52.806248 -297.204915)
			(xy 52.821832 -297.251596) (xy 52.829727 -297.300173) (xy 52.830222 -297.32478) (xy 53.16907 -297.32478)
			(xy 53.17303 -297.275726) (xy 53.184807 -297.227942) (xy 53.204098 -297.182666) (xy 53.230401 -297.14107)
			(xy 53.263036 -297.104233) (xy 53.301157 -297.073108) (xy 53.343778 -297.048501) (xy 53.389794 -297.031049)
			(xy 53.438013 -297.021205) (xy 53.487188 -297.019224) (xy 53.536043 -297.025156) (xy 53.583314 -297.038848)
			(xy 53.627776 -297.059946) (xy 53.668279 -297.087902) (xy 53.703772 -297.121994) (xy 53.733337 -297.161338)
			(xy 53.756208 -297.204915) (xy 53.771792 -297.251596) (xy 53.779687 -297.300173) (xy 53.780182 -297.32478)
			(xy 54.11903 -297.32478) (xy 54.12299 -297.275726) (xy 54.134767 -297.227942) (xy 54.154058 -297.182666)
			(xy 54.180361 -297.14107) (xy 54.212996 -297.104233) (xy 54.251117 -297.073108) (xy 54.293738 -297.048501)
			(xy 54.339754 -297.031049) (xy 54.387973 -297.021205) (xy 54.437148 -297.019224) (xy 54.486003 -297.025156)
			(xy 54.533274 -297.038848) (xy 54.577736 -297.059946) (xy 54.618239 -297.087902) (xy 54.653732 -297.121994)
			(xy 54.683297 -297.161338) (xy 54.706168 -297.204915) (xy 54.721752 -297.251596) (xy 54.729647 -297.300173)
			(xy 54.730142 -297.32478) (xy 55.06899 -297.32478) (xy 55.07295 -297.275726) (xy 55.084727 -297.227942)
			(xy 55.104018 -297.182666) (xy 55.130321 -297.14107) (xy 55.162956 -297.104233) (xy 55.201077 -297.073108)
			(xy 55.243698 -297.048501) (xy 55.289714 -297.031049) (xy 55.337933 -297.021205) (xy 55.387108 -297.019224)
			(xy 55.435963 -297.025156) (xy 55.483234 -297.038848) (xy 55.527696 -297.059946) (xy 55.568199 -297.087902)
			(xy 55.603692 -297.121994) (xy 55.633257 -297.161338) (xy 55.656128 -297.204915) (xy 55.671712 -297.251596)
			(xy 55.679607 -297.300173) (xy 55.680102 -297.32478) (xy 56.01895 -297.32478) (xy 56.02291 -297.275726)
			(xy 56.034687 -297.227942) (xy 56.053978 -297.182666) (xy 56.080281 -297.14107) (xy 56.112916 -297.104233)
			(xy 56.151037 -297.073108) (xy 56.193658 -297.048501) (xy 56.239674 -297.031049) (xy 56.287893 -297.021205)
			(xy 56.337068 -297.019224) (xy 56.385923 -297.025156) (xy 56.433194 -297.038848) (xy 56.477656 -297.059946)
			(xy 56.518159 -297.087902) (xy 56.553652 -297.121994) (xy 56.583217 -297.161338) (xy 56.606088 -297.204915)
			(xy 56.621672 -297.251596) (xy 56.629567 -297.300173) (xy 56.630062 -297.32478) (xy 56.969164 -297.32478)
			(xy 56.973124 -297.275726) (xy 56.984901 -297.227942) (xy 57.004192 -297.182666) (xy 57.030495 -297.14107)
			(xy 57.06313 -297.104233) (xy 57.101251 -297.073108) (xy 57.143872 -297.048501) (xy 57.189888 -297.031049)
			(xy 57.238107 -297.021205) (xy 57.287282 -297.019224) (xy 57.336137 -297.025156) (xy 57.383408 -297.038848)
			(xy 57.42787 -297.059946) (xy 57.468373 -297.087902) (xy 57.503866 -297.121994) (xy 57.533431 -297.161338)
			(xy 57.556302 -297.204915) (xy 57.571886 -297.251596) (xy 57.579781 -297.300173) (xy 57.580276 -297.32478)
			(xy 57.579781 -297.349387) (xy 57.571886 -297.397964) (xy 57.556302 -297.444645) (xy 57.533431 -297.488222)
			(xy 57.503866 -297.527566) (xy 57.468373 -297.561658) (xy 57.42787 -297.589614) (xy 57.383408 -297.610712)
			(xy 57.336137 -297.624404) (xy 57.287282 -297.630336) (xy 57.238107 -297.628355) (xy 57.189888 -297.618511)
			(xy 57.143872 -297.601059) (xy 57.101251 -297.576452) (xy 57.06313 -297.545327) (xy 57.030495 -297.50849)
			(xy 57.004192 -297.466894) (xy 56.984901 -297.421618) (xy 56.973124 -297.373834) (xy 56.969164 -297.32478)
			(xy 56.630062 -297.32478) (xy 56.629567 -297.349387) (xy 56.621672 -297.397964) (xy 56.606088 -297.444645)
			(xy 56.583217 -297.488222) (xy 56.553652 -297.527566) (xy 56.518159 -297.561658) (xy 56.477656 -297.589614)
			(xy 56.433194 -297.610712) (xy 56.385923 -297.624404) (xy 56.337068 -297.630336) (xy 56.287893 -297.628355)
			(xy 56.239674 -297.618511) (xy 56.193658 -297.601059) (xy 56.151037 -297.576452) (xy 56.112916 -297.545327)
			(xy 56.080281 -297.50849) (xy 56.053978 -297.466894) (xy 56.034687 -297.421618) (xy 56.02291 -297.373834)
			(xy 56.01895 -297.32478) (xy 55.680102 -297.32478) (xy 55.679607 -297.349387) (xy 55.671712 -297.397964)
			(xy 55.656128 -297.444645) (xy 55.633257 -297.488222) (xy 55.603692 -297.527566) (xy 55.568199 -297.561658)
			(xy 55.527696 -297.589614) (xy 55.483234 -297.610712) (xy 55.435963 -297.624404) (xy 55.387108 -297.630336)
			(xy 55.337933 -297.628355) (xy 55.289714 -297.618511) (xy 55.243698 -297.601059) (xy 55.201077 -297.576452)
			(xy 55.162956 -297.545327) (xy 55.130321 -297.50849) (xy 55.104018 -297.466894) (xy 55.084727 -297.421618)
			(xy 55.07295 -297.373834) (xy 55.06899 -297.32478) (xy 54.730142 -297.32478) (xy 54.729647 -297.349387)
			(xy 54.721752 -297.397964) (xy 54.706168 -297.444645) (xy 54.683297 -297.488222) (xy 54.653732 -297.527566)
			(xy 54.618239 -297.561658) (xy 54.577736 -297.589614) (xy 54.533274 -297.610712) (xy 54.486003 -297.624404)
			(xy 54.437148 -297.630336) (xy 54.387973 -297.628355) (xy 54.339754 -297.618511) (xy 54.293738 -297.601059)
			(xy 54.251117 -297.576452) (xy 54.212996 -297.545327) (xy 54.180361 -297.50849) (xy 54.154058 -297.466894)
			(xy 54.134767 -297.421618) (xy 54.12299 -297.373834) (xy 54.11903 -297.32478) (xy 53.780182 -297.32478)
			(xy 53.779687 -297.349387) (xy 53.771792 -297.397964) (xy 53.756208 -297.444645) (xy 53.733337 -297.488222)
			(xy 53.703772 -297.527566) (xy 53.668279 -297.561658) (xy 53.627776 -297.589614) (xy 53.583314 -297.610712)
			(xy 53.536043 -297.624404) (xy 53.487188 -297.630336) (xy 53.438013 -297.628355) (xy 53.389794 -297.618511)
			(xy 53.343778 -297.601059) (xy 53.301157 -297.576452) (xy 53.263036 -297.545327) (xy 53.230401 -297.50849)
			(xy 53.204098 -297.466894) (xy 53.184807 -297.421618) (xy 53.17303 -297.373834) (xy 53.16907 -297.32478)
			(xy 52.830222 -297.32478) (xy 52.829727 -297.349387) (xy 52.821832 -297.397964) (xy 52.806248 -297.444645)
			(xy 52.783377 -297.488222) (xy 52.753812 -297.527566) (xy 52.718319 -297.561658) (xy 52.677816 -297.589614)
			(xy 52.633354 -297.610712) (xy 52.586083 -297.624404) (xy 52.537228 -297.630336) (xy 52.488053 -297.628355)
			(xy 52.439834 -297.618511) (xy 52.393818 -297.601059) (xy 52.351197 -297.576452) (xy 52.313076 -297.545327)
			(xy 52.280441 -297.50849) (xy 52.254138 -297.466894) (xy 52.234847 -297.421618) (xy 52.22307 -297.373834)
			(xy 52.21911 -297.32478) (xy 51.880262 -297.32478) (xy 51.879767 -297.349387) (xy 51.871872 -297.397964)
			(xy 51.856288 -297.444645) (xy 51.833417 -297.488222) (xy 51.803852 -297.527566) (xy 51.768359 -297.561658)
			(xy 51.727856 -297.589614) (xy 51.683394 -297.610712) (xy 51.636123 -297.624404) (xy 51.587268 -297.630336)
			(xy 51.538093 -297.628355) (xy 51.489874 -297.618511) (xy 51.443858 -297.601059) (xy 51.401237 -297.576452)
			(xy 51.363116 -297.545327) (xy 51.330481 -297.50849) (xy 51.304178 -297.466894) (xy 51.284887 -297.421618)
			(xy 51.27311 -297.373834) (xy 51.26915 -297.32478) (xy 50.930302 -297.32478) (xy 50.929807 -297.349387)
			(xy 50.921912 -297.397964) (xy 50.906328 -297.444645) (xy 50.883457 -297.488222) (xy 50.853892 -297.527566)
			(xy 50.818399 -297.561658) (xy 50.777896 -297.589614) (xy 50.733434 -297.610712) (xy 50.686163 -297.624404)
			(xy 50.637308 -297.630336) (xy 50.588133 -297.628355) (xy 50.539914 -297.618511) (xy 50.493898 -297.601059)
			(xy 50.451277 -297.576452) (xy 50.413156 -297.545327) (xy 50.380521 -297.50849) (xy 50.354218 -297.466894)
			(xy 50.334927 -297.421618) (xy 50.32315 -297.373834) (xy 50.31919 -297.32478) (xy 50.15865 -297.32478)
			(xy 50.15865 -298.27474) (xy 50.31919 -298.27474) (xy 50.32315 -298.225686) (xy 50.334927 -298.177902)
			(xy 50.354218 -298.132626) (xy 50.380521 -298.09103) (xy 50.413156 -298.054193) (xy 50.451277 -298.023068)
			(xy 50.493898 -297.998461) (xy 50.539914 -297.981009) (xy 50.588133 -297.971165) (xy 50.637308 -297.969184)
			(xy 50.686163 -297.975116) (xy 50.733434 -297.988808) (xy 50.777896 -298.009906) (xy 50.818399 -298.037862)
			(xy 50.853892 -298.071954) (xy 50.883457 -298.111298) (xy 50.906328 -298.154875) (xy 50.921912 -298.201556)
			(xy 50.929807 -298.250133) (xy 50.930302 -298.27474) (xy 51.26915 -298.27474) (xy 51.27311 -298.225686)
			(xy 51.284887 -298.177902) (xy 51.304178 -298.132626) (xy 51.330481 -298.09103) (xy 51.363116 -298.054193)
			(xy 51.401237 -298.023068) (xy 51.443858 -297.998461) (xy 51.489874 -297.981009) (xy 51.538093 -297.971165)
			(xy 51.587268 -297.969184) (xy 51.636123 -297.975116) (xy 51.683394 -297.988808) (xy 51.727856 -298.009906)
			(xy 51.768359 -298.037862) (xy 51.803852 -298.071954) (xy 51.833417 -298.111298) (xy 51.856288 -298.154875)
			(xy 51.871872 -298.201556) (xy 51.879767 -298.250133) (xy 51.880262 -298.27474) (xy 52.21911 -298.27474)
			(xy 52.22307 -298.225686) (xy 52.234847 -298.177902) (xy 52.254138 -298.132626) (xy 52.280441 -298.09103)
			(xy 52.313076 -298.054193) (xy 52.351197 -298.023068) (xy 52.393818 -297.998461) (xy 52.439834 -297.981009)
			(xy 52.488053 -297.971165) (xy 52.537228 -297.969184) (xy 52.586083 -297.975116) (xy 52.633354 -297.988808)
			(xy 52.677816 -298.009906) (xy 52.718319 -298.037862) (xy 52.753812 -298.071954) (xy 52.783377 -298.111298)
			(xy 52.806248 -298.154875) (xy 52.821832 -298.201556) (xy 52.829727 -298.250133) (xy 52.830222 -298.27474)
			(xy 53.16907 -298.27474) (xy 53.17303 -298.225686) (xy 53.184807 -298.177902) (xy 53.204098 -298.132626)
			(xy 53.230401 -298.09103) (xy 53.263036 -298.054193) (xy 53.301157 -298.023068) (xy 53.343778 -297.998461)
			(xy 53.389794 -297.981009) (xy 53.438013 -297.971165) (xy 53.487188 -297.969184) (xy 53.536043 -297.975116)
			(xy 53.583314 -297.988808) (xy 53.627776 -298.009906) (xy 53.668279 -298.037862) (xy 53.703772 -298.071954)
			(xy 53.733337 -298.111298) (xy 53.756208 -298.154875) (xy 53.771792 -298.201556) (xy 53.779687 -298.250133)
			(xy 53.780182 -298.27474) (xy 54.11903 -298.27474) (xy 54.12299 -298.225686) (xy 54.134767 -298.177902)
			(xy 54.154058 -298.132626) (xy 54.180361 -298.09103) (xy 54.212996 -298.054193) (xy 54.251117 -298.023068)
			(xy 54.293738 -297.998461) (xy 54.339754 -297.981009) (xy 54.387973 -297.971165) (xy 54.437148 -297.969184)
			(xy 54.486003 -297.975116) (xy 54.533274 -297.988808) (xy 54.577736 -298.009906) (xy 54.618239 -298.037862)
			(xy 54.653732 -298.071954) (xy 54.683297 -298.111298) (xy 54.706168 -298.154875) (xy 54.721752 -298.201556)
			(xy 54.729647 -298.250133) (xy 54.730142 -298.27474) (xy 55.06899 -298.27474) (xy 55.07295 -298.225686)
			(xy 55.084727 -298.177902) (xy 55.104018 -298.132626) (xy 55.130321 -298.09103) (xy 55.162956 -298.054193)
			(xy 55.201077 -298.023068) (xy 55.243698 -297.998461) (xy 55.289714 -297.981009) (xy 55.337933 -297.971165)
			(xy 55.387108 -297.969184) (xy 55.435963 -297.975116) (xy 55.483234 -297.988808) (xy 55.527696 -298.009906)
			(xy 55.568199 -298.037862) (xy 55.603692 -298.071954) (xy 55.633257 -298.111298) (xy 55.656128 -298.154875)
			(xy 55.671712 -298.201556) (xy 55.679607 -298.250133) (xy 55.680102 -298.27474) (xy 56.01895 -298.27474)
			(xy 56.02291 -298.225686) (xy 56.034687 -298.177902) (xy 56.053978 -298.132626) (xy 56.080281 -298.09103)
			(xy 56.112916 -298.054193) (xy 56.151037 -298.023068) (xy 56.193658 -297.998461) (xy 56.239674 -297.981009)
			(xy 56.287893 -297.971165) (xy 56.337068 -297.969184) (xy 56.385923 -297.975116) (xy 56.433194 -297.988808)
			(xy 56.477656 -298.009906) (xy 56.518159 -298.037862) (xy 56.553652 -298.071954) (xy 56.583217 -298.111298)
			(xy 56.606088 -298.154875) (xy 56.621672 -298.201556) (xy 56.629567 -298.250133) (xy 56.630062 -298.27474)
			(xy 56.969164 -298.27474) (xy 56.973124 -298.225686) (xy 56.984901 -298.177902) (xy 57.004192 -298.132626)
			(xy 57.030495 -298.09103) (xy 57.06313 -298.054193) (xy 57.101251 -298.023068) (xy 57.143872 -297.998461)
			(xy 57.189888 -297.981009) (xy 57.238107 -297.971165) (xy 57.287282 -297.969184) (xy 57.336137 -297.975116)
			(xy 57.383408 -297.988808) (xy 57.42787 -298.009906) (xy 57.468373 -298.037862) (xy 57.503866 -298.071954)
			(xy 57.533431 -298.111298) (xy 57.556302 -298.154875) (xy 57.571886 -298.201556) (xy 57.579781 -298.250133)
			(xy 57.580276 -298.27474) (xy 57.579781 -298.299347) (xy 57.571886 -298.347924) (xy 57.556302 -298.394605)
			(xy 57.533431 -298.438182) (xy 57.503866 -298.477526) (xy 57.468373 -298.511618) (xy 57.42787 -298.539574)
			(xy 57.383408 -298.560672) (xy 57.336137 -298.574364) (xy 57.287282 -298.580296) (xy 57.238107 -298.578315)
			(xy 57.189888 -298.568471) (xy 57.143872 -298.551019) (xy 57.101251 -298.526412) (xy 57.06313 -298.495287)
			(xy 57.030495 -298.45845) (xy 57.004192 -298.416854) (xy 56.984901 -298.371578) (xy 56.973124 -298.323794)
			(xy 56.969164 -298.27474) (xy 56.630062 -298.27474) (xy 56.629567 -298.299347) (xy 56.621672 -298.347924)
			(xy 56.606088 -298.394605) (xy 56.583217 -298.438182) (xy 56.553652 -298.477526) (xy 56.518159 -298.511618)
			(xy 56.477656 -298.539574) (xy 56.433194 -298.560672) (xy 56.385923 -298.574364) (xy 56.337068 -298.580296)
			(xy 56.287893 -298.578315) (xy 56.239674 -298.568471) (xy 56.193658 -298.551019) (xy 56.151037 -298.526412)
			(xy 56.112916 -298.495287) (xy 56.080281 -298.45845) (xy 56.053978 -298.416854) (xy 56.034687 -298.371578)
			(xy 56.02291 -298.323794) (xy 56.01895 -298.27474) (xy 55.680102 -298.27474) (xy 55.679607 -298.299347)
			(xy 55.671712 -298.347924) (xy 55.656128 -298.394605) (xy 55.633257 -298.438182) (xy 55.603692 -298.477526)
			(xy 55.568199 -298.511618) (xy 55.527696 -298.539574) (xy 55.483234 -298.560672) (xy 55.435963 -298.574364)
			(xy 55.387108 -298.580296) (xy 55.337933 -298.578315) (xy 55.289714 -298.568471) (xy 55.243698 -298.551019)
			(xy 55.201077 -298.526412) (xy 55.162956 -298.495287) (xy 55.130321 -298.45845) (xy 55.104018 -298.416854)
			(xy 55.084727 -298.371578) (xy 55.07295 -298.323794) (xy 55.06899 -298.27474) (xy 54.730142 -298.27474)
			(xy 54.729647 -298.299347) (xy 54.721752 -298.347924) (xy 54.706168 -298.394605) (xy 54.683297 -298.438182)
			(xy 54.653732 -298.477526) (xy 54.618239 -298.511618) (xy 54.577736 -298.539574) (xy 54.533274 -298.560672)
			(xy 54.486003 -298.574364) (xy 54.437148 -298.580296) (xy 54.387973 -298.578315) (xy 54.339754 -298.568471)
			(xy 54.293738 -298.551019) (xy 54.251117 -298.526412) (xy 54.212996 -298.495287) (xy 54.180361 -298.45845)
			(xy 54.154058 -298.416854) (xy 54.134767 -298.371578) (xy 54.12299 -298.323794) (xy 54.11903 -298.27474)
			(xy 53.780182 -298.27474) (xy 53.779687 -298.299347) (xy 53.771792 -298.347924) (xy 53.756208 -298.394605)
			(xy 53.733337 -298.438182) (xy 53.703772 -298.477526) (xy 53.668279 -298.511618) (xy 53.627776 -298.539574)
			(xy 53.583314 -298.560672) (xy 53.536043 -298.574364) (xy 53.487188 -298.580296) (xy 53.438013 -298.578315)
			(xy 53.389794 -298.568471) (xy 53.343778 -298.551019) (xy 53.301157 -298.526412) (xy 53.263036 -298.495287)
			(xy 53.230401 -298.45845) (xy 53.204098 -298.416854) (xy 53.184807 -298.371578) (xy 53.17303 -298.323794)
			(xy 53.16907 -298.27474) (xy 52.830222 -298.27474) (xy 52.829727 -298.299347) (xy 52.821832 -298.347924)
			(xy 52.806248 -298.394605) (xy 52.783377 -298.438182) (xy 52.753812 -298.477526) (xy 52.718319 -298.511618)
			(xy 52.677816 -298.539574) (xy 52.633354 -298.560672) (xy 52.586083 -298.574364) (xy 52.537228 -298.580296)
			(xy 52.488053 -298.578315) (xy 52.439834 -298.568471) (xy 52.393818 -298.551019) (xy 52.351197 -298.526412)
			(xy 52.313076 -298.495287) (xy 52.280441 -298.45845) (xy 52.254138 -298.416854) (xy 52.234847 -298.371578)
			(xy 52.22307 -298.323794) (xy 52.21911 -298.27474) (xy 51.880262 -298.27474) (xy 51.879767 -298.299347)
			(xy 51.871872 -298.347924) (xy 51.856288 -298.394605) (xy 51.833417 -298.438182) (xy 51.803852 -298.477526)
			(xy 51.768359 -298.511618) (xy 51.727856 -298.539574) (xy 51.683394 -298.560672) (xy 51.636123 -298.574364)
			(xy 51.587268 -298.580296) (xy 51.538093 -298.578315) (xy 51.489874 -298.568471) (xy 51.443858 -298.551019)
			(xy 51.401237 -298.526412) (xy 51.363116 -298.495287) (xy 51.330481 -298.45845) (xy 51.304178 -298.416854)
			(xy 51.284887 -298.371578) (xy 51.27311 -298.323794) (xy 51.26915 -298.27474) (xy 50.930302 -298.27474)
			(xy 50.929807 -298.299347) (xy 50.921912 -298.347924) (xy 50.906328 -298.394605) (xy 50.883457 -298.438182)
			(xy 50.853892 -298.477526) (xy 50.818399 -298.511618) (xy 50.777896 -298.539574) (xy 50.733434 -298.560672)
			(xy 50.686163 -298.574364) (xy 50.637308 -298.580296) (xy 50.588133 -298.578315) (xy 50.539914 -298.568471)
			(xy 50.493898 -298.551019) (xy 50.451277 -298.526412) (xy 50.413156 -298.495287) (xy 50.380521 -298.45845)
			(xy 50.354218 -298.416854) (xy 50.334927 -298.371578) (xy 50.32315 -298.323794) (xy 50.31919 -298.27474)
			(xy 50.15865 -298.27474) (xy 50.15865 -300.174914) (xy 50.31919 -300.174914) (xy 50.32315 -300.12586)
			(xy 50.334927 -300.078076) (xy 50.354218 -300.0328) (xy 50.380521 -299.991204) (xy 50.413156 -299.954367)
			(xy 50.451277 -299.923242) (xy 50.493898 -299.898635) (xy 50.539914 -299.881183) (xy 50.588133 -299.871339)
			(xy 50.637308 -299.869358) (xy 50.686163 -299.87529) (xy 50.733434 -299.888982) (xy 50.777896 -299.91008)
			(xy 50.818399 -299.938036) (xy 50.853892 -299.972128) (xy 50.883457 -300.011472) (xy 50.906328 -300.055049)
			(xy 50.921912 -300.10173) (xy 50.929807 -300.150307) (xy 50.930302 -300.174914) (xy 51.26915 -300.174914)
			(xy 51.27311 -300.12586) (xy 51.284887 -300.078076) (xy 51.304178 -300.0328) (xy 51.330481 -299.991204)
			(xy 51.363116 -299.954367) (xy 51.401237 -299.923242) (xy 51.443858 -299.898635) (xy 51.489874 -299.881183)
			(xy 51.538093 -299.871339) (xy 51.587268 -299.869358) (xy 51.636123 -299.87529) (xy 51.683394 -299.888982)
			(xy 51.727856 -299.91008) (xy 51.768359 -299.938036) (xy 51.803852 -299.972128) (xy 51.833417 -300.011472)
			(xy 51.856288 -300.055049) (xy 51.871872 -300.10173) (xy 51.879767 -300.150307) (xy 51.880262 -300.174914)
			(xy 52.21911 -300.174914) (xy 52.22307 -300.12586) (xy 52.234847 -300.078076) (xy 52.254138 -300.0328)
			(xy 52.280441 -299.991204) (xy 52.313076 -299.954367) (xy 52.351197 -299.923242) (xy 52.393818 -299.898635)
			(xy 52.439834 -299.881183) (xy 52.488053 -299.871339) (xy 52.537228 -299.869358) (xy 52.586083 -299.87529)
			(xy 52.633354 -299.888982) (xy 52.677816 -299.91008) (xy 52.718319 -299.938036) (xy 52.753812 -299.972128)
			(xy 52.783377 -300.011472) (xy 52.806248 -300.055049) (xy 52.821832 -300.10173) (xy 52.829727 -300.150307)
			(xy 52.830222 -300.174914) (xy 53.16907 -300.174914) (xy 53.17303 -300.12586) (xy 53.184807 -300.078076)
			(xy 53.204098 -300.0328) (xy 53.230401 -299.991204) (xy 53.263036 -299.954367) (xy 53.301157 -299.923242)
			(xy 53.343778 -299.898635) (xy 53.389794 -299.881183) (xy 53.438013 -299.871339) (xy 53.487188 -299.869358)
			(xy 53.536043 -299.87529) (xy 53.583314 -299.888982) (xy 53.627776 -299.91008) (xy 53.668279 -299.938036)
			(xy 53.703772 -299.972128) (xy 53.733337 -300.011472) (xy 53.756208 -300.055049) (xy 53.771792 -300.10173)
			(xy 53.779687 -300.150307) (xy 53.780182 -300.174914) (xy 54.11903 -300.174914) (xy 54.12299 -300.12586)
			(xy 54.134767 -300.078076) (xy 54.154058 -300.0328) (xy 54.180361 -299.991204) (xy 54.212996 -299.954367)
			(xy 54.251117 -299.923242) (xy 54.293738 -299.898635) (xy 54.339754 -299.881183) (xy 54.387973 -299.871339)
			(xy 54.437148 -299.869358) (xy 54.486003 -299.87529) (xy 54.533274 -299.888982) (xy 54.577736 -299.91008)
			(xy 54.618239 -299.938036) (xy 54.653732 -299.972128) (xy 54.683297 -300.011472) (xy 54.706168 -300.055049)
			(xy 54.721752 -300.10173) (xy 54.729647 -300.150307) (xy 54.730142 -300.174914) (xy 55.06899 -300.174914)
			(xy 55.07295 -300.12586) (xy 55.084727 -300.078076) (xy 55.104018 -300.0328) (xy 55.130321 -299.991204)
			(xy 55.162956 -299.954367) (xy 55.201077 -299.923242) (xy 55.243698 -299.898635) (xy 55.289714 -299.881183)
			(xy 55.337933 -299.871339) (xy 55.387108 -299.869358) (xy 55.435963 -299.87529) (xy 55.483234 -299.888982)
			(xy 55.527696 -299.91008) (xy 55.568199 -299.938036) (xy 55.603692 -299.972128) (xy 55.633257 -300.011472)
			(xy 55.656128 -300.055049) (xy 55.671712 -300.10173) (xy 55.679607 -300.150307) (xy 55.680102 -300.174914)
			(xy 56.01895 -300.174914) (xy 56.02291 -300.12586) (xy 56.034687 -300.078076) (xy 56.053978 -300.0328)
			(xy 56.080281 -299.991204) (xy 56.112916 -299.954367) (xy 56.151037 -299.923242) (xy 56.193658 -299.898635)
			(xy 56.239674 -299.881183) (xy 56.287893 -299.871339) (xy 56.337068 -299.869358) (xy 56.385923 -299.87529)
			(xy 56.433194 -299.888982) (xy 56.477656 -299.91008) (xy 56.518159 -299.938036) (xy 56.553652 -299.972128)
			(xy 56.583217 -300.011472) (xy 56.606088 -300.055049) (xy 56.621672 -300.10173) (xy 56.629567 -300.150307)
			(xy 56.630062 -300.174914) (xy 56.969164 -300.174914) (xy 56.973124 -300.12586) (xy 56.984901 -300.078076)
			(xy 57.004192 -300.0328) (xy 57.030495 -299.991204) (xy 57.06313 -299.954367) (xy 57.101251 -299.923242)
			(xy 57.143872 -299.898635) (xy 57.189888 -299.881183) (xy 57.238107 -299.871339) (xy 57.287282 -299.869358)
			(xy 57.336137 -299.87529) (xy 57.383408 -299.888982) (xy 57.42787 -299.91008) (xy 57.468373 -299.938036)
			(xy 57.503866 -299.972128) (xy 57.533431 -300.011472) (xy 57.556302 -300.055049) (xy 57.571886 -300.10173)
			(xy 57.579781 -300.150307) (xy 57.580276 -300.174914) (xy 57.579781 -300.199521) (xy 57.571886 -300.248098)
			(xy 57.556302 -300.294779) (xy 57.533431 -300.338356) (xy 57.503866 -300.3777) (xy 57.468373 -300.411792)
			(xy 57.42787 -300.439748) (xy 57.383408 -300.460846) (xy 57.336137 -300.474538) (xy 57.287282 -300.48047)
			(xy 57.238107 -300.478489) (xy 57.189888 -300.468645) (xy 57.143872 -300.451193) (xy 57.101251 -300.426586)
			(xy 57.06313 -300.395461) (xy 57.030495 -300.358624) (xy 57.004192 -300.317028) (xy 56.984901 -300.271752)
			(xy 56.973124 -300.223968) (xy 56.969164 -300.174914) (xy 56.630062 -300.174914) (xy 56.629567 -300.199521)
			(xy 56.621672 -300.248098) (xy 56.606088 -300.294779) (xy 56.583217 -300.338356) (xy 56.553652 -300.3777)
			(xy 56.518159 -300.411792) (xy 56.477656 -300.439748) (xy 56.433194 -300.460846) (xy 56.385923 -300.474538)
			(xy 56.337068 -300.48047) (xy 56.287893 -300.478489) (xy 56.239674 -300.468645) (xy 56.193658 -300.451193)
			(xy 56.151037 -300.426586) (xy 56.112916 -300.395461) (xy 56.080281 -300.358624) (xy 56.053978 -300.317028)
			(xy 56.034687 -300.271752) (xy 56.02291 -300.223968) (xy 56.01895 -300.174914) (xy 55.680102 -300.174914)
			(xy 55.679607 -300.199521) (xy 55.671712 -300.248098) (xy 55.656128 -300.294779) (xy 55.633257 -300.338356)
			(xy 55.603692 -300.3777) (xy 55.568199 -300.411792) (xy 55.527696 -300.439748) (xy 55.483234 -300.460846)
			(xy 55.435963 -300.474538) (xy 55.387108 -300.48047) (xy 55.337933 -300.478489) (xy 55.289714 -300.468645)
			(xy 55.243698 -300.451193) (xy 55.201077 -300.426586) (xy 55.162956 -300.395461) (xy 55.130321 -300.358624)
			(xy 55.104018 -300.317028) (xy 55.084727 -300.271752) (xy 55.07295 -300.223968) (xy 55.06899 -300.174914)
			(xy 54.730142 -300.174914) (xy 54.729647 -300.199521) (xy 54.721752 -300.248098) (xy 54.706168 -300.294779)
			(xy 54.683297 -300.338356) (xy 54.653732 -300.3777) (xy 54.618239 -300.411792) (xy 54.577736 -300.439748)
			(xy 54.533274 -300.460846) (xy 54.486003 -300.474538) (xy 54.437148 -300.48047) (xy 54.387973 -300.478489)
			(xy 54.339754 -300.468645) (xy 54.293738 -300.451193) (xy 54.251117 -300.426586) (xy 54.212996 -300.395461)
			(xy 54.180361 -300.358624) (xy 54.154058 -300.317028) (xy 54.134767 -300.271752) (xy 54.12299 -300.223968)
			(xy 54.11903 -300.174914) (xy 53.780182 -300.174914) (xy 53.779687 -300.199521) (xy 53.771792 -300.248098)
			(xy 53.756208 -300.294779) (xy 53.733337 -300.338356) (xy 53.703772 -300.3777) (xy 53.668279 -300.411792)
			(xy 53.627776 -300.439748) (xy 53.583314 -300.460846) (xy 53.536043 -300.474538) (xy 53.487188 -300.48047)
			(xy 53.438013 -300.478489) (xy 53.389794 -300.468645) (xy 53.343778 -300.451193) (xy 53.301157 -300.426586)
			(xy 53.263036 -300.395461) (xy 53.230401 -300.358624) (xy 53.204098 -300.317028) (xy 53.184807 -300.271752)
			(xy 53.17303 -300.223968) (xy 53.16907 -300.174914) (xy 52.830222 -300.174914) (xy 52.829727 -300.199521)
			(xy 52.821832 -300.248098) (xy 52.806248 -300.294779) (xy 52.783377 -300.338356) (xy 52.753812 -300.3777)
			(xy 52.718319 -300.411792) (xy 52.677816 -300.439748) (xy 52.633354 -300.460846) (xy 52.586083 -300.474538)
			(xy 52.537228 -300.48047) (xy 52.488053 -300.478489) (xy 52.439834 -300.468645) (xy 52.393818 -300.451193)
			(xy 52.351197 -300.426586) (xy 52.313076 -300.395461) (xy 52.280441 -300.358624) (xy 52.254138 -300.317028)
			(xy 52.234847 -300.271752) (xy 52.22307 -300.223968) (xy 52.21911 -300.174914) (xy 51.880262 -300.174914)
			(xy 51.879767 -300.199521) (xy 51.871872 -300.248098) (xy 51.856288 -300.294779) (xy 51.833417 -300.338356)
			(xy 51.803852 -300.3777) (xy 51.768359 -300.411792) (xy 51.727856 -300.439748) (xy 51.683394 -300.460846)
			(xy 51.636123 -300.474538) (xy 51.587268 -300.48047) (xy 51.538093 -300.478489) (xy 51.489874 -300.468645)
			(xy 51.443858 -300.451193) (xy 51.401237 -300.426586) (xy 51.363116 -300.395461) (xy 51.330481 -300.358624)
			(xy 51.304178 -300.317028) (xy 51.284887 -300.271752) (xy 51.27311 -300.223968) (xy 51.26915 -300.174914)
			(xy 50.930302 -300.174914) (xy 50.929807 -300.199521) (xy 50.921912 -300.248098) (xy 50.906328 -300.294779)
			(xy 50.883457 -300.338356) (xy 50.853892 -300.3777) (xy 50.818399 -300.411792) (xy 50.777896 -300.439748)
			(xy 50.733434 -300.460846) (xy 50.686163 -300.474538) (xy 50.637308 -300.48047) (xy 50.588133 -300.478489)
			(xy 50.539914 -300.468645) (xy 50.493898 -300.451193) (xy 50.451277 -300.426586) (xy 50.413156 -300.395461)
			(xy 50.380521 -300.358624) (xy 50.354218 -300.317028) (xy 50.334927 -300.271752) (xy 50.32315 -300.223968)
			(xy 50.31919 -300.174914) (xy 50.15865 -300.174914) (xy 50.15865 -300.355762) (xy 50.158214 -300.365826)
			(xy 50.150478 -300.384409) (xy 50.143664 -300.39183) (xy 50.038 -300.497494) (xy 50.030602 -300.504341)
			(xy 50.012004 -300.512077) (xy 50.001932 -300.51248) (xy 49.024794 -300.51248) (xy 49.014724 -300.512904)
			(xy 48.996119 -300.520617) (xy 48.988726 -300.527466) (xy 48.848772 -300.66742) (xy 48.840794 -300.676381)
			(xy 48.833378 -300.699167) (xy 48.834548 -300.711108) (xy 48.846486 -300.787562) (xy 48.847966 -300.795483)
			(xy 48.855212 -300.809866) (xy 48.86071 -300.815756) (xy 48.869092 -300.824138) (xy 48.871769 -300.826747)
			(xy 48.877764 -300.831209) (xy 48.88103 -300.833028) (xy 48.903924 -300.845884) (xy 48.945687 -300.877703)
			(xy 48.981903 -300.915716) (xy 49.011665 -300.958968) (xy 49.034227 -301.006377) (xy 49.049021 -301.056753)
			(xy 49.055679 -301.108832) (xy 49.055175 -301.124874) (xy 49.368976 -301.124874) (xy 49.372936 -301.07582)
			(xy 49.384713 -301.028036) (xy 49.404004 -300.98276) (xy 49.430307 -300.941164) (xy 49.462942 -300.904327)
			(xy 49.501063 -300.873202) (xy 49.543684 -300.848595) (xy 49.5897 -300.831143) (xy 49.637919 -300.821299)
			(xy 49.687094 -300.819318) (xy 49.735949 -300.82525) (xy 49.78322 -300.838942) (xy 49.827682 -300.86004)
			(xy 49.868185 -300.887996) (xy 49.903678 -300.922088) (xy 49.933243 -300.961432) (xy 49.956114 -301.005009)
			(xy 49.971698 -301.05169) (xy 49.979593 -301.100267) (xy 49.980088 -301.124874) (xy 49.979593 -301.149481)
			(xy 49.971698 -301.198058) (xy 49.956114 -301.244739) (xy 49.933243 -301.288316) (xy 49.903678 -301.32766)
			(xy 49.868185 -301.361752) (xy 49.827682 -301.389708) (xy 49.78322 -301.410806) (xy 49.735949 -301.424498)
			(xy 49.687094 -301.43043) (xy 49.637919 -301.428449) (xy 49.5897 -301.418605) (xy 49.543684 -301.401153)
			(xy 49.501063 -301.376546) (xy 49.462942 -301.345421) (xy 49.430307 -301.308584) (xy 49.404004 -301.266988)
			(xy 49.384713 -301.221712) (xy 49.372936 -301.173928) (xy 49.368976 -301.124874) (xy 49.055175 -301.124874)
			(xy 49.054031 -301.16131) (xy 49.04412 -301.212869) (xy 49.026195 -301.262217) (xy 49.013872 -301.285402)
			(xy 49.001821 -301.306231) (xy 48.972622 -301.344481) (xy 48.938183 -301.37809) (xy 48.899235 -301.40635)
			(xy 48.856599 -301.428661) (xy 48.83404 -301.43704) (xy 48.826166 -301.439834) (xy 48.805846 -301.455582)
			(xy 48.798988 -301.460916) (xy 48.777906 -301.49292) (xy 48.773842 -301.509176) (xy 48.774604 -301.517812)
			(xy 48.77562 -301.54499) (xy 48.77562 -302.074834) (xy 49.368976 -302.074834) (xy 49.372936 -302.02578)
			(xy 49.384713 -301.977996) (xy 49.404004 -301.93272) (xy 49.430307 -301.891124) (xy 49.462942 -301.854287)
			(xy 49.501063 -301.823162) (xy 49.543684 -301.798555) (xy 49.5897 -301.781103) (xy 49.637919 -301.771259)
			(xy 49.687094 -301.769278) (xy 49.735949 -301.77521) (xy 49.78322 -301.788902) (xy 49.827682 -301.81)
			(xy 49.868185 -301.837956) (xy 49.903678 -301.872048) (xy 49.933243 -301.911392) (xy 49.956114 -301.954969)
			(xy 49.971698 -302.00165) (xy 49.979593 -302.050227) (xy 49.980088 -302.074834) (xy 50.31919 -302.074834)
			(xy 50.32315 -302.02578) (xy 50.334927 -301.977996) (xy 50.354218 -301.93272) (xy 50.380521 -301.891124)
			(xy 50.413156 -301.854287) (xy 50.451277 -301.823162) (xy 50.493898 -301.798555) (xy 50.539914 -301.781103)
			(xy 50.588133 -301.771259) (xy 50.637308 -301.769278) (xy 50.686163 -301.77521) (xy 50.733434 -301.788902)
			(xy 50.777896 -301.81) (xy 50.818399 -301.837956) (xy 50.853892 -301.872048) (xy 50.883457 -301.911392)
			(xy 50.906328 -301.954969) (xy 50.921912 -302.00165) (xy 50.929807 -302.050227) (xy 50.930302 -302.074834)
			(xy 51.26915 -302.074834) (xy 51.27311 -302.02578) (xy 51.284887 -301.977996) (xy 51.304178 -301.93272)
			(xy 51.330481 -301.891124) (xy 51.363116 -301.854287) (xy 51.401237 -301.823162) (xy 51.443858 -301.798555)
			(xy 51.489874 -301.781103) (xy 51.538093 -301.771259) (xy 51.587268 -301.769278) (xy 51.636123 -301.77521)
			(xy 51.683394 -301.788902) (xy 51.727856 -301.81) (xy 51.768359 -301.837956) (xy 51.803852 -301.872048)
			(xy 51.833417 -301.911392) (xy 51.856288 -301.954969) (xy 51.871872 -302.00165) (xy 51.879767 -302.050227)
			(xy 51.880262 -302.074834) (xy 52.21911 -302.074834) (xy 52.22307 -302.02578) (xy 52.234847 -301.977996)
			(xy 52.254138 -301.93272) (xy 52.280441 -301.891124) (xy 52.313076 -301.854287) (xy 52.351197 -301.823162)
			(xy 52.393818 -301.798555) (xy 52.439834 -301.781103) (xy 52.488053 -301.771259) (xy 52.537228 -301.769278)
			(xy 52.586083 -301.77521) (xy 52.633354 -301.788902) (xy 52.677816 -301.81) (xy 52.718319 -301.837956)
			(xy 52.753812 -301.872048) (xy 52.783377 -301.911392) (xy 52.806248 -301.954969) (xy 52.821832 -302.00165)
			(xy 52.829727 -302.050227) (xy 52.830222 -302.074834) (xy 53.16907 -302.074834) (xy 53.17303 -302.02578)
			(xy 53.184807 -301.977996) (xy 53.204098 -301.93272) (xy 53.230401 -301.891124) (xy 53.263036 -301.854287)
			(xy 53.301157 -301.823162) (xy 53.343778 -301.798555) (xy 53.389794 -301.781103) (xy 53.438013 -301.771259)
			(xy 53.487188 -301.769278) (xy 53.536043 -301.77521) (xy 53.583314 -301.788902) (xy 53.627776 -301.81)
			(xy 53.668279 -301.837956) (xy 53.703772 -301.872048) (xy 53.733337 -301.911392) (xy 53.756208 -301.954969)
			(xy 53.771792 -302.00165) (xy 53.779687 -302.050227) (xy 53.780182 -302.074834) (xy 54.11903 -302.074834)
			(xy 54.12299 -302.02578) (xy 54.134767 -301.977996) (xy 54.154058 -301.93272) (xy 54.180361 -301.891124)
			(xy 54.212996 -301.854287) (xy 54.251117 -301.823162) (xy 54.293738 -301.798555) (xy 54.339754 -301.781103)
			(xy 54.387973 -301.771259) (xy 54.437148 -301.769278) (xy 54.486003 -301.77521) (xy 54.533274 -301.788902)
			(xy 54.577736 -301.81) (xy 54.618239 -301.837956) (xy 54.653732 -301.872048) (xy 54.683297 -301.911392)
			(xy 54.706168 -301.954969) (xy 54.721752 -302.00165) (xy 54.729647 -302.050227) (xy 54.730142 -302.074834)
			(xy 55.06899 -302.074834) (xy 55.07295 -302.02578) (xy 55.084727 -301.977996) (xy 55.104018 -301.93272)
			(xy 55.130321 -301.891124) (xy 55.162956 -301.854287) (xy 55.201077 -301.823162) (xy 55.243698 -301.798555)
			(xy 55.289714 -301.781103) (xy 55.337933 -301.771259) (xy 55.387108 -301.769278) (xy 55.435963 -301.77521)
			(xy 55.483234 -301.788902) (xy 55.527696 -301.81) (xy 55.568199 -301.837956) (xy 55.603692 -301.872048)
			(xy 55.633257 -301.911392) (xy 55.656128 -301.954969) (xy 55.671712 -302.00165) (xy 55.679607 -302.050227)
			(xy 55.680102 -302.074834) (xy 56.01895 -302.074834) (xy 56.02291 -302.02578) (xy 56.034687 -301.977996)
			(xy 56.053978 -301.93272) (xy 56.080281 -301.891124) (xy 56.112916 -301.854287) (xy 56.151037 -301.823162)
			(xy 56.193658 -301.798555) (xy 56.239674 -301.781103) (xy 56.287893 -301.771259) (xy 56.337068 -301.769278)
			(xy 56.385923 -301.77521) (xy 56.433194 -301.788902) (xy 56.477656 -301.81) (xy 56.518159 -301.837956)
			(xy 56.553652 -301.872048) (xy 56.583217 -301.911392) (xy 56.606088 -301.954969) (xy 56.621672 -302.00165)
			(xy 56.629567 -302.050227) (xy 56.630062 -302.074834) (xy 56.969164 -302.074834) (xy 56.973124 -302.02578)
			(xy 56.984901 -301.977996) (xy 57.004192 -301.93272) (xy 57.030495 -301.891124) (xy 57.06313 -301.854287)
			(xy 57.101251 -301.823162) (xy 57.143872 -301.798555) (xy 57.189888 -301.781103) (xy 57.238107 -301.771259)
			(xy 57.287282 -301.769278) (xy 57.336137 -301.77521) (xy 57.383408 -301.788902) (xy 57.42787 -301.81)
			(xy 57.468373 -301.837956) (xy 57.503866 -301.872048) (xy 57.533431 -301.911392) (xy 57.556302 -301.954969)
			(xy 57.571886 -302.00165) (xy 57.579781 -302.050227) (xy 57.580276 -302.074834) (xy 57.579781 -302.099441)
			(xy 57.571886 -302.148018) (xy 57.556302 -302.194699) (xy 57.533431 -302.238276) (xy 57.503866 -302.27762)
			(xy 57.468373 -302.311712) (xy 57.42787 -302.339668) (xy 57.383408 -302.360766) (xy 57.336137 -302.374458)
			(xy 57.287282 -302.38039) (xy 57.238107 -302.378409) (xy 57.189888 -302.368565) (xy 57.143872 -302.351113)
			(xy 57.101251 -302.326506) (xy 57.06313 -302.295381) (xy 57.030495 -302.258544) (xy 57.004192 -302.216948)
			(xy 56.984901 -302.171672) (xy 56.973124 -302.123888) (xy 56.969164 -302.074834) (xy 56.630062 -302.074834)
			(xy 56.629567 -302.099441) (xy 56.621672 -302.148018) (xy 56.606088 -302.194699) (xy 56.583217 -302.238276)
			(xy 56.553652 -302.27762) (xy 56.518159 -302.311712) (xy 56.477656 -302.339668) (xy 56.433194 -302.360766)
			(xy 56.385923 -302.374458) (xy 56.337068 -302.38039) (xy 56.287893 -302.378409) (xy 56.239674 -302.368565)
			(xy 56.193658 -302.351113) (xy 56.151037 -302.326506) (xy 56.112916 -302.295381) (xy 56.080281 -302.258544)
			(xy 56.053978 -302.216948) (xy 56.034687 -302.171672) (xy 56.02291 -302.123888) (xy 56.01895 -302.074834)
			(xy 55.680102 -302.074834) (xy 55.679607 -302.099441) (xy 55.671712 -302.148018) (xy 55.656128 -302.194699)
			(xy 55.633257 -302.238276) (xy 55.603692 -302.27762) (xy 55.568199 -302.311712) (xy 55.527696 -302.339668)
			(xy 55.483234 -302.360766) (xy 55.435963 -302.374458) (xy 55.387108 -302.38039) (xy 55.337933 -302.378409)
			(xy 55.289714 -302.368565) (xy 55.243698 -302.351113) (xy 55.201077 -302.326506) (xy 55.162956 -302.295381)
			(xy 55.130321 -302.258544) (xy 55.104018 -302.216948) (xy 55.084727 -302.171672) (xy 55.07295 -302.123888)
			(xy 55.06899 -302.074834) (xy 54.730142 -302.074834) (xy 54.729647 -302.099441) (xy 54.721752 -302.148018)
			(xy 54.706168 -302.194699) (xy 54.683297 -302.238276) (xy 54.653732 -302.27762) (xy 54.618239 -302.311712)
			(xy 54.577736 -302.339668) (xy 54.533274 -302.360766) (xy 54.486003 -302.374458) (xy 54.437148 -302.38039)
			(xy 54.387973 -302.378409) (xy 54.339754 -302.368565) (xy 54.293738 -302.351113) (xy 54.251117 -302.326506)
			(xy 54.212996 -302.295381) (xy 54.180361 -302.258544) (xy 54.154058 -302.216948) (xy 54.134767 -302.171672)
			(xy 54.12299 -302.123888) (xy 54.11903 -302.074834) (xy 53.780182 -302.074834) (xy 53.779687 -302.099441)
			(xy 53.771792 -302.148018) (xy 53.756208 -302.194699) (xy 53.733337 -302.238276) (xy 53.703772 -302.27762)
			(xy 53.668279 -302.311712) (xy 53.627776 -302.339668) (xy 53.583314 -302.360766) (xy 53.536043 -302.374458)
			(xy 53.487188 -302.38039) (xy 53.438013 -302.378409) (xy 53.389794 -302.368565) (xy 53.343778 -302.351113)
			(xy 53.301157 -302.326506) (xy 53.263036 -302.295381) (xy 53.230401 -302.258544) (xy 53.204098 -302.216948)
			(xy 53.184807 -302.171672) (xy 53.17303 -302.123888) (xy 53.16907 -302.074834) (xy 52.830222 -302.074834)
			(xy 52.829727 -302.099441) (xy 52.821832 -302.148018) (xy 52.806248 -302.194699) (xy 52.783377 -302.238276)
			(xy 52.753812 -302.27762) (xy 52.718319 -302.311712) (xy 52.677816 -302.339668) (xy 52.633354 -302.360766)
			(xy 52.586083 -302.374458) (xy 52.537228 -302.38039) (xy 52.488053 -302.378409) (xy 52.439834 -302.368565)
			(xy 52.393818 -302.351113) (xy 52.351197 -302.326506) (xy 52.313076 -302.295381) (xy 52.280441 -302.258544)
			(xy 52.254138 -302.216948) (xy 52.234847 -302.171672) (xy 52.22307 -302.123888) (xy 52.21911 -302.074834)
			(xy 51.880262 -302.074834) (xy 51.879767 -302.099441) (xy 51.871872 -302.148018) (xy 51.856288 -302.194699)
			(xy 51.833417 -302.238276) (xy 51.803852 -302.27762) (xy 51.768359 -302.311712) (xy 51.727856 -302.339668)
			(xy 51.683394 -302.360766) (xy 51.636123 -302.374458) (xy 51.587268 -302.38039) (xy 51.538093 -302.378409)
			(xy 51.489874 -302.368565) (xy 51.443858 -302.351113) (xy 51.401237 -302.326506) (xy 51.363116 -302.295381)
			(xy 51.330481 -302.258544) (xy 51.304178 -302.216948) (xy 51.284887 -302.171672) (xy 51.27311 -302.123888)
			(xy 51.26915 -302.074834) (xy 50.930302 -302.074834) (xy 50.929807 -302.099441) (xy 50.921912 -302.148018)
			(xy 50.906328 -302.194699) (xy 50.883457 -302.238276) (xy 50.853892 -302.27762) (xy 50.818399 -302.311712)
			(xy 50.777896 -302.339668) (xy 50.733434 -302.360766) (xy 50.686163 -302.374458) (xy 50.637308 -302.38039)
			(xy 50.588133 -302.378409) (xy 50.539914 -302.368565) (xy 50.493898 -302.351113) (xy 50.451277 -302.326506)
			(xy 50.413156 -302.295381) (xy 50.380521 -302.258544) (xy 50.354218 -302.216948) (xy 50.334927 -302.171672)
			(xy 50.32315 -302.123888) (xy 50.31919 -302.074834) (xy 49.980088 -302.074834) (xy 49.979593 -302.099441)
			(xy 49.971698 -302.148018) (xy 49.956114 -302.194699) (xy 49.933243 -302.238276) (xy 49.903678 -302.27762)
			(xy 49.868185 -302.311712) (xy 49.827682 -302.339668) (xy 49.78322 -302.360766) (xy 49.735949 -302.374458)
			(xy 49.687094 -302.38039) (xy 49.637919 -302.378409) (xy 49.5897 -302.368565) (xy 49.543684 -302.351113)
			(xy 49.501063 -302.326506) (xy 49.462942 -302.295381) (xy 49.430307 -302.258544) (xy 49.404004 -302.216948)
			(xy 49.384713 -302.171672) (xy 49.372936 -302.123888) (xy 49.368976 -302.074834) (xy 48.77562 -302.074834)
			(xy 48.77562 -302.646842) (xy 48.776051 -302.656908) (xy 48.783779 -302.6755) (xy 48.790606 -302.68291)
			(xy 48.79086 -302.683164) (xy 48.80864 -302.700436) (xy 48.814736 -302.703738) (xy 48.824896 -302.709326)
			(xy 48.829468 -302.71085) (xy 48.853959 -302.719544) (xy 48.90009 -302.743471) (xy 48.941914 -302.774315)
			(xy 48.978402 -302.811318) (xy 49.008657 -302.85357) (xy 49.031935 -302.900032) (xy 49.047665 -302.949561)
			(xy 49.055458 -303.000941) (xy 49.055305 -303.024794) (xy 49.368976 -303.024794) (xy 49.372936 -302.97574)
			(xy 49.384713 -302.927956) (xy 49.404004 -302.88268) (xy 49.430307 -302.841084) (xy 49.462942 -302.804247)
			(xy 49.501063 -302.773122) (xy 49.543684 -302.748515) (xy 49.5897 -302.731063) (xy 49.637919 -302.721219)
			(xy 49.687094 -302.719238) (xy 49.735949 -302.72517) (xy 49.78322 -302.738862) (xy 49.827682 -302.75996)
			(xy 49.868185 -302.787916) (xy 49.903678 -302.822008) (xy 49.933243 -302.861352) (xy 49.956114 -302.904929)
			(xy 49.971698 -302.95161) (xy 49.979593 -303.000187) (xy 49.980088 -303.024794) (xy 50.31919 -303.024794)
			(xy 50.32315 -302.97574) (xy 50.334927 -302.927956) (xy 50.354218 -302.88268) (xy 50.380521 -302.841084)
			(xy 50.413156 -302.804247) (xy 50.451277 -302.773122) (xy 50.493898 -302.748515) (xy 50.539914 -302.731063)
			(xy 50.588133 -302.721219) (xy 50.637308 -302.719238) (xy 50.686163 -302.72517) (xy 50.733434 -302.738862)
			(xy 50.777896 -302.75996) (xy 50.818399 -302.787916) (xy 50.853892 -302.822008) (xy 50.883457 -302.861352)
			(xy 50.906328 -302.904929) (xy 50.921912 -302.95161) (xy 50.929807 -303.000187) (xy 50.930302 -303.024794)
			(xy 51.26915 -303.024794) (xy 51.27311 -302.97574) (xy 51.284887 -302.927956) (xy 51.304178 -302.88268)
			(xy 51.330481 -302.841084) (xy 51.363116 -302.804247) (xy 51.401237 -302.773122) (xy 51.443858 -302.748515)
			(xy 51.489874 -302.731063) (xy 51.538093 -302.721219) (xy 51.587268 -302.719238) (xy 51.636123 -302.72517)
			(xy 51.683394 -302.738862) (xy 51.727856 -302.75996) (xy 51.768359 -302.787916) (xy 51.803852 -302.822008)
			(xy 51.833417 -302.861352) (xy 51.856288 -302.904929) (xy 51.871872 -302.95161) (xy 51.879767 -303.000187)
			(xy 51.880262 -303.024794) (xy 52.21911 -303.024794) (xy 52.22307 -302.97574) (xy 52.234847 -302.927956)
			(xy 52.254138 -302.88268) (xy 52.280441 -302.841084) (xy 52.313076 -302.804247) (xy 52.351197 -302.773122)
			(xy 52.393818 -302.748515) (xy 52.439834 -302.731063) (xy 52.488053 -302.721219) (xy 52.537228 -302.719238)
			(xy 52.586083 -302.72517) (xy 52.633354 -302.738862) (xy 52.677816 -302.75996) (xy 52.718319 -302.787916)
			(xy 52.753812 -302.822008) (xy 52.783377 -302.861352) (xy 52.806248 -302.904929) (xy 52.821832 -302.95161)
			(xy 52.829727 -303.000187) (xy 52.830222 -303.024794) (xy 53.16907 -303.024794) (xy 53.17303 -302.97574)
			(xy 53.184807 -302.927956) (xy 53.204098 -302.88268) (xy 53.230401 -302.841084) (xy 53.263036 -302.804247)
			(xy 53.301157 -302.773122) (xy 53.343778 -302.748515) (xy 53.389794 -302.731063) (xy 53.438013 -302.721219)
			(xy 53.487188 -302.719238) (xy 53.536043 -302.72517) (xy 53.583314 -302.738862) (xy 53.627776 -302.75996)
			(xy 53.668279 -302.787916) (xy 53.703772 -302.822008) (xy 53.733337 -302.861352) (xy 53.756208 -302.904929)
			(xy 53.771792 -302.95161) (xy 53.779687 -303.000187) (xy 53.780182 -303.024794) (xy 54.11903 -303.024794)
			(xy 54.12299 -302.97574) (xy 54.134767 -302.927956) (xy 54.154058 -302.88268) (xy 54.180361 -302.841084)
			(xy 54.212996 -302.804247) (xy 54.251117 -302.773122) (xy 54.293738 -302.748515) (xy 54.339754 -302.731063)
			(xy 54.387973 -302.721219) (xy 54.437148 -302.719238) (xy 54.486003 -302.72517) (xy 54.533274 -302.738862)
			(xy 54.577736 -302.75996) (xy 54.618239 -302.787916) (xy 54.653732 -302.822008) (xy 54.683297 -302.861352)
			(xy 54.706168 -302.904929) (xy 54.721752 -302.95161) (xy 54.729647 -303.000187) (xy 54.730142 -303.024794)
			(xy 55.06899 -303.024794) (xy 55.07295 -302.97574) (xy 55.084727 -302.927956) (xy 55.104018 -302.88268)
			(xy 55.130321 -302.841084) (xy 55.162956 -302.804247) (xy 55.201077 -302.773122) (xy 55.243698 -302.748515)
			(xy 55.289714 -302.731063) (xy 55.337933 -302.721219) (xy 55.387108 -302.719238) (xy 55.435963 -302.72517)
			(xy 55.483234 -302.738862) (xy 55.527696 -302.75996) (xy 55.568199 -302.787916) (xy 55.603692 -302.822008)
			(xy 55.633257 -302.861352) (xy 55.656128 -302.904929) (xy 55.671712 -302.95161) (xy 55.679607 -303.000187)
			(xy 55.680102 -303.024794) (xy 56.01895 -303.024794) (xy 56.02291 -302.97574) (xy 56.034687 -302.927956)
			(xy 56.053978 -302.88268) (xy 56.080281 -302.841084) (xy 56.112916 -302.804247) (xy 56.151037 -302.773122)
			(xy 56.193658 -302.748515) (xy 56.239674 -302.731063) (xy 56.287893 -302.721219) (xy 56.337068 -302.719238)
			(xy 56.385923 -302.72517) (xy 56.433194 -302.738862) (xy 56.477656 -302.75996) (xy 56.518159 -302.787916)
			(xy 56.553652 -302.822008) (xy 56.583217 -302.861352) (xy 56.606088 -302.904929) (xy 56.621672 -302.95161)
			(xy 56.629567 -303.000187) (xy 56.630062 -303.024794) (xy 56.969164 -303.024794) (xy 56.973124 -302.97574)
			(xy 56.984901 -302.927956) (xy 57.004192 -302.88268) (xy 57.030495 -302.841084) (xy 57.06313 -302.804247)
			(xy 57.101251 -302.773122) (xy 57.143872 -302.748515) (xy 57.189888 -302.731063) (xy 57.238107 -302.721219)
			(xy 57.287282 -302.719238) (xy 57.336137 -302.72517) (xy 57.383408 -302.738862) (xy 57.42787 -302.75996)
			(xy 57.468373 -302.787916) (xy 57.503866 -302.822008) (xy 57.533431 -302.861352) (xy 57.556302 -302.904929)
			(xy 57.571886 -302.95161) (xy 57.579781 -303.000187) (xy 57.580276 -303.024794) (xy 57.579781 -303.049401)
			(xy 57.571886 -303.097978) (xy 57.556302 -303.144659) (xy 57.533431 -303.188236) (xy 57.503866 -303.22758)
			(xy 57.468373 -303.261672) (xy 57.42787 -303.289628) (xy 57.383408 -303.310726) (xy 57.336137 -303.324418)
			(xy 57.287282 -303.33035) (xy 57.238107 -303.328369) (xy 57.189888 -303.318525) (xy 57.143872 -303.301073)
			(xy 57.101251 -303.276466) (xy 57.06313 -303.245341) (xy 57.030495 -303.208504) (xy 57.004192 -303.166908)
			(xy 56.984901 -303.121632) (xy 56.973124 -303.073848) (xy 56.969164 -303.024794) (xy 56.630062 -303.024794)
			(xy 56.629567 -303.049401) (xy 56.621672 -303.097978) (xy 56.606088 -303.144659) (xy 56.583217 -303.188236)
			(xy 56.553652 -303.22758) (xy 56.518159 -303.261672) (xy 56.477656 -303.289628) (xy 56.433194 -303.310726)
			(xy 56.385923 -303.324418) (xy 56.337068 -303.33035) (xy 56.287893 -303.328369) (xy 56.239674 -303.318525)
			(xy 56.193658 -303.301073) (xy 56.151037 -303.276466) (xy 56.112916 -303.245341) (xy 56.080281 -303.208504)
			(xy 56.053978 -303.166908) (xy 56.034687 -303.121632) (xy 56.02291 -303.073848) (xy 56.01895 -303.024794)
			(xy 55.680102 -303.024794) (xy 55.679607 -303.049401) (xy 55.671712 -303.097978) (xy 55.656128 -303.144659)
			(xy 55.633257 -303.188236) (xy 55.603692 -303.22758) (xy 55.568199 -303.261672) (xy 55.527696 -303.289628)
			(xy 55.483234 -303.310726) (xy 55.435963 -303.324418) (xy 55.387108 -303.33035) (xy 55.337933 -303.328369)
			(xy 55.289714 -303.318525) (xy 55.243698 -303.301073) (xy 55.201077 -303.276466) (xy 55.162956 -303.245341)
			(xy 55.130321 -303.208504) (xy 55.104018 -303.166908) (xy 55.084727 -303.121632) (xy 55.07295 -303.073848)
			(xy 55.06899 -303.024794) (xy 54.730142 -303.024794) (xy 54.729647 -303.049401) (xy 54.721752 -303.097978)
			(xy 54.706168 -303.144659) (xy 54.683297 -303.188236) (xy 54.653732 -303.22758) (xy 54.618239 -303.261672)
			(xy 54.577736 -303.289628) (xy 54.533274 -303.310726) (xy 54.486003 -303.324418) (xy 54.437148 -303.33035)
			(xy 54.387973 -303.328369) (xy 54.339754 -303.318525) (xy 54.293738 -303.301073) (xy 54.251117 -303.276466)
			(xy 54.212996 -303.245341) (xy 54.180361 -303.208504) (xy 54.154058 -303.166908) (xy 54.134767 -303.121632)
			(xy 54.12299 -303.073848) (xy 54.11903 -303.024794) (xy 53.780182 -303.024794) (xy 53.779687 -303.049401)
			(xy 53.771792 -303.097978) (xy 53.756208 -303.144659) (xy 53.733337 -303.188236) (xy 53.703772 -303.22758)
			(xy 53.668279 -303.261672) (xy 53.627776 -303.289628) (xy 53.583314 -303.310726) (xy 53.536043 -303.324418)
			(xy 53.487188 -303.33035) (xy 53.438013 -303.328369) (xy 53.389794 -303.318525) (xy 53.343778 -303.301073)
			(xy 53.301157 -303.276466) (xy 53.263036 -303.245341) (xy 53.230401 -303.208504) (xy 53.204098 -303.166908)
			(xy 53.184807 -303.121632) (xy 53.17303 -303.073848) (xy 53.16907 -303.024794) (xy 52.830222 -303.024794)
			(xy 52.829727 -303.049401) (xy 52.821832 -303.097978) (xy 52.806248 -303.144659) (xy 52.783377 -303.188236)
			(xy 52.753812 -303.22758) (xy 52.718319 -303.261672) (xy 52.677816 -303.289628) (xy 52.633354 -303.310726)
			(xy 52.586083 -303.324418) (xy 52.537228 -303.33035) (xy 52.488053 -303.328369) (xy 52.439834 -303.318525)
			(xy 52.393818 -303.301073) (xy 52.351197 -303.276466) (xy 52.313076 -303.245341) (xy 52.280441 -303.208504)
			(xy 52.254138 -303.166908) (xy 52.234847 -303.121632) (xy 52.22307 -303.073848) (xy 52.21911 -303.024794)
			(xy 51.880262 -303.024794) (xy 51.879767 -303.049401) (xy 51.871872 -303.097978) (xy 51.856288 -303.144659)
			(xy 51.833417 -303.188236) (xy 51.803852 -303.22758) (xy 51.768359 -303.261672) (xy 51.727856 -303.289628)
			(xy 51.683394 -303.310726) (xy 51.636123 -303.324418) (xy 51.587268 -303.33035) (xy 51.538093 -303.328369)
			(xy 51.489874 -303.318525) (xy 51.443858 -303.301073) (xy 51.401237 -303.276466) (xy 51.363116 -303.245341)
			(xy 51.330481 -303.208504) (xy 51.304178 -303.166908) (xy 51.284887 -303.121632) (xy 51.27311 -303.073848)
			(xy 51.26915 -303.024794) (xy 50.930302 -303.024794) (xy 50.929807 -303.049401) (xy 50.921912 -303.097978)
			(xy 50.906328 -303.144659) (xy 50.883457 -303.188236) (xy 50.853892 -303.22758) (xy 50.818399 -303.261672)
			(xy 50.777896 -303.289628) (xy 50.733434 -303.310726) (xy 50.686163 -303.324418) (xy 50.637308 -303.33035)
			(xy 50.588133 -303.328369) (xy 50.539914 -303.318525) (xy 50.493898 -303.301073) (xy 50.451277 -303.276466)
			(xy 50.413156 -303.245341) (xy 50.380521 -303.208504) (xy 50.354218 -303.166908) (xy 50.334927 -303.121632)
			(xy 50.32315 -303.073848) (xy 50.31919 -303.024794) (xy 49.980088 -303.024794) (xy 49.979593 -303.049401)
			(xy 49.971698 -303.097978) (xy 49.956114 -303.144659) (xy 49.933243 -303.188236) (xy 49.903678 -303.22758)
			(xy 49.868185 -303.261672) (xy 49.827682 -303.289628) (xy 49.78322 -303.310726) (xy 49.735949 -303.324418)
			(xy 49.687094 -303.33035) (xy 49.637919 -303.328369) (xy 49.5897 -303.318525) (xy 49.543684 -303.301073)
			(xy 49.501063 -303.276466) (xy 49.462942 -303.245341) (xy 49.430307 -303.208504) (xy 49.404004 -303.166908)
			(xy 49.384713 -303.121632) (xy 49.372936 -303.073848) (xy 49.368976 -303.024794) (xy 49.055305 -303.024794)
			(xy 49.055124 -303.052907) (xy 49.046671 -303.104182) (xy 49.030306 -303.153505) (xy 49.006432 -303.199664)
			(xy 48.975637 -303.241523) (xy 48.938676 -303.278054) (xy 48.896459 -303.308358) (xy 48.850024 -303.33169)
			(xy 48.825404 -303.340008) (xy 48.814482 -303.343564) (xy 48.791876 -303.364392) (xy 48.784503 -303.371915)
			(xy 48.776104 -303.391207) (xy 48.77562 -303.40173) (xy 48.77562 -303.552606) (xy 48.775779 -303.558966)
			(xy 48.778856 -303.571307) (xy 48.781716 -303.57699) (xy 48.785018 -303.582832) (xy 48.7934 -303.591976)
			(xy 48.798734 -303.595278) (xy 48.804068 -303.598834) (xy 48.81372 -303.62271) (xy 48.818349 -303.632747)
			(xy 48.834416 -303.647891) (xy 48.844708 -303.65192) (xy 48.854106 -303.65573) (xy 48.878782 -303.666311)
			(xy 48.924779 -303.693999) (xy 48.965917 -303.728495) (xy 49.001198 -303.768962) (xy 49.029766 -303.814418)
			(xy 49.050926 -303.863759) (xy 49.064167 -303.915788) (xy 49.069165 -303.969243) (xy 49.068819 -303.974754)
			(xy 49.368976 -303.974754) (xy 49.372936 -303.9257) (xy 49.384713 -303.877916) (xy 49.404004 -303.83264)
			(xy 49.430307 -303.791044) (xy 49.462942 -303.754207) (xy 49.501063 -303.723082) (xy 49.543684 -303.698475)
			(xy 49.5897 -303.681023) (xy 49.637919 -303.671179) (xy 49.687094 -303.669198) (xy 49.735949 -303.67513)
			(xy 49.78322 -303.688822) (xy 49.827682 -303.70992) (xy 49.868185 -303.737876) (xy 49.903678 -303.771968)
			(xy 49.933243 -303.811312) (xy 49.956114 -303.854889) (xy 49.971698 -303.90157) (xy 49.979593 -303.950147)
			(xy 49.980088 -303.974754) (xy 50.31919 -303.974754) (xy 50.32315 -303.9257) (xy 50.334927 -303.877916)
			(xy 50.354218 -303.83264) (xy 50.380521 -303.791044) (xy 50.413156 -303.754207) (xy 50.451277 -303.723082)
			(xy 50.493898 -303.698475) (xy 50.539914 -303.681023) (xy 50.588133 -303.671179) (xy 50.637308 -303.669198)
			(xy 50.686163 -303.67513) (xy 50.733434 -303.688822) (xy 50.777896 -303.70992) (xy 50.818399 -303.737876)
			(xy 50.853892 -303.771968) (xy 50.883457 -303.811312) (xy 50.906328 -303.854889) (xy 50.921912 -303.90157)
			(xy 50.929807 -303.950147) (xy 50.930302 -303.974754) (xy 51.26915 -303.974754) (xy 51.27311 -303.9257)
			(xy 51.284887 -303.877916) (xy 51.304178 -303.83264) (xy 51.330481 -303.791044) (xy 51.363116 -303.754207)
			(xy 51.401237 -303.723082) (xy 51.443858 -303.698475) (xy 51.489874 -303.681023) (xy 51.538093 -303.671179)
			(xy 51.587268 -303.669198) (xy 51.636123 -303.67513) (xy 51.683394 -303.688822) (xy 51.727856 -303.70992)
			(xy 51.768359 -303.737876) (xy 51.803852 -303.771968) (xy 51.833417 -303.811312) (xy 51.856288 -303.854889)
			(xy 51.871872 -303.90157) (xy 51.879767 -303.950147) (xy 51.880262 -303.974754) (xy 52.21911 -303.974754)
			(xy 52.22307 -303.9257) (xy 52.234847 -303.877916) (xy 52.254138 -303.83264) (xy 52.280441 -303.791044)
			(xy 52.313076 -303.754207) (xy 52.351197 -303.723082) (xy 52.393818 -303.698475) (xy 52.439834 -303.681023)
			(xy 52.488053 -303.671179) (xy 52.537228 -303.669198) (xy 52.586083 -303.67513) (xy 52.633354 -303.688822)
			(xy 52.677816 -303.70992) (xy 52.718319 -303.737876) (xy 52.753812 -303.771968) (xy 52.783377 -303.811312)
			(xy 52.806248 -303.854889) (xy 52.821832 -303.90157) (xy 52.829727 -303.950147) (xy 52.830222 -303.974754)
			(xy 53.16907 -303.974754) (xy 53.17303 -303.9257) (xy 53.184807 -303.877916) (xy 53.204098 -303.83264)
			(xy 53.230401 -303.791044) (xy 53.263036 -303.754207) (xy 53.301157 -303.723082) (xy 53.343778 -303.698475)
			(xy 53.389794 -303.681023) (xy 53.438013 -303.671179) (xy 53.487188 -303.669198) (xy 53.536043 -303.67513)
			(xy 53.583314 -303.688822) (xy 53.627776 -303.70992) (xy 53.668279 -303.737876) (xy 53.703772 -303.771968)
			(xy 53.733337 -303.811312) (xy 53.756208 -303.854889) (xy 53.771792 -303.90157) (xy 53.779687 -303.950147)
			(xy 53.780182 -303.974754) (xy 54.11903 -303.974754) (xy 54.12299 -303.9257) (xy 54.134767 -303.877916)
			(xy 54.154058 -303.83264) (xy 54.180361 -303.791044) (xy 54.212996 -303.754207) (xy 54.251117 -303.723082)
			(xy 54.293738 -303.698475) (xy 54.339754 -303.681023) (xy 54.387973 -303.671179) (xy 54.437148 -303.669198)
			(xy 54.486003 -303.67513) (xy 54.533274 -303.688822) (xy 54.577736 -303.70992) (xy 54.618239 -303.737876)
			(xy 54.653732 -303.771968) (xy 54.683297 -303.811312) (xy 54.706168 -303.854889) (xy 54.721752 -303.90157)
			(xy 54.729647 -303.950147) (xy 54.730142 -303.974754) (xy 55.06899 -303.974754) (xy 55.07295 -303.9257)
			(xy 55.084727 -303.877916) (xy 55.104018 -303.83264) (xy 55.130321 -303.791044) (xy 55.162956 -303.754207)
			(xy 55.201077 -303.723082) (xy 55.243698 -303.698475) (xy 55.289714 -303.681023) (xy 55.337933 -303.671179)
			(xy 55.387108 -303.669198) (xy 55.435963 -303.67513) (xy 55.483234 -303.688822) (xy 55.527696 -303.70992)
			(xy 55.568199 -303.737876) (xy 55.603692 -303.771968) (xy 55.633257 -303.811312) (xy 55.656128 -303.854889)
			(xy 55.671712 -303.90157) (xy 55.679607 -303.950147) (xy 55.680102 -303.974754) (xy 56.01895 -303.974754)
			(xy 56.02291 -303.9257) (xy 56.034687 -303.877916) (xy 56.053978 -303.83264) (xy 56.080281 -303.791044)
			(xy 56.112916 -303.754207) (xy 56.151037 -303.723082) (xy 56.193658 -303.698475) (xy 56.239674 -303.681023)
			(xy 56.287893 -303.671179) (xy 56.337068 -303.669198) (xy 56.385923 -303.67513) (xy 56.433194 -303.688822)
			(xy 56.477656 -303.70992) (xy 56.518159 -303.737876) (xy 56.553652 -303.771968) (xy 56.583217 -303.811312)
			(xy 56.606088 -303.854889) (xy 56.621672 -303.90157) (xy 56.629567 -303.950147) (xy 56.630062 -303.974754)
			(xy 56.969164 -303.974754) (xy 56.973124 -303.9257) (xy 56.984901 -303.877916) (xy 57.004192 -303.83264)
			(xy 57.030495 -303.791044) (xy 57.06313 -303.754207) (xy 57.101251 -303.723082) (xy 57.143872 -303.698475)
			(xy 57.189888 -303.681023) (xy 57.238107 -303.671179) (xy 57.287282 -303.669198) (xy 57.336137 -303.67513)
			(xy 57.383408 -303.688822) (xy 57.42787 -303.70992) (xy 57.468373 -303.737876) (xy 57.503866 -303.771968)
			(xy 57.533431 -303.811312) (xy 57.556302 -303.854889) (xy 57.571886 -303.90157) (xy 57.579781 -303.950147)
			(xy 57.580276 -303.974754) (xy 57.919124 -303.974754) (xy 57.923084 -303.9257) (xy 57.934861 -303.877916)
			(xy 57.954152 -303.83264) (xy 57.980455 -303.791044) (xy 58.01309 -303.754207) (xy 58.051211 -303.723082)
			(xy 58.093832 -303.698475) (xy 58.139848 -303.681023) (xy 58.188067 -303.671179) (xy 58.237242 -303.669198)
			(xy 58.286097 -303.67513) (xy 58.333368 -303.688822) (xy 58.37783 -303.70992) (xy 58.418333 -303.737876)
			(xy 58.453826 -303.771968) (xy 58.483391 -303.811312) (xy 58.506262 -303.854889) (xy 58.521846 -303.90157)
			(xy 58.529741 -303.950147) (xy 58.530236 -303.974754) (xy 58.529741 -303.999361) (xy 58.521846 -304.047938)
			(xy 58.506262 -304.094619) (xy 58.483391 -304.138196) (xy 58.453826 -304.17754) (xy 58.418333 -304.211632)
			(xy 58.37783 -304.239588) (xy 58.333368 -304.260686) (xy 58.286097 -304.274378) (xy 58.237242 -304.28031)
			(xy 58.188067 -304.278329) (xy 58.139848 -304.268485) (xy 58.093832 -304.251033) (xy 58.051211 -304.226426)
			(xy 58.01309 -304.195301) (xy 57.980455 -304.158464) (xy 57.954152 -304.116868) (xy 57.934861 -304.071592)
			(xy 57.923084 -304.023808) (xy 57.919124 -303.974754) (xy 57.580276 -303.974754) (xy 57.579781 -303.999361)
			(xy 57.571886 -304.047938) (xy 57.556302 -304.094619) (xy 57.533431 -304.138196) (xy 57.503866 -304.17754)
			(xy 57.468373 -304.211632) (xy 57.42787 -304.239588) (xy 57.383408 -304.260686) (xy 57.336137 -304.274378)
			(xy 57.287282 -304.28031) (xy 57.238107 -304.278329) (xy 57.189888 -304.268485) (xy 57.143872 -304.251033)
			(xy 57.101251 -304.226426) (xy 57.06313 -304.195301) (xy 57.030495 -304.158464) (xy 57.004192 -304.116868)
			(xy 56.984901 -304.071592) (xy 56.973124 -304.023808) (xy 56.969164 -303.974754) (xy 56.630062 -303.974754)
			(xy 56.629567 -303.999361) (xy 56.621672 -304.047938) (xy 56.606088 -304.094619) (xy 56.583217 -304.138196)
			(xy 56.553652 -304.17754) (xy 56.518159 -304.211632) (xy 56.477656 -304.239588) (xy 56.433194 -304.260686)
			(xy 56.385923 -304.274378) (xy 56.337068 -304.28031) (xy 56.287893 -304.278329) (xy 56.239674 -304.268485)
			(xy 56.193658 -304.251033) (xy 56.151037 -304.226426) (xy 56.112916 -304.195301) (xy 56.080281 -304.158464)
			(xy 56.053978 -304.116868) (xy 56.034687 -304.071592) (xy 56.02291 -304.023808) (xy 56.01895 -303.974754)
			(xy 55.680102 -303.974754) (xy 55.679607 -303.999361) (xy 55.671712 -304.047938) (xy 55.656128 -304.094619)
			(xy 55.633257 -304.138196) (xy 55.603692 -304.17754) (xy 55.568199 -304.211632) (xy 55.527696 -304.239588)
			(xy 55.483234 -304.260686) (xy 55.435963 -304.274378) (xy 55.387108 -304.28031) (xy 55.337933 -304.278329)
			(xy 55.289714 -304.268485) (xy 55.243698 -304.251033) (xy 55.201077 -304.226426) (xy 55.162956 -304.195301)
			(xy 55.130321 -304.158464) (xy 55.104018 -304.116868) (xy 55.084727 -304.071592) (xy 55.07295 -304.023808)
			(xy 55.06899 -303.974754) (xy 54.730142 -303.974754) (xy 54.729647 -303.999361) (xy 54.721752 -304.047938)
			(xy 54.706168 -304.094619) (xy 54.683297 -304.138196) (xy 54.653732 -304.17754) (xy 54.618239 -304.211632)
			(xy 54.577736 -304.239588) (xy 54.533274 -304.260686) (xy 54.486003 -304.274378) (xy 54.437148 -304.28031)
			(xy 54.387973 -304.278329) (xy 54.339754 -304.268485) (xy 54.293738 -304.251033) (xy 54.251117 -304.226426)
			(xy 54.212996 -304.195301) (xy 54.180361 -304.158464) (xy 54.154058 -304.116868) (xy 54.134767 -304.071592)
			(xy 54.12299 -304.023808) (xy 54.11903 -303.974754) (xy 53.780182 -303.974754) (xy 53.779687 -303.999361)
			(xy 53.771792 -304.047938) (xy 53.756208 -304.094619) (xy 53.733337 -304.138196) (xy 53.703772 -304.17754)
			(xy 53.668279 -304.211632) (xy 53.627776 -304.239588) (xy 53.583314 -304.260686) (xy 53.536043 -304.274378)
			(xy 53.487188 -304.28031) (xy 53.438013 -304.278329) (xy 53.389794 -304.268485) (xy 53.343778 -304.251033)
			(xy 53.301157 -304.226426) (xy 53.263036 -304.195301) (xy 53.230401 -304.158464) (xy 53.204098 -304.116868)
			(xy 53.184807 -304.071592) (xy 53.17303 -304.023808) (xy 53.16907 -303.974754) (xy 52.830222 -303.974754)
			(xy 52.829727 -303.999361) (xy 52.821832 -304.047938) (xy 52.806248 -304.094619) (xy 52.783377 -304.138196)
			(xy 52.753812 -304.17754) (xy 52.718319 -304.211632) (xy 52.677816 -304.239588) (xy 52.633354 -304.260686)
			(xy 52.586083 -304.274378) (xy 52.537228 -304.28031) (xy 52.488053 -304.278329) (xy 52.439834 -304.268485)
			(xy 52.393818 -304.251033) (xy 52.351197 -304.226426) (xy 52.313076 -304.195301) (xy 52.280441 -304.158464)
			(xy 52.254138 -304.116868) (xy 52.234847 -304.071592) (xy 52.22307 -304.023808) (xy 52.21911 -303.974754)
			(xy 51.880262 -303.974754) (xy 51.879767 -303.999361) (xy 51.871872 -304.047938) (xy 51.856288 -304.094619)
			(xy 51.833417 -304.138196) (xy 51.803852 -304.17754) (xy 51.768359 -304.211632) (xy 51.727856 -304.239588)
			(xy 51.683394 -304.260686) (xy 51.636123 -304.274378) (xy 51.587268 -304.28031) (xy 51.538093 -304.278329)
			(xy 51.489874 -304.268485) (xy 51.443858 -304.251033) (xy 51.401237 -304.226426) (xy 51.363116 -304.195301)
			(xy 51.330481 -304.158464) (xy 51.304178 -304.116868) (xy 51.284887 -304.071592) (xy 51.27311 -304.023808)
			(xy 51.26915 -303.974754) (xy 50.930302 -303.974754) (xy 50.929807 -303.999361) (xy 50.921912 -304.047938)
			(xy 50.906328 -304.094619) (xy 50.883457 -304.138196) (xy 50.853892 -304.17754) (xy 50.818399 -304.211632)
			(xy 50.777896 -304.239588) (xy 50.733434 -304.260686) (xy 50.686163 -304.274378) (xy 50.637308 -304.28031)
			(xy 50.588133 -304.278329) (xy 50.539914 -304.268485) (xy 50.493898 -304.251033) (xy 50.451277 -304.226426)
			(xy 50.413156 -304.195301) (xy 50.380521 -304.158464) (xy 50.354218 -304.116868) (xy 50.334927 -304.071592)
			(xy 50.32315 -304.023808) (xy 50.31919 -303.974754) (xy 49.980088 -303.974754) (xy 49.979593 -303.999361)
			(xy 49.971698 -304.047938) (xy 49.956114 -304.094619) (xy 49.933243 -304.138196) (xy 49.903678 -304.17754)
			(xy 49.868185 -304.211632) (xy 49.827682 -304.239588) (xy 49.78322 -304.260686) (xy 49.735949 -304.274378)
			(xy 49.687094 -304.28031) (xy 49.637919 -304.278329) (xy 49.5897 -304.268485) (xy 49.543684 -304.251033)
			(xy 49.501063 -304.226426) (xy 49.462942 -304.195301) (xy 49.430307 -304.158464) (xy 49.404004 -304.116868)
			(xy 49.384713 -304.071592) (xy 49.372936 -304.023808) (xy 49.368976 -303.974754) (xy 49.068819 -303.974754)
			(xy 49.0658 -304.022825) (xy 49.054153 -304.075233) (xy 49.034508 -304.125197) (xy 49.00734 -304.171504)
			(xy 48.97331 -304.213028) (xy 48.933243 -304.248763) (xy 48.888112 -304.277842) (xy 48.839013 -304.299557)
			(xy 48.813212 -304.306986) (xy 48.796448 -304.311558) (xy 48.77562 -304.338482) (xy 48.77562 -304.449734)
			(xy 73.593972 -304.449734) (xy 73.597932 -304.40068) (xy 73.609709 -304.352896) (xy 73.629 -304.30762)
			(xy 73.655303 -304.266024) (xy 73.687938 -304.229187) (xy 73.726059 -304.198062) (xy 73.76868 -304.173455)
			(xy 73.814696 -304.156003) (xy 73.862915 -304.146159) (xy 73.91209 -304.144178) (xy 73.960945 -304.15011)
			(xy 74.008216 -304.163802) (xy 74.052678 -304.1849) (xy 74.093181 -304.212856) (xy 74.128674 -304.246948)
			(xy 74.158239 -304.286292) (xy 74.18111 -304.329869) (xy 74.196694 -304.37655) (xy 74.204589 -304.425127)
			(xy 74.205084 -304.449734) (xy 74.544186 -304.449734) (xy 74.548146 -304.40068) (xy 74.559923 -304.352896)
			(xy 74.579214 -304.30762) (xy 74.605517 -304.266024) (xy 74.638152 -304.229187) (xy 74.676273 -304.198062)
			(xy 74.718894 -304.173455) (xy 74.76491 -304.156003) (xy 74.813129 -304.146159) (xy 74.862304 -304.144178)
			(xy 74.911159 -304.15011) (xy 74.95843 -304.163802) (xy 75.002892 -304.1849) (xy 75.043395 -304.212856)
			(xy 75.078888 -304.246948) (xy 75.108453 -304.286292) (xy 75.131324 -304.329869) (xy 75.146908 -304.37655)
			(xy 75.154803 -304.425127) (xy 75.155298 -304.449734) (xy 75.494146 -304.449734) (xy 75.498106 -304.40068)
			(xy 75.509883 -304.352896) (xy 75.529174 -304.30762) (xy 75.555477 -304.266024) (xy 75.588112 -304.229187)
			(xy 75.626233 -304.198062) (xy 75.668854 -304.173455) (xy 75.71487 -304.156003) (xy 75.763089 -304.146159)
			(xy 75.812264 -304.144178) (xy 75.861119 -304.15011) (xy 75.90839 -304.163802) (xy 75.952852 -304.1849)
			(xy 75.993355 -304.212856) (xy 76.028848 -304.246948) (xy 76.058413 -304.286292) (xy 76.081284 -304.329869)
			(xy 76.096868 -304.37655) (xy 76.104763 -304.425127) (xy 76.105258 -304.449734) (xy 76.444106 -304.449734)
			(xy 76.448066 -304.40068) (xy 76.459843 -304.352896) (xy 76.479134 -304.30762) (xy 76.505437 -304.266024)
			(xy 76.538072 -304.229187) (xy 76.576193 -304.198062) (xy 76.618814 -304.173455) (xy 76.66483 -304.156003)
			(xy 76.713049 -304.146159) (xy 76.762224 -304.144178) (xy 76.811079 -304.15011) (xy 76.85835 -304.163802)
			(xy 76.902812 -304.1849) (xy 76.943315 -304.212856) (xy 76.978808 -304.246948) (xy 77.008373 -304.286292)
			(xy 77.031244 -304.329869) (xy 77.046828 -304.37655) (xy 77.054723 -304.425127) (xy 77.055218 -304.449734)
			(xy 77.394066 -304.449734) (xy 77.398026 -304.40068) (xy 77.409803 -304.352896) (xy 77.429094 -304.30762)
			(xy 77.455397 -304.266024) (xy 77.488032 -304.229187) (xy 77.526153 -304.198062) (xy 77.568774 -304.173455)
			(xy 77.61479 -304.156003) (xy 77.663009 -304.146159) (xy 77.712184 -304.144178) (xy 77.761039 -304.15011)
			(xy 77.80831 -304.163802) (xy 77.852772 -304.1849) (xy 77.893275 -304.212856) (xy 77.928768 -304.246948)
			(xy 77.958333 -304.286292) (xy 77.981204 -304.329869) (xy 77.996788 -304.37655) (xy 78.004683 -304.425127)
			(xy 78.00501 -304.441388) (xy 78.344116 -304.441388) (xy 78.349488 -304.392043) (xy 78.362772 -304.344218)
			(xy 78.383618 -304.299172) (xy 78.411477 -304.258091) (xy 78.445615 -304.222059) (xy 78.485133 -304.192024)
			(xy 78.52899 -304.168779) (xy 78.576029 -304.152935) (xy 78.625012 -304.144909) (xy 78.64983 -304.144426)
			(xy 78.664013 -304.144598) (xy 78.692253 -304.147273) (xy 78.706218 -304.14976) (xy 78.718664 -304.152046)
			(xy 78.742286 -304.14468) (xy 78.819756 -304.06721) (xy 78.827122 -304.043588) (xy 78.824836 -304.031142)
			(xy 78.822356 -304.017177) (xy 78.819686 -303.988937) (xy 78.819502 -303.974754) (xy 78.820024 -303.949499)
			(xy 78.828337 -303.899677) (xy 78.844738 -303.851903) (xy 78.868779 -303.80748) (xy 78.899803 -303.76762)
			(xy 78.936965 -303.73341) (xy 78.979251 -303.705784) (xy 79.025507 -303.685494) (xy 79.074472 -303.673094)
			(xy 79.12481 -303.668923) (xy 79.175148 -303.673094) (xy 79.224113 -303.685494) (xy 79.270369 -303.705784)
			(xy 79.312655 -303.73341) (xy 79.349817 -303.76762) (xy 79.380841 -303.80748) (xy 79.404882 -303.851903)
			(xy 79.421283 -303.899677) (xy 79.423781 -303.914651) (xy 85.191856 -303.914651) (xy 85.191856 -303.860149)
			(xy 85.199611 -303.806202) (xy 85.214965 -303.753908) (xy 85.237604 -303.704331) (xy 85.267068 -303.658481)
			(xy 85.302757 -303.617289) (xy 85.343944 -303.581596) (xy 85.389791 -303.552126) (xy 85.439365 -303.529481)
			(xy 85.491657 -303.514121) (xy 85.545603 -303.506359) (xy 85.572854 -303.50587) (xy 85.599171 -303.506293)
			(xy 85.651305 -303.513523) (xy 85.70195 -303.527852) (xy 85.750144 -303.549008) (xy 85.794972 -303.57659)
			(xy 85.835582 -303.610073) (xy 85.871203 -303.648821) (xy 85.886544 -303.670208) (xy 85.892386 -303.678844)
			(xy 85.908896 -303.689512) (xy 85.999828 -303.706276) (xy 86.019132 -303.702212) (xy 86.027514 -303.69637)
			(xy 86.051436 -303.68057) (xy 86.103046 -303.655608) (xy 86.15781 -303.63865) (xy 86.214495 -303.63008)
			(xy 86.24316 -303.629568) (xy 86.270413 -303.630077) (xy 86.314606 -303.636426) (xy 93.3229 -303.636426)
			(xy 93.326971 -303.580804) (xy 93.339097 -303.526367) (xy 93.35902 -303.474276) (xy 93.386316 -303.425641)
			(xy 93.420402 -303.381498) (xy 93.460551 -303.342789) (xy 93.505909 -303.310338) (xy 93.555509 -303.284837)
			(xy 93.608293 -303.26683) (xy 93.663136 -303.2567) (xy 93.71887 -303.254663) (xy 93.774307 -303.260763)
			(xy 93.828264 -303.274869) (xy 93.879593 -303.296681) (xy 93.927199 -303.325735) (xy 93.970067 -303.36141)
			(xy 94.007284 -303.402947) (xy 94.038057 -303.44946) (xy 94.061729 -303.499957) (xy 94.077797 -303.553364)
			(xy 94.085917 -303.60854) (xy 94.086426 -303.636426) (xy 94.085917 -303.664312) (xy 94.077797 -303.719488)
			(xy 94.061729 -303.772895) (xy 94.038057 -303.823392) (xy 94.007284 -303.869905) (xy 93.970067 -303.911442)
			(xy 93.927199 -303.947117) (xy 93.879593 -303.976171) (xy 93.828264 -303.997983) (xy 93.774307 -304.012089)
			(xy 93.71887 -304.018189) (xy 93.663136 -304.016152) (xy 93.608293 -304.006022) (xy 93.555509 -303.988015)
			(xy 93.505909 -303.962514) (xy 93.460551 -303.930063) (xy 93.420402 -303.891354) (xy 93.386316 -303.847211)
			(xy 93.35902 -303.798576) (xy 93.339097 -303.746485) (xy 93.326971 -303.692048) (xy 93.3229 -303.636426)
			(xy 86.314606 -303.636426) (xy 86.324365 -303.637828) (xy 86.376664 -303.65318) (xy 86.426246 -303.675819)
			(xy 86.472102 -303.705284) (xy 86.513296 -303.740975) (xy 86.548992 -303.782166) (xy 86.578462 -303.828019)
			(xy 86.601106 -303.877598) (xy 86.616463 -303.929896) (xy 86.624221 -303.983847) (xy 86.624221 -304.038353)
			(xy 86.616463 -304.092304) (xy 86.601106 -304.144602) (xy 86.578462 -304.194181) (xy 86.548992 -304.240034)
			(xy 86.513296 -304.281225) (xy 86.472102 -304.316916) (xy 86.426246 -304.346381) (xy 86.376664 -304.36902)
			(xy 86.324365 -304.384372) (xy 86.270413 -304.392123) (xy 86.24316 -304.392584) (xy 86.216845 -304.392128)
			(xy 86.164713 -304.384901) (xy 86.114069 -304.370575) (xy 86.065876 -304.349424) (xy 86.021048 -304.321848)
			(xy 85.980437 -304.288372) (xy 85.944813 -304.24963) (xy 85.92947 -304.228246) (xy 85.923628 -304.21961)
			(xy 85.907118 -304.208942) (xy 85.816186 -304.192178) (xy 85.796882 -304.196242) (xy 85.7885 -304.202084)
			(xy 85.764571 -304.217872) (xy 85.712964 -304.242839) (xy 85.658202 -304.2598) (xy 85.601518 -304.268373)
			(xy 85.572854 -304.268886) (xy 85.545603 -304.268441) (xy 85.491657 -304.260679) (xy 85.439365 -304.245319)
			(xy 85.389791 -304.222674) (xy 85.343944 -304.193204) (xy 85.302757 -304.157511) (xy 85.267068 -304.116319)
			(xy 85.237604 -304.070469) (xy 85.214965 -304.020892) (xy 85.199611 -303.968598) (xy 85.191856 -303.914651)
			(xy 79.423781 -303.914651) (xy 79.429596 -303.949499) (xy 79.430118 -303.974754) (xy 79.429935 -303.988937)
			(xy 79.427267 -304.017177) (xy 79.424784 -304.031142) (xy 79.422498 -304.043588) (xy 79.429864 -304.06721)
			(xy 79.507334 -304.14468) (xy 79.530956 -304.152046) (xy 79.543402 -304.14976) (xy 79.557369 -304.147288)
			(xy 79.585608 -304.144613) (xy 79.59979 -304.144426) (xy 79.624611 -304.144867) (xy 79.6736 -304.152897)
			(xy 79.720645 -304.168746) (xy 79.764505 -304.191997) (xy 79.804027 -304.222038) (xy 79.838167 -304.258076)
			(xy 79.866028 -304.299163) (xy 79.886875 -304.344217) (xy 79.900158 -304.392049) (xy 79.905528 -304.4414)
			(xy 79.905077 -304.449734) (xy 80.243946 -304.449734) (xy 80.247906 -304.40068) (xy 80.259683 -304.352896)
			(xy 80.278974 -304.30762) (xy 80.305277 -304.266024) (xy 80.337912 -304.229187) (xy 80.376033 -304.198062)
			(xy 80.418654 -304.173455) (xy 80.46467 -304.156003) (xy 80.512889 -304.146159) (xy 80.562064 -304.144178)
			(xy 80.610919 -304.15011) (xy 80.65819 -304.163802) (xy 80.702652 -304.1849) (xy 80.743155 -304.212856)
			(xy 80.778648 -304.246948) (xy 80.808213 -304.286292) (xy 80.831084 -304.329869) (xy 80.846668 -304.37655)
			(xy 80.854563 -304.425127) (xy 80.855058 -304.449734) (xy 81.19416 -304.449734) (xy 81.19812 -304.40068)
			(xy 81.209897 -304.352896) (xy 81.229188 -304.30762) (xy 81.255491 -304.266024) (xy 81.288126 -304.229187)
			(xy 81.326247 -304.198062) (xy 81.368868 -304.173455) (xy 81.414884 -304.156003) (xy 81.463103 -304.146159)
			(xy 81.512278 -304.144178) (xy 81.561133 -304.15011) (xy 81.608404 -304.163802) (xy 81.652866 -304.1849)
			(xy 81.693369 -304.212856) (xy 81.728862 -304.246948) (xy 81.758427 -304.286292) (xy 81.781298 -304.329869)
			(xy 81.796882 -304.37655) (xy 81.804777 -304.425127) (xy 81.805272 -304.449734) (xy 82.14412 -304.449734)
			(xy 82.14808 -304.40068) (xy 82.159857 -304.352896) (xy 82.179148 -304.30762) (xy 82.205451 -304.266024)
			(xy 82.238086 -304.229187) (xy 82.276207 -304.198062) (xy 82.318828 -304.173455) (xy 82.364844 -304.156003)
			(xy 82.413063 -304.146159) (xy 82.462238 -304.144178) (xy 82.511093 -304.15011) (xy 82.558364 -304.163802)
			(xy 82.602826 -304.1849) (xy 82.643329 -304.212856) (xy 82.678822 -304.246948) (xy 82.708387 -304.286292)
			(xy 82.731258 -304.329869) (xy 82.746842 -304.37655) (xy 82.754737 -304.425127) (xy 82.755232 -304.449734)
			(xy 83.094334 -304.449734) (xy 83.098294 -304.40068) (xy 83.110071 -304.352896) (xy 83.129362 -304.30762)
			(xy 83.155665 -304.266024) (xy 83.1883 -304.229187) (xy 83.226421 -304.198062) (xy 83.269042 -304.173455)
			(xy 83.315058 -304.156003) (xy 83.363277 -304.146159) (xy 83.412452 -304.144178) (xy 83.461307 -304.15011)
			(xy 83.508578 -304.163802) (xy 83.55304 -304.1849) (xy 83.593543 -304.212856) (xy 83.629036 -304.246948)
			(xy 83.658601 -304.286292) (xy 83.681472 -304.329869) (xy 83.697056 -304.37655) (xy 83.704951 -304.425127)
			(xy 83.705446 -304.449734) (xy 83.704951 -304.474341) (xy 83.697056 -304.522918) (xy 83.681472 -304.569599)
			(xy 83.65973 -304.611024) (xy 87.60028 -304.611024) (xy 87.604351 -304.555402) (xy 87.616477 -304.500965)
			(xy 87.6364 -304.448874) (xy 87.663696 -304.400239) (xy 87.697782 -304.356096) (xy 87.737931 -304.317387)
			(xy 87.783289 -304.284936) (xy 87.832889 -304.259435) (xy 87.885673 -304.241428) (xy 87.940516 -304.231298)
			(xy 87.99625 -304.229261) (xy 88.051687 -304.235361) (xy 88.105644 -304.249467) (xy 88.156973 -304.271279)
			(xy 88.204579 -304.300333) (xy 88.247447 -304.336008) (xy 88.284664 -304.377545) (xy 88.315437 -304.424058)
			(xy 88.339109 -304.474555) (xy 88.355177 -304.527962) (xy 88.363297 -304.583138) (xy 88.363806 -304.611024)
			(xy 88.363297 -304.63891) (xy 88.355177 -304.694086) (xy 88.339109 -304.747493) (xy 88.315437 -304.79799)
			(xy 88.284664 -304.844503) (xy 88.247447 -304.88604) (xy 88.204579 -304.921715) (xy 88.156973 -304.950769)
			(xy 88.105644 -304.972581) (xy 88.051687 -304.986687) (xy 87.99625 -304.992787) (xy 87.940516 -304.99075)
			(xy 87.885673 -304.98062) (xy 87.832889 -304.962613) (xy 87.783289 -304.937112) (xy 87.737931 -304.904661)
			(xy 87.697782 -304.865952) (xy 87.663696 -304.821809) (xy 87.6364 -304.773174) (xy 87.616477 -304.721083)
			(xy 87.604351 -304.666646) (xy 87.60028 -304.611024) (xy 83.65973 -304.611024) (xy 83.658601 -304.613176)
			(xy 83.629036 -304.65252) (xy 83.593543 -304.686612) (xy 83.55304 -304.714568) (xy 83.508578 -304.735666)
			(xy 83.461307 -304.749358) (xy 83.412452 -304.75529) (xy 83.363277 -304.753309) (xy 83.315058 -304.743465)
			(xy 83.269042 -304.726013) (xy 83.226421 -304.701406) (xy 83.1883 -304.670281) (xy 83.155665 -304.633444)
			(xy 83.129362 -304.591848) (xy 83.110071 -304.546572) (xy 83.098294 -304.498788) (xy 83.094334 -304.449734)
			(xy 82.755232 -304.449734) (xy 82.754737 -304.474341) (xy 82.746842 -304.522918) (xy 82.731258 -304.569599)
			(xy 82.708387 -304.613176) (xy 82.678822 -304.65252) (xy 82.643329 -304.686612) (xy 82.602826 -304.714568)
			(xy 82.558364 -304.735666) (xy 82.511093 -304.749358) (xy 82.462238 -304.75529) (xy 82.413063 -304.753309)
			(xy 82.364844 -304.743465) (xy 82.318828 -304.726013) (xy 82.276207 -304.701406) (xy 82.238086 -304.670281)
			(xy 82.205451 -304.633444) (xy 82.179148 -304.591848) (xy 82.159857 -304.546572) (xy 82.14808 -304.498788)
			(xy 82.14412 -304.449734) (xy 81.805272 -304.449734) (xy 81.804777 -304.474341) (xy 81.796882 -304.522918)
			(xy 81.781298 -304.569599) (xy 81.758427 -304.613176) (xy 81.728862 -304.65252) (xy 81.693369 -304.686612)
			(xy 81.652866 -304.714568) (xy 81.608404 -304.735666) (xy 81.561133 -304.749358) (xy 81.512278 -304.75529)
			(xy 81.463103 -304.753309) (xy 81.414884 -304.743465) (xy 81.368868 -304.726013) (xy 81.326247 -304.701406)
			(xy 81.288126 -304.670281) (xy 81.255491 -304.633444) (xy 81.229188 -304.591848) (xy 81.209897 -304.546572)
			(xy 81.19812 -304.498788) (xy 81.19416 -304.449734) (xy 80.855058 -304.449734) (xy 80.854563 -304.474341)
			(xy 80.846668 -304.522918) (xy 80.831084 -304.569599) (xy 80.808213 -304.613176) (xy 80.778648 -304.65252)
			(xy 80.743155 -304.686612) (xy 80.702652 -304.714568) (xy 80.65819 -304.735666) (xy 80.610919 -304.749358)
			(xy 80.562064 -304.75529) (xy 80.512889 -304.753309) (xy 80.46467 -304.743465) (xy 80.418654 -304.726013)
			(xy 80.376033 -304.701406) (xy 80.337912 -304.670281) (xy 80.305277 -304.633444) (xy 80.278974 -304.591848)
			(xy 80.259683 -304.546572) (xy 80.247906 -304.498788) (xy 80.243946 -304.449734) (xy 79.905077 -304.449734)
			(xy 79.902844 -304.49097) (xy 79.892175 -304.539453) (xy 79.873804 -304.58557) (xy 79.848213 -304.628109)
			(xy 79.816078 -304.665947) (xy 79.778245 -304.698087) (xy 79.73571 -304.723684) (xy 79.689595 -304.742062)
			(xy 79.641114 -304.752738) (xy 79.591544 -304.75543) (xy 79.542192 -304.750067) (xy 79.494358 -304.73679)
			(xy 79.449302 -304.71595) (xy 79.408211 -304.688095) (xy 79.372167 -304.653959) (xy 79.342121 -304.614442)
			(xy 79.318863 -304.570585) (xy 79.303007 -304.523543) (xy 79.294971 -304.474555) (xy 79.294482 -304.449734)
			(xy 79.294664 -304.435551) (xy 79.297332 -304.407311) (xy 79.299816 -304.393346) (xy 79.302102 -304.3809)
			(xy 79.294736 -304.357278) (xy 79.217266 -304.279808) (xy 79.193644 -304.272442) (xy 79.181198 -304.274728)
			(xy 79.167232 -304.277201) (xy 79.138992 -304.279875) (xy 79.12481 -304.280062) (xy 79.110627 -304.279885)
			(xy 79.082387 -304.277213) (xy 79.068422 -304.274728) (xy 79.055976 -304.272442) (xy 79.032354 -304.279808)
			(xy 78.954884 -304.357278) (xy 78.947518 -304.3809) (xy 78.949804 -304.393346) (xy 78.952283 -304.407311)
			(xy 78.954953 -304.435551) (xy 78.955138 -304.449734) (xy 78.954585 -304.474552) (xy 78.94655 -304.523533)
			(xy 78.930696 -304.570569) (xy 78.907441 -304.614421) (xy 78.877398 -304.653932) (xy 78.841359 -304.688063)
			(xy 78.800273 -304.715914) (xy 78.755222 -304.736751) (xy 78.707394 -304.750024) (xy 78.658048 -304.755386)
			(xy 78.608485 -304.752693) (xy 78.560011 -304.742018) (xy 78.513902 -304.723641) (xy 78.471374 -304.698046)
			(xy 78.433546 -304.665908) (xy 78.401416 -304.628074) (xy 78.375831 -304.585541) (xy 78.357463 -304.539428)
			(xy 78.346798 -304.490951) (xy 78.344116 -304.441388) (xy 78.00501 -304.441388) (xy 78.005178 -304.449734)
			(xy 78.004683 -304.474341) (xy 77.996788 -304.522918) (xy 77.981204 -304.569599) (xy 77.958333 -304.613176)
			(xy 77.928768 -304.65252) (xy 77.893275 -304.686612) (xy 77.852772 -304.714568) (xy 77.80831 -304.735666)
			(xy 77.761039 -304.749358) (xy 77.712184 -304.75529) (xy 77.663009 -304.753309) (xy 77.61479 -304.743465)
			(xy 77.568774 -304.726013) (xy 77.526153 -304.701406) (xy 77.488032 -304.670281) (xy 77.455397 -304.633444)
			(xy 77.429094 -304.591848) (xy 77.409803 -304.546572) (xy 77.398026 -304.498788) (xy 77.394066 -304.449734)
			(xy 77.055218 -304.449734) (xy 77.054723 -304.474341) (xy 77.046828 -304.522918) (xy 77.031244 -304.569599)
			(xy 77.008373 -304.613176) (xy 76.978808 -304.65252) (xy 76.943315 -304.686612) (xy 76.902812 -304.714568)
			(xy 76.85835 -304.735666) (xy 76.811079 -304.749358) (xy 76.762224 -304.75529) (xy 76.713049 -304.753309)
			(xy 76.66483 -304.743465) (xy 76.618814 -304.726013) (xy 76.576193 -304.701406) (xy 76.538072 -304.670281)
			(xy 76.505437 -304.633444) (xy 76.479134 -304.591848) (xy 76.459843 -304.546572) (xy 76.448066 -304.498788)
			(xy 76.444106 -304.449734) (xy 76.105258 -304.449734) (xy 76.104763 -304.474341) (xy 76.096868 -304.522918)
			(xy 76.081284 -304.569599) (xy 76.058413 -304.613176) (xy 76.028848 -304.65252) (xy 75.993355 -304.686612)
			(xy 75.952852 -304.714568) (xy 75.90839 -304.735666) (xy 75.861119 -304.749358) (xy 75.812264 -304.75529)
			(xy 75.763089 -304.753309) (xy 75.71487 -304.743465) (xy 75.668854 -304.726013) (xy 75.626233 -304.701406)
			(xy 75.588112 -304.670281) (xy 75.555477 -304.633444) (xy 75.529174 -304.591848) (xy 75.509883 -304.546572)
			(xy 75.498106 -304.498788) (xy 75.494146 -304.449734) (xy 75.155298 -304.449734) (xy 75.154803 -304.474341)
			(xy 75.146908 -304.522918) (xy 75.131324 -304.569599) (xy 75.108453 -304.613176) (xy 75.078888 -304.65252)
			(xy 75.043395 -304.686612) (xy 75.002892 -304.714568) (xy 74.95843 -304.735666) (xy 74.911159 -304.749358)
			(xy 74.862304 -304.75529) (xy 74.813129 -304.753309) (xy 74.76491 -304.743465) (xy 74.718894 -304.726013)
			(xy 74.676273 -304.701406) (xy 74.638152 -304.670281) (xy 74.605517 -304.633444) (xy 74.579214 -304.591848)
			(xy 74.559923 -304.546572) (xy 74.548146 -304.498788) (xy 74.544186 -304.449734) (xy 74.205084 -304.449734)
			(xy 74.204589 -304.474341) (xy 74.196694 -304.522918) (xy 74.18111 -304.569599) (xy 74.158239 -304.613176)
			(xy 74.128674 -304.65252) (xy 74.093181 -304.686612) (xy 74.052678 -304.714568) (xy 74.008216 -304.735666)
			(xy 73.960945 -304.749358) (xy 73.91209 -304.75529) (xy 73.862915 -304.753309) (xy 73.814696 -304.743465)
			(xy 73.76868 -304.726013) (xy 73.726059 -304.701406) (xy 73.687938 -304.670281) (xy 73.655303 -304.633444)
			(xy 73.629 -304.591848) (xy 73.609709 -304.546572) (xy 73.597932 -304.498788) (xy 73.593972 -304.449734)
			(xy 48.77562 -304.449734) (xy 48.77562 -304.502566) (xy 48.775787 -304.508924) (xy 48.778876 -304.521258)
			(xy 48.781716 -304.52695) (xy 48.785018 -304.532792) (xy 48.7934 -304.541936) (xy 48.798734 -304.545238)
			(xy 48.804068 -304.548794) (xy 48.81372 -304.57267) (xy 48.818344 -304.582712) (xy 48.834407 -304.597869)
			(xy 48.844708 -304.60188) (xy 48.854106 -304.60569) (xy 48.878785 -304.616271) (xy 48.924788 -304.64396)
			(xy 48.965933 -304.678458) (xy 49.00122 -304.718929) (xy 49.029792 -304.764388) (xy 49.050957 -304.813734)
			(xy 49.064201 -304.865769) (xy 49.069202 -304.919229) (xy 49.068858 -304.924714) (xy 49.368976 -304.924714)
			(xy 49.372936 -304.87566) (xy 49.384713 -304.827876) (xy 49.404004 -304.7826) (xy 49.430307 -304.741004)
			(xy 49.462942 -304.704167) (xy 49.501063 -304.673042) (xy 49.543684 -304.648435) (xy 49.5897 -304.630983)
			(xy 49.637919 -304.621139) (xy 49.687094 -304.619158) (xy 49.735949 -304.62509) (xy 49.78322 -304.638782)
			(xy 49.827682 -304.65988) (xy 49.868185 -304.687836) (xy 49.903678 -304.721928) (xy 49.933243 -304.761272)
			(xy 49.956114 -304.804849) (xy 49.971698 -304.85153) (xy 49.979593 -304.900107) (xy 49.980088 -304.924714)
			(xy 50.31919 -304.924714) (xy 50.32315 -304.87566) (xy 50.334927 -304.827876) (xy 50.354218 -304.7826)
			(xy 50.380521 -304.741004) (xy 50.413156 -304.704167) (xy 50.451277 -304.673042) (xy 50.493898 -304.648435)
			(xy 50.539914 -304.630983) (xy 50.588133 -304.621139) (xy 50.637308 -304.619158) (xy 50.686163 -304.62509)
			(xy 50.733434 -304.638782) (xy 50.777896 -304.65988) (xy 50.818399 -304.687836) (xy 50.853892 -304.721928)
			(xy 50.883457 -304.761272) (xy 50.906328 -304.804849) (xy 50.921912 -304.85153) (xy 50.929807 -304.900107)
			(xy 50.930302 -304.924714) (xy 51.26915 -304.924714) (xy 51.27311 -304.87566) (xy 51.284887 -304.827876)
			(xy 51.304178 -304.7826) (xy 51.330481 -304.741004) (xy 51.363116 -304.704167) (xy 51.401237 -304.673042)
			(xy 51.443858 -304.648435) (xy 51.489874 -304.630983) (xy 51.538093 -304.621139) (xy 51.587268 -304.619158)
			(xy 51.636123 -304.62509) (xy 51.683394 -304.638782) (xy 51.727856 -304.65988) (xy 51.768359 -304.687836)
			(xy 51.803852 -304.721928) (xy 51.833417 -304.761272) (xy 51.856288 -304.804849) (xy 51.871872 -304.85153)
			(xy 51.879767 -304.900107) (xy 51.880262 -304.924714) (xy 52.21911 -304.924714) (xy 52.22307 -304.87566)
			(xy 52.234847 -304.827876) (xy 52.254138 -304.7826) (xy 52.280441 -304.741004) (xy 52.313076 -304.704167)
			(xy 52.351197 -304.673042) (xy 52.393818 -304.648435) (xy 52.439834 -304.630983) (xy 52.488053 -304.621139)
			(xy 52.537228 -304.619158) (xy 52.586083 -304.62509) (xy 52.633354 -304.638782) (xy 52.677816 -304.65988)
			(xy 52.718319 -304.687836) (xy 52.753812 -304.721928) (xy 52.783377 -304.761272) (xy 52.806248 -304.804849)
			(xy 52.821832 -304.85153) (xy 52.829727 -304.900107) (xy 52.830222 -304.924714) (xy 53.16907 -304.924714)
			(xy 53.17303 -304.87566) (xy 53.184807 -304.827876) (xy 53.204098 -304.7826) (xy 53.230401 -304.741004)
			(xy 53.263036 -304.704167) (xy 53.301157 -304.673042) (xy 53.343778 -304.648435) (xy 53.389794 -304.630983)
			(xy 53.438013 -304.621139) (xy 53.487188 -304.619158) (xy 53.536043 -304.62509) (xy 53.583314 -304.638782)
			(xy 53.627776 -304.65988) (xy 53.668279 -304.687836) (xy 53.703772 -304.721928) (xy 53.733337 -304.761272)
			(xy 53.756208 -304.804849) (xy 53.771792 -304.85153) (xy 53.779687 -304.900107) (xy 53.780182 -304.924714)
			(xy 54.11903 -304.924714) (xy 54.12299 -304.87566) (xy 54.134767 -304.827876) (xy 54.154058 -304.7826)
			(xy 54.180361 -304.741004) (xy 54.212996 -304.704167) (xy 54.251117 -304.673042) (xy 54.293738 -304.648435)
			(xy 54.339754 -304.630983) (xy 54.387973 -304.621139) (xy 54.437148 -304.619158) (xy 54.486003 -304.62509)
			(xy 54.533274 -304.638782) (xy 54.577736 -304.65988) (xy 54.618239 -304.687836) (xy 54.653732 -304.721928)
			(xy 54.683297 -304.761272) (xy 54.706168 -304.804849) (xy 54.721752 -304.85153) (xy 54.729647 -304.900107)
			(xy 54.730142 -304.924714) (xy 55.06899 -304.924714) (xy 55.07295 -304.87566) (xy 55.084727 -304.827876)
			(xy 55.104018 -304.7826) (xy 55.130321 -304.741004) (xy 55.162956 -304.704167) (xy 55.201077 -304.673042)
			(xy 55.243698 -304.648435) (xy 55.289714 -304.630983) (xy 55.337933 -304.621139) (xy 55.387108 -304.619158)
			(xy 55.435963 -304.62509) (xy 55.483234 -304.638782) (xy 55.527696 -304.65988) (xy 55.568199 -304.687836)
			(xy 55.603692 -304.721928) (xy 55.633257 -304.761272) (xy 55.656128 -304.804849) (xy 55.671712 -304.85153)
			(xy 55.679607 -304.900107) (xy 55.680102 -304.924714) (xy 56.01895 -304.924714) (xy 56.02291 -304.87566)
			(xy 56.034687 -304.827876) (xy 56.053978 -304.7826) (xy 56.080281 -304.741004) (xy 56.112916 -304.704167)
			(xy 56.151037 -304.673042) (xy 56.193658 -304.648435) (xy 56.239674 -304.630983) (xy 56.287893 -304.621139)
			(xy 56.337068 -304.619158) (xy 56.385923 -304.62509) (xy 56.433194 -304.638782) (xy 56.477656 -304.65988)
			(xy 56.518159 -304.687836) (xy 56.553652 -304.721928) (xy 56.583217 -304.761272) (xy 56.606088 -304.804849)
			(xy 56.621672 -304.85153) (xy 56.629567 -304.900107) (xy 56.630062 -304.924714) (xy 56.969164 -304.924714)
			(xy 56.973124 -304.87566) (xy 56.984901 -304.827876) (xy 57.004192 -304.7826) (xy 57.030495 -304.741004)
			(xy 57.06313 -304.704167) (xy 57.101251 -304.673042) (xy 57.143872 -304.648435) (xy 57.189888 -304.630983)
			(xy 57.238107 -304.621139) (xy 57.287282 -304.619158) (xy 57.336137 -304.62509) (xy 57.383408 -304.638782)
			(xy 57.42787 -304.65988) (xy 57.468373 -304.687836) (xy 57.503866 -304.721928) (xy 57.533431 -304.761272)
			(xy 57.556302 -304.804849) (xy 57.571886 -304.85153) (xy 57.579781 -304.900107) (xy 57.580276 -304.924714)
			(xy 57.919124 -304.924714) (xy 57.923084 -304.87566) (xy 57.934861 -304.827876) (xy 57.954152 -304.7826)
			(xy 57.980455 -304.741004) (xy 58.01309 -304.704167) (xy 58.051211 -304.673042) (xy 58.093832 -304.648435)
			(xy 58.139848 -304.630983) (xy 58.188067 -304.621139) (xy 58.237242 -304.619158) (xy 58.286097 -304.62509)
			(xy 58.333368 -304.638782) (xy 58.37783 -304.65988) (xy 58.418333 -304.687836) (xy 58.453826 -304.721928)
			(xy 58.483391 -304.761272) (xy 58.506262 -304.804849) (xy 58.521846 -304.85153) (xy 58.529741 -304.900107)
			(xy 58.530236 -304.924714) (xy 59.819044 -304.924714) (xy 59.823004 -304.87566) (xy 59.834781 -304.827876)
			(xy 59.854072 -304.7826) (xy 59.880375 -304.741004) (xy 59.91301 -304.704167) (xy 59.951131 -304.673042)
			(xy 59.993752 -304.648435) (xy 60.039768 -304.630983) (xy 60.087987 -304.621139) (xy 60.137162 -304.619158)
			(xy 60.186017 -304.62509) (xy 60.233288 -304.638782) (xy 60.27775 -304.65988) (xy 60.318253 -304.687836)
			(xy 60.353746 -304.721928) (xy 60.383311 -304.761272) (xy 60.406182 -304.804849) (xy 60.421766 -304.85153)
			(xy 60.429661 -304.900107) (xy 60.430156 -304.924714) (xy 60.769004 -304.924714) (xy 60.772964 -304.87566)
			(xy 60.784741 -304.827876) (xy 60.804032 -304.7826) (xy 60.830335 -304.741004) (xy 60.86297 -304.704167)
			(xy 60.901091 -304.673042) (xy 60.943712 -304.648435) (xy 60.989728 -304.630983) (xy 61.037947 -304.621139)
			(xy 61.087122 -304.619158) (xy 61.135977 -304.62509) (xy 61.183248 -304.638782) (xy 61.22771 -304.65988)
			(xy 61.268213 -304.687836) (xy 61.303706 -304.721928) (xy 61.333271 -304.761272) (xy 61.356142 -304.804849)
			(xy 61.371726 -304.85153) (xy 61.379621 -304.900107) (xy 61.380116 -304.924714) (xy 61.718964 -304.924714)
			(xy 61.722924 -304.87566) (xy 61.734701 -304.827876) (xy 61.753992 -304.7826) (xy 61.780295 -304.741004)
			(xy 61.81293 -304.704167) (xy 61.851051 -304.673042) (xy 61.893672 -304.648435) (xy 61.939688 -304.630983)
			(xy 61.987907 -304.621139) (xy 62.037082 -304.619158) (xy 62.085937 -304.62509) (xy 62.133208 -304.638782)
			(xy 62.17767 -304.65988) (xy 62.218173 -304.687836) (xy 62.253666 -304.721928) (xy 62.283231 -304.761272)
			(xy 62.306102 -304.804849) (xy 62.321686 -304.85153) (xy 62.329581 -304.900107) (xy 62.330076 -304.924714)
			(xy 62.669178 -304.924714) (xy 62.673138 -304.87566) (xy 62.684915 -304.827876) (xy 62.704206 -304.7826)
			(xy 62.730509 -304.741004) (xy 62.763144 -304.704167) (xy 62.801265 -304.673042) (xy 62.843886 -304.648435)
			(xy 62.889902 -304.630983) (xy 62.938121 -304.621139) (xy 62.987296 -304.619158) (xy 63.036151 -304.62509)
			(xy 63.083422 -304.638782) (xy 63.127884 -304.65988) (xy 63.168387 -304.687836) (xy 63.20388 -304.721928)
			(xy 63.233445 -304.761272) (xy 63.256316 -304.804849) (xy 63.2719 -304.85153) (xy 63.279795 -304.900107)
			(xy 63.28029 -304.924714) (xy 63.619138 -304.924714) (xy 63.623098 -304.87566) (xy 63.634875 -304.827876)
			(xy 63.654166 -304.7826) (xy 63.680469 -304.741004) (xy 63.713104 -304.704167) (xy 63.751225 -304.673042)
			(xy 63.793846 -304.648435) (xy 63.839862 -304.630983) (xy 63.888081 -304.621139) (xy 63.937256 -304.619158)
			(xy 63.986111 -304.62509) (xy 64.033382 -304.638782) (xy 64.077844 -304.65988) (xy 64.118347 -304.687836)
			(xy 64.15384 -304.721928) (xy 64.183405 -304.761272) (xy 64.206276 -304.804849) (xy 64.22186 -304.85153)
			(xy 64.229755 -304.900107) (xy 64.23025 -304.924714) (xy 64.569098 -304.924714) (xy 64.573058 -304.87566)
			(xy 64.584835 -304.827876) (xy 64.604126 -304.7826) (xy 64.630429 -304.741004) (xy 64.663064 -304.704167)
			(xy 64.701185 -304.673042) (xy 64.743806 -304.648435) (xy 64.789822 -304.630983) (xy 64.838041 -304.621139)
			(xy 64.887216 -304.619158) (xy 64.936071 -304.62509) (xy 64.983342 -304.638782) (xy 65.027804 -304.65988)
			(xy 65.068307 -304.687836) (xy 65.1038 -304.721928) (xy 65.133365 -304.761272) (xy 65.156236 -304.804849)
			(xy 65.17182 -304.85153) (xy 65.179715 -304.900107) (xy 65.18021 -304.924714) (xy 65.519058 -304.924714)
			(xy 65.523018 -304.87566) (xy 65.534795 -304.827876) (xy 65.554086 -304.7826) (xy 65.580389 -304.741004)
			(xy 65.613024 -304.704167) (xy 65.651145 -304.673042) (xy 65.693766 -304.648435) (xy 65.739782 -304.630983)
			(xy 65.788001 -304.621139) (xy 65.837176 -304.619158) (xy 65.886031 -304.62509) (xy 65.933302 -304.638782)
			(xy 65.977764 -304.65988) (xy 66.018267 -304.687836) (xy 66.05376 -304.721928) (xy 66.083325 -304.761272)
			(xy 66.106196 -304.804849) (xy 66.12178 -304.85153) (xy 66.129675 -304.900107) (xy 66.13017 -304.924714)
			(xy 66.469018 -304.924714) (xy 66.472978 -304.87566) (xy 66.484755 -304.827876) (xy 66.504046 -304.7826)
			(xy 66.530349 -304.741004) (xy 66.562984 -304.704167) (xy 66.601105 -304.673042) (xy 66.643726 -304.648435)
			(xy 66.689742 -304.630983) (xy 66.737961 -304.621139) (xy 66.787136 -304.619158) (xy 66.835991 -304.62509)
			(xy 66.883262 -304.638782) (xy 66.927724 -304.65988) (xy 66.968227 -304.687836) (xy 67.00372 -304.721928)
			(xy 67.033285 -304.761272) (xy 67.056156 -304.804849) (xy 67.07174 -304.85153) (xy 67.079635 -304.900107)
			(xy 67.08013 -304.924714) (xy 67.418978 -304.924714) (xy 67.422938 -304.87566) (xy 67.434715 -304.827876)
			(xy 67.454006 -304.7826) (xy 67.480309 -304.741004) (xy 67.512944 -304.704167) (xy 67.551065 -304.673042)
			(xy 67.593686 -304.648435) (xy 67.639702 -304.630983) (xy 67.687921 -304.621139) (xy 67.737096 -304.619158)
			(xy 67.785951 -304.62509) (xy 67.833222 -304.638782) (xy 67.877684 -304.65988) (xy 67.918187 -304.687836)
			(xy 67.95368 -304.721928) (xy 67.983245 -304.761272) (xy 68.006116 -304.804849) (xy 68.0217 -304.85153)
			(xy 68.029595 -304.900107) (xy 68.03009 -304.924714) (xy 68.368938 -304.924714) (xy 68.372898 -304.87566)
			(xy 68.384675 -304.827876) (xy 68.403966 -304.7826) (xy 68.430269 -304.741004) (xy 68.462904 -304.704167)
			(xy 68.501025 -304.673042) (xy 68.543646 -304.648435) (xy 68.589662 -304.630983) (xy 68.637881 -304.621139)
			(xy 68.687056 -304.619158) (xy 68.735911 -304.62509) (xy 68.783182 -304.638782) (xy 68.827644 -304.65988)
			(xy 68.868147 -304.687836) (xy 68.90364 -304.721928) (xy 68.933205 -304.761272) (xy 68.956076 -304.804849)
			(xy 68.97166 -304.85153) (xy 68.979555 -304.900107) (xy 68.98005 -304.924714) (xy 69.319152 -304.924714)
			(xy 69.323112 -304.87566) (xy 69.334889 -304.827876) (xy 69.35418 -304.7826) (xy 69.380483 -304.741004)
			(xy 69.413118 -304.704167) (xy 69.451239 -304.673042) (xy 69.49386 -304.648435) (xy 69.539876 -304.630983)
			(xy 69.588095 -304.621139) (xy 69.63727 -304.619158) (xy 69.686125 -304.62509) (xy 69.733396 -304.638782)
			(xy 69.777858 -304.65988) (xy 69.818361 -304.687836) (xy 69.853854 -304.721928) (xy 69.883419 -304.761272)
			(xy 69.90629 -304.804849) (xy 69.921874 -304.85153) (xy 69.929769 -304.900107) (xy 69.930264 -304.924714)
			(xy 70.269112 -304.924714) (xy 70.273072 -304.87566) (xy 70.284849 -304.827876) (xy 70.30414 -304.7826)
			(xy 70.330443 -304.741004) (xy 70.363078 -304.704167) (xy 70.401199 -304.673042) (xy 70.44382 -304.648435)
			(xy 70.489836 -304.630983) (xy 70.538055 -304.621139) (xy 70.58723 -304.619158) (xy 70.636085 -304.62509)
			(xy 70.683356 -304.638782) (xy 70.727818 -304.65988) (xy 70.768321 -304.687836) (xy 70.803814 -304.721928)
			(xy 70.833379 -304.761272) (xy 70.85625 -304.804849) (xy 70.871834 -304.85153) (xy 70.879729 -304.900107)
			(xy 70.880224 -304.924714) (xy 71.219072 -304.924714) (xy 71.223032 -304.87566) (xy 71.234809 -304.827876)
			(xy 71.2541 -304.7826) (xy 71.280403 -304.741004) (xy 71.313038 -304.704167) (xy 71.351159 -304.673042)
			(xy 71.39378 -304.648435) (xy 71.439796 -304.630983) (xy 71.488015 -304.621139) (xy 71.53719 -304.619158)
			(xy 71.586045 -304.62509) (xy 71.633316 -304.638782) (xy 71.677778 -304.65988) (xy 71.718281 -304.687836)
			(xy 71.753774 -304.721928) (xy 71.783339 -304.761272) (xy 71.80621 -304.804849) (xy 71.821794 -304.85153)
			(xy 71.829689 -304.900107) (xy 71.830184 -304.924714) (xy 72.169032 -304.924714) (xy 72.172992 -304.87566)
			(xy 72.184769 -304.827876) (xy 72.20406 -304.7826) (xy 72.230363 -304.741004) (xy 72.262998 -304.704167)
			(xy 72.301119 -304.673042) (xy 72.34374 -304.648435) (xy 72.389756 -304.630983) (xy 72.437975 -304.621139)
			(xy 72.48715 -304.619158) (xy 72.536005 -304.62509) (xy 72.583276 -304.638782) (xy 72.627738 -304.65988)
			(xy 72.668241 -304.687836) (xy 72.703734 -304.721928) (xy 72.733299 -304.761272) (xy 72.75617 -304.804849)
			(xy 72.771754 -304.85153) (xy 72.779649 -304.900107) (xy 72.780144 -304.924714) (xy 72.779649 -304.949321)
			(xy 72.771754 -304.997898) (xy 72.75617 -305.044579) (xy 72.745493 -305.064922) (xy 88.62009 -305.064922)
			(xy 88.624161 -305.0093) (xy 88.636287 -304.954863) (xy 88.65621 -304.902772) (xy 88.683506 -304.854137)
			(xy 88.717592 -304.809994) (xy 88.757741 -304.771285) (xy 88.803099 -304.738834) (xy 88.852699 -304.713333)
			(xy 88.905483 -304.695326) (xy 88.960326 -304.685196) (xy 89.01606 -304.683159) (xy 89.071497 -304.689259)
			(xy 89.125454 -304.703365) (xy 89.176783 -304.725177) (xy 89.224389 -304.754231) (xy 89.267257 -304.789906)
			(xy 89.304474 -304.831443) (xy 89.335247 -304.877956) (xy 89.358919 -304.928453) (xy 89.374987 -304.98186)
			(xy 89.383107 -305.037036) (xy 89.383616 -305.064922) (xy 89.635074 -305.064922) (xy 89.639145 -305.0093)
			(xy 89.651271 -304.954863) (xy 89.671194 -304.902772) (xy 89.69849 -304.854137) (xy 89.732576 -304.809994)
			(xy 89.772725 -304.771285) (xy 89.818083 -304.738834) (xy 89.867683 -304.713333) (xy 89.920467 -304.695326)
			(xy 89.97531 -304.685196) (xy 90.031044 -304.683159) (xy 90.086481 -304.689259) (xy 90.140438 -304.703365)
			(xy 90.191767 -304.725177) (xy 90.239373 -304.754231) (xy 90.282241 -304.789906) (xy 90.319458 -304.831443)
			(xy 90.350231 -304.877956) (xy 90.373903 -304.928453) (xy 90.389971 -304.98186) (xy 90.398091 -305.037036)
			(xy 90.3986 -305.064922) (xy 90.643454 -305.064922) (xy 90.647525 -305.0093) (xy 90.659651 -304.954863)
			(xy 90.679574 -304.902772) (xy 90.70687 -304.854137) (xy 90.740956 -304.809994) (xy 90.781105 -304.771285)
			(xy 90.826463 -304.738834) (xy 90.876063 -304.713333) (xy 90.928847 -304.695326) (xy 90.98369 -304.685196)
			(xy 91.039424 -304.683159) (xy 91.094861 -304.689259) (xy 91.148818 -304.703365) (xy 91.200147 -304.725177)
			(xy 91.247753 -304.754231) (xy 91.290621 -304.789906) (xy 91.327838 -304.831443) (xy 91.358611 -304.877956)
			(xy 91.382283 -304.928453) (xy 91.398351 -304.98186) (xy 91.406471 -305.037036) (xy 91.406961 -305.063906)
			(xy 91.66809 -305.063906) (xy 91.672161 -305.008284) (xy 91.684287 -304.953847) (xy 91.70421 -304.901756)
			(xy 91.731506 -304.853121) (xy 91.765592 -304.808978) (xy 91.805741 -304.770269) (xy 91.851099 -304.737818)
			(xy 91.900699 -304.712317) (xy 91.953483 -304.69431) (xy 92.008326 -304.68418) (xy 92.06406 -304.682143)
			(xy 92.119497 -304.688243) (xy 92.173454 -304.702349) (xy 92.224783 -304.724161) (xy 92.272389 -304.753215)
			(xy 92.315257 -304.78889) (xy 92.352474 -304.830427) (xy 92.383247 -304.87694) (xy 92.406919 -304.927437)
			(xy 92.422987 -304.980844) (xy 92.431107 -305.03602) (xy 92.431291 -305.046126) (xy 92.68409 -305.046126)
			(xy 92.688161 -304.990504) (xy 92.700287 -304.936067) (xy 92.72021 -304.883976) (xy 92.747506 -304.835341)
			(xy 92.781592 -304.791198) (xy 92.821741 -304.752489) (xy 92.867099 -304.720038) (xy 92.916699 -304.694537)
			(xy 92.969483 -304.67653) (xy 93.024326 -304.6664) (xy 93.08006 -304.664363) (xy 93.135497 -304.670463)
			(xy 93.189454 -304.684569) (xy 93.240783 -304.706381) (xy 93.288389 -304.735435) (xy 93.331257 -304.77111)
			(xy 93.368474 -304.812647) (xy 93.399247 -304.85916) (xy 93.422919 -304.909657) (xy 93.438987 -304.963064)
			(xy 93.447107 -305.01824) (xy 93.447616 -305.046126) (xy 93.447107 -305.074012) (xy 93.438987 -305.129188)
			(xy 93.422919 -305.182595) (xy 93.399247 -305.233092) (xy 93.368474 -305.279605) (xy 93.331257 -305.321142)
			(xy 93.288389 -305.356817) (xy 93.240783 -305.385871) (xy 93.189454 -305.407683) (xy 93.135497 -305.421789)
			(xy 93.08006 -305.427889) (xy 93.024326 -305.425852) (xy 92.969483 -305.415722) (xy 92.916699 -305.397715)
			(xy 92.867099 -305.372214) (xy 92.821741 -305.339763) (xy 92.781592 -305.301054) (xy 92.747506 -305.256911)
			(xy 92.72021 -305.208276) (xy 92.700287 -305.156185) (xy 92.688161 -305.101748) (xy 92.68409 -305.046126)
			(xy 92.431291 -305.046126) (xy 92.431616 -305.063906) (xy 92.431107 -305.091792) (xy 92.422987 -305.146968)
			(xy 92.406919 -305.200375) (xy 92.383247 -305.250872) (xy 92.352474 -305.297385) (xy 92.315257 -305.338922)
			(xy 92.272389 -305.374597) (xy 92.224783 -305.403651) (xy 92.173454 -305.425463) (xy 92.119497 -305.439569)
			(xy 92.06406 -305.445669) (xy 92.008326 -305.443632) (xy 91.953483 -305.433502) (xy 91.900699 -305.415495)
			(xy 91.851099 -305.389994) (xy 91.805741 -305.357543) (xy 91.765592 -305.318834) (xy 91.731506 -305.274691)
			(xy 91.70421 -305.226056) (xy 91.684287 -305.173965) (xy 91.672161 -305.119528) (xy 91.66809 -305.063906)
			(xy 91.406961 -305.063906) (xy 91.40698 -305.064922) (xy 91.406471 -305.092808) (xy 91.398351 -305.147984)
			(xy 91.382283 -305.201391) (xy 91.358611 -305.251888) (xy 91.327838 -305.298401) (xy 91.290621 -305.339938)
			(xy 91.247753 -305.375613) (xy 91.200147 -305.404667) (xy 91.148818 -305.426479) (xy 91.094861 -305.440585)
			(xy 91.039424 -305.446685) (xy 90.98369 -305.444648) (xy 90.928847 -305.434518) (xy 90.876063 -305.416511)
			(xy 90.826463 -305.39101) (xy 90.781105 -305.358559) (xy 90.740956 -305.31985) (xy 90.70687 -305.275707)
			(xy 90.679574 -305.227072) (xy 90.659651 -305.174981) (xy 90.647525 -305.120544) (xy 90.643454 -305.064922)
			(xy 90.3986 -305.064922) (xy 90.398091 -305.092808) (xy 90.389971 -305.147984) (xy 90.373903 -305.201391)
			(xy 90.350231 -305.251888) (xy 90.319458 -305.298401) (xy 90.282241 -305.339938) (xy 90.239373 -305.375613)
			(xy 90.191767 -305.404667) (xy 90.140438 -305.426479) (xy 90.086481 -305.440585) (xy 90.031044 -305.446685)
			(xy 89.97531 -305.444648) (xy 89.920467 -305.434518) (xy 89.867683 -305.416511) (xy 89.818083 -305.39101)
			(xy 89.772725 -305.358559) (xy 89.732576 -305.31985) (xy 89.69849 -305.275707) (xy 89.671194 -305.227072)
			(xy 89.651271 -305.174981) (xy 89.639145 -305.120544) (xy 89.635074 -305.064922) (xy 89.383616 -305.064922)
			(xy 89.383107 -305.092808) (xy 89.374987 -305.147984) (xy 89.358919 -305.201391) (xy 89.335247 -305.251888)
			(xy 89.304474 -305.298401) (xy 89.267257 -305.339938) (xy 89.224389 -305.375613) (xy 89.176783 -305.404667)
			(xy 89.125454 -305.426479) (xy 89.071497 -305.440585) (xy 89.01606 -305.446685) (xy 88.960326 -305.444648)
			(xy 88.905483 -305.434518) (xy 88.852699 -305.416511) (xy 88.803099 -305.39101) (xy 88.757741 -305.358559)
			(xy 88.717592 -305.31985) (xy 88.683506 -305.275707) (xy 88.65621 -305.227072) (xy 88.636287 -305.174981)
			(xy 88.624161 -305.120544) (xy 88.62009 -305.064922) (xy 72.745493 -305.064922) (xy 72.733299 -305.088156)
			(xy 72.703734 -305.1275) (xy 72.668241 -305.161592) (xy 72.627738 -305.189548) (xy 72.583276 -305.210646)
			(xy 72.536005 -305.224338) (xy 72.48715 -305.23027) (xy 72.437975 -305.228289) (xy 72.389756 -305.218445)
			(xy 72.34374 -305.200993) (xy 72.301119 -305.176386) (xy 72.262998 -305.145261) (xy 72.230363 -305.108424)
			(xy 72.20406 -305.066828) (xy 72.184769 -305.021552) (xy 72.172992 -304.973768) (xy 72.169032 -304.924714)
			(xy 71.830184 -304.924714) (xy 71.829689 -304.949321) (xy 71.821794 -304.997898) (xy 71.80621 -305.044579)
			(xy 71.783339 -305.088156) (xy 71.753774 -305.1275) (xy 71.718281 -305.161592) (xy 71.677778 -305.189548)
			(xy 71.633316 -305.210646) (xy 71.586045 -305.224338) (xy 71.53719 -305.23027) (xy 71.488015 -305.228289)
			(xy 71.439796 -305.218445) (xy 71.39378 -305.200993) (xy 71.351159 -305.176386) (xy 71.313038 -305.145261)
			(xy 71.280403 -305.108424) (xy 71.2541 -305.066828) (xy 71.234809 -305.021552) (xy 71.223032 -304.973768)
			(xy 71.219072 -304.924714) (xy 70.880224 -304.924714) (xy 70.879729 -304.949321) (xy 70.871834 -304.997898)
			(xy 70.85625 -305.044579) (xy 70.833379 -305.088156) (xy 70.803814 -305.1275) (xy 70.768321 -305.161592)
			(xy 70.727818 -305.189548) (xy 70.683356 -305.210646) (xy 70.636085 -305.224338) (xy 70.58723 -305.23027)
			(xy 70.538055 -305.228289) (xy 70.489836 -305.218445) (xy 70.44382 -305.200993) (xy 70.401199 -305.176386)
			(xy 70.363078 -305.145261) (xy 70.330443 -305.108424) (xy 70.30414 -305.066828) (xy 70.284849 -305.021552)
			(xy 70.273072 -304.973768) (xy 70.269112 -304.924714) (xy 69.930264 -304.924714) (xy 69.929769 -304.949321)
			(xy 69.921874 -304.997898) (xy 69.90629 -305.044579) (xy 69.883419 -305.088156) (xy 69.853854 -305.1275)
			(xy 69.818361 -305.161592) (xy 69.777858 -305.189548) (xy 69.733396 -305.210646) (xy 69.686125 -305.224338)
			(xy 69.63727 -305.23027) (xy 69.588095 -305.228289) (xy 69.539876 -305.218445) (xy 69.49386 -305.200993)
			(xy 69.451239 -305.176386) (xy 69.413118 -305.145261) (xy 69.380483 -305.108424) (xy 69.35418 -305.066828)
			(xy 69.334889 -305.021552) (xy 69.323112 -304.973768) (xy 69.319152 -304.924714) (xy 68.98005 -304.924714)
			(xy 68.979555 -304.949321) (xy 68.97166 -304.997898) (xy 68.956076 -305.044579) (xy 68.933205 -305.088156)
			(xy 68.90364 -305.1275) (xy 68.868147 -305.161592) (xy 68.827644 -305.189548) (xy 68.783182 -305.210646)
			(xy 68.735911 -305.224338) (xy 68.687056 -305.23027) (xy 68.637881 -305.228289) (xy 68.589662 -305.218445)
			(xy 68.543646 -305.200993) (xy 68.501025 -305.176386) (xy 68.462904 -305.145261) (xy 68.430269 -305.108424)
			(xy 68.403966 -305.066828) (xy 68.384675 -305.021552) (xy 68.372898 -304.973768) (xy 68.368938 -304.924714)
			(xy 68.03009 -304.924714) (xy 68.029595 -304.949321) (xy 68.0217 -304.997898) (xy 68.006116 -305.044579)
			(xy 67.983245 -305.088156) (xy 67.95368 -305.1275) (xy 67.918187 -305.161592) (xy 67.877684 -305.189548)
			(xy 67.833222 -305.210646) (xy 67.785951 -305.224338) (xy 67.737096 -305.23027) (xy 67.687921 -305.228289)
			(xy 67.639702 -305.218445) (xy 67.593686 -305.200993) (xy 67.551065 -305.176386) (xy 67.512944 -305.145261)
			(xy 67.480309 -305.108424) (xy 67.454006 -305.066828) (xy 67.434715 -305.021552) (xy 67.422938 -304.973768)
			(xy 67.418978 -304.924714) (xy 67.08013 -304.924714) (xy 67.079635 -304.949321) (xy 67.07174 -304.997898)
			(xy 67.056156 -305.044579) (xy 67.033285 -305.088156) (xy 67.00372 -305.1275) (xy 66.968227 -305.161592)
			(xy 66.927724 -305.189548) (xy 66.883262 -305.210646) (xy 66.835991 -305.224338) (xy 66.787136 -305.23027)
			(xy 66.737961 -305.228289) (xy 66.689742 -305.218445) (xy 66.643726 -305.200993) (xy 66.601105 -305.176386)
			(xy 66.562984 -305.145261) (xy 66.530349 -305.108424) (xy 66.504046 -305.066828) (xy 66.484755 -305.021552)
			(xy 66.472978 -304.973768) (xy 66.469018 -304.924714) (xy 66.13017 -304.924714) (xy 66.129675 -304.949321)
			(xy 66.12178 -304.997898) (xy 66.106196 -305.044579) (xy 66.083325 -305.088156) (xy 66.05376 -305.1275)
			(xy 66.018267 -305.161592) (xy 65.977764 -305.189548) (xy 65.933302 -305.210646) (xy 65.886031 -305.224338)
			(xy 65.837176 -305.23027) (xy 65.788001 -305.228289) (xy 65.739782 -305.218445) (xy 65.693766 -305.200993)
			(xy 65.651145 -305.176386) (xy 65.613024 -305.145261) (xy 65.580389 -305.108424) (xy 65.554086 -305.066828)
			(xy 65.534795 -305.021552) (xy 65.523018 -304.973768) (xy 65.519058 -304.924714) (xy 65.18021 -304.924714)
			(xy 65.179715 -304.949321) (xy 65.17182 -304.997898) (xy 65.156236 -305.044579) (xy 65.133365 -305.088156)
			(xy 65.1038 -305.1275) (xy 65.068307 -305.161592) (xy 65.027804 -305.189548) (xy 64.983342 -305.210646)
			(xy 64.936071 -305.224338) (xy 64.887216 -305.23027) (xy 64.838041 -305.228289) (xy 64.789822 -305.218445)
			(xy 64.743806 -305.200993) (xy 64.701185 -305.176386) (xy 64.663064 -305.145261) (xy 64.630429 -305.108424)
			(xy 64.604126 -305.066828) (xy 64.584835 -305.021552) (xy 64.573058 -304.973768) (xy 64.569098 -304.924714)
			(xy 64.23025 -304.924714) (xy 64.229755 -304.949321) (xy 64.22186 -304.997898) (xy 64.206276 -305.044579)
			(xy 64.183405 -305.088156) (xy 64.15384 -305.1275) (xy 64.118347 -305.161592) (xy 64.077844 -305.189548)
			(xy 64.033382 -305.210646) (xy 63.986111 -305.224338) (xy 63.937256 -305.23027) (xy 63.888081 -305.228289)
			(xy 63.839862 -305.218445) (xy 63.793846 -305.200993) (xy 63.751225 -305.176386) (xy 63.713104 -305.145261)
			(xy 63.680469 -305.108424) (xy 63.654166 -305.066828) (xy 63.634875 -305.021552) (xy 63.623098 -304.973768)
			(xy 63.619138 -304.924714) (xy 63.28029 -304.924714) (xy 63.279795 -304.949321) (xy 63.2719 -304.997898)
			(xy 63.256316 -305.044579) (xy 63.233445 -305.088156) (xy 63.20388 -305.1275) (xy 63.168387 -305.161592)
			(xy 63.127884 -305.189548) (xy 63.083422 -305.210646) (xy 63.036151 -305.224338) (xy 62.987296 -305.23027)
			(xy 62.938121 -305.228289) (xy 62.889902 -305.218445) (xy 62.843886 -305.200993) (xy 62.801265 -305.176386)
			(xy 62.763144 -305.145261) (xy 62.730509 -305.108424) (xy 62.704206 -305.066828) (xy 62.684915 -305.021552)
			(xy 62.673138 -304.973768) (xy 62.669178 -304.924714) (xy 62.330076 -304.924714) (xy 62.329581 -304.949321)
			(xy 62.321686 -304.997898) (xy 62.306102 -305.044579) (xy 62.283231 -305.088156) (xy 62.253666 -305.1275)
			(xy 62.218173 -305.161592) (xy 62.17767 -305.189548) (xy 62.133208 -305.210646) (xy 62.085937 -305.224338)
			(xy 62.037082 -305.23027) (xy 61.987907 -305.228289) (xy 61.939688 -305.218445) (xy 61.893672 -305.200993)
			(xy 61.851051 -305.176386) (xy 61.81293 -305.145261) (xy 61.780295 -305.108424) (xy 61.753992 -305.066828)
			(xy 61.734701 -305.021552) (xy 61.722924 -304.973768) (xy 61.718964 -304.924714) (xy 61.380116 -304.924714)
			(xy 61.379621 -304.949321) (xy 61.371726 -304.997898) (xy 61.356142 -305.044579) (xy 61.333271 -305.088156)
			(xy 61.303706 -305.1275) (xy 61.268213 -305.161592) (xy 61.22771 -305.189548) (xy 61.183248 -305.210646)
			(xy 61.135977 -305.224338) (xy 61.087122 -305.23027) (xy 61.037947 -305.228289) (xy 60.989728 -305.218445)
			(xy 60.943712 -305.200993) (xy 60.901091 -305.176386) (xy 60.86297 -305.145261) (xy 60.830335 -305.108424)
			(xy 60.804032 -305.066828) (xy 60.784741 -305.021552) (xy 60.772964 -304.973768) (xy 60.769004 -304.924714)
			(xy 60.430156 -304.924714) (xy 60.429661 -304.949321) (xy 60.421766 -304.997898) (xy 60.406182 -305.044579)
			(xy 60.383311 -305.088156) (xy 60.353746 -305.1275) (xy 60.318253 -305.161592) (xy 60.27775 -305.189548)
			(xy 60.233288 -305.210646) (xy 60.186017 -305.224338) (xy 60.137162 -305.23027) (xy 60.087987 -305.228289)
			(xy 60.039768 -305.218445) (xy 59.993752 -305.200993) (xy 59.951131 -305.176386) (xy 59.91301 -305.145261)
			(xy 59.880375 -305.108424) (xy 59.854072 -305.066828) (xy 59.834781 -305.021552) (xy 59.823004 -304.973768)
			(xy 59.819044 -304.924714) (xy 58.530236 -304.924714) (xy 58.529741 -304.949321) (xy 58.521846 -304.997898)
			(xy 58.506262 -305.044579) (xy 58.483391 -305.088156) (xy 58.453826 -305.1275) (xy 58.418333 -305.161592)
			(xy 58.37783 -305.189548) (xy 58.333368 -305.210646) (xy 58.286097 -305.224338) (xy 58.237242 -305.23027)
			(xy 58.188067 -305.228289) (xy 58.139848 -305.218445) (xy 58.093832 -305.200993) (xy 58.051211 -305.176386)
			(xy 58.01309 -305.145261) (xy 57.980455 -305.108424) (xy 57.954152 -305.066828) (xy 57.934861 -305.021552)
			(xy 57.923084 -304.973768) (xy 57.919124 -304.924714) (xy 57.580276 -304.924714) (xy 57.579781 -304.949321)
			(xy 57.571886 -304.997898) (xy 57.556302 -305.044579) (xy 57.533431 -305.088156) (xy 57.503866 -305.1275)
			(xy 57.468373 -305.161592) (xy 57.42787 -305.189548) (xy 57.383408 -305.210646) (xy 57.336137 -305.224338)
			(xy 57.287282 -305.23027) (xy 57.238107 -305.228289) (xy 57.189888 -305.218445) (xy 57.143872 -305.200993)
			(xy 57.101251 -305.176386) (xy 57.06313 -305.145261) (xy 57.030495 -305.108424) (xy 57.004192 -305.066828)
			(xy 56.984901 -305.021552) (xy 56.973124 -304.973768) (xy 56.969164 -304.924714) (xy 56.630062 -304.924714)
			(xy 56.629567 -304.949321) (xy 56.621672 -304.997898) (xy 56.606088 -305.044579) (xy 56.583217 -305.088156)
			(xy 56.553652 -305.1275) (xy 56.518159 -305.161592) (xy 56.477656 -305.189548) (xy 56.433194 -305.210646)
			(xy 56.385923 -305.224338) (xy 56.337068 -305.23027) (xy 56.287893 -305.228289) (xy 56.239674 -305.218445)
			(xy 56.193658 -305.200993) (xy 56.151037 -305.176386) (xy 56.112916 -305.145261) (xy 56.080281 -305.108424)
			(xy 56.053978 -305.066828) (xy 56.034687 -305.021552) (xy 56.02291 -304.973768) (xy 56.01895 -304.924714)
			(xy 55.680102 -304.924714) (xy 55.679607 -304.949321) (xy 55.671712 -304.997898) (xy 55.656128 -305.044579)
			(xy 55.633257 -305.088156) (xy 55.603692 -305.1275) (xy 55.568199 -305.161592) (xy 55.527696 -305.189548)
			(xy 55.483234 -305.210646) (xy 55.435963 -305.224338) (xy 55.387108 -305.23027) (xy 55.337933 -305.228289)
			(xy 55.289714 -305.218445) (xy 55.243698 -305.200993) (xy 55.201077 -305.176386) (xy 55.162956 -305.145261)
			(xy 55.130321 -305.108424) (xy 55.104018 -305.066828) (xy 55.084727 -305.021552) (xy 55.07295 -304.973768)
			(xy 55.06899 -304.924714) (xy 54.730142 -304.924714) (xy 54.729647 -304.949321) (xy 54.721752 -304.997898)
			(xy 54.706168 -305.044579) (xy 54.683297 -305.088156) (xy 54.653732 -305.1275) (xy 54.618239 -305.161592)
			(xy 54.577736 -305.189548) (xy 54.533274 -305.210646) (xy 54.486003 -305.224338) (xy 54.437148 -305.23027)
			(xy 54.387973 -305.228289) (xy 54.339754 -305.218445) (xy 54.293738 -305.200993) (xy 54.251117 -305.176386)
			(xy 54.212996 -305.145261) (xy 54.180361 -305.108424) (xy 54.154058 -305.066828) (xy 54.134767 -305.021552)
			(xy 54.12299 -304.973768) (xy 54.11903 -304.924714) (xy 53.780182 -304.924714) (xy 53.779687 -304.949321)
			(xy 53.771792 -304.997898) (xy 53.756208 -305.044579) (xy 53.733337 -305.088156) (xy 53.703772 -305.1275)
			(xy 53.668279 -305.161592) (xy 53.627776 -305.189548) (xy 53.583314 -305.210646) (xy 53.536043 -305.224338)
			(xy 53.487188 -305.23027) (xy 53.438013 -305.228289) (xy 53.389794 -305.218445) (xy 53.343778 -305.200993)
			(xy 53.301157 -305.176386) (xy 53.263036 -305.145261) (xy 53.230401 -305.108424) (xy 53.204098 -305.066828)
			(xy 53.184807 -305.021552) (xy 53.17303 -304.973768) (xy 53.16907 -304.924714) (xy 52.830222 -304.924714)
			(xy 52.829727 -304.949321) (xy 52.821832 -304.997898) (xy 52.806248 -305.044579) (xy 52.783377 -305.088156)
			(xy 52.753812 -305.1275) (xy 52.718319 -305.161592) (xy 52.677816 -305.189548) (xy 52.633354 -305.210646)
			(xy 52.586083 -305.224338) (xy 52.537228 -305.23027) (xy 52.488053 -305.228289) (xy 52.439834 -305.218445)
			(xy 52.393818 -305.200993) (xy 52.351197 -305.176386) (xy 52.313076 -305.145261) (xy 52.280441 -305.108424)
			(xy 52.254138 -305.066828) (xy 52.234847 -305.021552) (xy 52.22307 -304.973768) (xy 52.21911 -304.924714)
			(xy 51.880262 -304.924714) (xy 51.879767 -304.949321) (xy 51.871872 -304.997898) (xy 51.856288 -305.044579)
			(xy 51.833417 -305.088156) (xy 51.803852 -305.1275) (xy 51.768359 -305.161592) (xy 51.727856 -305.189548)
			(xy 51.683394 -305.210646) (xy 51.636123 -305.224338) (xy 51.587268 -305.23027) (xy 51.538093 -305.228289)
			(xy 51.489874 -305.218445) (xy 51.443858 -305.200993) (xy 51.401237 -305.176386) (xy 51.363116 -305.145261)
			(xy 51.330481 -305.108424) (xy 51.304178 -305.066828) (xy 51.284887 -305.021552) (xy 51.27311 -304.973768)
			(xy 51.26915 -304.924714) (xy 50.930302 -304.924714) (xy 50.929807 -304.949321) (xy 50.921912 -304.997898)
			(xy 50.906328 -305.044579) (xy 50.883457 -305.088156) (xy 50.853892 -305.1275) (xy 50.818399 -305.161592)
			(xy 50.777896 -305.189548) (xy 50.733434 -305.210646) (xy 50.686163 -305.224338) (xy 50.637308 -305.23027)
			(xy 50.588133 -305.228289) (xy 50.539914 -305.218445) (xy 50.493898 -305.200993) (xy 50.451277 -305.176386)
			(xy 50.413156 -305.145261) (xy 50.380521 -305.108424) (xy 50.354218 -305.066828) (xy 50.334927 -305.021552)
			(xy 50.32315 -304.973768) (xy 50.31919 -304.924714) (xy 49.980088 -304.924714) (xy 49.979593 -304.949321)
			(xy 49.971698 -304.997898) (xy 49.956114 -305.044579) (xy 49.933243 -305.088156) (xy 49.903678 -305.1275)
			(xy 49.868185 -305.161592) (xy 49.827682 -305.189548) (xy 49.78322 -305.210646) (xy 49.735949 -305.224338)
			(xy 49.687094 -305.23027) (xy 49.637919 -305.228289) (xy 49.5897 -305.218445) (xy 49.543684 -305.200993)
			(xy 49.501063 -305.176386) (xy 49.462942 -305.145261) (xy 49.430307 -305.108424) (xy 49.404004 -305.066828)
			(xy 49.384713 -305.021552) (xy 49.372936 -304.973768) (xy 49.368976 -304.924714) (xy 49.068858 -304.924714)
			(xy 49.065838 -304.972817) (xy 49.054192 -305.025233) (xy 49.034546 -305.075203) (xy 49.007377 -305.121515)
			(xy 48.973345 -305.163046) (xy 48.933275 -305.198786) (xy 48.88814 -305.227869) (xy 48.839035 -305.249589)
			(xy 48.813212 -305.256946) (xy 48.796448 -305.261518) (xy 48.77562 -305.288442) (xy 48.77562 -305.399948)
			(xy 73.593972 -305.399948) (xy 73.597932 -305.350894) (xy 73.609709 -305.30311) (xy 73.629 -305.257834)
			(xy 73.655303 -305.216238) (xy 73.687938 -305.179401) (xy 73.726059 -305.148276) (xy 73.76868 -305.123669)
			(xy 73.814696 -305.106217) (xy 73.862915 -305.096373) (xy 73.91209 -305.094392) (xy 73.960945 -305.100324)
			(xy 74.008216 -305.114016) (xy 74.052678 -305.135114) (xy 74.093181 -305.16307) (xy 74.128674 -305.197162)
			(xy 74.158239 -305.236506) (xy 74.18111 -305.280083) (xy 74.196694 -305.326764) (xy 74.204589 -305.375341)
			(xy 74.205084 -305.399948) (xy 74.544186 -305.399948) (xy 74.548146 -305.350894) (xy 74.559923 -305.30311)
			(xy 74.579214 -305.257834) (xy 74.605517 -305.216238) (xy 74.638152 -305.179401) (xy 74.676273 -305.148276)
			(xy 74.718894 -305.123669) (xy 74.76491 -305.106217) (xy 74.813129 -305.096373) (xy 74.862304 -305.094392)
			(xy 74.911159 -305.100324) (xy 74.95843 -305.114016) (xy 75.002892 -305.135114) (xy 75.043395 -305.16307)
			(xy 75.078888 -305.197162) (xy 75.108453 -305.236506) (xy 75.131324 -305.280083) (xy 75.146908 -305.326764)
			(xy 75.154803 -305.375341) (xy 75.155298 -305.399948) (xy 75.494146 -305.399948) (xy 75.498106 -305.350894)
			(xy 75.509883 -305.30311) (xy 75.529174 -305.257834) (xy 75.555477 -305.216238) (xy 75.588112 -305.179401)
			(xy 75.626233 -305.148276) (xy 75.668854 -305.123669) (xy 75.71487 -305.106217) (xy 75.763089 -305.096373)
			(xy 75.812264 -305.094392) (xy 75.861119 -305.100324) (xy 75.90839 -305.114016) (xy 75.952852 -305.135114)
			(xy 75.993355 -305.16307) (xy 76.028848 -305.197162) (xy 76.058413 -305.236506) (xy 76.081284 -305.280083)
			(xy 76.096868 -305.326764) (xy 76.104763 -305.375341) (xy 76.105258 -305.399948) (xy 76.444106 -305.399948)
			(xy 76.448066 -305.350894) (xy 76.459843 -305.30311) (xy 76.479134 -305.257834) (xy 76.505437 -305.216238)
			(xy 76.538072 -305.179401) (xy 76.576193 -305.148276) (xy 76.618814 -305.123669) (xy 76.66483 -305.106217)
			(xy 76.713049 -305.096373) (xy 76.762224 -305.094392) (xy 76.811079 -305.100324) (xy 76.85835 -305.114016)
			(xy 76.902812 -305.135114) (xy 76.943315 -305.16307) (xy 76.978808 -305.197162) (xy 77.008373 -305.236506)
			(xy 77.031244 -305.280083) (xy 77.046828 -305.326764) (xy 77.054723 -305.375341) (xy 77.055218 -305.399948)
			(xy 77.394066 -305.399948) (xy 77.398026 -305.350894) (xy 77.409803 -305.30311) (xy 77.429094 -305.257834)
			(xy 77.455397 -305.216238) (xy 77.488032 -305.179401) (xy 77.526153 -305.148276) (xy 77.568774 -305.123669)
			(xy 77.61479 -305.106217) (xy 77.663009 -305.096373) (xy 77.712184 -305.094392) (xy 77.761039 -305.100324)
			(xy 77.80831 -305.114016) (xy 77.852772 -305.135114) (xy 77.893275 -305.16307) (xy 77.928768 -305.197162)
			(xy 77.958333 -305.236506) (xy 77.981204 -305.280083) (xy 77.996788 -305.326764) (xy 78.004683 -305.375341)
			(xy 78.005178 -305.399948) (xy 78.344026 -305.399948) (xy 78.347986 -305.350894) (xy 78.359763 -305.30311)
			(xy 78.379054 -305.257834) (xy 78.405357 -305.216238) (xy 78.437992 -305.179401) (xy 78.476113 -305.148276)
			(xy 78.518734 -305.123669) (xy 78.56475 -305.106217) (xy 78.612969 -305.096373) (xy 78.662144 -305.094392)
			(xy 78.710999 -305.100324) (xy 78.75827 -305.114016) (xy 78.802732 -305.135114) (xy 78.843235 -305.16307)
			(xy 78.878728 -305.197162) (xy 78.908293 -305.236506) (xy 78.931164 -305.280083) (xy 78.946748 -305.326764)
			(xy 78.954643 -305.375341) (xy 78.955138 -305.399948) (xy 79.293986 -305.399948) (xy 79.297946 -305.350894)
			(xy 79.309723 -305.30311) (xy 79.329014 -305.257834) (xy 79.355317 -305.216238) (xy 79.387952 -305.179401)
			(xy 79.426073 -305.148276) (xy 79.468694 -305.123669) (xy 79.51471 -305.106217) (xy 79.562929 -305.096373)
			(xy 79.612104 -305.094392) (xy 79.660959 -305.100324) (xy 79.70823 -305.114016) (xy 79.752692 -305.135114)
			(xy 79.793195 -305.16307) (xy 79.828688 -305.197162) (xy 79.858253 -305.236506) (xy 79.881124 -305.280083)
			(xy 79.896708 -305.326764) (xy 79.904603 -305.375341) (xy 79.905098 -305.399948) (xy 80.243946 -305.399948)
			(xy 80.247906 -305.350894) (xy 80.259683 -305.30311) (xy 80.278974 -305.257834) (xy 80.305277 -305.216238)
			(xy 80.337912 -305.179401) (xy 80.376033 -305.148276) (xy 80.418654 -305.123669) (xy 80.46467 -305.106217)
			(xy 80.512889 -305.096373) (xy 80.562064 -305.094392) (xy 80.610919 -305.100324) (xy 80.65819 -305.114016)
			(xy 80.702652 -305.135114) (xy 80.743155 -305.16307) (xy 80.778648 -305.197162) (xy 80.808213 -305.236506)
			(xy 80.831084 -305.280083) (xy 80.846668 -305.326764) (xy 80.854563 -305.375341) (xy 80.855058 -305.399948)
			(xy 81.19416 -305.399948) (xy 81.19812 -305.350894) (xy 81.209897 -305.30311) (xy 81.229188 -305.257834)
			(xy 81.255491 -305.216238) (xy 81.288126 -305.179401) (xy 81.326247 -305.148276) (xy 81.368868 -305.123669)
			(xy 81.414884 -305.106217) (xy 81.463103 -305.096373) (xy 81.512278 -305.094392) (xy 81.561133 -305.100324)
			(xy 81.608404 -305.114016) (xy 81.652866 -305.135114) (xy 81.693369 -305.16307) (xy 81.728862 -305.197162)
			(xy 81.758427 -305.236506) (xy 81.781298 -305.280083) (xy 81.796882 -305.326764) (xy 81.804777 -305.375341)
			(xy 81.805272 -305.399948) (xy 82.14412 -305.399948) (xy 82.14808 -305.350894) (xy 82.159857 -305.30311)
			(xy 82.179148 -305.257834) (xy 82.205451 -305.216238) (xy 82.238086 -305.179401) (xy 82.276207 -305.148276)
			(xy 82.318828 -305.123669) (xy 82.364844 -305.106217) (xy 82.413063 -305.096373) (xy 82.462238 -305.094392)
			(xy 82.511093 -305.100324) (xy 82.558364 -305.114016) (xy 82.602826 -305.135114) (xy 82.643329 -305.16307)
			(xy 82.678822 -305.197162) (xy 82.708387 -305.236506) (xy 82.731258 -305.280083) (xy 82.746842 -305.326764)
			(xy 82.754737 -305.375341) (xy 82.755232 -305.399948) (xy 82.754737 -305.424555) (xy 82.746842 -305.473132)
			(xy 82.731258 -305.519813) (xy 82.708387 -305.56339) (xy 82.678822 -305.602734) (xy 82.643329 -305.636826)
			(xy 82.602826 -305.664782) (xy 82.558364 -305.68588) (xy 82.511093 -305.699572) (xy 82.462238 -305.705504)
			(xy 82.413063 -305.703523) (xy 82.364844 -305.693679) (xy 82.318828 -305.676227) (xy 82.276207 -305.65162)
			(xy 82.238086 -305.620495) (xy 82.205451 -305.583658) (xy 82.179148 -305.542062) (xy 82.159857 -305.496786)
			(xy 82.14808 -305.449002) (xy 82.14412 -305.399948) (xy 81.805272 -305.399948) (xy 81.804777 -305.424555)
			(xy 81.796882 -305.473132) (xy 81.781298 -305.519813) (xy 81.758427 -305.56339) (xy 81.728862 -305.602734)
			(xy 81.693369 -305.636826) (xy 81.652866 -305.664782) (xy 81.608404 -305.68588) (xy 81.561133 -305.699572)
			(xy 81.512278 -305.705504) (xy 81.463103 -305.703523) (xy 81.414884 -305.693679) (xy 81.368868 -305.676227)
			(xy 81.326247 -305.65162) (xy 81.288126 -305.620495) (xy 81.255491 -305.583658) (xy 81.229188 -305.542062)
			(xy 81.209897 -305.496786) (xy 81.19812 -305.449002) (xy 81.19416 -305.399948) (xy 80.855058 -305.399948)
			(xy 80.854563 -305.424555) (xy 80.846668 -305.473132) (xy 80.831084 -305.519813) (xy 80.808213 -305.56339)
			(xy 80.778648 -305.602734) (xy 80.743155 -305.636826) (xy 80.702652 -305.664782) (xy 80.65819 -305.68588)
			(xy 80.610919 -305.699572) (xy 80.562064 -305.705504) (xy 80.512889 -305.703523) (xy 80.46467 -305.693679)
			(xy 80.418654 -305.676227) (xy 80.376033 -305.65162) (xy 80.337912 -305.620495) (xy 80.305277 -305.583658)
			(xy 80.278974 -305.542062) (xy 80.259683 -305.496786) (xy 80.247906 -305.449002) (xy 80.243946 -305.399948)
			(xy 79.905098 -305.399948) (xy 79.904603 -305.424555) (xy 79.896708 -305.473132) (xy 79.881124 -305.519813)
			(xy 79.858253 -305.56339) (xy 79.828688 -305.602734) (xy 79.793195 -305.636826) (xy 79.752692 -305.664782)
			(xy 79.70823 -305.68588) (xy 79.660959 -305.699572) (xy 79.612104 -305.705504) (xy 79.562929 -305.703523)
			(xy 79.51471 -305.693679) (xy 79.468694 -305.676227) (xy 79.426073 -305.65162) (xy 79.387952 -305.620495)
			(xy 79.355317 -305.583658) (xy 79.329014 -305.542062) (xy 79.309723 -305.496786) (xy 79.297946 -305.449002)
			(xy 79.293986 -305.399948) (xy 78.955138 -305.399948) (xy 78.954643 -305.424555) (xy 78.946748 -305.473132)
			(xy 78.931164 -305.519813) (xy 78.908293 -305.56339) (xy 78.878728 -305.602734) (xy 78.843235 -305.636826)
			(xy 78.802732 -305.664782) (xy 78.75827 -305.68588) (xy 78.710999 -305.699572) (xy 78.662144 -305.705504)
			(xy 78.612969 -305.703523) (xy 78.56475 -305.693679) (xy 78.518734 -305.676227) (xy 78.476113 -305.65162)
			(xy 78.437992 -305.620495) (xy 78.405357 -305.583658) (xy 78.379054 -305.542062) (xy 78.359763 -305.496786)
			(xy 78.347986 -305.449002) (xy 78.344026 -305.399948) (xy 78.005178 -305.399948) (xy 78.004683 -305.424555)
			(xy 77.996788 -305.473132) (xy 77.981204 -305.519813) (xy 77.958333 -305.56339) (xy 77.928768 -305.602734)
			(xy 77.893275 -305.636826) (xy 77.852772 -305.664782) (xy 77.80831 -305.68588) (xy 77.761039 -305.699572)
			(xy 77.712184 -305.705504) (xy 77.663009 -305.703523) (xy 77.61479 -305.693679) (xy 77.568774 -305.676227)
			(xy 77.526153 -305.65162) (xy 77.488032 -305.620495) (xy 77.455397 -305.583658) (xy 77.429094 -305.542062)
			(xy 77.409803 -305.496786) (xy 77.398026 -305.449002) (xy 77.394066 -305.399948) (xy 77.055218 -305.399948)
			(xy 77.054723 -305.424555) (xy 77.046828 -305.473132) (xy 77.031244 -305.519813) (xy 77.008373 -305.56339)
			(xy 76.978808 -305.602734) (xy 76.943315 -305.636826) (xy 76.902812 -305.664782) (xy 76.85835 -305.68588)
			(xy 76.811079 -305.699572) (xy 76.762224 -305.705504) (xy 76.713049 -305.703523) (xy 76.66483 -305.693679)
			(xy 76.618814 -305.676227) (xy 76.576193 -305.65162) (xy 76.538072 -305.620495) (xy 76.505437 -305.583658)
			(xy 76.479134 -305.542062) (xy 76.459843 -305.496786) (xy 76.448066 -305.449002) (xy 76.444106 -305.399948)
			(xy 76.105258 -305.399948) (xy 76.104763 -305.424555) (xy 76.096868 -305.473132) (xy 76.081284 -305.519813)
			(xy 76.058413 -305.56339) (xy 76.028848 -305.602734) (xy 75.993355 -305.636826) (xy 75.952852 -305.664782)
			(xy 75.90839 -305.68588) (xy 75.861119 -305.699572) (xy 75.812264 -305.705504) (xy 75.763089 -305.703523)
			(xy 75.71487 -305.693679) (xy 75.668854 -305.676227) (xy 75.626233 -305.65162) (xy 75.588112 -305.620495)
			(xy 75.555477 -305.583658) (xy 75.529174 -305.542062) (xy 75.509883 -305.496786) (xy 75.498106 -305.449002)
			(xy 75.494146 -305.399948) (xy 75.155298 -305.399948) (xy 75.154803 -305.424555) (xy 75.146908 -305.473132)
			(xy 75.131324 -305.519813) (xy 75.108453 -305.56339) (xy 75.078888 -305.602734) (xy 75.043395 -305.636826)
			(xy 75.002892 -305.664782) (xy 74.95843 -305.68588) (xy 74.911159 -305.699572) (xy 74.862304 -305.705504)
			(xy 74.813129 -305.703523) (xy 74.76491 -305.693679) (xy 74.718894 -305.676227) (xy 74.676273 -305.65162)
			(xy 74.638152 -305.620495) (xy 74.605517 -305.583658) (xy 74.579214 -305.542062) (xy 74.559923 -305.496786)
			(xy 74.548146 -305.449002) (xy 74.544186 -305.399948) (xy 74.205084 -305.399948) (xy 74.204589 -305.424555)
			(xy 74.196694 -305.473132) (xy 74.18111 -305.519813) (xy 74.158239 -305.56339) (xy 74.128674 -305.602734)
			(xy 74.093181 -305.636826) (xy 74.052678 -305.664782) (xy 74.008216 -305.68588) (xy 73.960945 -305.699572)
			(xy 73.91209 -305.705504) (xy 73.862915 -305.703523) (xy 73.814696 -305.693679) (xy 73.76868 -305.676227)
			(xy 73.726059 -305.65162) (xy 73.687938 -305.620495) (xy 73.655303 -305.583658) (xy 73.629 -305.542062)
			(xy 73.609709 -305.496786) (xy 73.597932 -305.449002) (xy 73.593972 -305.399948) (xy 48.77562 -305.399948)
			(xy 48.77562 -305.465734) (xy 48.788066 -305.488594) (xy 48.798734 -305.495452) (xy 48.804068 -305.499008)
			(xy 48.81372 -305.522884) (xy 48.818346 -305.532924) (xy 48.83441 -305.548077) (xy 48.844708 -305.552094)
			(xy 48.854106 -305.555904) (xy 48.878784 -305.566485) (xy 48.924785 -305.594174) (xy 48.965927 -305.628671)
			(xy 49.001212 -305.66914) (xy 49.029783 -305.714599) (xy 49.050946 -305.763943) (xy 49.064189 -305.815976)
			(xy 49.069189 -305.869434) (xy 49.068844 -305.874928) (xy 49.368976 -305.874928) (xy 49.372936 -305.825874)
			(xy 49.384713 -305.77809) (xy 49.404004 -305.732814) (xy 49.430307 -305.691218) (xy 49.462942 -305.654381)
			(xy 49.501063 -305.623256) (xy 49.543684 -305.598649) (xy 49.5897 -305.581197) (xy 49.637919 -305.571353)
			(xy 49.687094 -305.569372) (xy 49.735949 -305.575304) (xy 49.78322 -305.588996) (xy 49.827682 -305.610094)
			(xy 49.868185 -305.63805) (xy 49.903678 -305.672142) (xy 49.933243 -305.711486) (xy 49.956114 -305.755063)
			(xy 49.971698 -305.801744) (xy 49.979593 -305.850321) (xy 49.980088 -305.874928) (xy 50.31919 -305.874928)
			(xy 50.32315 -305.825874) (xy 50.334927 -305.77809) (xy 50.354218 -305.732814) (xy 50.380521 -305.691218)
			(xy 50.413156 -305.654381) (xy 50.451277 -305.623256) (xy 50.493898 -305.598649) (xy 50.539914 -305.581197)
			(xy 50.588133 -305.571353) (xy 50.637308 -305.569372) (xy 50.686163 -305.575304) (xy 50.733434 -305.588996)
			(xy 50.777896 -305.610094) (xy 50.818399 -305.63805) (xy 50.853892 -305.672142) (xy 50.883457 -305.711486)
			(xy 50.906328 -305.755063) (xy 50.921912 -305.801744) (xy 50.929807 -305.850321) (xy 50.930302 -305.874928)
			(xy 51.26915 -305.874928) (xy 51.27311 -305.825874) (xy 51.284887 -305.77809) (xy 51.304178 -305.732814)
			(xy 51.330481 -305.691218) (xy 51.363116 -305.654381) (xy 51.401237 -305.623256) (xy 51.443858 -305.598649)
			(xy 51.489874 -305.581197) (xy 51.538093 -305.571353) (xy 51.587268 -305.569372) (xy 51.636123 -305.575304)
			(xy 51.683394 -305.588996) (xy 51.727856 -305.610094) (xy 51.768359 -305.63805) (xy 51.803852 -305.672142)
			(xy 51.833417 -305.711486) (xy 51.856288 -305.755063) (xy 51.871872 -305.801744) (xy 51.879767 -305.850321)
			(xy 51.880262 -305.874928) (xy 52.21911 -305.874928) (xy 52.22307 -305.825874) (xy 52.234847 -305.77809)
			(xy 52.254138 -305.732814) (xy 52.280441 -305.691218) (xy 52.313076 -305.654381) (xy 52.351197 -305.623256)
			(xy 52.393818 -305.598649) (xy 52.439834 -305.581197) (xy 52.488053 -305.571353) (xy 52.537228 -305.569372)
			(xy 52.586083 -305.575304) (xy 52.633354 -305.588996) (xy 52.677816 -305.610094) (xy 52.718319 -305.63805)
			(xy 52.753812 -305.672142) (xy 52.783377 -305.711486) (xy 52.806248 -305.755063) (xy 52.821832 -305.801744)
			(xy 52.829727 -305.850321) (xy 52.830222 -305.874928) (xy 53.16907 -305.874928) (xy 53.17303 -305.825874)
			(xy 53.184807 -305.77809) (xy 53.204098 -305.732814) (xy 53.230401 -305.691218) (xy 53.263036 -305.654381)
			(xy 53.301157 -305.623256) (xy 53.343778 -305.598649) (xy 53.389794 -305.581197) (xy 53.438013 -305.571353)
			(xy 53.487188 -305.569372) (xy 53.536043 -305.575304) (xy 53.583314 -305.588996) (xy 53.627776 -305.610094)
			(xy 53.668279 -305.63805) (xy 53.703772 -305.672142) (xy 53.733337 -305.711486) (xy 53.756208 -305.755063)
			(xy 53.771792 -305.801744) (xy 53.779687 -305.850321) (xy 53.780182 -305.874928) (xy 54.11903 -305.874928)
			(xy 54.12299 -305.825874) (xy 54.134767 -305.77809) (xy 54.154058 -305.732814) (xy 54.180361 -305.691218)
			(xy 54.212996 -305.654381) (xy 54.251117 -305.623256) (xy 54.293738 -305.598649) (xy 54.339754 -305.581197)
			(xy 54.387973 -305.571353) (xy 54.437148 -305.569372) (xy 54.486003 -305.575304) (xy 54.533274 -305.588996)
			(xy 54.577736 -305.610094) (xy 54.618239 -305.63805) (xy 54.653732 -305.672142) (xy 54.683297 -305.711486)
			(xy 54.706168 -305.755063) (xy 54.721752 -305.801744) (xy 54.729647 -305.850321) (xy 54.730142 -305.874928)
			(xy 55.06899 -305.874928) (xy 55.07295 -305.825874) (xy 55.084727 -305.77809) (xy 55.104018 -305.732814)
			(xy 55.130321 -305.691218) (xy 55.162956 -305.654381) (xy 55.201077 -305.623256) (xy 55.243698 -305.598649)
			(xy 55.289714 -305.581197) (xy 55.337933 -305.571353) (xy 55.387108 -305.569372) (xy 55.435963 -305.575304)
			(xy 55.483234 -305.588996) (xy 55.527696 -305.610094) (xy 55.568199 -305.63805) (xy 55.603692 -305.672142)
			(xy 55.633257 -305.711486) (xy 55.656128 -305.755063) (xy 55.671712 -305.801744) (xy 55.679607 -305.850321)
			(xy 55.680102 -305.874928) (xy 56.01895 -305.874928) (xy 56.02291 -305.825874) (xy 56.034687 -305.77809)
			(xy 56.053978 -305.732814) (xy 56.080281 -305.691218) (xy 56.112916 -305.654381) (xy 56.151037 -305.623256)
			(xy 56.193658 -305.598649) (xy 56.239674 -305.581197) (xy 56.287893 -305.571353) (xy 56.337068 -305.569372)
			(xy 56.385923 -305.575304) (xy 56.433194 -305.588996) (xy 56.477656 -305.610094) (xy 56.518159 -305.63805)
			(xy 56.553652 -305.672142) (xy 56.583217 -305.711486) (xy 56.606088 -305.755063) (xy 56.621672 -305.801744)
			(xy 56.629567 -305.850321) (xy 56.630062 -305.874928) (xy 56.969164 -305.874928) (xy 56.973124 -305.825874)
			(xy 56.984901 -305.77809) (xy 57.004192 -305.732814) (xy 57.030495 -305.691218) (xy 57.06313 -305.654381)
			(xy 57.101251 -305.623256) (xy 57.143872 -305.598649) (xy 57.189888 -305.581197) (xy 57.238107 -305.571353)
			(xy 57.287282 -305.569372) (xy 57.336137 -305.575304) (xy 57.383408 -305.588996) (xy 57.42787 -305.610094)
			(xy 57.468373 -305.63805) (xy 57.503866 -305.672142) (xy 57.533431 -305.711486) (xy 57.556302 -305.755063)
			(xy 57.571886 -305.801744) (xy 57.579781 -305.850321) (xy 57.580276 -305.874928) (xy 57.919124 -305.874928)
			(xy 57.923084 -305.825874) (xy 57.934861 -305.77809) (xy 57.954152 -305.732814) (xy 57.980455 -305.691218)
			(xy 58.01309 -305.654381) (xy 58.051211 -305.623256) (xy 58.093832 -305.598649) (xy 58.139848 -305.581197)
			(xy 58.188067 -305.571353) (xy 58.237242 -305.569372) (xy 58.286097 -305.575304) (xy 58.333368 -305.588996)
			(xy 58.37783 -305.610094) (xy 58.418333 -305.63805) (xy 58.453826 -305.672142) (xy 58.483391 -305.711486)
			(xy 58.506262 -305.755063) (xy 58.521846 -305.801744) (xy 58.529741 -305.850321) (xy 58.530236 -305.874928)
			(xy 59.819044 -305.874928) (xy 59.823004 -305.825874) (xy 59.834781 -305.77809) (xy 59.854072 -305.732814)
			(xy 59.880375 -305.691218) (xy 59.91301 -305.654381) (xy 59.951131 -305.623256) (xy 59.993752 -305.598649)
			(xy 60.039768 -305.581197) (xy 60.087987 -305.571353) (xy 60.137162 -305.569372) (xy 60.186017 -305.575304)
			(xy 60.233288 -305.588996) (xy 60.27775 -305.610094) (xy 60.318253 -305.63805) (xy 60.353746 -305.672142)
			(xy 60.383311 -305.711486) (xy 60.406182 -305.755063) (xy 60.421766 -305.801744) (xy 60.429661 -305.850321)
			(xy 60.430156 -305.874928) (xy 60.769004 -305.874928) (xy 60.772964 -305.825874) (xy 60.784741 -305.77809)
			(xy 60.804032 -305.732814) (xy 60.830335 -305.691218) (xy 60.86297 -305.654381) (xy 60.901091 -305.623256)
			(xy 60.943712 -305.598649) (xy 60.989728 -305.581197) (xy 61.037947 -305.571353) (xy 61.087122 -305.569372)
			(xy 61.135977 -305.575304) (xy 61.183248 -305.588996) (xy 61.22771 -305.610094) (xy 61.268213 -305.63805)
			(xy 61.303706 -305.672142) (xy 61.333271 -305.711486) (xy 61.356142 -305.755063) (xy 61.371726 -305.801744)
			(xy 61.379621 -305.850321) (xy 61.380116 -305.874928) (xy 61.718964 -305.874928) (xy 61.722924 -305.825874)
			(xy 61.734701 -305.77809) (xy 61.753992 -305.732814) (xy 61.780295 -305.691218) (xy 61.81293 -305.654381)
			(xy 61.851051 -305.623256) (xy 61.893672 -305.598649) (xy 61.939688 -305.581197) (xy 61.987907 -305.571353)
			(xy 62.037082 -305.569372) (xy 62.085937 -305.575304) (xy 62.133208 -305.588996) (xy 62.17767 -305.610094)
			(xy 62.218173 -305.63805) (xy 62.253666 -305.672142) (xy 62.283231 -305.711486) (xy 62.306102 -305.755063)
			(xy 62.321686 -305.801744) (xy 62.329581 -305.850321) (xy 62.330076 -305.874928) (xy 62.669178 -305.874928)
			(xy 62.673138 -305.825874) (xy 62.684915 -305.77809) (xy 62.704206 -305.732814) (xy 62.730509 -305.691218)
			(xy 62.763144 -305.654381) (xy 62.801265 -305.623256) (xy 62.843886 -305.598649) (xy 62.889902 -305.581197)
			(xy 62.938121 -305.571353) (xy 62.987296 -305.569372) (xy 63.036151 -305.575304) (xy 63.083422 -305.588996)
			(xy 63.127884 -305.610094) (xy 63.168387 -305.63805) (xy 63.20388 -305.672142) (xy 63.233445 -305.711486)
			(xy 63.256316 -305.755063) (xy 63.2719 -305.801744) (xy 63.279795 -305.850321) (xy 63.28029 -305.874928)
			(xy 63.619138 -305.874928) (xy 63.623098 -305.825874) (xy 63.634875 -305.77809) (xy 63.654166 -305.732814)
			(xy 63.680469 -305.691218) (xy 63.713104 -305.654381) (xy 63.751225 -305.623256) (xy 63.793846 -305.598649)
			(xy 63.839862 -305.581197) (xy 63.888081 -305.571353) (xy 63.937256 -305.569372) (xy 63.986111 -305.575304)
			(xy 64.033382 -305.588996) (xy 64.077844 -305.610094) (xy 64.118347 -305.63805) (xy 64.15384 -305.672142)
			(xy 64.183405 -305.711486) (xy 64.206276 -305.755063) (xy 64.22186 -305.801744) (xy 64.229755 -305.850321)
			(xy 64.23025 -305.874928) (xy 64.569098 -305.874928) (xy 64.573058 -305.825874) (xy 64.584835 -305.77809)
			(xy 64.604126 -305.732814) (xy 64.630429 -305.691218) (xy 64.663064 -305.654381) (xy 64.701185 -305.623256)
			(xy 64.743806 -305.598649) (xy 64.789822 -305.581197) (xy 64.838041 -305.571353) (xy 64.887216 -305.569372)
			(xy 64.936071 -305.575304) (xy 64.983342 -305.588996) (xy 65.027804 -305.610094) (xy 65.068307 -305.63805)
			(xy 65.1038 -305.672142) (xy 65.133365 -305.711486) (xy 65.156236 -305.755063) (xy 65.17182 -305.801744)
			(xy 65.179715 -305.850321) (xy 65.18021 -305.874928) (xy 65.519058 -305.874928) (xy 65.523018 -305.825874)
			(xy 65.534795 -305.77809) (xy 65.554086 -305.732814) (xy 65.580389 -305.691218) (xy 65.613024 -305.654381)
			(xy 65.651145 -305.623256) (xy 65.693766 -305.598649) (xy 65.739782 -305.581197) (xy 65.788001 -305.571353)
			(xy 65.837176 -305.569372) (xy 65.886031 -305.575304) (xy 65.933302 -305.588996) (xy 65.977764 -305.610094)
			(xy 66.018267 -305.63805) (xy 66.05376 -305.672142) (xy 66.083325 -305.711486) (xy 66.106196 -305.755063)
			(xy 66.12178 -305.801744) (xy 66.129675 -305.850321) (xy 66.13017 -305.874928) (xy 66.469018 -305.874928)
			(xy 66.472978 -305.825874) (xy 66.484755 -305.77809) (xy 66.504046 -305.732814) (xy 66.530349 -305.691218)
			(xy 66.562984 -305.654381) (xy 66.601105 -305.623256) (xy 66.643726 -305.598649) (xy 66.689742 -305.581197)
			(xy 66.737961 -305.571353) (xy 66.787136 -305.569372) (xy 66.835991 -305.575304) (xy 66.883262 -305.588996)
			(xy 66.927724 -305.610094) (xy 66.968227 -305.63805) (xy 67.00372 -305.672142) (xy 67.033285 -305.711486)
			(xy 67.056156 -305.755063) (xy 67.07174 -305.801744) (xy 67.079635 -305.850321) (xy 67.08013 -305.874928)
			(xy 67.418978 -305.874928) (xy 67.422938 -305.825874) (xy 67.434715 -305.77809) (xy 67.454006 -305.732814)
			(xy 67.480309 -305.691218) (xy 67.512944 -305.654381) (xy 67.551065 -305.623256) (xy 67.593686 -305.598649)
			(xy 67.639702 -305.581197) (xy 67.687921 -305.571353) (xy 67.737096 -305.569372) (xy 67.785951 -305.575304)
			(xy 67.833222 -305.588996) (xy 67.877684 -305.610094) (xy 67.918187 -305.63805) (xy 67.95368 -305.672142)
			(xy 67.983245 -305.711486) (xy 68.006116 -305.755063) (xy 68.0217 -305.801744) (xy 68.029595 -305.850321)
			(xy 68.03009 -305.874928) (xy 68.368938 -305.874928) (xy 68.372898 -305.825874) (xy 68.384675 -305.77809)
			(xy 68.403966 -305.732814) (xy 68.430269 -305.691218) (xy 68.462904 -305.654381) (xy 68.501025 -305.623256)
			(xy 68.543646 -305.598649) (xy 68.589662 -305.581197) (xy 68.637881 -305.571353) (xy 68.687056 -305.569372)
			(xy 68.735911 -305.575304) (xy 68.783182 -305.588996) (xy 68.827644 -305.610094) (xy 68.868147 -305.63805)
			(xy 68.90364 -305.672142) (xy 68.933205 -305.711486) (xy 68.956076 -305.755063) (xy 68.97166 -305.801744)
			(xy 68.979555 -305.850321) (xy 68.98005 -305.874928) (xy 69.319152 -305.874928) (xy 69.323112 -305.825874)
			(xy 69.334889 -305.77809) (xy 69.35418 -305.732814) (xy 69.380483 -305.691218) (xy 69.413118 -305.654381)
			(xy 69.451239 -305.623256) (xy 69.49386 -305.598649) (xy 69.539876 -305.581197) (xy 69.588095 -305.571353)
			(xy 69.63727 -305.569372) (xy 69.686125 -305.575304) (xy 69.733396 -305.588996) (xy 69.777858 -305.610094)
			(xy 69.818361 -305.63805) (xy 69.853854 -305.672142) (xy 69.883419 -305.711486) (xy 69.90629 -305.755063)
			(xy 69.921874 -305.801744) (xy 69.929769 -305.850321) (xy 69.930264 -305.874928) (xy 70.269112 -305.874928)
			(xy 70.273072 -305.825874) (xy 70.284849 -305.77809) (xy 70.30414 -305.732814) (xy 70.330443 -305.691218)
			(xy 70.363078 -305.654381) (xy 70.401199 -305.623256) (xy 70.44382 -305.598649) (xy 70.489836 -305.581197)
			(xy 70.538055 -305.571353) (xy 70.58723 -305.569372) (xy 70.636085 -305.575304) (xy 70.683356 -305.588996)
			(xy 70.727818 -305.610094) (xy 70.768321 -305.63805) (xy 70.803814 -305.672142) (xy 70.833379 -305.711486)
			(xy 70.85625 -305.755063) (xy 70.871834 -305.801744) (xy 70.879729 -305.850321) (xy 70.880224 -305.874928)
			(xy 71.219072 -305.874928) (xy 71.223032 -305.825874) (xy 71.234809 -305.77809) (xy 71.2541 -305.732814)
			(xy 71.280403 -305.691218) (xy 71.313038 -305.654381) (xy 71.351159 -305.623256) (xy 71.39378 -305.598649)
			(xy 71.439796 -305.581197) (xy 71.488015 -305.571353) (xy 71.53719 -305.569372) (xy 71.586045 -305.575304)
			(xy 71.633316 -305.588996) (xy 71.677778 -305.610094) (xy 71.718281 -305.63805) (xy 71.753774 -305.672142)
			(xy 71.783339 -305.711486) (xy 71.80621 -305.755063) (xy 71.821794 -305.801744) (xy 71.829689 -305.850321)
			(xy 71.830184 -305.874928) (xy 72.169032 -305.874928) (xy 72.172992 -305.825874) (xy 72.184769 -305.77809)
			(xy 72.20406 -305.732814) (xy 72.230363 -305.691218) (xy 72.262998 -305.654381) (xy 72.301119 -305.623256)
			(xy 72.34374 -305.598649) (xy 72.389756 -305.581197) (xy 72.437975 -305.571353) (xy 72.48715 -305.569372)
			(xy 72.536005 -305.575304) (xy 72.583276 -305.588996) (xy 72.627738 -305.610094) (xy 72.668241 -305.63805)
			(xy 72.703734 -305.672142) (xy 72.733299 -305.711486) (xy 72.75617 -305.755063) (xy 72.771754 -305.801744)
			(xy 72.779649 -305.850321) (xy 72.780144 -305.874928) (xy 72.779649 -305.899535) (xy 72.771754 -305.948112)
			(xy 72.75617 -305.994793) (xy 72.733299 -306.03837) (xy 72.703734 -306.077714) (xy 72.668241 -306.111806)
			(xy 72.627738 -306.139762) (xy 72.583276 -306.16086) (xy 72.536005 -306.174552) (xy 72.48715 -306.180484)
			(xy 72.437975 -306.178503) (xy 72.389756 -306.168659) (xy 72.34374 -306.151207) (xy 72.301119 -306.1266)
			(xy 72.262998 -306.095475) (xy 72.230363 -306.058638) (xy 72.20406 -306.017042) (xy 72.184769 -305.971766)
			(xy 72.172992 -305.923982) (xy 72.169032 -305.874928) (xy 71.830184 -305.874928) (xy 71.829689 -305.899535)
			(xy 71.821794 -305.948112) (xy 71.80621 -305.994793) (xy 71.783339 -306.03837) (xy 71.753774 -306.077714)
			(xy 71.718281 -306.111806) (xy 71.677778 -306.139762) (xy 71.633316 -306.16086) (xy 71.586045 -306.174552)
			(xy 71.53719 -306.180484) (xy 71.488015 -306.178503) (xy 71.439796 -306.168659) (xy 71.39378 -306.151207)
			(xy 71.351159 -306.1266) (xy 71.313038 -306.095475) (xy 71.280403 -306.058638) (xy 71.2541 -306.017042)
			(xy 71.234809 -305.971766) (xy 71.223032 -305.923982) (xy 71.219072 -305.874928) (xy 70.880224 -305.874928)
			(xy 70.879729 -305.899535) (xy 70.871834 -305.948112) (xy 70.85625 -305.994793) (xy 70.833379 -306.03837)
			(xy 70.803814 -306.077714) (xy 70.768321 -306.111806) (xy 70.727818 -306.139762) (xy 70.683356 -306.16086)
			(xy 70.636085 -306.174552) (xy 70.58723 -306.180484) (xy 70.538055 -306.178503) (xy 70.489836 -306.168659)
			(xy 70.44382 -306.151207) (xy 70.401199 -306.1266) (xy 70.363078 -306.095475) (xy 70.330443 -306.058638)
			(xy 70.30414 -306.017042) (xy 70.284849 -305.971766) (xy 70.273072 -305.923982) (xy 70.269112 -305.874928)
			(xy 69.930264 -305.874928) (xy 69.929769 -305.899535) (xy 69.921874 -305.948112) (xy 69.90629 -305.994793)
			(xy 69.883419 -306.03837) (xy 69.853854 -306.077714) (xy 69.818361 -306.111806) (xy 69.777858 -306.139762)
			(xy 69.733396 -306.16086) (xy 69.686125 -306.174552) (xy 69.63727 -306.180484) (xy 69.588095 -306.178503)
			(xy 69.539876 -306.168659) (xy 69.49386 -306.151207) (xy 69.451239 -306.1266) (xy 69.413118 -306.095475)
			(xy 69.380483 -306.058638) (xy 69.35418 -306.017042) (xy 69.334889 -305.971766) (xy 69.323112 -305.923982)
			(xy 69.319152 -305.874928) (xy 68.98005 -305.874928) (xy 68.979555 -305.899535) (xy 68.97166 -305.948112)
			(xy 68.956076 -305.994793) (xy 68.933205 -306.03837) (xy 68.90364 -306.077714) (xy 68.868147 -306.111806)
			(xy 68.827644 -306.139762) (xy 68.783182 -306.16086) (xy 68.735911 -306.174552) (xy 68.687056 -306.180484)
			(xy 68.637881 -306.178503) (xy 68.589662 -306.168659) (xy 68.543646 -306.151207) (xy 68.501025 -306.1266)
			(xy 68.462904 -306.095475) (xy 68.430269 -306.058638) (xy 68.403966 -306.017042) (xy 68.384675 -305.971766)
			(xy 68.372898 -305.923982) (xy 68.368938 -305.874928) (xy 68.03009 -305.874928) (xy 68.029595 -305.899535)
			(xy 68.0217 -305.948112) (xy 68.006116 -305.994793) (xy 67.983245 -306.03837) (xy 67.95368 -306.077714)
			(xy 67.918187 -306.111806) (xy 67.877684 -306.139762) (xy 67.833222 -306.16086) (xy 67.785951 -306.174552)
			(xy 67.737096 -306.180484) (xy 67.687921 -306.178503) (xy 67.639702 -306.168659) (xy 67.593686 -306.151207)
			(xy 67.551065 -306.1266) (xy 67.512944 -306.095475) (xy 67.480309 -306.058638) (xy 67.454006 -306.017042)
			(xy 67.434715 -305.971766) (xy 67.422938 -305.923982) (xy 67.418978 -305.874928) (xy 67.08013 -305.874928)
			(xy 67.079635 -305.899535) (xy 67.07174 -305.948112) (xy 67.056156 -305.994793) (xy 67.033285 -306.03837)
			(xy 67.00372 -306.077714) (xy 66.968227 -306.111806) (xy 66.927724 -306.139762) (xy 66.883262 -306.16086)
			(xy 66.835991 -306.174552) (xy 66.787136 -306.180484) (xy 66.737961 -306.178503) (xy 66.689742 -306.168659)
			(xy 66.643726 -306.151207) (xy 66.601105 -306.1266) (xy 66.562984 -306.095475) (xy 66.530349 -306.058638)
			(xy 66.504046 -306.017042) (xy 66.484755 -305.971766) (xy 66.472978 -305.923982) (xy 66.469018 -305.874928)
			(xy 66.13017 -305.874928) (xy 66.129675 -305.899535) (xy 66.12178 -305.948112) (xy 66.106196 -305.994793)
			(xy 66.083325 -306.03837) (xy 66.05376 -306.077714) (xy 66.018267 -306.111806) (xy 65.977764 -306.139762)
			(xy 65.933302 -306.16086) (xy 65.886031 -306.174552) (xy 65.837176 -306.180484) (xy 65.788001 -306.178503)
			(xy 65.739782 -306.168659) (xy 65.693766 -306.151207) (xy 65.651145 -306.1266) (xy 65.613024 -306.095475)
			(xy 65.580389 -306.058638) (xy 65.554086 -306.017042) (xy 65.534795 -305.971766) (xy 65.523018 -305.923982)
			(xy 65.519058 -305.874928) (xy 65.18021 -305.874928) (xy 65.179715 -305.899535) (xy 65.17182 -305.948112)
			(xy 65.156236 -305.994793) (xy 65.133365 -306.03837) (xy 65.1038 -306.077714) (xy 65.068307 -306.111806)
			(xy 65.027804 -306.139762) (xy 64.983342 -306.16086) (xy 64.936071 -306.174552) (xy 64.887216 -306.180484)
			(xy 64.838041 -306.178503) (xy 64.789822 -306.168659) (xy 64.743806 -306.151207) (xy 64.701185 -306.1266)
			(xy 64.663064 -306.095475) (xy 64.630429 -306.058638) (xy 64.604126 -306.017042) (xy 64.584835 -305.971766)
			(xy 64.573058 -305.923982) (xy 64.569098 -305.874928) (xy 64.23025 -305.874928) (xy 64.229755 -305.899535)
			(xy 64.22186 -305.948112) (xy 64.206276 -305.994793) (xy 64.183405 -306.03837) (xy 64.15384 -306.077714)
			(xy 64.118347 -306.111806) (xy 64.077844 -306.139762) (xy 64.033382 -306.16086) (xy 63.986111 -306.174552)
			(xy 63.937256 -306.180484) (xy 63.888081 -306.178503) (xy 63.839862 -306.168659) (xy 63.793846 -306.151207)
			(xy 63.751225 -306.1266) (xy 63.713104 -306.095475) (xy 63.680469 -306.058638) (xy 63.654166 -306.017042)
			(xy 63.634875 -305.971766) (xy 63.623098 -305.923982) (xy 63.619138 -305.874928) (xy 63.28029 -305.874928)
			(xy 63.279795 -305.899535) (xy 63.2719 -305.948112) (xy 63.256316 -305.994793) (xy 63.233445 -306.03837)
			(xy 63.20388 -306.077714) (xy 63.168387 -306.111806) (xy 63.127884 -306.139762) (xy 63.083422 -306.16086)
			(xy 63.036151 -306.174552) (xy 62.987296 -306.180484) (xy 62.938121 -306.178503) (xy 62.889902 -306.168659)
			(xy 62.843886 -306.151207) (xy 62.801265 -306.1266) (xy 62.763144 -306.095475) (xy 62.730509 -306.058638)
			(xy 62.704206 -306.017042) (xy 62.684915 -305.971766) (xy 62.673138 -305.923982) (xy 62.669178 -305.874928)
			(xy 62.330076 -305.874928) (xy 62.329581 -305.899535) (xy 62.321686 -305.948112) (xy 62.306102 -305.994793)
			(xy 62.283231 -306.03837) (xy 62.253666 -306.077714) (xy 62.218173 -306.111806) (xy 62.17767 -306.139762)
			(xy 62.133208 -306.16086) (xy 62.085937 -306.174552) (xy 62.037082 -306.180484) (xy 61.987907 -306.178503)
			(xy 61.939688 -306.168659) (xy 61.893672 -306.151207) (xy 61.851051 -306.1266) (xy 61.81293 -306.095475)
			(xy 61.780295 -306.058638) (xy 61.753992 -306.017042) (xy 61.734701 -305.971766) (xy 61.722924 -305.923982)
			(xy 61.718964 -305.874928) (xy 61.380116 -305.874928) (xy 61.379621 -305.899535) (xy 61.371726 -305.948112)
			(xy 61.356142 -305.994793) (xy 61.333271 -306.03837) (xy 61.303706 -306.077714) (xy 61.268213 -306.111806)
			(xy 61.22771 -306.139762) (xy 61.183248 -306.16086) (xy 61.135977 -306.174552) (xy 61.087122 -306.180484)
			(xy 61.037947 -306.178503) (xy 60.989728 -306.168659) (xy 60.943712 -306.151207) (xy 60.901091 -306.1266)
			(xy 60.86297 -306.095475) (xy 60.830335 -306.058638) (xy 60.804032 -306.017042) (xy 60.784741 -305.971766)
			(xy 60.772964 -305.923982) (xy 60.769004 -305.874928) (xy 60.430156 -305.874928) (xy 60.429661 -305.899535)
			(xy 60.421766 -305.948112) (xy 60.406182 -305.994793) (xy 60.383311 -306.03837) (xy 60.353746 -306.077714)
			(xy 60.318253 -306.111806) (xy 60.27775 -306.139762) (xy 60.233288 -306.16086) (xy 60.186017 -306.174552)
			(xy 60.137162 -306.180484) (xy 60.087987 -306.178503) (xy 60.039768 -306.168659) (xy 59.993752 -306.151207)
			(xy 59.951131 -306.1266) (xy 59.91301 -306.095475) (xy 59.880375 -306.058638) (xy 59.854072 -306.017042)
			(xy 59.834781 -305.971766) (xy 59.823004 -305.923982) (xy 59.819044 -305.874928) (xy 58.530236 -305.874928)
			(xy 58.529741 -305.899535) (xy 58.521846 -305.948112) (xy 58.506262 -305.994793) (xy 58.483391 -306.03837)
			(xy 58.453826 -306.077714) (xy 58.418333 -306.111806) (xy 58.37783 -306.139762) (xy 58.333368 -306.16086)
			(xy 58.286097 -306.174552) (xy 58.237242 -306.180484) (xy 58.188067 -306.178503) (xy 58.139848 -306.168659)
			(xy 58.093832 -306.151207) (xy 58.051211 -306.1266) (xy 58.01309 -306.095475) (xy 57.980455 -306.058638)
			(xy 57.954152 -306.017042) (xy 57.934861 -305.971766) (xy 57.923084 -305.923982) (xy 57.919124 -305.874928)
			(xy 57.580276 -305.874928) (xy 57.579781 -305.899535) (xy 57.571886 -305.948112) (xy 57.556302 -305.994793)
			(xy 57.533431 -306.03837) (xy 57.503866 -306.077714) (xy 57.468373 -306.111806) (xy 57.42787 -306.139762)
			(xy 57.383408 -306.16086) (xy 57.336137 -306.174552) (xy 57.287282 -306.180484) (xy 57.238107 -306.178503)
			(xy 57.189888 -306.168659) (xy 57.143872 -306.151207) (xy 57.101251 -306.1266) (xy 57.06313 -306.095475)
			(xy 57.030495 -306.058638) (xy 57.004192 -306.017042) (xy 56.984901 -305.971766) (xy 56.973124 -305.923982)
			(xy 56.969164 -305.874928) (xy 56.630062 -305.874928) (xy 56.629567 -305.899535) (xy 56.621672 -305.948112)
			(xy 56.606088 -305.994793) (xy 56.583217 -306.03837) (xy 56.553652 -306.077714) (xy 56.518159 -306.111806)
			(xy 56.477656 -306.139762) (xy 56.433194 -306.16086) (xy 56.385923 -306.174552) (xy 56.337068 -306.180484)
			(xy 56.287893 -306.178503) (xy 56.239674 -306.168659) (xy 56.193658 -306.151207) (xy 56.151037 -306.1266)
			(xy 56.112916 -306.095475) (xy 56.080281 -306.058638) (xy 56.053978 -306.017042) (xy 56.034687 -305.971766)
			(xy 56.02291 -305.923982) (xy 56.01895 -305.874928) (xy 55.680102 -305.874928) (xy 55.679607 -305.899535)
			(xy 55.671712 -305.948112) (xy 55.656128 -305.994793) (xy 55.633257 -306.03837) (xy 55.603692 -306.077714)
			(xy 55.568199 -306.111806) (xy 55.527696 -306.139762) (xy 55.483234 -306.16086) (xy 55.435963 -306.174552)
			(xy 55.387108 -306.180484) (xy 55.337933 -306.178503) (xy 55.289714 -306.168659) (xy 55.243698 -306.151207)
			(xy 55.201077 -306.1266) (xy 55.162956 -306.095475) (xy 55.130321 -306.058638) (xy 55.104018 -306.017042)
			(xy 55.084727 -305.971766) (xy 55.07295 -305.923982) (xy 55.06899 -305.874928) (xy 54.730142 -305.874928)
			(xy 54.729647 -305.899535) (xy 54.721752 -305.948112) (xy 54.706168 -305.994793) (xy 54.683297 -306.03837)
			(xy 54.653732 -306.077714) (xy 54.618239 -306.111806) (xy 54.577736 -306.139762) (xy 54.533274 -306.16086)
			(xy 54.486003 -306.174552) (xy 54.437148 -306.180484) (xy 54.387973 -306.178503) (xy 54.339754 -306.168659)
			(xy 54.293738 -306.151207) (xy 54.251117 -306.1266) (xy 54.212996 -306.095475) (xy 54.180361 -306.058638)
			(xy 54.154058 -306.017042) (xy 54.134767 -305.971766) (xy 54.12299 -305.923982) (xy 54.11903 -305.874928)
			(xy 53.780182 -305.874928) (xy 53.779687 -305.899535) (xy 53.771792 -305.948112) (xy 53.756208 -305.994793)
			(xy 53.733337 -306.03837) (xy 53.703772 -306.077714) (xy 53.668279 -306.111806) (xy 53.627776 -306.139762)
			(xy 53.583314 -306.16086) (xy 53.536043 -306.174552) (xy 53.487188 -306.180484) (xy 53.438013 -306.178503)
			(xy 53.389794 -306.168659) (xy 53.343778 -306.151207) (xy 53.301157 -306.1266) (xy 53.263036 -306.095475)
			(xy 53.230401 -306.058638) (xy 53.204098 -306.017042) (xy 53.184807 -305.971766) (xy 53.17303 -305.923982)
			(xy 53.16907 -305.874928) (xy 52.830222 -305.874928) (xy 52.829727 -305.899535) (xy 52.821832 -305.948112)
			(xy 52.806248 -305.994793) (xy 52.783377 -306.03837) (xy 52.753812 -306.077714) (xy 52.718319 -306.111806)
			(xy 52.677816 -306.139762) (xy 52.633354 -306.16086) (xy 52.586083 -306.174552) (xy 52.537228 -306.180484)
			(xy 52.488053 -306.178503) (xy 52.439834 -306.168659) (xy 52.393818 -306.151207) (xy 52.351197 -306.1266)
			(xy 52.313076 -306.095475) (xy 52.280441 -306.058638) (xy 52.254138 -306.017042) (xy 52.234847 -305.971766)
			(xy 52.22307 -305.923982) (xy 52.21911 -305.874928) (xy 51.880262 -305.874928) (xy 51.879767 -305.899535)
			(xy 51.871872 -305.948112) (xy 51.856288 -305.994793) (xy 51.833417 -306.03837) (xy 51.803852 -306.077714)
			(xy 51.768359 -306.111806) (xy 51.727856 -306.139762) (xy 51.683394 -306.16086) (xy 51.636123 -306.174552)
			(xy 51.587268 -306.180484) (xy 51.538093 -306.178503) (xy 51.489874 -306.168659) (xy 51.443858 -306.151207)
			(xy 51.401237 -306.1266) (xy 51.363116 -306.095475) (xy 51.330481 -306.058638) (xy 51.304178 -306.017042)
			(xy 51.284887 -305.971766) (xy 51.27311 -305.923982) (xy 51.26915 -305.874928) (xy 50.930302 -305.874928)
			(xy 50.929807 -305.899535) (xy 50.921912 -305.948112) (xy 50.906328 -305.994793) (xy 50.883457 -306.03837)
			(xy 50.853892 -306.077714) (xy 50.818399 -306.111806) (xy 50.777896 -306.139762) (xy 50.733434 -306.16086)
			(xy 50.686163 -306.174552) (xy 50.637308 -306.180484) (xy 50.588133 -306.178503) (xy 50.539914 -306.168659)
			(xy 50.493898 -306.151207) (xy 50.451277 -306.1266) (xy 50.413156 -306.095475) (xy 50.380521 -306.058638)
			(xy 50.354218 -306.017042) (xy 50.334927 -305.971766) (xy 50.32315 -305.923982) (xy 50.31919 -305.874928)
			(xy 49.980088 -305.874928) (xy 49.979593 -305.899535) (xy 49.971698 -305.948112) (xy 49.956114 -305.994793)
			(xy 49.933243 -306.03837) (xy 49.903678 -306.077714) (xy 49.868185 -306.111806) (xy 49.827682 -306.139762)
			(xy 49.78322 -306.16086) (xy 49.735949 -306.174552) (xy 49.687094 -306.180484) (xy 49.637919 -306.178503)
			(xy 49.5897 -306.168659) (xy 49.543684 -306.151207) (xy 49.501063 -306.1266) (xy 49.462942 -306.095475)
			(xy 49.430307 -306.058638) (xy 49.404004 -306.017042) (xy 49.384713 -305.971766) (xy 49.372936 -305.923982)
			(xy 49.368976 -305.874928) (xy 49.068844 -305.874928) (xy 49.065825 -305.92302) (xy 49.054178 -305.975433)
			(xy 49.034533 -306.025401) (xy 49.007364 -306.071711) (xy 48.973333 -306.11324) (xy 48.933264 -306.148978)
			(xy 48.88813 -306.17806) (xy 48.839027 -306.199778) (xy 48.813212 -306.20716) (xy 48.796448 -306.211732)
			(xy 48.77562 -306.238656) (xy 48.77562 -306.349908) (xy 73.593972 -306.349908) (xy 73.597932 -306.300854)
			(xy 73.609709 -306.25307) (xy 73.629 -306.207794) (xy 73.655303 -306.166198) (xy 73.687938 -306.129361)
			(xy 73.726059 -306.098236) (xy 73.76868 -306.073629) (xy 73.814696 -306.056177) (xy 73.862915 -306.046333)
			(xy 73.91209 -306.044352) (xy 73.960945 -306.050284) (xy 74.008216 -306.063976) (xy 74.052678 -306.085074)
			(xy 74.093181 -306.11303) (xy 74.128674 -306.147122) (xy 74.158239 -306.186466) (xy 74.18111 -306.230043)
			(xy 74.196694 -306.276724) (xy 74.204589 -306.325301) (xy 74.205084 -306.349908) (xy 74.544186 -306.349908)
			(xy 74.548146 -306.300854) (xy 74.559923 -306.25307) (xy 74.579214 -306.207794) (xy 74.605517 -306.166198)
			(xy 74.638152 -306.129361) (xy 74.676273 -306.098236) (xy 74.718894 -306.073629) (xy 74.76491 -306.056177)
			(xy 74.813129 -306.046333) (xy 74.862304 -306.044352) (xy 74.911159 -306.050284) (xy 74.95843 -306.063976)
			(xy 75.002892 -306.085074) (xy 75.043395 -306.11303) (xy 75.078888 -306.147122) (xy 75.108453 -306.186466)
			(xy 75.131324 -306.230043) (xy 75.146908 -306.276724) (xy 75.154803 -306.325301) (xy 75.155298 -306.349908)
			(xy 75.494146 -306.349908) (xy 75.498106 -306.300854) (xy 75.509883 -306.25307) (xy 75.529174 -306.207794)
			(xy 75.555477 -306.166198) (xy 75.588112 -306.129361) (xy 75.626233 -306.098236) (xy 75.668854 -306.073629)
			(xy 75.71487 -306.056177) (xy 75.763089 -306.046333) (xy 75.812264 -306.044352) (xy 75.861119 -306.050284)
			(xy 75.90839 -306.063976) (xy 75.952852 -306.085074) (xy 75.993355 -306.11303) (xy 76.028848 -306.147122)
			(xy 76.058413 -306.186466) (xy 76.081284 -306.230043) (xy 76.096868 -306.276724) (xy 76.104763 -306.325301)
			(xy 76.105258 -306.349908) (xy 76.444106 -306.349908) (xy 76.448066 -306.300854) (xy 76.459843 -306.25307)
			(xy 76.479134 -306.207794) (xy 76.505437 -306.166198) (xy 76.538072 -306.129361) (xy 76.576193 -306.098236)
			(xy 76.618814 -306.073629) (xy 76.66483 -306.056177) (xy 76.713049 -306.046333) (xy 76.762224 -306.044352)
			(xy 76.811079 -306.050284) (xy 76.85835 -306.063976) (xy 76.902812 -306.085074) (xy 76.943315 -306.11303)
			(xy 76.978808 -306.147122) (xy 77.008373 -306.186466) (xy 77.031244 -306.230043) (xy 77.046828 -306.276724)
			(xy 77.054723 -306.325301) (xy 77.055218 -306.349908) (xy 77.394066 -306.349908) (xy 77.398026 -306.300854)
			(xy 77.409803 -306.25307) (xy 77.429094 -306.207794) (xy 77.455397 -306.166198) (xy 77.488032 -306.129361)
			(xy 77.526153 -306.098236) (xy 77.568774 -306.073629) (xy 77.61479 -306.056177) (xy 77.663009 -306.046333)
			(xy 77.712184 -306.044352) (xy 77.761039 -306.050284) (xy 77.80831 -306.063976) (xy 77.852772 -306.085074)
			(xy 77.893275 -306.11303) (xy 77.928768 -306.147122) (xy 77.958333 -306.186466) (xy 77.981204 -306.230043)
			(xy 77.996788 -306.276724) (xy 78.004683 -306.325301) (xy 78.005178 -306.349908) (xy 78.344026 -306.349908)
			(xy 78.347986 -306.300854) (xy 78.359763 -306.25307) (xy 78.379054 -306.207794) (xy 78.405357 -306.166198)
			(xy 78.437992 -306.129361) (xy 78.476113 -306.098236) (xy 78.518734 -306.073629) (xy 78.56475 -306.056177)
			(xy 78.612969 -306.046333) (xy 78.662144 -306.044352) (xy 78.710999 -306.050284) (xy 78.75827 -306.063976)
			(xy 78.802732 -306.085074) (xy 78.843235 -306.11303) (xy 78.878728 -306.147122) (xy 78.908293 -306.186466)
			(xy 78.931164 -306.230043) (xy 78.946748 -306.276724) (xy 78.954643 -306.325301) (xy 78.955138 -306.349908)
			(xy 79.293986 -306.349908) (xy 79.297946 -306.300854) (xy 79.309723 -306.25307) (xy 79.329014 -306.207794)
			(xy 79.355317 -306.166198) (xy 79.387952 -306.129361) (xy 79.426073 -306.098236) (xy 79.468694 -306.073629)
			(xy 79.51471 -306.056177) (xy 79.562929 -306.046333) (xy 79.612104 -306.044352) (xy 79.660959 -306.050284)
			(xy 79.70823 -306.063976) (xy 79.752692 -306.085074) (xy 79.793195 -306.11303) (xy 79.828688 -306.147122)
			(xy 79.858253 -306.186466) (xy 79.881124 -306.230043) (xy 79.896708 -306.276724) (xy 79.904603 -306.325301)
			(xy 79.905098 -306.349908) (xy 80.243946 -306.349908) (xy 80.247906 -306.300854) (xy 80.259683 -306.25307)
			(xy 80.278974 -306.207794) (xy 80.305277 -306.166198) (xy 80.337912 -306.129361) (xy 80.376033 -306.098236)
			(xy 80.418654 -306.073629) (xy 80.46467 -306.056177) (xy 80.512889 -306.046333) (xy 80.562064 -306.044352)
			(xy 80.610919 -306.050284) (xy 80.65819 -306.063976) (xy 80.702652 -306.085074) (xy 80.743155 -306.11303)
			(xy 80.778648 -306.147122) (xy 80.808213 -306.186466) (xy 80.831084 -306.230043) (xy 80.846668 -306.276724)
			(xy 80.854563 -306.325301) (xy 80.855058 -306.349908) (xy 81.19416 -306.349908) (xy 81.19812 -306.300854)
			(xy 81.209897 -306.25307) (xy 81.229188 -306.207794) (xy 81.255491 -306.166198) (xy 81.288126 -306.129361)
			(xy 81.326247 -306.098236) (xy 81.368868 -306.073629) (xy 81.414884 -306.056177) (xy 81.463103 -306.046333)
			(xy 81.512278 -306.044352) (xy 81.561133 -306.050284) (xy 81.608404 -306.063976) (xy 81.652866 -306.085074)
			(xy 81.693369 -306.11303) (xy 81.728862 -306.147122) (xy 81.758427 -306.186466) (xy 81.781298 -306.230043)
			(xy 81.796882 -306.276724) (xy 81.804777 -306.325301) (xy 81.805272 -306.349908) (xy 82.14412 -306.349908)
			(xy 82.14808 -306.300854) (xy 82.159857 -306.25307) (xy 82.179148 -306.207794) (xy 82.205451 -306.166198)
			(xy 82.238086 -306.129361) (xy 82.276207 -306.098236) (xy 82.318828 -306.073629) (xy 82.364844 -306.056177)
			(xy 82.413063 -306.046333) (xy 82.462238 -306.044352) (xy 82.511093 -306.050284) (xy 82.558364 -306.063976)
			(xy 82.602826 -306.085074) (xy 82.643329 -306.11303) (xy 82.678822 -306.147122) (xy 82.708387 -306.186466)
			(xy 82.731258 -306.230043) (xy 82.746842 -306.276724) (xy 82.754737 -306.325301) (xy 82.755232 -306.349908)
			(xy 83.094334 -306.349908) (xy 83.098294 -306.300854) (xy 83.110071 -306.25307) (xy 83.129362 -306.207794)
			(xy 83.155665 -306.166198) (xy 83.1883 -306.129361) (xy 83.226421 -306.098236) (xy 83.269042 -306.073629)
			(xy 83.315058 -306.056177) (xy 83.363277 -306.046333) (xy 83.412452 -306.044352) (xy 83.461307 -306.050284)
			(xy 83.508578 -306.063976) (xy 83.55304 -306.085074) (xy 83.593543 -306.11303) (xy 83.629036 -306.147122)
			(xy 83.658601 -306.186466) (xy 83.681472 -306.230043) (xy 83.697056 -306.276724) (xy 83.704951 -306.325301)
			(xy 83.705446 -306.349908) (xy 83.704951 -306.374515) (xy 83.697056 -306.423092) (xy 83.681472 -306.469773)
			(xy 83.658601 -306.51335) (xy 83.629036 -306.552694) (xy 83.593543 -306.586786) (xy 83.55304 -306.614742)
			(xy 83.508578 -306.63584) (xy 83.461307 -306.649532) (xy 83.412452 -306.655464) (xy 83.363277 -306.653483)
			(xy 83.315058 -306.643639) (xy 83.269042 -306.626187) (xy 83.226421 -306.60158) (xy 83.1883 -306.570455)
			(xy 83.155665 -306.533618) (xy 83.129362 -306.492022) (xy 83.110071 -306.446746) (xy 83.098294 -306.398962)
			(xy 83.094334 -306.349908) (xy 82.755232 -306.349908) (xy 82.754737 -306.374515) (xy 82.746842 -306.423092)
			(xy 82.731258 -306.469773) (xy 82.708387 -306.51335) (xy 82.678822 -306.552694) (xy 82.643329 -306.586786)
			(xy 82.602826 -306.614742) (xy 82.558364 -306.63584) (xy 82.511093 -306.649532) (xy 82.462238 -306.655464)
			(xy 82.413063 -306.653483) (xy 82.364844 -306.643639) (xy 82.318828 -306.626187) (xy 82.276207 -306.60158)
			(xy 82.238086 -306.570455) (xy 82.205451 -306.533618) (xy 82.179148 -306.492022) (xy 82.159857 -306.446746)
			(xy 82.14808 -306.398962) (xy 82.14412 -306.349908) (xy 81.805272 -306.349908) (xy 81.804777 -306.374515)
			(xy 81.796882 -306.423092) (xy 81.781298 -306.469773) (xy 81.758427 -306.51335) (xy 81.728862 -306.552694)
			(xy 81.693369 -306.586786) (xy 81.652866 -306.614742) (xy 81.608404 -306.63584) (xy 81.561133 -306.649532)
			(xy 81.512278 -306.655464) (xy 81.463103 -306.653483) (xy 81.414884 -306.643639) (xy 81.368868 -306.626187)
			(xy 81.326247 -306.60158) (xy 81.288126 -306.570455) (xy 81.255491 -306.533618) (xy 81.229188 -306.492022)
			(xy 81.209897 -306.446746) (xy 81.19812 -306.398962) (xy 81.19416 -306.349908) (xy 80.855058 -306.349908)
			(xy 80.854563 -306.374515) (xy 80.846668 -306.423092) (xy 80.831084 -306.469773) (xy 80.808213 -306.51335)
			(xy 80.778648 -306.552694) (xy 80.743155 -306.586786) (xy 80.702652 -306.614742) (xy 80.65819 -306.63584)
			(xy 80.610919 -306.649532) (xy 80.562064 -306.655464) (xy 80.512889 -306.653483) (xy 80.46467 -306.643639)
			(xy 80.418654 -306.626187) (xy 80.376033 -306.60158) (xy 80.337912 -306.570455) (xy 80.305277 -306.533618)
			(xy 80.278974 -306.492022) (xy 80.259683 -306.446746) (xy 80.247906 -306.398962) (xy 80.243946 -306.349908)
			(xy 79.905098 -306.349908) (xy 79.904603 -306.374515) (xy 79.896708 -306.423092) (xy 79.881124 -306.469773)
			(xy 79.858253 -306.51335) (xy 79.828688 -306.552694) (xy 79.793195 -306.586786) (xy 79.752692 -306.614742)
			(xy 79.70823 -306.63584) (xy 79.660959 -306.649532) (xy 79.612104 -306.655464) (xy 79.562929 -306.653483)
			(xy 79.51471 -306.643639) (xy 79.468694 -306.626187) (xy 79.426073 -306.60158) (xy 79.387952 -306.570455)
			(xy 79.355317 -306.533618) (xy 79.329014 -306.492022) (xy 79.309723 -306.446746) (xy 79.297946 -306.398962)
			(xy 79.293986 -306.349908) (xy 78.955138 -306.349908) (xy 78.954643 -306.374515) (xy 78.946748 -306.423092)
			(xy 78.931164 -306.469773) (xy 78.908293 -306.51335) (xy 78.878728 -306.552694) (xy 78.843235 -306.586786)
			(xy 78.802732 -306.614742) (xy 78.75827 -306.63584) (xy 78.710999 -306.649532) (xy 78.662144 -306.655464)
			(xy 78.612969 -306.653483) (xy 78.56475 -306.643639) (xy 78.518734 -306.626187) (xy 78.476113 -306.60158)
			(xy 78.437992 -306.570455) (xy 78.405357 -306.533618) (xy 78.379054 -306.492022) (xy 78.359763 -306.446746)
			(xy 78.347986 -306.398962) (xy 78.344026 -306.349908) (xy 78.005178 -306.349908) (xy 78.004683 -306.374515)
			(xy 77.996788 -306.423092) (xy 77.981204 -306.469773) (xy 77.958333 -306.51335) (xy 77.928768 -306.552694)
			(xy 77.893275 -306.586786) (xy 77.852772 -306.614742) (xy 77.80831 -306.63584) (xy 77.761039 -306.649532)
			(xy 77.712184 -306.655464) (xy 77.663009 -306.653483) (xy 77.61479 -306.643639) (xy 77.568774 -306.626187)
			(xy 77.526153 -306.60158) (xy 77.488032 -306.570455) (xy 77.455397 -306.533618) (xy 77.429094 -306.492022)
			(xy 77.409803 -306.446746) (xy 77.398026 -306.398962) (xy 77.394066 -306.349908) (xy 77.055218 -306.349908)
			(xy 77.054723 -306.374515) (xy 77.046828 -306.423092) (xy 77.031244 -306.469773) (xy 77.008373 -306.51335)
			(xy 76.978808 -306.552694) (xy 76.943315 -306.586786) (xy 76.902812 -306.614742) (xy 76.85835 -306.63584)
			(xy 76.811079 -306.649532) (xy 76.762224 -306.655464) (xy 76.713049 -306.653483) (xy 76.66483 -306.643639)
			(xy 76.618814 -306.626187) (xy 76.576193 -306.60158) (xy 76.538072 -306.570455) (xy 76.505437 -306.533618)
			(xy 76.479134 -306.492022) (xy 76.459843 -306.446746) (xy 76.448066 -306.398962) (xy 76.444106 -306.349908)
			(xy 76.105258 -306.349908) (xy 76.104763 -306.374515) (xy 76.096868 -306.423092) (xy 76.081284 -306.469773)
			(xy 76.058413 -306.51335) (xy 76.028848 -306.552694) (xy 75.993355 -306.586786) (xy 75.952852 -306.614742)
			(xy 75.90839 -306.63584) (xy 75.861119 -306.649532) (xy 75.812264 -306.655464) (xy 75.763089 -306.653483)
			(xy 75.71487 -306.643639) (xy 75.668854 -306.626187) (xy 75.626233 -306.60158) (xy 75.588112 -306.570455)
			(xy 75.555477 -306.533618) (xy 75.529174 -306.492022) (xy 75.509883 -306.446746) (xy 75.498106 -306.398962)
			(xy 75.494146 -306.349908) (xy 75.155298 -306.349908) (xy 75.154803 -306.374515) (xy 75.146908 -306.423092)
			(xy 75.131324 -306.469773) (xy 75.108453 -306.51335) (xy 75.078888 -306.552694) (xy 75.043395 -306.586786)
			(xy 75.002892 -306.614742) (xy 74.95843 -306.63584) (xy 74.911159 -306.649532) (xy 74.862304 -306.655464)
			(xy 74.813129 -306.653483) (xy 74.76491 -306.643639) (xy 74.718894 -306.626187) (xy 74.676273 -306.60158)
			(xy 74.638152 -306.570455) (xy 74.605517 -306.533618) (xy 74.579214 -306.492022) (xy 74.559923 -306.446746)
			(xy 74.548146 -306.398962) (xy 74.544186 -306.349908) (xy 74.205084 -306.349908) (xy 74.204589 -306.374515)
			(xy 74.196694 -306.423092) (xy 74.18111 -306.469773) (xy 74.158239 -306.51335) (xy 74.128674 -306.552694)
			(xy 74.093181 -306.586786) (xy 74.052678 -306.614742) (xy 74.008216 -306.63584) (xy 73.960945 -306.649532)
			(xy 73.91209 -306.655464) (xy 73.862915 -306.653483) (xy 73.814696 -306.643639) (xy 73.76868 -306.626187)
			(xy 73.726059 -306.60158) (xy 73.687938 -306.570455) (xy 73.655303 -306.533618) (xy 73.629 -306.492022)
			(xy 73.609709 -306.446746) (xy 73.597932 -306.398962) (xy 73.593972 -306.349908) (xy 48.77562 -306.349908)
			(xy 48.77562 -306.415694) (xy 48.788066 -306.438554) (xy 48.798734 -306.445412) (xy 48.804068 -306.448968)
			(xy 48.81372 -306.472844) (xy 48.818354 -306.482876) (xy 48.834423 -306.49801) (xy 48.844708 -306.502054)
			(xy 48.854106 -306.505864) (xy 48.877704 -306.515965) (xy 48.921859 -306.542137) (xy 48.961636 -306.574579)
			(xy 48.996151 -306.612571) (xy 49.024639 -306.655269) (xy 49.046467 -306.701725) (xy 49.061151 -306.750909)
			(xy 49.068364 -306.801729) (xy 49.067947 -306.853056) (xy 49.064418 -306.878482) (xy 49.06264 -306.890166)
			(xy 49.069498 -306.912518) (xy 49.14011 -306.988464) (xy 49.1617 -306.996592) (xy 49.173638 -306.995576)
			(xy 49.1998 -306.99456) (xy 49.213982 -306.994747) (xy 49.242222 -306.99742) (xy 49.256188 -306.999894)
			(xy 49.268634 -307.00218) (xy 49.292256 -306.994814) (xy 49.369726 -306.917344) (xy 49.377092 -306.893722)
			(xy 49.374806 -306.881276) (xy 49.372321 -306.867311) (xy 49.369651 -306.839071) (xy 49.369472 -306.824888)
			(xy 49.369994 -306.799633) (xy 49.378307 -306.749811) (xy 49.394708 -306.702037) (xy 49.418749 -306.657614)
			(xy 49.449773 -306.617754) (xy 49.486935 -306.583544) (xy 49.529221 -306.555918) (xy 49.575477 -306.535628)
			(xy 49.624442 -306.523228) (xy 49.67478 -306.519057) (xy 49.725118 -306.523228) (xy 49.774083 -306.535628)
			(xy 49.820339 -306.555918) (xy 49.862625 -306.583544) (xy 49.899787 -306.617754) (xy 49.930811 -306.657614)
			(xy 49.954852 -306.702037) (xy 49.971253 -306.749811) (xy 49.979566 -306.799633) (xy 49.980088 -306.824888)
			(xy 49.979902 -306.83907) (xy 49.977229 -306.86731) (xy 49.974754 -306.881276) (xy 49.972468 -306.893722)
			(xy 49.979834 -306.917344) (xy 50.057304 -306.994814) (xy 50.080926 -307.00218) (xy 50.093372 -306.999894)
			(xy 50.107337 -306.997407) (xy 50.135577 -306.994732) (xy 50.14976 -306.99456) (xy 50.164006 -306.994738)
			(xy 50.192373 -306.997412) (xy 50.206402 -306.999894) (xy 50.218594 -307.00218) (xy 50.242724 -306.994814)
			(xy 50.31994 -306.917598) (xy 50.327306 -306.893722) (xy 50.32502 -306.881276) (xy 50.322535 -306.867311)
			(xy 50.319864 -306.839071) (xy 50.319686 -306.824888) (xy 50.320173 -306.800067) (xy 50.328206 -306.751079)
			(xy 50.344059 -306.704035) (xy 50.367313 -306.660176) (xy 50.397357 -306.620658) (xy 50.433399 -306.58652)
			(xy 50.474488 -306.558662) (xy 50.519543 -306.53782) (xy 50.567377 -306.524541) (xy 50.616728 -306.519175)
			(xy 50.666298 -306.521864) (xy 50.714779 -306.532537) (xy 50.760895 -306.550913) (xy 50.803431 -306.576508)
			(xy 50.841266 -306.608647) (xy 50.873403 -306.646484) (xy 50.898995 -306.689021) (xy 50.917368 -306.735138)
			(xy 50.928038 -306.78362) (xy 50.930275 -306.824888) (xy 51.26915 -306.824888) (xy 51.27311 -306.775834)
			(xy 51.284887 -306.72805) (xy 51.304178 -306.682774) (xy 51.330481 -306.641178) (xy 51.363116 -306.604341)
			(xy 51.401237 -306.573216) (xy 51.443858 -306.548609) (xy 51.489874 -306.531157) (xy 51.538093 -306.521313)
			(xy 51.587268 -306.519332) (xy 51.636123 -306.525264) (xy 51.683394 -306.538956) (xy 51.727856 -306.560054)
			(xy 51.768359 -306.58801) (xy 51.803852 -306.622102) (xy 51.833417 -306.661446) (xy 51.856288 -306.705023)
			(xy 51.871872 -306.751704) (xy 51.879767 -306.800281) (xy 51.880262 -306.824888) (xy 52.21911 -306.824888)
			(xy 52.22307 -306.775834) (xy 52.234847 -306.72805) (xy 52.254138 -306.682774) (xy 52.280441 -306.641178)
			(xy 52.313076 -306.604341) (xy 52.351197 -306.573216) (xy 52.393818 -306.548609) (xy 52.439834 -306.531157)
			(xy 52.488053 -306.521313) (xy 52.537228 -306.519332) (xy 52.586083 -306.525264) (xy 52.633354 -306.538956)
			(xy 52.677816 -306.560054) (xy 52.718319 -306.58801) (xy 52.753812 -306.622102) (xy 52.783377 -306.661446)
			(xy 52.806248 -306.705023) (xy 52.821832 -306.751704) (xy 52.829727 -306.800281) (xy 52.830222 -306.824888)
			(xy 53.16907 -306.824888) (xy 53.17303 -306.775834) (xy 53.184807 -306.72805) (xy 53.204098 -306.682774)
			(xy 53.230401 -306.641178) (xy 53.263036 -306.604341) (xy 53.301157 -306.573216) (xy 53.343778 -306.548609)
			(xy 53.389794 -306.531157) (xy 53.438013 -306.521313) (xy 53.487188 -306.519332) (xy 53.536043 -306.525264)
			(xy 53.583314 -306.538956) (xy 53.627776 -306.560054) (xy 53.668279 -306.58801) (xy 53.703772 -306.622102)
			(xy 53.733337 -306.661446) (xy 53.756208 -306.705023) (xy 53.771792 -306.751704) (xy 53.779687 -306.800281)
			(xy 53.780182 -306.824888) (xy 54.11903 -306.824888) (xy 54.12299 -306.775834) (xy 54.134767 -306.72805)
			(xy 54.154058 -306.682774) (xy 54.180361 -306.641178) (xy 54.212996 -306.604341) (xy 54.251117 -306.573216)
			(xy 54.293738 -306.548609) (xy 54.339754 -306.531157) (xy 54.387973 -306.521313) (xy 54.437148 -306.519332)
			(xy 54.486003 -306.525264) (xy 54.533274 -306.538956) (xy 54.577736 -306.560054) (xy 54.618239 -306.58801)
			(xy 54.653732 -306.622102) (xy 54.683297 -306.661446) (xy 54.706168 -306.705023) (xy 54.721752 -306.751704)
			(xy 54.729647 -306.800281) (xy 54.730142 -306.824888) (xy 55.06899 -306.824888) (xy 55.07295 -306.775834)
			(xy 55.084727 -306.72805) (xy 55.104018 -306.682774) (xy 55.130321 -306.641178) (xy 55.162956 -306.604341)
			(xy 55.201077 -306.573216) (xy 55.243698 -306.548609) (xy 55.289714 -306.531157) (xy 55.337933 -306.521313)
			(xy 55.387108 -306.519332) (xy 55.435963 -306.525264) (xy 55.483234 -306.538956) (xy 55.527696 -306.560054)
			(xy 55.568199 -306.58801) (xy 55.603692 -306.622102) (xy 55.633257 -306.661446) (xy 55.656128 -306.705023)
			(xy 55.671712 -306.751704) (xy 55.679607 -306.800281) (xy 55.680102 -306.824888) (xy 56.01895 -306.824888)
			(xy 56.02291 -306.775834) (xy 56.034687 -306.72805) (xy 56.053978 -306.682774) (xy 56.080281 -306.641178)
			(xy 56.112916 -306.604341) (xy 56.151037 -306.573216) (xy 56.193658 -306.548609) (xy 56.239674 -306.531157)
			(xy 56.287893 -306.521313) (xy 56.337068 -306.519332) (xy 56.385923 -306.525264) (xy 56.433194 -306.538956)
			(xy 56.477656 -306.560054) (xy 56.518159 -306.58801) (xy 56.553652 -306.622102) (xy 56.583217 -306.661446)
			(xy 56.606088 -306.705023) (xy 56.621672 -306.751704) (xy 56.629567 -306.800281) (xy 56.630062 -306.824888)
			(xy 56.969164 -306.824888) (xy 56.973124 -306.775834) (xy 56.984901 -306.72805) (xy 57.004192 -306.682774)
			(xy 57.030495 -306.641178) (xy 57.06313 -306.604341) (xy 57.101251 -306.573216) (xy 57.143872 -306.548609)
			(xy 57.189888 -306.531157) (xy 57.238107 -306.521313) (xy 57.287282 -306.519332) (xy 57.336137 -306.525264)
			(xy 57.383408 -306.538956) (xy 57.42787 -306.560054) (xy 57.468373 -306.58801) (xy 57.503866 -306.622102)
			(xy 57.533431 -306.661446) (xy 57.556302 -306.705023) (xy 57.571886 -306.751704) (xy 57.579781 -306.800281)
			(xy 57.580276 -306.824888) (xy 57.919124 -306.824888) (xy 57.923084 -306.775834) (xy 57.934861 -306.72805)
			(xy 57.954152 -306.682774) (xy 57.980455 -306.641178) (xy 58.01309 -306.604341) (xy 58.051211 -306.573216)
			(xy 58.093832 -306.548609) (xy 58.139848 -306.531157) (xy 58.188067 -306.521313) (xy 58.237242 -306.519332)
			(xy 58.286097 -306.525264) (xy 58.333368 -306.538956) (xy 58.37783 -306.560054) (xy 58.418333 -306.58801)
			(xy 58.453826 -306.622102) (xy 58.483391 -306.661446) (xy 58.506262 -306.705023) (xy 58.521846 -306.751704)
			(xy 58.529741 -306.800281) (xy 58.530236 -306.824888) (xy 59.819044 -306.824888) (xy 59.823004 -306.775834)
			(xy 59.834781 -306.72805) (xy 59.854072 -306.682774) (xy 59.880375 -306.641178) (xy 59.91301 -306.604341)
			(xy 59.951131 -306.573216) (xy 59.993752 -306.548609) (xy 60.039768 -306.531157) (xy 60.087987 -306.521313)
			(xy 60.137162 -306.519332) (xy 60.186017 -306.525264) (xy 60.233288 -306.538956) (xy 60.27775 -306.560054)
			(xy 60.318253 -306.58801) (xy 60.353746 -306.622102) (xy 60.383311 -306.661446) (xy 60.406182 -306.705023)
			(xy 60.421766 -306.751704) (xy 60.429661 -306.800281) (xy 60.430156 -306.824888) (xy 60.769004 -306.824888)
			(xy 60.772964 -306.775834) (xy 60.784741 -306.72805) (xy 60.804032 -306.682774) (xy 60.830335 -306.641178)
			(xy 60.86297 -306.604341) (xy 60.901091 -306.573216) (xy 60.943712 -306.548609) (xy 60.989728 -306.531157)
			(xy 61.037947 -306.521313) (xy 61.087122 -306.519332) (xy 61.135977 -306.525264) (xy 61.183248 -306.538956)
			(xy 61.22771 -306.560054) (xy 61.268213 -306.58801) (xy 61.303706 -306.622102) (xy 61.333271 -306.661446)
			(xy 61.356142 -306.705023) (xy 61.371726 -306.751704) (xy 61.379621 -306.800281) (xy 61.380116 -306.824888)
			(xy 61.718964 -306.824888) (xy 61.722924 -306.775834) (xy 61.734701 -306.72805) (xy 61.753992 -306.682774)
			(xy 61.780295 -306.641178) (xy 61.81293 -306.604341) (xy 61.851051 -306.573216) (xy 61.893672 -306.548609)
			(xy 61.939688 -306.531157) (xy 61.987907 -306.521313) (xy 62.037082 -306.519332) (xy 62.085937 -306.525264)
			(xy 62.133208 -306.538956) (xy 62.17767 -306.560054) (xy 62.218173 -306.58801) (xy 62.253666 -306.622102)
			(xy 62.283231 -306.661446) (xy 62.306102 -306.705023) (xy 62.321686 -306.751704) (xy 62.329581 -306.800281)
			(xy 62.330076 -306.824888) (xy 62.669178 -306.824888) (xy 62.673138 -306.775834) (xy 62.684915 -306.72805)
			(xy 62.704206 -306.682774) (xy 62.730509 -306.641178) (xy 62.763144 -306.604341) (xy 62.801265 -306.573216)
			(xy 62.843886 -306.548609) (xy 62.889902 -306.531157) (xy 62.938121 -306.521313) (xy 62.987296 -306.519332)
			(xy 63.036151 -306.525264) (xy 63.083422 -306.538956) (xy 63.127884 -306.560054) (xy 63.168387 -306.58801)
			(xy 63.20388 -306.622102) (xy 63.233445 -306.661446) (xy 63.256316 -306.705023) (xy 63.2719 -306.751704)
			(xy 63.279795 -306.800281) (xy 63.28029 -306.824888) (xy 63.619138 -306.824888) (xy 63.623098 -306.775834)
			(xy 63.634875 -306.72805) (xy 63.654166 -306.682774) (xy 63.680469 -306.641178) (xy 63.713104 -306.604341)
			(xy 63.751225 -306.573216) (xy 63.793846 -306.548609) (xy 63.839862 -306.531157) (xy 63.888081 -306.521313)
			(xy 63.937256 -306.519332) (xy 63.986111 -306.525264) (xy 64.033382 -306.538956) (xy 64.077844 -306.560054)
			(xy 64.118347 -306.58801) (xy 64.15384 -306.622102) (xy 64.183405 -306.661446) (xy 64.206276 -306.705023)
			(xy 64.22186 -306.751704) (xy 64.229755 -306.800281) (xy 64.23025 -306.824888) (xy 64.569098 -306.824888)
			(xy 64.573058 -306.775834) (xy 64.584835 -306.72805) (xy 64.604126 -306.682774) (xy 64.630429 -306.641178)
			(xy 64.663064 -306.604341) (xy 64.701185 -306.573216) (xy 64.743806 -306.548609) (xy 64.789822 -306.531157)
			(xy 64.838041 -306.521313) (xy 64.887216 -306.519332) (xy 64.936071 -306.525264) (xy 64.983342 -306.538956)
			(xy 65.027804 -306.560054) (xy 65.068307 -306.58801) (xy 65.1038 -306.622102) (xy 65.133365 -306.661446)
			(xy 65.156236 -306.705023) (xy 65.17182 -306.751704) (xy 65.179715 -306.800281) (xy 65.18021 -306.824888)
			(xy 65.519058 -306.824888) (xy 65.523018 -306.775834) (xy 65.534795 -306.72805) (xy 65.554086 -306.682774)
			(xy 65.580389 -306.641178) (xy 65.613024 -306.604341) (xy 65.651145 -306.573216) (xy 65.693766 -306.548609)
			(xy 65.739782 -306.531157) (xy 65.788001 -306.521313) (xy 65.837176 -306.519332) (xy 65.886031 -306.525264)
			(xy 65.933302 -306.538956) (xy 65.977764 -306.560054) (xy 66.018267 -306.58801) (xy 66.05376 -306.622102)
			(xy 66.083325 -306.661446) (xy 66.106196 -306.705023) (xy 66.12178 -306.751704) (xy 66.129675 -306.800281)
			(xy 66.13017 -306.824888) (xy 66.469018 -306.824888) (xy 66.472978 -306.775834) (xy 66.484755 -306.72805)
			(xy 66.504046 -306.682774) (xy 66.530349 -306.641178) (xy 66.562984 -306.604341) (xy 66.601105 -306.573216)
			(xy 66.643726 -306.548609) (xy 66.689742 -306.531157) (xy 66.737961 -306.521313) (xy 66.787136 -306.519332)
			(xy 66.835991 -306.525264) (xy 66.883262 -306.538956) (xy 66.927724 -306.560054) (xy 66.968227 -306.58801)
			(xy 67.00372 -306.622102) (xy 67.033285 -306.661446) (xy 67.056156 -306.705023) (xy 67.07174 -306.751704)
			(xy 67.079635 -306.800281) (xy 67.08013 -306.824888) (xy 67.418978 -306.824888) (xy 67.422938 -306.775834)
			(xy 67.434715 -306.72805) (xy 67.454006 -306.682774) (xy 67.480309 -306.641178) (xy 67.512944 -306.604341)
			(xy 67.551065 -306.573216) (xy 67.593686 -306.548609) (xy 67.639702 -306.531157) (xy 67.687921 -306.521313)
			(xy 67.737096 -306.519332) (xy 67.785951 -306.525264) (xy 67.833222 -306.538956) (xy 67.877684 -306.560054)
			(xy 67.918187 -306.58801) (xy 67.95368 -306.622102) (xy 67.983245 -306.661446) (xy 68.006116 -306.705023)
			(xy 68.0217 -306.751704) (xy 68.029595 -306.800281) (xy 68.03009 -306.824888) (xy 68.368938 -306.824888)
			(xy 68.372898 -306.775834) (xy 68.384675 -306.72805) (xy 68.403966 -306.682774) (xy 68.430269 -306.641178)
			(xy 68.462904 -306.604341) (xy 68.501025 -306.573216) (xy 68.543646 -306.548609) (xy 68.589662 -306.531157)
			(xy 68.637881 -306.521313) (xy 68.687056 -306.519332) (xy 68.735911 -306.525264) (xy 68.783182 -306.538956)
			(xy 68.827644 -306.560054) (xy 68.868147 -306.58801) (xy 68.90364 -306.622102) (xy 68.933205 -306.661446)
			(xy 68.956076 -306.705023) (xy 68.97166 -306.751704) (xy 68.979555 -306.800281) (xy 68.98005 -306.824888)
			(xy 69.319152 -306.824888) (xy 69.323112 -306.775834) (xy 69.334889 -306.72805) (xy 69.35418 -306.682774)
			(xy 69.380483 -306.641178) (xy 69.413118 -306.604341) (xy 69.451239 -306.573216) (xy 69.49386 -306.548609)
			(xy 69.539876 -306.531157) (xy 69.588095 -306.521313) (xy 69.63727 -306.519332) (xy 69.686125 -306.525264)
			(xy 69.733396 -306.538956) (xy 69.777858 -306.560054) (xy 69.818361 -306.58801) (xy 69.853854 -306.622102)
			(xy 69.883419 -306.661446) (xy 69.90629 -306.705023) (xy 69.921874 -306.751704) (xy 69.929769 -306.800281)
			(xy 69.930264 -306.824888) (xy 70.269112 -306.824888) (xy 70.273072 -306.775834) (xy 70.284849 -306.72805)
			(xy 70.30414 -306.682774) (xy 70.330443 -306.641178) (xy 70.363078 -306.604341) (xy 70.401199 -306.573216)
			(xy 70.44382 -306.548609) (xy 70.489836 -306.531157) (xy 70.538055 -306.521313) (xy 70.58723 -306.519332)
			(xy 70.636085 -306.525264) (xy 70.683356 -306.538956) (xy 70.727818 -306.560054) (xy 70.768321 -306.58801)
			(xy 70.803814 -306.622102) (xy 70.833379 -306.661446) (xy 70.85625 -306.705023) (xy 70.871834 -306.751704)
			(xy 70.879729 -306.800281) (xy 70.880224 -306.824888) (xy 71.219072 -306.824888) (xy 71.223032 -306.775834)
			(xy 71.234809 -306.72805) (xy 71.2541 -306.682774) (xy 71.280403 -306.641178) (xy 71.313038 -306.604341)
			(xy 71.351159 -306.573216) (xy 71.39378 -306.548609) (xy 71.439796 -306.531157) (xy 71.488015 -306.521313)
			(xy 71.53719 -306.519332) (xy 71.586045 -306.525264) (xy 71.633316 -306.538956) (xy 71.677778 -306.560054)
			(xy 71.718281 -306.58801) (xy 71.753774 -306.622102) (xy 71.783339 -306.661446) (xy 71.80621 -306.705023)
			(xy 71.821794 -306.751704) (xy 71.829689 -306.800281) (xy 71.830184 -306.824888) (xy 72.169032 -306.824888)
			(xy 72.172992 -306.775834) (xy 72.184769 -306.72805) (xy 72.20406 -306.682774) (xy 72.230363 -306.641178)
			(xy 72.262998 -306.604341) (xy 72.301119 -306.573216) (xy 72.34374 -306.548609) (xy 72.389756 -306.531157)
			(xy 72.437975 -306.521313) (xy 72.48715 -306.519332) (xy 72.536005 -306.525264) (xy 72.583276 -306.538956)
			(xy 72.627738 -306.560054) (xy 72.668241 -306.58801) (xy 72.703734 -306.622102) (xy 72.733299 -306.661446)
			(xy 72.75617 -306.705023) (xy 72.771754 -306.751704) (xy 72.779649 -306.800281) (xy 72.780144 -306.824888)
			(xy 72.779649 -306.849495) (xy 72.771754 -306.898072) (xy 72.75617 -306.944753) (xy 72.733299 -306.98833)
			(xy 72.703734 -307.027674) (xy 72.668241 -307.061766) (xy 72.627738 -307.089722) (xy 72.583276 -307.11082)
			(xy 72.536005 -307.124512) (xy 72.48715 -307.130444) (xy 72.437975 -307.128463) (xy 72.389756 -307.118619)
			(xy 72.34374 -307.101167) (xy 72.301119 -307.07656) (xy 72.262998 -307.045435) (xy 72.230363 -307.008598)
			(xy 72.20406 -306.967002) (xy 72.184769 -306.921726) (xy 72.172992 -306.873942) (xy 72.169032 -306.824888)
			(xy 71.830184 -306.824888) (xy 71.829689 -306.849495) (xy 71.821794 -306.898072) (xy 71.80621 -306.944753)
			(xy 71.783339 -306.98833) (xy 71.753774 -307.027674) (xy 71.718281 -307.061766) (xy 71.677778 -307.089722)
			(xy 71.633316 -307.11082) (xy 71.586045 -307.124512) (xy 71.53719 -307.130444) (xy 71.488015 -307.128463)
			(xy 71.439796 -307.118619) (xy 71.39378 -307.101167) (xy 71.351159 -307.07656) (xy 71.313038 -307.045435)
			(xy 71.280403 -307.008598) (xy 71.2541 -306.967002) (xy 71.234809 -306.921726) (xy 71.223032 -306.873942)
			(xy 71.219072 -306.824888) (xy 70.880224 -306.824888) (xy 70.879729 -306.849495) (xy 70.871834 -306.898072)
			(xy 70.85625 -306.944753) (xy 70.833379 -306.98833) (xy 70.803814 -307.027674) (xy 70.768321 -307.061766)
			(xy 70.727818 -307.089722) (xy 70.683356 -307.11082) (xy 70.636085 -307.124512) (xy 70.58723 -307.130444)
			(xy 70.538055 -307.128463) (xy 70.489836 -307.118619) (xy 70.44382 -307.101167) (xy 70.401199 -307.07656)
			(xy 70.363078 -307.045435) (xy 70.330443 -307.008598) (xy 70.30414 -306.967002) (xy 70.284849 -306.921726)
			(xy 70.273072 -306.873942) (xy 70.269112 -306.824888) (xy 69.930264 -306.824888) (xy 69.929769 -306.849495)
			(xy 69.921874 -306.898072) (xy 69.90629 -306.944753) (xy 69.883419 -306.98833) (xy 69.853854 -307.027674)
			(xy 69.818361 -307.061766) (xy 69.777858 -307.089722) (xy 69.733396 -307.11082) (xy 69.686125 -307.124512)
			(xy 69.63727 -307.130444) (xy 69.588095 -307.128463) (xy 69.539876 -307.118619) (xy 69.49386 -307.101167)
			(xy 69.451239 -307.07656) (xy 69.413118 -307.045435) (xy 69.380483 -307.008598) (xy 69.35418 -306.967002)
			(xy 69.334889 -306.921726) (xy 69.323112 -306.873942) (xy 69.319152 -306.824888) (xy 68.98005 -306.824888)
			(xy 68.979555 -306.849495) (xy 68.97166 -306.898072) (xy 68.956076 -306.944753) (xy 68.933205 -306.98833)
			(xy 68.90364 -307.027674) (xy 68.868147 -307.061766) (xy 68.827644 -307.089722) (xy 68.783182 -307.11082)
			(xy 68.735911 -307.124512) (xy 68.687056 -307.130444) (xy 68.637881 -307.128463) (xy 68.589662 -307.118619)
			(xy 68.543646 -307.101167) (xy 68.501025 -307.07656) (xy 68.462904 -307.045435) (xy 68.430269 -307.008598)
			(xy 68.403966 -306.967002) (xy 68.384675 -306.921726) (xy 68.372898 -306.873942) (xy 68.368938 -306.824888)
			(xy 68.03009 -306.824888) (xy 68.029595 -306.849495) (xy 68.0217 -306.898072) (xy 68.006116 -306.944753)
			(xy 67.983245 -306.98833) (xy 67.95368 -307.027674) (xy 67.918187 -307.061766) (xy 67.877684 -307.089722)
			(xy 67.833222 -307.11082) (xy 67.785951 -307.124512) (xy 67.737096 -307.130444) (xy 67.687921 -307.128463)
			(xy 67.639702 -307.118619) (xy 67.593686 -307.101167) (xy 67.551065 -307.07656) (xy 67.512944 -307.045435)
			(xy 67.480309 -307.008598) (xy 67.454006 -306.967002) (xy 67.434715 -306.921726) (xy 67.422938 -306.873942)
			(xy 67.418978 -306.824888) (xy 67.08013 -306.824888) (xy 67.079635 -306.849495) (xy 67.07174 -306.898072)
			(xy 67.056156 -306.944753) (xy 67.033285 -306.98833) (xy 67.00372 -307.027674) (xy 66.968227 -307.061766)
			(xy 66.927724 -307.089722) (xy 66.883262 -307.11082) (xy 66.835991 -307.124512) (xy 66.787136 -307.130444)
			(xy 66.737961 -307.128463) (xy 66.689742 -307.118619) (xy 66.643726 -307.101167) (xy 66.601105 -307.07656)
			(xy 66.562984 -307.045435) (xy 66.530349 -307.008598) (xy 66.504046 -306.967002) (xy 66.484755 -306.921726)
			(xy 66.472978 -306.873942) (xy 66.469018 -306.824888) (xy 66.13017 -306.824888) (xy 66.129675 -306.849495)
			(xy 66.12178 -306.898072) (xy 66.106196 -306.944753) (xy 66.083325 -306.98833) (xy 66.05376 -307.027674)
			(xy 66.018267 -307.061766) (xy 65.977764 -307.089722) (xy 65.933302 -307.11082) (xy 65.886031 -307.124512)
			(xy 65.837176 -307.130444) (xy 65.788001 -307.128463) (xy 65.739782 -307.118619) (xy 65.693766 -307.101167)
			(xy 65.651145 -307.07656) (xy 65.613024 -307.045435) (xy 65.580389 -307.008598) (xy 65.554086 -306.967002)
			(xy 65.534795 -306.921726) (xy 65.523018 -306.873942) (xy 65.519058 -306.824888) (xy 65.18021 -306.824888)
			(xy 65.179715 -306.849495) (xy 65.17182 -306.898072) (xy 65.156236 -306.944753) (xy 65.133365 -306.98833)
			(xy 65.1038 -307.027674) (xy 65.068307 -307.061766) (xy 65.027804 -307.089722) (xy 64.983342 -307.11082)
			(xy 64.936071 -307.124512) (xy 64.887216 -307.130444) (xy 64.838041 -307.128463) (xy 64.789822 -307.118619)
			(xy 64.743806 -307.101167) (xy 64.701185 -307.07656) (xy 64.663064 -307.045435) (xy 64.630429 -307.008598)
			(xy 64.604126 -306.967002) (xy 64.584835 -306.921726) (xy 64.573058 -306.873942) (xy 64.569098 -306.824888)
			(xy 64.23025 -306.824888) (xy 64.229755 -306.849495) (xy 64.22186 -306.898072) (xy 64.206276 -306.944753)
			(xy 64.183405 -306.98833) (xy 64.15384 -307.027674) (xy 64.118347 -307.061766) (xy 64.077844 -307.089722)
			(xy 64.033382 -307.11082) (xy 63.986111 -307.124512) (xy 63.937256 -307.130444) (xy 63.888081 -307.128463)
			(xy 63.839862 -307.118619) (xy 63.793846 -307.101167) (xy 63.751225 -307.07656) (xy 63.713104 -307.045435)
			(xy 63.680469 -307.008598) (xy 63.654166 -306.967002) (xy 63.634875 -306.921726) (xy 63.623098 -306.873942)
			(xy 63.619138 -306.824888) (xy 63.28029 -306.824888) (xy 63.279795 -306.849495) (xy 63.2719 -306.898072)
			(xy 63.256316 -306.944753) (xy 63.233445 -306.98833) (xy 63.20388 -307.027674) (xy 63.168387 -307.061766)
			(xy 63.127884 -307.089722) (xy 63.083422 -307.11082) (xy 63.036151 -307.124512) (xy 62.987296 -307.130444)
			(xy 62.938121 -307.128463) (xy 62.889902 -307.118619) (xy 62.843886 -307.101167) (xy 62.801265 -307.07656)
			(xy 62.763144 -307.045435) (xy 62.730509 -307.008598) (xy 62.704206 -306.967002) (xy 62.684915 -306.921726)
			(xy 62.673138 -306.873942) (xy 62.669178 -306.824888) (xy 62.330076 -306.824888) (xy 62.329581 -306.849495)
			(xy 62.321686 -306.898072) (xy 62.306102 -306.944753) (xy 62.283231 -306.98833) (xy 62.253666 -307.027674)
			(xy 62.218173 -307.061766) (xy 62.17767 -307.089722) (xy 62.133208 -307.11082) (xy 62.085937 -307.124512)
			(xy 62.037082 -307.130444) (xy 61.987907 -307.128463) (xy 61.939688 -307.118619) (xy 61.893672 -307.101167)
			(xy 61.851051 -307.07656) (xy 61.81293 -307.045435) (xy 61.780295 -307.008598) (xy 61.753992 -306.967002)
			(xy 61.734701 -306.921726) (xy 61.722924 -306.873942) (xy 61.718964 -306.824888) (xy 61.380116 -306.824888)
			(xy 61.379621 -306.849495) (xy 61.371726 -306.898072) (xy 61.356142 -306.944753) (xy 61.333271 -306.98833)
			(xy 61.303706 -307.027674) (xy 61.268213 -307.061766) (xy 61.22771 -307.089722) (xy 61.183248 -307.11082)
			(xy 61.135977 -307.124512) (xy 61.087122 -307.130444) (xy 61.037947 -307.128463) (xy 60.989728 -307.118619)
			(xy 60.943712 -307.101167) (xy 60.901091 -307.07656) (xy 60.86297 -307.045435) (xy 60.830335 -307.008598)
			(xy 60.804032 -306.967002) (xy 60.784741 -306.921726) (xy 60.772964 -306.873942) (xy 60.769004 -306.824888)
			(xy 60.430156 -306.824888) (xy 60.429661 -306.849495) (xy 60.421766 -306.898072) (xy 60.406182 -306.944753)
			(xy 60.383311 -306.98833) (xy 60.353746 -307.027674) (xy 60.318253 -307.061766) (xy 60.27775 -307.089722)
			(xy 60.233288 -307.11082) (xy 60.186017 -307.124512) (xy 60.137162 -307.130444) (xy 60.087987 -307.128463)
			(xy 60.039768 -307.118619) (xy 59.993752 -307.101167) (xy 59.951131 -307.07656) (xy 59.91301 -307.045435)
			(xy 59.880375 -307.008598) (xy 59.854072 -306.967002) (xy 59.834781 -306.921726) (xy 59.823004 -306.873942)
			(xy 59.819044 -306.824888) (xy 58.530236 -306.824888) (xy 58.529741 -306.849495) (xy 58.521846 -306.898072)
			(xy 58.506262 -306.944753) (xy 58.483391 -306.98833) (xy 58.453826 -307.027674) (xy 58.418333 -307.061766)
			(xy 58.37783 -307.089722) (xy 58.333368 -307.11082) (xy 58.286097 -307.124512) (xy 58.237242 -307.130444)
			(xy 58.188067 -307.128463) (xy 58.139848 -307.118619) (xy 58.093832 -307.101167) (xy 58.051211 -307.07656)
			(xy 58.01309 -307.045435) (xy 57.980455 -307.008598) (xy 57.954152 -306.967002) (xy 57.934861 -306.921726)
			(xy 57.923084 -306.873942) (xy 57.919124 -306.824888) (xy 57.580276 -306.824888) (xy 57.579781 -306.849495)
			(xy 57.571886 -306.898072) (xy 57.556302 -306.944753) (xy 57.533431 -306.98833) (xy 57.503866 -307.027674)
			(xy 57.468373 -307.061766) (xy 57.42787 -307.089722) (xy 57.383408 -307.11082) (xy 57.336137 -307.124512)
			(xy 57.287282 -307.130444) (xy 57.238107 -307.128463) (xy 57.189888 -307.118619) (xy 57.143872 -307.101167)
			(xy 57.101251 -307.07656) (xy 57.06313 -307.045435) (xy 57.030495 -307.008598) (xy 57.004192 -306.967002)
			(xy 56.984901 -306.921726) (xy 56.973124 -306.873942) (xy 56.969164 -306.824888) (xy 56.630062 -306.824888)
			(xy 56.629567 -306.849495) (xy 56.621672 -306.898072) (xy 56.606088 -306.944753) (xy 56.583217 -306.98833)
			(xy 56.553652 -307.027674) (xy 56.518159 -307.061766) (xy 56.477656 -307.089722) (xy 56.433194 -307.11082)
			(xy 56.385923 -307.124512) (xy 56.337068 -307.130444) (xy 56.287893 -307.128463) (xy 56.239674 -307.118619)
			(xy 56.193658 -307.101167) (xy 56.151037 -307.07656) (xy 56.112916 -307.045435) (xy 56.080281 -307.008598)
			(xy 56.053978 -306.967002) (xy 56.034687 -306.921726) (xy 56.02291 -306.873942) (xy 56.01895 -306.824888)
			(xy 55.680102 -306.824888) (xy 55.679607 -306.849495) (xy 55.671712 -306.898072) (xy 55.656128 -306.944753)
			(xy 55.633257 -306.98833) (xy 55.603692 -307.027674) (xy 55.568199 -307.061766) (xy 55.527696 -307.089722)
			(xy 55.483234 -307.11082) (xy 55.435963 -307.124512) (xy 55.387108 -307.130444) (xy 55.337933 -307.128463)
			(xy 55.289714 -307.118619) (xy 55.243698 -307.101167) (xy 55.201077 -307.07656) (xy 55.162956 -307.045435)
			(xy 55.130321 -307.008598) (xy 55.104018 -306.967002) (xy 55.084727 -306.921726) (xy 55.07295 -306.873942)
			(xy 55.06899 -306.824888) (xy 54.730142 -306.824888) (xy 54.729647 -306.849495) (xy 54.721752 -306.898072)
			(xy 54.706168 -306.944753) (xy 54.683297 -306.98833) (xy 54.653732 -307.027674) (xy 54.618239 -307.061766)
			(xy 54.577736 -307.089722) (xy 54.533274 -307.11082) (xy 54.486003 -307.124512) (xy 54.437148 -307.130444)
			(xy 54.387973 -307.128463) (xy 54.339754 -307.118619) (xy 54.293738 -307.101167) (xy 54.251117 -307.07656)
			(xy 54.212996 -307.045435) (xy 54.180361 -307.008598) (xy 54.154058 -306.967002) (xy 54.134767 -306.921726)
			(xy 54.12299 -306.873942) (xy 54.11903 -306.824888) (xy 53.780182 -306.824888) (xy 53.779687 -306.849495)
			(xy 53.771792 -306.898072) (xy 53.756208 -306.944753) (xy 53.733337 -306.98833) (xy 53.703772 -307.027674)
			(xy 53.668279 -307.061766) (xy 53.627776 -307.089722) (xy 53.583314 -307.11082) (xy 53.536043 -307.124512)
			(xy 53.487188 -307.130444) (xy 53.438013 -307.128463) (xy 53.389794 -307.118619) (xy 53.343778 -307.101167)
			(xy 53.301157 -307.07656) (xy 53.263036 -307.045435) (xy 53.230401 -307.008598) (xy 53.204098 -306.967002)
			(xy 53.184807 -306.921726) (xy 53.17303 -306.873942) (xy 53.16907 -306.824888) (xy 52.830222 -306.824888)
			(xy 52.829727 -306.849495) (xy 52.821832 -306.898072) (xy 52.806248 -306.944753) (xy 52.783377 -306.98833)
			(xy 52.753812 -307.027674) (xy 52.718319 -307.061766) (xy 52.677816 -307.089722) (xy 52.633354 -307.11082)
			(xy 52.586083 -307.124512) (xy 52.537228 -307.130444) (xy 52.488053 -307.128463) (xy 52.439834 -307.118619)
			(xy 52.393818 -307.101167) (xy 52.351197 -307.07656) (xy 52.313076 -307.045435) (xy 52.280441 -307.008598)
			(xy 52.254138 -306.967002) (xy 52.234847 -306.921726) (xy 52.22307 -306.873942) (xy 52.21911 -306.824888)
			(xy 51.880262 -306.824888) (xy 51.879767 -306.849495) (xy 51.871872 -306.898072) (xy 51.856288 -306.944753)
			(xy 51.833417 -306.98833) (xy 51.803852 -307.027674) (xy 51.768359 -307.061766) (xy 51.727856 -307.089722)
			(xy 51.683394 -307.11082) (xy 51.636123 -307.124512) (xy 51.587268 -307.130444) (xy 51.538093 -307.128463)
			(xy 51.489874 -307.118619) (xy 51.443858 -307.101167) (xy 51.401237 -307.07656) (xy 51.363116 -307.045435)
			(xy 51.330481 -307.008598) (xy 51.304178 -306.967002) (xy 51.284887 -306.921726) (xy 51.27311 -306.873942)
			(xy 51.26915 -306.824888) (xy 50.930275 -306.824888) (xy 50.930725 -306.83319) (xy 50.925356 -306.882541)
			(xy 50.912074 -306.930374) (xy 50.891229 -306.975428) (xy 50.863369 -307.016516) (xy 50.829229 -307.052555)
			(xy 50.789708 -307.082596) (xy 50.745848 -307.105848) (xy 50.698804 -307.121698) (xy 50.649815 -307.129729)
			(xy 50.624994 -307.130196) (xy 50.610748 -307.13002) (xy 50.58238 -307.127352) (xy 50.568352 -307.124862)
			(xy 50.55616 -307.122576) (xy 50.53203 -307.129942) (xy 50.454814 -307.207158) (xy 50.447448 -307.231034)
			(xy 50.449734 -307.24348) (xy 50.452221 -307.257445) (xy 50.454896 -307.285685) (xy 50.455068 -307.299868)
			(xy 73.593972 -307.299868) (xy 73.597932 -307.250814) (xy 73.609709 -307.20303) (xy 73.629 -307.157754)
			(xy 73.655303 -307.116158) (xy 73.687938 -307.079321) (xy 73.726059 -307.048196) (xy 73.76868 -307.023589)
			(xy 73.814696 -307.006137) (xy 73.862915 -306.996293) (xy 73.91209 -306.994312) (xy 73.960945 -307.000244)
			(xy 74.008216 -307.013936) (xy 74.052678 -307.035034) (xy 74.093181 -307.06299) (xy 74.128674 -307.097082)
			(xy 74.158239 -307.136426) (xy 74.18111 -307.180003) (xy 74.196694 -307.226684) (xy 74.204589 -307.275261)
			(xy 74.205084 -307.299868) (xy 74.544186 -307.299868) (xy 74.548146 -307.250814) (xy 74.559923 -307.20303)
			(xy 74.579214 -307.157754) (xy 74.605517 -307.116158) (xy 74.638152 -307.079321) (xy 74.676273 -307.048196)
			(xy 74.718894 -307.023589) (xy 74.76491 -307.006137) (xy 74.813129 -306.996293) (xy 74.862304 -306.994312)
			(xy 74.911159 -307.000244) (xy 74.95843 -307.013936) (xy 75.002892 -307.035034) (xy 75.043395 -307.06299)
			(xy 75.078888 -307.097082) (xy 75.108453 -307.136426) (xy 75.131324 -307.180003) (xy 75.146908 -307.226684)
			(xy 75.154803 -307.275261) (xy 75.155298 -307.299868) (xy 75.494146 -307.299868) (xy 75.498106 -307.250814)
			(xy 75.509883 -307.20303) (xy 75.529174 -307.157754) (xy 75.555477 -307.116158) (xy 75.588112 -307.079321)
			(xy 75.626233 -307.048196) (xy 75.668854 -307.023589) (xy 75.71487 -307.006137) (xy 75.763089 -306.996293)
			(xy 75.812264 -306.994312) (xy 75.861119 -307.000244) (xy 75.90839 -307.013936) (xy 75.952852 -307.035034)
			(xy 75.993355 -307.06299) (xy 76.028848 -307.097082) (xy 76.058413 -307.136426) (xy 76.081284 -307.180003)
			(xy 76.096868 -307.226684) (xy 76.104763 -307.275261) (xy 76.105258 -307.299868) (xy 76.444106 -307.299868)
			(xy 76.448066 -307.250814) (xy 76.459843 -307.20303) (xy 76.479134 -307.157754) (xy 76.505437 -307.116158)
			(xy 76.538072 -307.079321) (xy 76.576193 -307.048196) (xy 76.618814 -307.023589) (xy 76.66483 -307.006137)
			(xy 76.713049 -306.996293) (xy 76.762224 -306.994312) (xy 76.811079 -307.000244) (xy 76.85835 -307.013936)
			(xy 76.902812 -307.035034) (xy 76.943315 -307.06299) (xy 76.978808 -307.097082) (xy 77.008373 -307.136426)
			(xy 77.031244 -307.180003) (xy 77.046828 -307.226684) (xy 77.054723 -307.275261) (xy 77.055218 -307.299868)
			(xy 77.394066 -307.299868) (xy 77.398026 -307.250814) (xy 77.409803 -307.20303) (xy 77.429094 -307.157754)
			(xy 77.455397 -307.116158) (xy 77.488032 -307.079321) (xy 77.526153 -307.048196) (xy 77.568774 -307.023589)
			(xy 77.61479 -307.006137) (xy 77.663009 -306.996293) (xy 77.712184 -306.994312) (xy 77.761039 -307.000244)
			(xy 77.80831 -307.013936) (xy 77.852772 -307.035034) (xy 77.893275 -307.06299) (xy 77.928768 -307.097082)
			(xy 77.958333 -307.136426) (xy 77.981204 -307.180003) (xy 77.996788 -307.226684) (xy 78.004683 -307.275261)
			(xy 78.005178 -307.299868) (xy 78.344026 -307.299868) (xy 78.347986 -307.250814) (xy 78.359763 -307.20303)
			(xy 78.379054 -307.157754) (xy 78.405357 -307.116158) (xy 78.437992 -307.079321) (xy 78.476113 -307.048196)
			(xy 78.518734 -307.023589) (xy 78.56475 -307.006137) (xy 78.612969 -306.996293) (xy 78.662144 -306.994312)
			(xy 78.710999 -307.000244) (xy 78.75827 -307.013936) (xy 78.802732 -307.035034) (xy 78.843235 -307.06299)
			(xy 78.878728 -307.097082) (xy 78.908293 -307.136426) (xy 78.931164 -307.180003) (xy 78.946748 -307.226684)
			(xy 78.954643 -307.275261) (xy 78.955138 -307.299868) (xy 79.293986 -307.299868) (xy 79.297946 -307.250814)
			(xy 79.309723 -307.20303) (xy 79.329014 -307.157754) (xy 79.355317 -307.116158) (xy 79.387952 -307.079321)
			(xy 79.426073 -307.048196) (xy 79.468694 -307.023589) (xy 79.51471 -307.006137) (xy 79.562929 -306.996293)
			(xy 79.612104 -306.994312) (xy 79.660959 -307.000244) (xy 79.70823 -307.013936) (xy 79.752692 -307.035034)
			(xy 79.793195 -307.06299) (xy 79.828688 -307.097082) (xy 79.858253 -307.136426) (xy 79.881124 -307.180003)
			(xy 79.896708 -307.226684) (xy 79.904603 -307.275261) (xy 79.905098 -307.299868) (xy 80.243946 -307.299868)
			(xy 80.247906 -307.250814) (xy 80.259683 -307.20303) (xy 80.278974 -307.157754) (xy 80.305277 -307.116158)
			(xy 80.337912 -307.079321) (xy 80.376033 -307.048196) (xy 80.418654 -307.023589) (xy 80.46467 -307.006137)
			(xy 80.512889 -306.996293) (xy 80.562064 -306.994312) (xy 80.610919 -307.000244) (xy 80.65819 -307.013936)
			(xy 80.702652 -307.035034) (xy 80.743155 -307.06299) (xy 80.778648 -307.097082) (xy 80.808213 -307.136426)
			(xy 80.831084 -307.180003) (xy 80.846668 -307.226684) (xy 80.854563 -307.275261) (xy 80.855058 -307.299868)
			(xy 81.19416 -307.299868) (xy 81.19812 -307.250814) (xy 81.209897 -307.20303) (xy 81.229188 -307.157754)
			(xy 81.255491 -307.116158) (xy 81.288126 -307.079321) (xy 81.326247 -307.048196) (xy 81.368868 -307.023589)
			(xy 81.414884 -307.006137) (xy 81.463103 -306.996293) (xy 81.512278 -306.994312) (xy 81.561133 -307.000244)
			(xy 81.608404 -307.013936) (xy 81.652866 -307.035034) (xy 81.693369 -307.06299) (xy 81.728862 -307.097082)
			(xy 81.758427 -307.136426) (xy 81.781298 -307.180003) (xy 81.796882 -307.226684) (xy 81.804777 -307.275261)
			(xy 81.805272 -307.299868) (xy 82.14412 -307.299868) (xy 82.14808 -307.250814) (xy 82.159857 -307.20303)
			(xy 82.179148 -307.157754) (xy 82.205451 -307.116158) (xy 82.238086 -307.079321) (xy 82.276207 -307.048196)
			(xy 82.318828 -307.023589) (xy 82.364844 -307.006137) (xy 82.413063 -306.996293) (xy 82.462238 -306.994312)
			(xy 82.511093 -307.000244) (xy 82.558364 -307.013936) (xy 82.602826 -307.035034) (xy 82.643329 -307.06299)
			(xy 82.678822 -307.097082) (xy 82.708387 -307.136426) (xy 82.731258 -307.180003) (xy 82.746842 -307.226684)
			(xy 82.754737 -307.275261) (xy 82.755232 -307.299868) (xy 82.754955 -307.313639) (xy 91.226391 -307.313639)
			(xy 91.226393 -307.259139) (xy 91.234151 -307.205193) (xy 91.249507 -307.152901) (xy 91.272148 -307.103327)
			(xy 91.301615 -307.057479) (xy 91.337306 -307.016292) (xy 91.378495 -306.980603) (xy 91.424344 -306.951139)
			(xy 91.47392 -306.9285) (xy 91.526213 -306.913147) (xy 91.580159 -306.905392) (xy 91.634659 -306.905393)
			(xy 91.688604 -306.91315) (xy 91.740896 -306.928506) (xy 91.790471 -306.951147) (xy 91.836319 -306.980613)
			(xy 91.877507 -307.016304) (xy 91.913196 -307.057493) (xy 91.930373 -307.084222) (xy 92.714316 -307.084222)
			(xy 92.718387 -307.0286) (xy 92.730513 -306.974163) (xy 92.750436 -306.922072) (xy 92.777732 -306.873437)
			(xy 92.811818 -306.829294) (xy 92.851967 -306.790585) (xy 92.897325 -306.758134) (xy 92.946925 -306.732633)
			(xy 92.999709 -306.714626) (xy 93.054552 -306.704496) (xy 93.110286 -306.702459) (xy 93.165723 -306.708559)
			(xy 93.21968 -306.722665) (xy 93.271009 -306.744477) (xy 93.318615 -306.773531) (xy 93.361483 -306.809206)
			(xy 93.3987 -306.850743) (xy 93.429473 -306.897256) (xy 93.453145 -306.947753) (xy 93.469213 -307.00116)
			(xy 93.477333 -307.056336) (xy 93.477842 -307.084222) (xy 93.477333 -307.112108) (xy 93.469213 -307.167284)
			(xy 93.453145 -307.220691) (xy 93.429473 -307.271188) (xy 93.3987 -307.317701) (xy 93.361483 -307.359238)
			(xy 93.318615 -307.394913) (xy 93.271009 -307.423967) (xy 93.21968 -307.445779) (xy 93.165723 -307.459885)
			(xy 93.110286 -307.465985) (xy 93.054552 -307.463948) (xy 92.999709 -307.453818) (xy 92.946925 -307.435811)
			(xy 92.897325 -307.41031) (xy 92.851967 -307.377859) (xy 92.811818 -307.33915) (xy 92.777732 -307.295007)
			(xy 92.750436 -307.246372) (xy 92.730513 -307.194281) (xy 92.718387 -307.139844) (xy 92.714316 -307.084222)
			(xy 91.930373 -307.084222) (xy 91.94266 -307.103342) (xy 91.965299 -307.152918) (xy 91.980653 -307.20521)
			(xy 91.988408 -307.259156) (xy 91.988894 -307.286406) (xy 91.987116 -307.322982) (xy 91.9861 -307.334412)
			(xy 91.99372 -307.355494) (xy 92.065348 -307.427122) (xy 92.086684 -307.434742) (xy 92.098114 -307.433726)
			(xy 92.13469 -307.431948) (xy 92.161939 -307.432487) (xy 92.215882 -307.440241) (xy 92.268173 -307.455593)
			(xy 92.317748 -307.47823) (xy 92.363596 -307.507691) (xy 92.404785 -307.543377) (xy 92.440477 -307.584561)
			(xy 92.469944 -307.630405) (xy 92.492588 -307.679976) (xy 92.507947 -307.732265) (xy 92.515709 -307.786207)
			(xy 92.516198 -307.813456) (xy 92.515841 -307.835962) (xy 92.510498 -307.880656) (xy 92.50553 -307.90261)
			(xy 92.502482 -307.915818) (xy 92.509594 -307.940964) (xy 92.589858 -308.021228) (xy 92.615004 -308.02834)
			(xy 92.628212 -308.025292) (xy 92.650166 -308.020324) (xy 92.69486 -308.014981) (xy 92.717366 -308.014624)
			(xy 92.744621 -308.015018) (xy 92.798578 -308.022771) (xy 92.850882 -308.038124) (xy 92.900469 -308.060764)
			(xy 92.946328 -308.090231) (xy 92.987528 -308.125924) (xy 93.023229 -308.167118) (xy 93.052703 -308.212972)
			(xy 93.075352 -308.262555) (xy 93.090714 -308.314856) (xy 93.098477 -308.368811) (xy 93.098481 -308.423322)
			(xy 93.090728 -308.477279) (xy 93.075376 -308.529583) (xy 93.052735 -308.579169) (xy 93.023269 -308.625029)
			(xy 92.987575 -308.666229) (xy 92.946382 -308.701929) (xy 92.900527 -308.731404) (xy 92.850944 -308.754052)
			(xy 92.798643 -308.769414) (xy 92.744688 -308.777177) (xy 92.690177 -308.777181) (xy 92.636221 -308.769428)
			(xy 92.583917 -308.754075) (xy 92.53433 -308.731435) (xy 92.48847 -308.701968) (xy 92.447271 -308.666275)
			(xy 92.411571 -308.625081) (xy 92.382096 -308.579227) (xy 92.359447 -308.529644) (xy 92.344085 -308.477343)
			(xy 92.336323 -308.423387) (xy 92.335858 -308.396132) (xy 92.336212 -308.373626) (xy 92.341557 -308.328931)
			(xy 92.346526 -308.306978) (xy 92.349574 -308.29377) (xy 92.342462 -308.268624) (xy 92.262198 -308.18836)
			(xy 92.237052 -308.181248) (xy 92.223844 -308.184296) (xy 92.201888 -308.189254) (xy 92.157195 -308.194604)
			(xy 92.13469 -308.194964) (xy 92.107435 -308.194554) (xy 92.05348 -308.186795) (xy 92.001178 -308.171435)
			(xy 91.951595 -308.148788) (xy 91.90574 -308.119315) (xy 91.864546 -308.083616) (xy 91.828852 -308.042417)
			(xy 91.799386 -307.996558) (xy 91.776746 -307.946971) (xy 91.761394 -307.894667) (xy 91.753642 -307.840711)
			(xy 91.753182 -307.813456) (xy 91.75496 -307.77688) (xy 91.755976 -307.76545) (xy 91.748356 -307.744368)
			(xy 91.676728 -307.67274) (xy 91.655392 -307.66512) (xy 91.643962 -307.666136) (xy 91.607386 -307.667914)
			(xy 91.580136 -307.667407) (xy 91.526191 -307.659649) (xy 91.473899 -307.644292) (xy 91.424324 -307.62165)
			(xy 91.378477 -307.592184) (xy 91.33729 -307.556492) (xy 91.301601 -307.515303) (xy 91.272137 -307.469453)
			(xy 91.249499 -307.419877) (xy 91.234146 -307.367584) (xy 91.226391 -307.313639) (xy 82.754955 -307.313639)
			(xy 82.754737 -307.324475) (xy 82.746842 -307.373052) (xy 82.731258 -307.419733) (xy 82.708387 -307.46331)
			(xy 82.678822 -307.502654) (xy 82.643329 -307.536746) (xy 82.602826 -307.564702) (xy 82.558364 -307.5858)
			(xy 82.511093 -307.599492) (xy 82.462238 -307.605424) (xy 82.413063 -307.603443) (xy 82.364844 -307.593599)
			(xy 82.318828 -307.576147) (xy 82.276207 -307.55154) (xy 82.238086 -307.520415) (xy 82.205451 -307.483578)
			(xy 82.179148 -307.441982) (xy 82.159857 -307.396706) (xy 82.14808 -307.348922) (xy 82.14412 -307.299868)
			(xy 81.805272 -307.299868) (xy 81.804777 -307.324475) (xy 81.796882 -307.373052) (xy 81.781298 -307.419733)
			(xy 81.758427 -307.46331) (xy 81.728862 -307.502654) (xy 81.693369 -307.536746) (xy 81.652866 -307.564702)
			(xy 81.608404 -307.5858) (xy 81.561133 -307.599492) (xy 81.512278 -307.605424) (xy 81.463103 -307.603443)
			(xy 81.414884 -307.593599) (xy 81.368868 -307.576147) (xy 81.326247 -307.55154) (xy 81.288126 -307.520415)
			(xy 81.255491 -307.483578) (xy 81.229188 -307.441982) (xy 81.209897 -307.396706) (xy 81.19812 -307.348922)
			(xy 81.19416 -307.299868) (xy 80.855058 -307.299868) (xy 80.854563 -307.324475) (xy 80.846668 -307.373052)
			(xy 80.831084 -307.419733) (xy 80.808213 -307.46331) (xy 80.778648 -307.502654) (xy 80.743155 -307.536746)
			(xy 80.702652 -307.564702) (xy 80.65819 -307.5858) (xy 80.610919 -307.599492) (xy 80.562064 -307.605424)
			(xy 80.512889 -307.603443) (xy 80.46467 -307.593599) (xy 80.418654 -307.576147) (xy 80.376033 -307.55154)
			(xy 80.337912 -307.520415) (xy 80.305277 -307.483578) (xy 80.278974 -307.441982) (xy 80.259683 -307.396706)
			(xy 80.247906 -307.348922) (xy 80.243946 -307.299868) (xy 79.905098 -307.299868) (xy 79.904603 -307.324475)
			(xy 79.896708 -307.373052) (xy 79.881124 -307.419733) (xy 79.858253 -307.46331) (xy 79.828688 -307.502654)
			(xy 79.793195 -307.536746) (xy 79.752692 -307.564702) (xy 79.70823 -307.5858) (xy 79.660959 -307.599492)
			(xy 79.612104 -307.605424) (xy 79.562929 -307.603443) (xy 79.51471 -307.593599) (xy 79.468694 -307.576147)
			(xy 79.426073 -307.55154) (xy 79.387952 -307.520415) (xy 79.355317 -307.483578) (xy 79.329014 -307.441982)
			(xy 79.309723 -307.396706) (xy 79.297946 -307.348922) (xy 79.293986 -307.299868) (xy 78.955138 -307.299868)
			(xy 78.954643 -307.324475) (xy 78.946748 -307.373052) (xy 78.931164 -307.419733) (xy 78.908293 -307.46331)
			(xy 78.878728 -307.502654) (xy 78.843235 -307.536746) (xy 78.802732 -307.564702) (xy 78.75827 -307.5858)
			(xy 78.710999 -307.599492) (xy 78.662144 -307.605424) (xy 78.612969 -307.603443) (xy 78.56475 -307.593599)
			(xy 78.518734 -307.576147) (xy 78.476113 -307.55154) (xy 78.437992 -307.520415) (xy 78.405357 -307.483578)
			(xy 78.379054 -307.441982) (xy 78.359763 -307.396706) (xy 78.347986 -307.348922) (xy 78.344026 -307.299868)
			(xy 78.005178 -307.299868) (xy 78.004683 -307.324475) (xy 77.996788 -307.373052) (xy 77.981204 -307.419733)
			(xy 77.958333 -307.46331) (xy 77.928768 -307.502654) (xy 77.893275 -307.536746) (xy 77.852772 -307.564702)
			(xy 77.80831 -307.5858) (xy 77.761039 -307.599492) (xy 77.712184 -307.605424) (xy 77.663009 -307.603443)
			(xy 77.61479 -307.593599) (xy 77.568774 -307.576147) (xy 77.526153 -307.55154) (xy 77.488032 -307.520415)
			(xy 77.455397 -307.483578) (xy 77.429094 -307.441982) (xy 77.409803 -307.396706) (xy 77.398026 -307.348922)
			(xy 77.394066 -307.299868) (xy 77.055218 -307.299868) (xy 77.054723 -307.324475) (xy 77.046828 -307.373052)
			(xy 77.031244 -307.419733) (xy 77.008373 -307.46331) (xy 76.978808 -307.502654) (xy 76.943315 -307.536746)
			(xy 76.902812 -307.564702) (xy 76.85835 -307.5858) (xy 76.811079 -307.599492) (xy 76.762224 -307.605424)
			(xy 76.713049 -307.603443) (xy 76.66483 -307.593599) (xy 76.618814 -307.576147) (xy 76.576193 -307.55154)
			(xy 76.538072 -307.520415) (xy 76.505437 -307.483578) (xy 76.479134 -307.441982) (xy 76.459843 -307.396706)
			(xy 76.448066 -307.348922) (xy 76.444106 -307.299868) (xy 76.105258 -307.299868) (xy 76.104763 -307.324475)
			(xy 76.096868 -307.373052) (xy 76.081284 -307.419733) (xy 76.058413 -307.46331) (xy 76.028848 -307.502654)
			(xy 75.993355 -307.536746) (xy 75.952852 -307.564702) (xy 75.90839 -307.5858) (xy 75.861119 -307.599492)
			(xy 75.812264 -307.605424) (xy 75.763089 -307.603443) (xy 75.71487 -307.593599) (xy 75.668854 -307.576147)
			(xy 75.626233 -307.55154) (xy 75.588112 -307.520415) (xy 75.555477 -307.483578) (xy 75.529174 -307.441982)
			(xy 75.509883 -307.396706) (xy 75.498106 -307.348922) (xy 75.494146 -307.299868) (xy 75.155298 -307.299868)
			(xy 75.154803 -307.324475) (xy 75.146908 -307.373052) (xy 75.131324 -307.419733) (xy 75.108453 -307.46331)
			(xy 75.078888 -307.502654) (xy 75.043395 -307.536746) (xy 75.002892 -307.564702) (xy 74.95843 -307.5858)
			(xy 74.911159 -307.599492) (xy 74.862304 -307.605424) (xy 74.813129 -307.603443) (xy 74.76491 -307.593599)
			(xy 74.718894 -307.576147) (xy 74.676273 -307.55154) (xy 74.638152 -307.520415) (xy 74.605517 -307.483578)
			(xy 74.579214 -307.441982) (xy 74.559923 -307.396706) (xy 74.548146 -307.348922) (xy 74.544186 -307.299868)
			(xy 74.205084 -307.299868) (xy 74.204589 -307.324475) (xy 74.196694 -307.373052) (xy 74.18111 -307.419733)
			(xy 74.158239 -307.46331) (xy 74.128674 -307.502654) (xy 74.093181 -307.536746) (xy 74.052678 -307.564702)
			(xy 74.008216 -307.5858) (xy 73.960945 -307.599492) (xy 73.91209 -307.605424) (xy 73.862915 -307.603443)
			(xy 73.814696 -307.593599) (xy 73.76868 -307.576147) (xy 73.726059 -307.55154) (xy 73.687938 -307.520415)
			(xy 73.655303 -307.483578) (xy 73.629 -307.441982) (xy 73.609709 -307.396706) (xy 73.597932 -307.348922)
			(xy 73.593972 -307.299868) (xy 50.455068 -307.299868) (xy 50.454546 -307.325123) (xy 50.446233 -307.374945)
			(xy 50.429832 -307.422719) (xy 50.405791 -307.467142) (xy 50.374767 -307.507002) (xy 50.337605 -307.541212)
			(xy 50.295319 -307.568838) (xy 50.249063 -307.589128) (xy 50.200098 -307.601528) (xy 50.14976 -307.605699)
			(xy 50.099422 -307.601528) (xy 50.050457 -307.589128) (xy 50.004201 -307.568838) (xy 49.961915 -307.541212)
			(xy 49.924753 -307.507002) (xy 49.893729 -307.467142) (xy 49.869688 -307.422719) (xy 49.853287 -307.374945)
			(xy 49.844974 -307.325123) (xy 49.844452 -307.299868) (xy 49.844635 -307.285685) (xy 49.847302 -307.257445)
			(xy 49.849786 -307.24348) (xy 49.852072 -307.231034) (xy 49.844706 -307.207412) (xy 49.767236 -307.129942)
			(xy 49.743614 -307.122576) (xy 49.731168 -307.124862) (xy 49.717203 -307.127346) (xy 49.688963 -307.130017)
			(xy 49.67478 -307.130196) (xy 49.660598 -307.130009) (xy 49.632359 -307.127333) (xy 49.618392 -307.124862)
			(xy 49.605946 -307.122576) (xy 49.582324 -307.129942) (xy 49.504854 -307.207412) (xy 49.497488 -307.231034)
			(xy 49.499774 -307.24348) (xy 49.502261 -307.257445) (xy 49.504936 -307.285685) (xy 49.505108 -307.299868)
			(xy 49.504664 -307.323863) (xy 49.497161 -307.371262) (xy 49.482336 -307.416904) (xy 49.460552 -307.459665)
			(xy 49.432347 -307.498491) (xy 49.398415 -307.532426) (xy 49.359592 -307.560635) (xy 49.316834 -307.582423)
			(xy 49.271193 -307.597254) (xy 49.223795 -307.604762) (xy 49.1998 -307.605176) (xy 49.173638 -307.60416)
			(xy 49.161954 -307.603144) (xy 49.14011 -307.611526) (xy 49.069498 -307.687218) (xy 49.06264 -307.709316)
			(xy 49.064418 -307.721) (xy 49.06815 -307.747733) (xy 49.068147 -307.801708) (xy 49.064418 -307.828442)
			(xy 49.06264 -307.840126) (xy 49.069498 -307.862478) (xy 49.14011 -307.938424) (xy 49.1617 -307.946552)
			(xy 49.173638 -307.945536) (xy 49.1998 -307.94452) (xy 49.223792 -307.944966) (xy 49.271186 -307.952473)
			(xy 49.316822 -307.967302) (xy 49.359576 -307.989088) (xy 49.398396 -308.017294) (xy 49.432324 -308.051226)
			(xy 49.460527 -308.090048) (xy 49.482309 -308.132804) (xy 49.497133 -308.178441) (xy 49.504636 -308.225836)
			(xy 49.505108 -308.249828) (xy 49.504925 -308.264011) (xy 49.502258 -308.292251) (xy 49.499774 -308.306216)
			(xy 49.497488 -308.318662) (xy 49.504854 -308.342284) (xy 49.582324 -308.419754) (xy 49.605946 -308.42712)
			(xy 49.618392 -308.424834) (xy 49.632357 -308.422348) (xy 49.660597 -308.419674) (xy 49.67478 -308.4195)
			(xy 49.698774 -308.419945) (xy 49.746171 -308.427449) (xy 49.791811 -308.442276) (xy 49.83457 -308.46406)
			(xy 49.873393 -308.492266) (xy 49.907326 -308.526198) (xy 49.935533 -308.56502) (xy 49.95732 -308.607778)
			(xy 49.972148 -308.653417) (xy 49.979654 -308.700814) (xy 49.980088 -308.724808) (xy 49.979901 -308.73899)
			(xy 49.977227 -308.76723) (xy 49.974754 -308.781196) (xy 49.972468 -308.793642) (xy 49.979834 -308.817264)
			(xy 50.057304 -308.894734) (xy 50.080926 -308.9021) (xy 50.093372 -308.899814) (xy 50.107337 -308.897327)
			(xy 50.135577 -308.894651) (xy 50.14976 -308.89448) (xy 50.174583 -308.894963) (xy 50.223575 -308.902988)
			(xy 50.270624 -308.918835) (xy 50.314489 -308.942084) (xy 50.354014 -308.972124) (xy 50.388159 -309.008163)
			(xy 50.416024 -309.049251) (xy 50.436873 -309.094306) (xy 50.450159 -309.142141) (xy 50.45553 -309.191495)
			(xy 50.455528 -309.191539) (xy 50.794269 -309.191539) (xy 50.799632 -309.142187) (xy 50.81291 -309.094352)
			(xy 50.833751 -309.049296) (xy 50.861607 -309.008205) (xy 50.895744 -308.972161) (xy 50.935262 -308.942115)
			(xy 50.979121 -308.918858) (xy 51.026164 -308.903003) (xy 51.075152 -308.894968) (xy 51.099974 -308.89448)
			(xy 51.114157 -308.89466) (xy 51.142397 -308.89733) (xy 51.156362 -308.899814) (xy 51.168808 -308.9021)
			(xy 51.19243 -308.894734) (xy 51.2699 -308.817264) (xy 51.277266 -308.793642) (xy 51.27498 -308.781196)
			(xy 51.272507 -308.76723) (xy 51.269833 -308.73899) (xy 51.269646 -308.724808) (xy 51.269825 -308.710625)
			(xy 51.272495 -308.682385) (xy 51.27498 -308.66842) (xy 51.277266 -308.655974) (xy 51.2699 -308.632352)
			(xy 51.19243 -308.554882) (xy 51.168808 -308.547516) (xy 51.156362 -308.549802) (xy 51.142396 -308.55228)
			(xy 51.114157 -308.554951) (xy 51.099974 -308.555136) (xy 51.075155 -308.554594) (xy 51.026172 -308.546559)
			(xy 50.979134 -308.530706) (xy 50.935281 -308.507452) (xy 50.895768 -308.477409) (xy 50.861635 -308.441369)
			(xy 50.833783 -308.400282) (xy 50.812944 -308.355231) (xy 50.799669 -308.307401) (xy 50.794306 -308.258054)
			(xy 50.796998 -308.20849) (xy 50.807673 -308.160014) (xy 50.82605 -308.113903) (xy 50.851644 -308.071373)
			(xy 50.883782 -308.033544) (xy 50.921617 -308.001413) (xy 50.964152 -307.975826) (xy 51.010265 -307.957457)
			(xy 51.058743 -307.946791) (xy 51.108308 -307.944108) (xy 51.157654 -307.949479) (xy 51.205482 -307.962763)
			(xy 51.25053 -307.983609) (xy 51.291611 -308.011469) (xy 51.327645 -308.045608) (xy 51.357681 -308.085127)
			(xy 51.380927 -308.128984) (xy 51.396772 -308.176025) (xy 51.404798 -308.225009) (xy 51.405282 -308.249828)
			(xy 51.40511 -308.264011) (xy 51.402435 -308.292251) (xy 51.399948 -308.306216) (xy 51.397662 -308.318662)
			(xy 51.405028 -308.342284) (xy 51.482498 -308.419754) (xy 51.50612 -308.42712) (xy 51.518566 -308.424834)
			(xy 51.532531 -308.422353) (xy 51.560771 -308.419684) (xy 51.574954 -308.4195) (xy 51.589137 -308.419683)
			(xy 51.617377 -308.422351) (xy 51.631342 -308.424834) (xy 51.643788 -308.42712) (xy 51.66741 -308.419754)
			(xy 51.74488 -308.342284) (xy 51.752246 -308.318662) (xy 51.74996 -308.306216) (xy 51.747477 -308.292251)
			(xy 51.744809 -308.264011) (xy 51.744626 -308.249828) (xy 51.745048 -308.225005) (xy 51.753075 -308.176012)
			(xy 51.768923 -308.128963) (xy 51.792173 -308.085098) (xy 51.822214 -308.045573) (xy 51.858254 -308.011428)
			(xy 51.899342 -307.983563) (xy 51.944398 -307.962713) (xy 51.992233 -307.949426) (xy 52.041588 -307.944054)
			(xy 52.091161 -307.946737) (xy 52.139647 -307.957404) (xy 52.185769 -307.975776) (xy 52.228311 -308.001367)
			(xy 52.266153 -308.033503) (xy 52.298297 -308.071338) (xy 52.323897 -308.113875) (xy 52.342277 -308.159993)
			(xy 52.352955 -308.208477) (xy 52.3552 -308.2498) (xy 52.694097 -308.2498) (xy 52.698268 -308.199467)
			(xy 52.710666 -308.150507) (xy 52.730953 -308.104256) (xy 52.758577 -308.061974) (xy 52.792783 -308.024816)
			(xy 52.832638 -307.993794) (xy 52.877056 -307.969756) (xy 52.924825 -307.953356) (xy 52.974641 -307.945042)
			(xy 52.999894 -307.94452) (xy 53.014077 -307.944697) (xy 53.042317 -307.947369) (xy 53.056282 -307.949854)
			(xy 53.068728 -307.95214) (xy 53.09235 -307.944774) (xy 53.16982 -307.867304) (xy 53.177186 -307.843682)
			(xy 53.1749 -307.831236) (xy 53.172419 -307.817271) (xy 53.16975 -307.789031) (xy 53.169566 -307.774848)
			(xy 53.170026 -307.750022) (xy 53.178051 -307.701023) (xy 53.193899 -307.653967) (xy 53.21715 -307.610096)
			(xy 53.247194 -307.570565) (xy 53.283237 -307.536415) (xy 53.32433 -307.508546) (xy 53.369391 -307.487693)
			(xy 53.417233 -307.474406) (xy 53.466593 -307.469033) (xy 53.516173 -307.471718) (xy 53.564665 -307.482388)
			(xy 53.610791 -307.500764) (xy 53.653337 -307.52636) (xy 53.691182 -307.558503) (xy 53.723327 -307.596345)
			(xy 53.748926 -307.638889) (xy 53.767305 -307.685014) (xy 53.777979 -307.733505) (xy 53.78022 -307.774848)
			(xy 54.11903 -307.774848) (xy 54.12299 -307.725794) (xy 54.134767 -307.67801) (xy 54.154058 -307.632734)
			(xy 54.180361 -307.591138) (xy 54.212996 -307.554301) (xy 54.251117 -307.523176) (xy 54.293738 -307.498569)
			(xy 54.339754 -307.481117) (xy 54.387973 -307.471273) (xy 54.437148 -307.469292) (xy 54.486003 -307.475224)
			(xy 54.533274 -307.488916) (xy 54.577736 -307.510014) (xy 54.618239 -307.53797) (xy 54.653732 -307.572062)
			(xy 54.683297 -307.611406) (xy 54.706168 -307.654983) (xy 54.721752 -307.701664) (xy 54.729647 -307.750241)
			(xy 54.730142 -307.774848) (xy 55.06899 -307.774848) (xy 55.07295 -307.725794) (xy 55.084727 -307.67801)
			(xy 55.104018 -307.632734) (xy 55.130321 -307.591138) (xy 55.162956 -307.554301) (xy 55.201077 -307.523176)
			(xy 55.243698 -307.498569) (xy 55.289714 -307.481117) (xy 55.337933 -307.471273) (xy 55.387108 -307.469292)
			(xy 55.435963 -307.475224) (xy 55.483234 -307.488916) (xy 55.527696 -307.510014) (xy 55.568199 -307.53797)
			(xy 55.603692 -307.572062) (xy 55.633257 -307.611406) (xy 55.656128 -307.654983) (xy 55.671712 -307.701664)
			(xy 55.679607 -307.750241) (xy 55.680102 -307.774848) (xy 56.019204 -307.774848) (xy 56.023164 -307.725794)
			(xy 56.034941 -307.67801) (xy 56.054232 -307.632734) (xy 56.080535 -307.591138) (xy 56.11317 -307.554301)
			(xy 56.151291 -307.523176) (xy 56.193912 -307.498569) (xy 56.239928 -307.481117) (xy 56.288147 -307.471273)
			(xy 56.337322 -307.469292) (xy 56.386177 -307.475224) (xy 56.433448 -307.488916) (xy 56.47791 -307.510014)
			(xy 56.518413 -307.53797) (xy 56.553906 -307.572062) (xy 56.583471 -307.611406) (xy 56.606342 -307.654983)
			(xy 56.621926 -307.701664) (xy 56.629821 -307.750241) (xy 56.630316 -307.774848) (xy 56.969164 -307.774848)
			(xy 56.973124 -307.725794) (xy 56.984901 -307.67801) (xy 57.004192 -307.632734) (xy 57.030495 -307.591138)
			(xy 57.06313 -307.554301) (xy 57.101251 -307.523176) (xy 57.143872 -307.498569) (xy 57.189888 -307.481117)
			(xy 57.238107 -307.471273) (xy 57.287282 -307.469292) (xy 57.336137 -307.475224) (xy 57.383408 -307.488916)
			(xy 57.42787 -307.510014) (xy 57.468373 -307.53797) (xy 57.503866 -307.572062) (xy 57.533431 -307.611406)
			(xy 57.556302 -307.654983) (xy 57.571886 -307.701664) (xy 57.579781 -307.750241) (xy 57.580276 -307.774848)
			(xy 57.919124 -307.774848) (xy 57.923084 -307.725794) (xy 57.934861 -307.67801) (xy 57.954152 -307.632734)
			(xy 57.980455 -307.591138) (xy 58.01309 -307.554301) (xy 58.051211 -307.523176) (xy 58.093832 -307.498569)
			(xy 58.139848 -307.481117) (xy 58.188067 -307.471273) (xy 58.237242 -307.469292) (xy 58.286097 -307.475224)
			(xy 58.333368 -307.488916) (xy 58.37783 -307.510014) (xy 58.418333 -307.53797) (xy 58.453826 -307.572062)
			(xy 58.483391 -307.611406) (xy 58.506262 -307.654983) (xy 58.521846 -307.701664) (xy 58.529741 -307.750241)
			(xy 58.530236 -307.774848) (xy 59.819044 -307.774848) (xy 59.823004 -307.725794) (xy 59.834781 -307.67801)
			(xy 59.854072 -307.632734) (xy 59.880375 -307.591138) (xy 59.91301 -307.554301) (xy 59.951131 -307.523176)
			(xy 59.993752 -307.498569) (xy 60.039768 -307.481117) (xy 60.087987 -307.471273) (xy 60.137162 -307.469292)
			(xy 60.186017 -307.475224) (xy 60.233288 -307.488916) (xy 60.27775 -307.510014) (xy 60.318253 -307.53797)
			(xy 60.353746 -307.572062) (xy 60.383311 -307.611406) (xy 60.406182 -307.654983) (xy 60.421766 -307.701664)
			(xy 60.429661 -307.750241) (xy 60.430156 -307.774848) (xy 60.769004 -307.774848) (xy 60.772964 -307.725794)
			(xy 60.784741 -307.67801) (xy 60.804032 -307.632734) (xy 60.830335 -307.591138) (xy 60.86297 -307.554301)
			(xy 60.901091 -307.523176) (xy 60.943712 -307.498569) (xy 60.989728 -307.481117) (xy 61.037947 -307.471273)
			(xy 61.087122 -307.469292) (xy 61.135977 -307.475224) (xy 61.183248 -307.488916) (xy 61.22771 -307.510014)
			(xy 61.268213 -307.53797) (xy 61.303706 -307.572062) (xy 61.333271 -307.611406) (xy 61.356142 -307.654983)
			(xy 61.371726 -307.701664) (xy 61.379621 -307.750241) (xy 61.380116 -307.774848) (xy 61.718964 -307.774848)
			(xy 61.722924 -307.725794) (xy 61.734701 -307.67801) (xy 61.753992 -307.632734) (xy 61.780295 -307.591138)
			(xy 61.81293 -307.554301) (xy 61.851051 -307.523176) (xy 61.893672 -307.498569) (xy 61.939688 -307.481117)
			(xy 61.987907 -307.471273) (xy 62.037082 -307.469292) (xy 62.085937 -307.475224) (xy 62.133208 -307.488916)
			(xy 62.17767 -307.510014) (xy 62.218173 -307.53797) (xy 62.253666 -307.572062) (xy 62.283231 -307.611406)
			(xy 62.306102 -307.654983) (xy 62.321686 -307.701664) (xy 62.329581 -307.750241) (xy 62.330071 -307.774594)
			(xy 62.668924 -307.774594) (xy 62.672884 -307.72554) (xy 62.684661 -307.677756) (xy 62.703952 -307.63248)
			(xy 62.730255 -307.590884) (xy 62.76289 -307.554047) (xy 62.801011 -307.522922) (xy 62.843632 -307.498315)
			(xy 62.889648 -307.480863) (xy 62.937867 -307.471019) (xy 62.987042 -307.469038) (xy 63.035897 -307.47497)
			(xy 63.083168 -307.488662) (xy 63.12763 -307.50976) (xy 63.168133 -307.537716) (xy 63.203626 -307.571808)
			(xy 63.233191 -307.611152) (xy 63.256062 -307.654729) (xy 63.271646 -307.70141) (xy 63.279541 -307.749987)
			(xy 63.280036 -307.774594) (xy 63.619138 -307.774594) (xy 63.623098 -307.72554) (xy 63.634875 -307.677756)
			(xy 63.654166 -307.63248) (xy 63.680469 -307.590884) (xy 63.713104 -307.554047) (xy 63.751225 -307.522922)
			(xy 63.793846 -307.498315) (xy 63.839862 -307.480863) (xy 63.888081 -307.471019) (xy 63.937256 -307.469038)
			(xy 63.986111 -307.47497) (xy 64.033382 -307.488662) (xy 64.077844 -307.50976) (xy 64.118347 -307.537716)
			(xy 64.15384 -307.571808) (xy 64.183405 -307.611152) (xy 64.206276 -307.654729) (xy 64.22186 -307.70141)
			(xy 64.229755 -307.749987) (xy 64.23025 -307.774594) (xy 64.230245 -307.774848) (xy 64.569098 -307.774848)
			(xy 64.573058 -307.725794) (xy 64.584835 -307.67801) (xy 64.604126 -307.632734) (xy 64.630429 -307.591138)
			(xy 64.663064 -307.554301) (xy 64.701185 -307.523176) (xy 64.743806 -307.498569) (xy 64.789822 -307.481117)
			(xy 64.838041 -307.471273) (xy 64.887216 -307.469292) (xy 64.936071 -307.475224) (xy 64.983342 -307.488916)
			(xy 65.027804 -307.510014) (xy 65.068307 -307.53797) (xy 65.1038 -307.572062) (xy 65.133365 -307.611406)
			(xy 65.156236 -307.654983) (xy 65.17182 -307.701664) (xy 65.179715 -307.750241) (xy 65.18021 -307.774848)
			(xy 65.519058 -307.774848) (xy 65.523018 -307.725794) (xy 65.534795 -307.67801) (xy 65.554086 -307.632734)
			(xy 65.580389 -307.591138) (xy 65.613024 -307.554301) (xy 65.651145 -307.523176) (xy 65.693766 -307.498569)
			(xy 65.739782 -307.481117) (xy 65.788001 -307.471273) (xy 65.837176 -307.469292) (xy 65.886031 -307.475224)
			(xy 65.933302 -307.488916) (xy 65.977764 -307.510014) (xy 66.018267 -307.53797) (xy 66.05376 -307.572062)
			(xy 66.083325 -307.611406) (xy 66.106196 -307.654983) (xy 66.12178 -307.701664) (xy 66.129675 -307.750241)
			(xy 66.13017 -307.774848) (xy 66.469018 -307.774848) (xy 66.472978 -307.725794) (xy 66.484755 -307.67801)
			(xy 66.504046 -307.632734) (xy 66.530349 -307.591138) (xy 66.562984 -307.554301) (xy 66.601105 -307.523176)
			(xy 66.643726 -307.498569) (xy 66.689742 -307.481117) (xy 66.737961 -307.471273) (xy 66.787136 -307.469292)
			(xy 66.835991 -307.475224) (xy 66.883262 -307.488916) (xy 66.927724 -307.510014) (xy 66.968227 -307.53797)
			(xy 67.00372 -307.572062) (xy 67.033285 -307.611406) (xy 67.056156 -307.654983) (xy 67.07174 -307.701664)
			(xy 67.079635 -307.750241) (xy 67.08013 -307.774848) (xy 67.418978 -307.774848) (xy 67.422938 -307.725794)
			(xy 67.434715 -307.67801) (xy 67.454006 -307.632734) (xy 67.480309 -307.591138) (xy 67.512944 -307.554301)
			(xy 67.551065 -307.523176) (xy 67.593686 -307.498569) (xy 67.639702 -307.481117) (xy 67.687921 -307.471273)
			(xy 67.737096 -307.469292) (xy 67.785951 -307.475224) (xy 67.833222 -307.488916) (xy 67.877684 -307.510014)
			(xy 67.918187 -307.53797) (xy 67.95368 -307.572062) (xy 67.983245 -307.611406) (xy 68.006116 -307.654983)
			(xy 68.0217 -307.701664) (xy 68.029595 -307.750241) (xy 68.03009 -307.774848) (xy 68.368938 -307.774848)
			(xy 68.372898 -307.725794) (xy 68.384675 -307.67801) (xy 68.403966 -307.632734) (xy 68.430269 -307.591138)
			(xy 68.462904 -307.554301) (xy 68.501025 -307.523176) (xy 68.543646 -307.498569) (xy 68.589662 -307.481117)
			(xy 68.637881 -307.471273) (xy 68.687056 -307.469292) (xy 68.735911 -307.475224) (xy 68.783182 -307.488916)
			(xy 68.827644 -307.510014) (xy 68.868147 -307.53797) (xy 68.90364 -307.572062) (xy 68.933205 -307.611406)
			(xy 68.956076 -307.654983) (xy 68.97166 -307.701664) (xy 68.979555 -307.750241) (xy 68.98005 -307.774848)
			(xy 69.319152 -307.774848) (xy 69.323112 -307.725794) (xy 69.334889 -307.67801) (xy 69.35418 -307.632734)
			(xy 69.380483 -307.591138) (xy 69.413118 -307.554301) (xy 69.451239 -307.523176) (xy 69.49386 -307.498569)
			(xy 69.539876 -307.481117) (xy 69.588095 -307.471273) (xy 69.63727 -307.469292) (xy 69.686125 -307.475224)
			(xy 69.733396 -307.488916) (xy 69.777858 -307.510014) (xy 69.818361 -307.53797) (xy 69.853854 -307.572062)
			(xy 69.883419 -307.611406) (xy 69.90629 -307.654983) (xy 69.921874 -307.701664) (xy 69.929769 -307.750241)
			(xy 69.930264 -307.774848) (xy 70.269112 -307.774848) (xy 70.273072 -307.725794) (xy 70.284849 -307.67801)
			(xy 70.30414 -307.632734) (xy 70.330443 -307.591138) (xy 70.363078 -307.554301) (xy 70.401199 -307.523176)
			(xy 70.44382 -307.498569) (xy 70.489836 -307.481117) (xy 70.538055 -307.471273) (xy 70.58723 -307.469292)
			(xy 70.636085 -307.475224) (xy 70.683356 -307.488916) (xy 70.727818 -307.510014) (xy 70.768321 -307.53797)
			(xy 70.803814 -307.572062) (xy 70.833379 -307.611406) (xy 70.85625 -307.654983) (xy 70.871834 -307.701664)
			(xy 70.879729 -307.750241) (xy 70.880224 -307.774848) (xy 71.219072 -307.774848) (xy 71.223032 -307.725794)
			(xy 71.234809 -307.67801) (xy 71.2541 -307.632734) (xy 71.280403 -307.591138) (xy 71.313038 -307.554301)
			(xy 71.351159 -307.523176) (xy 71.39378 -307.498569) (xy 71.439796 -307.481117) (xy 71.488015 -307.471273)
			(xy 71.53719 -307.469292) (xy 71.586045 -307.475224) (xy 71.633316 -307.488916) (xy 71.677778 -307.510014)
			(xy 71.718281 -307.53797) (xy 71.753774 -307.572062) (xy 71.783339 -307.611406) (xy 71.80621 -307.654983)
			(xy 71.821794 -307.701664) (xy 71.829689 -307.750241) (xy 71.830184 -307.774848) (xy 72.169032 -307.774848)
			(xy 72.172992 -307.725794) (xy 72.184769 -307.67801) (xy 72.20406 -307.632734) (xy 72.230363 -307.591138)
			(xy 72.262998 -307.554301) (xy 72.301119 -307.523176) (xy 72.34374 -307.498569) (xy 72.389756 -307.481117)
			(xy 72.437975 -307.471273) (xy 72.48715 -307.469292) (xy 72.536005 -307.475224) (xy 72.583276 -307.488916)
			(xy 72.627738 -307.510014) (xy 72.668241 -307.53797) (xy 72.703734 -307.572062) (xy 72.733299 -307.611406)
			(xy 72.75617 -307.654983) (xy 72.771754 -307.701664) (xy 72.779649 -307.750241) (xy 72.780144 -307.774848)
			(xy 72.779649 -307.799455) (xy 72.771754 -307.848032) (xy 72.75617 -307.894713) (xy 72.733299 -307.93829)
			(xy 72.703734 -307.977634) (xy 72.668241 -308.011726) (xy 72.627738 -308.039682) (xy 72.583276 -308.06078)
			(xy 72.536005 -308.074472) (xy 72.48715 -308.080404) (xy 72.437975 -308.078423) (xy 72.389756 -308.068579)
			(xy 72.34374 -308.051127) (xy 72.301119 -308.02652) (xy 72.262998 -307.995395) (xy 72.230363 -307.958558)
			(xy 72.20406 -307.916962) (xy 72.184769 -307.871686) (xy 72.172992 -307.823902) (xy 72.169032 -307.774848)
			(xy 71.830184 -307.774848) (xy 71.829689 -307.799455) (xy 71.821794 -307.848032) (xy 71.80621 -307.894713)
			(xy 71.783339 -307.93829) (xy 71.753774 -307.977634) (xy 71.718281 -308.011726) (xy 71.677778 -308.039682)
			(xy 71.633316 -308.06078) (xy 71.586045 -308.074472) (xy 71.53719 -308.080404) (xy 71.488015 -308.078423)
			(xy 71.439796 -308.068579) (xy 71.39378 -308.051127) (xy 71.351159 -308.02652) (xy 71.313038 -307.995395)
			(xy 71.280403 -307.958558) (xy 71.2541 -307.916962) (xy 71.234809 -307.871686) (xy 71.223032 -307.823902)
			(xy 71.219072 -307.774848) (xy 70.880224 -307.774848) (xy 70.879729 -307.799455) (xy 70.871834 -307.848032)
			(xy 70.85625 -307.894713) (xy 70.833379 -307.93829) (xy 70.803814 -307.977634) (xy 70.768321 -308.011726)
			(xy 70.727818 -308.039682) (xy 70.683356 -308.06078) (xy 70.636085 -308.074472) (xy 70.58723 -308.080404)
			(xy 70.538055 -308.078423) (xy 70.489836 -308.068579) (xy 70.44382 -308.051127) (xy 70.401199 -308.02652)
			(xy 70.363078 -307.995395) (xy 70.330443 -307.958558) (xy 70.30414 -307.916962) (xy 70.284849 -307.871686)
			(xy 70.273072 -307.823902) (xy 70.269112 -307.774848) (xy 69.930264 -307.774848) (xy 69.929769 -307.799455)
			(xy 69.921874 -307.848032) (xy 69.90629 -307.894713) (xy 69.883419 -307.93829) (xy 69.853854 -307.977634)
			(xy 69.818361 -308.011726) (xy 69.777858 -308.039682) (xy 69.733396 -308.06078) (xy 69.686125 -308.074472)
			(xy 69.63727 -308.080404) (xy 69.588095 -308.078423) (xy 69.539876 -308.068579) (xy 69.49386 -308.051127)
			(xy 69.451239 -308.02652) (xy 69.413118 -307.995395) (xy 69.380483 -307.958558) (xy 69.35418 -307.916962)
			(xy 69.334889 -307.871686) (xy 69.323112 -307.823902) (xy 69.319152 -307.774848) (xy 68.98005 -307.774848)
			(xy 68.979555 -307.799455) (xy 68.97166 -307.848032) (xy 68.956076 -307.894713) (xy 68.933205 -307.93829)
			(xy 68.90364 -307.977634) (xy 68.868147 -308.011726) (xy 68.827644 -308.039682) (xy 68.783182 -308.06078)
			(xy 68.735911 -308.074472) (xy 68.687056 -308.080404) (xy 68.637881 -308.078423) (xy 68.589662 -308.068579)
			(xy 68.543646 -308.051127) (xy 68.501025 -308.02652) (xy 68.462904 -307.995395) (xy 68.430269 -307.958558)
			(xy 68.403966 -307.916962) (xy 68.384675 -307.871686) (xy 68.372898 -307.823902) (xy 68.368938 -307.774848)
			(xy 68.03009 -307.774848) (xy 68.029595 -307.799455) (xy 68.0217 -307.848032) (xy 68.006116 -307.894713)
			(xy 67.983245 -307.93829) (xy 67.95368 -307.977634) (xy 67.918187 -308.011726) (xy 67.877684 -308.039682)
			(xy 67.833222 -308.06078) (xy 67.785951 -308.074472) (xy 67.737096 -308.080404) (xy 67.687921 -308.078423)
			(xy 67.639702 -308.068579) (xy 67.593686 -308.051127) (xy 67.551065 -308.02652) (xy 67.512944 -307.995395)
			(xy 67.480309 -307.958558) (xy 67.454006 -307.916962) (xy 67.434715 -307.871686) (xy 67.422938 -307.823902)
			(xy 67.418978 -307.774848) (xy 67.08013 -307.774848) (xy 67.079635 -307.799455) (xy 67.07174 -307.848032)
			(xy 67.056156 -307.894713) (xy 67.033285 -307.93829) (xy 67.00372 -307.977634) (xy 66.968227 -308.011726)
			(xy 66.927724 -308.039682) (xy 66.883262 -308.06078) (xy 66.835991 -308.074472) (xy 66.787136 -308.080404)
			(xy 66.737961 -308.078423) (xy 66.689742 -308.068579) (xy 66.643726 -308.051127) (xy 66.601105 -308.02652)
			(xy 66.562984 -307.995395) (xy 66.530349 -307.958558) (xy 66.504046 -307.916962) (xy 66.484755 -307.871686)
			(xy 66.472978 -307.823902) (xy 66.469018 -307.774848) (xy 66.13017 -307.774848) (xy 66.129675 -307.799455)
			(xy 66.12178 -307.848032) (xy 66.106196 -307.894713) (xy 66.083325 -307.93829) (xy 66.05376 -307.977634)
			(xy 66.018267 -308.011726) (xy 65.977764 -308.039682) (xy 65.933302 -308.06078) (xy 65.886031 -308.074472)
			(xy 65.837176 -308.080404) (xy 65.788001 -308.078423) (xy 65.739782 -308.068579) (xy 65.693766 -308.051127)
			(xy 65.651145 -308.02652) (xy 65.613024 -307.995395) (xy 65.580389 -307.958558) (xy 65.554086 -307.916962)
			(xy 65.534795 -307.871686) (xy 65.523018 -307.823902) (xy 65.519058 -307.774848) (xy 65.18021 -307.774848)
			(xy 65.179715 -307.799455) (xy 65.17182 -307.848032) (xy 65.156236 -307.894713) (xy 65.133365 -307.93829)
			(xy 65.1038 -307.977634) (xy 65.068307 -308.011726) (xy 65.027804 -308.039682) (xy 64.983342 -308.06078)
			(xy 64.936071 -308.074472) (xy 64.887216 -308.080404) (xy 64.838041 -308.078423) (xy 64.789822 -308.068579)
			(xy 64.743806 -308.051127) (xy 64.701185 -308.02652) (xy 64.663064 -307.995395) (xy 64.630429 -307.958558)
			(xy 64.604126 -307.916962) (xy 64.584835 -307.871686) (xy 64.573058 -307.823902) (xy 64.569098 -307.774848)
			(xy 64.230245 -307.774848) (xy 64.229755 -307.799201) (xy 64.22186 -307.847778) (xy 64.206276 -307.894459)
			(xy 64.183405 -307.938036) (xy 64.15384 -307.97738) (xy 64.118347 -308.011472) (xy 64.077844 -308.039428)
			(xy 64.033382 -308.060526) (xy 63.986111 -308.074218) (xy 63.937256 -308.08015) (xy 63.888081 -308.078169)
			(xy 63.839862 -308.068325) (xy 63.793846 -308.050873) (xy 63.751225 -308.026266) (xy 63.713104 -307.995141)
			(xy 63.680469 -307.958304) (xy 63.654166 -307.916708) (xy 63.634875 -307.871432) (xy 63.623098 -307.823648)
			(xy 63.619138 -307.774594) (xy 63.280036 -307.774594) (xy 63.279541 -307.799201) (xy 63.271646 -307.847778)
			(xy 63.256062 -307.894459) (xy 63.233191 -307.938036) (xy 63.203626 -307.97738) (xy 63.168133 -308.011472)
			(xy 63.12763 -308.039428) (xy 63.083168 -308.060526) (xy 63.035897 -308.074218) (xy 62.987042 -308.08015)
			(xy 62.937867 -308.078169) (xy 62.889648 -308.068325) (xy 62.843632 -308.050873) (xy 62.801011 -308.026266)
			(xy 62.76289 -307.995141) (xy 62.730255 -307.958304) (xy 62.703952 -307.916708) (xy 62.684661 -307.871432)
			(xy 62.672884 -307.823648) (xy 62.668924 -307.774594) (xy 62.330071 -307.774594) (xy 62.330076 -307.774848)
			(xy 62.329581 -307.799455) (xy 62.321686 -307.848032) (xy 62.306102 -307.894713) (xy 62.283231 -307.93829)
			(xy 62.253666 -307.977634) (xy 62.218173 -308.011726) (xy 62.17767 -308.039682) (xy 62.133208 -308.06078)
			(xy 62.085937 -308.074472) (xy 62.037082 -308.080404) (xy 61.987907 -308.078423) (xy 61.939688 -308.068579)
			(xy 61.893672 -308.051127) (xy 61.851051 -308.02652) (xy 61.81293 -307.995395) (xy 61.780295 -307.958558)
			(xy 61.753992 -307.916962) (xy 61.734701 -307.871686) (xy 61.722924 -307.823902) (xy 61.718964 -307.774848)
			(xy 61.380116 -307.774848) (xy 61.379621 -307.799455) (xy 61.371726 -307.848032) (xy 61.356142 -307.894713)
			(xy 61.333271 -307.93829) (xy 61.303706 -307.977634) (xy 61.268213 -308.011726) (xy 61.22771 -308.039682)
			(xy 61.183248 -308.06078) (xy 61.135977 -308.074472) (xy 61.087122 -308.080404) (xy 61.037947 -308.078423)
			(xy 60.989728 -308.068579) (xy 60.943712 -308.051127) (xy 60.901091 -308.02652) (xy 60.86297 -307.995395)
			(xy 60.830335 -307.958558) (xy 60.804032 -307.916962) (xy 60.784741 -307.871686) (xy 60.772964 -307.823902)
			(xy 60.769004 -307.774848) (xy 60.430156 -307.774848) (xy 60.429661 -307.799455) (xy 60.421766 -307.848032)
			(xy 60.406182 -307.894713) (xy 60.383311 -307.93829) (xy 60.353746 -307.977634) (xy 60.318253 -308.011726)
			(xy 60.27775 -308.039682) (xy 60.233288 -308.06078) (xy 60.186017 -308.074472) (xy 60.137162 -308.080404)
			(xy 60.087987 -308.078423) (xy 60.039768 -308.068579) (xy 59.993752 -308.051127) (xy 59.951131 -308.02652)
			(xy 59.91301 -307.995395) (xy 59.880375 -307.958558) (xy 59.854072 -307.916962) (xy 59.834781 -307.871686)
			(xy 59.823004 -307.823902) (xy 59.819044 -307.774848) (xy 58.530236 -307.774848) (xy 58.529741 -307.799455)
			(xy 58.521846 -307.848032) (xy 58.506262 -307.894713) (xy 58.483391 -307.93829) (xy 58.453826 -307.977634)
			(xy 58.418333 -308.011726) (xy 58.37783 -308.039682) (xy 58.333368 -308.06078) (xy 58.286097 -308.074472)
			(xy 58.237242 -308.080404) (xy 58.188067 -308.078423) (xy 58.139848 -308.068579) (xy 58.093832 -308.051127)
			(xy 58.051211 -308.02652) (xy 58.01309 -307.995395) (xy 57.980455 -307.958558) (xy 57.954152 -307.916962)
			(xy 57.934861 -307.871686) (xy 57.923084 -307.823902) (xy 57.919124 -307.774848) (xy 57.580276 -307.774848)
			(xy 57.579781 -307.799455) (xy 57.571886 -307.848032) (xy 57.556302 -307.894713) (xy 57.533431 -307.93829)
			(xy 57.503866 -307.977634) (xy 57.468373 -308.011726) (xy 57.42787 -308.039682) (xy 57.383408 -308.06078)
			(xy 57.336137 -308.074472) (xy 57.287282 -308.080404) (xy 57.238107 -308.078423) (xy 57.189888 -308.068579)
			(xy 57.143872 -308.051127) (xy 57.101251 -308.02652) (xy 57.06313 -307.995395) (xy 57.030495 -307.958558)
			(xy 57.004192 -307.916962) (xy 56.984901 -307.871686) (xy 56.973124 -307.823902) (xy 56.969164 -307.774848)
			(xy 56.630316 -307.774848) (xy 56.629821 -307.799455) (xy 56.621926 -307.848032) (xy 56.606342 -307.894713)
			(xy 56.583471 -307.93829) (xy 56.553906 -307.977634) (xy 56.518413 -308.011726) (xy 56.47791 -308.039682)
			(xy 56.433448 -308.06078) (xy 56.386177 -308.074472) (xy 56.337322 -308.080404) (xy 56.288147 -308.078423)
			(xy 56.239928 -308.068579) (xy 56.193912 -308.051127) (xy 56.151291 -308.02652) (xy 56.11317 -307.995395)
			(xy 56.080535 -307.958558) (xy 56.054232 -307.916962) (xy 56.034941 -307.871686) (xy 56.023164 -307.823902)
			(xy 56.019204 -307.774848) (xy 55.680102 -307.774848) (xy 55.679607 -307.799455) (xy 55.671712 -307.848032)
			(xy 55.656128 -307.894713) (xy 55.633257 -307.93829) (xy 55.603692 -307.977634) (xy 55.568199 -308.011726)
			(xy 55.527696 -308.039682) (xy 55.483234 -308.06078) (xy 55.435963 -308.074472) (xy 55.387108 -308.080404)
			(xy 55.337933 -308.078423) (xy 55.289714 -308.068579) (xy 55.243698 -308.051127) (xy 55.201077 -308.02652)
			(xy 55.162956 -307.995395) (xy 55.130321 -307.958558) (xy 55.104018 -307.916962) (xy 55.084727 -307.871686)
			(xy 55.07295 -307.823902) (xy 55.06899 -307.774848) (xy 54.730142 -307.774848) (xy 54.729647 -307.799455)
			(xy 54.721752 -307.848032) (xy 54.706168 -307.894713) (xy 54.683297 -307.93829) (xy 54.653732 -307.977634)
			(xy 54.618239 -308.011726) (xy 54.577736 -308.039682) (xy 54.533274 -308.06078) (xy 54.486003 -308.074472)
			(xy 54.437148 -308.080404) (xy 54.387973 -308.078423) (xy 54.339754 -308.068579) (xy 54.293738 -308.051127)
			(xy 54.251117 -308.02652) (xy 54.212996 -307.995395) (xy 54.180361 -307.958558) (xy 54.154058 -307.916962)
			(xy 54.134767 -307.871686) (xy 54.12299 -307.823902) (xy 54.11903 -307.774848) (xy 53.78022 -307.774848)
			(xy 53.780667 -307.783085) (xy 53.775298 -307.832446) (xy 53.762014 -307.880288) (xy 53.741165 -307.92535)
			(xy 53.713299 -307.966446) (xy 53.679152 -308.002492) (xy 53.639622 -308.032538) (xy 53.595753 -308.055793)
			(xy 53.548699 -308.071643) (xy 53.4997 -308.079672) (xy 53.474874 -308.080156) (xy 53.460691 -308.079984)
			(xy 53.432451 -308.077309) (xy 53.418486 -308.074822) (xy 53.40604 -308.072536) (xy 53.382418 -308.079902)
			(xy 53.304948 -308.157372) (xy 53.297582 -308.180994) (xy 53.299868 -308.19344) (xy 53.302346 -308.207406)
			(xy 53.305017 -308.235645) (xy 53.305202 -308.249828) (xy 73.593972 -308.249828) (xy 73.597932 -308.200774)
			(xy 73.609709 -308.15299) (xy 73.629 -308.107714) (xy 73.655303 -308.066118) (xy 73.687938 -308.029281)
			(xy 73.726059 -307.998156) (xy 73.76868 -307.973549) (xy 73.814696 -307.956097) (xy 73.862915 -307.946253)
			(xy 73.91209 -307.944272) (xy 73.960945 -307.950204) (xy 74.008216 -307.963896) (xy 74.052678 -307.984994)
			(xy 74.093181 -308.01295) (xy 74.128674 -308.047042) (xy 74.158239 -308.086386) (xy 74.18111 -308.129963)
			(xy 74.196694 -308.176644) (xy 74.204589 -308.225221) (xy 74.205084 -308.249828) (xy 74.544186 -308.249828)
			(xy 74.548146 -308.200774) (xy 74.559923 -308.15299) (xy 74.579214 -308.107714) (xy 74.605517 -308.066118)
			(xy 74.638152 -308.029281) (xy 74.676273 -307.998156) (xy 74.718894 -307.973549) (xy 74.76491 -307.956097)
			(xy 74.813129 -307.946253) (xy 74.862304 -307.944272) (xy 74.911159 -307.950204) (xy 74.95843 -307.963896)
			(xy 75.002892 -307.984994) (xy 75.043395 -308.01295) (xy 75.078888 -308.047042) (xy 75.108453 -308.086386)
			(xy 75.131324 -308.129963) (xy 75.146908 -308.176644) (xy 75.154803 -308.225221) (xy 75.155298 -308.249828)
			(xy 75.494146 -308.249828) (xy 75.498106 -308.200774) (xy 75.509883 -308.15299) (xy 75.529174 -308.107714)
			(xy 75.555477 -308.066118) (xy 75.588112 -308.029281) (xy 75.626233 -307.998156) (xy 75.668854 -307.973549)
			(xy 75.71487 -307.956097) (xy 75.763089 -307.946253) (xy 75.812264 -307.944272) (xy 75.861119 -307.950204)
			(xy 75.90839 -307.963896) (xy 75.952852 -307.984994) (xy 75.993355 -308.01295) (xy 76.028848 -308.047042)
			(xy 76.058413 -308.086386) (xy 76.081284 -308.129963) (xy 76.096868 -308.176644) (xy 76.104763 -308.225221)
			(xy 76.105258 -308.249828) (xy 76.444106 -308.249828) (xy 76.448066 -308.200774) (xy 76.459843 -308.15299)
			(xy 76.479134 -308.107714) (xy 76.505437 -308.066118) (xy 76.538072 -308.029281) (xy 76.576193 -307.998156)
			(xy 76.618814 -307.973549) (xy 76.66483 -307.956097) (xy 76.713049 -307.946253) (xy 76.762224 -307.944272)
			(xy 76.811079 -307.950204) (xy 76.85835 -307.963896) (xy 76.902812 -307.984994) (xy 76.943315 -308.01295)
			(xy 76.978808 -308.047042) (xy 77.008373 -308.086386) (xy 77.031244 -308.129963) (xy 77.046828 -308.176644)
			(xy 77.054723 -308.225221) (xy 77.055218 -308.249828) (xy 77.394066 -308.249828) (xy 77.398026 -308.200774)
			(xy 77.409803 -308.15299) (xy 77.429094 -308.107714) (xy 77.455397 -308.066118) (xy 77.488032 -308.029281)
			(xy 77.526153 -307.998156) (xy 77.568774 -307.973549) (xy 77.61479 -307.956097) (xy 77.663009 -307.946253)
			(xy 77.712184 -307.944272) (xy 77.761039 -307.950204) (xy 77.80831 -307.963896) (xy 77.852772 -307.984994)
			(xy 77.893275 -308.01295) (xy 77.928768 -308.047042) (xy 77.958333 -308.086386) (xy 77.981204 -308.129963)
			(xy 77.996788 -308.176644) (xy 78.004683 -308.225221) (xy 78.005178 -308.249828) (xy 78.344026 -308.249828)
			(xy 78.347986 -308.200774) (xy 78.359763 -308.15299) (xy 78.379054 -308.107714) (xy 78.405357 -308.066118)
			(xy 78.437992 -308.029281) (xy 78.476113 -307.998156) (xy 78.518734 -307.973549) (xy 78.56475 -307.956097)
			(xy 78.612969 -307.946253) (xy 78.662144 -307.944272) (xy 78.710999 -307.950204) (xy 78.75827 -307.963896)
			(xy 78.802732 -307.984994) (xy 78.843235 -308.01295) (xy 78.878728 -308.047042) (xy 78.908293 -308.086386)
			(xy 78.931164 -308.129963) (xy 78.946748 -308.176644) (xy 78.954643 -308.225221) (xy 78.955138 -308.249828)
			(xy 79.293986 -308.249828) (xy 79.297946 -308.200774) (xy 79.309723 -308.15299) (xy 79.329014 -308.107714)
			(xy 79.355317 -308.066118) (xy 79.387952 -308.029281) (xy 79.426073 -307.998156) (xy 79.468694 -307.973549)
			(xy 79.51471 -307.956097) (xy 79.562929 -307.946253) (xy 79.612104 -307.944272) (xy 79.660959 -307.950204)
			(xy 79.70823 -307.963896) (xy 79.752692 -307.984994) (xy 79.793195 -308.01295) (xy 79.828688 -308.047042)
			(xy 79.858253 -308.086386) (xy 79.881124 -308.129963) (xy 79.896708 -308.176644) (xy 79.904603 -308.225221)
			(xy 79.905098 -308.249828) (xy 80.243946 -308.249828) (xy 80.247906 -308.200774) (xy 80.259683 -308.15299)
			(xy 80.278974 -308.107714) (xy 80.305277 -308.066118) (xy 80.337912 -308.029281) (xy 80.376033 -307.998156)
			(xy 80.418654 -307.973549) (xy 80.46467 -307.956097) (xy 80.512889 -307.946253) (xy 80.562064 -307.944272)
			(xy 80.610919 -307.950204) (xy 80.65819 -307.963896) (xy 80.702652 -307.984994) (xy 80.743155 -308.01295)
			(xy 80.778648 -308.047042) (xy 80.808213 -308.086386) (xy 80.831084 -308.129963) (xy 80.846668 -308.176644)
			(xy 80.854563 -308.225221) (xy 80.855058 -308.249828) (xy 81.19416 -308.249828) (xy 81.19812 -308.200774)
			(xy 81.209897 -308.15299) (xy 81.229188 -308.107714) (xy 81.255491 -308.066118) (xy 81.288126 -308.029281)
			(xy 81.326247 -307.998156) (xy 81.368868 -307.973549) (xy 81.414884 -307.956097) (xy 81.463103 -307.946253)
			(xy 81.512278 -307.944272) (xy 81.561133 -307.950204) (xy 81.608404 -307.963896) (xy 81.652866 -307.984994)
			(xy 81.693369 -308.01295) (xy 81.728862 -308.047042) (xy 81.758427 -308.086386) (xy 81.781298 -308.129963)
			(xy 81.796882 -308.176644) (xy 81.804777 -308.225221) (xy 81.805272 -308.249828) (xy 82.14412 -308.249828)
			(xy 82.14808 -308.200774) (xy 82.159857 -308.15299) (xy 82.179148 -308.107714) (xy 82.205451 -308.066118)
			(xy 82.238086 -308.029281) (xy 82.276207 -307.998156) (xy 82.318828 -307.973549) (xy 82.364844 -307.956097)
			(xy 82.413063 -307.946253) (xy 82.462238 -307.944272) (xy 82.511093 -307.950204) (xy 82.558364 -307.963896)
			(xy 82.602826 -307.984994) (xy 82.643329 -308.01295) (xy 82.678822 -308.047042) (xy 82.708387 -308.086386)
			(xy 82.731258 -308.129963) (xy 82.746842 -308.176644) (xy 82.754737 -308.225221) (xy 82.755232 -308.249828)
			(xy 83.094334 -308.249828) (xy 83.098294 -308.200774) (xy 83.110071 -308.15299) (xy 83.129362 -308.107714)
			(xy 83.155665 -308.066118) (xy 83.1883 -308.029281) (xy 83.226421 -307.998156) (xy 83.269042 -307.973549)
			(xy 83.315058 -307.956097) (xy 83.363277 -307.946253) (xy 83.412452 -307.944272) (xy 83.461307 -307.950204)
			(xy 83.508578 -307.963896) (xy 83.55304 -307.984994) (xy 83.593543 -308.01295) (xy 83.629036 -308.047042)
			(xy 83.658601 -308.086386) (xy 83.681472 -308.129963) (xy 83.697056 -308.176644) (xy 83.704951 -308.225221)
			(xy 83.705446 -308.249828) (xy 83.704951 -308.274435) (xy 83.697056 -308.323012) (xy 83.681472 -308.369693)
			(xy 83.658601 -308.41327) (xy 83.629036 -308.452614) (xy 83.593543 -308.486706) (xy 83.55304 -308.514662)
			(xy 83.508578 -308.53576) (xy 83.461307 -308.549452) (xy 83.412452 -308.555384) (xy 83.363277 -308.553403)
			(xy 83.315058 -308.543559) (xy 83.269042 -308.526107) (xy 83.226421 -308.5015) (xy 83.1883 -308.470375)
			(xy 83.155665 -308.433538) (xy 83.129362 -308.391942) (xy 83.110071 -308.346666) (xy 83.098294 -308.298882)
			(xy 83.094334 -308.249828) (xy 82.755232 -308.249828) (xy 82.754737 -308.274435) (xy 82.746842 -308.323012)
			(xy 82.731258 -308.369693) (xy 82.708387 -308.41327) (xy 82.678822 -308.452614) (xy 82.643329 -308.486706)
			(xy 82.602826 -308.514662) (xy 82.558364 -308.53576) (xy 82.511093 -308.549452) (xy 82.462238 -308.555384)
			(xy 82.413063 -308.553403) (xy 82.364844 -308.543559) (xy 82.318828 -308.526107) (xy 82.276207 -308.5015)
			(xy 82.238086 -308.470375) (xy 82.205451 -308.433538) (xy 82.179148 -308.391942) (xy 82.159857 -308.346666)
			(xy 82.14808 -308.298882) (xy 82.14412 -308.249828) (xy 81.805272 -308.249828) (xy 81.804777 -308.274435)
			(xy 81.796882 -308.323012) (xy 81.781298 -308.369693) (xy 81.758427 -308.41327) (xy 81.728862 -308.452614)
			(xy 81.693369 -308.486706) (xy 81.652866 -308.514662) (xy 81.608404 -308.53576) (xy 81.561133 -308.549452)
			(xy 81.512278 -308.555384) (xy 81.463103 -308.553403) (xy 81.414884 -308.543559) (xy 81.368868 -308.526107)
			(xy 81.326247 -308.5015) (xy 81.288126 -308.470375) (xy 81.255491 -308.433538) (xy 81.229188 -308.391942)
			(xy 81.209897 -308.346666) (xy 81.19812 -308.298882) (xy 81.19416 -308.249828) (xy 80.855058 -308.249828)
			(xy 80.854563 -308.274435) (xy 80.846668 -308.323012) (xy 80.831084 -308.369693) (xy 80.808213 -308.41327)
			(xy 80.778648 -308.452614) (xy 80.743155 -308.486706) (xy 80.702652 -308.514662) (xy 80.65819 -308.53576)
			(xy 80.610919 -308.549452) (xy 80.562064 -308.555384) (xy 80.512889 -308.553403) (xy 80.46467 -308.543559)
			(xy 80.418654 -308.526107) (xy 80.376033 -308.5015) (xy 80.337912 -308.470375) (xy 80.305277 -308.433538)
			(xy 80.278974 -308.391942) (xy 80.259683 -308.346666) (xy 80.247906 -308.298882) (xy 80.243946 -308.249828)
			(xy 79.905098 -308.249828) (xy 79.904603 -308.274435) (xy 79.896708 -308.323012) (xy 79.881124 -308.369693)
			(xy 79.858253 -308.41327) (xy 79.828688 -308.452614) (xy 79.793195 -308.486706) (xy 79.752692 -308.514662)
			(xy 79.70823 -308.53576) (xy 79.660959 -308.549452) (xy 79.612104 -308.555384) (xy 79.562929 -308.553403)
			(xy 79.51471 -308.543559) (xy 79.468694 -308.526107) (xy 79.426073 -308.5015) (xy 79.387952 -308.470375)
			(xy 79.355317 -308.433538) (xy 79.329014 -308.391942) (xy 79.309723 -308.346666) (xy 79.297946 -308.298882)
			(xy 79.293986 -308.249828) (xy 78.955138 -308.249828) (xy 78.954643 -308.274435) (xy 78.946748 -308.323012)
			(xy 78.931164 -308.369693) (xy 78.908293 -308.41327) (xy 78.878728 -308.452614) (xy 78.843235 -308.486706)
			(xy 78.802732 -308.514662) (xy 78.75827 -308.53576) (xy 78.710999 -308.549452) (xy 78.662144 -308.555384)
			(xy 78.612969 -308.553403) (xy 78.56475 -308.543559) (xy 78.518734 -308.526107) (xy 78.476113 -308.5015)
			(xy 78.437992 -308.470375) (xy 78.405357 -308.433538) (xy 78.379054 -308.391942) (xy 78.359763 -308.346666)
			(xy 78.347986 -308.298882) (xy 78.344026 -308.249828) (xy 78.005178 -308.249828) (xy 78.004683 -308.274435)
			(xy 77.996788 -308.323012) (xy 77.981204 -308.369693) (xy 77.958333 -308.41327) (xy 77.928768 -308.452614)
			(xy 77.893275 -308.486706) (xy 77.852772 -308.514662) (xy 77.80831 -308.53576) (xy 77.761039 -308.549452)
			(xy 77.712184 -308.555384) (xy 77.663009 -308.553403) (xy 77.61479 -308.543559) (xy 77.568774 -308.526107)
			(xy 77.526153 -308.5015) (xy 77.488032 -308.470375) (xy 77.455397 -308.433538) (xy 77.429094 -308.391942)
			(xy 77.409803 -308.346666) (xy 77.398026 -308.298882) (xy 77.394066 -308.249828) (xy 77.055218 -308.249828)
			(xy 77.054723 -308.274435) (xy 77.046828 -308.323012) (xy 77.031244 -308.369693) (xy 77.008373 -308.41327)
			(xy 76.978808 -308.452614) (xy 76.943315 -308.486706) (xy 76.902812 -308.514662) (xy 76.85835 -308.53576)
			(xy 76.811079 -308.549452) (xy 76.762224 -308.555384) (xy 76.713049 -308.553403) (xy 76.66483 -308.543559)
			(xy 76.618814 -308.526107) (xy 76.576193 -308.5015) (xy 76.538072 -308.470375) (xy 76.505437 -308.433538)
			(xy 76.479134 -308.391942) (xy 76.459843 -308.346666) (xy 76.448066 -308.298882) (xy 76.444106 -308.249828)
			(xy 76.105258 -308.249828) (xy 76.104763 -308.274435) (xy 76.096868 -308.323012) (xy 76.081284 -308.369693)
			(xy 76.058413 -308.41327) (xy 76.028848 -308.452614) (xy 75.993355 -308.486706) (xy 75.952852 -308.514662)
			(xy 75.90839 -308.53576) (xy 75.861119 -308.549452) (xy 75.812264 -308.555384) (xy 75.763089 -308.553403)
			(xy 75.71487 -308.543559) (xy 75.668854 -308.526107) (xy 75.626233 -308.5015) (xy 75.588112 -308.470375)
			(xy 75.555477 -308.433538) (xy 75.529174 -308.391942) (xy 75.509883 -308.346666) (xy 75.498106 -308.298882)
			(xy 75.494146 -308.249828) (xy 75.155298 -308.249828) (xy 75.154803 -308.274435) (xy 75.146908 -308.323012)
			(xy 75.131324 -308.369693) (xy 75.108453 -308.41327) (xy 75.078888 -308.452614) (xy 75.043395 -308.486706)
			(xy 75.002892 -308.514662) (xy 74.95843 -308.53576) (xy 74.911159 -308.549452) (xy 74.862304 -308.555384)
			(xy 74.813129 -308.553403) (xy 74.76491 -308.543559) (xy 74.718894 -308.526107) (xy 74.676273 -308.5015)
			(xy 74.638152 -308.470375) (xy 74.605517 -308.433538) (xy 74.579214 -308.391942) (xy 74.559923 -308.346666)
			(xy 74.548146 -308.298882) (xy 74.544186 -308.249828) (xy 74.205084 -308.249828) (xy 74.204589 -308.274435)
			(xy 74.196694 -308.323012) (xy 74.18111 -308.369693) (xy 74.158239 -308.41327) (xy 74.128674 -308.452614)
			(xy 74.093181 -308.486706) (xy 74.052678 -308.514662) (xy 74.008216 -308.53576) (xy 73.960945 -308.549452)
			(xy 73.91209 -308.555384) (xy 73.862915 -308.553403) (xy 73.814696 -308.543559) (xy 73.76868 -308.526107)
			(xy 73.726059 -308.5015) (xy 73.687938 -308.470375) (xy 73.655303 -308.433538) (xy 73.629 -308.391942)
			(xy 73.609709 -308.346666) (xy 73.597932 -308.298882) (xy 73.593972 -308.249828) (xy 53.305202 -308.249828)
			(xy 53.305029 -308.264011) (xy 53.302355 -308.292251) (xy 53.299868 -308.306216) (xy 53.297582 -308.318662)
			(xy 53.304948 -308.342284) (xy 53.382418 -308.419754) (xy 53.40604 -308.42712) (xy 53.418486 -308.424834)
			(xy 53.432453 -308.422364) (xy 53.460692 -308.419688) (xy 53.474874 -308.4195) (xy 53.500134 -308.419975)
			(xy 53.549965 -308.428286) (xy 53.597748 -308.444687) (xy 53.64218 -308.468729) (xy 53.682049 -308.499756)
			(xy 53.716266 -308.536923) (xy 53.743899 -308.579216) (xy 53.764193 -308.62548) (xy 53.776596 -308.674453)
			(xy 53.780768 -308.7248) (xy 53.780767 -308.724808) (xy 54.11903 -308.724808) (xy 54.12299 -308.675754)
			(xy 54.134767 -308.62797) (xy 54.154058 -308.582694) (xy 54.180361 -308.541098) (xy 54.212996 -308.504261)
			(xy 54.251117 -308.473136) (xy 54.293738 -308.448529) (xy 54.339754 -308.431077) (xy 54.387973 -308.421233)
			(xy 54.437148 -308.419252) (xy 54.486003 -308.425184) (xy 54.533274 -308.438876) (xy 54.577736 -308.459974)
			(xy 54.618239 -308.48793) (xy 54.653732 -308.522022) (xy 54.683297 -308.561366) (xy 54.706168 -308.604943)
			(xy 54.721752 -308.651624) (xy 54.729647 -308.700201) (xy 54.730142 -308.724808) (xy 54.729976 -308.733075)
			(xy 55.069087 -308.733075) (xy 55.071776 -308.683507) (xy 55.082448 -308.635027) (xy 55.100823 -308.588912)
			(xy 55.126416 -308.546378) (xy 55.158554 -308.508544) (xy 55.196389 -308.476408) (xy 55.238925 -308.450817)
			(xy 55.28504 -308.432444) (xy 55.333521 -308.421774) (xy 55.383089 -308.419087) (xy 55.432439 -308.424456)
			(xy 55.48027 -308.437737) (xy 55.525322 -308.458582) (xy 55.566408 -308.486441) (xy 55.602447 -308.52058)
			(xy 55.632487 -308.560099) (xy 55.655738 -308.603958) (xy 55.671587 -308.651001) (xy 55.679617 -308.699988)
			(xy 55.680102 -308.724808) (xy 55.679927 -308.738991) (xy 55.677254 -308.767231) (xy 55.674768 -308.781196)
			(xy 55.672482 -308.793642) (xy 55.679848 -308.817264) (xy 55.757318 -308.894734) (xy 55.78094 -308.9021)
			(xy 55.793386 -308.899814) (xy 55.807353 -308.897343) (xy 55.835592 -308.894668) (xy 55.849774 -308.89448)
			(xy 55.864021 -308.894637) (xy 55.892389 -308.897313) (xy 55.906416 -308.899814) (xy 55.918608 -308.9021)
			(xy 55.942738 -308.894734) (xy 56.019954 -308.817518) (xy 56.02732 -308.793642) (xy 56.025034 -308.781196)
			(xy 56.022561 -308.76723) (xy 56.019887 -308.73899) (xy 56.0197 -308.724808) (xy 56.020169 -308.699986)
			(xy 56.028199 -308.650997) (xy 56.044049 -308.603952) (xy 56.067301 -308.560092) (xy 56.097343 -308.52057)
			(xy 56.133383 -308.48643) (xy 56.174471 -308.45857) (xy 56.219525 -308.437724) (xy 56.267358 -308.424442)
			(xy 56.31671 -308.419073) (xy 56.36628 -308.42176) (xy 56.414763 -308.43243) (xy 56.460881 -308.450804)
			(xy 56.503418 -308.476396) (xy 56.541255 -308.508534) (xy 56.573394 -308.546369) (xy 56.598989 -308.588905)
			(xy 56.617365 -308.635022) (xy 56.628038 -308.683504) (xy 56.630279 -308.724808) (xy 57.919124 -308.724808)
			(xy 57.923084 -308.675754) (xy 57.934861 -308.62797) (xy 57.954152 -308.582694) (xy 57.980455 -308.541098)
			(xy 58.01309 -308.504261) (xy 58.051211 -308.473136) (xy 58.093832 -308.448529) (xy 58.139848 -308.431077)
			(xy 58.188067 -308.421233) (xy 58.237242 -308.419252) (xy 58.286097 -308.425184) (xy 58.333368 -308.438876)
			(xy 58.37783 -308.459974) (xy 58.418333 -308.48793) (xy 58.453826 -308.522022) (xy 58.483391 -308.561366)
			(xy 58.506262 -308.604943) (xy 58.521846 -308.651624) (xy 58.529741 -308.700201) (xy 58.530236 -308.724808)
			(xy 58.530069 -308.733113) (xy 59.819033 -308.733113) (xy 59.821717 -308.683534) (xy 59.832386 -308.635042)
			(xy 59.85076 -308.588916) (xy 59.876355 -308.546369) (xy 59.908496 -308.508525) (xy 59.946337 -308.476379)
			(xy 59.98888 -308.450778) (xy 60.035004 -308.432398) (xy 60.083494 -308.421722) (xy 60.133073 -308.419032)
			(xy 60.182433 -308.424399) (xy 60.230275 -308.437681) (xy 60.275338 -308.458528) (xy 60.316435 -308.486392)
			(xy 60.352481 -308.520537) (xy 60.382529 -308.560064) (xy 60.405786 -308.603932) (xy 60.421639 -308.650985)
			(xy 60.429671 -308.699982) (xy 60.430156 -308.724808) (xy 60.429981 -308.738991) (xy 60.427308 -308.767231)
			(xy 60.424822 -308.781196) (xy 60.422536 -308.793642) (xy 60.429902 -308.817264) (xy 60.507372 -308.894734)
			(xy 60.530994 -308.9021) (xy 60.54344 -308.899814) (xy 60.557406 -308.897336) (xy 60.585645 -308.894665)
			(xy 60.599828 -308.89448) (xy 60.614011 -308.894653) (xy 60.642251 -308.897328) (xy 60.656216 -308.899814)
			(xy 60.668662 -308.9021) (xy 60.692284 -308.894734) (xy 60.769754 -308.817264) (xy 60.77712 -308.793642)
			(xy 60.774834 -308.781196) (xy 60.772361 -308.76723) (xy 60.769687 -308.73899) (xy 60.7695 -308.724808)
			(xy 60.770022 -308.699553) (xy 60.778335 -308.649731) (xy 60.794736 -308.601957) (xy 60.818777 -308.557534)
			(xy 60.849801 -308.517674) (xy 60.886963 -308.483464) (xy 60.929249 -308.455838) (xy 60.975505 -308.435548)
			(xy 61.02447 -308.423148) (xy 61.074808 -308.418977) (xy 61.125146 -308.423148) (xy 61.174111 -308.435548)
			(xy 61.220367 -308.455838) (xy 61.262653 -308.483464) (xy 61.299815 -308.517674) (xy 61.330839 -308.557534)
			(xy 61.35488 -308.601957) (xy 61.371281 -308.649731) (xy 61.379594 -308.699553) (xy 61.380116 -308.724808)
			(xy 61.37994 -308.738991) (xy 61.377268 -308.767231) (xy 61.374782 -308.781196) (xy 61.372496 -308.793642)
			(xy 61.379862 -308.817264) (xy 61.457332 -308.894734) (xy 61.480954 -308.9021) (xy 61.4934 -308.899814)
			(xy 61.507367 -308.897342) (xy 61.535606 -308.894667) (xy 61.549788 -308.89448) (xy 61.563971 -308.894659)
			(xy 61.592211 -308.897329) (xy 61.606176 -308.899814) (xy 61.618622 -308.9021) (xy 61.642244 -308.894734)
			(xy 61.719714 -308.817264) (xy 61.72708 -308.793642) (xy 61.724794 -308.781196) (xy 61.722321 -308.76723)
			(xy 61.719647 -308.73899) (xy 61.71946 -308.724808) (xy 61.719969 -308.699986) (xy 61.728 -308.650995)
			(xy 61.743851 -308.603949) (xy 61.767104 -308.560088) (xy 61.797147 -308.520566) (xy 61.833188 -308.486425)
			(xy 61.874279 -308.458565) (xy 61.919335 -308.437721) (xy 61.96717 -308.42444) (xy 62.016523 -308.419073)
			(xy 62.066095 -308.421762) (xy 62.114578 -308.432435) (xy 62.160696 -308.450811) (xy 62.203233 -308.476407)
			(xy 62.241069 -308.508548) (xy 62.273207 -308.546386) (xy 62.298799 -308.588925) (xy 62.317172 -308.635045)
			(xy 62.327842 -308.683529) (xy 62.330063 -308.724554) (xy 62.668924 -308.724554) (xy 62.672884 -308.6755)
			(xy 62.684661 -308.627716) (xy 62.703952 -308.58244) (xy 62.730255 -308.540844) (xy 62.76289 -308.504007)
			(xy 62.801011 -308.472882) (xy 62.843632 -308.448275) (xy 62.889648 -308.430823) (xy 62.937867 -308.420979)
			(xy 62.987042 -308.418998) (xy 63.035897 -308.42493) (xy 63.083168 -308.438622) (xy 63.12763 -308.45972)
			(xy 63.168133 -308.487676) (xy 63.203626 -308.521768) (xy 63.233191 -308.561112) (xy 63.256062 -308.604689)
			(xy 63.271646 -308.65137) (xy 63.279541 -308.699947) (xy 63.280036 -308.724554) (xy 63.280031 -308.724808)
			(xy 63.619138 -308.724808) (xy 63.623098 -308.675754) (xy 63.634875 -308.62797) (xy 63.654166 -308.582694)
			(xy 63.680469 -308.541098) (xy 63.713104 -308.504261) (xy 63.751225 -308.473136) (xy 63.793846 -308.448529)
			(xy 63.839862 -308.431077) (xy 63.888081 -308.421233) (xy 63.937256 -308.419252) (xy 63.986111 -308.425184)
			(xy 64.033382 -308.438876) (xy 64.077844 -308.459974) (xy 64.118347 -308.48793) (xy 64.15384 -308.522022)
			(xy 64.183405 -308.561366) (xy 64.206276 -308.604943) (xy 64.22186 -308.651624) (xy 64.229755 -308.700201)
			(xy 64.23025 -308.724808) (xy 64.569098 -308.724808) (xy 64.573058 -308.675754) (xy 64.584835 -308.62797)
			(xy 64.604126 -308.582694) (xy 64.630429 -308.541098) (xy 64.663064 -308.504261) (xy 64.701185 -308.473136)
			(xy 64.743806 -308.448529) (xy 64.789822 -308.431077) (xy 64.838041 -308.421233) (xy 64.887216 -308.419252)
			(xy 64.936071 -308.425184) (xy 64.983342 -308.438876) (xy 65.027804 -308.459974) (xy 65.068307 -308.48793)
			(xy 65.1038 -308.522022) (xy 65.133365 -308.561366) (xy 65.156236 -308.604943) (xy 65.17182 -308.651624)
			(xy 65.179715 -308.700201) (xy 65.18021 -308.724808) (xy 65.519058 -308.724808) (xy 65.523018 -308.675754)
			(xy 65.534795 -308.62797) (xy 65.554086 -308.582694) (xy 65.580389 -308.541098) (xy 65.613024 -308.504261)
			(xy 65.651145 -308.473136) (xy 65.693766 -308.448529) (xy 65.739782 -308.431077) (xy 65.788001 -308.421233)
			(xy 65.837176 -308.419252) (xy 65.886031 -308.425184) (xy 65.933302 -308.438876) (xy 65.977764 -308.459974)
			(xy 66.018267 -308.48793) (xy 66.05376 -308.522022) (xy 66.083325 -308.561366) (xy 66.106196 -308.604943)
			(xy 66.12178 -308.651624) (xy 66.129675 -308.700201) (xy 66.13017 -308.724808) (xy 66.469018 -308.724808)
			(xy 66.472978 -308.675754) (xy 66.484755 -308.62797) (xy 66.504046 -308.582694) (xy 66.530349 -308.541098)
			(xy 66.562984 -308.504261) (xy 66.601105 -308.473136) (xy 66.643726 -308.448529) (xy 66.689742 -308.431077)
			(xy 66.737961 -308.421233) (xy 66.787136 -308.419252) (xy 66.835991 -308.425184) (xy 66.883262 -308.438876)
			(xy 66.927724 -308.459974) (xy 66.968227 -308.48793) (xy 67.00372 -308.522022) (xy 67.033285 -308.561366)
			(xy 67.056156 -308.604943) (xy 67.07174 -308.651624) (xy 67.079635 -308.700201) (xy 67.08013 -308.724808)
			(xy 67.418978 -308.724808) (xy 67.422938 -308.675754) (xy 67.434715 -308.62797) (xy 67.454006 -308.582694)
			(xy 67.480309 -308.541098) (xy 67.512944 -308.504261) (xy 67.551065 -308.473136) (xy 67.593686 -308.448529)
			(xy 67.639702 -308.431077) (xy 67.687921 -308.421233) (xy 67.737096 -308.419252) (xy 67.785951 -308.425184)
			(xy 67.833222 -308.438876) (xy 67.877684 -308.459974) (xy 67.918187 -308.48793) (xy 67.95368 -308.522022)
			(xy 67.983245 -308.561366) (xy 68.006116 -308.604943) (xy 68.0217 -308.651624) (xy 68.029595 -308.700201)
			(xy 68.03009 -308.724808) (xy 68.369192 -308.724808) (xy 68.373152 -308.675754) (xy 68.384929 -308.62797)
			(xy 68.40422 -308.582694) (xy 68.430523 -308.541098) (xy 68.463158 -308.504261) (xy 68.501279 -308.473136)
			(xy 68.5439 -308.448529) (xy 68.589916 -308.431077) (xy 68.638135 -308.421233) (xy 68.68731 -308.419252)
			(xy 68.736165 -308.425184) (xy 68.783436 -308.438876) (xy 68.827898 -308.459974) (xy 68.868401 -308.48793)
			(xy 68.903894 -308.522022) (xy 68.933459 -308.561366) (xy 68.95633 -308.604943) (xy 68.971914 -308.651624)
			(xy 68.979809 -308.700201) (xy 68.980304 -308.724808) (xy 69.319152 -308.724808) (xy 69.323112 -308.675754)
			(xy 69.334889 -308.62797) (xy 69.35418 -308.582694) (xy 69.380483 -308.541098) (xy 69.413118 -308.504261)
			(xy 69.451239 -308.473136) (xy 69.49386 -308.448529) (xy 69.539876 -308.431077) (xy 69.588095 -308.421233)
			(xy 69.63727 -308.419252) (xy 69.686125 -308.425184) (xy 69.733396 -308.438876) (xy 69.777858 -308.459974)
			(xy 69.818361 -308.48793) (xy 69.853854 -308.522022) (xy 69.883419 -308.561366) (xy 69.90629 -308.604943)
			(xy 69.921874 -308.651624) (xy 69.929769 -308.700201) (xy 69.930264 -308.724808) (xy 70.269112 -308.724808)
			(xy 70.273072 -308.675754) (xy 70.284849 -308.62797) (xy 70.30414 -308.582694) (xy 70.330443 -308.541098)
			(xy 70.363078 -308.504261) (xy 70.401199 -308.473136) (xy 70.44382 -308.448529) (xy 70.489836 -308.431077)
			(xy 70.538055 -308.421233) (xy 70.58723 -308.419252) (xy 70.636085 -308.425184) (xy 70.683356 -308.438876)
			(xy 70.727818 -308.459974) (xy 70.768321 -308.48793) (xy 70.803814 -308.522022) (xy 70.833379 -308.561366)
			(xy 70.85625 -308.604943) (xy 70.871834 -308.651624) (xy 70.879729 -308.700201) (xy 70.880224 -308.724808)
			(xy 71.219072 -308.724808) (xy 71.223032 -308.675754) (xy 71.234809 -308.62797) (xy 71.2541 -308.582694)
			(xy 71.280403 -308.541098) (xy 71.313038 -308.504261) (xy 71.351159 -308.473136) (xy 71.39378 -308.448529)
			(xy 71.439796 -308.431077) (xy 71.488015 -308.421233) (xy 71.53719 -308.419252) (xy 71.586045 -308.425184)
			(xy 71.633316 -308.438876) (xy 71.677778 -308.459974) (xy 71.718281 -308.48793) (xy 71.753774 -308.522022)
			(xy 71.783339 -308.561366) (xy 71.80621 -308.604943) (xy 71.821794 -308.651624) (xy 71.829689 -308.700201)
			(xy 71.830184 -308.724808) (xy 72.169032 -308.724808) (xy 72.172992 -308.675754) (xy 72.184769 -308.62797)
			(xy 72.20406 -308.582694) (xy 72.230363 -308.541098) (xy 72.262998 -308.504261) (xy 72.301119 -308.473136)
			(xy 72.34374 -308.448529) (xy 72.389756 -308.431077) (xy 72.437975 -308.421233) (xy 72.48715 -308.419252)
			(xy 72.536005 -308.425184) (xy 72.583276 -308.438876) (xy 72.627738 -308.459974) (xy 72.668241 -308.48793)
			(xy 72.703734 -308.522022) (xy 72.733299 -308.561366) (xy 72.75617 -308.604943) (xy 72.771754 -308.651624)
			(xy 72.779649 -308.700201) (xy 72.780144 -308.724808) (xy 72.779649 -308.749415) (xy 72.771754 -308.797992)
			(xy 72.75617 -308.844673) (xy 72.733299 -308.88825) (xy 72.703734 -308.927594) (xy 72.668241 -308.961686)
			(xy 72.627738 -308.989642) (xy 72.583276 -309.01074) (xy 72.536005 -309.024432) (xy 72.48715 -309.030364)
			(xy 72.437975 -309.028383) (xy 72.389756 -309.018539) (xy 72.34374 -309.001087) (xy 72.301119 -308.97648)
			(xy 72.262998 -308.945355) (xy 72.230363 -308.908518) (xy 72.20406 -308.866922) (xy 72.184769 -308.821646)
			(xy 72.172992 -308.773862) (xy 72.169032 -308.724808) (xy 71.830184 -308.724808) (xy 71.829689 -308.749415)
			(xy 71.821794 -308.797992) (xy 71.80621 -308.844673) (xy 71.783339 -308.88825) (xy 71.753774 -308.927594)
			(xy 71.718281 -308.961686) (xy 71.677778 -308.989642) (xy 71.633316 -309.01074) (xy 71.586045 -309.024432)
			(xy 71.53719 -309.030364) (xy 71.488015 -309.028383) (xy 71.439796 -309.018539) (xy 71.39378 -309.001087)
			(xy 71.351159 -308.97648) (xy 71.313038 -308.945355) (xy 71.280403 -308.908518) (xy 71.2541 -308.866922)
			(xy 71.234809 -308.821646) (xy 71.223032 -308.773862) (xy 71.219072 -308.724808) (xy 70.880224 -308.724808)
			(xy 70.879729 -308.749415) (xy 70.871834 -308.797992) (xy 70.85625 -308.844673) (xy 70.833379 -308.88825)
			(xy 70.803814 -308.927594) (xy 70.768321 -308.961686) (xy 70.727818 -308.989642) (xy 70.683356 -309.01074)
			(xy 70.636085 -309.024432) (xy 70.58723 -309.030364) (xy 70.538055 -309.028383) (xy 70.489836 -309.018539)
			(xy 70.44382 -309.001087) (xy 70.401199 -308.97648) (xy 70.363078 -308.945355) (xy 70.330443 -308.908518)
			(xy 70.30414 -308.866922) (xy 70.284849 -308.821646) (xy 70.273072 -308.773862) (xy 70.269112 -308.724808)
			(xy 69.930264 -308.724808) (xy 69.929769 -308.749415) (xy 69.921874 -308.797992) (xy 69.90629 -308.844673)
			(xy 69.883419 -308.88825) (xy 69.853854 -308.927594) (xy 69.818361 -308.961686) (xy 69.777858 -308.989642)
			(xy 69.733396 -309.01074) (xy 69.686125 -309.024432) (xy 69.63727 -309.030364) (xy 69.588095 -309.028383)
			(xy 69.539876 -309.018539) (xy 69.49386 -309.001087) (xy 69.451239 -308.97648) (xy 69.413118 -308.945355)
			(xy 69.380483 -308.908518) (xy 69.35418 -308.866922) (xy 69.334889 -308.821646) (xy 69.323112 -308.773862)
			(xy 69.319152 -308.724808) (xy 68.980304 -308.724808) (xy 68.979809 -308.749415) (xy 68.971914 -308.797992)
			(xy 68.95633 -308.844673) (xy 68.933459 -308.88825) (xy 68.903894 -308.927594) (xy 68.868401 -308.961686)
			(xy 68.827898 -308.989642) (xy 68.783436 -309.01074) (xy 68.736165 -309.024432) (xy 68.68731 -309.030364)
			(xy 68.638135 -309.028383) (xy 68.589916 -309.018539) (xy 68.5439 -309.001087) (xy 68.501279 -308.97648)
			(xy 68.463158 -308.945355) (xy 68.430523 -308.908518) (xy 68.40422 -308.866922) (xy 68.384929 -308.821646)
			(xy 68.373152 -308.773862) (xy 68.369192 -308.724808) (xy 68.03009 -308.724808) (xy 68.029595 -308.749415)
			(xy 68.0217 -308.797992) (xy 68.006116 -308.844673) (xy 67.983245 -308.88825) (xy 67.95368 -308.927594)
			(xy 67.918187 -308.961686) (xy 67.877684 -308.989642) (xy 67.833222 -309.01074) (xy 67.785951 -309.024432)
			(xy 67.737096 -309.030364) (xy 67.687921 -309.028383) (xy 67.639702 -309.018539) (xy 67.593686 -309.001087)
			(xy 67.551065 -308.97648) (xy 67.512944 -308.945355) (xy 67.480309 -308.908518) (xy 67.454006 -308.866922)
			(xy 67.434715 -308.821646) (xy 67.422938 -308.773862) (xy 67.418978 -308.724808) (xy 67.08013 -308.724808)
			(xy 67.079635 -308.749415) (xy 67.07174 -308.797992) (xy 67.056156 -308.844673) (xy 67.033285 -308.88825)
			(xy 67.00372 -308.927594) (xy 66.968227 -308.961686) (xy 66.927724 -308.989642) (xy 66.883262 -309.01074)
			(xy 66.835991 -309.024432) (xy 66.787136 -309.030364) (xy 66.737961 -309.028383) (xy 66.689742 -309.018539)
			(xy 66.643726 -309.001087) (xy 66.601105 -308.97648) (xy 66.562984 -308.945355) (xy 66.530349 -308.908518)
			(xy 66.504046 -308.866922) (xy 66.484755 -308.821646) (xy 66.472978 -308.773862) (xy 66.469018 -308.724808)
			(xy 66.13017 -308.724808) (xy 66.129675 -308.749415) (xy 66.12178 -308.797992) (xy 66.106196 -308.844673)
			(xy 66.083325 -308.88825) (xy 66.05376 -308.927594) (xy 66.018267 -308.961686) (xy 65.977764 -308.989642)
			(xy 65.933302 -309.01074) (xy 65.886031 -309.024432) (xy 65.837176 -309.030364) (xy 65.788001 -309.028383)
			(xy 65.739782 -309.018539) (xy 65.693766 -309.001087) (xy 65.651145 -308.97648) (xy 65.613024 -308.945355)
			(xy 65.580389 -308.908518) (xy 65.554086 -308.866922) (xy 65.534795 -308.821646) (xy 65.523018 -308.773862)
			(xy 65.519058 -308.724808) (xy 65.18021 -308.724808) (xy 65.179715 -308.749415) (xy 65.17182 -308.797992)
			(xy 65.156236 -308.844673) (xy 65.133365 -308.88825) (xy 65.1038 -308.927594) (xy 65.068307 -308.961686)
			(xy 65.027804 -308.989642) (xy 64.983342 -309.01074) (xy 64.936071 -309.024432) (xy 64.887216 -309.030364)
			(xy 64.838041 -309.028383) (xy 64.789822 -309.018539) (xy 64.743806 -309.001087) (xy 64.701185 -308.97648)
			(xy 64.663064 -308.945355) (xy 64.630429 -308.908518) (xy 64.604126 -308.866922) (xy 64.584835 -308.821646)
			(xy 64.573058 -308.773862) (xy 64.569098 -308.724808) (xy 64.23025 -308.724808) (xy 64.229755 -308.749415)
			(xy 64.22186 -308.797992) (xy 64.206276 -308.844673) (xy 64.183405 -308.88825) (xy 64.15384 -308.927594)
			(xy 64.118347 -308.961686) (xy 64.077844 -308.989642) (xy 64.033382 -309.01074) (xy 63.986111 -309.024432)
			(xy 63.937256 -309.030364) (xy 63.888081 -309.028383) (xy 63.839862 -309.018539) (xy 63.793846 -309.001087)
			(xy 63.751225 -308.97648) (xy 63.713104 -308.945355) (xy 63.680469 -308.908518) (xy 63.654166 -308.866922)
			(xy 63.634875 -308.821646) (xy 63.623098 -308.773862) (xy 63.619138 -308.724808) (xy 63.280031 -308.724808)
			(xy 63.279541 -308.749161) (xy 63.271646 -308.797738) (xy 63.256062 -308.844419) (xy 63.233191 -308.887996)
			(xy 63.203626 -308.92734) (xy 63.168133 -308.961432) (xy 63.12763 -308.989388) (xy 63.083168 -309.010486)
			(xy 63.035897 -309.024178) (xy 62.987042 -309.03011) (xy 62.937867 -309.028129) (xy 62.889648 -309.018285)
			(xy 62.843632 -309.000833) (xy 62.801011 -308.976226) (xy 62.76289 -308.945101) (xy 62.730255 -308.908264)
			(xy 62.703952 -308.866668) (xy 62.684661 -308.821392) (xy 62.672884 -308.773608) (xy 62.668924 -308.724554)
			(xy 62.330063 -308.724554) (xy 62.330526 -308.733101) (xy 62.325156 -308.782454) (xy 62.311871 -308.830288)
			(xy 62.291023 -308.875342) (xy 62.26316 -308.91643) (xy 62.229016 -308.952469) (xy 62.189492 -308.982509)
			(xy 62.145629 -309.005759) (xy 62.098581 -309.021606) (xy 62.04959 -309.029633) (xy 62.024768 -309.030116)
			(xy 62.010585 -309.029944) (xy 61.982345 -309.027269) (xy 61.96838 -309.024782) (xy 61.955934 -309.022496)
			(xy 61.932312 -309.029862) (xy 61.854842 -309.107332) (xy 61.847476 -309.130954) (xy 61.849762 -309.1434)
			(xy 61.852234 -309.157367) (xy 61.854909 -309.185606) (xy 61.855096 -309.199788) (xy 73.593972 -309.199788)
			(xy 73.597932 -309.150734) (xy 73.609709 -309.10295) (xy 73.629 -309.057674) (xy 73.655303 -309.016078)
			(xy 73.687938 -308.979241) (xy 73.726059 -308.948116) (xy 73.76868 -308.923509) (xy 73.814696 -308.906057)
			(xy 73.862915 -308.896213) (xy 73.91209 -308.894232) (xy 73.960945 -308.900164) (xy 74.008216 -308.913856)
			(xy 74.052678 -308.934954) (xy 74.093181 -308.96291) (xy 74.128674 -308.997002) (xy 74.158239 -309.036346)
			(xy 74.18111 -309.079923) (xy 74.196694 -309.126604) (xy 74.204589 -309.175181) (xy 74.205084 -309.199788)
			(xy 74.544186 -309.199788) (xy 74.548146 -309.150734) (xy 74.559923 -309.10295) (xy 74.579214 -309.057674)
			(xy 74.605517 -309.016078) (xy 74.638152 -308.979241) (xy 74.676273 -308.948116) (xy 74.718894 -308.923509)
			(xy 74.76491 -308.906057) (xy 74.813129 -308.896213) (xy 74.862304 -308.894232) (xy 74.911159 -308.900164)
			(xy 74.95843 -308.913856) (xy 75.002892 -308.934954) (xy 75.043395 -308.96291) (xy 75.078888 -308.997002)
			(xy 75.108453 -309.036346) (xy 75.131324 -309.079923) (xy 75.146908 -309.126604) (xy 75.154803 -309.175181)
			(xy 75.155298 -309.199788) (xy 75.494146 -309.199788) (xy 75.498106 -309.150734) (xy 75.509883 -309.10295)
			(xy 75.529174 -309.057674) (xy 75.555477 -309.016078) (xy 75.588112 -308.979241) (xy 75.626233 -308.948116)
			(xy 75.668854 -308.923509) (xy 75.71487 -308.906057) (xy 75.763089 -308.896213) (xy 75.812264 -308.894232)
			(xy 75.861119 -308.900164) (xy 75.90839 -308.913856) (xy 75.952852 -308.934954) (xy 75.993355 -308.96291)
			(xy 76.028848 -308.997002) (xy 76.058413 -309.036346) (xy 76.081284 -309.079923) (xy 76.096868 -309.126604)
			(xy 76.104763 -309.175181) (xy 76.105258 -309.199788) (xy 76.444106 -309.199788) (xy 76.448066 -309.150734)
			(xy 76.459843 -309.10295) (xy 76.479134 -309.057674) (xy 76.505437 -309.016078) (xy 76.538072 -308.979241)
			(xy 76.576193 -308.948116) (xy 76.618814 -308.923509) (xy 76.66483 -308.906057) (xy 76.713049 -308.896213)
			(xy 76.762224 -308.894232) (xy 76.811079 -308.900164) (xy 76.85835 -308.913856) (xy 76.902812 -308.934954)
			(xy 76.943315 -308.96291) (xy 76.978808 -308.997002) (xy 77.008373 -309.036346) (xy 77.031244 -309.079923)
			(xy 77.046828 -309.126604) (xy 77.054723 -309.175181) (xy 77.055218 -309.199788) (xy 77.394066 -309.199788)
			(xy 77.398026 -309.150734) (xy 77.409803 -309.10295) (xy 77.429094 -309.057674) (xy 77.455397 -309.016078)
			(xy 77.488032 -308.979241) (xy 77.526153 -308.948116) (xy 77.568774 -308.923509) (xy 77.61479 -308.906057)
			(xy 77.663009 -308.896213) (xy 77.712184 -308.894232) (xy 77.761039 -308.900164) (xy 77.80831 -308.913856)
			(xy 77.852772 -308.934954) (xy 77.893275 -308.96291) (xy 77.928768 -308.997002) (xy 77.958333 -309.036346)
			(xy 77.981204 -309.079923) (xy 77.996788 -309.126604) (xy 78.004683 -309.175181) (xy 78.005178 -309.199788)
			(xy 78.344026 -309.199788) (xy 78.347986 -309.150734) (xy 78.359763 -309.10295) (xy 78.379054 -309.057674)
			(xy 78.405357 -309.016078) (xy 78.437992 -308.979241) (xy 78.476113 -308.948116) (xy 78.518734 -308.923509)
			(xy 78.56475 -308.906057) (xy 78.612969 -308.896213) (xy 78.662144 -308.894232) (xy 78.710999 -308.900164)
			(xy 78.75827 -308.913856) (xy 78.802732 -308.934954) (xy 78.843235 -308.96291) (xy 78.878728 -308.997002)
			(xy 78.908293 -309.036346) (xy 78.931164 -309.079923) (xy 78.946748 -309.126604) (xy 78.954643 -309.175181)
			(xy 78.955138 -309.199788) (xy 79.293986 -309.199788) (xy 79.297946 -309.150734) (xy 79.309723 -309.10295)
			(xy 79.329014 -309.057674) (xy 79.355317 -309.016078) (xy 79.387952 -308.979241) (xy 79.426073 -308.948116)
			(xy 79.468694 -308.923509) (xy 79.51471 -308.906057) (xy 79.562929 -308.896213) (xy 79.612104 -308.894232)
			(xy 79.660959 -308.900164) (xy 79.70823 -308.913856) (xy 79.752692 -308.934954) (xy 79.793195 -308.96291)
			(xy 79.828688 -308.997002) (xy 79.858253 -309.036346) (xy 79.881124 -309.079923) (xy 79.896708 -309.126604)
			(xy 79.904603 -309.175181) (xy 79.905098 -309.199788) (xy 80.243946 -309.199788) (xy 80.247906 -309.150734)
			(xy 80.259683 -309.10295) (xy 80.278974 -309.057674) (xy 80.305277 -309.016078) (xy 80.337912 -308.979241)
			(xy 80.376033 -308.948116) (xy 80.418654 -308.923509) (xy 80.46467 -308.906057) (xy 80.512889 -308.896213)
			(xy 80.562064 -308.894232) (xy 80.610919 -308.900164) (xy 80.65819 -308.913856) (xy 80.702652 -308.934954)
			(xy 80.743155 -308.96291) (xy 80.778648 -308.997002) (xy 80.808213 -309.036346) (xy 80.831084 -309.079923)
			(xy 80.846668 -309.126604) (xy 80.854563 -309.175181) (xy 80.855058 -309.199788) (xy 81.19416 -309.199788)
			(xy 81.19812 -309.150734) (xy 81.209897 -309.10295) (xy 81.229188 -309.057674) (xy 81.255491 -309.016078)
			(xy 81.288126 -308.979241) (xy 81.326247 -308.948116) (xy 81.368868 -308.923509) (xy 81.414884 -308.906057)
			(xy 81.463103 -308.896213) (xy 81.512278 -308.894232) (xy 81.561133 -308.900164) (xy 81.608404 -308.913856)
			(xy 81.652866 -308.934954) (xy 81.693369 -308.96291) (xy 81.728862 -308.997002) (xy 81.758427 -309.036346)
			(xy 81.781298 -309.079923) (xy 81.796882 -309.126604) (xy 81.804777 -309.175181) (xy 81.805272 -309.199788)
			(xy 82.14412 -309.199788) (xy 82.14808 -309.150734) (xy 82.159857 -309.10295) (xy 82.179148 -309.057674)
			(xy 82.205451 -309.016078) (xy 82.238086 -308.979241) (xy 82.276207 -308.948116) (xy 82.318828 -308.923509)
			(xy 82.364844 -308.906057) (xy 82.413063 -308.896213) (xy 82.462238 -308.894232) (xy 82.511093 -308.900164)
			(xy 82.558364 -308.913856) (xy 82.602826 -308.934954) (xy 82.643329 -308.96291) (xy 82.678822 -308.997002)
			(xy 82.708387 -309.036346) (xy 82.731258 -309.079923) (xy 82.746842 -309.126604) (xy 82.754737 -309.175181)
			(xy 82.754752 -309.175912) (xy 88.334086 -309.175912) (xy 88.338157 -309.12029) (xy 88.350283 -309.065853)
			(xy 88.370206 -309.013762) (xy 88.397502 -308.965127) (xy 88.431588 -308.920984) (xy 88.471737 -308.882275)
			(xy 88.517095 -308.849824) (xy 88.566695 -308.824323) (xy 88.619479 -308.806316) (xy 88.674322 -308.796186)
			(xy 88.730056 -308.794149) (xy 88.785493 -308.800249) (xy 88.83945 -308.814355) (xy 88.890779 -308.836167)
			(xy 88.938385 -308.865221) (xy 88.981253 -308.900896) (xy 89.01847 -308.942433) (xy 89.049243 -308.988946)
			(xy 89.072915 -309.039443) (xy 89.088983 -309.09285) (xy 89.097103 -309.148026) (xy 89.097612 -309.175912)
			(xy 89.097103 -309.203798) (xy 89.088983 -309.258974) (xy 89.072915 -309.312381) (xy 89.049243 -309.362878)
			(xy 89.01847 -309.409391) (xy 88.981253 -309.450928) (xy 88.938385 -309.486603) (xy 88.890779 -309.515657)
			(xy 88.83945 -309.537469) (xy 88.785493 -309.551575) (xy 88.730056 -309.557675) (xy 88.674322 -309.555638)
			(xy 88.619479 -309.545508) (xy 88.566695 -309.527501) (xy 88.517095 -309.502) (xy 88.471737 -309.469549)
			(xy 88.431588 -309.43084) (xy 88.397502 -309.386697) (xy 88.370206 -309.338062) (xy 88.350283 -309.285971)
			(xy 88.338157 -309.231534) (xy 88.334086 -309.175912) (xy 82.754752 -309.175912) (xy 82.755232 -309.199788)
			(xy 82.754737 -309.224395) (xy 82.746842 -309.272972) (xy 82.731258 -309.319653) (xy 82.708387 -309.36323)
			(xy 82.678822 -309.402574) (xy 82.643329 -309.436666) (xy 82.602826 -309.464622) (xy 82.558364 -309.48572)
			(xy 82.511093 -309.499412) (xy 82.462238 -309.505344) (xy 82.413063 -309.503363) (xy 82.364844 -309.493519)
			(xy 82.318828 -309.476067) (xy 82.276207 -309.45146) (xy 82.238086 -309.420335) (xy 82.205451 -309.383498)
			(xy 82.179148 -309.341902) (xy 82.159857 -309.296626) (xy 82.14808 -309.248842) (xy 82.14412 -309.199788)
			(xy 81.805272 -309.199788) (xy 81.804777 -309.224395) (xy 81.796882 -309.272972) (xy 81.781298 -309.319653)
			(xy 81.758427 -309.36323) (xy 81.728862 -309.402574) (xy 81.693369 -309.436666) (xy 81.652866 -309.464622)
			(xy 81.608404 -309.48572) (xy 81.561133 -309.499412) (xy 81.512278 -309.505344) (xy 81.463103 -309.503363)
			(xy 81.414884 -309.493519) (xy 81.368868 -309.476067) (xy 81.326247 -309.45146) (xy 81.288126 -309.420335)
			(xy 81.255491 -309.383498) (xy 81.229188 -309.341902) (xy 81.209897 -309.296626) (xy 81.19812 -309.248842)
			(xy 81.19416 -309.199788) (xy 80.855058 -309.199788) (xy 80.854563 -309.224395) (xy 80.846668 -309.272972)
			(xy 80.831084 -309.319653) (xy 80.808213 -309.36323) (xy 80.778648 -309.402574) (xy 80.743155 -309.436666)
			(xy 80.702652 -309.464622) (xy 80.65819 -309.48572) (xy 80.610919 -309.499412) (xy 80.562064 -309.505344)
			(xy 80.512889 -309.503363) (xy 80.46467 -309.493519) (xy 80.418654 -309.476067) (xy 80.376033 -309.45146)
			(xy 80.337912 -309.420335) (xy 80.305277 -309.383498) (xy 80.278974 -309.341902) (xy 80.259683 -309.296626)
			(xy 80.247906 -309.248842) (xy 80.243946 -309.199788) (xy 79.905098 -309.199788) (xy 79.904603 -309.224395)
			(xy 79.896708 -309.272972) (xy 79.881124 -309.319653) (xy 79.858253 -309.36323) (xy 79.828688 -309.402574)
			(xy 79.793195 -309.436666) (xy 79.752692 -309.464622) (xy 79.70823 -309.48572) (xy 79.660959 -309.499412)
			(xy 79.612104 -309.505344) (xy 79.562929 -309.503363) (xy 79.51471 -309.493519) (xy 79.468694 -309.476067)
			(xy 79.426073 -309.45146) (xy 79.387952 -309.420335) (xy 79.355317 -309.383498) (xy 79.329014 -309.341902)
			(xy 79.309723 -309.296626) (xy 79.297946 -309.248842) (xy 79.293986 -309.199788) (xy 78.955138 -309.199788)
			(xy 78.954643 -309.224395) (xy 78.946748 -309.272972) (xy 78.931164 -309.319653) (xy 78.908293 -309.36323)
			(xy 78.878728 -309.402574) (xy 78.843235 -309.436666) (xy 78.802732 -309.464622) (xy 78.75827 -309.48572)
			(xy 78.710999 -309.499412) (xy 78.662144 -309.505344) (xy 78.612969 -309.503363) (xy 78.56475 -309.493519)
			(xy 78.518734 -309.476067) (xy 78.476113 -309.45146) (xy 78.437992 -309.420335) (xy 78.405357 -309.383498)
			(xy 78.379054 -309.341902) (xy 78.359763 -309.296626) (xy 78.347986 -309.248842) (xy 78.344026 -309.199788)
			(xy 78.005178 -309.199788) (xy 78.004683 -309.224395) (xy 77.996788 -309.272972) (xy 77.981204 -309.319653)
			(xy 77.958333 -309.36323) (xy 77.928768 -309.402574) (xy 77.893275 -309.436666) (xy 77.852772 -309.464622)
			(xy 77.80831 -309.48572) (xy 77.761039 -309.499412) (xy 77.712184 -309.505344) (xy 77.663009 -309.503363)
			(xy 77.61479 -309.493519) (xy 77.568774 -309.476067) (xy 77.526153 -309.45146) (xy 77.488032 -309.420335)
			(xy 77.455397 -309.383498) (xy 77.429094 -309.341902) (xy 77.409803 -309.296626) (xy 77.398026 -309.248842)
			(xy 77.394066 -309.199788) (xy 77.055218 -309.199788) (xy 77.054723 -309.224395) (xy 77.046828 -309.272972)
			(xy 77.031244 -309.319653) (xy 77.008373 -309.36323) (xy 76.978808 -309.402574) (xy 76.943315 -309.436666)
			(xy 76.902812 -309.464622) (xy 76.85835 -309.48572) (xy 76.811079 -309.499412) (xy 76.762224 -309.505344)
			(xy 76.713049 -309.503363) (xy 76.66483 -309.493519) (xy 76.618814 -309.476067) (xy 76.576193 -309.45146)
			(xy 76.538072 -309.420335) (xy 76.505437 -309.383498) (xy 76.479134 -309.341902) (xy 76.459843 -309.296626)
			(xy 76.448066 -309.248842) (xy 76.444106 -309.199788) (xy 76.105258 -309.199788) (xy 76.104763 -309.224395)
			(xy 76.096868 -309.272972) (xy 76.081284 -309.319653) (xy 76.058413 -309.36323) (xy 76.028848 -309.402574)
			(xy 75.993355 -309.436666) (xy 75.952852 -309.464622) (xy 75.90839 -309.48572) (xy 75.861119 -309.499412)
			(xy 75.812264 -309.505344) (xy 75.763089 -309.503363) (xy 75.71487 -309.493519) (xy 75.668854 -309.476067)
			(xy 75.626233 -309.45146) (xy 75.588112 -309.420335) (xy 75.555477 -309.383498) (xy 75.529174 -309.341902)
			(xy 75.509883 -309.296626) (xy 75.498106 -309.248842) (xy 75.494146 -309.199788) (xy 75.155298 -309.199788)
			(xy 75.154803 -309.224395) (xy 75.146908 -309.272972) (xy 75.131324 -309.319653) (xy 75.108453 -309.36323)
			(xy 75.078888 -309.402574) (xy 75.043395 -309.436666) (xy 75.002892 -309.464622) (xy 74.95843 -309.48572)
			(xy 74.911159 -309.499412) (xy 74.862304 -309.505344) (xy 74.813129 -309.503363) (xy 74.76491 -309.493519)
			(xy 74.718894 -309.476067) (xy 74.676273 -309.45146) (xy 74.638152 -309.420335) (xy 74.605517 -309.383498)
			(xy 74.579214 -309.341902) (xy 74.559923 -309.296626) (xy 74.548146 -309.248842) (xy 74.544186 -309.199788)
			(xy 74.205084 -309.199788) (xy 74.204589 -309.224395) (xy 74.196694 -309.272972) (xy 74.18111 -309.319653)
			(xy 74.158239 -309.36323) (xy 74.128674 -309.402574) (xy 74.093181 -309.436666) (xy 74.052678 -309.464622)
			(xy 74.008216 -309.48572) (xy 73.960945 -309.499412) (xy 73.91209 -309.505344) (xy 73.862915 -309.503363)
			(xy 73.814696 -309.493519) (xy 73.76868 -309.476067) (xy 73.726059 -309.45146) (xy 73.687938 -309.420335)
			(xy 73.655303 -309.383498) (xy 73.629 -309.341902) (xy 73.609709 -309.296626) (xy 73.597932 -309.248842)
			(xy 73.593972 -309.199788) (xy 61.855096 -309.199788) (xy 61.854574 -309.225043) (xy 61.846261 -309.274865)
			(xy 61.82986 -309.322639) (xy 61.805819 -309.367062) (xy 61.774795 -309.406922) (xy 61.737633 -309.441132)
			(xy 61.695347 -309.468758) (xy 61.649091 -309.489048) (xy 61.600126 -309.501448) (xy 61.549788 -309.505619)
			(xy 61.49945 -309.501448) (xy 61.450485 -309.489048) (xy 61.404229 -309.468758) (xy 61.361943 -309.441132)
			(xy 61.324781 -309.406922) (xy 61.293757 -309.367062) (xy 61.269716 -309.322639) (xy 61.253315 -309.274865)
			(xy 61.245002 -309.225043) (xy 61.24448 -309.199788) (xy 61.244655 -309.185605) (xy 61.247328 -309.157365)
			(xy 61.249814 -309.1434) (xy 61.2521 -309.130954) (xy 61.244734 -309.107332) (xy 61.167264 -309.029862)
			(xy 61.143642 -309.022496) (xy 61.131196 -309.024782) (xy 61.11723 -309.027255) (xy 61.08899 -309.029929)
			(xy 61.074808 -309.030116) (xy 61.060625 -309.029938) (xy 61.032385 -309.027267) (xy 61.01842 -309.024782)
			(xy 61.005974 -309.022496) (xy 60.982352 -309.029862) (xy 60.904882 -309.107332) (xy 60.897516 -309.130954)
			(xy 60.899802 -309.1434) (xy 60.902275 -309.157367) (xy 60.904949 -309.185606) (xy 60.905136 -309.199788)
			(xy 60.904614 -309.225043) (xy 60.896301 -309.274865) (xy 60.8799 -309.322639) (xy 60.855859 -309.367062)
			(xy 60.824835 -309.406922) (xy 60.787673 -309.441132) (xy 60.745387 -309.468758) (xy 60.699131 -309.489048)
			(xy 60.650166 -309.501448) (xy 60.599828 -309.505619) (xy 60.54949 -309.501448) (xy 60.500525 -309.489048)
			(xy 60.454269 -309.468758) (xy 60.411983 -309.441132) (xy 60.374821 -309.406922) (xy 60.343797 -309.367062)
			(xy 60.319756 -309.322639) (xy 60.303355 -309.274865) (xy 60.295042 -309.225043) (xy 60.29452 -309.199788)
			(xy 60.294695 -309.185605) (xy 60.297368 -309.157365) (xy 60.299854 -309.1434) (xy 60.30214 -309.130954)
			(xy 60.294774 -309.107332) (xy 60.217304 -309.029862) (xy 60.193682 -309.022496) (xy 60.181236 -309.024782)
			(xy 60.167271 -309.027263) (xy 60.139031 -309.029932) (xy 60.124848 -309.030116) (xy 60.100022 -309.029674)
			(xy 60.051024 -309.021649) (xy 60.003969 -309.005802) (xy 59.960098 -308.982551) (xy 59.920567 -308.952508)
			(xy 59.886417 -308.916466) (xy 59.858548 -308.875373) (xy 59.837695 -308.830313) (xy 59.824407 -308.782473)
			(xy 59.819033 -308.733113) (xy 58.530069 -308.733113) (xy 58.529741 -308.749415) (xy 58.521846 -308.797992)
			(xy 58.506262 -308.844673) (xy 58.483391 -308.88825) (xy 58.453826 -308.927594) (xy 58.418333 -308.961686)
			(xy 58.37783 -308.989642) (xy 58.333368 -309.01074) (xy 58.286097 -309.024432) (xy 58.237242 -309.030364)
			(xy 58.188067 -309.028383) (xy 58.139848 -309.018539) (xy 58.093832 -309.001087) (xy 58.051211 -308.97648)
			(xy 58.01309 -308.945355) (xy 57.980455 -308.908518) (xy 57.954152 -308.866922) (xy 57.934861 -308.821646)
			(xy 57.923084 -308.773862) (xy 57.919124 -308.724808) (xy 56.630279 -308.724808) (xy 56.630727 -308.733074)
			(xy 56.625361 -308.782426) (xy 56.612081 -308.83026) (xy 56.591238 -308.875315) (xy 56.56338 -308.916405)
			(xy 56.529242 -308.952446) (xy 56.489722 -308.98249) (xy 56.445862 -309.005744) (xy 56.398818 -309.021597)
			(xy 56.349829 -309.029629) (xy 56.325008 -309.030116) (xy 56.310762 -309.029941) (xy 56.282394 -309.027274)
			(xy 56.268366 -309.024782) (xy 56.256174 -309.022496) (xy 56.232044 -309.029862) (xy 56.154828 -309.107078)
			(xy 56.147462 -309.130954) (xy 56.149748 -309.1434) (xy 56.15222 -309.157367) (xy 56.154895 -309.185606)
			(xy 56.155082 -309.199788) (xy 56.15456 -309.225043) (xy 56.146247 -309.274865) (xy 56.129846 -309.322639)
			(xy 56.105805 -309.367062) (xy 56.074781 -309.406922) (xy 56.037619 -309.441132) (xy 55.995333 -309.468758)
			(xy 55.949077 -309.489048) (xy 55.900112 -309.501448) (xy 55.849774 -309.505619) (xy 55.799436 -309.501448)
			(xy 55.750471 -309.489048) (xy 55.704215 -309.468758) (xy 55.661929 -309.441132) (xy 55.624767 -309.406922)
			(xy 55.593743 -309.367062) (xy 55.569702 -309.322639) (xy 55.553301 -309.274865) (xy 55.544988 -309.225043)
			(xy 55.544466 -309.199788) (xy 55.544641 -309.185605) (xy 55.547314 -309.157365) (xy 55.5498 -309.1434)
			(xy 55.552086 -309.130954) (xy 55.54472 -309.107332) (xy 55.46725 -309.029862) (xy 55.443628 -309.022496)
			(xy 55.431182 -309.024782) (xy 55.417216 -309.027257) (xy 55.388976 -309.02993) (xy 55.374794 -309.030116)
			(xy 55.349974 -309.029616) (xy 55.300987 -309.021584) (xy 55.253945 -309.005732) (xy 55.210087 -308.982479)
			(xy 55.170569 -308.952437) (xy 55.136432 -308.916397) (xy 55.108575 -308.87531) (xy 55.087732 -308.830256)
			(xy 55.074453 -308.782425) (xy 55.069087 -308.733075) (xy 54.729976 -308.733075) (xy 54.729647 -308.749415)
			(xy 54.721752 -308.797992) (xy 54.706168 -308.844673) (xy 54.683297 -308.88825) (xy 54.653732 -308.927594)
			(xy 54.618239 -308.961686) (xy 54.577736 -308.989642) (xy 54.533274 -309.01074) (xy 54.486003 -309.024432)
			(xy 54.437148 -309.030364) (xy 54.387973 -309.028383) (xy 54.339754 -309.018539) (xy 54.293738 -309.001087)
			(xy 54.251117 -308.97648) (xy 54.212996 -308.945355) (xy 54.180361 -308.908518) (xy 54.154058 -308.866922)
			(xy 54.134767 -308.821646) (xy 54.12299 -308.773862) (xy 54.11903 -308.724808) (xy 53.780767 -308.724808)
			(xy 53.776596 -308.775147) (xy 53.764193 -308.82412) (xy 53.743899 -308.870384) (xy 53.716266 -308.912677)
			(xy 53.682049 -308.949844) (xy 53.64218 -308.980871) (xy 53.597748 -309.004913) (xy 53.549965 -309.021314)
			(xy 53.500134 -309.029625) (xy 53.474874 -309.030116) (xy 53.460691 -309.029943) (xy 53.432451 -309.027268)
			(xy 53.418486 -309.024782) (xy 53.40604 -309.022496) (xy 53.382418 -309.029862) (xy 53.304948 -309.107332)
			(xy 53.297582 -309.130954) (xy 53.299868 -309.1434) (xy 53.30234 -309.157367) (xy 53.305015 -309.185606)
			(xy 53.305202 -309.199788) (xy 53.304735 -309.22461) (xy 53.296705 -309.2736) (xy 53.280856 -309.320646)
			(xy 53.257604 -309.364508) (xy 53.227562 -309.40403) (xy 53.191522 -309.438171) (xy 53.150433 -309.466032)
			(xy 53.105379 -309.486879) (xy 53.057545 -309.500161) (xy 53.008192 -309.505531) (xy 52.958621 -309.502845)
			(xy 52.910137 -309.492174) (xy 52.864019 -309.4738) (xy 52.82148 -309.448208) (xy 52.783643 -309.41607)
			(xy 52.751503 -309.378234) (xy 52.725908 -309.335697) (xy 52.707531 -309.28958) (xy 52.696858 -309.241097)
			(xy 52.694169 -309.191526) (xy 52.699535 -309.142173) (xy 52.712815 -309.094338) (xy 52.733659 -309.049282)
			(xy 52.761517 -309.008192) (xy 52.795657 -308.97215) (xy 52.835177 -308.942106) (xy 52.879038 -308.918851)
			(xy 52.926082 -308.902999) (xy 52.975072 -308.894966) (xy 52.999894 -308.89448) (xy 53.014077 -308.894658)
			(xy 53.042317 -308.897329) (xy 53.056282 -308.899814) (xy 53.068728 -308.9021) (xy 53.09235 -308.894734)
			(xy 53.16982 -308.817264) (xy 53.177186 -308.793642) (xy 53.1749 -308.781196) (xy 53.172427 -308.76723)
			(xy 53.169753 -308.73899) (xy 53.169566 -308.724808) (xy 53.169744 -308.710625) (xy 53.172415 -308.682385)
			(xy 53.1749 -308.66842) (xy 53.177186 -308.655974) (xy 53.16982 -308.632352) (xy 53.09235 -308.554882)
			(xy 53.068728 -308.547516) (xy 53.056282 -308.549802) (xy 53.042316 -308.552277) (xy 53.014076 -308.55495)
			(xy 52.999894 -308.555136) (xy 52.974641 -308.554558) (xy 52.924825 -308.546244) (xy 52.877056 -308.529844)
			(xy 52.832638 -308.505806) (xy 52.792783 -308.474784) (xy 52.758577 -308.437626) (xy 52.730953 -308.395344)
			(xy 52.710666 -308.349093) (xy 52.698268 -308.300133) (xy 52.694097 -308.2498) (xy 52.3552 -308.2498)
			(xy 52.355648 -308.25805) (xy 52.350285 -308.307406) (xy 52.337009 -308.355244) (xy 52.316168 -308.400304)
			(xy 52.288311 -308.441398) (xy 52.254174 -308.477445) (xy 52.214654 -308.507493) (xy 52.170794 -308.530753)
			(xy 52.123748 -308.54661) (xy 52.074757 -308.554647) (xy 52.049934 -308.555136) (xy 52.035751 -308.554954)
			(xy 52.007511 -308.552285) (xy 51.993546 -308.549802) (xy 51.9811 -308.547516) (xy 51.957478 -308.554882)
			(xy 51.880008 -308.632352) (xy 51.872642 -308.655974) (xy 51.874928 -308.66842) (xy 51.877404 -308.682386)
			(xy 51.880076 -308.710626) (xy 51.880262 -308.724808) (xy 51.879869 -308.748804) (xy 51.87236 -308.796204)
			(xy 51.857527 -308.841846) (xy 51.835737 -308.884605) (xy 51.807525 -308.923428) (xy 51.773587 -308.95736)
			(xy 51.734759 -308.985565) (xy 51.691996 -309.007348) (xy 51.646351 -309.022172) (xy 51.59895 -309.029673)
			(xy 51.574954 -309.030116) (xy 51.560771 -309.029932) (xy 51.532531 -309.027265) (xy 51.518566 -309.024782)
			(xy 51.50612 -309.022496) (xy 51.482498 -309.029862) (xy 51.405028 -309.107332) (xy 51.397662 -309.130954)
			(xy 51.399948 -309.1434) (xy 51.40242 -309.157367) (xy 51.405095 -309.185606) (xy 51.405282 -309.199788)
			(xy 51.404835 -309.22461) (xy 51.396806 -309.273599) (xy 51.380957 -309.320644) (xy 51.357705 -309.364506)
			(xy 51.327664 -309.404028) (xy 51.291625 -309.438169) (xy 51.250537 -309.46603) (xy 51.205484 -309.486877)
			(xy 51.157651 -309.50016) (xy 51.108299 -309.50553) (xy 51.058728 -309.502845) (xy 51.010245 -309.492176)
			(xy 50.964127 -309.473804) (xy 50.921588 -309.448213) (xy 50.88375 -309.416077) (xy 50.851609 -309.378243)
			(xy 50.826013 -309.335708) (xy 50.807635 -309.289591) (xy 50.79696 -309.24111) (xy 50.794269 -309.191539)
			(xy 50.455528 -309.191539) (xy 50.452846 -309.241068) (xy 50.442177 -309.289553) (xy 50.423804 -309.335674)
			(xy 50.398212 -309.378214) (xy 50.366074 -309.416054) (xy 50.328237 -309.448195) (xy 50.285699 -309.473792)
			(xy 50.23958 -309.492169) (xy 50.191096 -309.502842) (xy 50.141523 -309.505531) (xy 50.092169 -309.500164)
			(xy 50.044333 -309.486883) (xy 49.999276 -309.466037) (xy 49.958185 -309.438177) (xy 49.922143 -309.404035)
			(xy 49.892099 -309.364512) (xy 49.868846 -309.32065) (xy 49.852995 -309.273602) (xy 49.844965 -309.224611)
			(xy 49.844452 -309.199788) (xy 49.844639 -309.185606) (xy 49.847313 -309.157366) (xy 49.849786 -309.1434)
			(xy 49.852072 -309.130954) (xy 49.844706 -309.107332) (xy 49.767236 -309.029862) (xy 49.743614 -309.022496)
			(xy 49.731168 -309.024782) (xy 49.717203 -309.027266) (xy 49.688963 -309.029936) (xy 49.67478 -309.030116)
			(xy 49.65079 -309.029644) (xy 49.6034 -309.022135) (xy 49.557768 -309.007306) (xy 49.515017 -308.985522)
			(xy 49.476201 -308.957318) (xy 49.442274 -308.92339) (xy 49.414072 -308.884572) (xy 49.392289 -308.841821)
			(xy 49.377462 -308.796188) (xy 49.369955 -308.748798) (xy 49.369472 -308.724808) (xy 49.369658 -308.710626)
			(xy 49.372331 -308.682386) (xy 49.374806 -308.66842) (xy 49.377092 -308.655974) (xy 49.369726 -308.632352)
			(xy 49.292256 -308.554882) (xy 49.268634 -308.547516) (xy 49.256188 -308.549802) (xy 49.242223 -308.552287)
			(xy 49.213983 -308.554959) (xy 49.1998 -308.555136) (xy 49.190696 -308.555039) (xy 49.172522 -308.553898)
			(xy 49.163478 -308.55285) (xy 49.151286 -308.55158) (xy 49.129188 -308.559454) (xy 49.056036 -308.635908)
			(xy 49.049178 -308.658514) (xy 49.05121 -308.670452) (xy 49.055025 -308.696424) (xy 49.055364 -308.748914)
			(xy 49.047411 -308.8008) (xy 49.031367 -308.850779) (xy 49.007633 -308.897599) (xy 48.976805 -308.940084)
			(xy 48.939657 -308.97717) (xy 48.897119 -309.007925) (xy 48.85026 -309.03158) (xy 48.825404 -309.040022)
			(xy 48.814482 -309.043578) (xy 48.791876 -309.064406) (xy 48.784505 -309.07193) (xy 48.776111 -309.091222)
			(xy 48.77562 -309.101744) (xy 48.77562 -309.265574) (xy 48.788066 -309.288434) (xy 48.798734 -309.295292)
			(xy 48.804068 -309.298848) (xy 48.81372 -309.322724) (xy 48.818351 -309.332759) (xy 48.834419 -309.347899)
			(xy 48.844708 -309.351934) (xy 48.854106 -309.355744) (xy 48.877705 -309.365844) (xy 48.921862 -309.392016)
			(xy 48.961641 -309.424458) (xy 48.996158 -309.462449) (xy 49.024649 -309.505148) (xy 49.046479 -309.551605)
			(xy 49.061165 -309.600789) (xy 49.068381 -309.65161) (xy 49.067967 -309.702939) (xy 49.064418 -309.728362)
			(xy 49.06264 -309.740046) (xy 49.069498 -309.762398) (xy 49.14011 -309.838344) (xy 49.1617 -309.846472)
			(xy 49.173638 -309.845456) (xy 49.1998 -309.84444) (xy 49.225051 -309.844961) (xy 49.274865 -309.853274)
			(xy 49.322632 -309.869672) (xy 49.367047 -309.893709) (xy 49.406901 -309.924728) (xy 49.441106 -309.961884)
			(xy 49.468728 -310.004163) (xy 49.489015 -310.050412) (xy 49.501413 -310.09937) (xy 49.505583 -310.1497)
			(xy 49.505579 -310.149748) (xy 49.843956 -310.149748) (xy 49.847916 -310.100694) (xy 49.859693 -310.05291)
			(xy 49.878984 -310.007634) (xy 49.905287 -309.966038) (xy 49.937922 -309.929201) (xy 49.976043 -309.898076)
			(xy 50.018664 -309.873469) (xy 50.06468 -309.856017) (xy 50.112899 -309.846173) (xy 50.162074 -309.844192)
			(xy 50.210929 -309.850124) (xy 50.2582 -309.863816) (xy 50.302662 -309.884914) (xy 50.343165 -309.91287)
			(xy 50.378658 -309.946962) (xy 50.408223 -309.986306) (xy 50.431094 -310.029883) (xy 50.446678 -310.076564)
			(xy 50.454573 -310.125141) (xy 50.455068 -310.149748) (xy 50.79417 -310.149748) (xy 50.79813 -310.100694)
			(xy 50.809907 -310.05291) (xy 50.829198 -310.007634) (xy 50.855501 -309.966038) (xy 50.888136 -309.929201)
			(xy 50.926257 -309.898076) (xy 50.968878 -309.873469) (xy 51.014894 -309.856017) (xy 51.063113 -309.846173)
			(xy 51.112288 -309.844192) (xy 51.161143 -309.850124) (xy 51.208414 -309.863816) (xy 51.252876 -309.884914)
			(xy 51.293379 -309.91287) (xy 51.328872 -309.946962) (xy 51.358437 -309.986306) (xy 51.381308 -310.029883)
			(xy 51.396892 -310.076564) (xy 51.404787 -310.125141) (xy 51.405282 -310.149748) (xy 51.74413 -310.149748)
			(xy 51.74809 -310.100694) (xy 51.759867 -310.05291) (xy 51.779158 -310.007634) (xy 51.805461 -309.966038)
			(xy 51.838096 -309.929201) (xy 51.876217 -309.898076) (xy 51.918838 -309.873469) (xy 51.964854 -309.856017)
			(xy 52.013073 -309.846173) (xy 52.062248 -309.844192) (xy 52.111103 -309.850124) (xy 52.158374 -309.863816)
			(xy 52.202836 -309.884914) (xy 52.243339 -309.91287) (xy 52.278832 -309.946962) (xy 52.308397 -309.986306)
			(xy 52.331268 -310.029883) (xy 52.346852 -310.076564) (xy 52.354747 -310.125141) (xy 52.355242 -310.149748)
			(xy 52.69409 -310.149748) (xy 52.69805 -310.100694) (xy 52.709827 -310.05291) (xy 52.729118 -310.007634)
			(xy 52.755421 -309.966038) (xy 52.788056 -309.929201) (xy 52.826177 -309.898076) (xy 52.868798 -309.873469)
			(xy 52.914814 -309.856017) (xy 52.963033 -309.846173) (xy 53.012208 -309.844192) (xy 53.061063 -309.850124)
			(xy 53.108334 -309.863816) (xy 53.152796 -309.884914) (xy 53.193299 -309.91287) (xy 53.228792 -309.946962)
			(xy 53.258357 -309.986306) (xy 53.281228 -310.029883) (xy 53.296812 -310.076564) (xy 53.304707 -310.125141)
			(xy 53.305202 -310.149748) (xy 53.64405 -310.149748) (xy 53.64801 -310.100694) (xy 53.659787 -310.05291)
			(xy 53.679078 -310.007634) (xy 53.705381 -309.966038) (xy 53.738016 -309.929201) (xy 53.776137 -309.898076)
			(xy 53.818758 -309.873469) (xy 53.864774 -309.856017) (xy 53.912993 -309.846173) (xy 53.962168 -309.844192)
			(xy 54.011023 -309.850124) (xy 54.058294 -309.863816) (xy 54.102756 -309.884914) (xy 54.143259 -309.91287)
			(xy 54.178752 -309.946962) (xy 54.208317 -309.986306) (xy 54.231188 -310.029883) (xy 54.246772 -310.076564)
			(xy 54.254667 -310.125141) (xy 54.255162 -310.149748) (xy 54.59401 -310.149748) (xy 54.59797 -310.100694)
			(xy 54.609747 -310.05291) (xy 54.629038 -310.007634) (xy 54.655341 -309.966038) (xy 54.687976 -309.929201)
			(xy 54.726097 -309.898076) (xy 54.768718 -309.873469) (xy 54.814734 -309.856017) (xy 54.862953 -309.846173)
			(xy 54.912128 -309.844192) (xy 54.960983 -309.850124) (xy 55.008254 -309.863816) (xy 55.052716 -309.884914)
			(xy 55.093219 -309.91287) (xy 55.128712 -309.946962) (xy 55.158277 -309.986306) (xy 55.181148 -310.029883)
			(xy 55.196732 -310.076564) (xy 55.204627 -310.125141) (xy 55.205122 -310.149748) (xy 55.54397 -310.149748)
			(xy 55.54793 -310.100694) (xy 55.559707 -310.05291) (xy 55.578998 -310.007634) (xy 55.605301 -309.966038)
			(xy 55.637936 -309.929201) (xy 55.676057 -309.898076) (xy 55.718678 -309.873469) (xy 55.764694 -309.856017)
			(xy 55.812913 -309.846173) (xy 55.862088 -309.844192) (xy 55.910943 -309.850124) (xy 55.958214 -309.863816)
			(xy 56.002676 -309.884914) (xy 56.043179 -309.91287) (xy 56.078672 -309.946962) (xy 56.108237 -309.986306)
			(xy 56.131108 -310.029883) (xy 56.146692 -310.076564) (xy 56.154587 -310.125141) (xy 56.155082 -310.149748)
			(xy 56.494184 -310.149748) (xy 56.498144 -310.100694) (xy 56.509921 -310.05291) (xy 56.529212 -310.007634)
			(xy 56.555515 -309.966038) (xy 56.58815 -309.929201) (xy 56.626271 -309.898076) (xy 56.668892 -309.873469)
			(xy 56.714908 -309.856017) (xy 56.763127 -309.846173) (xy 56.812302 -309.844192) (xy 56.861157 -309.850124)
			(xy 56.908428 -309.863816) (xy 56.95289 -309.884914) (xy 56.993393 -309.91287) (xy 57.028886 -309.946962)
			(xy 57.058451 -309.986306) (xy 57.081322 -310.029883) (xy 57.096906 -310.076564) (xy 57.104801 -310.125141)
			(xy 57.105296 -310.149748) (xy 57.444144 -310.149748) (xy 57.448104 -310.100694) (xy 57.459881 -310.05291)
			(xy 57.479172 -310.007634) (xy 57.505475 -309.966038) (xy 57.53811 -309.929201) (xy 57.576231 -309.898076)
			(xy 57.618852 -309.873469) (xy 57.664868 -309.856017) (xy 57.713087 -309.846173) (xy 57.762262 -309.844192)
			(xy 57.811117 -309.850124) (xy 57.858388 -309.863816) (xy 57.90285 -309.884914) (xy 57.943353 -309.91287)
			(xy 57.978846 -309.946962) (xy 58.008411 -309.986306) (xy 58.031282 -310.029883) (xy 58.046866 -310.076564)
			(xy 58.054761 -310.125141) (xy 58.055256 -310.149748) (xy 58.394104 -310.149748) (xy 58.398064 -310.100694)
			(xy 58.409841 -310.05291) (xy 58.429132 -310.007634) (xy 58.455435 -309.966038) (xy 58.48807 -309.929201)
			(xy 58.526191 -309.898076) (xy 58.568812 -309.873469) (xy 58.614828 -309.856017) (xy 58.663047 -309.846173)
			(xy 58.712222 -309.844192) (xy 58.761077 -309.850124) (xy 58.808348 -309.863816) (xy 58.85281 -309.884914)
			(xy 58.893313 -309.91287) (xy 58.928806 -309.946962) (xy 58.958371 -309.986306) (xy 58.981242 -310.029883)
			(xy 58.996826 -310.076564) (xy 59.004721 -310.125141) (xy 59.005216 -310.149748) (xy 59.344064 -310.149748)
			(xy 59.348024 -310.100694) (xy 59.359801 -310.05291) (xy 59.379092 -310.007634) (xy 59.405395 -309.966038)
			(xy 59.43803 -309.929201) (xy 59.476151 -309.898076) (xy 59.518772 -309.873469) (xy 59.564788 -309.856017)
			(xy 59.613007 -309.846173) (xy 59.662182 -309.844192) (xy 59.711037 -309.850124) (xy 59.758308 -309.863816)
			(xy 59.80277 -309.884914) (xy 59.843273 -309.91287) (xy 59.878766 -309.946962) (xy 59.908331 -309.986306)
			(xy 59.931202 -310.029883) (xy 59.946786 -310.076564) (xy 59.954681 -310.125141) (xy 59.955176 -310.149748)
			(xy 60.294024 -310.149748) (xy 60.297984 -310.100694) (xy 60.309761 -310.05291) (xy 60.329052 -310.007634)
			(xy 60.355355 -309.966038) (xy 60.38799 -309.929201) (xy 60.426111 -309.898076) (xy 60.468732 -309.873469)
			(xy 60.514748 -309.856017) (xy 60.562967 -309.846173) (xy 60.612142 -309.844192) (xy 60.660997 -309.850124)
			(xy 60.708268 -309.863816) (xy 60.75273 -309.884914) (xy 60.793233 -309.91287) (xy 60.828726 -309.946962)
			(xy 60.858291 -309.986306) (xy 60.881162 -310.029883) (xy 60.896746 -310.076564) (xy 60.904641 -310.125141)
			(xy 60.905136 -310.149748) (xy 61.243984 -310.149748) (xy 61.247944 -310.100694) (xy 61.259721 -310.05291)
			(xy 61.279012 -310.007634) (xy 61.305315 -309.966038) (xy 61.33795 -309.929201) (xy 61.376071 -309.898076)
			(xy 61.418692 -309.873469) (xy 61.464708 -309.856017) (xy 61.512927 -309.846173) (xy 61.562102 -309.844192)
			(xy 61.610957 -309.850124) (xy 61.658228 -309.863816) (xy 61.70269 -309.884914) (xy 61.743193 -309.91287)
			(xy 61.778686 -309.946962) (xy 61.808251 -309.986306) (xy 61.831122 -310.029883) (xy 61.846706 -310.076564)
			(xy 61.854601 -310.125141) (xy 61.855096 -310.149748) (xy 62.193944 -310.149748) (xy 62.197904 -310.100694)
			(xy 62.209681 -310.05291) (xy 62.228972 -310.007634) (xy 62.255275 -309.966038) (xy 62.28791 -309.929201)
			(xy 62.326031 -309.898076) (xy 62.368652 -309.873469) (xy 62.414668 -309.856017) (xy 62.462887 -309.846173)
			(xy 62.512062 -309.844192) (xy 62.560917 -309.850124) (xy 62.608188 -309.863816) (xy 62.65265 -309.884914)
			(xy 62.693153 -309.91287) (xy 62.728646 -309.946962) (xy 62.758211 -309.986306) (xy 62.781082 -310.029883)
			(xy 62.796666 -310.076564) (xy 62.804561 -310.125141) (xy 62.805056 -310.149748) (xy 63.144158 -310.149748)
			(xy 63.148118 -310.100694) (xy 63.159895 -310.05291) (xy 63.179186 -310.007634) (xy 63.205489 -309.966038)
			(xy 63.238124 -309.929201) (xy 63.276245 -309.898076) (xy 63.318866 -309.873469) (xy 63.364882 -309.856017)
			(xy 63.413101 -309.846173) (xy 63.462276 -309.844192) (xy 63.511131 -309.850124) (xy 63.558402 -309.863816)
			(xy 63.602864 -309.884914) (xy 63.643367 -309.91287) (xy 63.67886 -309.946962) (xy 63.708425 -309.986306)
			(xy 63.731296 -310.029883) (xy 63.74688 -310.076564) (xy 63.754775 -310.125141) (xy 63.75527 -310.149748)
			(xy 64.094118 -310.149748) (xy 64.098078 -310.100694) (xy 64.109855 -310.05291) (xy 64.129146 -310.007634)
			(xy 64.155449 -309.966038) (xy 64.188084 -309.929201) (xy 64.226205 -309.898076) (xy 64.268826 -309.873469)
			(xy 64.314842 -309.856017) (xy 64.363061 -309.846173) (xy 64.412236 -309.844192) (xy 64.461091 -309.850124)
			(xy 64.508362 -309.863816) (xy 64.552824 -309.884914) (xy 64.593327 -309.91287) (xy 64.62882 -309.946962)
			(xy 64.658385 -309.986306) (xy 64.681256 -310.029883) (xy 64.69684 -310.076564) (xy 64.704735 -310.125141)
			(xy 64.70523 -310.149748) (xy 65.044078 -310.149748) (xy 65.048038 -310.100694) (xy 65.059815 -310.05291)
			(xy 65.079106 -310.007634) (xy 65.105409 -309.966038) (xy 65.138044 -309.929201) (xy 65.176165 -309.898076)
			(xy 65.218786 -309.873469) (xy 65.264802 -309.856017) (xy 65.313021 -309.846173) (xy 65.362196 -309.844192)
			(xy 65.411051 -309.850124) (xy 65.458322 -309.863816) (xy 65.502784 -309.884914) (xy 65.543287 -309.91287)
			(xy 65.57878 -309.946962) (xy 65.608345 -309.986306) (xy 65.631216 -310.029883) (xy 65.6468 -310.076564)
			(xy 65.654695 -310.125141) (xy 65.65519 -310.149748) (xy 65.994038 -310.149748) (xy 65.997998 -310.100694)
			(xy 66.009775 -310.05291) (xy 66.029066 -310.007634) (xy 66.055369 -309.966038) (xy 66.088004 -309.929201)
			(xy 66.126125 -309.898076) (xy 66.168746 -309.873469) (xy 66.214762 -309.856017) (xy 66.262981 -309.846173)
			(xy 66.312156 -309.844192) (xy 66.361011 -309.850124) (xy 66.408282 -309.863816) (xy 66.452744 -309.884914)
			(xy 66.493247 -309.91287) (xy 66.52874 -309.946962) (xy 66.558305 -309.986306) (xy 66.581176 -310.029883)
			(xy 66.59676 -310.076564) (xy 66.604655 -310.125141) (xy 66.60515 -310.149748) (xy 66.943998 -310.149748)
			(xy 66.947958 -310.100694) (xy 66.959735 -310.05291) (xy 66.979026 -310.007634) (xy 67.005329 -309.966038)
			(xy 67.037964 -309.929201) (xy 67.076085 -309.898076) (xy 67.118706 -309.873469) (xy 67.164722 -309.856017)
			(xy 67.212941 -309.846173) (xy 67.262116 -309.844192) (xy 67.310971 -309.850124) (xy 67.358242 -309.863816)
			(xy 67.402704 -309.884914) (xy 67.443207 -309.91287) (xy 67.4787 -309.946962) (xy 67.508265 -309.986306)
			(xy 67.531136 -310.029883) (xy 67.54672 -310.076564) (xy 67.554615 -310.125141) (xy 67.55511 -310.149748)
			(xy 67.893958 -310.149748) (xy 67.897918 -310.100694) (xy 67.909695 -310.05291) (xy 67.928986 -310.007634)
			(xy 67.955289 -309.966038) (xy 67.987924 -309.929201) (xy 68.026045 -309.898076) (xy 68.068666 -309.873469)
			(xy 68.114682 -309.856017) (xy 68.162901 -309.846173) (xy 68.212076 -309.844192) (xy 68.260931 -309.850124)
			(xy 68.308202 -309.863816) (xy 68.352664 -309.884914) (xy 68.393167 -309.91287) (xy 68.42866 -309.946962)
			(xy 68.458225 -309.986306) (xy 68.481096 -310.029883) (xy 68.49668 -310.076564) (xy 68.504575 -310.125141)
			(xy 68.50507 -310.149748) (xy 68.844172 -310.149748) (xy 68.848132 -310.100694) (xy 68.859909 -310.05291)
			(xy 68.8792 -310.007634) (xy 68.905503 -309.966038) (xy 68.938138 -309.929201) (xy 68.976259 -309.898076)
			(xy 69.01888 -309.873469) (xy 69.064896 -309.856017) (xy 69.113115 -309.846173) (xy 69.16229 -309.844192)
			(xy 69.211145 -309.850124) (xy 69.258416 -309.863816) (xy 69.302878 -309.884914) (xy 69.343381 -309.91287)
			(xy 69.378874 -309.946962) (xy 69.408439 -309.986306) (xy 69.43131 -310.029883) (xy 69.446894 -310.076564)
			(xy 69.454789 -310.125141) (xy 69.455284 -310.149748) (xy 69.794132 -310.149748) (xy 69.798092 -310.100694)
			(xy 69.809869 -310.05291) (xy 69.82916 -310.007634) (xy 69.855463 -309.966038) (xy 69.888098 -309.929201)
			(xy 69.926219 -309.898076) (xy 69.96884 -309.873469) (xy 70.014856 -309.856017) (xy 70.063075 -309.846173)
			(xy 70.11225 -309.844192) (xy 70.161105 -309.850124) (xy 70.208376 -309.863816) (xy 70.252838 -309.884914)
			(xy 70.293341 -309.91287) (xy 70.328834 -309.946962) (xy 70.358399 -309.986306) (xy 70.38127 -310.029883)
			(xy 70.396854 -310.076564) (xy 70.404749 -310.125141) (xy 70.405244 -310.149748) (xy 70.744092 -310.149748)
			(xy 70.748052 -310.100694) (xy 70.759829 -310.05291) (xy 70.77912 -310.007634) (xy 70.805423 -309.966038)
			(xy 70.838058 -309.929201) (xy 70.876179 -309.898076) (xy 70.9188 -309.873469) (xy 70.964816 -309.856017)
			(xy 71.013035 -309.846173) (xy 71.06221 -309.844192) (xy 71.111065 -309.850124) (xy 71.158336 -309.863816)
			(xy 71.202798 -309.884914) (xy 71.243301 -309.91287) (xy 71.278794 -309.946962) (xy 71.308359 -309.986306)
			(xy 71.33123 -310.029883) (xy 71.346814 -310.076564) (xy 71.354709 -310.125141) (xy 71.355204 -310.149748)
			(xy 71.694052 -310.149748) (xy 71.698012 -310.100694) (xy 71.709789 -310.05291) (xy 71.72908 -310.007634)
			(xy 71.755383 -309.966038) (xy 71.788018 -309.929201) (xy 71.826139 -309.898076) (xy 71.86876 -309.873469)
			(xy 71.914776 -309.856017) (xy 71.962995 -309.846173) (xy 72.01217 -309.844192) (xy 72.061025 -309.850124)
			(xy 72.108296 -309.863816) (xy 72.152758 -309.884914) (xy 72.193261 -309.91287) (xy 72.228754 -309.946962)
			(xy 72.258319 -309.986306) (xy 72.28119 -310.029883) (xy 72.296774 -310.076564) (xy 72.304669 -310.125141)
			(xy 72.305164 -310.149748) (xy 72.644012 -310.149748) (xy 72.647972 -310.100694) (xy 72.659749 -310.05291)
			(xy 72.67904 -310.007634) (xy 72.705343 -309.966038) (xy 72.737978 -309.929201) (xy 72.776099 -309.898076)
			(xy 72.81872 -309.873469) (xy 72.864736 -309.856017) (xy 72.912955 -309.846173) (xy 72.96213 -309.844192)
			(xy 73.010985 -309.850124) (xy 73.058256 -309.863816) (xy 73.102718 -309.884914) (xy 73.143221 -309.91287)
			(xy 73.178714 -309.946962) (xy 73.208279 -309.986306) (xy 73.23115 -310.029883) (xy 73.246734 -310.076564)
			(xy 73.254629 -310.125141) (xy 73.255124 -310.149748) (xy 73.593972 -310.149748) (xy 73.597932 -310.100694)
			(xy 73.609709 -310.05291) (xy 73.629 -310.007634) (xy 73.655303 -309.966038) (xy 73.687938 -309.929201)
			(xy 73.726059 -309.898076) (xy 73.76868 -309.873469) (xy 73.814696 -309.856017) (xy 73.862915 -309.846173)
			(xy 73.91209 -309.844192) (xy 73.960945 -309.850124) (xy 74.008216 -309.863816) (xy 74.052678 -309.884914)
			(xy 74.093181 -309.91287) (xy 74.128674 -309.946962) (xy 74.158239 -309.986306) (xy 74.18111 -310.029883)
			(xy 74.196694 -310.076564) (xy 74.204589 -310.125141) (xy 74.205084 -310.149748) (xy 74.544186 -310.149748)
			(xy 74.548146 -310.100694) (xy 74.559923 -310.05291) (xy 74.579214 -310.007634) (xy 74.605517 -309.966038)
			(xy 74.638152 -309.929201) (xy 74.676273 -309.898076) (xy 74.718894 -309.873469) (xy 74.76491 -309.856017)
			(xy 74.813129 -309.846173) (xy 74.862304 -309.844192) (xy 74.911159 -309.850124) (xy 74.95843 -309.863816)
			(xy 75.002892 -309.884914) (xy 75.043395 -309.91287) (xy 75.078888 -309.946962) (xy 75.108453 -309.986306)
			(xy 75.131324 -310.029883) (xy 75.146908 -310.076564) (xy 75.154803 -310.125141) (xy 75.155298 -310.149748)
			(xy 75.494146 -310.149748) (xy 75.498106 -310.100694) (xy 75.509883 -310.05291) (xy 75.529174 -310.007634)
			(xy 75.555477 -309.966038) (xy 75.588112 -309.929201) (xy 75.626233 -309.898076) (xy 75.668854 -309.873469)
			(xy 75.71487 -309.856017) (xy 75.763089 -309.846173) (xy 75.812264 -309.844192) (xy 75.861119 -309.850124)
			(xy 75.90839 -309.863816) (xy 75.952852 -309.884914) (xy 75.993355 -309.91287) (xy 76.028848 -309.946962)
			(xy 76.058413 -309.986306) (xy 76.081284 -310.029883) (xy 76.096868 -310.076564) (xy 76.104763 -310.125141)
			(xy 76.105258 -310.149748) (xy 76.444106 -310.149748) (xy 76.448066 -310.100694) (xy 76.459843 -310.05291)
			(xy 76.479134 -310.007634) (xy 76.505437 -309.966038) (xy 76.538072 -309.929201) (xy 76.576193 -309.898076)
			(xy 76.618814 -309.873469) (xy 76.66483 -309.856017) (xy 76.713049 -309.846173) (xy 76.762224 -309.844192)
			(xy 76.811079 -309.850124) (xy 76.85835 -309.863816) (xy 76.902812 -309.884914) (xy 76.943315 -309.91287)
			(xy 76.978808 -309.946962) (xy 77.008373 -309.986306) (xy 77.031244 -310.029883) (xy 77.046828 -310.076564)
			(xy 77.054723 -310.125141) (xy 77.055218 -310.149748) (xy 77.394066 -310.149748) (xy 77.398026 -310.100694)
			(xy 77.409803 -310.05291) (xy 77.429094 -310.007634) (xy 77.455397 -309.966038) (xy 77.488032 -309.929201)
			(xy 77.526153 -309.898076) (xy 77.568774 -309.873469) (xy 77.61479 -309.856017) (xy 77.663009 -309.846173)
			(xy 77.712184 -309.844192) (xy 77.761039 -309.850124) (xy 77.80831 -309.863816) (xy 77.852772 -309.884914)
			(xy 77.893275 -309.91287) (xy 77.928768 -309.946962) (xy 77.958333 -309.986306) (xy 77.981204 -310.029883)
			(xy 77.996788 -310.076564) (xy 78.004683 -310.125141) (xy 78.005178 -310.149748) (xy 78.344026 -310.149748)
			(xy 78.347986 -310.100694) (xy 78.359763 -310.05291) (xy 78.379054 -310.007634) (xy 78.405357 -309.966038)
			(xy 78.437992 -309.929201) (xy 78.476113 -309.898076) (xy 78.518734 -309.873469) (xy 78.56475 -309.856017)
			(xy 78.612969 -309.846173) (xy 78.662144 -309.844192) (xy 78.710999 -309.850124) (xy 78.75827 -309.863816)
			(xy 78.802732 -309.884914) (xy 78.843235 -309.91287) (xy 78.878728 -309.946962) (xy 78.908293 -309.986306)
			(xy 78.931164 -310.029883) (xy 78.946748 -310.076564) (xy 78.954643 -310.125141) (xy 78.955138 -310.149748)
			(xy 79.293986 -310.149748) (xy 79.297946 -310.100694) (xy 79.309723 -310.05291) (xy 79.329014 -310.007634)
			(xy 79.355317 -309.966038) (xy 79.387952 -309.929201) (xy 79.426073 -309.898076) (xy 79.468694 -309.873469)
			(xy 79.51471 -309.856017) (xy 79.562929 -309.846173) (xy 79.612104 -309.844192) (xy 79.660959 -309.850124)
			(xy 79.70823 -309.863816) (xy 79.752692 -309.884914) (xy 79.793195 -309.91287) (xy 79.828688 -309.946962)
			(xy 79.858253 -309.986306) (xy 79.881124 -310.029883) (xy 79.896708 -310.076564) (xy 79.904603 -310.125141)
			(xy 79.905098 -310.149748) (xy 80.243946 -310.149748) (xy 80.247906 -310.100694) (xy 80.259683 -310.05291)
			(xy 80.278974 -310.007634) (xy 80.305277 -309.966038) (xy 80.337912 -309.929201) (xy 80.376033 -309.898076)
			(xy 80.418654 -309.873469) (xy 80.46467 -309.856017) (xy 80.512889 -309.846173) (xy 80.562064 -309.844192)
			(xy 80.610919 -309.850124) (xy 80.65819 -309.863816) (xy 80.702652 -309.884914) (xy 80.743155 -309.91287)
			(xy 80.778648 -309.946962) (xy 80.808213 -309.986306) (xy 80.831084 -310.029883) (xy 80.846668 -310.076564)
			(xy 80.854563 -310.125141) (xy 80.855058 -310.149748) (xy 81.19416 -310.149748) (xy 81.19812 -310.100694)
			(xy 81.209897 -310.05291) (xy 81.229188 -310.007634) (xy 81.255491 -309.966038) (xy 81.288126 -309.929201)
			(xy 81.326247 -309.898076) (xy 81.368868 -309.873469) (xy 81.414884 -309.856017) (xy 81.463103 -309.846173)
			(xy 81.512278 -309.844192) (xy 81.561133 -309.850124) (xy 81.608404 -309.863816) (xy 81.652866 -309.884914)
			(xy 81.693369 -309.91287) (xy 81.728862 -309.946962) (xy 81.758427 -309.986306) (xy 81.781298 -310.029883)
			(xy 81.796882 -310.076564) (xy 81.804777 -310.125141) (xy 81.805272 -310.149748) (xy 82.14412 -310.149748)
			(xy 82.14808 -310.100694) (xy 82.159857 -310.05291) (xy 82.179148 -310.007634) (xy 82.205451 -309.966038)
			(xy 82.238086 -309.929201) (xy 82.276207 -309.898076) (xy 82.318828 -309.873469) (xy 82.364844 -309.856017)
			(xy 82.413063 -309.846173) (xy 82.462238 -309.844192) (xy 82.511093 -309.850124) (xy 82.558364 -309.863816)
			(xy 82.602826 -309.884914) (xy 82.643329 -309.91287) (xy 82.678822 -309.946962) (xy 82.708387 -309.986306)
			(xy 82.731258 -310.029883) (xy 82.746842 -310.076564) (xy 82.754737 -310.125141) (xy 82.755232 -310.149748)
			(xy 83.094334 -310.149748) (xy 83.098294 -310.100694) (xy 83.110071 -310.05291) (xy 83.129362 -310.007634)
			(xy 83.155665 -309.966038) (xy 83.1883 -309.929201) (xy 83.226421 -309.898076) (xy 83.269042 -309.873469)
			(xy 83.315058 -309.856017) (xy 83.363277 -309.846173) (xy 83.412452 -309.844192) (xy 83.461307 -309.850124)
			(xy 83.472376 -309.85333) (xy 89.010742 -309.85333) (xy 89.014813 -309.797708) (xy 89.026939 -309.743271)
			(xy 89.046862 -309.69118) (xy 89.074158 -309.642545) (xy 89.108244 -309.598402) (xy 89.148393 -309.559693)
			(xy 89.193751 -309.527242) (xy 89.243351 -309.501741) (xy 89.296135 -309.483734) (xy 89.350978 -309.473604)
			(xy 89.406712 -309.471567) (xy 89.462149 -309.477667) (xy 89.516106 -309.491773) (xy 89.567435 -309.513585)
			(xy 89.615041 -309.542639) (xy 89.657909 -309.578314) (xy 89.68698 -309.61076) (xy 93.557088 -309.61076)
			(xy 93.561159 -309.555138) (xy 93.573285 -309.500701) (xy 93.593208 -309.44861) (xy 93.620504 -309.399975)
			(xy 93.65459 -309.355832) (xy 93.694739 -309.317123) (xy 93.740097 -309.284672) (xy 93.789697 -309.259171)
			(xy 93.842481 -309.241164) (xy 93.897324 -309.231034) (xy 93.953058 -309.228997) (xy 94.008495 -309.235097)
			(xy 94.062452 -309.249203) (xy 94.113781 -309.271015) (xy 94.161387 -309.300069) (xy 94.204255 -309.335744)
			(xy 94.241472 -309.377281) (xy 94.272245 -309.423794) (xy 94.295917 -309.474291) (xy 94.311985 -309.527698)
			(xy 94.320105 -309.582874) (xy 94.320614 -309.61076) (xy 94.320105 -309.638646) (xy 94.311985 -309.693822)
			(xy 94.295917 -309.747229) (xy 94.272245 -309.797726) (xy 94.241472 -309.844239) (xy 94.204255 -309.885776)
			(xy 94.161387 -309.921451) (xy 94.113781 -309.950505) (xy 94.062452 -309.972317) (xy 94.008495 -309.986423)
			(xy 93.953058 -309.992523) (xy 93.897324 -309.990486) (xy 93.842481 -309.980356) (xy 93.789697 -309.962349)
			(xy 93.740097 -309.936848) (xy 93.694739 -309.904397) (xy 93.65459 -309.865688) (xy 93.620504 -309.821545)
			(xy 93.593208 -309.77291) (xy 93.573285 -309.720819) (xy 93.561159 -309.666382) (xy 93.557088 -309.61076)
			(xy 89.68698 -309.61076) (xy 89.695126 -309.619851) (xy 89.725899 -309.666364) (xy 89.749571 -309.716861)
			(xy 89.765639 -309.770268) (xy 89.773759 -309.825444) (xy 89.774268 -309.85333) (xy 89.773759 -309.881216)
			(xy 89.765639 -309.936392) (xy 89.749571 -309.989799) (xy 89.725899 -310.040296) (xy 89.695126 -310.086809)
			(xy 89.657909 -310.128346) (xy 89.615041 -310.164021) (xy 89.567435 -310.193075) (xy 89.516106 -310.214887)
			(xy 89.462149 -310.228993) (xy 89.406712 -310.235093) (xy 89.350978 -310.233056) (xy 89.296135 -310.222926)
			(xy 89.243351 -310.204919) (xy 89.193751 -310.179418) (xy 89.148393 -310.146967) (xy 89.108244 -310.108258)
			(xy 89.074158 -310.064115) (xy 89.046862 -310.01548) (xy 89.026939 -309.963389) (xy 89.014813 -309.908952)
			(xy 89.010742 -309.85333) (xy 83.472376 -309.85333) (xy 83.508578 -309.863816) (xy 83.55304 -309.884914)
			(xy 83.593543 -309.91287) (xy 83.629036 -309.946962) (xy 83.658601 -309.986306) (xy 83.681472 -310.029883)
			(xy 83.697056 -310.076564) (xy 83.704951 -310.125141) (xy 83.705446 -310.149748) (xy 83.704951 -310.174355)
			(xy 83.697056 -310.222932) (xy 83.690453 -310.242712) (xy 100.471984 -310.242712) (xy 100.476055 -310.18709)
			(xy 100.488181 -310.132653) (xy 100.508104 -310.080562) (xy 100.5354 -310.031927) (xy 100.569486 -309.987784)
			(xy 100.609635 -309.949075) (xy 100.654993 -309.916624) (xy 100.704593 -309.891123) (xy 100.757377 -309.873116)
			(xy 100.81222 -309.862986) (xy 100.867954 -309.860949) (xy 100.923391 -309.867049) (xy 100.977348 -309.881155)
			(xy 101.028677 -309.902967) (xy 101.076283 -309.932021) (xy 101.119151 -309.967696) (xy 101.156368 -310.009233)
			(xy 101.187141 -310.055746) (xy 101.210813 -310.106243) (xy 101.226881 -310.15965) (xy 101.235001 -310.214826)
			(xy 101.23551 -310.242712) (xy 101.487984 -310.242712) (xy 101.492055 -310.18709) (xy 101.504181 -310.132653)
			(xy 101.524104 -310.080562) (xy 101.5514 -310.031927) (xy 101.585486 -309.987784) (xy 101.625635 -309.949075)
			(xy 101.670993 -309.916624) (xy 101.720593 -309.891123) (xy 101.773377 -309.873116) (xy 101.82822 -309.862986)
			(xy 101.883954 -309.860949) (xy 101.939391 -309.867049) (xy 101.993348 -309.881155) (xy 102.044677 -309.902967)
			(xy 102.092283 -309.932021) (xy 102.135151 -309.967696) (xy 102.172368 -310.009233) (xy 102.203141 -310.055746)
			(xy 102.226813 -310.106243) (xy 102.242881 -310.15965) (xy 102.251001 -310.214826) (xy 102.25151 -310.242712)
			(xy 102.503984 -310.242712) (xy 102.508055 -310.18709) (xy 102.520181 -310.132653) (xy 102.540104 -310.080562)
			(xy 102.5674 -310.031927) (xy 102.601486 -309.987784) (xy 102.641635 -309.949075) (xy 102.686993 -309.916624)
			(xy 102.736593 -309.891123) (xy 102.789377 -309.873116) (xy 102.84422 -309.862986) (xy 102.899954 -309.860949)
			(xy 102.955391 -309.867049) (xy 103.009348 -309.881155) (xy 103.060677 -309.902967) (xy 103.108283 -309.932021)
			(xy 103.151151 -309.967696) (xy 103.188368 -310.009233) (xy 103.219141 -310.055746) (xy 103.242813 -310.106243)
			(xy 103.258881 -310.15965) (xy 103.267001 -310.214826) (xy 103.26751 -310.242712) (xy 103.519984 -310.242712)
			(xy 103.524055 -310.18709) (xy 103.536181 -310.132653) (xy 103.556104 -310.080562) (xy 103.5834 -310.031927)
			(xy 103.617486 -309.987784) (xy 103.657635 -309.949075) (xy 103.702993 -309.916624) (xy 103.752593 -309.891123)
			(xy 103.805377 -309.873116) (xy 103.86022 -309.862986) (xy 103.915954 -309.860949) (xy 103.971391 -309.867049)
			(xy 104.025348 -309.881155) (xy 104.076677 -309.902967) (xy 104.124283 -309.932021) (xy 104.167151 -309.967696)
			(xy 104.204368 -310.009233) (xy 104.235141 -310.055746) (xy 104.258813 -310.106243) (xy 104.274881 -310.15965)
			(xy 104.283001 -310.214826) (xy 104.28351 -310.242712) (xy 104.535984 -310.242712) (xy 104.540055 -310.18709)
			(xy 104.552181 -310.132653) (xy 104.572104 -310.080562) (xy 104.5994 -310.031927) (xy 104.633486 -309.987784)
			(xy 104.673635 -309.949075) (xy 104.718993 -309.916624) (xy 104.768593 -309.891123) (xy 104.821377 -309.873116)
			(xy 104.87622 -309.862986) (xy 104.931954 -309.860949) (xy 104.987391 -309.867049) (xy 105.041348 -309.881155)
			(xy 105.092677 -309.902967) (xy 105.140283 -309.932021) (xy 105.183151 -309.967696) (xy 105.220368 -310.009233)
			(xy 105.251141 -310.055746) (xy 105.274813 -310.106243) (xy 105.290881 -310.15965) (xy 105.299001 -310.214826)
			(xy 105.29951 -310.242712) (xy 105.551984 -310.242712) (xy 105.556055 -310.18709) (xy 105.568181 -310.132653)
			(xy 105.588104 -310.080562) (xy 105.6154 -310.031927) (xy 105.649486 -309.987784) (xy 105.689635 -309.949075)
			(xy 105.734993 -309.916624) (xy 105.784593 -309.891123) (xy 105.837377 -309.873116) (xy 105.89222 -309.862986)
			(xy 105.947954 -309.860949) (xy 106.003391 -309.867049) (xy 106.057348 -309.881155) (xy 106.108677 -309.902967)
			(xy 106.156283 -309.932021) (xy 106.199151 -309.967696) (xy 106.236368 -310.009233) (xy 106.267141 -310.055746)
			(xy 106.290813 -310.106243) (xy 106.306881 -310.15965) (xy 106.315001 -310.214826) (xy 106.31551 -310.242712)
			(xy 106.567984 -310.242712) (xy 106.572055 -310.18709) (xy 106.584181 -310.132653) (xy 106.604104 -310.080562)
			(xy 106.6314 -310.031927) (xy 106.665486 -309.987784) (xy 106.705635 -309.949075) (xy 106.750993 -309.916624)
			(xy 106.800593 -309.891123) (xy 106.853377 -309.873116) (xy 106.90822 -309.862986) (xy 106.963954 -309.860949)
			(xy 107.019391 -309.867049) (xy 107.073348 -309.881155) (xy 107.124677 -309.902967) (xy 107.172283 -309.932021)
			(xy 107.215151 -309.967696) (xy 107.252368 -310.009233) (xy 107.283141 -310.055746) (xy 107.306813 -310.106243)
			(xy 107.322881 -310.15965) (xy 107.331001 -310.214826) (xy 107.33151 -310.242712) (xy 107.583984 -310.242712)
			(xy 107.588055 -310.18709) (xy 107.600181 -310.132653) (xy 107.620104 -310.080562) (xy 107.6474 -310.031927)
			(xy 107.681486 -309.987784) (xy 107.721635 -309.949075) (xy 107.766993 -309.916624) (xy 107.816593 -309.891123)
			(xy 107.869377 -309.873116) (xy 107.92422 -309.862986) (xy 107.979954 -309.860949) (xy 108.035391 -309.867049)
			(xy 108.089348 -309.881155) (xy 108.140677 -309.902967) (xy 108.188283 -309.932021) (xy 108.231151 -309.967696)
			(xy 108.268368 -310.009233) (xy 108.299141 -310.055746) (xy 108.322813 -310.106243) (xy 108.338881 -310.15965)
			(xy 108.347001 -310.214826) (xy 108.34751 -310.242712) (xy 108.599984 -310.242712) (xy 108.604055 -310.18709)
			(xy 108.616181 -310.132653) (xy 108.636104 -310.080562) (xy 108.6634 -310.031927) (xy 108.697486 -309.987784)
			(xy 108.737635 -309.949075) (xy 108.782993 -309.916624) (xy 108.832593 -309.891123) (xy 108.885377 -309.873116)
			(xy 108.94022 -309.862986) (xy 108.995954 -309.860949) (xy 109.051391 -309.867049) (xy 109.105348 -309.881155)
			(xy 109.156677 -309.902967) (xy 109.204283 -309.932021) (xy 109.247151 -309.967696) (xy 109.284368 -310.009233)
			(xy 109.315141 -310.055746) (xy 109.338813 -310.106243) (xy 109.354881 -310.15965) (xy 109.363001 -310.214826)
			(xy 109.36351 -310.242712) (xy 109.615984 -310.242712) (xy 109.620055 -310.18709) (xy 109.632181 -310.132653)
			(xy 109.652104 -310.080562) (xy 109.6794 -310.031927) (xy 109.713486 -309.987784) (xy 109.753635 -309.949075)
			(xy 109.798993 -309.916624) (xy 109.848593 -309.891123) (xy 109.901377 -309.873116) (xy 109.95622 -309.862986)
			(xy 110.011954 -309.860949) (xy 110.067391 -309.867049) (xy 110.121348 -309.881155) (xy 110.172677 -309.902967)
			(xy 110.220283 -309.932021) (xy 110.263151 -309.967696) (xy 110.300368 -310.009233) (xy 110.331141 -310.055746)
			(xy 110.354813 -310.106243) (xy 110.370881 -310.15965) (xy 110.379001 -310.214826) (xy 110.37951 -310.242712)
			(xy 110.379001 -310.270598) (xy 110.370881 -310.325774) (xy 110.354813 -310.379181) (xy 110.331141 -310.429678)
			(xy 110.300368 -310.476191) (xy 110.263151 -310.517728) (xy 110.220283 -310.553403) (xy 110.172677 -310.582457)
			(xy 110.121348 -310.604269) (xy 110.067391 -310.618375) (xy 110.011954 -310.624475) (xy 109.95622 -310.622438)
			(xy 109.901377 -310.612308) (xy 109.848593 -310.594301) (xy 109.798993 -310.5688) (xy 109.753635 -310.536349)
			(xy 109.713486 -310.49764) (xy 109.6794 -310.453497) (xy 109.652104 -310.404862) (xy 109.632181 -310.352771)
			(xy 109.620055 -310.298334) (xy 109.615984 -310.242712) (xy 109.36351 -310.242712) (xy 109.363001 -310.270598)
			(xy 109.354881 -310.325774) (xy 109.338813 -310.379181) (xy 109.315141 -310.429678) (xy 109.284368 -310.476191)
			(xy 109.247151 -310.517728) (xy 109.204283 -310.553403) (xy 109.156677 -310.582457) (xy 109.105348 -310.604269)
			(xy 109.051391 -310.618375) (xy 108.995954 -310.624475) (xy 108.94022 -310.622438) (xy 108.885377 -310.612308)
			(xy 108.832593 -310.594301) (xy 108.782993 -310.5688) (xy 108.737635 -310.536349) (xy 108.697486 -310.49764)
			(xy 108.6634 -310.453497) (xy 108.636104 -310.404862) (xy 108.616181 -310.352771) (xy 108.604055 -310.298334)
			(xy 108.599984 -310.242712) (xy 108.34751 -310.242712) (xy 108.347001 -310.270598) (xy 108.338881 -310.325774)
			(xy 108.322813 -310.379181) (xy 108.299141 -310.429678) (xy 108.268368 -310.476191) (xy 108.231151 -310.517728)
			(xy 108.188283 -310.553403) (xy 108.140677 -310.582457) (xy 108.089348 -310.604269) (xy 108.035391 -310.618375)
			(xy 107.979954 -310.624475) (xy 107.92422 -310.622438) (xy 107.869377 -310.612308) (xy 107.816593 -310.594301)
			(xy 107.766993 -310.5688) (xy 107.721635 -310.536349) (xy 107.681486 -310.49764) (xy 107.6474 -310.453497)
			(xy 107.620104 -310.404862) (xy 107.600181 -310.352771) (xy 107.588055 -310.298334) (xy 107.583984 -310.242712)
			(xy 107.33151 -310.242712) (xy 107.331001 -310.270598) (xy 107.322881 -310.325774) (xy 107.306813 -310.379181)
			(xy 107.283141 -310.429678) (xy 107.252368 -310.476191) (xy 107.215151 -310.517728) (xy 107.172283 -310.553403)
			(xy 107.124677 -310.582457) (xy 107.073348 -310.604269) (xy 107.019391 -310.618375) (xy 106.963954 -310.624475)
			(xy 106.90822 -310.622438) (xy 106.853377 -310.612308) (xy 106.800593 -310.594301) (xy 106.750993 -310.5688)
			(xy 106.705635 -310.536349) (xy 106.665486 -310.49764) (xy 106.6314 -310.453497) (xy 106.604104 -310.404862)
			(xy 106.584181 -310.352771) (xy 106.572055 -310.298334) (xy 106.567984 -310.242712) (xy 106.31551 -310.242712)
			(xy 106.315001 -310.270598) (xy 106.306881 -310.325774) (xy 106.290813 -310.379181) (xy 106.267141 -310.429678)
			(xy 106.236368 -310.476191) (xy 106.199151 -310.517728) (xy 106.156283 -310.553403) (xy 106.108677 -310.582457)
			(xy 106.057348 -310.604269) (xy 106.003391 -310.618375) (xy 105.947954 -310.624475) (xy 105.89222 -310.622438)
			(xy 105.837377 -310.612308) (xy 105.784593 -310.594301) (xy 105.734993 -310.5688) (xy 105.689635 -310.536349)
			(xy 105.649486 -310.49764) (xy 105.6154 -310.453497) (xy 105.588104 -310.404862) (xy 105.568181 -310.352771)
			(xy 105.556055 -310.298334) (xy 105.551984 -310.242712) (xy 105.29951 -310.242712) (xy 105.299001 -310.270598)
			(xy 105.290881 -310.325774) (xy 105.274813 -310.379181) (xy 105.251141 -310.429678) (xy 105.220368 -310.476191)
			(xy 105.183151 -310.517728) (xy 105.140283 -310.553403) (xy 105.092677 -310.582457) (xy 105.041348 -310.604269)
			(xy 104.987391 -310.618375) (xy 104.931954 -310.624475) (xy 104.87622 -310.622438) (xy 104.821377 -310.612308)
			(xy 104.768593 -310.594301) (xy 104.718993 -310.5688) (xy 104.673635 -310.536349) (xy 104.633486 -310.49764)
			(xy 104.5994 -310.453497) (xy 104.572104 -310.404862) (xy 104.552181 -310.352771) (xy 104.540055 -310.298334)
			(xy 104.535984 -310.242712) (xy 104.28351 -310.242712) (xy 104.283001 -310.270598) (xy 104.274881 -310.325774)
			(xy 104.258813 -310.379181) (xy 104.235141 -310.429678) (xy 104.204368 -310.476191) (xy 104.167151 -310.517728)
			(xy 104.124283 -310.553403) (xy 104.076677 -310.582457) (xy 104.025348 -310.604269) (xy 103.971391 -310.618375)
			(xy 103.915954 -310.624475) (xy 103.86022 -310.622438) (xy 103.805377 -310.612308) (xy 103.752593 -310.594301)
			(xy 103.702993 -310.5688) (xy 103.657635 -310.536349) (xy 103.617486 -310.49764) (xy 103.5834 -310.453497)
			(xy 103.556104 -310.404862) (xy 103.536181 -310.352771) (xy 103.524055 -310.298334) (xy 103.519984 -310.242712)
			(xy 103.26751 -310.242712) (xy 103.267001 -310.270598) (xy 103.258881 -310.325774) (xy 103.242813 -310.379181)
			(xy 103.219141 -310.429678) (xy 103.188368 -310.476191) (xy 103.151151 -310.517728) (xy 103.108283 -310.553403)
			(xy 103.060677 -310.582457) (xy 103.009348 -310.604269) (xy 102.955391 -310.618375) (xy 102.899954 -310.624475)
			(xy 102.84422 -310.622438) (xy 102.789377 -310.612308) (xy 102.736593 -310.594301) (xy 102.686993 -310.5688)
			(xy 102.641635 -310.536349) (xy 102.601486 -310.49764) (xy 102.5674 -310.453497) (xy 102.540104 -310.404862)
			(xy 102.520181 -310.352771) (xy 102.508055 -310.298334) (xy 102.503984 -310.242712) (xy 102.25151 -310.242712)
			(xy 102.251001 -310.270598) (xy 102.242881 -310.325774) (xy 102.226813 -310.379181) (xy 102.203141 -310.429678)
			(xy 102.172368 -310.476191) (xy 102.135151 -310.517728) (xy 102.092283 -310.553403) (xy 102.044677 -310.582457)
			(xy 101.993348 -310.604269) (xy 101.939391 -310.618375) (xy 101.883954 -310.624475) (xy 101.82822 -310.622438)
			(xy 101.773377 -310.612308) (xy 101.720593 -310.594301) (xy 101.670993 -310.5688) (xy 101.625635 -310.536349)
			(xy 101.585486 -310.49764) (xy 101.5514 -310.453497) (xy 101.524104 -310.404862) (xy 101.504181 -310.352771)
			(xy 101.492055 -310.298334) (xy 101.487984 -310.242712) (xy 101.23551 -310.242712) (xy 101.235001 -310.270598)
			(xy 101.226881 -310.325774) (xy 101.210813 -310.379181) (xy 101.187141 -310.429678) (xy 101.156368 -310.476191)
			(xy 101.119151 -310.517728) (xy 101.076283 -310.553403) (xy 101.028677 -310.582457) (xy 100.977348 -310.604269)
			(xy 100.923391 -310.618375) (xy 100.867954 -310.624475) (xy 100.81222 -310.622438) (xy 100.757377 -310.612308)
			(xy 100.704593 -310.594301) (xy 100.654993 -310.5688) (xy 100.609635 -310.536349) (xy 100.569486 -310.49764)
			(xy 100.5354 -310.453497) (xy 100.508104 -310.404862) (xy 100.488181 -310.352771) (xy 100.476055 -310.298334)
			(xy 100.471984 -310.242712) (xy 83.690453 -310.242712) (xy 83.681472 -310.269613) (xy 83.658601 -310.31319)
			(xy 83.629036 -310.352534) (xy 83.593543 -310.386626) (xy 83.55304 -310.414582) (xy 83.508578 -310.43568)
			(xy 83.461307 -310.449372) (xy 83.412452 -310.455304) (xy 83.363277 -310.453323) (xy 83.315058 -310.443479)
			(xy 83.269042 -310.426027) (xy 83.226421 -310.40142) (xy 83.1883 -310.370295) (xy 83.155665 -310.333458)
			(xy 83.129362 -310.291862) (xy 83.110071 -310.246586) (xy 83.098294 -310.198802) (xy 83.094334 -310.149748)
			(xy 82.755232 -310.149748) (xy 82.754737 -310.174355) (xy 82.746842 -310.222932) (xy 82.731258 -310.269613)
			(xy 82.708387 -310.31319) (xy 82.678822 -310.352534) (xy 82.643329 -310.386626) (xy 82.602826 -310.414582)
			(xy 82.558364 -310.43568) (xy 82.511093 -310.449372) (xy 82.462238 -310.455304) (xy 82.413063 -310.453323)
			(xy 82.364844 -310.443479) (xy 82.318828 -310.426027) (xy 82.276207 -310.40142) (xy 82.238086 -310.370295)
			(xy 82.205451 -310.333458) (xy 82.179148 -310.291862) (xy 82.159857 -310.246586) (xy 82.14808 -310.198802)
			(xy 82.14412 -310.149748) (xy 81.805272 -310.149748) (xy 81.804777 -310.174355) (xy 81.796882 -310.222932)
			(xy 81.781298 -310.269613) (xy 81.758427 -310.31319) (xy 81.728862 -310.352534) (xy 81.693369 -310.386626)
			(xy 81.652866 -310.414582) (xy 81.608404 -310.43568) (xy 81.561133 -310.449372) (xy 81.512278 -310.455304)
			(xy 81.463103 -310.453323) (xy 81.414884 -310.443479) (xy 81.368868 -310.426027) (xy 81.326247 -310.40142)
			(xy 81.288126 -310.370295) (xy 81.255491 -310.333458) (xy 81.229188 -310.291862) (xy 81.209897 -310.246586)
			(xy 81.19812 -310.198802) (xy 81.19416 -310.149748) (xy 80.855058 -310.149748) (xy 80.854563 -310.174355)
			(xy 80.846668 -310.222932) (xy 80.831084 -310.269613) (xy 80.808213 -310.31319) (xy 80.778648 -310.352534)
			(xy 80.743155 -310.386626) (xy 80.702652 -310.414582) (xy 80.65819 -310.43568) (xy 80.610919 -310.449372)
			(xy 80.562064 -310.455304) (xy 80.512889 -310.453323) (xy 80.46467 -310.443479) (xy 80.418654 -310.426027)
			(xy 80.376033 -310.40142) (xy 80.337912 -310.370295) (xy 80.305277 -310.333458) (xy 80.278974 -310.291862)
			(xy 80.259683 -310.246586) (xy 80.247906 -310.198802) (xy 80.243946 -310.149748) (xy 79.905098 -310.149748)
			(xy 79.904603 -310.174355) (xy 79.896708 -310.222932) (xy 79.881124 -310.269613) (xy 79.858253 -310.31319)
			(xy 79.828688 -310.352534) (xy 79.793195 -310.386626) (xy 79.752692 -310.414582) (xy 79.70823 -310.43568)
			(xy 79.660959 -310.449372) (xy 79.612104 -310.455304) (xy 79.562929 -310.453323) (xy 79.51471 -310.443479)
			(xy 79.468694 -310.426027) (xy 79.426073 -310.40142) (xy 79.387952 -310.370295) (xy 79.355317 -310.333458)
			(xy 79.329014 -310.291862) (xy 79.309723 -310.246586) (xy 79.297946 -310.198802) (xy 79.293986 -310.149748)
			(xy 78.955138 -310.149748) (xy 78.954643 -310.174355) (xy 78.946748 -310.222932) (xy 78.931164 -310.269613)
			(xy 78.908293 -310.31319) (xy 78.878728 -310.352534) (xy 78.843235 -310.386626) (xy 78.802732 -310.414582)
			(xy 78.75827 -310.43568) (xy 78.710999 -310.449372) (xy 78.662144 -310.455304) (xy 78.612969 -310.453323)
			(xy 78.56475 -310.443479) (xy 78.518734 -310.426027) (xy 78.476113 -310.40142) (xy 78.437992 -310.370295)
			(xy 78.405357 -310.333458) (xy 78.379054 -310.291862) (xy 78.359763 -310.246586) (xy 78.347986 -310.198802)
			(xy 78.344026 -310.149748) (xy 78.005178 -310.149748) (xy 78.004683 -310.174355) (xy 77.996788 -310.222932)
			(xy 77.981204 -310.269613) (xy 77.958333 -310.31319) (xy 77.928768 -310.352534) (xy 77.893275 -310.386626)
			(xy 77.852772 -310.414582) (xy 77.80831 -310.43568) (xy 77.761039 -310.449372) (xy 77.712184 -310.455304)
			(xy 77.663009 -310.453323) (xy 77.61479 -310.443479) (xy 77.568774 -310.426027) (xy 77.526153 -310.40142)
			(xy 77.488032 -310.370295) (xy 77.455397 -310.333458) (xy 77.429094 -310.291862) (xy 77.409803 -310.246586)
			(xy 77.398026 -310.198802) (xy 77.394066 -310.149748) (xy 77.055218 -310.149748) (xy 77.054723 -310.174355)
			(xy 77.046828 -310.222932) (xy 77.031244 -310.269613) (xy 77.008373 -310.31319) (xy 76.978808 -310.352534)
			(xy 76.943315 -310.386626) (xy 76.902812 -310.414582) (xy 76.85835 -310.43568) (xy 76.811079 -310.449372)
			(xy 76.762224 -310.455304) (xy 76.713049 -310.453323) (xy 76.66483 -310.443479) (xy 76.618814 -310.426027)
			(xy 76.576193 -310.40142) (xy 76.538072 -310.370295) (xy 76.505437 -310.333458) (xy 76.479134 -310.291862)
			(xy 76.459843 -310.246586) (xy 76.448066 -310.198802) (xy 76.444106 -310.149748) (xy 76.105258 -310.149748)
			(xy 76.104763 -310.174355) (xy 76.096868 -310.222932) (xy 76.081284 -310.269613) (xy 76.058413 -310.31319)
			(xy 76.028848 -310.352534) (xy 75.993355 -310.386626) (xy 75.952852 -310.414582) (xy 75.90839 -310.43568)
			(xy 75.861119 -310.449372) (xy 75.812264 -310.455304) (xy 75.763089 -310.453323) (xy 75.71487 -310.443479)
			(xy 75.668854 -310.426027) (xy 75.626233 -310.40142) (xy 75.588112 -310.370295) (xy 75.555477 -310.333458)
			(xy 75.529174 -310.291862) (xy 75.509883 -310.246586) (xy 75.498106 -310.198802) (xy 75.494146 -310.149748)
			(xy 75.155298 -310.149748) (xy 75.154803 -310.174355) (xy 75.146908 -310.222932) (xy 75.131324 -310.269613)
			(xy 75.108453 -310.31319) (xy 75.078888 -310.352534) (xy 75.043395 -310.386626) (xy 75.002892 -310.414582)
			(xy 74.95843 -310.43568) (xy 74.911159 -310.449372) (xy 74.862304 -310.455304) (xy 74.813129 -310.453323)
			(xy 74.76491 -310.443479) (xy 74.718894 -310.426027) (xy 74.676273 -310.40142) (xy 74.638152 -310.370295)
			(xy 74.605517 -310.333458) (xy 74.579214 -310.291862) (xy 74.559923 -310.246586) (xy 74.548146 -310.198802)
			(xy 74.544186 -310.149748) (xy 74.205084 -310.149748) (xy 74.204589 -310.174355) (xy 74.196694 -310.222932)
			(xy 74.18111 -310.269613) (xy 74.158239 -310.31319) (xy 74.128674 -310.352534) (xy 74.093181 -310.386626)
			(xy 74.052678 -310.414582) (xy 74.008216 -310.43568) (xy 73.960945 -310.449372) (xy 73.91209 -310.455304)
			(xy 73.862915 -310.453323) (xy 73.814696 -310.443479) (xy 73.76868 -310.426027) (xy 73.726059 -310.40142)
			(xy 73.687938 -310.370295) (xy 73.655303 -310.333458) (xy 73.629 -310.291862) (xy 73.609709 -310.246586)
			(xy 73.597932 -310.198802) (xy 73.593972 -310.149748) (xy 73.255124 -310.149748) (xy 73.254629 -310.174355)
			(xy 73.246734 -310.222932) (xy 73.23115 -310.269613) (xy 73.208279 -310.31319) (xy 73.178714 -310.352534)
			(xy 73.143221 -310.386626) (xy 73.102718 -310.414582) (xy 73.058256 -310.43568) (xy 73.010985 -310.449372)
			(xy 72.96213 -310.455304) (xy 72.912955 -310.453323) (xy 72.864736 -310.443479) (xy 72.81872 -310.426027)
			(xy 72.776099 -310.40142) (xy 72.737978 -310.370295) (xy 72.705343 -310.333458) (xy 72.67904 -310.291862)
			(xy 72.659749 -310.246586) (xy 72.647972 -310.198802) (xy 72.644012 -310.149748) (xy 72.305164 -310.149748)
			(xy 72.304669 -310.174355) (xy 72.296774 -310.222932) (xy 72.28119 -310.269613) (xy 72.258319 -310.31319)
			(xy 72.228754 -310.352534) (xy 72.193261 -310.386626) (xy 72.152758 -310.414582) (xy 72.108296 -310.43568)
			(xy 72.061025 -310.449372) (xy 72.01217 -310.455304) (xy 71.962995 -310.453323) (xy 71.914776 -310.443479)
			(xy 71.86876 -310.426027) (xy 71.826139 -310.40142) (xy 71.788018 -310.370295) (xy 71.755383 -310.333458)
			(xy 71.72908 -310.291862) (xy 71.709789 -310.246586) (xy 71.698012 -310.198802) (xy 71.694052 -310.149748)
			(xy 71.355204 -310.149748) (xy 71.354709 -310.174355) (xy 71.346814 -310.222932) (xy 71.33123 -310.269613)
			(xy 71.308359 -310.31319) (xy 71.278794 -310.352534) (xy 71.243301 -310.386626) (xy 71.202798 -310.414582)
			(xy 71.158336 -310.43568) (xy 71.111065 -310.449372) (xy 71.06221 -310.455304) (xy 71.013035 -310.453323)
			(xy 70.964816 -310.443479) (xy 70.9188 -310.426027) (xy 70.876179 -310.40142) (xy 70.838058 -310.370295)
			(xy 70.805423 -310.333458) (xy 70.77912 -310.291862) (xy 70.759829 -310.246586) (xy 70.748052 -310.198802)
			(xy 70.744092 -310.149748) (xy 70.405244 -310.149748) (xy 70.404749 -310.174355) (xy 70.396854 -310.222932)
			(xy 70.38127 -310.269613) (xy 70.358399 -310.31319) (xy 70.328834 -310.352534) (xy 70.293341 -310.386626)
			(xy 70.252838 -310.414582) (xy 70.208376 -310.43568) (xy 70.161105 -310.449372) (xy 70.11225 -310.455304)
			(xy 70.063075 -310.453323) (xy 70.014856 -310.443479) (xy 69.96884 -310.426027) (xy 69.926219 -310.40142)
			(xy 69.888098 -310.370295) (xy 69.855463 -310.333458) (xy 69.82916 -310.291862) (xy 69.809869 -310.246586)
			(xy 69.798092 -310.198802) (xy 69.794132 -310.149748) (xy 69.455284 -310.149748) (xy 69.454789 -310.174355)
			(xy 69.446894 -310.222932) (xy 69.43131 -310.269613) (xy 69.408439 -310.31319) (xy 69.378874 -310.352534)
			(xy 69.343381 -310.386626) (xy 69.302878 -310.414582) (xy 69.258416 -310.43568) (xy 69.211145 -310.449372)
			(xy 69.16229 -310.455304) (xy 69.113115 -310.453323) (xy 69.064896 -310.443479) (xy 69.01888 -310.426027)
			(xy 68.976259 -310.40142) (xy 68.938138 -310.370295) (xy 68.905503 -310.333458) (xy 68.8792 -310.291862)
			(xy 68.859909 -310.246586) (xy 68.848132 -310.198802) (xy 68.844172 -310.149748) (xy 68.50507 -310.149748)
			(xy 68.504575 -310.174355) (xy 68.49668 -310.222932) (xy 68.481096 -310.269613) (xy 68.458225 -310.31319)
			(xy 68.42866 -310.352534) (xy 68.393167 -310.386626) (xy 68.352664 -310.414582) (xy 68.308202 -310.43568)
			(xy 68.260931 -310.449372) (xy 68.212076 -310.455304) (xy 68.162901 -310.453323) (xy 68.114682 -310.443479)
			(xy 68.068666 -310.426027) (xy 68.026045 -310.40142) (xy 67.987924 -310.370295) (xy 67.955289 -310.333458)
			(xy 67.928986 -310.291862) (xy 67.909695 -310.246586) (xy 67.897918 -310.198802) (xy 67.893958 -310.149748)
			(xy 67.55511 -310.149748) (xy 67.554615 -310.174355) (xy 67.54672 -310.222932) (xy 67.531136 -310.269613)
			(xy 67.508265 -310.31319) (xy 67.4787 -310.352534) (xy 67.443207 -310.386626) (xy 67.402704 -310.414582)
			(xy 67.358242 -310.43568) (xy 67.310971 -310.449372) (xy 67.262116 -310.455304) (xy 67.212941 -310.453323)
			(xy 67.164722 -310.443479) (xy 67.118706 -310.426027) (xy 67.076085 -310.40142) (xy 67.037964 -310.370295)
			(xy 67.005329 -310.333458) (xy 66.979026 -310.291862) (xy 66.959735 -310.246586) (xy 66.947958 -310.198802)
			(xy 66.943998 -310.149748) (xy 66.60515 -310.149748) (xy 66.604655 -310.174355) (xy 66.59676 -310.222932)
			(xy 66.581176 -310.269613) (xy 66.558305 -310.31319) (xy 66.52874 -310.352534) (xy 66.493247 -310.386626)
			(xy 66.452744 -310.414582) (xy 66.408282 -310.43568) (xy 66.361011 -310.449372) (xy 66.312156 -310.455304)
			(xy 66.262981 -310.453323) (xy 66.214762 -310.443479) (xy 66.168746 -310.426027) (xy 66.126125 -310.40142)
			(xy 66.088004 -310.370295) (xy 66.055369 -310.333458) (xy 66.029066 -310.291862) (xy 66.009775 -310.246586)
			(xy 65.997998 -310.198802) (xy 65.994038 -310.149748) (xy 65.65519 -310.149748) (xy 65.654695 -310.174355)
			(xy 65.6468 -310.222932) (xy 65.631216 -310.269613) (xy 65.608345 -310.31319) (xy 65.57878 -310.352534)
			(xy 65.543287 -310.386626) (xy 65.502784 -310.414582) (xy 65.458322 -310.43568) (xy 65.411051 -310.449372)
			(xy 65.362196 -310.455304) (xy 65.313021 -310.453323) (xy 65.264802 -310.443479) (xy 65.218786 -310.426027)
			(xy 65.176165 -310.40142) (xy 65.138044 -310.370295) (xy 65.105409 -310.333458) (xy 65.079106 -310.291862)
			(xy 65.059815 -310.246586) (xy 65.048038 -310.198802) (xy 65.044078 -310.149748) (xy 64.70523 -310.149748)
			(xy 64.704735 -310.174355) (xy 64.69684 -310.222932) (xy 64.681256 -310.269613) (xy 64.658385 -310.31319)
			(xy 64.62882 -310.352534) (xy 64.593327 -310.386626) (xy 64.552824 -310.414582) (xy 64.508362 -310.43568)
			(xy 64.461091 -310.449372) (xy 64.412236 -310.455304) (xy 64.363061 -310.453323) (xy 64.314842 -310.443479)
			(xy 64.268826 -310.426027) (xy 64.226205 -310.40142) (xy 64.188084 -310.370295) (xy 64.155449 -310.333458)
			(xy 64.129146 -310.291862) (xy 64.109855 -310.246586) (xy 64.098078 -310.198802) (xy 64.094118 -310.149748)
			(xy 63.75527 -310.149748) (xy 63.754775 -310.174355) (xy 63.74688 -310.222932) (xy 63.731296 -310.269613)
			(xy 63.708425 -310.31319) (xy 63.67886 -310.352534) (xy 63.643367 -310.386626) (xy 63.602864 -310.414582)
			(xy 63.558402 -310.43568) (xy 63.511131 -310.449372) (xy 63.462276 -310.455304) (xy 63.413101 -310.453323)
			(xy 63.364882 -310.443479) (xy 63.318866 -310.426027) (xy 63.276245 -310.40142) (xy 63.238124 -310.370295)
			(xy 63.205489 -310.333458) (xy 63.179186 -310.291862) (xy 63.159895 -310.246586) (xy 63.148118 -310.198802)
			(xy 63.144158 -310.149748) (xy 62.805056 -310.149748) (xy 62.804561 -310.174355) (xy 62.796666 -310.222932)
			(xy 62.781082 -310.269613) (xy 62.758211 -310.31319) (xy 62.728646 -310.352534) (xy 62.693153 -310.386626)
			(xy 62.65265 -310.414582) (xy 62.608188 -310.43568) (xy 62.560917 -310.449372) (xy 62.512062 -310.455304)
			(xy 62.462887 -310.453323) (xy 62.414668 -310.443479) (xy 62.368652 -310.426027) (xy 62.326031 -310.40142)
			(xy 62.28791 -310.370295) (xy 62.255275 -310.333458) (xy 62.228972 -310.291862) (xy 62.209681 -310.246586)
			(xy 62.197904 -310.198802) (xy 62.193944 -310.149748) (xy 61.855096 -310.149748) (xy 61.854601 -310.174355)
			(xy 61.846706 -310.222932) (xy 61.831122 -310.269613) (xy 61.808251 -310.31319) (xy 61.778686 -310.352534)
			(xy 61.743193 -310.386626) (xy 61.70269 -310.414582) (xy 61.658228 -310.43568) (xy 61.610957 -310.449372)
			(xy 61.562102 -310.455304) (xy 61.512927 -310.453323) (xy 61.464708 -310.443479) (xy 61.418692 -310.426027)
			(xy 61.376071 -310.40142) (xy 61.33795 -310.370295) (xy 61.305315 -310.333458) (xy 61.279012 -310.291862)
			(xy 61.259721 -310.246586) (xy 61.247944 -310.198802) (xy 61.243984 -310.149748) (xy 60.905136 -310.149748)
			(xy 60.904641 -310.174355) (xy 60.896746 -310.222932) (xy 60.881162 -310.269613) (xy 60.858291 -310.31319)
			(xy 60.828726 -310.352534) (xy 60.793233 -310.386626) (xy 60.75273 -310.414582) (xy 60.708268 -310.43568)
			(xy 60.660997 -310.449372) (xy 60.612142 -310.455304) (xy 60.562967 -310.453323) (xy 60.514748 -310.443479)
			(xy 60.468732 -310.426027) (xy 60.426111 -310.40142) (xy 60.38799 -310.370295) (xy 60.355355 -310.333458)
			(xy 60.329052 -310.291862) (xy 60.309761 -310.246586) (xy 60.297984 -310.198802) (xy 60.294024 -310.149748)
			(xy 59.955176 -310.149748) (xy 59.954681 -310.174355) (xy 59.946786 -310.222932) (xy 59.931202 -310.269613)
			(xy 59.908331 -310.31319) (xy 59.878766 -310.352534) (xy 59.843273 -310.386626) (xy 59.80277 -310.414582)
			(xy 59.758308 -310.43568) (xy 59.711037 -310.449372) (xy 59.662182 -310.455304) (xy 59.613007 -310.453323)
			(xy 59.564788 -310.443479) (xy 59.518772 -310.426027) (xy 59.476151 -310.40142) (xy 59.43803 -310.370295)
			(xy 59.405395 -310.333458) (xy 59.379092 -310.291862) (xy 59.359801 -310.246586) (xy 59.348024 -310.198802)
			(xy 59.344064 -310.149748) (xy 59.005216 -310.149748) (xy 59.004721 -310.174355) (xy 58.996826 -310.222932)
			(xy 58.981242 -310.269613) (xy 58.958371 -310.31319) (xy 58.928806 -310.352534) (xy 58.893313 -310.386626)
			(xy 58.85281 -310.414582) (xy 58.808348 -310.43568) (xy 58.761077 -310.449372) (xy 58.712222 -310.455304)
			(xy 58.663047 -310.453323) (xy 58.614828 -310.443479) (xy 58.568812 -310.426027) (xy 58.526191 -310.40142)
			(xy 58.48807 -310.370295) (xy 58.455435 -310.333458) (xy 58.429132 -310.291862) (xy 58.409841 -310.246586)
			(xy 58.398064 -310.198802) (xy 58.394104 -310.149748) (xy 58.055256 -310.149748) (xy 58.054761 -310.174355)
			(xy 58.046866 -310.222932) (xy 58.031282 -310.269613) (xy 58.008411 -310.31319) (xy 57.978846 -310.352534)
			(xy 57.943353 -310.386626) (xy 57.90285 -310.414582) (xy 57.858388 -310.43568) (xy 57.811117 -310.449372)
			(xy 57.762262 -310.455304) (xy 57.713087 -310.453323) (xy 57.664868 -310.443479) (xy 57.618852 -310.426027)
			(xy 57.576231 -310.40142) (xy 57.53811 -310.370295) (xy 57.505475 -310.333458) (xy 57.479172 -310.291862)
			(xy 57.459881 -310.246586) (xy 57.448104 -310.198802) (xy 57.444144 -310.149748) (xy 57.105296 -310.149748)
			(xy 57.104801 -310.174355) (xy 57.096906 -310.222932) (xy 57.081322 -310.269613) (xy 57.058451 -310.31319)
			(xy 57.028886 -310.352534) (xy 56.993393 -310.386626) (xy 56.95289 -310.414582) (xy 56.908428 -310.43568)
			(xy 56.861157 -310.449372) (xy 56.812302 -310.455304) (xy 56.763127 -310.453323) (xy 56.714908 -310.443479)
			(xy 56.668892 -310.426027) (xy 56.626271 -310.40142) (xy 56.58815 -310.370295) (xy 56.555515 -310.333458)
			(xy 56.529212 -310.291862) (xy 56.509921 -310.246586) (xy 56.498144 -310.198802) (xy 56.494184 -310.149748)
			(xy 56.155082 -310.149748) (xy 56.154587 -310.174355) (xy 56.146692 -310.222932) (xy 56.131108 -310.269613)
			(xy 56.108237 -310.31319) (xy 56.078672 -310.352534) (xy 56.043179 -310.386626) (xy 56.002676 -310.414582)
			(xy 55.958214 -310.43568) (xy 55.910943 -310.449372) (xy 55.862088 -310.455304) (xy 55.812913 -310.453323)
			(xy 55.764694 -310.443479) (xy 55.718678 -310.426027) (xy 55.676057 -310.40142) (xy 55.637936 -310.370295)
			(xy 55.605301 -310.333458) (xy 55.578998 -310.291862) (xy 55.559707 -310.246586) (xy 55.54793 -310.198802)
			(xy 55.54397 -310.149748) (xy 55.205122 -310.149748) (xy 55.204627 -310.174355) (xy 55.196732 -310.222932)
			(xy 55.181148 -310.269613) (xy 55.158277 -310.31319) (xy 55.128712 -310.352534) (xy 55.093219 -310.386626)
			(xy 55.052716 -310.414582) (xy 55.008254 -310.43568) (xy 54.960983 -310.449372) (xy 54.912128 -310.455304)
			(xy 54.862953 -310.453323) (xy 54.814734 -310.443479) (xy 54.768718 -310.426027) (xy 54.726097 -310.40142)
			(xy 54.687976 -310.370295) (xy 54.655341 -310.333458) (xy 54.629038 -310.291862) (xy 54.609747 -310.246586)
			(xy 54.59797 -310.198802) (xy 54.59401 -310.149748) (xy 54.255162 -310.149748) (xy 54.254667 -310.174355)
			(xy 54.246772 -310.222932) (xy 54.231188 -310.269613) (xy 54.208317 -310.31319) (xy 54.178752 -310.352534)
			(xy 54.143259 -310.386626) (xy 54.102756 -310.414582) (xy 54.058294 -310.43568) (xy 54.011023 -310.449372)
			(xy 53.962168 -310.455304) (xy 53.912993 -310.453323) (xy 53.864774 -310.443479) (xy 53.818758 -310.426027)
			(xy 53.776137 -310.40142) (xy 53.738016 -310.370295) (xy 53.705381 -310.333458) (xy 53.679078 -310.291862)
			(xy 53.659787 -310.246586) (xy 53.64801 -310.198802) (xy 53.64405 -310.149748) (xy 53.305202 -310.149748)
			(xy 53.304707 -310.174355) (xy 53.296812 -310.222932) (xy 53.281228 -310.269613) (xy 53.258357 -310.31319)
			(xy 53.228792 -310.352534) (xy 53.193299 -310.386626) (xy 53.152796 -310.414582) (xy 53.108334 -310.43568)
			(xy 53.061063 -310.449372) (xy 53.012208 -310.455304) (xy 52.963033 -310.453323) (xy 52.914814 -310.443479)
			(xy 52.868798 -310.426027) (xy 52.826177 -310.40142) (xy 52.788056 -310.370295) (xy 52.755421 -310.333458)
			(xy 52.729118 -310.291862) (xy 52.709827 -310.246586) (xy 52.69805 -310.198802) (xy 52.69409 -310.149748)
			(xy 52.355242 -310.149748) (xy 52.354747 -310.174355) (xy 52.346852 -310.222932) (xy 52.331268 -310.269613)
			(xy 52.308397 -310.31319) (xy 52.278832 -310.352534) (xy 52.243339 -310.386626) (xy 52.202836 -310.414582)
			(xy 52.158374 -310.43568) (xy 52.111103 -310.449372) (xy 52.062248 -310.455304) (xy 52.013073 -310.453323)
			(xy 51.964854 -310.443479) (xy 51.918838 -310.426027) (xy 51.876217 -310.40142) (xy 51.838096 -310.370295)
			(xy 51.805461 -310.333458) (xy 51.779158 -310.291862) (xy 51.759867 -310.246586) (xy 51.74809 -310.198802)
			(xy 51.74413 -310.149748) (xy 51.405282 -310.149748) (xy 51.404787 -310.174355) (xy 51.396892 -310.222932)
			(xy 51.381308 -310.269613) (xy 51.358437 -310.31319) (xy 51.328872 -310.352534) (xy 51.293379 -310.386626)
			(xy 51.252876 -310.414582) (xy 51.208414 -310.43568) (xy 51.161143 -310.449372) (xy 51.112288 -310.455304)
			(xy 51.063113 -310.453323) (xy 51.014894 -310.443479) (xy 50.968878 -310.426027) (xy 50.926257 -310.40142)
			(xy 50.888136 -310.370295) (xy 50.855501 -310.333458) (xy 50.829198 -310.291862) (xy 50.809907 -310.246586)
			(xy 50.79813 -310.198802) (xy 50.79417 -310.149748) (xy 50.455068 -310.149748) (xy 50.454573 -310.174355)
			(xy 50.446678 -310.222932) (xy 50.431094 -310.269613) (xy 50.408223 -310.31319) (xy 50.378658 -310.352534)
			(xy 50.343165 -310.386626) (xy 50.302662 -310.414582) (xy 50.2582 -310.43568) (xy 50.210929 -310.449372)
			(xy 50.162074 -310.455304) (xy 50.112899 -310.453323) (xy 50.06468 -310.443479) (xy 50.018664 -310.426027)
			(xy 49.976043 -310.40142) (xy 49.937922 -310.370295) (xy 49.905287 -310.333458) (xy 49.878984 -310.291862)
			(xy 49.859693 -310.246586) (xy 49.847916 -310.198802) (xy 49.843956 -310.149748) (xy 49.505579 -310.149748)
			(xy 49.501413 -310.20003) (xy 49.489015 -310.248988) (xy 49.468728 -310.295237) (xy 49.441106 -310.337516)
			(xy 49.406901 -310.374672) (xy 49.367047 -310.405691) (xy 49.322632 -310.429728) (xy 49.274865 -310.446126)
			(xy 49.225051 -310.454439) (xy 49.1998 -310.455056) (xy 49.190696 -310.454959) (xy 49.172522 -310.453818)
			(xy 49.163478 -310.45277) (xy 49.151286 -310.4515) (xy 49.128934 -310.459374) (xy 49.056036 -310.535828)
			(xy 49.048924 -310.558434) (xy 49.050956 -310.570372) (xy 49.053085 -310.58386) (xy 49.055372 -310.611074)
			(xy 49.055528 -310.624728) (xy 49.055528 -310.68518) (xy 89.842592 -310.68518) (xy 89.846663 -310.629558)
			(xy 89.858789 -310.575121) (xy 89.878712 -310.52303) (xy 89.906008 -310.474395) (xy 89.940094 -310.430252)
			(xy 89.980243 -310.391543) (xy 90.025601 -310.359092) (xy 90.075201 -310.333591) (xy 90.127985 -310.315584)
			(xy 90.182828 -310.305454) (xy 90.238562 -310.303417) (xy 90.293999 -310.309517) (xy 90.347956 -310.323623)
			(xy 90.399285 -310.345435) (xy 90.446891 -310.374489) (xy 90.489759 -310.410164) (xy 90.526976 -310.451701)
			(xy 90.557749 -310.498214) (xy 90.581421 -310.548711) (xy 90.597489 -310.602118) (xy 90.605609 -310.657294)
			(xy 90.606118 -310.68518) (xy 90.605609 -310.713066) (xy 90.597489 -310.768242) (xy 90.581421 -310.821649)
			(xy 90.557749 -310.872146) (xy 90.526976 -310.918659) (xy 90.489759 -310.960196) (xy 90.446891 -310.995871)
			(xy 90.399285 -311.024925) (xy 90.347956 -311.046737) (xy 90.293999 -311.060843) (xy 90.238562 -311.066943)
			(xy 90.182828 -311.064906) (xy 90.127985 -311.054776) (xy 90.075201 -311.036769) (xy 90.025601 -311.011268)
			(xy 89.980243 -310.978817) (xy 89.940094 -310.940108) (xy 89.906008 -310.895965) (xy 89.878712 -310.84733)
			(xy 89.858789 -310.795239) (xy 89.846663 -310.740802) (xy 89.842592 -310.68518) (xy 49.055528 -310.68518)
			(xy 49.055528 -310.69534) (xy 49.056095 -310.70603) (xy 49.064762 -310.725577) (xy 49.072292 -310.733186)
			(xy 49.136554 -310.790844) (xy 49.156874 -310.797448) (xy 49.167796 -310.796432) (xy 49.1998 -310.794654)
			(xy 49.225058 -310.795176) (xy 49.274886 -310.803491) (xy 49.322666 -310.819893) (xy 49.367094 -310.843937)
			(xy 49.406959 -310.874965) (xy 49.441174 -310.912131) (xy 49.468804 -310.954422) (xy 49.489096 -311.000684)
			(xy 49.501497 -311.049656) (xy 49.505666 -311.099962) (xy 49.843956 -311.099962) (xy 49.847916 -311.050908)
			(xy 49.859693 -311.003124) (xy 49.878984 -310.957848) (xy 49.905287 -310.916252) (xy 49.937922 -310.879415)
			(xy 49.976043 -310.84829) (xy 50.018664 -310.823683) (xy 50.06468 -310.806231) (xy 50.112899 -310.796387)
			(xy 50.162074 -310.794406) (xy 50.210929 -310.800338) (xy 50.2582 -310.81403) (xy 50.302662 -310.835128)
			(xy 50.343165 -310.863084) (xy 50.378658 -310.897176) (xy 50.408223 -310.93652) (xy 50.431094 -310.980097)
			(xy 50.446678 -311.026778) (xy 50.454573 -311.075355) (xy 50.455068 -311.099962) (xy 50.79417 -311.099962)
			(xy 50.79813 -311.050908) (xy 50.809907 -311.003124) (xy 50.829198 -310.957848) (xy 50.855501 -310.916252)
			(xy 50.888136 -310.879415) (xy 50.926257 -310.84829) (xy 50.968878 -310.823683) (xy 51.014894 -310.806231)
			(xy 51.063113 -310.796387) (xy 51.112288 -310.794406) (xy 51.161143 -310.800338) (xy 51.208414 -310.81403)
			(xy 51.252876 -310.835128) (xy 51.293379 -310.863084) (xy 51.328872 -310.897176) (xy 51.358437 -310.93652)
			(xy 51.381308 -310.980097) (xy 51.396892 -311.026778) (xy 51.404787 -311.075355) (xy 51.405282 -311.099962)
			(xy 51.74413 -311.099962) (xy 51.74809 -311.050908) (xy 51.759867 -311.003124) (xy 51.779158 -310.957848)
			(xy 51.805461 -310.916252) (xy 51.838096 -310.879415) (xy 51.876217 -310.84829) (xy 51.918838 -310.823683)
			(xy 51.964854 -310.806231) (xy 52.013073 -310.796387) (xy 52.062248 -310.794406) (xy 52.111103 -310.800338)
			(xy 52.158374 -310.81403) (xy 52.202836 -310.835128) (xy 52.243339 -310.863084) (xy 52.278832 -310.897176)
			(xy 52.308397 -310.93652) (xy 52.331268 -310.980097) (xy 52.346852 -311.026778) (xy 52.354747 -311.075355)
			(xy 52.355242 -311.099962) (xy 52.69409 -311.099962) (xy 52.69805 -311.050908) (xy 52.709827 -311.003124)
			(xy 52.729118 -310.957848) (xy 52.755421 -310.916252) (xy 52.788056 -310.879415) (xy 52.826177 -310.84829)
			(xy 52.868798 -310.823683) (xy 52.914814 -310.806231) (xy 52.963033 -310.796387) (xy 53.012208 -310.794406)
			(xy 53.061063 -310.800338) (xy 53.108334 -310.81403) (xy 53.152796 -310.835128) (xy 53.193299 -310.863084)
			(xy 53.228792 -310.897176) (xy 53.258357 -310.93652) (xy 53.281228 -310.980097) (xy 53.296812 -311.026778)
			(xy 53.304707 -311.075355) (xy 53.305202 -311.099962) (xy 53.64405 -311.099962) (xy 53.64801 -311.050908)
			(xy 53.659787 -311.003124) (xy 53.679078 -310.957848) (xy 53.705381 -310.916252) (xy 53.738016 -310.879415)
			(xy 53.776137 -310.84829) (xy 53.818758 -310.823683) (xy 53.864774 -310.806231) (xy 53.912993 -310.796387)
			(xy 53.962168 -310.794406) (xy 54.011023 -310.800338) (xy 54.058294 -310.81403) (xy 54.102756 -310.835128)
			(xy 54.143259 -310.863084) (xy 54.178752 -310.897176) (xy 54.208317 -310.93652) (xy 54.231188 -310.980097)
			(xy 54.246772 -311.026778) (xy 54.254667 -311.075355) (xy 54.255162 -311.099962) (xy 54.59401 -311.099962)
			(xy 54.59797 -311.050908) (xy 54.609747 -311.003124) (xy 54.629038 -310.957848) (xy 54.655341 -310.916252)
			(xy 54.687976 -310.879415) (xy 54.726097 -310.84829) (xy 54.768718 -310.823683) (xy 54.814734 -310.806231)
			(xy 54.862953 -310.796387) (xy 54.912128 -310.794406) (xy 54.960983 -310.800338) (xy 55.008254 -310.81403)
			(xy 55.052716 -310.835128) (xy 55.093219 -310.863084) (xy 55.128712 -310.897176) (xy 55.158277 -310.93652)
			(xy 55.181148 -310.980097) (xy 55.196732 -311.026778) (xy 55.204627 -311.075355) (xy 55.205122 -311.099962)
			(xy 55.54397 -311.099962) (xy 55.54793 -311.050908) (xy 55.559707 -311.003124) (xy 55.578998 -310.957848)
			(xy 55.605301 -310.916252) (xy 55.637936 -310.879415) (xy 55.676057 -310.84829) (xy 55.718678 -310.823683)
			(xy 55.764694 -310.806231) (xy 55.812913 -310.796387) (xy 55.862088 -310.794406) (xy 55.910943 -310.800338)
			(xy 55.958214 -310.81403) (xy 56.002676 -310.835128) (xy 56.043179 -310.863084) (xy 56.078672 -310.897176)
			(xy 56.108237 -310.93652) (xy 56.131108 -310.980097) (xy 56.146692 -311.026778) (xy 56.154587 -311.075355)
			(xy 56.155082 -311.099962) (xy 56.494184 -311.099962) (xy 56.498144 -311.050908) (xy 56.509921 -311.003124)
			(xy 56.529212 -310.957848) (xy 56.555515 -310.916252) (xy 56.58815 -310.879415) (xy 56.626271 -310.84829)
			(xy 56.668892 -310.823683) (xy 56.714908 -310.806231) (xy 56.763127 -310.796387) (xy 56.812302 -310.794406)
			(xy 56.861157 -310.800338) (xy 56.908428 -310.81403) (xy 56.95289 -310.835128) (xy 56.993393 -310.863084)
			(xy 57.028886 -310.897176) (xy 57.058451 -310.93652) (xy 57.081322 -310.980097) (xy 57.096906 -311.026778)
			(xy 57.104801 -311.075355) (xy 57.105296 -311.099962) (xy 57.444144 -311.099962) (xy 57.448104 -311.050908)
			(xy 57.459881 -311.003124) (xy 57.479172 -310.957848) (xy 57.505475 -310.916252) (xy 57.53811 -310.879415)
			(xy 57.576231 -310.84829) (xy 57.618852 -310.823683) (xy 57.664868 -310.806231) (xy 57.713087 -310.796387)
			(xy 57.762262 -310.794406) (xy 57.811117 -310.800338) (xy 57.858388 -310.81403) (xy 57.90285 -310.835128)
			(xy 57.943353 -310.863084) (xy 57.978846 -310.897176) (xy 58.008411 -310.93652) (xy 58.031282 -310.980097)
			(xy 58.046866 -311.026778) (xy 58.054761 -311.075355) (xy 58.055256 -311.099962) (xy 58.054761 -311.124569)
			(xy 58.054582 -311.12567) (xy 58.37326 -311.12567) (xy 58.37326 -311.074254) (xy 58.381303 -311.023472)
			(xy 58.397191 -310.974573) (xy 58.420534 -310.928761) (xy 58.450755 -310.887165) (xy 58.487111 -310.850809)
			(xy 58.528707 -310.820588) (xy 58.574519 -310.797245) (xy 58.623418 -310.781357) (xy 58.6742 -310.773314)
			(xy 58.725616 -310.773314) (xy 58.776398 -310.781357) (xy 58.825297 -310.797245) (xy 58.871109 -310.820588)
			(xy 58.912705 -310.850809) (xy 58.949061 -310.887165) (xy 58.979282 -310.928761) (xy 59.002625 -310.974573)
			(xy 59.018513 -311.023472) (xy 59.026556 -311.074254) (xy 59.02706 -311.099962) (xy 59.344064 -311.099962)
			(xy 59.348024 -311.050908) (xy 59.359801 -311.003124) (xy 59.379092 -310.957848) (xy 59.405395 -310.916252)
			(xy 59.43803 -310.879415) (xy 59.476151 -310.84829) (xy 59.518772 -310.823683) (xy 59.564788 -310.806231)
			(xy 59.613007 -310.796387) (xy 59.662182 -310.794406) (xy 59.711037 -310.800338) (xy 59.758308 -310.81403)
			(xy 59.80277 -310.835128) (xy 59.843273 -310.863084) (xy 59.878766 -310.897176) (xy 59.908331 -310.93652)
			(xy 59.931202 -310.980097) (xy 59.946786 -311.026778) (xy 59.954681 -311.075355) (xy 59.955176 -311.099962)
			(xy 59.954681 -311.124569) (xy 59.954502 -311.12567) (xy 60.27318 -311.12567) (xy 60.27318 -311.074254)
			(xy 60.281223 -311.023472) (xy 60.297111 -310.974573) (xy 60.320454 -310.928761) (xy 60.350675 -310.887165)
			(xy 60.387031 -310.850809) (xy 60.428627 -310.820588) (xy 60.474439 -310.797245) (xy 60.523338 -310.781357)
			(xy 60.57412 -310.773314) (xy 60.625536 -310.773314) (xy 60.676318 -310.781357) (xy 60.725217 -310.797245)
			(xy 60.771029 -310.820588) (xy 60.812625 -310.850809) (xy 60.848981 -310.887165) (xy 60.879202 -310.928761)
			(xy 60.902545 -310.974573) (xy 60.918433 -311.023472) (xy 60.926476 -311.074254) (xy 60.92698 -311.099962)
			(xy 61.243984 -311.099962) (xy 61.247944 -311.050908) (xy 61.259721 -311.003124) (xy 61.279012 -310.957848)
			(xy 61.305315 -310.916252) (xy 61.33795 -310.879415) (xy 61.376071 -310.84829) (xy 61.418692 -310.823683)
			(xy 61.464708 -310.806231) (xy 61.512927 -310.796387) (xy 61.562102 -310.794406) (xy 61.610957 -310.800338)
			(xy 61.658228 -310.81403) (xy 61.70269 -310.835128) (xy 61.743193 -310.863084) (xy 61.778686 -310.897176)
			(xy 61.808251 -310.93652) (xy 61.831122 -310.980097) (xy 61.846706 -311.026778) (xy 61.854601 -311.075355)
			(xy 61.855096 -311.099962) (xy 61.854601 -311.124569) (xy 61.854422 -311.12567) (xy 62.1731 -311.12567)
			(xy 62.1731 -311.074254) (xy 62.181143 -311.023472) (xy 62.197031 -310.974573) (xy 62.220374 -310.928761)
			(xy 62.250595 -310.887165) (xy 62.286951 -310.850809) (xy 62.328547 -310.820588) (xy 62.374359 -310.797245)
			(xy 62.423258 -310.781357) (xy 62.47404 -310.773314) (xy 62.525456 -310.773314) (xy 62.576238 -310.781357)
			(xy 62.625137 -310.797245) (xy 62.670949 -310.820588) (xy 62.712545 -310.850809) (xy 62.748901 -310.887165)
			(xy 62.779122 -310.928761) (xy 62.802465 -310.974573) (xy 62.818353 -311.023472) (xy 62.826396 -311.074254)
			(xy 62.8269 -311.099962) (xy 63.144158 -311.099962) (xy 63.148118 -311.050908) (xy 63.159895 -311.003124)
			(xy 63.179186 -310.957848) (xy 63.205489 -310.916252) (xy 63.238124 -310.879415) (xy 63.276245 -310.84829)
			(xy 63.318866 -310.823683) (xy 63.364882 -310.806231) (xy 63.413101 -310.796387) (xy 63.462276 -310.794406)
			(xy 63.511131 -310.800338) (xy 63.558402 -310.81403) (xy 63.602864 -310.835128) (xy 63.643367 -310.863084)
			(xy 63.67886 -310.897176) (xy 63.708425 -310.93652) (xy 63.731296 -310.980097) (xy 63.74688 -311.026778)
			(xy 63.754775 -311.075355) (xy 63.75527 -311.099962) (xy 63.754775 -311.124569) (xy 63.754596 -311.12567)
			(xy 64.073274 -311.12567) (xy 64.073274 -311.074254) (xy 64.081317 -311.023472) (xy 64.097205 -310.974573)
			(xy 64.120548 -310.928761) (xy 64.150769 -310.887165) (xy 64.187125 -310.850809) (xy 64.228721 -310.820588)
			(xy 64.274533 -310.797245) (xy 64.323432 -310.781357) (xy 64.374214 -310.773314) (xy 64.42563 -310.773314)
			(xy 64.476412 -310.781357) (xy 64.525311 -310.797245) (xy 64.571123 -310.820588) (xy 64.612719 -310.850809)
			(xy 64.649075 -310.887165) (xy 64.679296 -310.928761) (xy 64.702639 -310.974573) (xy 64.718527 -311.023472)
			(xy 64.72657 -311.074254) (xy 64.727074 -311.099962) (xy 65.044078 -311.099962) (xy 65.048038 -311.050908)
			(xy 65.059815 -311.003124) (xy 65.079106 -310.957848) (xy 65.105409 -310.916252) (xy 65.138044 -310.879415)
			(xy 65.176165 -310.84829) (xy 65.218786 -310.823683) (xy 65.264802 -310.806231) (xy 65.313021 -310.796387)
			(xy 65.362196 -310.794406) (xy 65.411051 -310.800338) (xy 65.458322 -310.81403) (xy 65.502784 -310.835128)
			(xy 65.543287 -310.863084) (xy 65.57878 -310.897176) (xy 65.608345 -310.93652) (xy 65.631216 -310.980097)
			(xy 65.6468 -311.026778) (xy 65.654695 -311.075355) (xy 65.65519 -311.099962) (xy 65.654695 -311.124569)
			(xy 65.654516 -311.12567) (xy 65.973194 -311.12567) (xy 65.973194 -311.074254) (xy 65.981237 -311.023472)
			(xy 65.997125 -310.974573) (xy 66.020468 -310.928761) (xy 66.050689 -310.887165) (xy 66.087045 -310.850809)
			(xy 66.128641 -310.820588) (xy 66.174453 -310.797245) (xy 66.223352 -310.781357) (xy 66.274134 -310.773314)
			(xy 66.32555 -310.773314) (xy 66.376332 -310.781357) (xy 66.425231 -310.797245) (xy 66.471043 -310.820588)
			(xy 66.512639 -310.850809) (xy 66.548995 -310.887165) (xy 66.579216 -310.928761) (xy 66.602559 -310.974573)
			(xy 66.618447 -311.023472) (xy 66.62649 -311.074254) (xy 66.626994 -311.099962) (xy 66.943998 -311.099962)
			(xy 66.947958 -311.050908) (xy 66.959735 -311.003124) (xy 66.979026 -310.957848) (xy 67.005329 -310.916252)
			(xy 67.037964 -310.879415) (xy 67.076085 -310.84829) (xy 67.118706 -310.823683) (xy 67.164722 -310.806231)
			(xy 67.212941 -310.796387) (xy 67.262116 -310.794406) (xy 67.310971 -310.800338) (xy 67.358242 -310.81403)
			(xy 67.402704 -310.835128) (xy 67.443207 -310.863084) (xy 67.4787 -310.897176) (xy 67.508265 -310.93652)
			(xy 67.531136 -310.980097) (xy 67.54672 -311.026778) (xy 67.554615 -311.075355) (xy 67.55511 -311.099962)
			(xy 67.554615 -311.124569) (xy 67.554436 -311.12567) (xy 67.873114 -311.12567) (xy 67.873114 -311.074254)
			(xy 67.881157 -311.023472) (xy 67.897045 -310.974573) (xy 67.920388 -310.928761) (xy 67.950609 -310.887165)
			(xy 67.986965 -310.850809) (xy 68.028561 -310.820588) (xy 68.074373 -310.797245) (xy 68.123272 -310.781357)
			(xy 68.174054 -310.773314) (xy 68.22547 -310.773314) (xy 68.276252 -310.781357) (xy 68.325151 -310.797245)
			(xy 68.370963 -310.820588) (xy 68.412559 -310.850809) (xy 68.448915 -310.887165) (xy 68.479136 -310.928761)
			(xy 68.502479 -310.974573) (xy 68.518367 -311.023472) (xy 68.52641 -311.074254) (xy 68.526914 -311.099962)
			(xy 68.844172 -311.099962) (xy 68.848132 -311.050908) (xy 68.859909 -311.003124) (xy 68.8792 -310.957848)
			(xy 68.905503 -310.916252) (xy 68.938138 -310.879415) (xy 68.976259 -310.84829) (xy 69.01888 -310.823683)
			(xy 69.064896 -310.806231) (xy 69.113115 -310.796387) (xy 69.16229 -310.794406) (xy 69.211145 -310.800338)
			(xy 69.258416 -310.81403) (xy 69.302878 -310.835128) (xy 69.343381 -310.863084) (xy 69.378874 -310.897176)
			(xy 69.408439 -310.93652) (xy 69.43131 -310.980097) (xy 69.446894 -311.026778) (xy 69.454789 -311.075355)
			(xy 69.455284 -311.099962) (xy 69.454789 -311.124569) (xy 69.45461 -311.12567) (xy 69.773288 -311.12567)
			(xy 69.773288 -311.074254) (xy 69.781331 -311.023472) (xy 69.797219 -310.974573) (xy 69.820562 -310.928761)
			(xy 69.850783 -310.887165) (xy 69.887139 -310.850809) (xy 69.928735 -310.820588) (xy 69.974547 -310.797245)
			(xy 70.023446 -310.781357) (xy 70.074228 -310.773314) (xy 70.125644 -310.773314) (xy 70.176426 -310.781357)
			(xy 70.225325 -310.797245) (xy 70.271137 -310.820588) (xy 70.312733 -310.850809) (xy 70.349089 -310.887165)
			(xy 70.37931 -310.928761) (xy 70.402653 -310.974573) (xy 70.418541 -311.023472) (xy 70.426584 -311.074254)
			(xy 70.427088 -311.099962) (xy 70.744092 -311.099962) (xy 70.748052 -311.050908) (xy 70.759829 -311.003124)
			(xy 70.77912 -310.957848) (xy 70.805423 -310.916252) (xy 70.838058 -310.879415) (xy 70.876179 -310.84829)
			(xy 70.9188 -310.823683) (xy 70.964816 -310.806231) (xy 71.013035 -310.796387) (xy 71.06221 -310.794406)
			(xy 71.111065 -310.800338) (xy 71.158336 -310.81403) (xy 71.202798 -310.835128) (xy 71.243301 -310.863084)
			(xy 71.278794 -310.897176) (xy 71.308359 -310.93652) (xy 71.33123 -310.980097) (xy 71.346814 -311.026778)
			(xy 71.354709 -311.075355) (xy 71.355204 -311.099962) (xy 71.354709 -311.124569) (xy 71.35453 -311.12567)
			(xy 71.673208 -311.12567) (xy 71.673208 -311.074254) (xy 71.681251 -311.023472) (xy 71.697139 -310.974573)
			(xy 71.720482 -310.928761) (xy 71.750703 -310.887165) (xy 71.787059 -310.850809) (xy 71.828655 -310.820588)
			(xy 71.874467 -310.797245) (xy 71.923366 -310.781357) (xy 71.974148 -310.773314) (xy 72.025564 -310.773314)
			(xy 72.076346 -310.781357) (xy 72.125245 -310.797245) (xy 72.171057 -310.820588) (xy 72.212653 -310.850809)
			(xy 72.249009 -310.887165) (xy 72.27923 -310.928761) (xy 72.302573 -310.974573) (xy 72.318461 -311.023472)
			(xy 72.326504 -311.074254) (xy 72.327008 -311.099962) (xy 72.644012 -311.099962) (xy 72.647972 -311.050908)
			(xy 72.659749 -311.003124) (xy 72.67904 -310.957848) (xy 72.705343 -310.916252) (xy 72.737978 -310.879415)
			(xy 72.776099 -310.84829) (xy 72.81872 -310.823683) (xy 72.864736 -310.806231) (xy 72.912955 -310.796387)
			(xy 72.96213 -310.794406) (xy 73.010985 -310.800338) (xy 73.058256 -310.81403) (xy 73.102718 -310.835128)
			(xy 73.143221 -310.863084) (xy 73.178714 -310.897176) (xy 73.208279 -310.93652) (xy 73.23115 -310.980097)
			(xy 73.246734 -311.026778) (xy 73.254629 -311.075355) (xy 73.255124 -311.099962) (xy 73.593972 -311.099962)
			(xy 73.597932 -311.050908) (xy 73.609709 -311.003124) (xy 73.629 -310.957848) (xy 73.655303 -310.916252)
			(xy 73.687938 -310.879415) (xy 73.726059 -310.84829) (xy 73.76868 -310.823683) (xy 73.814696 -310.806231)
			(xy 73.862915 -310.796387) (xy 73.91209 -310.794406) (xy 73.960945 -310.800338) (xy 74.008216 -310.81403)
			(xy 74.052678 -310.835128) (xy 74.093181 -310.863084) (xy 74.128674 -310.897176) (xy 74.158239 -310.93652)
			(xy 74.18111 -310.980097) (xy 74.196694 -311.026778) (xy 74.204589 -311.075355) (xy 74.205084 -311.099962)
			(xy 74.544186 -311.099962) (xy 74.548146 -311.050908) (xy 74.559923 -311.003124) (xy 74.579214 -310.957848)
			(xy 74.605517 -310.916252) (xy 74.638152 -310.879415) (xy 74.676273 -310.84829) (xy 74.718894 -310.823683)
			(xy 74.76491 -310.806231) (xy 74.813129 -310.796387) (xy 74.862304 -310.794406) (xy 74.911159 -310.800338)
			(xy 74.95843 -310.81403) (xy 75.002892 -310.835128) (xy 75.043395 -310.863084) (xy 75.078888 -310.897176)
			(xy 75.108453 -310.93652) (xy 75.131324 -310.980097) (xy 75.146908 -311.026778) (xy 75.154803 -311.075355)
			(xy 75.155298 -311.099962) (xy 75.494146 -311.099962) (xy 75.498106 -311.050908) (xy 75.509883 -311.003124)
			(xy 75.529174 -310.957848) (xy 75.555477 -310.916252) (xy 75.588112 -310.879415) (xy 75.626233 -310.84829)
			(xy 75.668854 -310.823683) (xy 75.71487 -310.806231) (xy 75.763089 -310.796387) (xy 75.812264 -310.794406)
			(xy 75.861119 -310.800338) (xy 75.90839 -310.81403) (xy 75.952852 -310.835128) (xy 75.993355 -310.863084)
			(xy 76.028848 -310.897176) (xy 76.058413 -310.93652) (xy 76.081284 -310.980097) (xy 76.096868 -311.026778)
			(xy 76.104763 -311.075355) (xy 76.105258 -311.099962) (xy 76.444106 -311.099962) (xy 76.448066 -311.050908)
			(xy 76.459843 -311.003124) (xy 76.479134 -310.957848) (xy 76.505437 -310.916252) (xy 76.538072 -310.879415)
			(xy 76.576193 -310.84829) (xy 76.618814 -310.823683) (xy 76.66483 -310.806231) (xy 76.713049 -310.796387)
			(xy 76.762224 -310.794406) (xy 76.811079 -310.800338) (xy 76.85835 -310.81403) (xy 76.902812 -310.835128)
			(xy 76.943315 -310.863084) (xy 76.978808 -310.897176) (xy 77.008373 -310.93652) (xy 77.031244 -310.980097)
			(xy 77.046828 -311.026778) (xy 77.054723 -311.075355) (xy 77.055218 -311.099962) (xy 77.394066 -311.099962)
			(xy 77.398026 -311.050908) (xy 77.409803 -311.003124) (xy 77.429094 -310.957848) (xy 77.455397 -310.916252)
			(xy 77.488032 -310.879415) (xy 77.526153 -310.84829) (xy 77.568774 -310.823683) (xy 77.61479 -310.806231)
			(xy 77.663009 -310.796387) (xy 77.712184 -310.794406) (xy 77.761039 -310.800338) (xy 77.80831 -310.81403)
			(xy 77.852772 -310.835128) (xy 77.893275 -310.863084) (xy 77.928768 -310.897176) (xy 77.958333 -310.93652)
			(xy 77.981204 -310.980097) (xy 77.996788 -311.026778) (xy 78.004683 -311.075355) (xy 78.005178 -311.099962)
			(xy 78.344026 -311.099962) (xy 78.347986 -311.050908) (xy 78.359763 -311.003124) (xy 78.379054 -310.957848)
			(xy 78.405357 -310.916252) (xy 78.437992 -310.879415) (xy 78.476113 -310.84829) (xy 78.518734 -310.823683)
			(xy 78.56475 -310.806231) (xy 78.612969 -310.796387) (xy 78.662144 -310.794406) (xy 78.710999 -310.800338)
			(xy 78.75827 -310.81403) (xy 78.802732 -310.835128) (xy 78.843235 -310.863084) (xy 78.878728 -310.897176)
			(xy 78.908293 -310.93652) (xy 78.931164 -310.980097) (xy 78.946748 -311.026778) (xy 78.954643 -311.075355)
			(xy 78.955138 -311.099962) (xy 79.293986 -311.099962) (xy 79.297946 -311.050908) (xy 79.309723 -311.003124)
			(xy 79.329014 -310.957848) (xy 79.355317 -310.916252) (xy 79.387952 -310.879415) (xy 79.426073 -310.84829)
			(xy 79.468694 -310.823683) (xy 79.51471 -310.806231) (xy 79.562929 -310.796387) (xy 79.612104 -310.794406)
			(xy 79.660959 -310.800338) (xy 79.70823 -310.81403) (xy 79.752692 -310.835128) (xy 79.793195 -310.863084)
			(xy 79.828688 -310.897176) (xy 79.858253 -310.93652) (xy 79.881124 -310.980097) (xy 79.896708 -311.026778)
			(xy 79.904603 -311.075355) (xy 79.905098 -311.099962) (xy 80.243946 -311.099962) (xy 80.247906 -311.050908)
			(xy 80.259683 -311.003124) (xy 80.278974 -310.957848) (xy 80.305277 -310.916252) (xy 80.337912 -310.879415)
			(xy 80.376033 -310.84829) (xy 80.418654 -310.823683) (xy 80.46467 -310.806231) (xy 80.512889 -310.796387)
			(xy 80.562064 -310.794406) (xy 80.610919 -310.800338) (xy 80.65819 -310.81403) (xy 80.702652 -310.835128)
			(xy 80.743155 -310.863084) (xy 80.778648 -310.897176) (xy 80.808213 -310.93652) (xy 80.831084 -310.980097)
			(xy 80.846668 -311.026778) (xy 80.854563 -311.075355) (xy 80.855058 -311.099962) (xy 81.19416 -311.099962)
			(xy 81.19812 -311.050908) (xy 81.209897 -311.003124) (xy 81.229188 -310.957848) (xy 81.255491 -310.916252)
			(xy 81.288126 -310.879415) (xy 81.326247 -310.84829) (xy 81.368868 -310.823683) (xy 81.414884 -310.806231)
			(xy 81.463103 -310.796387) (xy 81.512278 -310.794406) (xy 81.561133 -310.800338) (xy 81.608404 -310.81403)
			(xy 81.652866 -310.835128) (xy 81.693369 -310.863084) (xy 81.728862 -310.897176) (xy 81.758427 -310.93652)
			(xy 81.781298 -310.980097) (xy 81.796882 -311.026778) (xy 81.804777 -311.075355) (xy 81.805272 -311.099962)
			(xy 82.14412 -311.099962) (xy 82.14808 -311.050908) (xy 82.159857 -311.003124) (xy 82.179148 -310.957848)
			(xy 82.205451 -310.916252) (xy 82.238086 -310.879415) (xy 82.276207 -310.84829) (xy 82.318828 -310.823683)
			(xy 82.364844 -310.806231) (xy 82.413063 -310.796387) (xy 82.462238 -310.794406) (xy 82.511093 -310.800338)
			(xy 82.558364 -310.81403) (xy 82.602826 -310.835128) (xy 82.643329 -310.863084) (xy 82.678822 -310.897176)
			(xy 82.708387 -310.93652) (xy 82.731258 -310.980097) (xy 82.746842 -311.026778) (xy 82.754737 -311.075355)
			(xy 82.755232 -311.099962) (xy 82.754737 -311.124569) (xy 82.746842 -311.173146) (xy 82.731258 -311.219827)
			(xy 82.708387 -311.263404) (xy 82.678822 -311.302748) (xy 82.643329 -311.33684) (xy 82.602826 -311.364796)
			(xy 82.568916 -311.380887) (xy 90.566604 -311.380887) (xy 90.574356 -311.326928) (xy 90.589708 -311.274622)
			(xy 90.612348 -311.225033) (xy 90.641815 -311.17917) (xy 90.677508 -311.137968) (xy 90.718703 -311.102265)
			(xy 90.764559 -311.072788) (xy 90.814143 -311.050137) (xy 90.866446 -311.034774) (xy 90.920404 -311.02701)
			(xy 90.974917 -311.027004) (xy 91.028875 -311.034757) (xy 91.081182 -311.050109) (xy 91.130771 -311.07275)
			(xy 91.176633 -311.102217) (xy 91.217835 -311.137911) (xy 91.253537 -311.179106) (xy 91.283014 -311.224962)
			(xy 91.298431 -311.258712) (xy 100.471984 -311.258712) (xy 100.476055 -311.20309) (xy 100.488181 -311.148653)
			(xy 100.508104 -311.096562) (xy 100.5354 -311.047927) (xy 100.569486 -311.003784) (xy 100.609635 -310.965075)
			(xy 100.654993 -310.932624) (xy 100.704593 -310.907123) (xy 100.757377 -310.889116) (xy 100.81222 -310.878986)
			(xy 100.867954 -310.876949) (xy 100.923391 -310.883049) (xy 100.977348 -310.897155) (xy 101.028677 -310.918967)
			(xy 101.076283 -310.948021) (xy 101.119151 -310.983696) (xy 101.156368 -311.025233) (xy 101.187141 -311.071746)
			(xy 101.210813 -311.122243) (xy 101.226881 -311.17565) (xy 101.235001 -311.230826) (xy 101.23551 -311.258712)
			(xy 101.487984 -311.258712) (xy 101.492055 -311.20309) (xy 101.504181 -311.148653) (xy 101.524104 -311.096562)
			(xy 101.5514 -311.047927) (xy 101.585486 -311.003784) (xy 101.625635 -310.965075) (xy 101.670993 -310.932624)
			(xy 101.720593 -310.907123) (xy 101.773377 -310.889116) (xy 101.82822 -310.878986) (xy 101.883954 -310.876949)
			(xy 101.939391 -310.883049) (xy 101.993348 -310.897155) (xy 102.044677 -310.918967) (xy 102.092283 -310.948021)
			(xy 102.135151 -310.983696) (xy 102.172368 -311.025233) (xy 102.203141 -311.071746) (xy 102.226813 -311.122243)
			(xy 102.242881 -311.17565) (xy 102.251001 -311.230826) (xy 102.25151 -311.258712) (xy 102.503984 -311.258712)
			(xy 102.508055 -311.20309) (xy 102.520181 -311.148653) (xy 102.540104 -311.096562) (xy 102.5674 -311.047927)
			(xy 102.601486 -311.003784) (xy 102.641635 -310.965075) (xy 102.686993 -310.932624) (xy 102.736593 -310.907123)
			(xy 102.789377 -310.889116) (xy 102.84422 -310.878986) (xy 102.899954 -310.876949) (xy 102.955391 -310.883049)
			(xy 103.009348 -310.897155) (xy 103.060677 -310.918967) (xy 103.108283 -310.948021) (xy 103.151151 -310.983696)
			(xy 103.188368 -311.025233) (xy 103.219141 -311.071746) (xy 103.242813 -311.122243) (xy 103.258881 -311.17565)
			(xy 103.267001 -311.230826) (xy 103.26751 -311.258712) (xy 103.519984 -311.258712) (xy 103.524055 -311.20309)
			(xy 103.536181 -311.148653) (xy 103.556104 -311.096562) (xy 103.5834 -311.047927) (xy 103.617486 -311.003784)
			(xy 103.657635 -310.965075) (xy 103.702993 -310.932624) (xy 103.752593 -310.907123) (xy 103.805377 -310.889116)
			(xy 103.86022 -310.878986) (xy 103.915954 -310.876949) (xy 103.971391 -310.883049) (xy 104.025348 -310.897155)
			(xy 104.076677 -310.918967) (xy 104.124283 -310.948021) (xy 104.167151 -310.983696) (xy 104.204368 -311.025233)
			(xy 104.235141 -311.071746) (xy 104.258813 -311.122243) (xy 104.274881 -311.17565) (xy 104.283001 -311.230826)
			(xy 104.28351 -311.258712) (xy 104.535984 -311.258712) (xy 104.540055 -311.20309) (xy 104.552181 -311.148653)
			(xy 104.572104 -311.096562) (xy 104.5994 -311.047927) (xy 104.633486 -311.003784) (xy 104.673635 -310.965075)
			(xy 104.718993 -310.932624) (xy 104.768593 -310.907123) (xy 104.821377 -310.889116) (xy 104.87622 -310.878986)
			(xy 104.931954 -310.876949) (xy 104.987391 -310.883049) (xy 105.041348 -310.897155) (xy 105.092677 -310.918967)
			(xy 105.140283 -310.948021) (xy 105.183151 -310.983696) (xy 105.220368 -311.025233) (xy 105.251141 -311.071746)
			(xy 105.274813 -311.122243) (xy 105.290881 -311.17565) (xy 105.299001 -311.230826) (xy 105.29951 -311.258712)
			(xy 105.551984 -311.258712) (xy 105.556055 -311.20309) (xy 105.568181 -311.148653) (xy 105.588104 -311.096562)
			(xy 105.6154 -311.047927) (xy 105.649486 -311.003784) (xy 105.689635 -310.965075) (xy 105.734993 -310.932624)
			(xy 105.784593 -310.907123) (xy 105.837377 -310.889116) (xy 105.89222 -310.878986) (xy 105.947954 -310.876949)
			(xy 106.003391 -310.883049) (xy 106.057348 -310.897155) (xy 106.108677 -310.918967) (xy 106.156283 -310.948021)
			(xy 106.199151 -310.983696) (xy 106.236368 -311.025233) (xy 106.267141 -311.071746) (xy 106.290813 -311.122243)
			(xy 106.306881 -311.17565) (xy 106.315001 -311.230826) (xy 106.31551 -311.258712) (xy 106.567984 -311.258712)
			(xy 106.572055 -311.20309) (xy 106.584181 -311.148653) (xy 106.604104 -311.096562) (xy 106.6314 -311.047927)
			(xy 106.665486 -311.003784) (xy 106.705635 -310.965075) (xy 106.750993 -310.932624) (xy 106.800593 -310.907123)
			(xy 106.853377 -310.889116) (xy 106.90822 -310.878986) (xy 106.963954 -310.876949) (xy 107.019391 -310.883049)
			(xy 107.073348 -310.897155) (xy 107.124677 -310.918967) (xy 107.172283 -310.948021) (xy 107.215151 -310.983696)
			(xy 107.252368 -311.025233) (xy 107.283141 -311.071746) (xy 107.306813 -311.122243) (xy 107.322881 -311.17565)
			(xy 107.331001 -311.230826) (xy 107.33151 -311.258712) (xy 107.583984 -311.258712) (xy 107.588055 -311.20309)
			(xy 107.600181 -311.148653) (xy 107.620104 -311.096562) (xy 107.6474 -311.047927) (xy 107.681486 -311.003784)
			(xy 107.721635 -310.965075) (xy 107.766993 -310.932624) (xy 107.816593 -310.907123) (xy 107.869377 -310.889116)
			(xy 107.92422 -310.878986) (xy 107.979954 -310.876949) (xy 108.035391 -310.883049) (xy 108.089348 -310.897155)
			(xy 108.140677 -310.918967) (xy 108.188283 -310.948021) (xy 108.231151 -310.983696) (xy 108.268368 -311.025233)
			(xy 108.299141 -311.071746) (xy 108.322813 -311.122243) (xy 108.338881 -311.17565) (xy 108.347001 -311.230826)
			(xy 108.34751 -311.258712) (xy 108.599984 -311.258712) (xy 108.604055 -311.20309) (xy 108.616181 -311.148653)
			(xy 108.636104 -311.096562) (xy 108.6634 -311.047927) (xy 108.697486 -311.003784) (xy 108.737635 -310.965075)
			(xy 108.782993 -310.932624) (xy 108.832593 -310.907123) (xy 108.885377 -310.889116) (xy 108.94022 -310.878986)
			(xy 108.995954 -310.876949) (xy 109.051391 -310.883049) (xy 109.105348 -310.897155) (xy 109.156677 -310.918967)
			(xy 109.204283 -310.948021) (xy 109.247151 -310.983696) (xy 109.284368 -311.025233) (xy 109.315141 -311.071746)
			(xy 109.338813 -311.122243) (xy 109.354881 -311.17565) (xy 109.363001 -311.230826) (xy 109.36351 -311.258712)
			(xy 109.615984 -311.258712) (xy 109.620055 -311.20309) (xy 109.632181 -311.148653) (xy 109.652104 -311.096562)
			(xy 109.6794 -311.047927) (xy 109.713486 -311.003784) (xy 109.753635 -310.965075) (xy 109.798993 -310.932624)
			(xy 109.848593 -310.907123) (xy 109.901377 -310.889116) (xy 109.95622 -310.878986) (xy 110.011954 -310.876949)
			(xy 110.067391 -310.883049) (xy 110.121348 -310.897155) (xy 110.172677 -310.918967) (xy 110.220283 -310.948021)
			(xy 110.263151 -310.983696) (xy 110.300368 -311.025233) (xy 110.331141 -311.071746) (xy 110.354813 -311.122243)
			(xy 110.370881 -311.17565) (xy 110.379001 -311.230826) (xy 110.37951 -311.258712) (xy 110.379001 -311.286598)
			(xy 110.370881 -311.341774) (xy 110.354813 -311.395181) (xy 110.331141 -311.445678) (xy 110.300368 -311.492191)
			(xy 110.263151 -311.533728) (xy 110.220283 -311.569403) (xy 110.172677 -311.598457) (xy 110.121348 -311.620269)
			(xy 110.067391 -311.634375) (xy 110.011954 -311.640475) (xy 109.95622 -311.638438) (xy 109.901377 -311.628308)
			(xy 109.848593 -311.610301) (xy 109.798993 -311.5848) (xy 109.753635 -311.552349) (xy 109.713486 -311.51364)
			(xy 109.6794 -311.469497) (xy 109.652104 -311.420862) (xy 109.632181 -311.368771) (xy 109.620055 -311.314334)
			(xy 109.615984 -311.258712) (xy 109.36351 -311.258712) (xy 109.363001 -311.286598) (xy 109.354881 -311.341774)
			(xy 109.338813 -311.395181) (xy 109.315141 -311.445678) (xy 109.284368 -311.492191) (xy 109.247151 -311.533728)
			(xy 109.204283 -311.569403) (xy 109.156677 -311.598457) (xy 109.105348 -311.620269) (xy 109.051391 -311.634375)
			(xy 108.995954 -311.640475) (xy 108.94022 -311.638438) (xy 108.885377 -311.628308) (xy 108.832593 -311.610301)
			(xy 108.782993 -311.5848) (xy 108.737635 -311.552349) (xy 108.697486 -311.51364) (xy 108.6634 -311.469497)
			(xy 108.636104 -311.420862) (xy 108.616181 -311.368771) (xy 108.604055 -311.314334) (xy 108.599984 -311.258712)
			(xy 108.34751 -311.258712) (xy 108.347001 -311.286598) (xy 108.338881 -311.341774) (xy 108.322813 -311.395181)
			(xy 108.299141 -311.445678) (xy 108.268368 -311.492191) (xy 108.231151 -311.533728) (xy 108.188283 -311.569403)
			(xy 108.140677 -311.598457) (xy 108.089348 -311.620269) (xy 108.035391 -311.634375) (xy 107.979954 -311.640475)
			(xy 107.92422 -311.638438) (xy 107.869377 -311.628308) (xy 107.816593 -311.610301) (xy 107.766993 -311.5848)
			(xy 107.721635 -311.552349) (xy 107.681486 -311.51364) (xy 107.6474 -311.469497) (xy 107.620104 -311.420862)
			(xy 107.600181 -311.368771) (xy 107.588055 -311.314334) (xy 107.583984 -311.258712) (xy 107.33151 -311.258712)
			(xy 107.331001 -311.286598) (xy 107.322881 -311.341774) (xy 107.306813 -311.395181) (xy 107.283141 -311.445678)
			(xy 107.252368 -311.492191) (xy 107.215151 -311.533728) (xy 107.172283 -311.569403) (xy 107.124677 -311.598457)
			(xy 107.073348 -311.620269) (xy 107.019391 -311.634375) (xy 106.963954 -311.640475) (xy 106.90822 -311.638438)
			(xy 106.853377 -311.628308) (xy 106.800593 -311.610301) (xy 106.750993 -311.5848) (xy 106.705635 -311.552349)
			(xy 106.665486 -311.51364) (xy 106.6314 -311.469497) (xy 106.604104 -311.420862) (xy 106.584181 -311.368771)
			(xy 106.572055 -311.314334) (xy 106.567984 -311.258712) (xy 106.31551 -311.258712) (xy 106.315001 -311.286598)
			(xy 106.306881 -311.341774) (xy 106.290813 -311.395181) (xy 106.267141 -311.445678) (xy 106.236368 -311.492191)
			(xy 106.199151 -311.533728) (xy 106.156283 -311.569403) (xy 106.108677 -311.598457) (xy 106.057348 -311.620269)
			(xy 106.003391 -311.634375) (xy 105.947954 -311.640475) (xy 105.89222 -311.638438) (xy 105.837377 -311.628308)
			(xy 105.784593 -311.610301) (xy 105.734993 -311.5848) (xy 105.689635 -311.552349) (xy 105.649486 -311.51364)
			(xy 105.6154 -311.469497) (xy 105.588104 -311.420862) (xy 105.568181 -311.368771) (xy 105.556055 -311.314334)
			(xy 105.551984 -311.258712) (xy 105.29951 -311.258712) (xy 105.299001 -311.286598) (xy 105.290881 -311.341774)
			(xy 105.274813 -311.395181) (xy 105.251141 -311.445678) (xy 105.220368 -311.492191) (xy 105.183151 -311.533728)
			(xy 105.140283 -311.569403) (xy 105.092677 -311.598457) (xy 105.041348 -311.620269) (xy 104.987391 -311.634375)
			(xy 104.931954 -311.640475) (xy 104.87622 -311.638438) (xy 104.821377 -311.628308) (xy 104.768593 -311.610301)
			(xy 104.718993 -311.5848) (xy 104.673635 -311.552349) (xy 104.633486 -311.51364) (xy 104.5994 -311.469497)
			(xy 104.572104 -311.420862) (xy 104.552181 -311.368771) (xy 104.540055 -311.314334) (xy 104.535984 -311.258712)
			(xy 104.28351 -311.258712) (xy 104.283001 -311.286598) (xy 104.274881 -311.341774) (xy 104.258813 -311.395181)
			(xy 104.235141 -311.445678) (xy 104.204368 -311.492191) (xy 104.167151 -311.533728) (xy 104.124283 -311.569403)
			(xy 104.076677 -311.598457) (xy 104.025348 -311.620269) (xy 103.971391 -311.634375) (xy 103.915954 -311.640475)
			(xy 103.86022 -311.638438) (xy 103.805377 -311.628308) (xy 103.752593 -311.610301) (xy 103.702993 -311.5848)
			(xy 103.657635 -311.552349) (xy 103.617486 -311.51364) (xy 103.5834 -311.469497) (xy 103.556104 -311.420862)
			(xy 103.536181 -311.368771) (xy 103.524055 -311.314334) (xy 103.519984 -311.258712) (xy 103.26751 -311.258712)
			(xy 103.267001 -311.286598) (xy 103.258881 -311.341774) (xy 103.242813 -311.395181) (xy 103.219141 -311.445678)
			(xy 103.188368 -311.492191) (xy 103.151151 -311.533728) (xy 103.108283 -311.569403) (xy 103.060677 -311.598457)
			(xy 103.009348 -311.620269) (xy 102.955391 -311.634375) (xy 102.899954 -311.640475) (xy 102.84422 -311.638438)
			(xy 102.789377 -311.628308) (xy 102.736593 -311.610301) (xy 102.686993 -311.5848) (xy 102.641635 -311.552349)
			(xy 102.601486 -311.51364) (xy 102.5674 -311.469497) (xy 102.540104 -311.420862) (xy 102.520181 -311.368771)
			(xy 102.508055 -311.314334) (xy 102.503984 -311.258712) (xy 102.25151 -311.258712) (xy 102.251001 -311.286598)
			(xy 102.242881 -311.341774) (xy 102.226813 -311.395181) (xy 102.203141 -311.445678) (xy 102.172368 -311.492191)
			(xy 102.135151 -311.533728) (xy 102.092283 -311.569403) (xy 102.044677 -311.598457) (xy 101.993348 -311.620269)
			(xy 101.939391 -311.634375) (xy 101.883954 -311.640475) (xy 101.82822 -311.638438) (xy 101.773377 -311.628308)
			(xy 101.720593 -311.610301) (xy 101.670993 -311.5848) (xy 101.625635 -311.552349) (xy 101.585486 -311.51364)
			(xy 101.5514 -311.469497) (xy 101.524104 -311.420862) (xy 101.504181 -311.368771) (xy 101.492055 -311.314334)
			(xy 101.487984 -311.258712) (xy 101.23551 -311.258712) (xy 101.235001 -311.286598) (xy 101.226881 -311.341774)
			(xy 101.210813 -311.395181) (xy 101.187141 -311.445678) (xy 101.156368 -311.492191) (xy 101.119151 -311.533728)
			(xy 101.076283 -311.569403) (xy 101.028677 -311.598457) (xy 100.977348 -311.620269) (xy 100.923391 -311.634375)
			(xy 100.867954 -311.640475) (xy 100.81222 -311.638438) (xy 100.757377 -311.628308) (xy 100.704593 -311.610301)
			(xy 100.654993 -311.5848) (xy 100.609635 -311.552349) (xy 100.569486 -311.51364) (xy 100.5354 -311.469497)
			(xy 100.508104 -311.420862) (xy 100.488181 -311.368771) (xy 100.476055 -311.314334) (xy 100.471984 -311.258712)
			(xy 91.298431 -311.258712) (xy 91.305664 -311.274547) (xy 91.321027 -311.32685) (xy 91.32879 -311.380808)
			(xy 91.329256 -311.408064) (xy 91.329059 -311.425112) (xy 91.326005 -311.459072) (xy 91.32316 -311.475882)
			(xy 91.320874 -311.488328) (xy 91.32824 -311.51195) (xy 91.405202 -311.588912) (xy 91.428824 -311.596278)
			(xy 91.44127 -311.593992) (xy 91.458141 -311.591124) (xy 91.49223 -311.58807) (xy 91.509342 -311.587896)
			(xy 91.536594 -311.588339) (xy 91.590544 -311.596101) (xy 91.64284 -311.611462) (xy 91.692417 -311.634108)
			(xy 91.738268 -311.663579) (xy 91.779458 -311.699275) (xy 91.815149 -311.740469) (xy 91.844614 -311.786323)
			(xy 91.867254 -311.835903) (xy 91.882609 -311.888201) (xy 91.890365 -311.942151) (xy 91.89085 -311.969404)
			(xy 91.889834 -311.99836) (xy 91.888818 -312.009536) (xy 91.896692 -312.030364) (xy 91.967558 -312.100722)
			(xy 91.988386 -312.108088) (xy 91.999816 -312.107072) (xy 92.032328 -312.105802) (xy 92.059577 -312.106308)
			(xy 92.113519 -312.114068) (xy 92.165807 -312.129425) (xy 92.215378 -312.152067) (xy 92.261223 -312.181533)
			(xy 92.302407 -312.217224) (xy 92.338093 -312.258412) (xy 92.348567 -312.274712) (xy 100.471984 -312.274712)
			(xy 100.476055 -312.21909) (xy 100.488181 -312.164653) (xy 100.508104 -312.112562) (xy 100.5354 -312.063927)
			(xy 100.569486 -312.019784) (xy 100.609635 -311.981075) (xy 100.654993 -311.948624) (xy 100.704593 -311.923123)
			(xy 100.757377 -311.905116) (xy 100.81222 -311.894986) (xy 100.867954 -311.892949) (xy 100.923391 -311.899049)
			(xy 100.977348 -311.913155) (xy 101.028677 -311.934967) (xy 101.076283 -311.964021) (xy 101.119151 -311.999696)
			(xy 101.156368 -312.041233) (xy 101.187141 -312.087746) (xy 101.210813 -312.138243) (xy 101.226881 -312.19165)
			(xy 101.235001 -312.246826) (xy 101.23551 -312.274712) (xy 101.487984 -312.274712) (xy 101.492055 -312.21909)
			(xy 101.504181 -312.164653) (xy 101.524104 -312.112562) (xy 101.5514 -312.063927) (xy 101.585486 -312.019784)
			(xy 101.625635 -311.981075) (xy 101.670993 -311.948624) (xy 101.720593 -311.923123) (xy 101.773377 -311.905116)
			(xy 101.82822 -311.894986) (xy 101.883954 -311.892949) (xy 101.939391 -311.899049) (xy 101.993348 -311.913155)
			(xy 102.044677 -311.934967) (xy 102.092283 -311.964021) (xy 102.135151 -311.999696) (xy 102.172368 -312.041233)
			(xy 102.203141 -312.087746) (xy 102.226813 -312.138243) (xy 102.242881 -312.19165) (xy 102.251001 -312.246826)
			(xy 102.25151 -312.274712) (xy 102.503984 -312.274712) (xy 102.508055 -312.21909) (xy 102.520181 -312.164653)
			(xy 102.540104 -312.112562) (xy 102.5674 -312.063927) (xy 102.601486 -312.019784) (xy 102.641635 -311.981075)
			(xy 102.686993 -311.948624) (xy 102.736593 -311.923123) (xy 102.789377 -311.905116) (xy 102.84422 -311.894986)
			(xy 102.899954 -311.892949) (xy 102.955391 -311.899049) (xy 103.009348 -311.913155) (xy 103.060677 -311.934967)
			(xy 103.108283 -311.964021) (xy 103.151151 -311.999696) (xy 103.188368 -312.041233) (xy 103.219141 -312.087746)
			(xy 103.242813 -312.138243) (xy 103.258881 -312.19165) (xy 103.267001 -312.246826) (xy 103.26751 -312.274712)
			(xy 103.519984 -312.274712) (xy 103.524055 -312.21909) (xy 103.536181 -312.164653) (xy 103.556104 -312.112562)
			(xy 103.5834 -312.063927) (xy 103.617486 -312.019784) (xy 103.657635 -311.981075) (xy 103.702993 -311.948624)
			(xy 103.752593 -311.923123) (xy 103.805377 -311.905116) (xy 103.86022 -311.894986) (xy 103.915954 -311.892949)
			(xy 103.971391 -311.899049) (xy 104.025348 -311.913155) (xy 104.076677 -311.934967) (xy 104.124283 -311.964021)
			(xy 104.167151 -311.999696) (xy 104.204368 -312.041233) (xy 104.235141 -312.087746) (xy 104.258813 -312.138243)
			(xy 104.274881 -312.19165) (xy 104.283001 -312.246826) (xy 104.28351 -312.274712) (xy 104.535984 -312.274712)
			(xy 104.540055 -312.21909) (xy 104.552181 -312.164653) (xy 104.572104 -312.112562) (xy 104.5994 -312.063927)
			(xy 104.633486 -312.019784) (xy 104.673635 -311.981075) (xy 104.718993 -311.948624) (xy 104.768593 -311.923123)
			(xy 104.821377 -311.905116) (xy 104.87622 -311.894986) (xy 104.931954 -311.892949) (xy 104.987391 -311.899049)
			(xy 105.041348 -311.913155) (xy 105.092677 -311.934967) (xy 105.140283 -311.964021) (xy 105.183151 -311.999696)
			(xy 105.220368 -312.041233) (xy 105.251141 -312.087746) (xy 105.274813 -312.138243) (xy 105.290881 -312.19165)
			(xy 105.299001 -312.246826) (xy 105.29951 -312.274712) (xy 105.551984 -312.274712) (xy 105.556055 -312.21909)
			(xy 105.568181 -312.164653) (xy 105.588104 -312.112562) (xy 105.6154 -312.063927) (xy 105.649486 -312.019784)
			(xy 105.689635 -311.981075) (xy 105.734993 -311.948624) (xy 105.784593 -311.923123) (xy 105.837377 -311.905116)
			(xy 105.89222 -311.894986) (xy 105.947954 -311.892949) (xy 106.003391 -311.899049) (xy 106.057348 -311.913155)
			(xy 106.108677 -311.934967) (xy 106.156283 -311.964021) (xy 106.199151 -311.999696) (xy 106.236368 -312.041233)
			(xy 106.267141 -312.087746) (xy 106.290813 -312.138243) (xy 106.306881 -312.19165) (xy 106.315001 -312.246826)
			(xy 106.31551 -312.274712) (xy 106.567984 -312.274712) (xy 106.572055 -312.21909) (xy 106.584181 -312.164653)
			(xy 106.604104 -312.112562) (xy 106.6314 -312.063927) (xy 106.665486 -312.019784) (xy 106.705635 -311.981075)
			(xy 106.750993 -311.948624) (xy 106.800593 -311.923123) (xy 106.853377 -311.905116) (xy 106.90822 -311.894986)
			(xy 106.963954 -311.892949) (xy 107.019391 -311.899049) (xy 107.073348 -311.913155) (xy 107.124677 -311.934967)
			(xy 107.172283 -311.964021) (xy 107.215151 -311.999696) (xy 107.252368 -312.041233) (xy 107.283141 -312.087746)
			(xy 107.306813 -312.138243) (xy 107.322881 -312.19165) (xy 107.331001 -312.246826) (xy 107.33151 -312.274712)
			(xy 107.583984 -312.274712) (xy 107.588055 -312.21909) (xy 107.600181 -312.164653) (xy 107.620104 -312.112562)
			(xy 107.6474 -312.063927) (xy 107.681486 -312.019784) (xy 107.721635 -311.981075) (xy 107.766993 -311.948624)
			(xy 107.816593 -311.923123) (xy 107.869377 -311.905116) (xy 107.92422 -311.894986) (xy 107.979954 -311.892949)
			(xy 108.035391 -311.899049) (xy 108.089348 -311.913155) (xy 108.140677 -311.934967) (xy 108.188283 -311.964021)
			(xy 108.231151 -311.999696) (xy 108.268368 -312.041233) (xy 108.299141 -312.087746) (xy 108.322813 -312.138243)
			(xy 108.338881 -312.19165) (xy 108.347001 -312.246826) (xy 108.34751 -312.274712) (xy 108.599984 -312.274712)
			(xy 108.604055 -312.21909) (xy 108.616181 -312.164653) (xy 108.636104 -312.112562) (xy 108.6634 -312.063927)
			(xy 108.697486 -312.019784) (xy 108.737635 -311.981075) (xy 108.782993 -311.948624) (xy 108.832593 -311.923123)
			(xy 108.885377 -311.905116) (xy 108.94022 -311.894986) (xy 108.995954 -311.892949) (xy 109.051391 -311.899049)
			(xy 109.105348 -311.913155) (xy 109.156677 -311.934967) (xy 109.204283 -311.964021) (xy 109.247151 -311.999696)
			(xy 109.284368 -312.041233) (xy 109.315141 -312.087746) (xy 109.338813 -312.138243) (xy 109.354881 -312.19165)
			(xy 109.363001 -312.246826) (xy 109.36351 -312.274712) (xy 109.615984 -312.274712) (xy 109.620055 -312.21909)
			(xy 109.632181 -312.164653) (xy 109.652104 -312.112562) (xy 109.6794 -312.063927) (xy 109.713486 -312.019784)
			(xy 109.753635 -311.981075) (xy 109.798993 -311.948624) (xy 109.848593 -311.923123) (xy 109.901377 -311.905116)
			(xy 109.95622 -311.894986) (xy 110.011954 -311.892949) (xy 110.067391 -311.899049) (xy 110.121348 -311.913155)
			(xy 110.172677 -311.934967) (xy 110.220283 -311.964021) (xy 110.263151 -311.999696) (xy 110.300368 -312.041233)
			(xy 110.331141 -312.087746) (xy 110.354813 -312.138243) (xy 110.370881 -312.19165) (xy 110.379001 -312.246826)
			(xy 110.37951 -312.274712) (xy 110.379001 -312.302598) (xy 110.370881 -312.357774) (xy 110.354813 -312.411181)
			(xy 110.331141 -312.461678) (xy 110.300368 -312.508191) (xy 110.263151 -312.549728) (xy 110.220283 -312.585403)
			(xy 110.172677 -312.614457) (xy 110.121348 -312.636269) (xy 110.067391 -312.650375) (xy 110.011954 -312.656475)
			(xy 109.95622 -312.654438) (xy 109.901377 -312.644308) (xy 109.848593 -312.626301) (xy 109.798993 -312.6008)
			(xy 109.753635 -312.568349) (xy 109.713486 -312.52964) (xy 109.6794 -312.485497) (xy 109.652104 -312.436862)
			(xy 109.632181 -312.384771) (xy 109.620055 -312.330334) (xy 109.615984 -312.274712) (xy 109.36351 -312.274712)
			(xy 109.363001 -312.302598) (xy 109.354881 -312.357774) (xy 109.338813 -312.411181) (xy 109.315141 -312.461678)
			(xy 109.284368 -312.508191) (xy 109.247151 -312.549728) (xy 109.204283 -312.585403) (xy 109.156677 -312.614457)
			(xy 109.105348 -312.636269) (xy 109.051391 -312.650375) (xy 108.995954 -312.656475) (xy 108.94022 -312.654438)
			(xy 108.885377 -312.644308) (xy 108.832593 -312.626301) (xy 108.782993 -312.6008) (xy 108.737635 -312.568349)
			(xy 108.697486 -312.52964) (xy 108.6634 -312.485497) (xy 108.636104 -312.436862) (xy 108.616181 -312.384771)
			(xy 108.604055 -312.330334) (xy 108.599984 -312.274712) (xy 108.34751 -312.274712) (xy 108.347001 -312.302598)
			(xy 108.338881 -312.357774) (xy 108.322813 -312.411181) (xy 108.299141 -312.461678) (xy 108.268368 -312.508191)
			(xy 108.231151 -312.549728) (xy 108.188283 -312.585403) (xy 108.140677 -312.614457) (xy 108.089348 -312.636269)
			(xy 108.035391 -312.650375) (xy 107.979954 -312.656475) (xy 107.92422 -312.654438) (xy 107.869377 -312.644308)
			(xy 107.816593 -312.626301) (xy 107.766993 -312.6008) (xy 107.721635 -312.568349) (xy 107.681486 -312.52964)
			(xy 107.6474 -312.485497) (xy 107.620104 -312.436862) (xy 107.600181 -312.384771) (xy 107.588055 -312.330334)
			(xy 107.583984 -312.274712) (xy 107.33151 -312.274712) (xy 107.331001 -312.302598) (xy 107.322881 -312.357774)
			(xy 107.306813 -312.411181) (xy 107.283141 -312.461678) (xy 107.252368 -312.508191) (xy 107.215151 -312.549728)
			(xy 107.172283 -312.585403) (xy 107.124677 -312.614457) (xy 107.073348 -312.636269) (xy 107.019391 -312.650375)
			(xy 106.963954 -312.656475) (xy 106.90822 -312.654438) (xy 106.853377 -312.644308) (xy 106.800593 -312.626301)
			(xy 106.750993 -312.6008) (xy 106.705635 -312.568349) (xy 106.665486 -312.52964) (xy 106.6314 -312.485497)
			(xy 106.604104 -312.436862) (xy 106.584181 -312.384771) (xy 106.572055 -312.330334) (xy 106.567984 -312.274712)
			(xy 106.31551 -312.274712) (xy 106.315001 -312.302598) (xy 106.306881 -312.357774) (xy 106.290813 -312.411181)
			(xy 106.267141 -312.461678) (xy 106.236368 -312.508191) (xy 106.199151 -312.549728) (xy 106.156283 -312.585403)
			(xy 106.108677 -312.614457) (xy 106.057348 -312.636269) (xy 106.003391 -312.650375) (xy 105.947954 -312.656475)
			(xy 105.89222 -312.654438) (xy 105.837377 -312.644308) (xy 105.784593 -312.626301) (xy 105.734993 -312.6008)
			(xy 105.689635 -312.568349) (xy 105.649486 -312.52964) (xy 105.6154 -312.485497) (xy 105.588104 -312.436862)
			(xy 105.568181 -312.384771) (xy 105.556055 -312.330334) (xy 105.551984 -312.274712) (xy 105.29951 -312.274712)
			(xy 105.299001 -312.302598) (xy 105.290881 -312.357774) (xy 105.274813 -312.411181) (xy 105.251141 -312.461678)
			(xy 105.220368 -312.508191) (xy 105.183151 -312.549728) (xy 105.140283 -312.585403) (xy 105.092677 -312.614457)
			(xy 105.041348 -312.636269) (xy 104.987391 -312.650375) (xy 104.931954 -312.656475) (xy 104.87622 -312.654438)
			(xy 104.821377 -312.644308) (xy 104.768593 -312.626301) (xy 104.718993 -312.6008) (xy 104.673635 -312.568349)
			(xy 104.633486 -312.52964) (xy 104.5994 -312.485497) (xy 104.572104 -312.436862) (xy 104.552181 -312.384771)
			(xy 104.540055 -312.330334) (xy 104.535984 -312.274712) (xy 104.28351 -312.274712) (xy 104.283001 -312.302598)
			(xy 104.274881 -312.357774) (xy 104.258813 -312.411181) (xy 104.235141 -312.461678) (xy 104.204368 -312.508191)
			(xy 104.167151 -312.549728) (xy 104.124283 -312.585403) (xy 104.076677 -312.614457) (xy 104.025348 -312.636269)
			(xy 103.971391 -312.650375) (xy 103.915954 -312.656475) (xy 103.86022 -312.654438) (xy 103.805377 -312.644308)
			(xy 103.752593 -312.626301) (xy 103.702993 -312.6008) (xy 103.657635 -312.568349) (xy 103.617486 -312.52964)
			(xy 103.5834 -312.485497) (xy 103.556104 -312.436862) (xy 103.536181 -312.384771) (xy 103.524055 -312.330334)
			(xy 103.519984 -312.274712) (xy 103.26751 -312.274712) (xy 103.267001 -312.302598) (xy 103.258881 -312.357774)
			(xy 103.242813 -312.411181) (xy 103.219141 -312.461678) (xy 103.188368 -312.508191) (xy 103.151151 -312.549728)
			(xy 103.108283 -312.585403) (xy 103.060677 -312.614457) (xy 103.009348 -312.636269) (xy 102.955391 -312.650375)
			(xy 102.899954 -312.656475) (xy 102.84422 -312.654438) (xy 102.789377 -312.644308) (xy 102.736593 -312.626301)
			(xy 102.686993 -312.6008) (xy 102.641635 -312.568349) (xy 102.601486 -312.52964) (xy 102.5674 -312.485497)
			(xy 102.540104 -312.436862) (xy 102.520181 -312.384771) (xy 102.508055 -312.330334) (xy 102.503984 -312.274712)
			(xy 102.25151 -312.274712) (xy 102.251001 -312.302598) (xy 102.242881 -312.357774) (xy 102.226813 -312.411181)
			(xy 102.203141 -312.461678) (xy 102.172368 -312.508191) (xy 102.135151 -312.549728) (xy 102.092283 -312.585403)
			(xy 102.044677 -312.614457) (xy 101.993348 -312.636269) (xy 101.939391 -312.650375) (xy 101.883954 -312.656475)
			(xy 101.82822 -312.654438) (xy 101.773377 -312.644308) (xy 101.720593 -312.626301) (xy 101.670993 -312.6008)
			(xy 101.625635 -312.568349) (xy 101.585486 -312.52964) (xy 101.5514 -312.485497) (xy 101.524104 -312.436862)
			(xy 101.504181 -312.384771) (xy 101.492055 -312.330334) (xy 101.487984 -312.274712) (xy 101.23551 -312.274712)
			(xy 101.235001 -312.302598) (xy 101.226881 -312.357774) (xy 101.210813 -312.411181) (xy 101.187141 -312.461678)
			(xy 101.156368 -312.508191) (xy 101.119151 -312.549728) (xy 101.076283 -312.585403) (xy 101.028677 -312.614457)
			(xy 100.977348 -312.636269) (xy 100.923391 -312.650375) (xy 100.867954 -312.656475) (xy 100.81222 -312.654438)
			(xy 100.757377 -312.644308) (xy 100.704593 -312.626301) (xy 100.654993 -312.6008) (xy 100.609635 -312.568349)
			(xy 100.569486 -312.52964) (xy 100.5354 -312.485497) (xy 100.508104 -312.436862) (xy 100.488181 -312.384771)
			(xy 100.476055 -312.330334) (xy 100.471984 -312.274712) (xy 92.348567 -312.274712) (xy 92.367554 -312.30426)
			(xy 92.39019 -312.353833) (xy 92.405541 -312.406124) (xy 92.413295 -312.460067) (xy 92.413293 -312.514564)
			(xy 92.405535 -312.568506) (xy 92.39018 -312.620795) (xy 92.367539 -312.670367) (xy 92.338074 -312.716212)
			(xy 92.302385 -312.757398) (xy 92.261198 -312.793085) (xy 92.215351 -312.822548) (xy 92.165779 -312.845186)
			(xy 92.113489 -312.860539) (xy 92.059546 -312.868294) (xy 92.005049 -312.868294) (xy 91.951106 -312.860538)
			(xy 91.898816 -312.845184) (xy 91.849244 -312.822545) (xy 91.803398 -312.793082) (xy 91.762211 -312.757394)
			(xy 91.726523 -312.716208) (xy 91.697058 -312.670363) (xy 91.674419 -312.62079) (xy 91.659064 -312.568501)
			(xy 91.651307 -312.514559) (xy 91.65082 -312.48731) (xy 91.651836 -312.458354) (xy 91.652852 -312.447178)
			(xy 91.644978 -312.42635) (xy 91.574112 -312.355992) (xy 91.553284 -312.348626) (xy 91.541854 -312.349642)
			(xy 91.509342 -312.350912) (xy 91.48209 -312.350406) (xy 91.428141 -312.342654) (xy 91.375844 -312.327304)
			(xy 91.326265 -312.304667) (xy 91.280412 -312.275203) (xy 91.239218 -312.239514) (xy 91.203524 -312.198325)
			(xy 91.174055 -312.152476) (xy 91.151412 -312.102899) (xy 91.136055 -312.050604) (xy 91.128298 -311.996656)
			(xy 91.127834 -311.969404) (xy 91.12804 -311.952356) (xy 91.131088 -311.918397) (xy 91.13393 -311.901586)
			(xy 91.136216 -311.88914) (xy 91.12885 -311.865518) (xy 91.051888 -311.788556) (xy 91.028266 -311.78119)
			(xy 91.01582 -311.783476) (xy 90.998949 -311.786345) (xy 90.964861 -311.789398) (xy 90.947748 -311.789572)
			(xy 90.920491 -311.789196) (xy 90.866532 -311.781445) (xy 90.814226 -311.766094) (xy 90.764636 -311.743454)
			(xy 90.718773 -311.713988) (xy 90.677571 -311.678294) (xy 90.641867 -311.637101) (xy 90.61239 -311.591245)
			(xy 90.589739 -311.541661) (xy 90.574374 -311.489358) (xy 90.56661 -311.4354) (xy 90.566604 -311.380887)
			(xy 82.568916 -311.380887) (xy 82.558364 -311.385894) (xy 82.511093 -311.399586) (xy 82.462238 -311.405518)
			(xy 82.413063 -311.403537) (xy 82.364844 -311.393693) (xy 82.318828 -311.376241) (xy 82.276207 -311.351634)
			(xy 82.238086 -311.320509) (xy 82.205451 -311.283672) (xy 82.179148 -311.242076) (xy 82.159857 -311.1968)
			(xy 82.14808 -311.149016) (xy 82.14412 -311.099962) (xy 81.805272 -311.099962) (xy 81.804777 -311.124569)
			(xy 81.796882 -311.173146) (xy 81.781298 -311.219827) (xy 81.758427 -311.263404) (xy 81.728862 -311.302748)
			(xy 81.693369 -311.33684) (xy 81.652866 -311.364796) (xy 81.608404 -311.385894) (xy 81.561133 -311.399586)
			(xy 81.512278 -311.405518) (xy 81.463103 -311.403537) (xy 81.414884 -311.393693) (xy 81.368868 -311.376241)
			(xy 81.326247 -311.351634) (xy 81.288126 -311.320509) (xy 81.255491 -311.283672) (xy 81.229188 -311.242076)
			(xy 81.209897 -311.1968) (xy 81.19812 -311.149016) (xy 81.19416 -311.099962) (xy 80.855058 -311.099962)
			(xy 80.854563 -311.124569) (xy 80.846668 -311.173146) (xy 80.831084 -311.219827) (xy 80.808213 -311.263404)
			(xy 80.778648 -311.302748) (xy 80.743155 -311.33684) (xy 80.702652 -311.364796) (xy 80.65819 -311.385894)
			(xy 80.610919 -311.399586) (xy 80.562064 -311.405518) (xy 80.512889 -311.403537) (xy 80.46467 -311.393693)
			(xy 80.418654 -311.376241) (xy 80.376033 -311.351634) (xy 80.337912 -311.320509) (xy 80.305277 -311.283672)
			(xy 80.278974 -311.242076) (xy 80.259683 -311.1968) (xy 80.247906 -311.149016) (xy 80.243946 -311.099962)
			(xy 79.905098 -311.099962) (xy 79.904603 -311.124569) (xy 79.896708 -311.173146) (xy 79.881124 -311.219827)
			(xy 79.858253 -311.263404) (xy 79.828688 -311.302748) (xy 79.793195 -311.33684) (xy 79.752692 -311.364796)
			(xy 79.70823 -311.385894) (xy 79.660959 -311.399586) (xy 79.612104 -311.405518) (xy 79.562929 -311.403537)
			(xy 79.51471 -311.393693) (xy 79.468694 -311.376241) (xy 79.426073 -311.351634) (xy 79.387952 -311.320509)
			(xy 79.355317 -311.283672) (xy 79.329014 -311.242076) (xy 79.309723 -311.1968) (xy 79.297946 -311.149016)
			(xy 79.293986 -311.099962) (xy 78.955138 -311.099962) (xy 78.954643 -311.124569) (xy 78.946748 -311.173146)
			(xy 78.931164 -311.219827) (xy 78.908293 -311.263404) (xy 78.878728 -311.302748) (xy 78.843235 -311.33684)
			(xy 78.802732 -311.364796) (xy 78.75827 -311.385894) (xy 78.710999 -311.399586) (xy 78.662144 -311.405518)
			(xy 78.612969 -311.403537) (xy 78.56475 -311.393693) (xy 78.518734 -311.376241) (xy 78.476113 -311.351634)
			(xy 78.437992 -311.320509) (xy 78.405357 -311.283672) (xy 78.379054 -311.242076) (xy 78.359763 -311.1968)
			(xy 78.347986 -311.149016) (xy 78.344026 -311.099962) (xy 78.005178 -311.099962) (xy 78.004683 -311.124569)
			(xy 77.996788 -311.173146) (xy 77.981204 -311.219827) (xy 77.958333 -311.263404) (xy 77.928768 -311.302748)
			(xy 77.893275 -311.33684) (xy 77.852772 -311.364796) (xy 77.80831 -311.385894) (xy 77.761039 -311.399586)
			(xy 77.712184 -311.405518) (xy 77.663009 -311.403537) (xy 77.61479 -311.393693) (xy 77.568774 -311.376241)
			(xy 77.526153 -311.351634) (xy 77.488032 -311.320509) (xy 77.455397 -311.283672) (xy 77.429094 -311.242076)
			(xy 77.409803 -311.1968) (xy 77.398026 -311.149016) (xy 77.394066 -311.099962) (xy 77.055218 -311.099962)
			(xy 77.054723 -311.124569) (xy 77.046828 -311.173146) (xy 77.031244 -311.219827) (xy 77.008373 -311.263404)
			(xy 76.978808 -311.302748) (xy 76.943315 -311.33684) (xy 76.902812 -311.364796) (xy 76.85835 -311.385894)
			(xy 76.811079 -311.399586) (xy 76.762224 -311.405518) (xy 76.713049 -311.403537) (xy 76.66483 -311.393693)
			(xy 76.618814 -311.376241) (xy 76.576193 -311.351634) (xy 76.538072 -311.320509) (xy 76.505437 -311.283672)
			(xy 76.479134 -311.242076) (xy 76.459843 -311.1968) (xy 76.448066 -311.149016) (xy 76.444106 -311.099962)
			(xy 76.105258 -311.099962) (xy 76.104763 -311.124569) (xy 76.096868 -311.173146) (xy 76.081284 -311.219827)
			(xy 76.058413 -311.263404) (xy 76.028848 -311.302748) (xy 75.993355 -311.33684) (xy 75.952852 -311.364796)
			(xy 75.90839 -311.385894) (xy 75.861119 -311.399586) (xy 75.812264 -311.405518) (xy 75.763089 -311.403537)
			(xy 75.71487 -311.393693) (xy 75.668854 -311.376241) (xy 75.626233 -311.351634) (xy 75.588112 -311.320509)
			(xy 75.555477 -311.283672) (xy 75.529174 -311.242076) (xy 75.509883 -311.1968) (xy 75.498106 -311.149016)
			(xy 75.494146 -311.099962) (xy 75.155298 -311.099962) (xy 75.154803 -311.124569) (xy 75.146908 -311.173146)
			(xy 75.131324 -311.219827) (xy 75.108453 -311.263404) (xy 75.078888 -311.302748) (xy 75.043395 -311.33684)
			(xy 75.002892 -311.364796) (xy 74.95843 -311.385894) (xy 74.911159 -311.399586) (xy 74.862304 -311.405518)
			(xy 74.813129 -311.403537) (xy 74.76491 -311.393693) (xy 74.718894 -311.376241) (xy 74.676273 -311.351634)
			(xy 74.638152 -311.320509) (xy 74.605517 -311.283672) (xy 74.579214 -311.242076) (xy 74.559923 -311.1968)
			(xy 74.548146 -311.149016) (xy 74.544186 -311.099962) (xy 74.205084 -311.099962) (xy 74.204589 -311.124569)
			(xy 74.196694 -311.173146) (xy 74.18111 -311.219827) (xy 74.158239 -311.263404) (xy 74.128674 -311.302748)
			(xy 74.093181 -311.33684) (xy 74.052678 -311.364796) (xy 74.008216 -311.385894) (xy 73.960945 -311.399586)
			(xy 73.91209 -311.405518) (xy 73.862915 -311.403537) (xy 73.814696 -311.393693) (xy 73.76868 -311.376241)
			(xy 73.726059 -311.351634) (xy 73.687938 -311.320509) (xy 73.655303 -311.283672) (xy 73.629 -311.242076)
			(xy 73.609709 -311.1968) (xy 73.597932 -311.149016) (xy 73.593972 -311.099962) (xy 73.255124 -311.099962)
			(xy 73.254629 -311.124569) (xy 73.246734 -311.173146) (xy 73.23115 -311.219827) (xy 73.208279 -311.263404)
			(xy 73.178714 -311.302748) (xy 73.143221 -311.33684) (xy 73.102718 -311.364796) (xy 73.058256 -311.385894)
			(xy 73.010985 -311.399586) (xy 72.96213 -311.405518) (xy 72.912955 -311.403537) (xy 72.864736 -311.393693)
			(xy 72.81872 -311.376241) (xy 72.776099 -311.351634) (xy 72.737978 -311.320509) (xy 72.705343 -311.283672)
			(xy 72.67904 -311.242076) (xy 72.659749 -311.1968) (xy 72.647972 -311.149016) (xy 72.644012 -311.099962)
			(xy 72.327008 -311.099962) (xy 72.326504 -311.12567) (xy 72.318461 -311.176452) (xy 72.302573 -311.225351)
			(xy 72.27923 -311.271163) (xy 72.249009 -311.312759) (xy 72.212653 -311.349115) (xy 72.171057 -311.379336)
			(xy 72.125245 -311.402679) (xy 72.076346 -311.418567) (xy 72.025564 -311.42661) (xy 71.974148 -311.42661)
			(xy 71.923366 -311.418567) (xy 71.874467 -311.402679) (xy 71.828655 -311.379336) (xy 71.787059 -311.349115)
			(xy 71.750703 -311.312759) (xy 71.720482 -311.271163) (xy 71.697139 -311.225351) (xy 71.681251 -311.176452)
			(xy 71.673208 -311.12567) (xy 71.35453 -311.12567) (xy 71.346814 -311.173146) (xy 71.33123 -311.219827)
			(xy 71.308359 -311.263404) (xy 71.278794 -311.302748) (xy 71.243301 -311.33684) (xy 71.202798 -311.364796)
			(xy 71.158336 -311.385894) (xy 71.111065 -311.399586) (xy 71.06221 -311.405518) (xy 71.013035 -311.403537)
			(xy 70.964816 -311.393693) (xy 70.9188 -311.376241) (xy 70.876179 -311.351634) (xy 70.838058 -311.320509)
			(xy 70.805423 -311.283672) (xy 70.77912 -311.242076) (xy 70.759829 -311.1968) (xy 70.748052 -311.149016)
			(xy 70.744092 -311.099962) (xy 70.427088 -311.099962) (xy 70.426584 -311.12567) (xy 70.418541 -311.176452)
			(xy 70.402653 -311.225351) (xy 70.37931 -311.271163) (xy 70.349089 -311.312759) (xy 70.312733 -311.349115)
			(xy 70.271137 -311.379336) (xy 70.225325 -311.402679) (xy 70.176426 -311.418567) (xy 70.125644 -311.42661)
			(xy 70.074228 -311.42661) (xy 70.023446 -311.418567) (xy 69.974547 -311.402679) (xy 69.928735 -311.379336)
			(xy 69.887139 -311.349115) (xy 69.850783 -311.312759) (xy 69.820562 -311.271163) (xy 69.797219 -311.225351)
			(xy 69.781331 -311.176452) (xy 69.773288 -311.12567) (xy 69.45461 -311.12567) (xy 69.446894 -311.173146)
			(xy 69.43131 -311.219827) (xy 69.408439 -311.263404) (xy 69.378874 -311.302748) (xy 69.343381 -311.33684)
			(xy 69.302878 -311.364796) (xy 69.258416 -311.385894) (xy 69.211145 -311.399586) (xy 69.16229 -311.405518)
			(xy 69.113115 -311.403537) (xy 69.064896 -311.393693) (xy 69.01888 -311.376241) (xy 68.976259 -311.351634)
			(xy 68.938138 -311.320509) (xy 68.905503 -311.283672) (xy 68.8792 -311.242076) (xy 68.859909 -311.1968)
			(xy 68.848132 -311.149016) (xy 68.844172 -311.099962) (xy 68.526914 -311.099962) (xy 68.52641 -311.12567)
			(xy 68.518367 -311.176452) (xy 68.502479 -311.225351) (xy 68.479136 -311.271163) (xy 68.448915 -311.312759)
			(xy 68.412559 -311.349115) (xy 68.370963 -311.379336) (xy 68.325151 -311.402679) (xy 68.276252 -311.418567)
			(xy 68.22547 -311.42661) (xy 68.174054 -311.42661) (xy 68.123272 -311.418567) (xy 68.074373 -311.402679)
			(xy 68.028561 -311.379336) (xy 67.986965 -311.349115) (xy 67.950609 -311.312759) (xy 67.920388 -311.271163)
			(xy 67.897045 -311.225351) (xy 67.881157 -311.176452) (xy 67.873114 -311.12567) (xy 67.554436 -311.12567)
			(xy 67.54672 -311.173146) (xy 67.531136 -311.219827) (xy 67.508265 -311.263404) (xy 67.4787 -311.302748)
			(xy 67.443207 -311.33684) (xy 67.402704 -311.364796) (xy 67.358242 -311.385894) (xy 67.310971 -311.399586)
			(xy 67.262116 -311.405518) (xy 67.212941 -311.403537) (xy 67.164722 -311.393693) (xy 67.118706 -311.376241)
			(xy 67.076085 -311.351634) (xy 67.037964 -311.320509) (xy 67.005329 -311.283672) (xy 66.979026 -311.242076)
			(xy 66.959735 -311.1968) (xy 66.947958 -311.149016) (xy 66.943998 -311.099962) (xy 66.626994 -311.099962)
			(xy 66.62649 -311.12567) (xy 66.618447 -311.176452) (xy 66.602559 -311.225351) (xy 66.579216 -311.271163)
			(xy 66.548995 -311.312759) (xy 66.512639 -311.349115) (xy 66.471043 -311.379336) (xy 66.425231 -311.402679)
			(xy 66.376332 -311.418567) (xy 66.32555 -311.42661) (xy 66.274134 -311.42661) (xy 66.223352 -311.418567)
			(xy 66.174453 -311.402679) (xy 66.128641 -311.379336) (xy 66.087045 -311.349115) (xy 66.050689 -311.312759)
			(xy 66.020468 -311.271163) (xy 65.997125 -311.225351) (xy 65.981237 -311.176452) (xy 65.973194 -311.12567)
			(xy 65.654516 -311.12567) (xy 65.6468 -311.173146) (xy 65.631216 -311.219827) (xy 65.608345 -311.263404)
			(xy 65.57878 -311.302748) (xy 65.543287 -311.33684) (xy 65.502784 -311.364796) (xy 65.458322 -311.385894)
			(xy 65.411051 -311.399586) (xy 65.362196 -311.405518) (xy 65.313021 -311.403537) (xy 65.264802 -311.393693)
			(xy 65.218786 -311.376241) (xy 65.176165 -311.351634) (xy 65.138044 -311.320509) (xy 65.105409 -311.283672)
			(xy 65.079106 -311.242076) (xy 65.059815 -311.1968) (xy 65.048038 -311.149016) (xy 65.044078 -311.099962)
			(xy 64.727074 -311.099962) (xy 64.72657 -311.12567) (xy 64.718527 -311.176452) (xy 64.702639 -311.225351)
			(xy 64.679296 -311.271163) (xy 64.649075 -311.312759) (xy 64.612719 -311.349115) (xy 64.571123 -311.379336)
			(xy 64.525311 -311.402679) (xy 64.476412 -311.418567) (xy 64.42563 -311.42661) (xy 64.374214 -311.42661)
			(xy 64.323432 -311.418567) (xy 64.274533 -311.402679) (xy 64.228721 -311.379336) (xy 64.187125 -311.349115)
			(xy 64.150769 -311.312759) (xy 64.120548 -311.271163) (xy 64.097205 -311.225351) (xy 64.081317 -311.176452)
			(xy 64.073274 -311.12567) (xy 63.754596 -311.12567) (xy 63.74688 -311.173146) (xy 63.731296 -311.219827)
			(xy 63.708425 -311.263404) (xy 63.67886 -311.302748) (xy 63.643367 -311.33684) (xy 63.602864 -311.364796)
			(xy 63.558402 -311.385894) (xy 63.511131 -311.399586) (xy 63.462276 -311.405518) (xy 63.413101 -311.403537)
			(xy 63.364882 -311.393693) (xy 63.318866 -311.376241) (xy 63.276245 -311.351634) (xy 63.238124 -311.320509)
			(xy 63.205489 -311.283672) (xy 63.179186 -311.242076) (xy 63.159895 -311.1968) (xy 63.148118 -311.149016)
			(xy 63.144158 -311.099962) (xy 62.8269 -311.099962) (xy 62.826396 -311.12567) (xy 62.818353 -311.176452)
			(xy 62.802465 -311.225351) (xy 62.779122 -311.271163) (xy 62.748901 -311.312759) (xy 62.712545 -311.349115)
			(xy 62.670949 -311.379336) (xy 62.625137 -311.402679) (xy 62.576238 -311.418567) (xy 62.525456 -311.42661)
			(xy 62.47404 -311.42661) (xy 62.423258 -311.418567) (xy 62.374359 -311.402679) (xy 62.328547 -311.379336)
			(xy 62.286951 -311.349115) (xy 62.250595 -311.312759) (xy 62.220374 -311.271163) (xy 62.197031 -311.225351)
			(xy 62.181143 -311.176452) (xy 62.1731 -311.12567) (xy 61.854422 -311.12567) (xy 61.846706 -311.173146)
			(xy 61.831122 -311.219827) (xy 61.808251 -311.263404) (xy 61.778686 -311.302748) (xy 61.743193 -311.33684)
			(xy 61.70269 -311.364796) (xy 61.658228 -311.385894) (xy 61.610957 -311.399586) (xy 61.562102 -311.405518)
			(xy 61.512927 -311.403537) (xy 61.464708 -311.393693) (xy 61.418692 -311.376241) (xy 61.376071 -311.351634)
			(xy 61.33795 -311.320509) (xy 61.305315 -311.283672) (xy 61.279012 -311.242076) (xy 61.259721 -311.1968)
			(xy 61.247944 -311.149016) (xy 61.243984 -311.099962) (xy 60.92698 -311.099962) (xy 60.926476 -311.12567)
			(xy 60.918433 -311.176452) (xy 60.902545 -311.225351) (xy 60.879202 -311.271163) (xy 60.848981 -311.312759)
			(xy 60.812625 -311.349115) (xy 60.771029 -311.379336) (xy 60.725217 -311.402679) (xy 60.676318 -311.418567)
			(xy 60.625536 -311.42661) (xy 60.57412 -311.42661) (xy 60.523338 -311.418567) (xy 60.474439 -311.402679)
			(xy 60.428627 -311.379336) (xy 60.387031 -311.349115) (xy 60.350675 -311.312759) (xy 60.320454 -311.271163)
			(xy 60.297111 -311.225351) (xy 60.281223 -311.176452) (xy 60.27318 -311.12567) (xy 59.954502 -311.12567)
			(xy 59.946786 -311.173146) (xy 59.931202 -311.219827) (xy 59.908331 -311.263404) (xy 59.878766 -311.302748)
			(xy 59.843273 -311.33684) (xy 59.80277 -311.364796) (xy 59.758308 -311.385894) (xy 59.711037 -311.399586)
			(xy 59.662182 -311.405518) (xy 59.613007 -311.403537) (xy 59.564788 -311.393693) (xy 59.518772 -311.376241)
			(xy 59.476151 -311.351634) (xy 59.43803 -311.320509) (xy 59.405395 -311.283672) (xy 59.379092 -311.242076)
			(xy 59.359801 -311.1968) (xy 59.348024 -311.149016) (xy 59.344064 -311.099962) (xy 59.02706 -311.099962)
			(xy 59.026556 -311.12567) (xy 59.018513 -311.176452) (xy 59.002625 -311.225351) (xy 58.979282 -311.271163)
			(xy 58.949061 -311.312759) (xy 58.912705 -311.349115) (xy 58.871109 -311.379336) (xy 58.825297 -311.402679)
			(xy 58.776398 -311.418567) (xy 58.725616 -311.42661) (xy 58.6742 -311.42661) (xy 58.623418 -311.418567)
			(xy 58.574519 -311.402679) (xy 58.528707 -311.379336) (xy 58.487111 -311.349115) (xy 58.450755 -311.312759)
			(xy 58.420534 -311.271163) (xy 58.397191 -311.225351) (xy 58.381303 -311.176452) (xy 58.37326 -311.12567)
			(xy 58.054582 -311.12567) (xy 58.046866 -311.173146) (xy 58.031282 -311.219827) (xy 58.008411 -311.263404)
			(xy 57.978846 -311.302748) (xy 57.943353 -311.33684) (xy 57.90285 -311.364796) (xy 57.858388 -311.385894)
			(xy 57.811117 -311.399586) (xy 57.762262 -311.405518) (xy 57.713087 -311.403537) (xy 57.664868 -311.393693)
			(xy 57.618852 -311.376241) (xy 57.576231 -311.351634) (xy 57.53811 -311.320509) (xy 57.505475 -311.283672)
			(xy 57.479172 -311.242076) (xy 57.459881 -311.1968) (xy 57.448104 -311.149016) (xy 57.444144 -311.099962)
			(xy 57.105296 -311.099962) (xy 57.104801 -311.124569) (xy 57.096906 -311.173146) (xy 57.081322 -311.219827)
			(xy 57.058451 -311.263404) (xy 57.028886 -311.302748) (xy 56.993393 -311.33684) (xy 56.95289 -311.364796)
			(xy 56.908428 -311.385894) (xy 56.861157 -311.399586) (xy 56.812302 -311.405518) (xy 56.763127 -311.403537)
			(xy 56.714908 -311.393693) (xy 56.668892 -311.376241) (xy 56.626271 -311.351634) (xy 56.58815 -311.320509)
			(xy 56.555515 -311.283672) (xy 56.529212 -311.242076) (xy 56.509921 -311.1968) (xy 56.498144 -311.149016)
			(xy 56.494184 -311.099962) (xy 56.155082 -311.099962) (xy 56.154587 -311.124569) (xy 56.146692 -311.173146)
			(xy 56.131108 -311.219827) (xy 56.108237 -311.263404) (xy 56.078672 -311.302748) (xy 56.043179 -311.33684)
			(xy 56.002676 -311.364796) (xy 55.958214 -311.385894) (xy 55.910943 -311.399586) (xy 55.862088 -311.405518)
			(xy 55.812913 -311.403537) (xy 55.764694 -311.393693) (xy 55.718678 -311.376241) (xy 55.676057 -311.351634)
			(xy 55.637936 -311.320509) (xy 55.605301 -311.283672) (xy 55.578998 -311.242076) (xy 55.559707 -311.1968)
			(xy 55.54793 -311.149016) (xy 55.54397 -311.099962) (xy 55.205122 -311.099962) (xy 55.204627 -311.124569)
			(xy 55.196732 -311.173146) (xy 55.181148 -311.219827) (xy 55.158277 -311.263404) (xy 55.128712 -311.302748)
			(xy 55.093219 -311.33684) (xy 55.052716 -311.364796) (xy 55.008254 -311.385894) (xy 54.960983 -311.399586)
			(xy 54.912128 -311.405518) (xy 54.862953 -311.403537) (xy 54.814734 -311.393693) (xy 54.768718 -311.376241)
			(xy 54.726097 -311.351634) (xy 54.687976 -311.320509) (xy 54.655341 -311.283672) (xy 54.629038 -311.242076)
			(xy 54.609747 -311.1968) (xy 54.59797 -311.149016) (xy 54.59401 -311.099962) (xy 54.255162 -311.099962)
			(xy 54.254667 -311.124569) (xy 54.246772 -311.173146) (xy 54.231188 -311.219827) (xy 54.208317 -311.263404)
			(xy 54.178752 -311.302748) (xy 54.143259 -311.33684) (xy 54.102756 -311.364796) (xy 54.058294 -311.385894)
			(xy 54.011023 -311.399586) (xy 53.962168 -311.405518) (xy 53.912993 -311.403537) (xy 53.864774 -311.393693)
			(xy 53.818758 -311.376241) (xy 53.776137 -311.351634) (xy 53.738016 -311.320509) (xy 53.705381 -311.283672)
			(xy 53.679078 -311.242076) (xy 53.659787 -311.1968) (xy 53.64801 -311.149016) (xy 53.64405 -311.099962)
			(xy 53.305202 -311.099962) (xy 53.304707 -311.124569) (xy 53.296812 -311.173146) (xy 53.281228 -311.219827)
			(xy 53.258357 -311.263404) (xy 53.228792 -311.302748) (xy 53.193299 -311.33684) (xy 53.152796 -311.364796)
			(xy 53.108334 -311.385894) (xy 53.061063 -311.399586) (xy 53.012208 -311.405518) (xy 52.963033 -311.403537)
			(xy 52.914814 -311.393693) (xy 52.868798 -311.376241) (xy 52.826177 -311.351634) (xy 52.788056 -311.320509)
			(xy 52.755421 -311.283672) (xy 52.729118 -311.242076) (xy 52.709827 -311.1968) (xy 52.69805 -311.149016)
			(xy 52.69409 -311.099962) (xy 52.355242 -311.099962) (xy 52.354747 -311.124569) (xy 52.346852 -311.173146)
			(xy 52.331268 -311.219827) (xy 52.308397 -311.263404) (xy 52.278832 -311.302748) (xy 52.243339 -311.33684)
			(xy 52.202836 -311.364796) (xy 52.158374 -311.385894) (xy 52.111103 -311.399586) (xy 52.062248 -311.405518)
			(xy 52.013073 -311.403537) (xy 51.964854 -311.393693) (xy 51.918838 -311.376241) (xy 51.876217 -311.351634)
			(xy 51.838096 -311.320509) (xy 51.805461 -311.283672) (xy 51.779158 -311.242076) (xy 51.759867 -311.1968)
			(xy 51.74809 -311.149016) (xy 51.74413 -311.099962) (xy 51.405282 -311.099962) (xy 51.404787 -311.124569)
			(xy 51.396892 -311.173146) (xy 51.381308 -311.219827) (xy 51.358437 -311.263404) (xy 51.328872 -311.302748)
			(xy 51.293379 -311.33684) (xy 51.252876 -311.364796) (xy 51.208414 -311.385894) (xy 51.161143 -311.399586)
			(xy 51.112288 -311.405518) (xy 51.063113 -311.403537) (xy 51.014894 -311.393693) (xy 50.968878 -311.376241)
			(xy 50.926257 -311.351634) (xy 50.888136 -311.320509) (xy 50.855501 -311.283672) (xy 50.829198 -311.242076)
			(xy 50.809907 -311.1968) (xy 50.79813 -311.149016) (xy 50.79417 -311.099962) (xy 50.455068 -311.099962)
			(xy 50.454573 -311.124569) (xy 50.446678 -311.173146) (xy 50.431094 -311.219827) (xy 50.408223 -311.263404)
			(xy 50.378658 -311.302748) (xy 50.343165 -311.33684) (xy 50.302662 -311.364796) (xy 50.2582 -311.385894)
			(xy 50.210929 -311.399586) (xy 50.162074 -311.405518) (xy 50.112899 -311.403537) (xy 50.06468 -311.393693)
			(xy 50.018664 -311.376241) (xy 49.976043 -311.351634) (xy 49.937922 -311.320509) (xy 49.905287 -311.283672)
			(xy 49.878984 -311.242076) (xy 49.859693 -311.1968) (xy 49.847916 -311.149016) (xy 49.843956 -311.099962)
			(xy 49.505666 -311.099962) (xy 49.505669 -311.1) (xy 49.501497 -311.150344) (xy 49.489096 -311.199316)
			(xy 49.468804 -311.245578) (xy 49.441174 -311.287869) (xy 49.406959 -311.325035) (xy 49.367094 -311.356063)
			(xy 49.322666 -311.380107) (xy 49.274886 -311.396509) (xy 49.225058 -311.404824) (xy 49.1998 -311.40527)
			(xy 49.167796 -311.403492) (xy 49.156874 -311.402476) (xy 49.136554 -311.40908) (xy 49.072292 -311.466738)
			(xy 49.064644 -311.47426) (xy 49.055984 -311.493864) (xy 49.055528 -311.504584) (xy 49.055528 -311.574942)
			(xy 49.055367 -311.588596) (xy 49.053077 -311.615809) (xy 49.050956 -311.629298) (xy 49.048924 -311.641236)
			(xy 49.056036 -311.663842) (xy 49.128934 -311.740296) (xy 49.151286 -311.74817) (xy 49.163478 -311.7469)
			(xy 49.172522 -311.745852) (xy 49.190696 -311.744708) (xy 49.1998 -311.744614) (xy 49.225054 -311.745135)
			(xy 49.274872 -311.753449) (xy 49.322642 -311.769848) (xy 49.367062 -311.793887) (xy 49.406919 -311.824909)
			(xy 49.441126 -311.862068) (xy 49.468751 -311.904351) (xy 49.489039 -311.950604) (xy 49.501438 -311.999565)
			(xy 49.505609 -312.0499) (xy 49.505607 -312.049922) (xy 49.843956 -312.049922) (xy 49.847916 -312.000868)
			(xy 49.859693 -311.953084) (xy 49.878984 -311.907808) (xy 49.905287 -311.866212) (xy 49.937922 -311.829375)
			(xy 49.976043 -311.79825) (xy 50.018664 -311.773643) (xy 50.06468 -311.756191) (xy 50.112899 -311.746347)
			(xy 50.162074 -311.744366) (xy 50.210929 -311.750298) (xy 50.2582 -311.76399) (xy 50.302662 -311.785088)
			(xy 50.343165 -311.813044) (xy 50.378658 -311.847136) (xy 50.408223 -311.88648) (xy 50.431094 -311.930057)
			(xy 50.446678 -311.976738) (xy 50.454573 -312.025315) (xy 50.455068 -312.049922) (xy 50.79417 -312.049922)
			(xy 50.79813 -312.000868) (xy 50.809907 -311.953084) (xy 50.829198 -311.907808) (xy 50.855501 -311.866212)
			(xy 50.888136 -311.829375) (xy 50.926257 -311.79825) (xy 50.968878 -311.773643) (xy 51.014894 -311.756191)
			(xy 51.063113 -311.746347) (xy 51.112288 -311.744366) (xy 51.161143 -311.750298) (xy 51.208414 -311.76399)
			(xy 51.252876 -311.785088) (xy 51.293379 -311.813044) (xy 51.328872 -311.847136) (xy 51.358437 -311.88648)
			(xy 51.381308 -311.930057) (xy 51.396892 -311.976738) (xy 51.404787 -312.025315) (xy 51.405282 -312.049922)
			(xy 51.74413 -312.049922) (xy 51.74809 -312.000868) (xy 51.759867 -311.953084) (xy 51.779158 -311.907808)
			(xy 51.805461 -311.866212) (xy 51.838096 -311.829375) (xy 51.876217 -311.79825) (xy 51.918838 -311.773643)
			(xy 51.964854 -311.756191) (xy 52.013073 -311.746347) (xy 52.062248 -311.744366) (xy 52.111103 -311.750298)
			(xy 52.158374 -311.76399) (xy 52.202836 -311.785088) (xy 52.243339 -311.813044) (xy 52.278832 -311.847136)
			(xy 52.308397 -311.88648) (xy 52.331268 -311.930057) (xy 52.346852 -311.976738) (xy 52.354747 -312.025315)
			(xy 52.355242 -312.049922) (xy 52.69409 -312.049922) (xy 52.69805 -312.000868) (xy 52.709827 -311.953084)
			(xy 52.729118 -311.907808) (xy 52.755421 -311.866212) (xy 52.788056 -311.829375) (xy 52.826177 -311.79825)
			(xy 52.868798 -311.773643) (xy 52.914814 -311.756191) (xy 52.963033 -311.746347) (xy 53.012208 -311.744366)
			(xy 53.061063 -311.750298) (xy 53.108334 -311.76399) (xy 53.152796 -311.785088) (xy 53.193299 -311.813044)
			(xy 53.228792 -311.847136) (xy 53.258357 -311.88648) (xy 53.281228 -311.930057) (xy 53.296812 -311.976738)
			(xy 53.304707 -312.025315) (xy 53.305202 -312.049922) (xy 53.64405 -312.049922) (xy 53.64801 -312.000868)
			(xy 53.659787 -311.953084) (xy 53.679078 -311.907808) (xy 53.705381 -311.866212) (xy 53.738016 -311.829375)
			(xy 53.776137 -311.79825) (xy 53.818758 -311.773643) (xy 53.864774 -311.756191) (xy 53.912993 -311.746347)
			(xy 53.962168 -311.744366) (xy 54.011023 -311.750298) (xy 54.058294 -311.76399) (xy 54.102756 -311.785088)
			(xy 54.143259 -311.813044) (xy 54.178752 -311.847136) (xy 54.208317 -311.88648) (xy 54.231188 -311.930057)
			(xy 54.246772 -311.976738) (xy 54.254667 -312.025315) (xy 54.255162 -312.049922) (xy 54.59401 -312.049922)
			(xy 54.59797 -312.000868) (xy 54.609747 -311.953084) (xy 54.629038 -311.907808) (xy 54.655341 -311.866212)
			(xy 54.687976 -311.829375) (xy 54.726097 -311.79825) (xy 54.768718 -311.773643) (xy 54.814734 -311.756191)
			(xy 54.862953 -311.746347) (xy 54.912128 -311.744366) (xy 54.960983 -311.750298) (xy 55.008254 -311.76399)
			(xy 55.052716 -311.785088) (xy 55.093219 -311.813044) (xy 55.128712 -311.847136) (xy 55.158277 -311.88648)
			(xy 55.181148 -311.930057) (xy 55.196732 -311.976738) (xy 55.204627 -312.025315) (xy 55.205122 -312.049922)
			(xy 55.54397 -312.049922) (xy 55.54793 -312.000868) (xy 55.559707 -311.953084) (xy 55.578998 -311.907808)
			(xy 55.605301 -311.866212) (xy 55.637936 -311.829375) (xy 55.676057 -311.79825) (xy 55.718678 -311.773643)
			(xy 55.764694 -311.756191) (xy 55.812913 -311.746347) (xy 55.862088 -311.744366) (xy 55.910943 -311.750298)
			(xy 55.958214 -311.76399) (xy 56.002676 -311.785088) (xy 56.043179 -311.813044) (xy 56.078672 -311.847136)
			(xy 56.108237 -311.88648) (xy 56.131108 -311.930057) (xy 56.146692 -311.976738) (xy 56.154587 -312.025315)
			(xy 56.155082 -312.049922) (xy 56.494184 -312.049922) (xy 56.498144 -312.000868) (xy 56.509921 -311.953084)
			(xy 56.529212 -311.907808) (xy 56.555515 -311.866212) (xy 56.58815 -311.829375) (xy 56.626271 -311.79825)
			(xy 56.668892 -311.773643) (xy 56.714908 -311.756191) (xy 56.763127 -311.746347) (xy 56.812302 -311.744366)
			(xy 56.861157 -311.750298) (xy 56.908428 -311.76399) (xy 56.95289 -311.785088) (xy 56.993393 -311.813044)
			(xy 57.028886 -311.847136) (xy 57.058451 -311.88648) (xy 57.081322 -311.930057) (xy 57.096906 -311.976738)
			(xy 57.104801 -312.025315) (xy 57.105296 -312.049922) (xy 57.444144 -312.049922) (xy 57.448104 -312.000868)
			(xy 57.459881 -311.953084) (xy 57.479172 -311.907808) (xy 57.505475 -311.866212) (xy 57.53811 -311.829375)
			(xy 57.576231 -311.79825) (xy 57.618852 -311.773643) (xy 57.664868 -311.756191) (xy 57.713087 -311.746347)
			(xy 57.762262 -311.744366) (xy 57.811117 -311.750298) (xy 57.858388 -311.76399) (xy 57.90285 -311.785088)
			(xy 57.943353 -311.813044) (xy 57.978846 -311.847136) (xy 58.008411 -311.88648) (xy 58.031282 -311.930057)
			(xy 58.046866 -311.976738) (xy 58.054761 -312.025315) (xy 58.055256 -312.049922) (xy 58.054761 -312.074529)
			(xy 58.054582 -312.07563) (xy 58.37326 -312.07563) (xy 58.37326 -312.024214) (xy 58.381303 -311.973432)
			(xy 58.397191 -311.924533) (xy 58.420534 -311.878721) (xy 58.450755 -311.837125) (xy 58.487111 -311.800769)
			(xy 58.528707 -311.770548) (xy 58.574519 -311.747205) (xy 58.623418 -311.731317) (xy 58.6742 -311.723274)
			(xy 58.725616 -311.723274) (xy 58.776398 -311.731317) (xy 58.825297 -311.747205) (xy 58.871109 -311.770548)
			(xy 58.912705 -311.800769) (xy 58.949061 -311.837125) (xy 58.979282 -311.878721) (xy 59.002625 -311.924533)
			(xy 59.018513 -311.973432) (xy 59.026556 -312.024214) (xy 59.02706 -312.049922) (xy 59.344064 -312.049922)
			(xy 59.348024 -312.000868) (xy 59.359801 -311.953084) (xy 59.379092 -311.907808) (xy 59.405395 -311.866212)
			(xy 59.43803 -311.829375) (xy 59.476151 -311.79825) (xy 59.518772 -311.773643) (xy 59.564788 -311.756191)
			(xy 59.613007 -311.746347) (xy 59.662182 -311.744366) (xy 59.711037 -311.750298) (xy 59.758308 -311.76399)
			(xy 59.80277 -311.785088) (xy 59.843273 -311.813044) (xy 59.878766 -311.847136) (xy 59.908331 -311.88648)
			(xy 59.931202 -311.930057) (xy 59.946786 -311.976738) (xy 59.954681 -312.025315) (xy 59.955176 -312.049922)
			(xy 59.954681 -312.074529) (xy 59.954502 -312.07563) (xy 60.27318 -312.07563) (xy 60.27318 -312.024214)
			(xy 60.281223 -311.973432) (xy 60.297111 -311.924533) (xy 60.320454 -311.878721) (xy 60.350675 -311.837125)
			(xy 60.387031 -311.800769) (xy 60.428627 -311.770548) (xy 60.474439 -311.747205) (xy 60.523338 -311.731317)
			(xy 60.57412 -311.723274) (xy 60.625536 -311.723274) (xy 60.676318 -311.731317) (xy 60.725217 -311.747205)
			(xy 60.771029 -311.770548) (xy 60.812625 -311.800769) (xy 60.848981 -311.837125) (xy 60.879202 -311.878721)
			(xy 60.902545 -311.924533) (xy 60.918433 -311.973432) (xy 60.926476 -312.024214) (xy 60.92698 -312.049922)
			(xy 61.243984 -312.049922) (xy 61.247944 -312.000868) (xy 61.259721 -311.953084) (xy 61.279012 -311.907808)
			(xy 61.305315 -311.866212) (xy 61.33795 -311.829375) (xy 61.376071 -311.79825) (xy 61.418692 -311.773643)
			(xy 61.464708 -311.756191) (xy 61.512927 -311.746347) (xy 61.562102 -311.744366) (xy 61.610957 -311.750298)
			(xy 61.658228 -311.76399) (xy 61.70269 -311.785088) (xy 61.743193 -311.813044) (xy 61.778686 -311.847136)
			(xy 61.808251 -311.88648) (xy 61.831122 -311.930057) (xy 61.846706 -311.976738) (xy 61.854601 -312.025315)
			(xy 61.855096 -312.049922) (xy 61.854601 -312.074529) (xy 61.854422 -312.07563) (xy 62.1731 -312.07563)
			(xy 62.1731 -312.024214) (xy 62.181143 -311.973432) (xy 62.197031 -311.924533) (xy 62.220374 -311.878721)
			(xy 62.250595 -311.837125) (xy 62.286951 -311.800769) (xy 62.328547 -311.770548) (xy 62.374359 -311.747205)
			(xy 62.423258 -311.731317) (xy 62.47404 -311.723274) (xy 62.525456 -311.723274) (xy 62.576238 -311.731317)
			(xy 62.625137 -311.747205) (xy 62.670949 -311.770548) (xy 62.712545 -311.800769) (xy 62.748901 -311.837125)
			(xy 62.779122 -311.878721) (xy 62.802465 -311.924533) (xy 62.818353 -311.973432) (xy 62.826396 -312.024214)
			(xy 62.8269 -312.049922) (xy 63.144158 -312.049922) (xy 63.148118 -312.000868) (xy 63.159895 -311.953084)
			(xy 63.179186 -311.907808) (xy 63.205489 -311.866212) (xy 63.238124 -311.829375) (xy 63.276245 -311.79825)
			(xy 63.318866 -311.773643) (xy 63.364882 -311.756191) (xy 63.413101 -311.746347) (xy 63.462276 -311.744366)
			(xy 63.511131 -311.750298) (xy 63.558402 -311.76399) (xy 63.602864 -311.785088) (xy 63.643367 -311.813044)
			(xy 63.67886 -311.847136) (xy 63.708425 -311.88648) (xy 63.731296 -311.930057) (xy 63.74688 -311.976738)
			(xy 63.754775 -312.025315) (xy 63.75527 -312.049922) (xy 63.754775 -312.074529) (xy 63.754596 -312.07563)
			(xy 64.073274 -312.07563) (xy 64.073274 -312.024214) (xy 64.081317 -311.973432) (xy 64.097205 -311.924533)
			(xy 64.120548 -311.878721) (xy 64.150769 -311.837125) (xy 64.187125 -311.800769) (xy 64.228721 -311.770548)
			(xy 64.274533 -311.747205) (xy 64.323432 -311.731317) (xy 64.374214 -311.723274) (xy 64.42563 -311.723274)
			(xy 64.476412 -311.731317) (xy 64.525311 -311.747205) (xy 64.571123 -311.770548) (xy 64.612719 -311.800769)
			(xy 64.649075 -311.837125) (xy 64.679296 -311.878721) (xy 64.702639 -311.924533) (xy 64.718527 -311.973432)
			(xy 64.72657 -312.024214) (xy 64.727074 -312.049922) (xy 65.044078 -312.049922) (xy 65.048038 -312.000868)
			(xy 65.059815 -311.953084) (xy 65.079106 -311.907808) (xy 65.105409 -311.866212) (xy 65.138044 -311.829375)
			(xy 65.176165 -311.79825) (xy 65.218786 -311.773643) (xy 65.264802 -311.756191) (xy 65.313021 -311.746347)
			(xy 65.362196 -311.744366) (xy 65.411051 -311.750298) (xy 65.458322 -311.76399) (xy 65.502784 -311.785088)
			(xy 65.543287 -311.813044) (xy 65.57878 -311.847136) (xy 65.608345 -311.88648) (xy 65.631216 -311.930057)
			(xy 65.6468 -311.976738) (xy 65.654695 -312.025315) (xy 65.65519 -312.049922) (xy 65.654695 -312.074529)
			(xy 65.654516 -312.07563) (xy 65.973194 -312.07563) (xy 65.973194 -312.024214) (xy 65.981237 -311.973432)
			(xy 65.997125 -311.924533) (xy 66.020468 -311.878721) (xy 66.050689 -311.837125) (xy 66.087045 -311.800769)
			(xy 66.128641 -311.770548) (xy 66.174453 -311.747205) (xy 66.223352 -311.731317) (xy 66.274134 -311.723274)
			(xy 66.32555 -311.723274) (xy 66.376332 -311.731317) (xy 66.425231 -311.747205) (xy 66.471043 -311.770548)
			(xy 66.512639 -311.800769) (xy 66.548995 -311.837125) (xy 66.579216 -311.878721) (xy 66.602559 -311.924533)
			(xy 66.618447 -311.973432) (xy 66.62649 -312.024214) (xy 66.626994 -312.049922) (xy 66.943998 -312.049922)
			(xy 66.947958 -312.000868) (xy 66.959735 -311.953084) (xy 66.979026 -311.907808) (xy 67.005329 -311.866212)
			(xy 67.037964 -311.829375) (xy 67.076085 -311.79825) (xy 67.118706 -311.773643) (xy 67.164722 -311.756191)
			(xy 67.212941 -311.746347) (xy 67.262116 -311.744366) (xy 67.310971 -311.750298) (xy 67.358242 -311.76399)
			(xy 67.402704 -311.785088) (xy 67.443207 -311.813044) (xy 67.4787 -311.847136) (xy 67.508265 -311.88648)
			(xy 67.531136 -311.930057) (xy 67.54672 -311.976738) (xy 67.554615 -312.025315) (xy 67.55511 -312.049922)
			(xy 67.554615 -312.074529) (xy 67.554436 -312.07563) (xy 67.873114 -312.07563) (xy 67.873114 -312.024214)
			(xy 67.881157 -311.973432) (xy 67.897045 -311.924533) (xy 67.920388 -311.878721) (xy 67.950609 -311.837125)
			(xy 67.986965 -311.800769) (xy 68.028561 -311.770548) (xy 68.074373 -311.747205) (xy 68.123272 -311.731317)
			(xy 68.174054 -311.723274) (xy 68.22547 -311.723274) (xy 68.276252 -311.731317) (xy 68.325151 -311.747205)
			(xy 68.370963 -311.770548) (xy 68.412559 -311.800769) (xy 68.448915 -311.837125) (xy 68.479136 -311.878721)
			(xy 68.502479 -311.924533) (xy 68.518367 -311.973432) (xy 68.52641 -312.024214) (xy 68.526914 -312.049922)
			(xy 68.844172 -312.049922) (xy 68.848132 -312.000868) (xy 68.859909 -311.953084) (xy 68.8792 -311.907808)
			(xy 68.905503 -311.866212) (xy 68.938138 -311.829375) (xy 68.976259 -311.79825) (xy 69.01888 -311.773643)
			(xy 69.064896 -311.756191) (xy 69.113115 -311.746347) (xy 69.16229 -311.744366) (xy 69.211145 -311.750298)
			(xy 69.258416 -311.76399) (xy 69.302878 -311.785088) (xy 69.343381 -311.813044) (xy 69.378874 -311.847136)
			(xy 69.408439 -311.88648) (xy 69.43131 -311.930057) (xy 69.446894 -311.976738) (xy 69.454789 -312.025315)
			(xy 69.455284 -312.049922) (xy 69.454789 -312.074529) (xy 69.45461 -312.07563) (xy 69.773288 -312.07563)
			(xy 69.773288 -312.024214) (xy 69.781331 -311.973432) (xy 69.797219 -311.924533) (xy 69.820562 -311.878721)
			(xy 69.850783 -311.837125) (xy 69.887139 -311.800769) (xy 69.928735 -311.770548) (xy 69.974547 -311.747205)
			(xy 70.023446 -311.731317) (xy 70.074228 -311.723274) (xy 70.125644 -311.723274) (xy 70.176426 -311.731317)
			(xy 70.225325 -311.747205) (xy 70.271137 -311.770548) (xy 70.312733 -311.800769) (xy 70.349089 -311.837125)
			(xy 70.37931 -311.878721) (xy 70.402653 -311.924533) (xy 70.418541 -311.973432) (xy 70.426584 -312.024214)
			(xy 70.427088 -312.049922) (xy 70.744092 -312.049922) (xy 70.748052 -312.000868) (xy 70.759829 -311.953084)
			(xy 70.77912 -311.907808) (xy 70.805423 -311.866212) (xy 70.838058 -311.829375) (xy 70.876179 -311.79825)
			(xy 70.9188 -311.773643) (xy 70.964816 -311.756191) (xy 71.013035 -311.746347) (xy 71.06221 -311.744366)
			(xy 71.111065 -311.750298) (xy 71.158336 -311.76399) (xy 71.202798 -311.785088) (xy 71.243301 -311.813044)
			(xy 71.278794 -311.847136) (xy 71.308359 -311.88648) (xy 71.33123 -311.930057) (xy 71.346814 -311.976738)
			(xy 71.354709 -312.025315) (xy 71.355204 -312.049922) (xy 71.354709 -312.074529) (xy 71.35453 -312.07563)
			(xy 71.673208 -312.07563) (xy 71.673208 -312.024214) (xy 71.681251 -311.973432) (xy 71.697139 -311.924533)
			(xy 71.720482 -311.878721) (xy 71.750703 -311.837125) (xy 71.787059 -311.800769) (xy 71.828655 -311.770548)
			(xy 71.874467 -311.747205) (xy 71.923366 -311.731317) (xy 71.974148 -311.723274) (xy 72.025564 -311.723274)
			(xy 72.076346 -311.731317) (xy 72.125245 -311.747205) (xy 72.171057 -311.770548) (xy 72.212653 -311.800769)
			(xy 72.249009 -311.837125) (xy 72.27923 -311.878721) (xy 72.302573 -311.924533) (xy 72.318461 -311.973432)
			(xy 72.326504 -312.024214) (xy 72.327008 -312.049922) (xy 72.644012 -312.049922) (xy 72.647972 -312.000868)
			(xy 72.659749 -311.953084) (xy 72.67904 -311.907808) (xy 72.705343 -311.866212) (xy 72.737978 -311.829375)
			(xy 72.776099 -311.79825) (xy 72.81872 -311.773643) (xy 72.864736 -311.756191) (xy 72.912955 -311.746347)
			(xy 72.96213 -311.744366) (xy 73.010985 -311.750298) (xy 73.058256 -311.76399) (xy 73.102718 -311.785088)
			(xy 73.143221 -311.813044) (xy 73.178714 -311.847136) (xy 73.208279 -311.88648) (xy 73.23115 -311.930057)
			(xy 73.246734 -311.976738) (xy 73.254629 -312.025315) (xy 73.255124 -312.049922) (xy 73.593972 -312.049922)
			(xy 73.597932 -312.000868) (xy 73.609709 -311.953084) (xy 73.629 -311.907808) (xy 73.655303 -311.866212)
			(xy 73.687938 -311.829375) (xy 73.726059 -311.79825) (xy 73.76868 -311.773643) (xy 73.814696 -311.756191)
			(xy 73.862915 -311.746347) (xy 73.91209 -311.744366) (xy 73.960945 -311.750298) (xy 74.008216 -311.76399)
			(xy 74.052678 -311.785088) (xy 74.093181 -311.813044) (xy 74.128674 -311.847136) (xy 74.158239 -311.88648)
			(xy 74.18111 -311.930057) (xy 74.196694 -311.976738) (xy 74.204589 -312.025315) (xy 74.205084 -312.049922)
			(xy 74.544186 -312.049922) (xy 74.548146 -312.000868) (xy 74.559923 -311.953084) (xy 74.579214 -311.907808)
			(xy 74.605517 -311.866212) (xy 74.638152 -311.829375) (xy 74.676273 -311.79825) (xy 74.718894 -311.773643)
			(xy 74.76491 -311.756191) (xy 74.813129 -311.746347) (xy 74.862304 -311.744366) (xy 74.911159 -311.750298)
			(xy 74.95843 -311.76399) (xy 75.002892 -311.785088) (xy 75.043395 -311.813044) (xy 75.078888 -311.847136)
			(xy 75.108453 -311.88648) (xy 75.131324 -311.930057) (xy 75.146908 -311.976738) (xy 75.154803 -312.025315)
			(xy 75.155298 -312.049922) (xy 75.494146 -312.049922) (xy 75.498106 -312.000868) (xy 75.509883 -311.953084)
			(xy 75.529174 -311.907808) (xy 75.555477 -311.866212) (xy 75.588112 -311.829375) (xy 75.626233 -311.79825)
			(xy 75.668854 -311.773643) (xy 75.71487 -311.756191) (xy 75.763089 -311.746347) (xy 75.812264 -311.744366)
			(xy 75.861119 -311.750298) (xy 75.90839 -311.76399) (xy 75.952852 -311.785088) (xy 75.993355 -311.813044)
			(xy 76.028848 -311.847136) (xy 76.058413 -311.88648) (xy 76.081284 -311.930057) (xy 76.096868 -311.976738)
			(xy 76.104763 -312.025315) (xy 76.105258 -312.049922) (xy 76.444106 -312.049922) (xy 76.448066 -312.000868)
			(xy 76.459843 -311.953084) (xy 76.479134 -311.907808) (xy 76.505437 -311.866212) (xy 76.538072 -311.829375)
			(xy 76.576193 -311.79825) (xy 76.618814 -311.773643) (xy 76.66483 -311.756191) (xy 76.713049 -311.746347)
			(xy 76.762224 -311.744366) (xy 76.811079 -311.750298) (xy 76.85835 -311.76399) (xy 76.902812 -311.785088)
			(xy 76.943315 -311.813044) (xy 76.978808 -311.847136) (xy 77.008373 -311.88648) (xy 77.031244 -311.930057)
			(xy 77.046828 -311.976738) (xy 77.054723 -312.025315) (xy 77.055218 -312.049922) (xy 77.394066 -312.049922)
			(xy 77.398026 -312.000868) (xy 77.409803 -311.953084) (xy 77.429094 -311.907808) (xy 77.455397 -311.866212)
			(xy 77.488032 -311.829375) (xy 77.526153 -311.79825) (xy 77.568774 -311.773643) (xy 77.61479 -311.756191)
			(xy 77.663009 -311.746347) (xy 77.712184 -311.744366) (xy 77.761039 -311.750298) (xy 77.80831 -311.76399)
			(xy 77.852772 -311.785088) (xy 77.893275 -311.813044) (xy 77.928768 -311.847136) (xy 77.958333 -311.88648)
			(xy 77.981204 -311.930057) (xy 77.996788 -311.976738) (xy 78.004683 -312.025315) (xy 78.005178 -312.049922)
			(xy 78.344026 -312.049922) (xy 78.347986 -312.000868) (xy 78.359763 -311.953084) (xy 78.379054 -311.907808)
			(xy 78.405357 -311.866212) (xy 78.437992 -311.829375) (xy 78.476113 -311.79825) (xy 78.518734 -311.773643)
			(xy 78.56475 -311.756191) (xy 78.612969 -311.746347) (xy 78.662144 -311.744366) (xy 78.710999 -311.750298)
			(xy 78.75827 -311.76399) (xy 78.802732 -311.785088) (xy 78.843235 -311.813044) (xy 78.878728 -311.847136)
			(xy 78.908293 -311.88648) (xy 78.931164 -311.930057) (xy 78.946748 -311.976738) (xy 78.954643 -312.025315)
			(xy 78.955138 -312.049922) (xy 79.293986 -312.049922) (xy 79.297946 -312.000868) (xy 79.309723 -311.953084)
			(xy 79.329014 -311.907808) (xy 79.355317 -311.866212) (xy 79.387952 -311.829375) (xy 79.426073 -311.79825)
			(xy 79.468694 -311.773643) (xy 79.51471 -311.756191) (xy 79.562929 -311.746347) (xy 79.612104 -311.744366)
			(xy 79.660959 -311.750298) (xy 79.70823 -311.76399) (xy 79.752692 -311.785088) (xy 79.793195 -311.813044)
			(xy 79.828688 -311.847136) (xy 79.858253 -311.88648) (xy 79.881124 -311.930057) (xy 79.896708 -311.976738)
			(xy 79.904603 -312.025315) (xy 79.905098 -312.049922) (xy 80.243946 -312.049922) (xy 80.247906 -312.000868)
			(xy 80.259683 -311.953084) (xy 80.278974 -311.907808) (xy 80.305277 -311.866212) (xy 80.337912 -311.829375)
			(xy 80.376033 -311.79825) (xy 80.418654 -311.773643) (xy 80.46467 -311.756191) (xy 80.512889 -311.746347)
			(xy 80.562064 -311.744366) (xy 80.610919 -311.750298) (xy 80.65819 -311.76399) (xy 80.702652 -311.785088)
			(xy 80.743155 -311.813044) (xy 80.778648 -311.847136) (xy 80.808213 -311.88648) (xy 80.831084 -311.930057)
			(xy 80.846668 -311.976738) (xy 80.854563 -312.025315) (xy 80.855058 -312.049922) (xy 81.19416 -312.049922)
			(xy 81.19812 -312.000868) (xy 81.209897 -311.953084) (xy 81.229188 -311.907808) (xy 81.255491 -311.866212)
			(xy 81.288126 -311.829375) (xy 81.326247 -311.79825) (xy 81.368868 -311.773643) (xy 81.414884 -311.756191)
			(xy 81.463103 -311.746347) (xy 81.512278 -311.744366) (xy 81.561133 -311.750298) (xy 81.608404 -311.76399)
			(xy 81.652866 -311.785088) (xy 81.693369 -311.813044) (xy 81.728862 -311.847136) (xy 81.758427 -311.88648)
			(xy 81.781298 -311.930057) (xy 81.796882 -311.976738) (xy 81.804777 -312.025315) (xy 81.805272 -312.049922)
			(xy 82.14412 -312.049922) (xy 82.14808 -312.000868) (xy 82.159857 -311.953084) (xy 82.179148 -311.907808)
			(xy 82.205451 -311.866212) (xy 82.238086 -311.829375) (xy 82.276207 -311.79825) (xy 82.318828 -311.773643)
			(xy 82.364844 -311.756191) (xy 82.413063 -311.746347) (xy 82.462238 -311.744366) (xy 82.511093 -311.750298)
			(xy 82.558364 -311.76399) (xy 82.602826 -311.785088) (xy 82.643329 -311.813044) (xy 82.678822 -311.847136)
			(xy 82.708387 -311.88648) (xy 82.731258 -311.930057) (xy 82.746842 -311.976738) (xy 82.754737 -312.025315)
			(xy 82.755232 -312.049922) (xy 83.094334 -312.049922) (xy 83.098294 -312.000868) (xy 83.110071 -311.953084)
			(xy 83.129362 -311.907808) (xy 83.155665 -311.866212) (xy 83.1883 -311.829375) (xy 83.226421 -311.79825)
			(xy 83.269042 -311.773643) (xy 83.315058 -311.756191) (xy 83.363277 -311.746347) (xy 83.412452 -311.744366)
			(xy 83.461307 -311.750298) (xy 83.508578 -311.76399) (xy 83.55304 -311.785088) (xy 83.593543 -311.813044)
			(xy 83.629036 -311.847136) (xy 83.658601 -311.88648) (xy 83.681472 -311.930057) (xy 83.697056 -311.976738)
			(xy 83.704951 -312.025315) (xy 83.705446 -312.049922) (xy 83.704951 -312.074529) (xy 83.697056 -312.123106)
			(xy 83.681472 -312.169787) (xy 83.658601 -312.213364) (xy 83.629036 -312.252708) (xy 83.593543 -312.2868)
			(xy 83.55304 -312.314756) (xy 83.508578 -312.335854) (xy 83.461307 -312.349546) (xy 83.412452 -312.355478)
			(xy 83.363277 -312.353497) (xy 83.315058 -312.343653) (xy 83.269042 -312.326201) (xy 83.226421 -312.301594)
			(xy 83.1883 -312.270469) (xy 83.155665 -312.233632) (xy 83.129362 -312.192036) (xy 83.110071 -312.14676)
			(xy 83.098294 -312.098976) (xy 83.094334 -312.049922) (xy 82.755232 -312.049922) (xy 82.754737 -312.074529)
			(xy 82.746842 -312.123106) (xy 82.731258 -312.169787) (xy 82.708387 -312.213364) (xy 82.678822 -312.252708)
			(xy 82.643329 -312.2868) (xy 82.602826 -312.314756) (xy 82.558364 -312.335854) (xy 82.511093 -312.349546)
			(xy 82.462238 -312.355478) (xy 82.413063 -312.353497) (xy 82.364844 -312.343653) (xy 82.318828 -312.326201)
			(xy 82.276207 -312.301594) (xy 82.238086 -312.270469) (xy 82.205451 -312.233632) (xy 82.179148 -312.192036)
			(xy 82.159857 -312.14676) (xy 82.14808 -312.098976) (xy 82.14412 -312.049922) (xy 81.805272 -312.049922)
			(xy 81.804777 -312.074529) (xy 81.796882 -312.123106) (xy 81.781298 -312.169787) (xy 81.758427 -312.213364)
			(xy 81.728862 -312.252708) (xy 81.693369 -312.2868) (xy 81.652866 -312.314756) (xy 81.608404 -312.335854)
			(xy 81.561133 -312.349546) (xy 81.512278 -312.355478) (xy 81.463103 -312.353497) (xy 81.414884 -312.343653)
			(xy 81.368868 -312.326201) (xy 81.326247 -312.301594) (xy 81.288126 -312.270469) (xy 81.255491 -312.233632)
			(xy 81.229188 -312.192036) (xy 81.209897 -312.14676) (xy 81.19812 -312.098976) (xy 81.19416 -312.049922)
			(xy 80.855058 -312.049922) (xy 80.854563 -312.074529) (xy 80.846668 -312.123106) (xy 80.831084 -312.169787)
			(xy 80.808213 -312.213364) (xy 80.778648 -312.252708) (xy 80.743155 -312.2868) (xy 80.702652 -312.314756)
			(xy 80.65819 -312.335854) (xy 80.610919 -312.349546) (xy 80.562064 -312.355478) (xy 80.512889 -312.353497)
			(xy 80.46467 -312.343653) (xy 80.418654 -312.326201) (xy 80.376033 -312.301594) (xy 80.337912 -312.270469)
			(xy 80.305277 -312.233632) (xy 80.278974 -312.192036) (xy 80.259683 -312.14676) (xy 80.247906 -312.098976)
			(xy 80.243946 -312.049922) (xy 79.905098 -312.049922) (xy 79.904603 -312.074529) (xy 79.896708 -312.123106)
			(xy 79.881124 -312.169787) (xy 79.858253 -312.213364) (xy 79.828688 -312.252708) (xy 79.793195 -312.2868)
			(xy 79.752692 -312.314756) (xy 79.70823 -312.335854) (xy 79.660959 -312.349546) (xy 79.612104 -312.355478)
			(xy 79.562929 -312.353497) (xy 79.51471 -312.343653) (xy 79.468694 -312.326201) (xy 79.426073 -312.301594)
			(xy 79.387952 -312.270469) (xy 79.355317 -312.233632) (xy 79.329014 -312.192036) (xy 79.309723 -312.14676)
			(xy 79.297946 -312.098976) (xy 79.293986 -312.049922) (xy 78.955138 -312.049922) (xy 78.954643 -312.074529)
			(xy 78.946748 -312.123106) (xy 78.931164 -312.169787) (xy 78.908293 -312.213364) (xy 78.878728 -312.252708)
			(xy 78.843235 -312.2868) (xy 78.802732 -312.314756) (xy 78.75827 -312.335854) (xy 78.710999 -312.349546)
			(xy 78.662144 -312.355478) (xy 78.612969 -312.353497) (xy 78.56475 -312.343653) (xy 78.518734 -312.326201)
			(xy 78.476113 -312.301594) (xy 78.437992 -312.270469) (xy 78.405357 -312.233632) (xy 78.379054 -312.192036)
			(xy 78.359763 -312.14676) (xy 78.347986 -312.098976) (xy 78.344026 -312.049922) (xy 78.005178 -312.049922)
			(xy 78.004683 -312.074529) (xy 77.996788 -312.123106) (xy 77.981204 -312.169787) (xy 77.958333 -312.213364)
			(xy 77.928768 -312.252708) (xy 77.893275 -312.2868) (xy 77.852772 -312.314756) (xy 77.80831 -312.335854)
			(xy 77.761039 -312.349546) (xy 77.712184 -312.355478) (xy 77.663009 -312.353497) (xy 77.61479 -312.343653)
			(xy 77.568774 -312.326201) (xy 77.526153 -312.301594) (xy 77.488032 -312.270469) (xy 77.455397 -312.233632)
			(xy 77.429094 -312.192036) (xy 77.409803 -312.14676) (xy 77.398026 -312.098976) (xy 77.394066 -312.049922)
			(xy 77.055218 -312.049922) (xy 77.054723 -312.074529) (xy 77.046828 -312.123106) (xy 77.031244 -312.169787)
			(xy 77.008373 -312.213364) (xy 76.978808 -312.252708) (xy 76.943315 -312.2868) (xy 76.902812 -312.314756)
			(xy 76.85835 -312.335854) (xy 76.811079 -312.349546) (xy 76.762224 -312.355478) (xy 76.713049 -312.353497)
			(xy 76.66483 -312.343653) (xy 76.618814 -312.326201) (xy 76.576193 -312.301594) (xy 76.538072 -312.270469)
			(xy 76.505437 -312.233632) (xy 76.479134 -312.192036) (xy 76.459843 -312.14676) (xy 76.448066 -312.098976)
			(xy 76.444106 -312.049922) (xy 76.105258 -312.049922) (xy 76.104763 -312.074529) (xy 76.096868 -312.123106)
			(xy 76.081284 -312.169787) (xy 76.058413 -312.213364) (xy 76.028848 -312.252708) (xy 75.993355 -312.2868)
			(xy 75.952852 -312.314756) (xy 75.90839 -312.335854) (xy 75.861119 -312.349546) (xy 75.812264 -312.355478)
			(xy 75.763089 -312.353497) (xy 75.71487 -312.343653) (xy 75.668854 -312.326201) (xy 75.626233 -312.301594)
			(xy 75.588112 -312.270469) (xy 75.555477 -312.233632) (xy 75.529174 -312.192036) (xy 75.509883 -312.14676)
			(xy 75.498106 -312.098976) (xy 75.494146 -312.049922) (xy 75.155298 -312.049922) (xy 75.154803 -312.074529)
			(xy 75.146908 -312.123106) (xy 75.131324 -312.169787) (xy 75.108453 -312.213364) (xy 75.078888 -312.252708)
			(xy 75.043395 -312.2868) (xy 75.002892 -312.314756) (xy 74.95843 -312.335854) (xy 74.911159 -312.349546)
			(xy 74.862304 -312.355478) (xy 74.813129 -312.353497) (xy 74.76491 -312.343653) (xy 74.718894 -312.326201)
			(xy 74.676273 -312.301594) (xy 74.638152 -312.270469) (xy 74.605517 -312.233632) (xy 74.579214 -312.192036)
			(xy 74.559923 -312.14676) (xy 74.548146 -312.098976) (xy 74.544186 -312.049922) (xy 74.205084 -312.049922)
			(xy 74.204589 -312.074529) (xy 74.196694 -312.123106) (xy 74.18111 -312.169787) (xy 74.158239 -312.213364)
			(xy 74.128674 -312.252708) (xy 74.093181 -312.2868) (xy 74.052678 -312.314756) (xy 74.008216 -312.335854)
			(xy 73.960945 -312.349546) (xy 73.91209 -312.355478) (xy 73.862915 -312.353497) (xy 73.814696 -312.343653)
			(xy 73.76868 -312.326201) (xy 73.726059 -312.301594) (xy 73.687938 -312.270469) (xy 73.655303 -312.233632)
			(xy 73.629 -312.192036) (xy 73.609709 -312.14676) (xy 73.597932 -312.098976) (xy 73.593972 -312.049922)
			(xy 73.255124 -312.049922) (xy 73.254629 -312.074529) (xy 73.246734 -312.123106) (xy 73.23115 -312.169787)
			(xy 73.208279 -312.213364) (xy 73.178714 -312.252708) (xy 73.143221 -312.2868) (xy 73.102718 -312.314756)
			(xy 73.058256 -312.335854) (xy 73.010985 -312.349546) (xy 72.96213 -312.355478) (xy 72.912955 -312.353497)
			(xy 72.864736 -312.343653) (xy 72.81872 -312.326201) (xy 72.776099 -312.301594) (xy 72.737978 -312.270469)
			(xy 72.705343 -312.233632) (xy 72.67904 -312.192036) (xy 72.659749 -312.14676) (xy 72.647972 -312.098976)
			(xy 72.644012 -312.049922) (xy 72.327008 -312.049922) (xy 72.326504 -312.07563) (xy 72.318461 -312.126412)
			(xy 72.302573 -312.175311) (xy 72.27923 -312.221123) (xy 72.249009 -312.262719) (xy 72.212653 -312.299075)
			(xy 72.171057 -312.329296) (xy 72.125245 -312.352639) (xy 72.076346 -312.368527) (xy 72.025564 -312.37657)
			(xy 71.974148 -312.37657) (xy 71.923366 -312.368527) (xy 71.874467 -312.352639) (xy 71.828655 -312.329296)
			(xy 71.787059 -312.299075) (xy 71.750703 -312.262719) (xy 71.720482 -312.221123) (xy 71.697139 -312.175311)
			(xy 71.681251 -312.126412) (xy 71.673208 -312.07563) (xy 71.35453 -312.07563) (xy 71.346814 -312.123106)
			(xy 71.33123 -312.169787) (xy 71.308359 -312.213364) (xy 71.278794 -312.252708) (xy 71.243301 -312.2868)
			(xy 71.202798 -312.314756) (xy 71.158336 -312.335854) (xy 71.111065 -312.349546) (xy 71.06221 -312.355478)
			(xy 71.013035 -312.353497) (xy 70.964816 -312.343653) (xy 70.9188 -312.326201) (xy 70.876179 -312.301594)
			(xy 70.838058 -312.270469) (xy 70.805423 -312.233632) (xy 70.77912 -312.192036) (xy 70.759829 -312.14676)
			(xy 70.748052 -312.098976) (xy 70.744092 -312.049922) (xy 70.427088 -312.049922) (xy 70.426584 -312.07563)
			(xy 70.418541 -312.126412) (xy 70.402653 -312.175311) (xy 70.37931 -312.221123) (xy 70.349089 -312.262719)
			(xy 70.312733 -312.299075) (xy 70.271137 -312.329296) (xy 70.225325 -312.352639) (xy 70.176426 -312.368527)
			(xy 70.125644 -312.37657) (xy 70.074228 -312.37657) (xy 70.023446 -312.368527) (xy 69.974547 -312.352639)
			(xy 69.928735 -312.329296) (xy 69.887139 -312.299075) (xy 69.850783 -312.262719) (xy 69.820562 -312.221123)
			(xy 69.797219 -312.175311) (xy 69.781331 -312.126412) (xy 69.773288 -312.07563) (xy 69.45461 -312.07563)
			(xy 69.446894 -312.123106) (xy 69.43131 -312.169787) (xy 69.408439 -312.213364) (xy 69.378874 -312.252708)
			(xy 69.343381 -312.2868) (xy 69.302878 -312.314756) (xy 69.258416 -312.335854) (xy 69.211145 -312.349546)
			(xy 69.16229 -312.355478) (xy 69.113115 -312.353497) (xy 69.064896 -312.343653) (xy 69.01888 -312.326201)
			(xy 68.976259 -312.301594) (xy 68.938138 -312.270469) (xy 68.905503 -312.233632) (xy 68.8792 -312.192036)
			(xy 68.859909 -312.14676) (xy 68.848132 -312.098976) (xy 68.844172 -312.049922) (xy 68.526914 -312.049922)
			(xy 68.52641 -312.07563) (xy 68.518367 -312.126412) (xy 68.502479 -312.175311) (xy 68.479136 -312.221123)
			(xy 68.448915 -312.262719) (xy 68.412559 -312.299075) (xy 68.370963 -312.329296) (xy 68.325151 -312.352639)
			(xy 68.276252 -312.368527) (xy 68.22547 -312.37657) (xy 68.174054 -312.37657) (xy 68.123272 -312.368527)
			(xy 68.074373 -312.352639) (xy 68.028561 -312.329296) (xy 67.986965 -312.299075) (xy 67.950609 -312.262719)
			(xy 67.920388 -312.221123) (xy 67.897045 -312.175311) (xy 67.881157 -312.126412) (xy 67.873114 -312.07563)
			(xy 67.554436 -312.07563) (xy 67.54672 -312.123106) (xy 67.531136 -312.169787) (xy 67.508265 -312.213364)
			(xy 67.4787 -312.252708) (xy 67.443207 -312.2868) (xy 67.402704 -312.314756) (xy 67.358242 -312.335854)
			(xy 67.310971 -312.349546) (xy 67.262116 -312.355478) (xy 67.212941 -312.353497) (xy 67.164722 -312.343653)
			(xy 67.118706 -312.326201) (xy 67.076085 -312.301594) (xy 67.037964 -312.270469) (xy 67.005329 -312.233632)
			(xy 66.979026 -312.192036) (xy 66.959735 -312.14676) (xy 66.947958 -312.098976) (xy 66.943998 -312.049922)
			(xy 66.626994 -312.049922) (xy 66.62649 -312.07563) (xy 66.618447 -312.126412) (xy 66.602559 -312.175311)
			(xy 66.579216 -312.221123) (xy 66.548995 -312.262719) (xy 66.512639 -312.299075) (xy 66.471043 -312.329296)
			(xy 66.425231 -312.352639) (xy 66.376332 -312.368527) (xy 66.32555 -312.37657) (xy 66.274134 -312.37657)
			(xy 66.223352 -312.368527) (xy 66.174453 -312.352639) (xy 66.128641 -312.329296) (xy 66.087045 -312.299075)
			(xy 66.050689 -312.262719) (xy 66.020468 -312.221123) (xy 65.997125 -312.175311) (xy 65.981237 -312.126412)
			(xy 65.973194 -312.07563) (xy 65.654516 -312.07563) (xy 65.6468 -312.123106) (xy 65.631216 -312.169787)
			(xy 65.608345 -312.213364) (xy 65.57878 -312.252708) (xy 65.543287 -312.2868) (xy 65.502784 -312.314756)
			(xy 65.458322 -312.335854) (xy 65.411051 -312.349546) (xy 65.362196 -312.355478) (xy 65.313021 -312.353497)
			(xy 65.264802 -312.343653) (xy 65.218786 -312.326201) (xy 65.176165 -312.301594) (xy 65.138044 -312.270469)
			(xy 65.105409 -312.233632) (xy 65.079106 -312.192036) (xy 65.059815 -312.14676) (xy 65.048038 -312.098976)
			(xy 65.044078 -312.049922) (xy 64.727074 -312.049922) (xy 64.72657 -312.07563) (xy 64.718527 -312.126412)
			(xy 64.702639 -312.175311) (xy 64.679296 -312.221123) (xy 64.649075 -312.262719) (xy 64.612719 -312.299075)
			(xy 64.571123 -312.329296) (xy 64.525311 -312.352639) (xy 64.476412 -312.368527) (xy 64.42563 -312.37657)
			(xy 64.374214 -312.37657) (xy 64.323432 -312.368527) (xy 64.274533 -312.352639) (xy 64.228721 -312.329296)
			(xy 64.187125 -312.299075) (xy 64.150769 -312.262719) (xy 64.120548 -312.221123) (xy 64.097205 -312.175311)
			(xy 64.081317 -312.126412) (xy 64.073274 -312.07563) (xy 63.754596 -312.07563) (xy 63.74688 -312.123106)
			(xy 63.731296 -312.169787) (xy 63.708425 -312.213364) (xy 63.67886 -312.252708) (xy 63.643367 -312.2868)
			(xy 63.602864 -312.314756) (xy 63.558402 -312.335854) (xy 63.511131 -312.349546) (xy 63.462276 -312.355478)
			(xy 63.413101 -312.353497) (xy 63.364882 -312.343653) (xy 63.318866 -312.326201) (xy 63.276245 -312.301594)
			(xy 63.238124 -312.270469) (xy 63.205489 -312.233632) (xy 63.179186 -312.192036) (xy 63.159895 -312.14676)
			(xy 63.148118 -312.098976) (xy 63.144158 -312.049922) (xy 62.8269 -312.049922) (xy 62.826396 -312.07563)
			(xy 62.818353 -312.126412) (xy 62.802465 -312.175311) (xy 62.779122 -312.221123) (xy 62.748901 -312.262719)
			(xy 62.712545 -312.299075) (xy 62.670949 -312.329296) (xy 62.625137 -312.352639) (xy 62.576238 -312.368527)
			(xy 62.525456 -312.37657) (xy 62.47404 -312.37657) (xy 62.423258 -312.368527) (xy 62.374359 -312.352639)
			(xy 62.328547 -312.329296) (xy 62.286951 -312.299075) (xy 62.250595 -312.262719) (xy 62.220374 -312.221123)
			(xy 62.197031 -312.175311) (xy 62.181143 -312.126412) (xy 62.1731 -312.07563) (xy 61.854422 -312.07563)
			(xy 61.846706 -312.123106) (xy 61.831122 -312.169787) (xy 61.808251 -312.213364) (xy 61.778686 -312.252708)
			(xy 61.743193 -312.2868) (xy 61.70269 -312.314756) (xy 61.658228 -312.335854) (xy 61.610957 -312.349546)
			(xy 61.562102 -312.355478) (xy 61.512927 -312.353497) (xy 61.464708 -312.343653) (xy 61.418692 -312.326201)
			(xy 61.376071 -312.301594) (xy 61.33795 -312.270469) (xy 61.305315 -312.233632) (xy 61.279012 -312.192036)
			(xy 61.259721 -312.14676) (xy 61.247944 -312.098976) (xy 61.243984 -312.049922) (xy 60.92698 -312.049922)
			(xy 60.926476 -312.07563) (xy 60.918433 -312.126412) (xy 60.902545 -312.175311) (xy 60.879202 -312.221123)
			(xy 60.848981 -312.262719) (xy 60.812625 -312.299075) (xy 60.771029 -312.329296) (xy 60.725217 -312.352639)
			(xy 60.676318 -312.368527) (xy 60.625536 -312.37657) (xy 60.57412 -312.37657) (xy 60.523338 -312.368527)
			(xy 60.474439 -312.352639) (xy 60.428627 -312.329296) (xy 60.387031 -312.299075) (xy 60.350675 -312.262719)
			(xy 60.320454 -312.221123) (xy 60.297111 -312.175311) (xy 60.281223 -312.126412) (xy 60.27318 -312.07563)
			(xy 59.954502 -312.07563) (xy 59.946786 -312.123106) (xy 59.931202 -312.169787) (xy 59.908331 -312.213364)
			(xy 59.878766 -312.252708) (xy 59.843273 -312.2868) (xy 59.80277 -312.314756) (xy 59.758308 -312.335854)
			(xy 59.711037 -312.349546) (xy 59.662182 -312.355478) (xy 59.613007 -312.353497) (xy 59.564788 -312.343653)
			(xy 59.518772 -312.326201) (xy 59.476151 -312.301594) (xy 59.43803 -312.270469) (xy 59.405395 -312.233632)
			(xy 59.379092 -312.192036) (xy 59.359801 -312.14676) (xy 59.348024 -312.098976) (xy 59.344064 -312.049922)
			(xy 59.02706 -312.049922) (xy 59.026556 -312.07563) (xy 59.018513 -312.126412) (xy 59.002625 -312.175311)
			(xy 58.979282 -312.221123) (xy 58.949061 -312.262719) (xy 58.912705 -312.299075) (xy 58.871109 -312.329296)
			(xy 58.825297 -312.352639) (xy 58.776398 -312.368527) (xy 58.725616 -312.37657) (xy 58.6742 -312.37657)
			(xy 58.623418 -312.368527) (xy 58.574519 -312.352639) (xy 58.528707 -312.329296) (xy 58.487111 -312.299075)
			(xy 58.450755 -312.262719) (xy 58.420534 -312.221123) (xy 58.397191 -312.175311) (xy 58.381303 -312.126412)
			(xy 58.37326 -312.07563) (xy 58.054582 -312.07563) (xy 58.046866 -312.123106) (xy 58.031282 -312.169787)
			(xy 58.008411 -312.213364) (xy 57.978846 -312.252708) (xy 57.943353 -312.2868) (xy 57.90285 -312.314756)
			(xy 57.858388 -312.335854) (xy 57.811117 -312.349546) (xy 57.762262 -312.355478) (xy 57.713087 -312.353497)
			(xy 57.664868 -312.343653) (xy 57.618852 -312.326201) (xy 57.576231 -312.301594) (xy 57.53811 -312.270469)
			(xy 57.505475 -312.233632) (xy 57.479172 -312.192036) (xy 57.459881 -312.14676) (xy 57.448104 -312.098976)
			(xy 57.444144 -312.049922) (xy 57.105296 -312.049922) (xy 57.104801 -312.074529) (xy 57.096906 -312.123106)
			(xy 57.081322 -312.169787) (xy 57.058451 -312.213364) (xy 57.028886 -312.252708) (xy 56.993393 -312.2868)
			(xy 56.95289 -312.314756) (xy 56.908428 -312.335854) (xy 56.861157 -312.349546) (xy 56.812302 -312.355478)
			(xy 56.763127 -312.353497) (xy 56.714908 -312.343653) (xy 56.668892 -312.326201) (xy 56.626271 -312.301594)
			(xy 56.58815 -312.270469) (xy 56.555515 -312.233632) (xy 56.529212 -312.192036) (xy 56.509921 -312.14676)
			(xy 56.498144 -312.098976) (xy 56.494184 -312.049922) (xy 56.155082 -312.049922) (xy 56.154587 -312.074529)
			(xy 56.146692 -312.123106) (xy 56.131108 -312.169787) (xy 56.108237 -312.213364) (xy 56.078672 -312.252708)
			(xy 56.043179 -312.2868) (xy 56.002676 -312.314756) (xy 55.958214 -312.335854) (xy 55.910943 -312.349546)
			(xy 55.862088 -312.355478) (xy 55.812913 -312.353497) (xy 55.764694 -312.343653) (xy 55.718678 -312.326201)
			(xy 55.676057 -312.301594) (xy 55.637936 -312.270469) (xy 55.605301 -312.233632) (xy 55.578998 -312.192036)
			(xy 55.559707 -312.14676) (xy 55.54793 -312.098976) (xy 55.54397 -312.049922) (xy 55.205122 -312.049922)
			(xy 55.204627 -312.074529) (xy 55.196732 -312.123106) (xy 55.181148 -312.169787) (xy 55.158277 -312.213364)
			(xy 55.128712 -312.252708) (xy 55.093219 -312.2868) (xy 55.052716 -312.314756) (xy 55.008254 -312.335854)
			(xy 54.960983 -312.349546) (xy 54.912128 -312.355478) (xy 54.862953 -312.353497) (xy 54.814734 -312.343653)
			(xy 54.768718 -312.326201) (xy 54.726097 -312.301594) (xy 54.687976 -312.270469) (xy 54.655341 -312.233632)
			(xy 54.629038 -312.192036) (xy 54.609747 -312.14676) (xy 54.59797 -312.098976) (xy 54.59401 -312.049922)
			(xy 54.255162 -312.049922) (xy 54.254667 -312.074529) (xy 54.246772 -312.123106) (xy 54.231188 -312.169787)
			(xy 54.208317 -312.213364) (xy 54.178752 -312.252708) (xy 54.143259 -312.2868) (xy 54.102756 -312.314756)
			(xy 54.058294 -312.335854) (xy 54.011023 -312.349546) (xy 53.962168 -312.355478) (xy 53.912993 -312.353497)
			(xy 53.864774 -312.343653) (xy 53.818758 -312.326201) (xy 53.776137 -312.301594) (xy 53.738016 -312.270469)
			(xy 53.705381 -312.233632) (xy 53.679078 -312.192036) (xy 53.659787 -312.14676) (xy 53.64801 -312.098976)
			(xy 53.64405 -312.049922) (xy 53.305202 -312.049922) (xy 53.304707 -312.074529) (xy 53.296812 -312.123106)
			(xy 53.281228 -312.169787) (xy 53.258357 -312.213364) (xy 53.228792 -312.252708) (xy 53.193299 -312.2868)
			(xy 53.152796 -312.314756) (xy 53.108334 -312.335854) (xy 53.061063 -312.349546) (xy 53.012208 -312.355478)
			(xy 52.963033 -312.353497) (xy 52.914814 -312.343653) (xy 52.868798 -312.326201) (xy 52.826177 -312.301594)
			(xy 52.788056 -312.270469) (xy 52.755421 -312.233632) (xy 52.729118 -312.192036) (xy 52.709827 -312.14676)
			(xy 52.69805 -312.098976) (xy 52.69409 -312.049922) (xy 52.355242 -312.049922) (xy 52.354747 -312.074529)
			(xy 52.346852 -312.123106) (xy 52.331268 -312.169787) (xy 52.308397 -312.213364) (xy 52.278832 -312.252708)
			(xy 52.243339 -312.2868) (xy 52.202836 -312.314756) (xy 52.158374 -312.335854) (xy 52.111103 -312.349546)
			(xy 52.062248 -312.355478) (xy 52.013073 -312.353497) (xy 51.964854 -312.343653) (xy 51.918838 -312.326201)
			(xy 51.876217 -312.301594) (xy 51.838096 -312.270469) (xy 51.805461 -312.233632) (xy 51.779158 -312.192036)
			(xy 51.759867 -312.14676) (xy 51.74809 -312.098976) (xy 51.74413 -312.049922) (xy 51.405282 -312.049922)
			(xy 51.404787 -312.074529) (xy 51.396892 -312.123106) (xy 51.381308 -312.169787) (xy 51.358437 -312.213364)
			(xy 51.328872 -312.252708) (xy 51.293379 -312.2868) (xy 51.252876 -312.314756) (xy 51.208414 -312.335854)
			(xy 51.161143 -312.349546) (xy 51.112288 -312.355478) (xy 51.063113 -312.353497) (xy 51.014894 -312.343653)
			(xy 50.968878 -312.326201) (xy 50.926257 -312.301594) (xy 50.888136 -312.270469) (xy 50.855501 -312.233632)
			(xy 50.829198 -312.192036) (xy 50.809907 -312.14676) (xy 50.79813 -312.098976) (xy 50.79417 -312.049922)
			(xy 50.455068 -312.049922) (xy 50.454573 -312.074529) (xy 50.446678 -312.123106) (xy 50.431094 -312.169787)
			(xy 50.408223 -312.213364) (xy 50.378658 -312.252708) (xy 50.343165 -312.2868) (xy 50.302662 -312.314756)
			(xy 50.2582 -312.335854) (xy 50.210929 -312.349546) (xy 50.162074 -312.355478) (xy 50.112899 -312.353497)
			(xy 50.06468 -312.343653) (xy 50.018664 -312.326201) (xy 49.976043 -312.301594) (xy 49.937922 -312.270469)
			(xy 49.905287 -312.233632) (xy 49.878984 -312.192036) (xy 49.859693 -312.14676) (xy 49.847916 -312.098976)
			(xy 49.843956 -312.049922) (xy 49.505607 -312.049922) (xy 49.501438 -312.100235) (xy 49.489039 -312.149196)
			(xy 49.468751 -312.195449) (xy 49.441126 -312.237732) (xy 49.406919 -312.274891) (xy 49.367062 -312.305913)
			(xy 49.322642 -312.329952) (xy 49.274872 -312.346351) (xy 49.225054 -312.354665) (xy 49.1998 -312.35523)
			(xy 49.173638 -312.354214) (xy 49.161954 -312.353198) (xy 49.14011 -312.36158) (xy 49.069498 -312.437272)
			(xy 49.06264 -312.45937) (xy 49.064418 -312.471054) (xy 49.068153 -312.497787) (xy 49.068157 -312.551764)
			(xy 49.064418 -312.578496) (xy 49.06264 -312.59018) (xy 49.069498 -312.612532) (xy 49.14011 -312.688478)
			(xy 49.1617 -312.696606) (xy 49.173638 -312.69559) (xy 49.1998 -312.694574) (xy 49.223792 -312.695045)
			(xy 49.271184 -312.702551) (xy 49.31682 -312.717378) (xy 49.359574 -312.739161) (xy 49.398394 -312.767364)
			(xy 49.432324 -312.801293) (xy 49.46053 -312.840111) (xy 49.482315 -312.882864) (xy 49.497145 -312.928498)
			(xy 49.504654 -312.97589) (xy 49.505108 -312.999882) (xy 49.505061 -313.008919) (xy 49.504044 -313.026965)
			(xy 49.503076 -313.03595) (xy 49.501552 -313.047888) (xy 49.509426 -313.07024) (xy 49.58588 -313.143138)
			(xy 49.608486 -313.149996) (xy 49.620424 -313.148218) (xy 49.633913 -313.146096) (xy 49.661126 -313.14381)
			(xy 49.67478 -313.143646) (xy 49.688434 -313.143809) (xy 49.715646 -313.146101) (xy 49.729136 -313.148218)
			(xy 49.741074 -313.149996) (xy 49.76368 -313.143138) (xy 49.840134 -313.07024) (xy 49.848008 -313.047888)
			(xy 49.846484 -313.03595) (xy 49.845501 -313.026966) (xy 49.844482 -313.00892) (xy 49.844452 -312.999882)
			(xy 49.84494 -312.975058) (xy 49.852975 -312.926063) (xy 49.868831 -312.879014) (xy 49.89209 -312.83515)
			(xy 49.922139 -312.795627) (xy 49.958186 -312.761486) (xy 49.999282 -312.733627) (xy 50.044344 -312.712783)
			(xy 50.092184 -312.699504) (xy 50.141542 -312.69414) (xy 50.191118 -312.696833) (xy 50.239606 -312.70751)
			(xy 50.285727 -312.725891) (xy 50.328266 -312.751491) (xy 50.366104 -312.783637) (xy 50.398242 -312.821481)
			(xy 50.423835 -312.864025) (xy 50.442207 -312.91015) (xy 50.452875 -312.958639) (xy 50.455558 -313.008216)
			(xy 50.450185 -313.057573) (xy 50.436897 -313.105411) (xy 50.416045 -313.150469) (xy 50.388177 -313.191559)
			(xy 50.35403 -313.2276) (xy 50.314501 -313.257642) (xy 50.270632 -313.280892) (xy 50.22358 -313.296739)
			(xy 50.174585 -313.304765) (xy 50.14976 -313.30519) (xy 50.140723 -313.305144) (xy 50.122677 -313.304129)
			(xy 50.113692 -313.303158) (xy 50.101754 -313.301634) (xy 50.079402 -313.309508) (xy 50.006504 -313.385962)
			(xy 49.999646 -313.408568) (xy 50.001424 -313.420506) (xy 50.003547 -313.433995) (xy 50.005834 -313.461208)
			(xy 50.005996 -313.474862) (xy 50.005996 -313.54522) (xy 50.006459 -313.555877) (xy 50.015146 -313.57534)
			(xy 50.02276 -313.582812) (xy 50.087022 -313.640724) (xy 50.107342 -313.647328) (xy 50.11801 -313.646058)
			(xy 50.14976 -313.644534) (xy 50.173754 -313.644977) (xy 50.221152 -313.652479) (xy 50.266792 -313.667305)
			(xy 50.309551 -313.689089) (xy 50.348374 -313.717294) (xy 50.382307 -313.751227) (xy 50.410512 -313.790051)
			(xy 50.432296 -313.83281) (xy 50.447121 -313.87845) (xy 50.454623 -313.925848) (xy 50.455068 -313.949842)
			(xy 50.454052 -313.976004) (xy 50.453036 -313.987688) (xy 50.461418 -314.009278) (xy 50.53711 -314.07989)
			(xy 50.559462 -314.086748) (xy 50.571146 -314.08497) (xy 50.584518 -314.082961) (xy 50.611473 -314.080797)
			(xy 50.624994 -314.080652) (xy 50.638451 -314.080813) (xy 50.665279 -314.082975) (xy 50.678588 -314.08497)
			(xy 50.690272 -314.086748) (xy 50.712624 -314.07989) (xy 50.788316 -314.009278) (xy 50.796698 -313.987688)
			(xy 50.795682 -313.97575) (xy 50.794666 -313.949842) (xy 50.795109 -313.925846) (xy 50.80261 -313.878444)
			(xy 50.817435 -313.832799) (xy 50.839218 -313.790035) (xy 50.867422 -313.751205) (xy 50.901354 -313.717266)
			(xy 50.940177 -313.689053) (xy 50.982936 -313.667261) (xy 51.028578 -313.652426) (xy 51.075978 -313.644914)
			(xy 51.099974 -313.644534) (xy 51.13147 -313.646058) (xy 51.142392 -313.647328) (xy 51.162458 -313.640724)
			(xy 51.22672 -313.582812) (xy 51.234224 -313.575264) (xy 51.242877 -313.555846) (xy 51.243484 -313.54522)
			(xy 51.243484 -313.474862) (xy 51.243645 -313.461208) (xy 51.245934 -313.433995) (xy 51.248056 -313.420506)
			(xy 51.249834 -313.408568) (xy 51.242976 -313.385962) (xy 51.170078 -313.309762) (xy 51.14798 -313.301634)
			(xy 51.135788 -313.303158) (xy 51.126866 -313.304119) (xy 51.108948 -313.305134) (xy 51.099974 -313.30519)
			(xy 51.075155 -313.304702) (xy 51.026173 -313.296668) (xy 50.979135 -313.280815) (xy 50.935281 -313.257561)
			(xy 50.895768 -313.22752) (xy 50.861634 -313.191481) (xy 50.833781 -313.150395) (xy 50.812941 -313.105345)
			(xy 50.799664 -313.057516) (xy 50.794299 -313.00817) (xy 50.796988 -312.958605) (xy 50.80766 -312.910129)
			(xy 50.826034 -312.864017) (xy 50.851625 -312.821486) (xy 50.88376 -312.783655) (xy 50.921592 -312.751521)
			(xy 50.964125 -312.72593) (xy 51.010236 -312.707558) (xy 51.058713 -312.696887) (xy 51.108278 -312.694199)
			(xy 51.157624 -312.699565) (xy 51.205452 -312.712844) (xy 51.250502 -312.733685) (xy 51.291587 -312.761539)
			(xy 51.327625 -312.795673) (xy 51.357666 -312.835188) (xy 51.380918 -312.879042) (xy 51.39677 -312.92608)
			(xy 51.404803 -312.975063) (xy 51.405282 -312.999882) (xy 51.405235 -313.008919) (xy 51.404218 -313.026965)
			(xy 51.40325 -313.03595) (xy 51.401726 -313.047888) (xy 51.4096 -313.07024) (xy 51.486054 -313.143138)
			(xy 51.50866 -313.149996) (xy 51.520598 -313.147964) (xy 51.534028 -313.14591) (xy 51.561114 -313.143745)
			(xy 51.5747 -313.143646) (xy 51.588354 -313.143806) (xy 51.615567 -313.146092) (xy 51.629056 -313.148218)
			(xy 51.641248 -313.15025) (xy 51.663854 -313.143138) (xy 51.740308 -313.07024) (xy 51.748182 -313.048142)
			(xy 51.746658 -313.03595) (xy 51.745675 -313.026966) (xy 51.744656 -313.00892) (xy 51.744626 -312.999882)
			(xy 51.745113 -312.975065) (xy 51.753146 -312.926085) (xy 51.768996 -312.879049) (xy 51.792247 -312.835198)
			(xy 51.822286 -312.795685) (xy 51.858321 -312.761553) (xy 51.899404 -312.733699) (xy 51.944451 -312.712859)
			(xy 51.992277 -312.699581) (xy 52.04162 -312.694215) (xy 52.091182 -312.696902) (xy 52.139656 -312.707572)
			(xy 52.185765 -312.725943) (xy 52.228295 -312.751531) (xy 52.266125 -312.783663) (xy 52.298259 -312.821492)
			(xy 52.32385 -312.86402) (xy 52.342223 -312.910129) (xy 52.352896 -312.958602) (xy 52.355585 -313.008164)
			(xy 52.350222 -313.057508) (xy 52.336946 -313.105334) (xy 52.316108 -313.150382) (xy 52.288257 -313.191466)
			(xy 52.254127 -313.227503) (xy 52.214616 -313.257544) (xy 52.170765 -313.280797) (xy 52.123731 -313.29665)
			(xy 52.074751 -313.304686) (xy 52.049934 -313.30519) (xy 52.040833 -313.305152) (xy 52.02266 -313.304137)
			(xy 52.013612 -313.303158) (xy 52.001674 -313.301634) (xy 51.979322 -313.309508) (xy 51.906424 -313.385962)
			(xy 51.899312 -313.408568) (xy 51.901344 -313.420506) (xy 51.903467 -313.433995) (xy 51.905753 -313.461208)
			(xy 51.905916 -313.474862) (xy 51.905916 -313.54522) (xy 51.90638 -313.555877) (xy 51.915069 -313.575337)
			(xy 51.92268 -313.582812) (xy 51.986942 -313.640724) (xy 52.007262 -313.647328) (xy 52.018184 -313.646312)
			(xy 52.049934 -313.644534) (xy 52.073924 -313.644983) (xy 52.121313 -313.652494) (xy 52.166944 -313.667326)
			(xy 52.209692 -313.689114) (xy 52.248505 -313.717321) (xy 52.282429 -313.751252) (xy 52.310626 -313.790073)
			(xy 52.332403 -313.832827) (xy 52.347224 -313.878461) (xy 52.354723 -313.925852) (xy 52.355242 -313.949842)
			(xy 52.354226 -313.97575) (xy 52.35321 -313.987688) (xy 52.361592 -314.009278) (xy 52.437284 -314.07989)
			(xy 52.459636 -314.086748) (xy 52.47132 -314.08497) (xy 52.484629 -314.082973) (xy 52.511457 -314.080809)
			(xy 52.524914 -314.080652) (xy 52.538371 -314.080814) (xy 52.565198 -314.082977) (xy 52.578508 -314.08497)
			(xy 52.590192 -314.086748) (xy 52.612544 -314.07989) (xy 52.688236 -314.009278) (xy 52.696618 -313.987688)
			(xy 52.695602 -313.97575) (xy 52.694586 -313.949842) (xy 52.695029 -313.925847) (xy 52.702531 -313.878446)
			(xy 52.717355 -313.832802) (xy 52.739138 -313.79004) (xy 52.767343 -313.751212) (xy 52.801275 -313.717274)
			(xy 52.840099 -313.689063) (xy 52.882858 -313.667274) (xy 52.928499 -313.652442) (xy 52.975899 -313.644933)
			(xy 52.999894 -313.644534) (xy 53.03139 -313.646058) (xy 53.042312 -313.647328) (xy 53.062378 -313.640724)
			(xy 53.12664 -313.582812) (xy 53.134153 -313.575269) (xy 53.142821 -313.55585) (xy 53.143404 -313.54522)
			(xy 53.143404 -313.474862) (xy 53.143565 -313.461208) (xy 53.145854 -313.433995) (xy 53.147976 -313.420506)
			(xy 53.149754 -313.408568) (xy 53.142896 -313.385962) (xy 53.069998 -313.309762) (xy 53.0479 -313.301634)
			(xy 53.035708 -313.303158) (xy 53.026786 -313.30412) (xy 53.008868 -313.305136) (xy 52.999894 -313.30519)
			(xy 52.975075 -313.304704) (xy 52.926091 -313.296672) (xy 52.879052 -313.280822) (xy 52.835196 -313.257571)
			(xy 52.79568 -313.227531) (xy 52.761544 -313.191494) (xy 52.733688 -313.150409) (xy 52.712846 -313.105359)
			(xy 52.699566 -313.05753) (xy 52.694199 -313.008183) (xy 52.696886 -312.958618) (xy 52.707556 -312.91014)
			(xy 52.725929 -312.864028) (xy 52.751519 -312.821495) (xy 52.783653 -312.783662) (xy 52.821485 -312.751526)
			(xy 52.864017 -312.725934) (xy 52.910129 -312.70756) (xy 52.958606 -312.696888) (xy 53.008171 -312.694199)
			(xy 53.057518 -312.699564) (xy 53.105347 -312.712842) (xy 53.150398 -312.733682) (xy 53.191484 -312.761537)
			(xy 53.227523 -312.795671) (xy 53.257564 -312.835186) (xy 53.280817 -312.879041) (xy 53.296669 -312.926079)
			(xy 53.304703 -312.975063) (xy 53.305202 -312.999882) (xy 53.305155 -313.008919) (xy 53.304138 -313.026965)
			(xy 53.30317 -313.03595) (xy 53.301646 -313.047888) (xy 53.30952 -313.07024) (xy 53.385974 -313.143138)
			(xy 53.40858 -313.149996) (xy 53.420518 -313.147964) (xy 53.433948 -313.145911) (xy 53.461034 -313.143748)
			(xy 53.47462 -313.143646) (xy 53.488274 -313.143806) (xy 53.515487 -313.146094) (xy 53.528976 -313.148218)
			(xy 53.541168 -313.15025) (xy 53.563774 -313.143138) (xy 53.640228 -313.07024) (xy 53.648102 -313.048142)
			(xy 53.646578 -313.03595) (xy 53.645595 -313.026966) (xy 53.644576 -313.00892) (xy 53.644546 -312.999882)
			(xy 53.645033 -312.975057) (xy 53.653069 -312.926061) (xy 53.668925 -312.879011) (xy 53.692185 -312.835146)
			(xy 53.722234 -312.795622) (xy 53.758283 -312.76148) (xy 53.79938 -312.73362) (xy 53.844443 -312.712777)
			(xy 53.892285 -312.699498) (xy 53.941644 -312.694134) (xy 53.991221 -312.696826) (xy 54.03971 -312.707504)
			(xy 54.085832 -312.725886) (xy 54.128373 -312.751488) (xy 54.166211 -312.783635) (xy 54.19835 -312.82148)
			(xy 54.223942 -312.864026) (xy 54.242315 -312.910151) (xy 54.252982 -312.958642) (xy 54.255664 -313.00822)
			(xy 54.25029 -313.057578) (xy 54.237001 -313.105417) (xy 54.216148 -313.150476) (xy 54.188279 -313.191567)
			(xy 54.15413 -313.227608) (xy 54.1146 -313.25765) (xy 54.07073 -313.2809) (xy 54.023677 -313.296747)
			(xy 53.974679 -313.304772) (xy 53.949854 -313.30519) (xy 53.940753 -313.305149) (xy 53.922581 -313.30413)
			(xy 53.913532 -313.303158) (xy 53.901594 -313.301634) (xy 53.879242 -313.309508) (xy 53.806344 -313.385962)
			(xy 53.799232 -313.408568) (xy 53.801264 -313.420506) (xy 53.803387 -313.433995) (xy 53.805673 -313.461208)
			(xy 53.805836 -313.474862) (xy 53.805836 -313.54522) (xy 53.8063 -313.555876) (xy 53.814992 -313.575334)
			(xy 53.8226 -313.582812) (xy 53.886862 -313.640724) (xy 53.907182 -313.647328) (xy 53.918104 -313.646312)
			(xy 53.949854 -313.644534) (xy 53.973848 -313.644977) (xy 54.021247 -313.652478) (xy 54.066888 -313.667303)
			(xy 54.109647 -313.689087) (xy 54.148472 -313.717292) (xy 54.182405 -313.751225) (xy 54.210611 -313.790049)
			(xy 54.232395 -313.832808) (xy 54.247221 -313.878449) (xy 54.254723 -313.925848) (xy 54.255162 -313.949842)
			(xy 54.254146 -313.97575) (xy 54.25313 -313.987688) (xy 54.261512 -314.009278) (xy 54.337204 -314.07989)
			(xy 54.359556 -314.086748) (xy 54.37124 -314.08497) (xy 54.384549 -314.082973) (xy 54.411377 -314.080812)
			(xy 54.424834 -314.080652) (xy 54.438291 -314.080814) (xy 54.465118 -314.082979) (xy 54.478428 -314.08497)
			(xy 54.490112 -314.086748) (xy 54.512464 -314.07989) (xy 54.588156 -314.009278) (xy 54.596538 -313.987688)
			(xy 54.595522 -313.97575) (xy 54.594506 -313.949842) (xy 54.594949 -313.925847) (xy 54.602451 -313.878447)
			(xy 54.617276 -313.832805) (xy 54.639059 -313.790044) (xy 54.667264 -313.751218) (xy 54.701196 -313.717282)
			(xy 54.74002 -313.689074) (xy 54.782779 -313.667286) (xy 54.82842 -313.652457) (xy 54.875819 -313.644951)
			(xy 54.899814 -313.644534) (xy 54.931564 -313.646312) (xy 54.942486 -313.647328) (xy 54.962806 -313.640724)
			(xy 55.027068 -313.582812) (xy 55.034578 -313.575268) (xy 55.043241 -313.555848) (xy 55.043832 -313.54522)
			(xy 55.043832 -313.474862) (xy 55.043993 -313.461208) (xy 55.04628 -313.433995) (xy 55.048404 -313.420506)
			(xy 55.050436 -313.408568) (xy 55.043324 -313.385962) (xy 54.970426 -313.309508) (xy 54.948074 -313.301634)
			(xy 54.936136 -313.303158) (xy 54.927089 -313.304147) (xy 54.908915 -313.305162) (xy 54.899814 -313.30519)
			(xy 54.874995 -313.304705) (xy 54.82601 -313.296677) (xy 54.778969 -313.280829) (xy 54.735111 -313.25758)
			(xy 54.695593 -313.227542) (xy 54.661455 -313.191506) (xy 54.633596 -313.150422) (xy 54.612751 -313.105373)
			(xy 54.599469 -313.057544) (xy 54.5941 -313.008197) (xy 54.596784 -312.958631) (xy 54.607453 -312.910152)
			(xy 54.625824 -312.864038) (xy 54.651413 -312.821503) (xy 54.683546 -312.783669) (xy 54.721377 -312.751532)
			(xy 54.763909 -312.725938) (xy 54.810021 -312.707562) (xy 54.858499 -312.696889) (xy 54.908065 -312.694199)
			(xy 54.957412 -312.699563) (xy 55.005243 -312.71284) (xy 55.050295 -312.73368) (xy 55.091381 -312.761534)
			(xy 55.127421 -312.795669) (xy 55.157463 -312.835184) (xy 55.180717 -312.879039) (xy 55.196569 -312.926078)
			(xy 55.204603 -312.975063) (xy 55.205122 -312.999882) (xy 55.205083 -313.008983) (xy 55.204067 -313.027156)
			(xy 55.20309 -313.036204) (xy 55.201566 -313.048142) (xy 55.20944 -313.070494) (xy 55.285894 -313.143392)
			(xy 55.3085 -313.150504) (xy 55.320438 -313.148472) (xy 55.333926 -313.146342) (xy 55.361139 -313.144051)
			(xy 55.374794 -313.1439) (xy 55.388448 -313.144063) (xy 55.41566 -313.146355) (xy 55.42915 -313.148472)
			(xy 55.441088 -313.150504) (xy 55.463694 -313.143392) (xy 55.540148 -313.070494) (xy 55.548022 -313.048142)
			(xy 55.546498 -313.036204) (xy 55.54551 -313.027157) (xy 55.544496 -313.008983) (xy 55.544466 -312.999882)
			(xy 55.544953 -312.975059) (xy 55.552988 -312.926067) (xy 55.568843 -312.879021) (xy 55.592101 -312.835159)
			(xy 55.622148 -312.795638) (xy 55.658193 -312.761499) (xy 55.699286 -312.733641) (xy 55.744345 -312.712798)
			(xy 55.792183 -312.699519) (xy 55.841538 -312.694155) (xy 55.891111 -312.696846) (xy 55.939596 -312.707522)
			(xy 55.985715 -312.725901) (xy 56.028253 -312.751499) (xy 56.066089 -312.783642) (xy 56.098227 -312.821483)
			(xy 56.123819 -312.864024) (xy 56.142191 -312.910146) (xy 56.15286 -312.958632) (xy 56.155544 -313.008206)
			(xy 56.150173 -313.057561) (xy 56.136887 -313.105396) (xy 56.116038 -313.150452) (xy 56.088174 -313.191542)
			(xy 56.054029 -313.227582) (xy 56.014504 -313.257623) (xy 55.970639 -313.280874) (xy 55.92359 -313.296722)
			(xy 55.874597 -313.30475) (xy 55.849774 -313.30519) (xy 55.840673 -313.30515) (xy 55.822501 -313.304132)
			(xy 55.813452 -313.303158) (xy 55.801514 -313.301634) (xy 55.779162 -313.309508) (xy 55.706264 -313.385962)
			(xy 55.699152 -313.408568) (xy 55.701184 -313.420506) (xy 55.703315 -313.433994) (xy 55.705608 -313.461207)
			(xy 55.705756 -313.474862) (xy 55.705756 -313.54522) (xy 55.706221 -313.555876) (xy 55.714915 -313.575331)
			(xy 55.72252 -313.582812) (xy 55.786782 -313.640724) (xy 55.807102 -313.647328) (xy 55.818024 -313.646312)
			(xy 55.849774 -313.644534) (xy 55.873767 -313.644978) (xy 55.921163 -313.652482) (xy 55.966802 -313.667309)
			(xy 56.009559 -313.689093) (xy 56.04838 -313.717299) (xy 56.082311 -313.751232) (xy 56.110515 -313.790055)
			(xy 56.132297 -313.832813) (xy 56.147122 -313.878452) (xy 56.154623 -313.925849) (xy 56.155082 -313.949842)
			(xy 56.154984 -313.958946) (xy 56.153841 -313.977119) (xy 56.152796 -313.986164) (xy 56.151526 -313.998356)
			(xy 56.1594 -314.020708) (xy 56.235854 -314.093606) (xy 56.25846 -314.100718) (xy 56.270398 -314.098686)
			(xy 56.283886 -314.096553) (xy 56.311099 -314.094261) (xy 56.324754 -314.094114) (xy 56.338472 -314.09427)
			(xy 56.365811 -314.096562) (xy 56.379364 -314.098686) (xy 56.391302 -314.100718) (xy 56.413908 -314.093606)
			(xy 56.490362 -314.020708) (xy 56.498236 -313.998356) (xy 56.496966 -313.986418) (xy 56.495911 -313.97731)
			(xy 56.494767 -313.95901) (xy 56.49468 -313.949842) (xy 56.495123 -313.925846) (xy 56.502624 -313.878445)
			(xy 56.517449 -313.832801) (xy 56.539232 -313.790038) (xy 56.567437 -313.75121) (xy 56.601369 -313.717272)
			(xy 56.640192 -313.68906) (xy 56.682951 -313.66727) (xy 56.728592 -313.652437) (xy 56.775992 -313.644927)
			(xy 56.799988 -313.644534) (xy 56.831738 -313.646312) (xy 56.84266 -313.647328) (xy 56.86298 -313.640724)
			(xy 56.927242 -313.582812) (xy 56.934755 -313.575269) (xy 56.943422 -313.555849) (xy 56.944006 -313.54522)
			(xy 56.944006 -313.474862) (xy 56.944167 -313.461208) (xy 56.946454 -313.433995) (xy 56.948578 -313.420506)
			(xy 56.95061 -313.408568) (xy 56.943498 -313.385962) (xy 56.8706 -313.309508) (xy 56.848248 -313.301634)
			(xy 56.83631 -313.303158) (xy 56.827263 -313.304146) (xy 56.809089 -313.30516) (xy 56.799988 -313.30519)
			(xy 56.775169 -313.304703) (xy 56.726186 -313.296671) (xy 56.679147 -313.28082) (xy 56.635292 -313.257568)
			(xy 56.595776 -313.227528) (xy 56.561641 -313.19149) (xy 56.533786 -313.150405) (xy 56.512944 -313.105354)
			(xy 56.499665 -313.057526) (xy 56.494299 -313.008179) (xy 56.496987 -312.958614) (xy 56.507657 -312.910137)
			(xy 56.52603 -312.864025) (xy 56.551621 -312.821492) (xy 56.583755 -312.78366) (xy 56.621587 -312.751524)
			(xy 56.664119 -312.725933) (xy 56.710231 -312.707559) (xy 56.758708 -312.696888) (xy 56.808273 -312.694199)
			(xy 56.85762 -312.699564) (xy 56.905449 -312.712842) (xy 56.9505 -312.733683) (xy 56.991585 -312.761538)
			(xy 57.027624 -312.795672) (xy 57.057665 -312.835187) (xy 57.080918 -312.879041) (xy 57.09677 -312.92608)
			(xy 57.104803 -312.975063) (xy 57.105296 -312.999882) (xy 57.105257 -313.008983) (xy 57.104242 -313.027156)
			(xy 57.103264 -313.036204) (xy 57.10174 -313.048142) (xy 57.109614 -313.070494) (xy 57.186068 -313.143392)
			(xy 57.208674 -313.150504) (xy 57.220612 -313.148472) (xy 57.2341 -313.146341) (xy 57.261313 -313.144048)
			(xy 57.274968 -313.1439) (xy 57.288622 -313.144062) (xy 57.315835 -313.146351) (xy 57.329324 -313.148472)
			(xy 57.341262 -313.150504) (xy 57.363868 -313.143392) (xy 57.440322 -313.070494) (xy 57.448196 -313.048142)
			(xy 57.446672 -313.036204) (xy 57.445684 -313.027157) (xy 57.44467 -313.008983) (xy 57.44464 -312.999882)
			(xy 57.445127 -312.975066) (xy 57.453159 -312.926089) (xy 57.469009 -312.879056) (xy 57.492258 -312.835207)
			(xy 57.522295 -312.795696) (xy 57.558328 -312.761565) (xy 57.599408 -312.733713) (xy 57.644453 -312.712874)
			(xy 57.692275 -312.699596) (xy 57.741616 -312.694229) (xy 57.791175 -312.696915) (xy 57.839646 -312.707584)
			(xy 57.885754 -312.725953) (xy 57.928282 -312.751539) (xy 57.966111 -312.783668) (xy 57.998243 -312.821494)
			(xy 58.023834 -312.864019) (xy 58.042207 -312.910125) (xy 58.05288 -312.958595) (xy 58.055123 -312.999882)
			(xy 58.394104 -312.999882) (xy 58.398064 -312.950828) (xy 58.409841 -312.903044) (xy 58.429132 -312.857768)
			(xy 58.455435 -312.816172) (xy 58.48807 -312.779335) (xy 58.526191 -312.74821) (xy 58.568812 -312.723603)
			(xy 58.614828 -312.706151) (xy 58.663047 -312.696307) (xy 58.712222 -312.694326) (xy 58.761077 -312.700258)
			(xy 58.808348 -312.71395) (xy 58.85281 -312.735048) (xy 58.893313 -312.763004) (xy 58.928806 -312.797096)
			(xy 58.958371 -312.83644) (xy 58.981242 -312.880017) (xy 58.996826 -312.926698) (xy 59.004721 -312.975275)
			(xy 59.005216 -312.999882) (xy 59.004721 -313.024489) (xy 59.004542 -313.02559) (xy 59.32322 -313.02559)
			(xy 59.32322 -312.974174) (xy 59.331263 -312.923392) (xy 59.347151 -312.874493) (xy 59.370494 -312.828681)
			(xy 59.400715 -312.787085) (xy 59.437071 -312.750729) (xy 59.478667 -312.720508) (xy 59.524479 -312.697165)
			(xy 59.573378 -312.681277) (xy 59.62416 -312.673234) (xy 59.675576 -312.673234) (xy 59.726358 -312.681277)
			(xy 59.775257 -312.697165) (xy 59.821069 -312.720508) (xy 59.862665 -312.750729) (xy 59.899021 -312.787085)
			(xy 59.929242 -312.828681) (xy 59.952585 -312.874493) (xy 59.968473 -312.923392) (xy 59.976516 -312.974174)
			(xy 59.97702 -312.999882) (xy 60.294024 -312.999882) (xy 60.297984 -312.950828) (xy 60.309761 -312.903044)
			(xy 60.329052 -312.857768) (xy 60.355355 -312.816172) (xy 60.38799 -312.779335) (xy 60.426111 -312.74821)
			(xy 60.468732 -312.723603) (xy 60.514748 -312.706151) (xy 60.562967 -312.696307) (xy 60.612142 -312.694326)
			(xy 60.660997 -312.700258) (xy 60.708268 -312.71395) (xy 60.75273 -312.735048) (xy 60.793233 -312.763004)
			(xy 60.828726 -312.797096) (xy 60.858291 -312.83644) (xy 60.881162 -312.880017) (xy 60.896746 -312.926698)
			(xy 60.904641 -312.975275) (xy 60.905136 -312.999882) (xy 60.904641 -313.024489) (xy 60.904462 -313.02559)
			(xy 61.22314 -313.02559) (xy 61.22314 -312.974174) (xy 61.231183 -312.923392) (xy 61.247071 -312.874493)
			(xy 61.270414 -312.828681) (xy 61.300635 -312.787085) (xy 61.336991 -312.750729) (xy 61.378587 -312.720508)
			(xy 61.424399 -312.697165) (xy 61.473298 -312.681277) (xy 61.52408 -312.673234) (xy 61.575496 -312.673234)
			(xy 61.626278 -312.681277) (xy 61.675177 -312.697165) (xy 61.720989 -312.720508) (xy 61.762585 -312.750729)
			(xy 61.798941 -312.787085) (xy 61.829162 -312.828681) (xy 61.852505 -312.874493) (xy 61.868393 -312.923392)
			(xy 61.876436 -312.974174) (xy 61.87694 -312.999882) (xy 62.193944 -312.999882) (xy 62.197904 -312.950828)
			(xy 62.209681 -312.903044) (xy 62.228972 -312.857768) (xy 62.255275 -312.816172) (xy 62.28791 -312.779335)
			(xy 62.326031 -312.74821) (xy 62.368652 -312.723603) (xy 62.414668 -312.706151) (xy 62.462887 -312.696307)
			(xy 62.512062 -312.694326) (xy 62.560917 -312.700258) (xy 62.608188 -312.71395) (xy 62.65265 -312.735048)
			(xy 62.693153 -312.763004) (xy 62.728646 -312.797096) (xy 62.758211 -312.83644) (xy 62.781082 -312.880017)
			(xy 62.796666 -312.926698) (xy 62.804561 -312.975275) (xy 62.805056 -312.999882) (xy 62.804561 -313.024489)
			(xy 62.804382 -313.02559) (xy 63.123314 -313.02559) (xy 63.123314 -312.974174) (xy 63.131357 -312.923392)
			(xy 63.147245 -312.874493) (xy 63.170588 -312.828681) (xy 63.200809 -312.787085) (xy 63.237165 -312.750729)
			(xy 63.278761 -312.720508) (xy 63.324573 -312.697165) (xy 63.373472 -312.681277) (xy 63.424254 -312.673234)
			(xy 63.47567 -312.673234) (xy 63.526452 -312.681277) (xy 63.575351 -312.697165) (xy 63.621163 -312.720508)
			(xy 63.662759 -312.750729) (xy 63.699115 -312.787085) (xy 63.729336 -312.828681) (xy 63.752679 -312.874493)
			(xy 63.768567 -312.923392) (xy 63.77661 -312.974174) (xy 63.777114 -312.999882) (xy 64.094118 -312.999882)
			(xy 64.098078 -312.950828) (xy 64.109855 -312.903044) (xy 64.129146 -312.857768) (xy 64.155449 -312.816172)
			(xy 64.188084 -312.779335) (xy 64.226205 -312.74821) (xy 64.268826 -312.723603) (xy 64.314842 -312.706151)
			(xy 64.363061 -312.696307) (xy 64.412236 -312.694326) (xy 64.461091 -312.700258) (xy 64.508362 -312.71395)
			(xy 64.552824 -312.735048) (xy 64.593327 -312.763004) (xy 64.62882 -312.797096) (xy 64.658385 -312.83644)
			(xy 64.681256 -312.880017) (xy 64.69684 -312.926698) (xy 64.704735 -312.975275) (xy 64.70523 -312.999882)
			(xy 64.704735 -313.024489) (xy 64.704556 -313.02559) (xy 65.023234 -313.02559) (xy 65.023234 -312.974174)
			(xy 65.031277 -312.923392) (xy 65.047165 -312.874493) (xy 65.070508 -312.828681) (xy 65.100729 -312.787085)
			(xy 65.137085 -312.750729) (xy 65.178681 -312.720508) (xy 65.224493 -312.697165) (xy 65.273392 -312.681277)
			(xy 65.324174 -312.673234) (xy 65.37559 -312.673234) (xy 65.426372 -312.681277) (xy 65.475271 -312.697165)
			(xy 65.521083 -312.720508) (xy 65.562679 -312.750729) (xy 65.599035 -312.787085) (xy 65.629256 -312.828681)
			(xy 65.652599 -312.874493) (xy 65.668487 -312.923392) (xy 65.67653 -312.974174) (xy 65.677034 -312.999882)
			(xy 65.994038 -312.999882) (xy 65.997998 -312.950828) (xy 66.009775 -312.903044) (xy 66.029066 -312.857768)
			(xy 66.055369 -312.816172) (xy 66.088004 -312.779335) (xy 66.126125 -312.74821) (xy 66.168746 -312.723603)
			(xy 66.214762 -312.706151) (xy 66.262981 -312.696307) (xy 66.312156 -312.694326) (xy 66.361011 -312.700258)
			(xy 66.408282 -312.71395) (xy 66.452744 -312.735048) (xy 66.493247 -312.763004) (xy 66.52874 -312.797096)
			(xy 66.558305 -312.83644) (xy 66.581176 -312.880017) (xy 66.59676 -312.926698) (xy 66.604655 -312.975275)
			(xy 66.60515 -312.999882) (xy 66.604655 -313.024489) (xy 66.604476 -313.02559) (xy 66.923154 -313.02559)
			(xy 66.923154 -312.974174) (xy 66.931197 -312.923392) (xy 66.947085 -312.874493) (xy 66.970428 -312.828681)
			(xy 67.000649 -312.787085) (xy 67.037005 -312.750729) (xy 67.078601 -312.720508) (xy 67.124413 -312.697165)
			(xy 67.173312 -312.681277) (xy 67.224094 -312.673234) (xy 67.27551 -312.673234) (xy 67.326292 -312.681277)
			(xy 67.375191 -312.697165) (xy 67.421003 -312.720508) (xy 67.462599 -312.750729) (xy 67.498955 -312.787085)
			(xy 67.529176 -312.828681) (xy 67.552519 -312.874493) (xy 67.568407 -312.923392) (xy 67.57645 -312.974174)
			(xy 67.576954 -312.999882) (xy 67.893958 -312.999882) (xy 67.897918 -312.950828) (xy 67.909695 -312.903044)
			(xy 67.928986 -312.857768) (xy 67.955289 -312.816172) (xy 67.987924 -312.779335) (xy 68.026045 -312.74821)
			(xy 68.068666 -312.723603) (xy 68.114682 -312.706151) (xy 68.162901 -312.696307) (xy 68.212076 -312.694326)
			(xy 68.260931 -312.700258) (xy 68.308202 -312.71395) (xy 68.352664 -312.735048) (xy 68.393167 -312.763004)
			(xy 68.42866 -312.797096) (xy 68.458225 -312.83644) (xy 68.481096 -312.880017) (xy 68.49668 -312.926698)
			(xy 68.504575 -312.975275) (xy 68.50507 -312.999882) (xy 68.504575 -313.024489) (xy 68.504396 -313.02559)
			(xy 68.823328 -313.02559) (xy 68.823328 -312.974174) (xy 68.831371 -312.923392) (xy 68.847259 -312.874493)
			(xy 68.870602 -312.828681) (xy 68.900823 -312.787085) (xy 68.937179 -312.750729) (xy 68.978775 -312.720508)
			(xy 69.024587 -312.697165) (xy 69.073486 -312.681277) (xy 69.124268 -312.673234) (xy 69.175684 -312.673234)
			(xy 69.226466 -312.681277) (xy 69.275365 -312.697165) (xy 69.321177 -312.720508) (xy 69.362773 -312.750729)
			(xy 69.399129 -312.787085) (xy 69.42935 -312.828681) (xy 69.452693 -312.874493) (xy 69.468581 -312.923392)
			(xy 69.476624 -312.974174) (xy 69.477128 -312.999882) (xy 69.794132 -312.999882) (xy 69.798092 -312.950828)
			(xy 69.809869 -312.903044) (xy 69.82916 -312.857768) (xy 69.855463 -312.816172) (xy 69.888098 -312.779335)
			(xy 69.926219 -312.74821) (xy 69.96884 -312.723603) (xy 70.014856 -312.706151) (xy 70.063075 -312.696307)
			(xy 70.11225 -312.694326) (xy 70.161105 -312.700258) (xy 70.208376 -312.71395) (xy 70.252838 -312.735048)
			(xy 70.293341 -312.763004) (xy 70.328834 -312.797096) (xy 70.358399 -312.83644) (xy 70.38127 -312.880017)
			(xy 70.396854 -312.926698) (xy 70.404749 -312.975275) (xy 70.405244 -312.999882) (xy 70.404749 -313.024489)
			(xy 70.40457 -313.02559) (xy 70.723248 -313.02559) (xy 70.723248 -312.974174) (xy 70.731291 -312.923392)
			(xy 70.747179 -312.874493) (xy 70.770522 -312.828681) (xy 70.800743 -312.787085) (xy 70.837099 -312.750729)
			(xy 70.878695 -312.720508) (xy 70.924507 -312.697165) (xy 70.973406 -312.681277) (xy 71.024188 -312.673234)
			(xy 71.075604 -312.673234) (xy 71.126386 -312.681277) (xy 71.175285 -312.697165) (xy 71.221097 -312.720508)
			(xy 71.262693 -312.750729) (xy 71.299049 -312.787085) (xy 71.32927 -312.828681) (xy 71.352613 -312.874493)
			(xy 71.368501 -312.923392) (xy 71.376544 -312.974174) (xy 71.377048 -312.999882) (xy 71.694052 -312.999882)
			(xy 71.698012 -312.950828) (xy 71.709789 -312.903044) (xy 71.72908 -312.857768) (xy 71.755383 -312.816172)
			(xy 71.788018 -312.779335) (xy 71.826139 -312.74821) (xy 71.86876 -312.723603) (xy 71.914776 -312.706151)
			(xy 71.962995 -312.696307) (xy 72.01217 -312.694326) (xy 72.061025 -312.700258) (xy 72.108296 -312.71395)
			(xy 72.152758 -312.735048) (xy 72.193261 -312.763004) (xy 72.228754 -312.797096) (xy 72.258319 -312.83644)
			(xy 72.28119 -312.880017) (xy 72.296774 -312.926698) (xy 72.304669 -312.975275) (xy 72.305164 -312.999882)
			(xy 72.304669 -313.024489) (xy 72.30449 -313.02559) (xy 72.623168 -313.02559) (xy 72.623168 -312.974174)
			(xy 72.631211 -312.923392) (xy 72.647099 -312.874493) (xy 72.670442 -312.828681) (xy 72.700663 -312.787085)
			(xy 72.737019 -312.750729) (xy 72.778615 -312.720508) (xy 72.824427 -312.697165) (xy 72.873326 -312.681277)
			(xy 72.924108 -312.673234) (xy 72.975524 -312.673234) (xy 73.026306 -312.681277) (xy 73.075205 -312.697165)
			(xy 73.121017 -312.720508) (xy 73.162613 -312.750729) (xy 73.198969 -312.787085) (xy 73.22919 -312.828681)
			(xy 73.252533 -312.874493) (xy 73.268421 -312.923392) (xy 73.276464 -312.974174) (xy 73.276968 -312.999882)
			(xy 73.593972 -312.999882) (xy 73.597932 -312.950828) (xy 73.609709 -312.903044) (xy 73.629 -312.857768)
			(xy 73.655303 -312.816172) (xy 73.687938 -312.779335) (xy 73.726059 -312.74821) (xy 73.76868 -312.723603)
			(xy 73.814696 -312.706151) (xy 73.862915 -312.696307) (xy 73.91209 -312.694326) (xy 73.960945 -312.700258)
			(xy 74.008216 -312.71395) (xy 74.052678 -312.735048) (xy 74.093181 -312.763004) (xy 74.128674 -312.797096)
			(xy 74.158239 -312.83644) (xy 74.18111 -312.880017) (xy 74.196694 -312.926698) (xy 74.204589 -312.975275)
			(xy 74.205084 -312.999882) (xy 74.544186 -312.999882) (xy 74.548146 -312.950828) (xy 74.559923 -312.903044)
			(xy 74.579214 -312.857768) (xy 74.605517 -312.816172) (xy 74.638152 -312.779335) (xy 74.676273 -312.74821)
			(xy 74.718894 -312.723603) (xy 74.76491 -312.706151) (xy 74.813129 -312.696307) (xy 74.862304 -312.694326)
			(xy 74.911159 -312.700258) (xy 74.95843 -312.71395) (xy 75.002892 -312.735048) (xy 75.043395 -312.763004)
			(xy 75.078888 -312.797096) (xy 75.108453 -312.83644) (xy 75.131324 -312.880017) (xy 75.146908 -312.926698)
			(xy 75.154803 -312.975275) (xy 75.155298 -312.999882) (xy 75.494146 -312.999882) (xy 75.498106 -312.950828)
			(xy 75.509883 -312.903044) (xy 75.529174 -312.857768) (xy 75.555477 -312.816172) (xy 75.588112 -312.779335)
			(xy 75.626233 -312.74821) (xy 75.668854 -312.723603) (xy 75.71487 -312.706151) (xy 75.763089 -312.696307)
			(xy 75.812264 -312.694326) (xy 75.861119 -312.700258) (xy 75.90839 -312.71395) (xy 75.952852 -312.735048)
			(xy 75.993355 -312.763004) (xy 76.028848 -312.797096) (xy 76.058413 -312.83644) (xy 76.081284 -312.880017)
			(xy 76.096868 -312.926698) (xy 76.104763 -312.975275) (xy 76.105258 -312.999882) (xy 76.444106 -312.999882)
			(xy 76.448066 -312.950828) (xy 76.459843 -312.903044) (xy 76.479134 -312.857768) (xy 76.505437 -312.816172)
			(xy 76.538072 -312.779335) (xy 76.576193 -312.74821) (xy 76.618814 -312.723603) (xy 76.66483 -312.706151)
			(xy 76.713049 -312.696307) (xy 76.762224 -312.694326) (xy 76.811079 -312.700258) (xy 76.85835 -312.71395)
			(xy 76.902812 -312.735048) (xy 76.943315 -312.763004) (xy 76.978808 -312.797096) (xy 77.008373 -312.83644)
			(xy 77.031244 -312.880017) (xy 77.046828 -312.926698) (xy 77.054723 -312.975275) (xy 77.055218 -312.999882)
			(xy 77.394066 -312.999882) (xy 77.398026 -312.950828) (xy 77.409803 -312.903044) (xy 77.429094 -312.857768)
			(xy 77.455397 -312.816172) (xy 77.488032 -312.779335) (xy 77.526153 -312.74821) (xy 77.568774 -312.723603)
			(xy 77.61479 -312.706151) (xy 77.663009 -312.696307) (xy 77.712184 -312.694326) (xy 77.761039 -312.700258)
			(xy 77.80831 -312.71395) (xy 77.852772 -312.735048) (xy 77.893275 -312.763004) (xy 77.928768 -312.797096)
			(xy 77.958333 -312.83644) (xy 77.981204 -312.880017) (xy 77.996788 -312.926698) (xy 78.004683 -312.975275)
			(xy 78.005178 -312.999882) (xy 78.344026 -312.999882) (xy 78.347986 -312.950828) (xy 78.359763 -312.903044)
			(xy 78.379054 -312.857768) (xy 78.405357 -312.816172) (xy 78.437992 -312.779335) (xy 78.476113 -312.74821)
			(xy 78.518734 -312.723603) (xy 78.56475 -312.706151) (xy 78.612969 -312.696307) (xy 78.662144 -312.694326)
			(xy 78.710999 -312.700258) (xy 78.75827 -312.71395) (xy 78.802732 -312.735048) (xy 78.843235 -312.763004)
			(xy 78.878728 -312.797096) (xy 78.908293 -312.83644) (xy 78.931164 -312.880017) (xy 78.946748 -312.926698)
			(xy 78.954643 -312.975275) (xy 78.955138 -312.999882) (xy 79.293986 -312.999882) (xy 79.297946 -312.950828)
			(xy 79.309723 -312.903044) (xy 79.329014 -312.857768) (xy 79.355317 -312.816172) (xy 79.387952 -312.779335)
			(xy 79.426073 -312.74821) (xy 79.468694 -312.723603) (xy 79.51471 -312.706151) (xy 79.562929 -312.696307)
			(xy 79.612104 -312.694326) (xy 79.660959 -312.700258) (xy 79.70823 -312.71395) (xy 79.752692 -312.735048)
			(xy 79.793195 -312.763004) (xy 79.828688 -312.797096) (xy 79.858253 -312.83644) (xy 79.881124 -312.880017)
			(xy 79.896708 -312.926698) (xy 79.904603 -312.975275) (xy 79.905098 -312.999882) (xy 80.243946 -312.999882)
			(xy 80.247906 -312.950828) (xy 80.259683 -312.903044) (xy 80.278974 -312.857768) (xy 80.305277 -312.816172)
			(xy 80.337912 -312.779335) (xy 80.376033 -312.74821) (xy 80.418654 -312.723603) (xy 80.46467 -312.706151)
			(xy 80.512889 -312.696307) (xy 80.562064 -312.694326) (xy 80.610919 -312.700258) (xy 80.65819 -312.71395)
			(xy 80.702652 -312.735048) (xy 80.743155 -312.763004) (xy 80.778648 -312.797096) (xy 80.808213 -312.83644)
			(xy 80.831084 -312.880017) (xy 80.846668 -312.926698) (xy 80.854563 -312.975275) (xy 80.855058 -312.999882)
			(xy 81.19416 -312.999882) (xy 81.19812 -312.950828) (xy 81.209897 -312.903044) (xy 81.229188 -312.857768)
			(xy 81.255491 -312.816172) (xy 81.288126 -312.779335) (xy 81.326247 -312.74821) (xy 81.368868 -312.723603)
			(xy 81.414884 -312.706151) (xy 81.463103 -312.696307) (xy 81.512278 -312.694326) (xy 81.561133 -312.700258)
			(xy 81.608404 -312.71395) (xy 81.652866 -312.735048) (xy 81.693369 -312.763004) (xy 81.728862 -312.797096)
			(xy 81.758427 -312.83644) (xy 81.781298 -312.880017) (xy 81.796882 -312.926698) (xy 81.804777 -312.975275)
			(xy 81.805272 -312.999882) (xy 82.14412 -312.999882) (xy 82.14808 -312.950828) (xy 82.159857 -312.903044)
			(xy 82.179148 -312.857768) (xy 82.205451 -312.816172) (xy 82.238086 -312.779335) (xy 82.276207 -312.74821)
			(xy 82.318828 -312.723603) (xy 82.364844 -312.706151) (xy 82.413063 -312.696307) (xy 82.462238 -312.694326)
			(xy 82.511093 -312.700258) (xy 82.558364 -312.71395) (xy 82.602826 -312.735048) (xy 82.643329 -312.763004)
			(xy 82.678822 -312.797096) (xy 82.708387 -312.83644) (xy 82.731258 -312.880017) (xy 82.746842 -312.926698)
			(xy 82.754737 -312.975275) (xy 82.755232 -312.999882) (xy 82.754737 -313.024489) (xy 82.746842 -313.073066)
			(xy 82.731258 -313.119747) (xy 82.708387 -313.163324) (xy 82.678822 -313.202668) (xy 82.643329 -313.23676)
			(xy 82.602826 -313.264716) (xy 82.558364 -313.285814) (xy 82.541454 -313.290712) (xy 100.471984 -313.290712)
			(xy 100.476055 -313.23509) (xy 100.488181 -313.180653) (xy 100.508104 -313.128562) (xy 100.5354 -313.079927)
			(xy 100.569486 -313.035784) (xy 100.609635 -312.997075) (xy 100.654993 -312.964624) (xy 100.704593 -312.939123)
			(xy 100.757377 -312.921116) (xy 100.81222 -312.910986) (xy 100.867954 -312.908949) (xy 100.923391 -312.915049)
			(xy 100.977348 -312.929155) (xy 101.028677 -312.950967) (xy 101.076283 -312.980021) (xy 101.119151 -313.015696)
			(xy 101.156368 -313.057233) (xy 101.187141 -313.103746) (xy 101.210813 -313.154243) (xy 101.226881 -313.20765)
			(xy 101.235001 -313.262826) (xy 101.23551 -313.290712) (xy 101.487984 -313.290712) (xy 101.492055 -313.23509)
			(xy 101.504181 -313.180653) (xy 101.524104 -313.128562) (xy 101.5514 -313.079927) (xy 101.585486 -313.035784)
			(xy 101.625635 -312.997075) (xy 101.670993 -312.964624) (xy 101.720593 -312.939123) (xy 101.773377 -312.921116)
			(xy 101.82822 -312.910986) (xy 101.883954 -312.908949) (xy 101.939391 -312.915049) (xy 101.993348 -312.929155)
			(xy 102.044677 -312.950967) (xy 102.092283 -312.980021) (xy 102.135151 -313.015696) (xy 102.172368 -313.057233)
			(xy 102.203141 -313.103746) (xy 102.226813 -313.154243) (xy 102.242881 -313.20765) (xy 102.251001 -313.262826)
			(xy 102.25151 -313.290712) (xy 102.503984 -313.290712) (xy 102.508055 -313.23509) (xy 102.520181 -313.180653)
			(xy 102.540104 -313.128562) (xy 102.5674 -313.079927) (xy 102.601486 -313.035784) (xy 102.641635 -312.997075)
			(xy 102.686993 -312.964624) (xy 102.736593 -312.939123) (xy 102.789377 -312.921116) (xy 102.84422 -312.910986)
			(xy 102.899954 -312.908949) (xy 102.955391 -312.915049) (xy 103.009348 -312.929155) (xy 103.060677 -312.950967)
			(xy 103.108283 -312.980021) (xy 103.151151 -313.015696) (xy 103.188368 -313.057233) (xy 103.219141 -313.103746)
			(xy 103.242813 -313.154243) (xy 103.258881 -313.20765) (xy 103.267001 -313.262826) (xy 103.26751 -313.290712)
			(xy 103.519984 -313.290712) (xy 103.524055 -313.23509) (xy 103.536181 -313.180653) (xy 103.556104 -313.128562)
			(xy 103.5834 -313.079927) (xy 103.617486 -313.035784) (xy 103.657635 -312.997075) (xy 103.702993 -312.964624)
			(xy 103.752593 -312.939123) (xy 103.805377 -312.921116) (xy 103.86022 -312.910986) (xy 103.915954 -312.908949)
			(xy 103.971391 -312.915049) (xy 104.025348 -312.929155) (xy 104.076677 -312.950967) (xy 104.124283 -312.980021)
			(xy 104.167151 -313.015696) (xy 104.204368 -313.057233) (xy 104.235141 -313.103746) (xy 104.258813 -313.154243)
			(xy 104.274881 -313.20765) (xy 104.283001 -313.262826) (xy 104.28351 -313.290712) (xy 104.535984 -313.290712)
			(xy 104.540055 -313.23509) (xy 104.552181 -313.180653) (xy 104.572104 -313.128562) (xy 104.5994 -313.079927)
			(xy 104.633486 -313.035784) (xy 104.673635 -312.997075) (xy 104.718993 -312.964624) (xy 104.768593 -312.939123)
			(xy 104.821377 -312.921116) (xy 104.87622 -312.910986) (xy 104.931954 -312.908949) (xy 104.987391 -312.915049)
			(xy 105.041348 -312.929155) (xy 105.092677 -312.950967) (xy 105.140283 -312.980021) (xy 105.183151 -313.015696)
			(xy 105.220368 -313.057233) (xy 105.251141 -313.103746) (xy 105.274813 -313.154243) (xy 105.290881 -313.20765)
			(xy 105.299001 -313.262826) (xy 105.29951 -313.290712) (xy 105.551984 -313.290712) (xy 105.556055 -313.23509)
			(xy 105.568181 -313.180653) (xy 105.588104 -313.128562) (xy 105.6154 -313.079927) (xy 105.649486 -313.035784)
			(xy 105.689635 -312.997075) (xy 105.734993 -312.964624) (xy 105.784593 -312.939123) (xy 105.837377 -312.921116)
			(xy 105.89222 -312.910986) (xy 105.947954 -312.908949) (xy 106.003391 -312.915049) (xy 106.057348 -312.929155)
			(xy 106.108677 -312.950967) (xy 106.156283 -312.980021) (xy 106.199151 -313.015696) (xy 106.236368 -313.057233)
			(xy 106.267141 -313.103746) (xy 106.290813 -313.154243) (xy 106.306881 -313.20765) (xy 106.315001 -313.262826)
			(xy 106.31551 -313.290712) (xy 106.567984 -313.290712) (xy 106.572055 -313.23509) (xy 106.584181 -313.180653)
			(xy 106.604104 -313.128562) (xy 106.6314 -313.079927) (xy 106.665486 -313.035784) (xy 106.705635 -312.997075)
			(xy 106.750993 -312.964624) (xy 106.800593 -312.939123) (xy 106.853377 -312.921116) (xy 106.90822 -312.910986)
			(xy 106.963954 -312.908949) (xy 107.019391 -312.915049) (xy 107.073348 -312.929155) (xy 107.124677 -312.950967)
			(xy 107.172283 -312.980021) (xy 107.215151 -313.015696) (xy 107.252368 -313.057233) (xy 107.283141 -313.103746)
			(xy 107.306813 -313.154243) (xy 107.322881 -313.20765) (xy 107.331001 -313.262826) (xy 107.33151 -313.290712)
			(xy 107.583984 -313.290712) (xy 107.588055 -313.23509) (xy 107.600181 -313.180653) (xy 107.620104 -313.128562)
			(xy 107.6474 -313.079927) (xy 107.681486 -313.035784) (xy 107.721635 -312.997075) (xy 107.766993 -312.964624)
			(xy 107.816593 -312.939123) (xy 107.869377 -312.921116) (xy 107.92422 -312.910986) (xy 107.979954 -312.908949)
			(xy 108.035391 -312.915049) (xy 108.089348 -312.929155) (xy 108.140677 -312.950967) (xy 108.188283 -312.980021)
			(xy 108.231151 -313.015696) (xy 108.268368 -313.057233) (xy 108.299141 -313.103746) (xy 108.322813 -313.154243)
			(xy 108.338881 -313.20765) (xy 108.347001 -313.262826) (xy 108.34751 -313.290712) (xy 108.599984 -313.290712)
			(xy 108.604055 -313.23509) (xy 108.616181 -313.180653) (xy 108.636104 -313.128562) (xy 108.6634 -313.079927)
			(xy 108.697486 -313.035784) (xy 108.737635 -312.997075) (xy 108.782993 -312.964624) (xy 108.832593 -312.939123)
			(xy 108.885377 -312.921116) (xy 108.94022 -312.910986) (xy 108.995954 -312.908949) (xy 109.051391 -312.915049)
			(xy 109.105348 -312.929155) (xy 109.156677 -312.950967) (xy 109.204283 -312.980021) (xy 109.247151 -313.015696)
			(xy 109.284368 -313.057233) (xy 109.315141 -313.103746) (xy 109.338813 -313.154243) (xy 109.354881 -313.20765)
			(xy 109.363001 -313.262826) (xy 109.36351 -313.290712) (xy 109.615984 -313.290712) (xy 109.620055 -313.23509)
			(xy 109.632181 -313.180653) (xy 109.652104 -313.128562) (xy 109.6794 -313.079927) (xy 109.713486 -313.035784)
			(xy 109.753635 -312.997075) (xy 109.798993 -312.964624) (xy 109.848593 -312.939123) (xy 109.901377 -312.921116)
			(xy 109.95622 -312.910986) (xy 110.011954 -312.908949) (xy 110.067391 -312.915049) (xy 110.121348 -312.929155)
			(xy 110.172677 -312.950967) (xy 110.220283 -312.980021) (xy 110.263151 -313.015696) (xy 110.300368 -313.057233)
			(xy 110.331141 -313.103746) (xy 110.354813 -313.154243) (xy 110.370881 -313.20765) (xy 110.379001 -313.262826)
			(xy 110.37951 -313.290712) (xy 110.379001 -313.318598) (xy 110.370881 -313.373774) (xy 110.354813 -313.427181)
			(xy 110.331141 -313.477678) (xy 110.300368 -313.524191) (xy 110.263151 -313.565728) (xy 110.220283 -313.601403)
			(xy 110.172677 -313.630457) (xy 110.121348 -313.652269) (xy 110.067391 -313.666375) (xy 110.011954 -313.672475)
			(xy 109.95622 -313.670438) (xy 109.901377 -313.660308) (xy 109.848593 -313.642301) (xy 109.798993 -313.6168)
			(xy 109.753635 -313.584349) (xy 109.713486 -313.54564) (xy 109.6794 -313.501497) (xy 109.652104 -313.452862)
			(xy 109.632181 -313.400771) (xy 109.620055 -313.346334) (xy 109.615984 -313.290712) (xy 109.36351 -313.290712)
			(xy 109.363001 -313.318598) (xy 109.354881 -313.373774) (xy 109.338813 -313.427181) (xy 109.315141 -313.477678)
			(xy 109.284368 -313.524191) (xy 109.247151 -313.565728) (xy 109.204283 -313.601403) (xy 109.156677 -313.630457)
			(xy 109.105348 -313.652269) (xy 109.051391 -313.666375) (xy 108.995954 -313.672475) (xy 108.94022 -313.670438)
			(xy 108.885377 -313.660308) (xy 108.832593 -313.642301) (xy 108.782993 -313.6168) (xy 108.737635 -313.584349)
			(xy 108.697486 -313.54564) (xy 108.6634 -313.501497) (xy 108.636104 -313.452862) (xy 108.616181 -313.400771)
			(xy 108.604055 -313.346334) (xy 108.599984 -313.290712) (xy 108.34751 -313.290712) (xy 108.347001 -313.318598)
			(xy 108.338881 -313.373774) (xy 108.322813 -313.427181) (xy 108.299141 -313.477678) (xy 108.268368 -313.524191)
			(xy 108.231151 -313.565728) (xy 108.188283 -313.601403) (xy 108.140677 -313.630457) (xy 108.089348 -313.652269)
			(xy 108.035391 -313.666375) (xy 107.979954 -313.672475) (xy 107.92422 -313.670438) (xy 107.869377 -313.660308)
			(xy 107.816593 -313.642301) (xy 107.766993 -313.6168) (xy 107.721635 -313.584349) (xy 107.681486 -313.54564)
			(xy 107.6474 -313.501497) (xy 107.620104 -313.452862) (xy 107.600181 -313.400771) (xy 107.588055 -313.346334)
			(xy 107.583984 -313.290712) (xy 107.33151 -313.290712) (xy 107.331001 -313.318598) (xy 107.322881 -313.373774)
			(xy 107.306813 -313.427181) (xy 107.283141 -313.477678) (xy 107.252368 -313.524191) (xy 107.215151 -313.565728)
			(xy 107.172283 -313.601403) (xy 107.124677 -313.630457) (xy 107.073348 -313.652269) (xy 107.019391 -313.666375)
			(xy 106.963954 -313.672475) (xy 106.90822 -313.670438) (xy 106.853377 -313.660308) (xy 106.800593 -313.642301)
			(xy 106.750993 -313.6168) (xy 106.705635 -313.584349) (xy 106.665486 -313.54564) (xy 106.6314 -313.501497)
			(xy 106.604104 -313.452862) (xy 106.584181 -313.400771) (xy 106.572055 -313.346334) (xy 106.567984 -313.290712)
			(xy 106.31551 -313.290712) (xy 106.315001 -313.318598) (xy 106.306881 -313.373774) (xy 106.290813 -313.427181)
			(xy 106.267141 -313.477678) (xy 106.236368 -313.524191) (xy 106.199151 -313.565728) (xy 106.156283 -313.601403)
			(xy 106.108677 -313.630457) (xy 106.057348 -313.652269) (xy 106.003391 -313.666375) (xy 105.947954 -313.672475)
			(xy 105.89222 -313.670438) (xy 105.837377 -313.660308) (xy 105.784593 -313.642301) (xy 105.734993 -313.6168)
			(xy 105.689635 -313.584349) (xy 105.649486 -313.54564) (xy 105.6154 -313.501497) (xy 105.588104 -313.452862)
			(xy 105.568181 -313.400771) (xy 105.556055 -313.346334) (xy 105.551984 -313.290712) (xy 105.29951 -313.290712)
			(xy 105.299001 -313.318598) (xy 105.290881 -313.373774) (xy 105.274813 -313.427181) (xy 105.251141 -313.477678)
			(xy 105.220368 -313.524191) (xy 105.183151 -313.565728) (xy 105.140283 -313.601403) (xy 105.092677 -313.630457)
			(xy 105.041348 -313.652269) (xy 104.987391 -313.666375) (xy 104.931954 -313.672475) (xy 104.87622 -313.670438)
			(xy 104.821377 -313.660308) (xy 104.768593 -313.642301) (xy 104.718993 -313.6168) (xy 104.673635 -313.584349)
			(xy 104.633486 -313.54564) (xy 104.5994 -313.501497) (xy 104.572104 -313.452862) (xy 104.552181 -313.400771)
			(xy 104.540055 -313.346334) (xy 104.535984 -313.290712) (xy 104.28351 -313.290712) (xy 104.283001 -313.318598)
			(xy 104.274881 -313.373774) (xy 104.258813 -313.427181) (xy 104.235141 -313.477678) (xy 104.204368 -313.524191)
			(xy 104.167151 -313.565728) (xy 104.124283 -313.601403) (xy 104.076677 -313.630457) (xy 104.025348 -313.652269)
			(xy 103.971391 -313.666375) (xy 103.915954 -313.672475) (xy 103.86022 -313.670438) (xy 103.805377 -313.660308)
			(xy 103.752593 -313.642301) (xy 103.702993 -313.6168) (xy 103.657635 -313.584349) (xy 103.617486 -313.54564)
			(xy 103.5834 -313.501497) (xy 103.556104 -313.452862) (xy 103.536181 -313.400771) (xy 103.524055 -313.346334)
			(xy 103.519984 -313.290712) (xy 103.26751 -313.290712) (xy 103.267001 -313.318598) (xy 103.258881 -313.373774)
			(xy 103.242813 -313.427181) (xy 103.219141 -313.477678) (xy 103.188368 -313.524191) (xy 103.151151 -313.565728)
			(xy 103.108283 -313.601403) (xy 103.060677 -313.630457) (xy 103.009348 -313.652269) (xy 102.955391 -313.666375)
			(xy 102.899954 -313.672475) (xy 102.84422 -313.670438) (xy 102.789377 -313.660308) (xy 102.736593 -313.642301)
			(xy 102.686993 -313.6168) (xy 102.641635 -313.584349) (xy 102.601486 -313.54564) (xy 102.5674 -313.501497)
			(xy 102.540104 -313.452862) (xy 102.520181 -313.400771) (xy 102.508055 -313.346334) (xy 102.503984 -313.290712)
			(xy 102.25151 -313.290712) (xy 102.251001 -313.318598) (xy 102.242881 -313.373774) (xy 102.226813 -313.427181)
			(xy 102.203141 -313.477678) (xy 102.172368 -313.524191) (xy 102.135151 -313.565728) (xy 102.092283 -313.601403)
			(xy 102.044677 -313.630457) (xy 101.993348 -313.652269) (xy 101.939391 -313.666375) (xy 101.883954 -313.672475)
			(xy 101.82822 -313.670438) (xy 101.773377 -313.660308) (xy 101.720593 -313.642301) (xy 101.670993 -313.6168)
			(xy 101.625635 -313.584349) (xy 101.585486 -313.54564) (xy 101.5514 -313.501497) (xy 101.524104 -313.452862)
			(xy 101.504181 -313.400771) (xy 101.492055 -313.346334) (xy 101.487984 -313.290712) (xy 101.23551 -313.290712)
			(xy 101.235001 -313.318598) (xy 101.226881 -313.373774) (xy 101.210813 -313.427181) (xy 101.187141 -313.477678)
			(xy 101.156368 -313.524191) (xy 101.119151 -313.565728) (xy 101.076283 -313.601403) (xy 101.028677 -313.630457)
			(xy 100.977348 -313.652269) (xy 100.923391 -313.666375) (xy 100.867954 -313.672475) (xy 100.81222 -313.670438)
			(xy 100.757377 -313.660308) (xy 100.704593 -313.642301) (xy 100.654993 -313.6168) (xy 100.609635 -313.584349)
			(xy 100.569486 -313.54564) (xy 100.5354 -313.501497) (xy 100.508104 -313.452862) (xy 100.488181 -313.400771)
			(xy 100.476055 -313.346334) (xy 100.471984 -313.290712) (xy 82.541454 -313.290712) (xy 82.511093 -313.299506)
			(xy 82.462238 -313.305438) (xy 82.413063 -313.303457) (xy 82.364844 -313.293613) (xy 82.318828 -313.276161)
			(xy 82.276207 -313.251554) (xy 82.238086 -313.220429) (xy 82.205451 -313.183592) (xy 82.179148 -313.141996)
			(xy 82.159857 -313.09672) (xy 82.14808 -313.048936) (xy 82.14412 -312.999882) (xy 81.805272 -312.999882)
			(xy 81.804777 -313.024489) (xy 81.796882 -313.073066) (xy 81.781298 -313.119747) (xy 81.758427 -313.163324)
			(xy 81.728862 -313.202668) (xy 81.693369 -313.23676) (xy 81.652866 -313.264716) (xy 81.608404 -313.285814)
			(xy 81.561133 -313.299506) (xy 81.512278 -313.305438) (xy 81.463103 -313.303457) (xy 81.414884 -313.293613)
			(xy 81.368868 -313.276161) (xy 81.326247 -313.251554) (xy 81.288126 -313.220429) (xy 81.255491 -313.183592)
			(xy 81.229188 -313.141996) (xy 81.209897 -313.09672) (xy 81.19812 -313.048936) (xy 81.19416 -312.999882)
			(xy 80.855058 -312.999882) (xy 80.854563 -313.024489) (xy 80.846668 -313.073066) (xy 80.831084 -313.119747)
			(xy 80.808213 -313.163324) (xy 80.778648 -313.202668) (xy 80.743155 -313.23676) (xy 80.702652 -313.264716)
			(xy 80.65819 -313.285814) (xy 80.610919 -313.299506) (xy 80.562064 -313.305438) (xy 80.512889 -313.303457)
			(xy 80.46467 -313.293613) (xy 80.418654 -313.276161) (xy 80.376033 -313.251554) (xy 80.337912 -313.220429)
			(xy 80.305277 -313.183592) (xy 80.278974 -313.141996) (xy 80.259683 -313.09672) (xy 80.247906 -313.048936)
			(xy 80.243946 -312.999882) (xy 79.905098 -312.999882) (xy 79.904603 -313.024489) (xy 79.896708 -313.073066)
			(xy 79.881124 -313.119747) (xy 79.858253 -313.163324) (xy 79.828688 -313.202668) (xy 79.793195 -313.23676)
			(xy 79.752692 -313.264716) (xy 79.70823 -313.285814) (xy 79.660959 -313.299506) (xy 79.612104 -313.305438)
			(xy 79.562929 -313.303457) (xy 79.51471 -313.293613) (xy 79.468694 -313.276161) (xy 79.426073 -313.251554)
			(xy 79.387952 -313.220429) (xy 79.355317 -313.183592) (xy 79.329014 -313.141996) (xy 79.309723 -313.09672)
			(xy 79.297946 -313.048936) (xy 79.293986 -312.999882) (xy 78.955138 -312.999882) (xy 78.954643 -313.024489)
			(xy 78.946748 -313.073066) (xy 78.931164 -313.119747) (xy 78.908293 -313.163324) (xy 78.878728 -313.202668)
			(xy 78.843235 -313.23676) (xy 78.802732 -313.264716) (xy 78.75827 -313.285814) (xy 78.710999 -313.299506)
			(xy 78.662144 -313.305438) (xy 78.612969 -313.303457) (xy 78.56475 -313.293613) (xy 78.518734 -313.276161)
			(xy 78.476113 -313.251554) (xy 78.437992 -313.220429) (xy 78.405357 -313.183592) (xy 78.379054 -313.141996)
			(xy 78.359763 -313.09672) (xy 78.347986 -313.048936) (xy 78.344026 -312.999882) (xy 78.005178 -312.999882)
			(xy 78.004683 -313.024489) (xy 77.996788 -313.073066) (xy 77.981204 -313.119747) (xy 77.958333 -313.163324)
			(xy 77.928768 -313.202668) (xy 77.893275 -313.23676) (xy 77.852772 -313.264716) (xy 77.80831 -313.285814)
			(xy 77.761039 -313.299506) (xy 77.712184 -313.305438) (xy 77.663009 -313.303457) (xy 77.61479 -313.293613)
			(xy 77.568774 -313.276161) (xy 77.526153 -313.251554) (xy 77.488032 -313.220429) (xy 77.455397 -313.183592)
			(xy 77.429094 -313.141996) (xy 77.409803 -313.09672) (xy 77.398026 -313.048936) (xy 77.394066 -312.999882)
			(xy 77.055218 -312.999882) (xy 77.054723 -313.024489) (xy 77.046828 -313.073066) (xy 77.031244 -313.119747)
			(xy 77.008373 -313.163324) (xy 76.978808 -313.202668) (xy 76.943315 -313.23676) (xy 76.902812 -313.264716)
			(xy 76.85835 -313.285814) (xy 76.811079 -313.299506) (xy 76.762224 -313.305438) (xy 76.713049 -313.303457)
			(xy 76.66483 -313.293613) (xy 76.618814 -313.276161) (xy 76.576193 -313.251554) (xy 76.538072 -313.220429)
			(xy 76.505437 -313.183592) (xy 76.479134 -313.141996) (xy 76.459843 -313.09672) (xy 76.448066 -313.048936)
			(xy 76.444106 -312.999882) (xy 76.105258 -312.999882) (xy 76.104763 -313.024489) (xy 76.096868 -313.073066)
			(xy 76.081284 -313.119747) (xy 76.058413 -313.163324) (xy 76.028848 -313.202668) (xy 75.993355 -313.23676)
			(xy 75.952852 -313.264716) (xy 75.90839 -313.285814) (xy 75.861119 -313.299506) (xy 75.812264 -313.305438)
			(xy 75.763089 -313.303457) (xy 75.71487 -313.293613) (xy 75.668854 -313.276161) (xy 75.626233 -313.251554)
			(xy 75.588112 -313.220429) (xy 75.555477 -313.183592) (xy 75.529174 -313.141996) (xy 75.509883 -313.09672)
			(xy 75.498106 -313.048936) (xy 75.494146 -312.999882) (xy 75.155298 -312.999882) (xy 75.154803 -313.024489)
			(xy 75.146908 -313.073066) (xy 75.131324 -313.119747) (xy 75.108453 -313.163324) (xy 75.078888 -313.202668)
			(xy 75.043395 -313.23676) (xy 75.002892 -313.264716) (xy 74.95843 -313.285814) (xy 74.911159 -313.299506)
			(xy 74.862304 -313.305438) (xy 74.813129 -313.303457) (xy 74.76491 -313.293613) (xy 74.718894 -313.276161)
			(xy 74.676273 -313.251554) (xy 74.638152 -313.220429) (xy 74.605517 -313.183592) (xy 74.579214 -313.141996)
			(xy 74.559923 -313.09672) (xy 74.548146 -313.048936) (xy 74.544186 -312.999882) (xy 74.205084 -312.999882)
			(xy 74.204589 -313.024489) (xy 74.196694 -313.073066) (xy 74.18111 -313.119747) (xy 74.158239 -313.163324)
			(xy 74.128674 -313.202668) (xy 74.093181 -313.23676) (xy 74.052678 -313.264716) (xy 74.008216 -313.285814)
			(xy 73.960945 -313.299506) (xy 73.91209 -313.305438) (xy 73.862915 -313.303457) (xy 73.814696 -313.293613)
			(xy 73.76868 -313.276161) (xy 73.726059 -313.251554) (xy 73.687938 -313.220429) (xy 73.655303 -313.183592)
			(xy 73.629 -313.141996) (xy 73.609709 -313.09672) (xy 73.597932 -313.048936) (xy 73.593972 -312.999882)
			(xy 73.276968 -312.999882) (xy 73.276464 -313.02559) (xy 73.268421 -313.076372) (xy 73.252533 -313.125271)
			(xy 73.22919 -313.171083) (xy 73.198969 -313.212679) (xy 73.162613 -313.249035) (xy 73.121017 -313.279256)
			(xy 73.075205 -313.302599) (xy 73.026306 -313.318487) (xy 72.975524 -313.32653) (xy 72.924108 -313.32653)
			(xy 72.873326 -313.318487) (xy 72.824427 -313.302599) (xy 72.778615 -313.279256) (xy 72.737019 -313.249035)
			(xy 72.700663 -313.212679) (xy 72.670442 -313.171083) (xy 72.647099 -313.125271) (xy 72.631211 -313.076372)
			(xy 72.623168 -313.02559) (xy 72.30449 -313.02559) (xy 72.296774 -313.073066) (xy 72.28119 -313.119747)
			(xy 72.258319 -313.163324) (xy 72.228754 -313.202668) (xy 72.193261 -313.23676) (xy 72.152758 -313.264716)
			(xy 72.108296 -313.285814) (xy 72.061025 -313.299506) (xy 72.01217 -313.305438) (xy 71.962995 -313.303457)
			(xy 71.914776 -313.293613) (xy 71.86876 -313.276161) (xy 71.826139 -313.251554) (xy 71.788018 -313.220429)
			(xy 71.755383 -313.183592) (xy 71.72908 -313.141996) (xy 71.709789 -313.09672) (xy 71.698012 -313.048936)
			(xy 71.694052 -312.999882) (xy 71.377048 -312.999882) (xy 71.376544 -313.02559) (xy 71.368501 -313.076372)
			(xy 71.352613 -313.125271) (xy 71.32927 -313.171083) (xy 71.299049 -313.212679) (xy 71.262693 -313.249035)
			(xy 71.221097 -313.279256) (xy 71.175285 -313.302599) (xy 71.126386 -313.318487) (xy 71.075604 -313.32653)
			(xy 71.024188 -313.32653) (xy 70.973406 -313.318487) (xy 70.924507 -313.302599) (xy 70.878695 -313.279256)
			(xy 70.837099 -313.249035) (xy 70.800743 -313.212679) (xy 70.770522 -313.171083) (xy 70.747179 -313.125271)
			(xy 70.731291 -313.076372) (xy 70.723248 -313.02559) (xy 70.40457 -313.02559) (xy 70.396854 -313.073066)
			(xy 70.38127 -313.119747) (xy 70.358399 -313.163324) (xy 70.328834 -313.202668) (xy 70.293341 -313.23676)
			(xy 70.252838 -313.264716) (xy 70.208376 -313.285814) (xy 70.161105 -313.299506) (xy 70.11225 -313.305438)
			(xy 70.063075 -313.303457) (xy 70.014856 -313.293613) (xy 69.96884 -313.276161) (xy 69.926219 -313.251554)
			(xy 69.888098 -313.220429) (xy 69.855463 -313.183592) (xy 69.82916 -313.141996) (xy 69.809869 -313.09672)
			(xy 69.798092 -313.048936) (xy 69.794132 -312.999882) (xy 69.477128 -312.999882) (xy 69.476624 -313.02559)
			(xy 69.468581 -313.076372) (xy 69.452693 -313.125271) (xy 69.42935 -313.171083) (xy 69.399129 -313.212679)
			(xy 69.362773 -313.249035) (xy 69.321177 -313.279256) (xy 69.275365 -313.302599) (xy 69.226466 -313.318487)
			(xy 69.175684 -313.32653) (xy 69.124268 -313.32653) (xy 69.073486 -313.318487) (xy 69.024587 -313.302599)
			(xy 68.978775 -313.279256) (xy 68.937179 -313.249035) (xy 68.900823 -313.212679) (xy 68.870602 -313.171083)
			(xy 68.847259 -313.125271) (xy 68.831371 -313.076372) (xy 68.823328 -313.02559) (xy 68.504396 -313.02559)
			(xy 68.49668 -313.073066) (xy 68.481096 -313.119747) (xy 68.458225 -313.163324) (xy 68.42866 -313.202668)
			(xy 68.393167 -313.23676) (xy 68.352664 -313.264716) (xy 68.308202 -313.285814) (xy 68.260931 -313.299506)
			(xy 68.212076 -313.305438) (xy 68.162901 -313.303457) (xy 68.114682 -313.293613) (xy 68.068666 -313.276161)
			(xy 68.026045 -313.251554) (xy 67.987924 -313.220429) (xy 67.955289 -313.183592) (xy 67.928986 -313.141996)
			(xy 67.909695 -313.09672) (xy 67.897918 -313.048936) (xy 67.893958 -312.999882) (xy 67.576954 -312.999882)
			(xy 67.57645 -313.02559) (xy 67.568407 -313.076372) (xy 67.552519 -313.125271) (xy 67.529176 -313.171083)
			(xy 67.498955 -313.212679) (xy 67.462599 -313.249035) (xy 67.421003 -313.279256) (xy 67.375191 -313.302599)
			(xy 67.326292 -313.318487) (xy 67.27551 -313.32653) (xy 67.224094 -313.32653) (xy 67.173312 -313.318487)
			(xy 67.124413 -313.302599) (xy 67.078601 -313.279256) (xy 67.037005 -313.249035) (xy 67.000649 -313.212679)
			(xy 66.970428 -313.171083) (xy 66.947085 -313.125271) (xy 66.931197 -313.076372) (xy 66.923154 -313.02559)
			(xy 66.604476 -313.02559) (xy 66.59676 -313.073066) (xy 66.581176 -313.119747) (xy 66.558305 -313.163324)
			(xy 66.52874 -313.202668) (xy 66.493247 -313.23676) (xy 66.452744 -313.264716) (xy 66.408282 -313.285814)
			(xy 66.361011 -313.299506) (xy 66.312156 -313.305438) (xy 66.262981 -313.303457) (xy 66.214762 -313.293613)
			(xy 66.168746 -313.276161) (xy 66.126125 -313.251554) (xy 66.088004 -313.220429) (xy 66.055369 -313.183592)
			(xy 66.029066 -313.141996) (xy 66.009775 -313.09672) (xy 65.997998 -313.048936) (xy 65.994038 -312.999882)
			(xy 65.677034 -312.999882) (xy 65.67653 -313.02559) (xy 65.668487 -313.076372) (xy 65.652599 -313.125271)
			(xy 65.629256 -313.171083) (xy 65.599035 -313.212679) (xy 65.562679 -313.249035) (xy 65.521083 -313.279256)
			(xy 65.475271 -313.302599) (xy 65.426372 -313.318487) (xy 65.37559 -313.32653) (xy 65.324174 -313.32653)
			(xy 65.273392 -313.318487) (xy 65.224493 -313.302599) (xy 65.178681 -313.279256) (xy 65.137085 -313.249035)
			(xy 65.100729 -313.212679) (xy 65.070508 -313.171083) (xy 65.047165 -313.125271) (xy 65.031277 -313.076372)
			(xy 65.023234 -313.02559) (xy 64.704556 -313.02559) (xy 64.69684 -313.073066) (xy 64.681256 -313.119747)
			(xy 64.658385 -313.163324) (xy 64.62882 -313.202668) (xy 64.593327 -313.23676) (xy 64.552824 -313.264716)
			(xy 64.508362 -313.285814) (xy 64.461091 -313.299506) (xy 64.412236 -313.305438) (xy 64.363061 -313.303457)
			(xy 64.314842 -313.293613) (xy 64.268826 -313.276161) (xy 64.226205 -313.251554) (xy 64.188084 -313.220429)
			(xy 64.155449 -313.183592) (xy 64.129146 -313.141996) (xy 64.109855 -313.09672) (xy 64.098078 -313.048936)
			(xy 64.094118 -312.999882) (xy 63.777114 -312.999882) (xy 63.77661 -313.02559) (xy 63.768567 -313.076372)
			(xy 63.752679 -313.125271) (xy 63.729336 -313.171083) (xy 63.699115 -313.212679) (xy 63.662759 -313.249035)
			(xy 63.621163 -313.279256) (xy 63.575351 -313.302599) (xy 63.526452 -313.318487) (xy 63.47567 -313.32653)
			(xy 63.424254 -313.32653) (xy 63.373472 -313.318487) (xy 63.324573 -313.302599) (xy 63.278761 -313.279256)
			(xy 63.237165 -313.249035) (xy 63.200809 -313.212679) (xy 63.170588 -313.171083) (xy 63.147245 -313.125271)
			(xy 63.131357 -313.076372) (xy 63.123314 -313.02559) (xy 62.804382 -313.02559) (xy 62.796666 -313.073066)
			(xy 62.781082 -313.119747) (xy 62.758211 -313.163324) (xy 62.728646 -313.202668) (xy 62.693153 -313.23676)
			(xy 62.65265 -313.264716) (xy 62.608188 -313.285814) (xy 62.560917 -313.299506) (xy 62.512062 -313.305438)
			(xy 62.462887 -313.303457) (xy 62.414668 -313.293613) (xy 62.368652 -313.276161) (xy 62.326031 -313.251554)
			(xy 62.28791 -313.220429) (xy 62.255275 -313.183592) (xy 62.228972 -313.141996) (xy 62.209681 -313.09672)
			(xy 62.197904 -313.048936) (xy 62.193944 -312.999882) (xy 61.87694 -312.999882) (xy 61.876436 -313.02559)
			(xy 61.868393 -313.076372) (xy 61.852505 -313.125271) (xy 61.829162 -313.171083) (xy 61.798941 -313.212679)
			(xy 61.762585 -313.249035) (xy 61.720989 -313.279256) (xy 61.675177 -313.302599) (xy 61.626278 -313.318487)
			(xy 61.575496 -313.32653) (xy 61.52408 -313.32653) (xy 61.473298 -313.318487) (xy 61.424399 -313.302599)
			(xy 61.378587 -313.279256) (xy 61.336991 -313.249035) (xy 61.300635 -313.212679) (xy 61.270414 -313.171083)
			(xy 61.247071 -313.125271) (xy 61.231183 -313.076372) (xy 61.22314 -313.02559) (xy 60.904462 -313.02559)
			(xy 60.896746 -313.073066) (xy 60.881162 -313.119747) (xy 60.858291 -313.163324) (xy 60.828726 -313.202668)
			(xy 60.793233 -313.23676) (xy 60.75273 -313.264716) (xy 60.708268 -313.285814) (xy 60.660997 -313.299506)
			(xy 60.612142 -313.305438) (xy 60.562967 -313.303457) (xy 60.514748 -313.293613) (xy 60.468732 -313.276161)
			(xy 60.426111 -313.251554) (xy 60.38799 -313.220429) (xy 60.355355 -313.183592) (xy 60.329052 -313.141996)
			(xy 60.309761 -313.09672) (xy 60.297984 -313.048936) (xy 60.294024 -312.999882) (xy 59.97702 -312.999882)
			(xy 59.976516 -313.02559) (xy 59.968473 -313.076372) (xy 59.952585 -313.125271) (xy 59.929242 -313.171083)
			(xy 59.899021 -313.212679) (xy 59.862665 -313.249035) (xy 59.821069 -313.279256) (xy 59.775257 -313.302599)
			(xy 59.726358 -313.318487) (xy 59.675576 -313.32653) (xy 59.62416 -313.32653) (xy 59.573378 -313.318487)
			(xy 59.524479 -313.302599) (xy 59.478667 -313.279256) (xy 59.437071 -313.249035) (xy 59.400715 -313.212679)
			(xy 59.370494 -313.171083) (xy 59.347151 -313.125271) (xy 59.331263 -313.076372) (xy 59.32322 -313.02559)
			(xy 59.004542 -313.02559) (xy 58.996826 -313.073066) (xy 58.981242 -313.119747) (xy 58.958371 -313.163324)
			(xy 58.928806 -313.202668) (xy 58.893313 -313.23676) (xy 58.85281 -313.264716) (xy 58.808348 -313.285814)
			(xy 58.761077 -313.299506) (xy 58.712222 -313.305438) (xy 58.663047 -313.303457) (xy 58.614828 -313.293613)
			(xy 58.568812 -313.276161) (xy 58.526191 -313.251554) (xy 58.48807 -313.220429) (xy 58.455435 -313.183592)
			(xy 58.429132 -313.141996) (xy 58.409841 -313.09672) (xy 58.398064 -313.048936) (xy 58.394104 -312.999882)
			(xy 58.055123 -312.999882) (xy 58.055572 -313.008154) (xy 58.05021 -313.057495) (xy 58.036937 -313.105319)
			(xy 58.016102 -313.150366) (xy 57.988254 -313.191448) (xy 57.954126 -313.227485) (xy 57.914619 -313.257526)
			(xy 57.870772 -313.280779) (xy 57.82374 -313.296634) (xy 57.774764 -313.30467) (xy 57.749948 -313.30519)
			(xy 57.740847 -313.305152) (xy 57.722674 -313.304138) (xy 57.713626 -313.303158) (xy 57.701688 -313.301634)
			(xy 57.679336 -313.309508) (xy 57.606438 -313.385962) (xy 57.599326 -313.408568) (xy 57.601358 -313.420506)
			(xy 57.603489 -313.433994) (xy 57.605782 -313.461207) (xy 57.60593 -313.474862) (xy 57.60593 -313.54522)
			(xy 57.606394 -313.555876) (xy 57.615085 -313.575335) (xy 57.622694 -313.582812) (xy 57.686956 -313.640724)
			(xy 57.707276 -313.647328) (xy 57.718198 -313.646312) (xy 57.749948 -313.644534) (xy 57.775197 -313.645059)
			(xy 57.825006 -313.653378) (xy 57.872766 -313.669781) (xy 57.917176 -313.69382) (xy 57.957024 -313.724841)
			(xy 57.991223 -313.761996) (xy 58.018841 -313.804274) (xy 58.039124 -313.85052) (xy 58.051519 -313.899474)
			(xy 58.055689 -313.9498) (xy 58.055686 -313.949842) (xy 58.394104 -313.949842) (xy 58.398064 -313.900788)
			(xy 58.409841 -313.853004) (xy 58.429132 -313.807728) (xy 58.455435 -313.766132) (xy 58.48807 -313.729295)
			(xy 58.526191 -313.69817) (xy 58.568812 -313.673563) (xy 58.614828 -313.656111) (xy 58.663047 -313.646267)
			(xy 58.712222 -313.644286) (xy 58.761077 -313.650218) (xy 58.808348 -313.66391) (xy 58.85281 -313.685008)
			(xy 58.893313 -313.712964) (xy 58.928806 -313.747056) (xy 58.958371 -313.7864) (xy 58.981242 -313.829977)
			(xy 58.996826 -313.876658) (xy 59.004721 -313.925235) (xy 59.005216 -313.949842) (xy 59.004721 -313.974449)
			(xy 59.004542 -313.97555) (xy 59.32322 -313.97555) (xy 59.32322 -313.924134) (xy 59.331263 -313.873352)
			(xy 59.347151 -313.824453) (xy 59.370494 -313.778641) (xy 59.400715 -313.737045) (xy 59.437071 -313.700689)
			(xy 59.478667 -313.670468) (xy 59.524479 -313.647125) (xy 59.573378 -313.631237) (xy 59.62416 -313.623194)
			(xy 59.675576 -313.623194) (xy 59.726358 -313.631237) (xy 59.775257 -313.647125) (xy 59.821069 -313.670468)
			(xy 59.862665 -313.700689) (xy 59.899021 -313.737045) (xy 59.929242 -313.778641) (xy 59.952585 -313.824453)
			(xy 59.968473 -313.873352) (xy 59.976516 -313.924134) (xy 59.97702 -313.949842) (xy 60.294024 -313.949842)
			(xy 60.297984 -313.900788) (xy 60.309761 -313.853004) (xy 60.329052 -313.807728) (xy 60.355355 -313.766132)
			(xy 60.38799 -313.729295) (xy 60.426111 -313.69817) (xy 60.468732 -313.673563) (xy 60.514748 -313.656111)
			(xy 60.562967 -313.646267) (xy 60.612142 -313.644286) (xy 60.660997 -313.650218) (xy 60.708268 -313.66391)
			(xy 60.75273 -313.685008) (xy 60.793233 -313.712964) (xy 60.828726 -313.747056) (xy 60.858291 -313.7864)
			(xy 60.881162 -313.829977) (xy 60.896746 -313.876658) (xy 60.904641 -313.925235) (xy 60.905136 -313.949842)
			(xy 60.904641 -313.974449) (xy 60.904462 -313.97555) (xy 61.22314 -313.97555) (xy 61.22314 -313.924134)
			(xy 61.231183 -313.873352) (xy 61.247071 -313.824453) (xy 61.270414 -313.778641) (xy 61.300635 -313.737045)
			(xy 61.336991 -313.700689) (xy 61.378587 -313.670468) (xy 61.424399 -313.647125) (xy 61.473298 -313.631237)
			(xy 61.52408 -313.623194) (xy 61.575496 -313.623194) (xy 61.626278 -313.631237) (xy 61.675177 -313.647125)
			(xy 61.720989 -313.670468) (xy 61.762585 -313.700689) (xy 61.798941 -313.737045) (xy 61.829162 -313.778641)
			(xy 61.852505 -313.824453) (xy 61.868393 -313.873352) (xy 61.876436 -313.924134) (xy 61.87694 -313.949842)
			(xy 62.193944 -313.949842) (xy 62.197904 -313.900788) (xy 62.209681 -313.853004) (xy 62.228972 -313.807728)
			(xy 62.255275 -313.766132) (xy 62.28791 -313.729295) (xy 62.326031 -313.69817) (xy 62.368652 -313.673563)
			(xy 62.414668 -313.656111) (xy 62.462887 -313.646267) (xy 62.512062 -313.644286) (xy 62.560917 -313.650218)
			(xy 62.608188 -313.66391) (xy 62.65265 -313.685008) (xy 62.693153 -313.712964) (xy 62.728646 -313.747056)
			(xy 62.758211 -313.7864) (xy 62.781082 -313.829977) (xy 62.796666 -313.876658) (xy 62.804561 -313.925235)
			(xy 62.805056 -313.949842) (xy 62.804561 -313.974449) (xy 62.804382 -313.97555) (xy 63.123314 -313.97555)
			(xy 63.123314 -313.924134) (xy 63.131357 -313.873352) (xy 63.147245 -313.824453) (xy 63.170588 -313.778641)
			(xy 63.200809 -313.737045) (xy 63.237165 -313.700689) (xy 63.278761 -313.670468) (xy 63.324573 -313.647125)
			(xy 63.373472 -313.631237) (xy 63.424254 -313.623194) (xy 63.47567 -313.623194) (xy 63.526452 -313.631237)
			(xy 63.575351 -313.647125) (xy 63.621163 -313.670468) (xy 63.662759 -313.700689) (xy 63.699115 -313.737045)
			(xy 63.729336 -313.778641) (xy 63.752679 -313.824453) (xy 63.768567 -313.873352) (xy 63.77661 -313.924134)
			(xy 63.777114 -313.949842) (xy 64.094118 -313.949842) (xy 64.098078 -313.900788) (xy 64.109855 -313.853004)
			(xy 64.129146 -313.807728) (xy 64.155449 -313.766132) (xy 64.188084 -313.729295) (xy 64.226205 -313.69817)
			(xy 64.268826 -313.673563) (xy 64.314842 -313.656111) (xy 64.363061 -313.646267) (xy 64.412236 -313.644286)
			(xy 64.461091 -313.650218) (xy 64.508362 -313.66391) (xy 64.552824 -313.685008) (xy 64.593327 -313.712964)
			(xy 64.62882 -313.747056) (xy 64.658385 -313.7864) (xy 64.681256 -313.829977) (xy 64.69684 -313.876658)
			(xy 64.704735 -313.925235) (xy 64.70523 -313.949842) (xy 64.704735 -313.974449) (xy 64.704556 -313.97555)
			(xy 65.023234 -313.97555) (xy 65.023234 -313.924134) (xy 65.031277 -313.873352) (xy 65.047165 -313.824453)
			(xy 65.070508 -313.778641) (xy 65.100729 -313.737045) (xy 65.137085 -313.700689) (xy 65.178681 -313.670468)
			(xy 65.224493 -313.647125) (xy 65.273392 -313.631237) (xy 65.324174 -313.623194) (xy 65.37559 -313.623194)
			(xy 65.426372 -313.631237) (xy 65.475271 -313.647125) (xy 65.521083 -313.670468) (xy 65.562679 -313.700689)
			(xy 65.599035 -313.737045) (xy 65.629256 -313.778641) (xy 65.652599 -313.824453) (xy 65.668487 -313.873352)
			(xy 65.67653 -313.924134) (xy 65.677034 -313.949842) (xy 65.994038 -313.949842) (xy 65.997998 -313.900788)
			(xy 66.009775 -313.853004) (xy 66.029066 -313.807728) (xy 66.055369 -313.766132) (xy 66.088004 -313.729295)
			(xy 66.126125 -313.69817) (xy 66.168746 -313.673563) (xy 66.214762 -313.656111) (xy 66.262981 -313.646267)
			(xy 66.312156 -313.644286) (xy 66.361011 -313.650218) (xy 66.408282 -313.66391) (xy 66.452744 -313.685008)
			(xy 66.493247 -313.712964) (xy 66.52874 -313.747056) (xy 66.558305 -313.7864) (xy 66.581176 -313.829977)
			(xy 66.59676 -313.876658) (xy 66.604655 -313.925235) (xy 66.60515 -313.949842) (xy 66.604655 -313.974449)
			(xy 66.604476 -313.97555) (xy 66.923154 -313.97555) (xy 66.923154 -313.924134) (xy 66.931197 -313.873352)
			(xy 66.947085 -313.824453) (xy 66.970428 -313.778641) (xy 67.000649 -313.737045) (xy 67.037005 -313.700689)
			(xy 67.078601 -313.670468) (xy 67.124413 -313.647125) (xy 67.173312 -313.631237) (xy 67.224094 -313.623194)
			(xy 67.27551 -313.623194) (xy 67.326292 -313.631237) (xy 67.375191 -313.647125) (xy 67.421003 -313.670468)
			(xy 67.462599 -313.700689) (xy 67.498955 -313.737045) (xy 67.529176 -313.778641) (xy 67.552519 -313.824453)
			(xy 67.568407 -313.873352) (xy 67.57645 -313.924134) (xy 67.576954 -313.949842) (xy 67.893958 -313.949842)
			(xy 67.897918 -313.900788) (xy 67.909695 -313.853004) (xy 67.928986 -313.807728) (xy 67.955289 -313.766132)
			(xy 67.987924 -313.729295) (xy 68.026045 -313.69817) (xy 68.068666 -313.673563) (xy 68.114682 -313.656111)
			(xy 68.162901 -313.646267) (xy 68.212076 -313.644286) (xy 68.260931 -313.650218) (xy 68.308202 -313.66391)
			(xy 68.352664 -313.685008) (xy 68.393167 -313.712964) (xy 68.42866 -313.747056) (xy 68.458225 -313.7864)
			(xy 68.481096 -313.829977) (xy 68.49668 -313.876658) (xy 68.504575 -313.925235) (xy 68.50507 -313.949842)
			(xy 68.504575 -313.974449) (xy 68.504396 -313.97555) (xy 68.823328 -313.97555) (xy 68.823328 -313.924134)
			(xy 68.831371 -313.873352) (xy 68.847259 -313.824453) (xy 68.870602 -313.778641) (xy 68.900823 -313.737045)
			(xy 68.937179 -313.700689) (xy 68.978775 -313.670468) (xy 69.024587 -313.647125) (xy 69.073486 -313.631237)
			(xy 69.124268 -313.623194) (xy 69.175684 -313.623194) (xy 69.226466 -313.631237) (xy 69.275365 -313.647125)
			(xy 69.321177 -313.670468) (xy 69.362773 -313.700689) (xy 69.399129 -313.737045) (xy 69.42935 -313.778641)
			(xy 69.452693 -313.824453) (xy 69.468581 -313.873352) (xy 69.476624 -313.924134) (xy 69.477128 -313.949842)
			(xy 69.794132 -313.949842) (xy 69.798092 -313.900788) (xy 69.809869 -313.853004) (xy 69.82916 -313.807728)
			(xy 69.855463 -313.766132) (xy 69.888098 -313.729295) (xy 69.926219 -313.69817) (xy 69.96884 -313.673563)
			(xy 70.014856 -313.656111) (xy 70.063075 -313.646267) (xy 70.11225 -313.644286) (xy 70.161105 -313.650218)
			(xy 70.208376 -313.66391) (xy 70.252838 -313.685008) (xy 70.293341 -313.712964) (xy 70.328834 -313.747056)
			(xy 70.358399 -313.7864) (xy 70.38127 -313.829977) (xy 70.396854 -313.876658) (xy 70.404749 -313.925235)
			(xy 70.405244 -313.949842) (xy 70.404749 -313.974449) (xy 70.40457 -313.97555) (xy 70.723248 -313.97555)
			(xy 70.723248 -313.924134) (xy 70.731291 -313.873352) (xy 70.747179 -313.824453) (xy 70.770522 -313.778641)
			(xy 70.800743 -313.737045) (xy 70.837099 -313.700689) (xy 70.878695 -313.670468) (xy 70.924507 -313.647125)
			(xy 70.973406 -313.631237) (xy 71.024188 -313.623194) (xy 71.075604 -313.623194) (xy 71.126386 -313.631237)
			(xy 71.175285 -313.647125) (xy 71.221097 -313.670468) (xy 71.262693 -313.700689) (xy 71.299049 -313.737045)
			(xy 71.32927 -313.778641) (xy 71.352613 -313.824453) (xy 71.368501 -313.873352) (xy 71.376544 -313.924134)
			(xy 71.377048 -313.949842) (xy 71.694052 -313.949842) (xy 71.698012 -313.900788) (xy 71.709789 -313.853004)
			(xy 71.72908 -313.807728) (xy 71.755383 -313.766132) (xy 71.788018 -313.729295) (xy 71.826139 -313.69817)
			(xy 71.86876 -313.673563) (xy 71.914776 -313.656111) (xy 71.962995 -313.646267) (xy 72.01217 -313.644286)
			(xy 72.061025 -313.650218) (xy 72.108296 -313.66391) (xy 72.152758 -313.685008) (xy 72.193261 -313.712964)
			(xy 72.228754 -313.747056) (xy 72.258319 -313.7864) (xy 72.28119 -313.829977) (xy 72.296774 -313.876658)
			(xy 72.304669 -313.925235) (xy 72.305164 -313.949842) (xy 72.304669 -313.974449) (xy 72.30449 -313.97555)
			(xy 72.623168 -313.97555) (xy 72.623168 -313.924134) (xy 72.631211 -313.873352) (xy 72.647099 -313.824453)
			(xy 72.670442 -313.778641) (xy 72.700663 -313.737045) (xy 72.737019 -313.700689) (xy 72.778615 -313.670468)
			(xy 72.824427 -313.647125) (xy 72.873326 -313.631237) (xy 72.924108 -313.623194) (xy 72.975524 -313.623194)
			(xy 73.026306 -313.631237) (xy 73.075205 -313.647125) (xy 73.121017 -313.670468) (xy 73.162613 -313.700689)
			(xy 73.198969 -313.737045) (xy 73.22919 -313.778641) (xy 73.252533 -313.824453) (xy 73.268421 -313.873352)
			(xy 73.276464 -313.924134) (xy 73.276968 -313.949842) (xy 73.593972 -313.949842) (xy 73.597932 -313.900788)
			(xy 73.609709 -313.853004) (xy 73.629 -313.807728) (xy 73.655303 -313.766132) (xy 73.687938 -313.729295)
			(xy 73.726059 -313.69817) (xy 73.76868 -313.673563) (xy 73.814696 -313.656111) (xy 73.862915 -313.646267)
			(xy 73.91209 -313.644286) (xy 73.960945 -313.650218) (xy 74.008216 -313.66391) (xy 74.052678 -313.685008)
			(xy 74.093181 -313.712964) (xy 74.128674 -313.747056) (xy 74.158239 -313.7864) (xy 74.18111 -313.829977)
			(xy 74.196694 -313.876658) (xy 74.204589 -313.925235) (xy 74.205084 -313.949842) (xy 74.544186 -313.949842)
			(xy 74.548146 -313.900788) (xy 74.559923 -313.853004) (xy 74.579214 -313.807728) (xy 74.605517 -313.766132)
			(xy 74.638152 -313.729295) (xy 74.676273 -313.69817) (xy 74.718894 -313.673563) (xy 74.76491 -313.656111)
			(xy 74.813129 -313.646267) (xy 74.862304 -313.644286) (xy 74.911159 -313.650218) (xy 74.95843 -313.66391)
			(xy 75.002892 -313.685008) (xy 75.043395 -313.712964) (xy 75.078888 -313.747056) (xy 75.108453 -313.7864)
			(xy 75.131324 -313.829977) (xy 75.146908 -313.876658) (xy 75.154803 -313.925235) (xy 75.155298 -313.949842)
			(xy 75.494146 -313.949842) (xy 75.498106 -313.900788) (xy 75.509883 -313.853004) (xy 75.529174 -313.807728)
			(xy 75.555477 -313.766132) (xy 75.588112 -313.729295) (xy 75.626233 -313.69817) (xy 75.668854 -313.673563)
			(xy 75.71487 -313.656111) (xy 75.763089 -313.646267) (xy 75.812264 -313.644286) (xy 75.861119 -313.650218)
			(xy 75.90839 -313.66391) (xy 75.952852 -313.685008) (xy 75.993355 -313.712964) (xy 76.028848 -313.747056)
			(xy 76.058413 -313.7864) (xy 76.081284 -313.829977) (xy 76.096868 -313.876658) (xy 76.104763 -313.925235)
			(xy 76.105258 -313.949842) (xy 76.444106 -313.949842) (xy 76.448066 -313.900788) (xy 76.459843 -313.853004)
			(xy 76.479134 -313.807728) (xy 76.505437 -313.766132) (xy 76.538072 -313.729295) (xy 76.576193 -313.69817)
			(xy 76.618814 -313.673563) (xy 76.66483 -313.656111) (xy 76.713049 -313.646267) (xy 76.762224 -313.644286)
			(xy 76.811079 -313.650218) (xy 76.85835 -313.66391) (xy 76.902812 -313.685008) (xy 76.943315 -313.712964)
			(xy 76.978808 -313.747056) (xy 77.008373 -313.7864) (xy 77.031244 -313.829977) (xy 77.046828 -313.876658)
			(xy 77.054723 -313.925235) (xy 77.055218 -313.949842) (xy 77.394066 -313.949842) (xy 77.398026 -313.900788)
			(xy 77.409803 -313.853004) (xy 77.429094 -313.807728) (xy 77.455397 -313.766132) (xy 77.488032 -313.729295)
			(xy 77.526153 -313.69817) (xy 77.568774 -313.673563) (xy 77.61479 -313.656111) (xy 77.663009 -313.646267)
			(xy 77.712184 -313.644286) (xy 77.761039 -313.650218) (xy 77.80831 -313.66391) (xy 77.852772 -313.685008)
			(xy 77.893275 -313.712964) (xy 77.928768 -313.747056) (xy 77.958333 -313.7864) (xy 77.981204 -313.829977)
			(xy 77.996788 -313.876658) (xy 78.004683 -313.925235) (xy 78.005178 -313.949842) (xy 78.344026 -313.949842)
			(xy 78.347986 -313.900788) (xy 78.359763 -313.853004) (xy 78.379054 -313.807728) (xy 78.405357 -313.766132)
			(xy 78.437992 -313.729295) (xy 78.476113 -313.69817) (xy 78.518734 -313.673563) (xy 78.56475 -313.656111)
			(xy 78.612969 -313.646267) (xy 78.662144 -313.644286) (xy 78.710999 -313.650218) (xy 78.75827 -313.66391)
			(xy 78.802732 -313.685008) (xy 78.843235 -313.712964) (xy 78.878728 -313.747056) (xy 78.908293 -313.7864)
			(xy 78.931164 -313.829977) (xy 78.946748 -313.876658) (xy 78.954643 -313.925235) (xy 78.955138 -313.949842)
			(xy 79.293986 -313.949842) (xy 79.297946 -313.900788) (xy 79.309723 -313.853004) (xy 79.329014 -313.807728)
			(xy 79.355317 -313.766132) (xy 79.387952 -313.729295) (xy 79.426073 -313.69817) (xy 79.468694 -313.673563)
			(xy 79.51471 -313.656111) (xy 79.562929 -313.646267) (xy 79.612104 -313.644286) (xy 79.660959 -313.650218)
			(xy 79.70823 -313.66391) (xy 79.752692 -313.685008) (xy 79.793195 -313.712964) (xy 79.828688 -313.747056)
			(xy 79.858253 -313.7864) (xy 79.881124 -313.829977) (xy 79.896708 -313.876658) (xy 79.904603 -313.925235)
			(xy 79.905098 -313.949842) (xy 80.243946 -313.949842) (xy 80.247906 -313.900788) (xy 80.259683 -313.853004)
			(xy 80.278974 -313.807728) (xy 80.305277 -313.766132) (xy 80.337912 -313.729295) (xy 80.376033 -313.69817)
			(xy 80.418654 -313.673563) (xy 80.46467 -313.656111) (xy 80.512889 -313.646267) (xy 80.562064 -313.644286)
			(xy 80.610919 -313.650218) (xy 80.65819 -313.66391) (xy 80.702652 -313.685008) (xy 80.743155 -313.712964)
			(xy 80.778648 -313.747056) (xy 80.808213 -313.7864) (xy 80.831084 -313.829977) (xy 80.846668 -313.876658)
			(xy 80.854563 -313.925235) (xy 80.855058 -313.949842) (xy 81.19416 -313.949842) (xy 81.19812 -313.900788)
			(xy 81.209897 -313.853004) (xy 81.229188 -313.807728) (xy 81.255491 -313.766132) (xy 81.288126 -313.729295)
			(xy 81.326247 -313.69817) (xy 81.368868 -313.673563) (xy 81.414884 -313.656111) (xy 81.463103 -313.646267)
			(xy 81.512278 -313.644286) (xy 81.561133 -313.650218) (xy 81.608404 -313.66391) (xy 81.652866 -313.685008)
			(xy 81.693369 -313.712964) (xy 81.728862 -313.747056) (xy 81.758427 -313.7864) (xy 81.781298 -313.829977)
			(xy 81.796882 -313.876658) (xy 81.804777 -313.925235) (xy 81.805272 -313.949842) (xy 82.14412 -313.949842)
			(xy 82.14808 -313.900788) (xy 82.159857 -313.853004) (xy 82.179148 -313.807728) (xy 82.205451 -313.766132)
			(xy 82.238086 -313.729295) (xy 82.276207 -313.69817) (xy 82.318828 -313.673563) (xy 82.364844 -313.656111)
			(xy 82.413063 -313.646267) (xy 82.462238 -313.644286) (xy 82.511093 -313.650218) (xy 82.558364 -313.66391)
			(xy 82.602826 -313.685008) (xy 82.643329 -313.712964) (xy 82.678822 -313.747056) (xy 82.708387 -313.7864)
			(xy 82.731258 -313.829977) (xy 82.746842 -313.876658) (xy 82.754737 -313.925235) (xy 82.755232 -313.949842)
			(xy 82.754737 -313.974449) (xy 82.746842 -314.023026) (xy 82.731258 -314.069707) (xy 82.708387 -314.113284)
			(xy 82.678822 -314.152628) (xy 82.643329 -314.18672) (xy 82.602826 -314.214676) (xy 82.558364 -314.235774)
			(xy 82.511093 -314.249466) (xy 82.462238 -314.255398) (xy 82.413063 -314.253417) (xy 82.364844 -314.243573)
			(xy 82.318828 -314.226121) (xy 82.276207 -314.201514) (xy 82.238086 -314.170389) (xy 82.205451 -314.133552)
			(xy 82.179148 -314.091956) (xy 82.159857 -314.04668) (xy 82.14808 -313.998896) (xy 82.14412 -313.949842)
			(xy 81.805272 -313.949842) (xy 81.804777 -313.974449) (xy 81.796882 -314.023026) (xy 81.781298 -314.069707)
			(xy 81.758427 -314.113284) (xy 81.728862 -314.152628) (xy 81.693369 -314.18672) (xy 81.652866 -314.214676)
			(xy 81.608404 -314.235774) (xy 81.561133 -314.249466) (xy 81.512278 -314.255398) (xy 81.463103 -314.253417)
			(xy 81.414884 -314.243573) (xy 81.368868 -314.226121) (xy 81.326247 -314.201514) (xy 81.288126 -314.170389)
			(xy 81.255491 -314.133552) (xy 81.229188 -314.091956) (xy 81.209897 -314.04668) (xy 81.19812 -313.998896)
			(xy 81.19416 -313.949842) (xy 80.855058 -313.949842) (xy 80.854563 -313.974449) (xy 80.846668 -314.023026)
			(xy 80.831084 -314.069707) (xy 80.808213 -314.113284) (xy 80.778648 -314.152628) (xy 80.743155 -314.18672)
			(xy 80.702652 -314.214676) (xy 80.65819 -314.235774) (xy 80.610919 -314.249466) (xy 80.562064 -314.255398)
			(xy 80.512889 -314.253417) (xy 80.46467 -314.243573) (xy 80.418654 -314.226121) (xy 80.376033 -314.201514)
			(xy 80.337912 -314.170389) (xy 80.305277 -314.133552) (xy 80.278974 -314.091956) (xy 80.259683 -314.04668)
			(xy 80.247906 -313.998896) (xy 80.243946 -313.949842) (xy 79.905098 -313.949842) (xy 79.904603 -313.974449)
			(xy 79.896708 -314.023026) (xy 79.881124 -314.069707) (xy 79.858253 -314.113284) (xy 79.828688 -314.152628)
			(xy 79.793195 -314.18672) (xy 79.752692 -314.214676) (xy 79.70823 -314.235774) (xy 79.660959 -314.249466)
			(xy 79.612104 -314.255398) (xy 79.562929 -314.253417) (xy 79.51471 -314.243573) (xy 79.468694 -314.226121)
			(xy 79.426073 -314.201514) (xy 79.387952 -314.170389) (xy 79.355317 -314.133552) (xy 79.329014 -314.091956)
			(xy 79.309723 -314.04668) (xy 79.297946 -313.998896) (xy 79.293986 -313.949842) (xy 78.955138 -313.949842)
			(xy 78.954643 -313.974449) (xy 78.946748 -314.023026) (xy 78.931164 -314.069707) (xy 78.908293 -314.113284)
			(xy 78.878728 -314.152628) (xy 78.843235 -314.18672) (xy 78.802732 -314.214676) (xy 78.75827 -314.235774)
			(xy 78.710999 -314.249466) (xy 78.662144 -314.255398) (xy 78.612969 -314.253417) (xy 78.56475 -314.243573)
			(xy 78.518734 -314.226121) (xy 78.476113 -314.201514) (xy 78.437992 -314.170389) (xy 78.405357 -314.133552)
			(xy 78.379054 -314.091956) (xy 78.359763 -314.04668) (xy 78.347986 -313.998896) (xy 78.344026 -313.949842)
			(xy 78.005178 -313.949842) (xy 78.004683 -313.974449) (xy 77.996788 -314.023026) (xy 77.981204 -314.069707)
			(xy 77.958333 -314.113284) (xy 77.928768 -314.152628) (xy 77.893275 -314.18672) (xy 77.852772 -314.214676)
			(xy 77.80831 -314.235774) (xy 77.761039 -314.249466) (xy 77.712184 -314.255398) (xy 77.663009 -314.253417)
			(xy 77.61479 -314.243573) (xy 77.568774 -314.226121) (xy 77.526153 -314.201514) (xy 77.488032 -314.170389)
			(xy 77.455397 -314.133552) (xy 77.429094 -314.091956) (xy 77.409803 -314.04668) (xy 77.398026 -313.998896)
			(xy 77.394066 -313.949842) (xy 77.055218 -313.949842) (xy 77.054723 -313.974449) (xy 77.046828 -314.023026)
			(xy 77.031244 -314.069707) (xy 77.008373 -314.113284) (xy 76.978808 -314.152628) (xy 76.943315 -314.18672)
			(xy 76.902812 -314.214676) (xy 76.85835 -314.235774) (xy 76.811079 -314.249466) (xy 76.762224 -314.255398)
			(xy 76.713049 -314.253417) (xy 76.66483 -314.243573) (xy 76.618814 -314.226121) (xy 76.576193 -314.201514)
			(xy 76.538072 -314.170389) (xy 76.505437 -314.133552) (xy 76.479134 -314.091956) (xy 76.459843 -314.04668)
			(xy 76.448066 -313.998896) (xy 76.444106 -313.949842) (xy 76.105258 -313.949842) (xy 76.104763 -313.974449)
			(xy 76.096868 -314.023026) (xy 76.081284 -314.069707) (xy 76.058413 -314.113284) (xy 76.028848 -314.152628)
			(xy 75.993355 -314.18672) (xy 75.952852 -314.214676) (xy 75.90839 -314.235774) (xy 75.861119 -314.249466)
			(xy 75.812264 -314.255398) (xy 75.763089 -314.253417) (xy 75.71487 -314.243573) (xy 75.668854 -314.226121)
			(xy 75.626233 -314.201514) (xy 75.588112 -314.170389) (xy 75.555477 -314.133552) (xy 75.529174 -314.091956)
			(xy 75.509883 -314.04668) (xy 75.498106 -313.998896) (xy 75.494146 -313.949842) (xy 75.155298 -313.949842)
			(xy 75.154803 -313.974449) (xy 75.146908 -314.023026) (xy 75.131324 -314.069707) (xy 75.108453 -314.113284)
			(xy 75.078888 -314.152628) (xy 75.043395 -314.18672) (xy 75.002892 -314.214676) (xy 74.95843 -314.235774)
			(xy 74.911159 -314.249466) (xy 74.862304 -314.255398) (xy 74.813129 -314.253417) (xy 74.76491 -314.243573)
			(xy 74.718894 -314.226121) (xy 74.676273 -314.201514) (xy 74.638152 -314.170389) (xy 74.605517 -314.133552)
			(xy 74.579214 -314.091956) (xy 74.559923 -314.04668) (xy 74.548146 -313.998896) (xy 74.544186 -313.949842)
			(xy 74.205084 -313.949842) (xy 74.204589 -313.974449) (xy 74.196694 -314.023026) (xy 74.18111 -314.069707)
			(xy 74.158239 -314.113284) (xy 74.128674 -314.152628) (xy 74.093181 -314.18672) (xy 74.052678 -314.214676)
			(xy 74.008216 -314.235774) (xy 73.960945 -314.249466) (xy 73.91209 -314.255398) (xy 73.862915 -314.253417)
			(xy 73.814696 -314.243573) (xy 73.76868 -314.226121) (xy 73.726059 -314.201514) (xy 73.687938 -314.170389)
			(xy 73.655303 -314.133552) (xy 73.629 -314.091956) (xy 73.609709 -314.04668) (xy 73.597932 -313.998896)
			(xy 73.593972 -313.949842) (xy 73.276968 -313.949842) (xy 73.276464 -313.97555) (xy 73.268421 -314.026332)
			(xy 73.252533 -314.075231) (xy 73.22919 -314.121043) (xy 73.198969 -314.162639) (xy 73.162613 -314.198995)
			(xy 73.121017 -314.229216) (xy 73.075205 -314.252559) (xy 73.026306 -314.268447) (xy 72.975524 -314.27649)
			(xy 72.924108 -314.27649) (xy 72.873326 -314.268447) (xy 72.824427 -314.252559) (xy 72.778615 -314.229216)
			(xy 72.737019 -314.198995) (xy 72.700663 -314.162639) (xy 72.670442 -314.121043) (xy 72.647099 -314.075231)
			(xy 72.631211 -314.026332) (xy 72.623168 -313.97555) (xy 72.30449 -313.97555) (xy 72.296774 -314.023026)
			(xy 72.28119 -314.069707) (xy 72.258319 -314.113284) (xy 72.228754 -314.152628) (xy 72.193261 -314.18672)
			(xy 72.152758 -314.214676) (xy 72.108296 -314.235774) (xy 72.061025 -314.249466) (xy 72.01217 -314.255398)
			(xy 71.962995 -314.253417) (xy 71.914776 -314.243573) (xy 71.86876 -314.226121) (xy 71.826139 -314.201514)
			(xy 71.788018 -314.170389) (xy 71.755383 -314.133552) (xy 71.72908 -314.091956) (xy 71.709789 -314.04668)
			(xy 71.698012 -313.998896) (xy 71.694052 -313.949842) (xy 71.377048 -313.949842) (xy 71.376544 -313.97555)
			(xy 71.368501 -314.026332) (xy 71.352613 -314.075231) (xy 71.32927 -314.121043) (xy 71.299049 -314.162639)
			(xy 71.262693 -314.198995) (xy 71.221097 -314.229216) (xy 71.175285 -314.252559) (xy 71.126386 -314.268447)
			(xy 71.075604 -314.27649) (xy 71.024188 -314.27649) (xy 70.973406 -314.268447) (xy 70.924507 -314.252559)
			(xy 70.878695 -314.229216) (xy 70.837099 -314.198995) (xy 70.800743 -314.162639) (xy 70.770522 -314.121043)
			(xy 70.747179 -314.075231) (xy 70.731291 -314.026332) (xy 70.723248 -313.97555) (xy 70.40457 -313.97555)
			(xy 70.396854 -314.023026) (xy 70.38127 -314.069707) (xy 70.358399 -314.113284) (xy 70.328834 -314.152628)
			(xy 70.293341 -314.18672) (xy 70.252838 -314.214676) (xy 70.208376 -314.235774) (xy 70.161105 -314.249466)
			(xy 70.11225 -314.255398) (xy 70.063075 -314.253417) (xy 70.014856 -314.243573) (xy 69.96884 -314.226121)
			(xy 69.926219 -314.201514) (xy 69.888098 -314.170389) (xy 69.855463 -314.133552) (xy 69.82916 -314.091956)
			(xy 69.809869 -314.04668) (xy 69.798092 -313.998896) (xy 69.794132 -313.949842) (xy 69.477128 -313.949842)
			(xy 69.476624 -313.97555) (xy 69.468581 -314.026332) (xy 69.452693 -314.075231) (xy 69.42935 -314.121043)
			(xy 69.399129 -314.162639) (xy 69.362773 -314.198995) (xy 69.321177 -314.229216) (xy 69.275365 -314.252559)
			(xy 69.226466 -314.268447) (xy 69.175684 -314.27649) (xy 69.124268 -314.27649) (xy 69.073486 -314.268447)
			(xy 69.024587 -314.252559) (xy 68.978775 -314.229216) (xy 68.937179 -314.198995) (xy 68.900823 -314.162639)
			(xy 68.870602 -314.121043) (xy 68.847259 -314.075231) (xy 68.831371 -314.026332) (xy 68.823328 -313.97555)
			(xy 68.504396 -313.97555) (xy 68.49668 -314.023026) (xy 68.481096 -314.069707) (xy 68.458225 -314.113284)
			(xy 68.42866 -314.152628) (xy 68.393167 -314.18672) (xy 68.352664 -314.214676) (xy 68.308202 -314.235774)
			(xy 68.260931 -314.249466) (xy 68.212076 -314.255398) (xy 68.162901 -314.253417) (xy 68.114682 -314.243573)
			(xy 68.068666 -314.226121) (xy 68.026045 -314.201514) (xy 67.987924 -314.170389) (xy 67.955289 -314.133552)
			(xy 67.928986 -314.091956) (xy 67.909695 -314.04668) (xy 67.897918 -313.998896) (xy 67.893958 -313.949842)
			(xy 67.576954 -313.949842) (xy 67.57645 -313.97555) (xy 67.568407 -314.026332) (xy 67.552519 -314.075231)
			(xy 67.529176 -314.121043) (xy 67.498955 -314.162639) (xy 67.462599 -314.198995) (xy 67.421003 -314.229216)
			(xy 67.375191 -314.252559) (xy 67.326292 -314.268447) (xy 67.27551 -314.27649) (xy 67.224094 -314.27649)
			(xy 67.173312 -314.268447) (xy 67.124413 -314.252559) (xy 67.078601 -314.229216) (xy 67.037005 -314.198995)
			(xy 67.000649 -314.162639) (xy 66.970428 -314.121043) (xy 66.947085 -314.075231) (xy 66.931197 -314.026332)
			(xy 66.923154 -313.97555) (xy 66.604476 -313.97555) (xy 66.59676 -314.023026) (xy 66.581176 -314.069707)
			(xy 66.558305 -314.113284) (xy 66.52874 -314.152628) (xy 66.493247 -314.18672) (xy 66.452744 -314.214676)
			(xy 66.408282 -314.235774) (xy 66.361011 -314.249466) (xy 66.312156 -314.255398) (xy 66.262981 -314.253417)
			(xy 66.214762 -314.243573) (xy 66.168746 -314.226121) (xy 66.126125 -314.201514) (xy 66.088004 -314.170389)
			(xy 66.055369 -314.133552) (xy 66.029066 -314.091956) (xy 66.009775 -314.04668) (xy 65.997998 -313.998896)
			(xy 65.994038 -313.949842) (xy 65.677034 -313.949842) (xy 65.67653 -313.97555) (xy 65.668487 -314.026332)
			(xy 65.652599 -314.075231) (xy 65.629256 -314.121043) (xy 65.599035 -314.162639) (xy 65.562679 -314.198995)
			(xy 65.521083 -314.229216) (xy 65.475271 -314.252559) (xy 65.426372 -314.268447) (xy 65.37559 -314.27649)
			(xy 65.324174 -314.27649) (xy 65.273392 -314.268447) (xy 65.224493 -314.252559) (xy 65.178681 -314.229216)
			(xy 65.137085 -314.198995) (xy 65.100729 -314.162639) (xy 65.070508 -314.121043) (xy 65.047165 -314.075231)
			(xy 65.031277 -314.026332) (xy 65.023234 -313.97555) (xy 64.704556 -313.97555) (xy 64.69684 -314.023026)
			(xy 64.681256 -314.069707) (xy 64.658385 -314.113284) (xy 64.62882 -314.152628) (xy 64.593327 -314.18672)
			(xy 64.552824 -314.214676) (xy 64.508362 -314.235774) (xy 64.461091 -314.249466) (xy 64.412236 -314.255398)
			(xy 64.363061 -314.253417) (xy 64.314842 -314.243573) (xy 64.268826 -314.226121) (xy 64.226205 -314.201514)
			(xy 64.188084 -314.170389) (xy 64.155449 -314.133552) (xy 64.129146 -314.091956) (xy 64.109855 -314.04668)
			(xy 64.098078 -313.998896) (xy 64.094118 -313.949842) (xy 63.777114 -313.949842) (xy 63.77661 -313.97555)
			(xy 63.768567 -314.026332) (xy 63.752679 -314.075231) (xy 63.729336 -314.121043) (xy 63.699115 -314.162639)
			(xy 63.662759 -314.198995) (xy 63.621163 -314.229216) (xy 63.575351 -314.252559) (xy 63.526452 -314.268447)
			(xy 63.47567 -314.27649) (xy 63.424254 -314.27649) (xy 63.373472 -314.268447) (xy 63.324573 -314.252559)
			(xy 63.278761 -314.229216) (xy 63.237165 -314.198995) (xy 63.200809 -314.162639) (xy 63.170588 -314.121043)
			(xy 63.147245 -314.075231) (xy 63.131357 -314.026332) (xy 63.123314 -313.97555) (xy 62.804382 -313.97555)
			(xy 62.796666 -314.023026) (xy 62.781082 -314.069707) (xy 62.758211 -314.113284) (xy 62.728646 -314.152628)
			(xy 62.693153 -314.18672) (xy 62.65265 -314.214676) (xy 62.608188 -314.235774) (xy 62.560917 -314.249466)
			(xy 62.512062 -314.255398) (xy 62.462887 -314.253417) (xy 62.414668 -314.243573) (xy 62.368652 -314.226121)
			(xy 62.326031 -314.201514) (xy 62.28791 -314.170389) (xy 62.255275 -314.133552) (xy 62.228972 -314.091956)
			(xy 62.209681 -314.04668) (xy 62.197904 -313.998896) (xy 62.193944 -313.949842) (xy 61.87694 -313.949842)
			(xy 61.876436 -313.97555) (xy 61.868393 -314.026332) (xy 61.852505 -314.075231) (xy 61.829162 -314.121043)
			(xy 61.798941 -314.162639) (xy 61.762585 -314.198995) (xy 61.720989 -314.229216) (xy 61.675177 -314.252559)
			(xy 61.626278 -314.268447) (xy 61.575496 -314.27649) (xy 61.52408 -314.27649) (xy 61.473298 -314.268447)
			(xy 61.424399 -314.252559) (xy 61.378587 -314.229216) (xy 61.336991 -314.198995) (xy 61.300635 -314.162639)
			(xy 61.270414 -314.121043) (xy 61.247071 -314.075231) (xy 61.231183 -314.026332) (xy 61.22314 -313.97555)
			(xy 60.904462 -313.97555) (xy 60.896746 -314.023026) (xy 60.881162 -314.069707) (xy 60.858291 -314.113284)
			(xy 60.828726 -314.152628) (xy 60.793233 -314.18672) (xy 60.75273 -314.214676) (xy 60.708268 -314.235774)
			(xy 60.660997 -314.249466) (xy 60.612142 -314.255398) (xy 60.562967 -314.253417) (xy 60.514748 -314.243573)
			(xy 60.468732 -314.226121) (xy 60.426111 -314.201514) (xy 60.38799 -314.170389) (xy 60.355355 -314.133552)
			(xy 60.329052 -314.091956) (xy 60.309761 -314.04668) (xy 60.297984 -313.998896) (xy 60.294024 -313.949842)
			(xy 59.97702 -313.949842) (xy 59.976516 -313.97555) (xy 59.968473 -314.026332) (xy 59.952585 -314.075231)
			(xy 59.929242 -314.121043) (xy 59.899021 -314.162639) (xy 59.862665 -314.198995) (xy 59.821069 -314.229216)
			(xy 59.775257 -314.252559) (xy 59.726358 -314.268447) (xy 59.675576 -314.27649) (xy 59.62416 -314.27649)
			(xy 59.573378 -314.268447) (xy 59.524479 -314.252559) (xy 59.478667 -314.229216) (xy 59.437071 -314.198995)
			(xy 59.400715 -314.162639) (xy 59.370494 -314.121043) (xy 59.347151 -314.075231) (xy 59.331263 -314.026332)
			(xy 59.32322 -313.97555) (xy 59.004542 -313.97555) (xy 58.996826 -314.023026) (xy 58.981242 -314.069707)
			(xy 58.958371 -314.113284) (xy 58.928806 -314.152628) (xy 58.893313 -314.18672) (xy 58.85281 -314.214676)
			(xy 58.808348 -314.235774) (xy 58.761077 -314.249466) (xy 58.712222 -314.255398) (xy 58.663047 -314.253417)
			(xy 58.614828 -314.243573) (xy 58.568812 -314.226121) (xy 58.526191 -314.201514) (xy 58.48807 -314.170389)
			(xy 58.455435 -314.133552) (xy 58.429132 -314.091956) (xy 58.409841 -314.04668) (xy 58.398064 -313.998896)
			(xy 58.394104 -313.949842) (xy 58.055686 -313.949842) (xy 58.051519 -314.000126) (xy 58.039124 -314.04908)
			(xy 58.018841 -314.095326) (xy 57.991223 -314.137604) (xy 57.957024 -314.174759) (xy 57.917176 -314.20578)
			(xy 57.872766 -314.229819) (xy 57.825006 -314.246222) (xy 57.775197 -314.254541) (xy 57.749948 -314.25515)
			(xy 57.718198 -314.253372) (xy 57.707276 -314.252356) (xy 57.686956 -314.25896) (xy 57.633968 -314.306712)
			(xy 101.487984 -314.306712) (xy 101.492055 -314.25109) (xy 101.504181 -314.196653) (xy 101.524104 -314.144562)
			(xy 101.5514 -314.095927) (xy 101.585486 -314.051784) (xy 101.625635 -314.013075) (xy 101.670993 -313.980624)
			(xy 101.720593 -313.955123) (xy 101.773377 -313.937116) (xy 101.82822 -313.926986) (xy 101.883954 -313.924949)
			(xy 101.939391 -313.931049) (xy 101.993348 -313.945155) (xy 102.044677 -313.966967) (xy 102.092283 -313.996021)
			(xy 102.135151 -314.031696) (xy 102.172368 -314.073233) (xy 102.203141 -314.119746) (xy 102.226813 -314.170243)
			(xy 102.242881 -314.22365) (xy 102.251001 -314.278826) (xy 102.25151 -314.306712) (xy 102.503984 -314.306712)
			(xy 102.508055 -314.25109) (xy 102.520181 -314.196653) (xy 102.540104 -314.144562) (xy 102.5674 -314.095927)
			(xy 102.601486 -314.051784) (xy 102.641635 -314.013075) (xy 102.686993 -313.980624) (xy 102.736593 -313.955123)
			(xy 102.789377 -313.937116) (xy 102.84422 -313.926986) (xy 102.899954 -313.924949) (xy 102.955391 -313.931049)
			(xy 103.009348 -313.945155) (xy 103.060677 -313.966967) (xy 103.108283 -313.996021) (xy 103.151151 -314.031696)
			(xy 103.188368 -314.073233) (xy 103.219141 -314.119746) (xy 103.242813 -314.170243) (xy 103.258881 -314.22365)
			(xy 103.267001 -314.278826) (xy 103.26751 -314.306712) (xy 103.519984 -314.306712) (xy 103.524055 -314.25109)
			(xy 103.536181 -314.196653) (xy 103.556104 -314.144562) (xy 103.5834 -314.095927) (xy 103.617486 -314.051784)
			(xy 103.657635 -314.013075) (xy 103.702993 -313.980624) (xy 103.752593 -313.955123) (xy 103.805377 -313.937116)
			(xy 103.86022 -313.926986) (xy 103.915954 -313.924949) (xy 103.971391 -313.931049) (xy 104.025348 -313.945155)
			(xy 104.076677 -313.966967) (xy 104.124283 -313.996021) (xy 104.167151 -314.031696) (xy 104.204368 -314.073233)
			(xy 104.235141 -314.119746) (xy 104.258813 -314.170243) (xy 104.274881 -314.22365) (xy 104.283001 -314.278826)
			(xy 104.28351 -314.306712) (xy 104.535984 -314.306712) (xy 104.540055 -314.25109) (xy 104.552181 -314.196653)
			(xy 104.572104 -314.144562) (xy 104.5994 -314.095927) (xy 104.633486 -314.051784) (xy 104.673635 -314.013075)
			(xy 104.718993 -313.980624) (xy 104.768593 -313.955123) (xy 104.821377 -313.937116) (xy 104.87622 -313.926986)
			(xy 104.931954 -313.924949) (xy 104.987391 -313.931049) (xy 105.041348 -313.945155) (xy 105.092677 -313.966967)
			(xy 105.140283 -313.996021) (xy 105.183151 -314.031696) (xy 105.220368 -314.073233) (xy 105.251141 -314.119746)
			(xy 105.274813 -314.170243) (xy 105.290881 -314.22365) (xy 105.299001 -314.278826) (xy 105.29951 -314.306712)
			(xy 105.551984 -314.306712) (xy 105.556055 -314.25109) (xy 105.568181 -314.196653) (xy 105.588104 -314.144562)
			(xy 105.6154 -314.095927) (xy 105.649486 -314.051784) (xy 105.689635 -314.013075) (xy 105.734993 -313.980624)
			(xy 105.784593 -313.955123) (xy 105.837377 -313.937116) (xy 105.89222 -313.926986) (xy 105.947954 -313.924949)
			(xy 106.003391 -313.931049) (xy 106.057348 -313.945155) (xy 106.108677 -313.966967) (xy 106.156283 -313.996021)
			(xy 106.199151 -314.031696) (xy 106.236368 -314.073233) (xy 106.267141 -314.119746) (xy 106.290813 -314.170243)
			(xy 106.306881 -314.22365) (xy 106.315001 -314.278826) (xy 106.31551 -314.306712) (xy 106.567984 -314.306712)
			(xy 106.572055 -314.25109) (xy 106.584181 -314.196653) (xy 106.604104 -314.144562) (xy 106.6314 -314.095927)
			(xy 106.665486 -314.051784) (xy 106.705635 -314.013075) (xy 106.750993 -313.980624) (xy 106.800593 -313.955123)
			(xy 106.853377 -313.937116) (xy 106.90822 -313.926986) (xy 106.963954 -313.924949) (xy 107.019391 -313.931049)
			(xy 107.073348 -313.945155) (xy 107.124677 -313.966967) (xy 107.172283 -313.996021) (xy 107.215151 -314.031696)
			(xy 107.252368 -314.073233) (xy 107.283141 -314.119746) (xy 107.306813 -314.170243) (xy 107.322881 -314.22365)
			(xy 107.331001 -314.278826) (xy 107.33151 -314.306712) (xy 107.583984 -314.306712) (xy 107.588055 -314.25109)
			(xy 107.600181 -314.196653) (xy 107.620104 -314.144562) (xy 107.6474 -314.095927) (xy 107.681486 -314.051784)
			(xy 107.721635 -314.013075) (xy 107.766993 -313.980624) (xy 107.816593 -313.955123) (xy 107.869377 -313.937116)
			(xy 107.92422 -313.926986) (xy 107.979954 -313.924949) (xy 108.035391 -313.931049) (xy 108.089348 -313.945155)
			(xy 108.140677 -313.966967) (xy 108.188283 -313.996021) (xy 108.231151 -314.031696) (xy 108.268368 -314.073233)
			(xy 108.299141 -314.119746) (xy 108.322813 -314.170243) (xy 108.338881 -314.22365) (xy 108.347001 -314.278826)
			(xy 108.34751 -314.306712) (xy 108.599984 -314.306712) (xy 108.604055 -314.25109) (xy 108.616181 -314.196653)
			(xy 108.636104 -314.144562) (xy 108.6634 -314.095927) (xy 108.697486 -314.051784) (xy 108.737635 -314.013075)
			(xy 108.782993 -313.980624) (xy 108.832593 -313.955123) (xy 108.885377 -313.937116) (xy 108.94022 -313.926986)
			(xy 108.995954 -313.924949) (xy 109.051391 -313.931049) (xy 109.105348 -313.945155) (xy 109.156677 -313.966967)
			(xy 109.204283 -313.996021) (xy 109.247151 -314.031696) (xy 109.284368 -314.073233) (xy 109.315141 -314.119746)
			(xy 109.338813 -314.170243) (xy 109.354881 -314.22365) (xy 109.363001 -314.278826) (xy 109.36351 -314.306712)
			(xy 109.615984 -314.306712) (xy 109.620055 -314.25109) (xy 109.632181 -314.196653) (xy 109.652104 -314.144562)
			(xy 109.6794 -314.095927) (xy 109.713486 -314.051784) (xy 109.753635 -314.013075) (xy 109.798993 -313.980624)
			(xy 109.848593 -313.955123) (xy 109.901377 -313.937116) (xy 109.95622 -313.926986) (xy 110.011954 -313.924949)
			(xy 110.067391 -313.931049) (xy 110.121348 -313.945155) (xy 110.172677 -313.966967) (xy 110.220283 -313.996021)
			(xy 110.263151 -314.031696) (xy 110.300368 -314.073233) (xy 110.331141 -314.119746) (xy 110.354813 -314.170243)
			(xy 110.370881 -314.22365) (xy 110.379001 -314.278826) (xy 110.37951 -314.306712) (xy 110.379001 -314.334598)
			(xy 110.370881 -314.389774) (xy 110.354813 -314.443181) (xy 110.331141 -314.493678) (xy 110.300368 -314.540191)
			(xy 110.263151 -314.581728) (xy 110.220283 -314.617403) (xy 110.172677 -314.646457) (xy 110.121348 -314.668269)
			(xy 110.067391 -314.682375) (xy 110.011954 -314.688475) (xy 109.95622 -314.686438) (xy 109.901377 -314.676308)
			(xy 109.848593 -314.658301) (xy 109.798993 -314.6328) (xy 109.753635 -314.600349) (xy 109.713486 -314.56164)
			(xy 109.6794 -314.517497) (xy 109.652104 -314.468862) (xy 109.632181 -314.416771) (xy 109.620055 -314.362334)
			(xy 109.615984 -314.306712) (xy 109.36351 -314.306712) (xy 109.363001 -314.334598) (xy 109.354881 -314.389774)
			(xy 109.338813 -314.443181) (xy 109.315141 -314.493678) (xy 109.284368 -314.540191) (xy 109.247151 -314.581728)
			(xy 109.204283 -314.617403) (xy 109.156677 -314.646457) (xy 109.105348 -314.668269) (xy 109.051391 -314.682375)
			(xy 108.995954 -314.688475) (xy 108.94022 -314.686438) (xy 108.885377 -314.676308) (xy 108.832593 -314.658301)
			(xy 108.782993 -314.6328) (xy 108.737635 -314.600349) (xy 108.697486 -314.56164) (xy 108.6634 -314.517497)
			(xy 108.636104 -314.468862) (xy 108.616181 -314.416771) (xy 108.604055 -314.362334) (xy 108.599984 -314.306712)
			(xy 108.34751 -314.306712) (xy 108.347001 -314.334598) (xy 108.338881 -314.389774) (xy 108.322813 -314.443181)
			(xy 108.299141 -314.493678) (xy 108.268368 -314.540191) (xy 108.231151 -314.581728) (xy 108.188283 -314.617403)
			(xy 108.140677 -314.646457) (xy 108.089348 -314.668269) (xy 108.035391 -314.682375) (xy 107.979954 -314.688475)
			(xy 107.92422 -314.686438) (xy 107.869377 -314.676308) (xy 107.816593 -314.658301) (xy 107.766993 -314.6328)
			(xy 107.721635 -314.600349) (xy 107.681486 -314.56164) (xy 107.6474 -314.517497) (xy 107.620104 -314.468862)
			(xy 107.600181 -314.416771) (xy 107.588055 -314.362334) (xy 107.583984 -314.306712) (xy 107.33151 -314.306712)
			(xy 107.331001 -314.334598) (xy 107.322881 -314.389774) (xy 107.306813 -314.443181) (xy 107.283141 -314.493678)
			(xy 107.252368 -314.540191) (xy 107.215151 -314.581728) (xy 107.172283 -314.617403) (xy 107.124677 -314.646457)
			(xy 107.073348 -314.668269) (xy 107.019391 -314.682375) (xy 106.963954 -314.688475) (xy 106.90822 -314.686438)
			(xy 106.853377 -314.676308) (xy 106.800593 -314.658301) (xy 106.750993 -314.6328) (xy 106.705635 -314.600349)
			(xy 106.665486 -314.56164) (xy 106.6314 -314.517497) (xy 106.604104 -314.468862) (xy 106.584181 -314.416771)
			(xy 106.572055 -314.362334) (xy 106.567984 -314.306712) (xy 106.31551 -314.306712) (xy 106.315001 -314.334598)
			(xy 106.306881 -314.389774) (xy 106.290813 -314.443181) (xy 106.267141 -314.493678) (xy 106.236368 -314.540191)
			(xy 106.199151 -314.581728) (xy 106.156283 -314.617403) (xy 106.108677 -314.646457) (xy 106.057348 -314.668269)
			(xy 106.003391 -314.682375) (xy 105.947954 -314.688475) (xy 105.89222 -314.686438) (xy 105.837377 -314.676308)
			(xy 105.784593 -314.658301) (xy 105.734993 -314.6328) (xy 105.689635 -314.600349) (xy 105.649486 -314.56164)
			(xy 105.6154 -314.517497) (xy 105.588104 -314.468862) (xy 105.568181 -314.416771) (xy 105.556055 -314.362334)
			(xy 105.551984 -314.306712) (xy 105.29951 -314.306712) (xy 105.299001 -314.334598) (xy 105.290881 -314.389774)
			(xy 105.274813 -314.443181) (xy 105.251141 -314.493678) (xy 105.220368 -314.540191) (xy 105.183151 -314.581728)
			(xy 105.140283 -314.617403) (xy 105.092677 -314.646457) (xy 105.041348 -314.668269) (xy 104.987391 -314.682375)
			(xy 104.931954 -314.688475) (xy 104.87622 -314.686438) (xy 104.821377 -314.676308) (xy 104.768593 -314.658301)
			(xy 104.718993 -314.6328) (xy 104.673635 -314.600349) (xy 104.633486 -314.56164) (xy 104.5994 -314.517497)
			(xy 104.572104 -314.468862) (xy 104.552181 -314.416771) (xy 104.540055 -314.362334) (xy 104.535984 -314.306712)
			(xy 104.28351 -314.306712) (xy 104.283001 -314.334598) (xy 104.274881 -314.389774) (xy 104.258813 -314.443181)
			(xy 104.235141 -314.493678) (xy 104.204368 -314.540191) (xy 104.167151 -314.581728) (xy 104.124283 -314.617403)
			(xy 104.076677 -314.646457) (xy 104.025348 -314.668269) (xy 103.971391 -314.682375) (xy 103.915954 -314.688475)
			(xy 103.86022 -314.686438) (xy 103.805377 -314.676308) (xy 103.752593 -314.658301) (xy 103.702993 -314.6328)
			(xy 103.657635 -314.600349) (xy 103.617486 -314.56164) (xy 103.5834 -314.517497) (xy 103.556104 -314.468862)
			(xy 103.536181 -314.416771) (xy 103.524055 -314.362334) (xy 103.519984 -314.306712) (xy 103.26751 -314.306712)
			(xy 103.267001 -314.334598) (xy 103.258881 -314.389774) (xy 103.242813 -314.443181) (xy 103.219141 -314.493678)
			(xy 103.188368 -314.540191) (xy 103.151151 -314.581728) (xy 103.108283 -314.617403) (xy 103.060677 -314.646457)
			(xy 103.009348 -314.668269) (xy 102.955391 -314.682375) (xy 102.899954 -314.688475) (xy 102.84422 -314.686438)
			(xy 102.789377 -314.676308) (xy 102.736593 -314.658301) (xy 102.686993 -314.6328) (xy 102.641635 -314.600349)
			(xy 102.601486 -314.56164) (xy 102.5674 -314.517497) (xy 102.540104 -314.468862) (xy 102.520181 -314.416771)
			(xy 102.508055 -314.362334) (xy 102.503984 -314.306712) (xy 102.25151 -314.306712) (xy 102.251001 -314.334598)
			(xy 102.242881 -314.389774) (xy 102.226813 -314.443181) (xy 102.203141 -314.493678) (xy 102.172368 -314.540191)
			(xy 102.135151 -314.581728) (xy 102.092283 -314.617403) (xy 102.044677 -314.646457) (xy 101.993348 -314.668269)
			(xy 101.939391 -314.682375) (xy 101.883954 -314.688475) (xy 101.82822 -314.686438) (xy 101.773377 -314.676308)
			(xy 101.720593 -314.658301) (xy 101.670993 -314.6328) (xy 101.625635 -314.600349) (xy 101.585486 -314.56164)
			(xy 101.5514 -314.517497) (xy 101.524104 -314.468862) (xy 101.504181 -314.416771) (xy 101.492055 -314.362334)
			(xy 101.487984 -314.306712) (xy 57.633968 -314.306712) (xy 57.622694 -314.316872) (xy 57.615186 -314.324418)
			(xy 57.606524 -314.343836) (xy 57.60593 -314.354464) (xy 57.60593 -314.424822) (xy 57.60577 -314.438476)
			(xy 57.603484 -314.465689) (xy 57.601358 -314.479178) (xy 57.599326 -314.491116) (xy 57.606438 -314.513722)
			(xy 57.679336 -314.590176) (xy 57.701688 -314.59805) (xy 57.713626 -314.596526) (xy 57.722673 -314.595536)
			(xy 57.740847 -314.594518) (xy 57.749948 -314.594494) (xy 57.773937 -314.594968) (xy 57.821322 -314.60248)
			(xy 57.86695 -314.617312) (xy 57.909696 -314.639098) (xy 57.948508 -314.667302) (xy 57.98243 -314.70123)
			(xy 58.010628 -314.740047) (xy 58.032407 -314.782796) (xy 58.047231 -314.828426) (xy 58.054736 -314.875813)
			(xy 58.055256 -314.899802) (xy 58.054701 -314.925921) (xy 58.04576 -314.977388) (xy 58.037476 -315.002164)
			(xy 58.034621 -315.011471) (xy 58.03539 -315.030908) (xy 58.043344 -315.048659) (xy 58.057339 -315.062168)
			(xy 58.075359 -315.069492) (xy 58.09481 -315.069575) (xy 58.104024 -315.066426) (xy 58.133488 -315.05652)
			(xy 58.137472 -315.055291) (xy 58.145003 -315.051717) (xy 58.148474 -315.049408) (xy 58.181765 -315.026987)
			(xy 58.251407 -314.98707) (xy 58.324101 -314.953029) (xy 58.36158 -314.938664) (xy 58.370909 -314.934688)
			(xy 58.385662 -314.920799) (xy 58.393931 -314.9023) (xy 58.3946 -314.892182) (xy 58.395709 -314.867339)
			(xy 58.404986 -314.818487) (xy 58.422055 -314.771783) (xy 58.446465 -314.728461) (xy 58.477571 -314.689666)
			(xy 58.514551 -314.656422) (xy 58.556428 -314.629609) (xy 58.602095 -314.609934) (xy 58.650347 -314.597917)
			(xy 58.699908 -314.593875) (xy 58.749469 -314.597917) (xy 58.797721 -314.609934) (xy 58.843388 -314.629609)
			(xy 58.885265 -314.656422) (xy 58.922245 -314.689666) (xy 58.953351 -314.728461) (xy 58.977761 -314.771783)
			(xy 58.99483 -314.818487) (xy 59.004107 -314.867339) (xy 59.005216 -314.892182) (xy 59.005847 -314.902316)
			(xy 59.014073 -314.920861) (xy 59.028872 -314.934739) (xy 59.038236 -314.938664) (xy 59.078071 -314.953959)
			(xy 59.155144 -314.99059) (xy 59.19216 -315.011816) (xy 59.204606 -315.018928) (xy 59.232292 -315.018674)
			(xy 59.33313 -314.956952) (xy 59.346084 -314.932314) (xy 59.345068 -314.91809) (xy 59.34456 -314.899802)
			(xy 59.345082 -314.874547) (xy 59.353395 -314.824725) (xy 59.369796 -314.776951) (xy 59.393837 -314.732528)
			(xy 59.424861 -314.692668) (xy 59.462023 -314.658458) (xy 59.504309 -314.630832) (xy 59.550565 -314.610542)
			(xy 59.59953 -314.598142) (xy 59.649868 -314.593971) (xy 59.700206 -314.598142) (xy 59.749171 -314.610542)
			(xy 59.795427 -314.630832) (xy 59.837713 -314.658458) (xy 59.874875 -314.692668) (xy 59.905899 -314.732528)
			(xy 59.92994 -314.776951) (xy 59.946341 -314.824725) (xy 59.954654 -314.874547) (xy 59.955176 -314.899802)
			(xy 59.954621 -314.925921) (xy 59.945681 -314.977388) (xy 59.937396 -315.002164) (xy 59.9345 -315.011485)
			(xy 59.935208 -315.030975) (xy 59.943137 -315.048792) (xy 59.957142 -315.062364) (xy 59.9752 -315.069731)
			(xy 59.994702 -315.069827) (xy 60.003944 -315.06668) (xy 60.033408 -315.05652) (xy 60.037321 -315.055349)
			(xy 60.044721 -315.051896) (xy 60.04814 -315.049662) (xy 60.081466 -315.027189) (xy 60.151185 -314.987176)
			(xy 60.223968 -314.953051) (xy 60.2615 -314.938664) (xy 60.270826 -314.934686) (xy 60.285574 -314.920795)
			(xy 60.293839 -314.902298) (xy 60.29452 -314.892182) (xy 60.295629 -314.867339) (xy 60.304906 -314.818487)
			(xy 60.321975 -314.771783) (xy 60.346385 -314.728461) (xy 60.377491 -314.689666) (xy 60.414471 -314.656422)
			(xy 60.456348 -314.629609) (xy 60.502015 -314.609934) (xy 60.550267 -314.597917) (xy 60.599828 -314.593875)
			(xy 60.649389 -314.597917) (xy 60.697641 -314.609934) (xy 60.743308 -314.629609) (xy 60.785185 -314.656422)
			(xy 60.822165 -314.689666) (xy 60.853271 -314.728461) (xy 60.877681 -314.771783) (xy 60.89475 -314.818487)
			(xy 60.904027 -314.867339) (xy 60.905136 -314.892182) (xy 60.905765 -314.90232) (xy 60.913985 -314.920877)
			(xy 60.928775 -314.934774) (xy 60.938156 -314.938664) (xy 60.975642 -314.953012) (xy 61.04834 -314.987049)
			(xy 61.117979 -315.026974) (xy 61.151262 -315.049408) (xy 61.154687 -315.051631) (xy 61.162089 -315.055073)
			(xy 61.165994 -315.056266) (xy 61.195712 -315.066426) (xy 61.204911 -315.069582) (xy 61.224342 -315.069456)
			(xy 61.242329 -315.062105) (xy 61.256287 -315.048587) (xy 61.264209 -315.030844) (xy 61.264957 -315.011427)
			(xy 61.262006 -315.002164) (xy 61.253799 -314.977375) (xy 61.244984 -314.92591) (xy 61.24448 -314.899802)
			(xy 61.245002 -314.874547) (xy 61.253315 -314.824725) (xy 61.269716 -314.776951) (xy 61.293757 -314.732528)
			(xy 61.324781 -314.692668) (xy 61.361943 -314.658458) (xy 61.404229 -314.630832) (xy 61.450485 -314.610542)
			(xy 61.49945 -314.598142) (xy 61.549788 -314.593971) (xy 61.600126 -314.598142) (xy 61.649091 -314.610542)
			(xy 61.695347 -314.630832) (xy 61.737633 -314.658458) (xy 61.774795 -314.692668) (xy 61.805819 -314.732528)
			(xy 61.82986 -314.776951) (xy 61.846261 -314.824725) (xy 61.854574 -314.874547) (xy 61.855096 -314.899802)
			(xy 61.854541 -314.925921) (xy 61.845601 -314.977388) (xy 61.837316 -315.002164) (xy 61.83442 -315.011484)
			(xy 61.835127 -315.03097) (xy 61.843055 -315.048784) (xy 61.85706 -315.062353) (xy 61.875116 -315.069714)
			(xy 61.894615 -315.069805) (xy 61.903864 -315.06668) (xy 61.933328 -315.05652) (xy 61.937243 -315.055355)
			(xy 61.944651 -315.051912) (xy 61.94806 -315.049662) (xy 61.981386 -315.02719) (xy 62.051106 -314.987178)
			(xy 62.123889 -314.953054) (xy 62.16142 -314.938664) (xy 62.170757 -314.934695) (xy 62.185528 -314.92081)
			(xy 62.193808 -314.902306) (xy 62.19444 -314.892182) (xy 62.195549 -314.867339) (xy 62.204826 -314.818487)
			(xy 62.221895 -314.771783) (xy 62.246305 -314.728461) (xy 62.277411 -314.689666) (xy 62.314391 -314.656422)
			(xy 62.356268 -314.629609) (xy 62.401935 -314.609934) (xy 62.450187 -314.597917) (xy 62.499748 -314.593875)
			(xy 62.549309 -314.597917) (xy 62.597561 -314.609934) (xy 62.643228 -314.629609) (xy 62.685105 -314.656422)
			(xy 62.722085 -314.689666) (xy 62.753191 -314.728461) (xy 62.777601 -314.771783) (xy 62.79467 -314.818487)
			(xy 62.803947 -314.867339) (xy 62.805056 -314.892182) (xy 62.805686 -314.902319) (xy 62.813907 -314.920873)
			(xy 62.8287 -314.934765) (xy 62.838076 -314.938664) (xy 62.875515 -314.952975) (xy 62.948125 -314.986931)
			(xy 63.017683 -315.026765) (xy 63.050928 -315.049154) (xy 63.054399 -315.051462) (xy 63.061932 -315.055032)
			(xy 63.065914 -315.056266) (xy 63.095886 -315.066426) (xy 63.105076 -315.069567) (xy 63.124481 -315.06942)
			(xy 63.14244 -315.062066) (xy 63.156373 -315.04856) (xy 63.164282 -315.030839) (xy 63.165032 -315.011448)
			(xy 63.16218 -315.002164) (xy 63.153973 -314.977375) (xy 63.145159 -314.92591) (xy 63.144654 -314.899802)
			(xy 63.145176 -314.874547) (xy 63.153489 -314.824725) (xy 63.16989 -314.776951) (xy 63.193931 -314.732528)
			(xy 63.224955 -314.692668) (xy 63.262117 -314.658458) (xy 63.304403 -314.630832) (xy 63.350659 -314.610542)
			(xy 63.399624 -314.598142) (xy 63.449962 -314.593971) (xy 63.5003 -314.598142) (xy 63.549265 -314.610542)
			(xy 63.595521 -314.630832) (xy 63.637807 -314.658458) (xy 63.674969 -314.692668) (xy 63.705993 -314.732528)
			(xy 63.730034 -314.776951) (xy 63.746435 -314.824725) (xy 63.754748 -314.874547) (xy 63.75527 -314.899802)
			(xy 63.754715 -314.925921) (xy 63.745774 -314.977388) (xy 63.73749 -315.002164) (xy 63.734594 -315.011486)
			(xy 63.735303 -315.030976) (xy 63.743232 -315.048795) (xy 63.757237 -315.062368) (xy 63.775295 -315.069735)
			(xy 63.794798 -315.069833) (xy 63.804038 -315.06668) (xy 63.833502 -315.05652) (xy 63.837415 -315.05535)
			(xy 63.844816 -315.051898) (xy 63.848234 -315.049662) (xy 63.88156 -315.027189) (xy 63.951279 -314.987176)
			(xy 64.024062 -314.95305) (xy 64.061594 -314.938664) (xy 64.070921 -314.934687) (xy 64.08567 -314.920796)
			(xy 64.093937 -314.902298) (xy 64.094614 -314.892182) (xy 64.095723 -314.867339) (xy 64.105 -314.818487)
			(xy 64.122069 -314.771783) (xy 64.146479 -314.728461) (xy 64.177585 -314.689666) (xy 64.214565 -314.656422)
			(xy 64.256442 -314.629609) (xy 64.302109 -314.609934) (xy 64.350361 -314.597917) (xy 64.399922 -314.593875)
			(xy 64.449483 -314.597917) (xy 64.497735 -314.609934) (xy 64.543402 -314.629609) (xy 64.585279 -314.656422)
			(xy 64.622259 -314.689666) (xy 64.653365 -314.728461) (xy 64.677775 -314.771783) (xy 64.694844 -314.818487)
			(xy 64.704121 -314.867339) (xy 64.70523 -314.892182) (xy 64.705859 -314.902321) (xy 64.714078 -314.920878)
			(xy 64.728868 -314.934777) (xy 64.73825 -314.938664) (xy 64.775923 -314.953056) (xy 64.848973 -314.987242)
			(xy 64.918939 -315.027364) (xy 64.952372 -315.049916) (xy 64.95573 -315.052185) (xy 64.963 -315.055765)
			(xy 64.96685 -315.057028) (xy 64.99606 -315.066934) (xy 65.005274 -315.070083) (xy 65.024728 -315.069928)
			(xy 65.042723 -315.062532) (xy 65.056663 -315.048961) (xy 65.064539 -315.031171) (xy 65.065215 -315.011728)
			(xy 65.062354 -315.002418) (xy 65.054057 -314.97758) (xy 65.04512 -314.925984) (xy 65.044574 -314.899802)
			(xy 65.045096 -314.874547) (xy 65.053409 -314.824725) (xy 65.06981 -314.776951) (xy 65.093851 -314.732528)
			(xy 65.124875 -314.692668) (xy 65.162037 -314.658458) (xy 65.204323 -314.630832) (xy 65.250579 -314.610542)
			(xy 65.299544 -314.598142) (xy 65.349882 -314.593971) (xy 65.40022 -314.598142) (xy 65.449185 -314.610542)
			(xy 65.495441 -314.630832) (xy 65.537727 -314.658458) (xy 65.574889 -314.692668) (xy 65.605913 -314.732528)
			(xy 65.629954 -314.776951) (xy 65.646355 -314.824725) (xy 65.654668 -314.874547) (xy 65.65519 -314.899802)
			(xy 65.655003 -314.913984) (xy 65.65233 -314.942224) (xy 65.649856 -314.95619) (xy 65.64757 -314.968636)
			(xy 65.654936 -314.992258) (xy 65.732406 -315.069728) (xy 65.756028 -315.077094) (xy 65.768474 -315.074808)
			(xy 65.782439 -315.072321) (xy 65.810679 -315.069646) (xy 65.824862 -315.069474) (xy 65.839045 -315.069659)
			(xy 65.867285 -315.072329) (xy 65.88125 -315.074808) (xy 65.893696 -315.077094) (xy 65.917318 -315.069728)
			(xy 65.994788 -314.992258) (xy 66.002154 -314.968636) (xy 65.999868 -314.95619) (xy 65.997382 -314.942225)
			(xy 65.99471 -314.913985) (xy 65.994534 -314.899802) (xy 65.99502 -314.874985) (xy 66.003049 -314.826005)
			(xy 66.018896 -314.77897) (xy 66.042144 -314.735118) (xy 66.07218 -314.695604) (xy 66.108213 -314.66147)
			(xy 66.149293 -314.633615) (xy 66.194338 -314.612773) (xy 66.242162 -314.599492) (xy 66.291504 -314.594124)
			(xy 66.341065 -314.596808) (xy 66.389539 -314.607475) (xy 66.435648 -314.625844) (xy 66.478179 -314.65143)
			(xy 66.51601 -314.683559) (xy 66.548145 -314.721385) (xy 66.573737 -314.763912) (xy 66.592112 -314.810019)
			(xy 66.602786 -314.858491) (xy 66.60503 -314.899802) (xy 66.943998 -314.899802) (xy 66.947958 -314.850748)
			(xy 66.959735 -314.802964) (xy 66.979026 -314.757688) (xy 67.005329 -314.716092) (xy 67.037964 -314.679255)
			(xy 67.076085 -314.64813) (xy 67.118706 -314.623523) (xy 67.164722 -314.606071) (xy 67.212941 -314.596227)
			(xy 67.262116 -314.594246) (xy 67.310971 -314.600178) (xy 67.358242 -314.61387) (xy 67.402704 -314.634968)
			(xy 67.443207 -314.662924) (xy 67.4787 -314.697016) (xy 67.508265 -314.73636) (xy 67.531136 -314.779937)
			(xy 67.54672 -314.826618) (xy 67.554615 -314.875195) (xy 67.55511 -314.899802) (xy 67.893958 -314.899802)
			(xy 67.897918 -314.850748) (xy 67.909695 -314.802964) (xy 67.928986 -314.757688) (xy 67.955289 -314.716092)
			(xy 67.987924 -314.679255) (xy 68.026045 -314.64813) (xy 68.068666 -314.623523) (xy 68.114682 -314.606071)
			(xy 68.162901 -314.596227) (xy 68.212076 -314.594246) (xy 68.260931 -314.600178) (xy 68.308202 -314.61387)
			(xy 68.352664 -314.634968) (xy 68.393167 -314.662924) (xy 68.42866 -314.697016) (xy 68.458225 -314.73636)
			(xy 68.481096 -314.779937) (xy 68.49668 -314.826618) (xy 68.504575 -314.875195) (xy 68.50507 -314.899802)
			(xy 68.844172 -314.899802) (xy 68.848132 -314.850748) (xy 68.859909 -314.802964) (xy 68.8792 -314.757688)
			(xy 68.905503 -314.716092) (xy 68.938138 -314.679255) (xy 68.976259 -314.64813) (xy 69.01888 -314.623523)
			(xy 69.064896 -314.606071) (xy 69.113115 -314.596227) (xy 69.16229 -314.594246) (xy 69.211145 -314.600178)
			(xy 69.258416 -314.61387) (xy 69.302878 -314.634968) (xy 69.343381 -314.662924) (xy 69.378874 -314.697016)
			(xy 69.408439 -314.73636) (xy 69.43131 -314.779937) (xy 69.446894 -314.826618) (xy 69.454789 -314.875195)
			(xy 69.455284 -314.899802) (xy 69.794132 -314.899802) (xy 69.798092 -314.850748) (xy 69.809869 -314.802964)
			(xy 69.82916 -314.757688) (xy 69.855463 -314.716092) (xy 69.888098 -314.679255) (xy 69.926219 -314.64813)
			(xy 69.96884 -314.623523) (xy 70.014856 -314.606071) (xy 70.063075 -314.596227) (xy 70.11225 -314.594246)
			(xy 70.161105 -314.600178) (xy 70.208376 -314.61387) (xy 70.252838 -314.634968) (xy 70.293341 -314.662924)
			(xy 70.328834 -314.697016) (xy 70.358399 -314.73636) (xy 70.38127 -314.779937) (xy 70.396854 -314.826618)
			(xy 70.404749 -314.875195) (xy 70.405244 -314.899802) (xy 70.744092 -314.899802) (xy 70.748052 -314.850748)
			(xy 70.759829 -314.802964) (xy 70.77912 -314.757688) (xy 70.805423 -314.716092) (xy 70.838058 -314.679255)
			(xy 70.876179 -314.64813) (xy 70.9188 -314.623523) (xy 70.964816 -314.606071) (xy 71.013035 -314.596227)
			(xy 71.06221 -314.594246) (xy 71.111065 -314.600178) (xy 71.158336 -314.61387) (xy 71.202798 -314.634968)
			(xy 71.243301 -314.662924) (xy 71.278794 -314.697016) (xy 71.308359 -314.73636) (xy 71.33123 -314.779937)
			(xy 71.346814 -314.826618) (xy 71.354709 -314.875195) (xy 71.355204 -314.899802) (xy 71.694052 -314.899802)
			(xy 71.698012 -314.850748) (xy 71.709789 -314.802964) (xy 71.72908 -314.757688) (xy 71.755383 -314.716092)
			(xy 71.788018 -314.679255) (xy 71.826139 -314.64813) (xy 71.86876 -314.623523) (xy 71.914776 -314.606071)
			(xy 71.962995 -314.596227) (xy 72.01217 -314.594246) (xy 72.061025 -314.600178) (xy 72.108296 -314.61387)
			(xy 72.152758 -314.634968) (xy 72.193261 -314.662924) (xy 72.228754 -314.697016) (xy 72.258319 -314.73636)
			(xy 72.28119 -314.779937) (xy 72.296774 -314.826618) (xy 72.304669 -314.875195) (xy 72.305164 -314.899802)
			(xy 72.644012 -314.899802) (xy 72.647972 -314.850748) (xy 72.659749 -314.802964) (xy 72.67904 -314.757688)
			(xy 72.705343 -314.716092) (xy 72.737978 -314.679255) (xy 72.776099 -314.64813) (xy 72.81872 -314.623523)
			(xy 72.864736 -314.606071) (xy 72.912955 -314.596227) (xy 72.96213 -314.594246) (xy 73.010985 -314.600178)
			(xy 73.058256 -314.61387) (xy 73.102718 -314.634968) (xy 73.143221 -314.662924) (xy 73.178714 -314.697016)
			(xy 73.208279 -314.73636) (xy 73.23115 -314.779937) (xy 73.246734 -314.826618) (xy 73.254629 -314.875195)
			(xy 73.255124 -314.899802) (xy 73.593972 -314.899802) (xy 73.597932 -314.850748) (xy 73.609709 -314.802964)
			(xy 73.629 -314.757688) (xy 73.655303 -314.716092) (xy 73.687938 -314.679255) (xy 73.726059 -314.64813)
			(xy 73.76868 -314.623523) (xy 73.814696 -314.606071) (xy 73.862915 -314.596227) (xy 73.91209 -314.594246)
			(xy 73.960945 -314.600178) (xy 74.008216 -314.61387) (xy 74.052678 -314.634968) (xy 74.093181 -314.662924)
			(xy 74.128674 -314.697016) (xy 74.158239 -314.73636) (xy 74.18111 -314.779937) (xy 74.196694 -314.826618)
			(xy 74.204589 -314.875195) (xy 74.205084 -314.899802) (xy 74.544186 -314.899802) (xy 74.548146 -314.850748)
			(xy 74.559923 -314.802964) (xy 74.579214 -314.757688) (xy 74.605517 -314.716092) (xy 74.638152 -314.679255)
			(xy 74.676273 -314.64813) (xy 74.718894 -314.623523) (xy 74.76491 -314.606071) (xy 74.813129 -314.596227)
			(xy 74.862304 -314.594246) (xy 74.911159 -314.600178) (xy 74.95843 -314.61387) (xy 75.002892 -314.634968)
			(xy 75.043395 -314.662924) (xy 75.078888 -314.697016) (xy 75.108453 -314.73636) (xy 75.131324 -314.779937)
			(xy 75.146908 -314.826618) (xy 75.154803 -314.875195) (xy 75.155298 -314.899802) (xy 75.494146 -314.899802)
			(xy 75.498106 -314.850748) (xy 75.509883 -314.802964) (xy 75.529174 -314.757688) (xy 75.555477 -314.716092)
			(xy 75.588112 -314.679255) (xy 75.626233 -314.64813) (xy 75.668854 -314.623523) (xy 75.71487 -314.606071)
			(xy 75.763089 -314.596227) (xy 75.812264 -314.594246) (xy 75.861119 -314.600178) (xy 75.90839 -314.61387)
			(xy 75.952852 -314.634968) (xy 75.993355 -314.662924) (xy 76.028848 -314.697016) (xy 76.058413 -314.73636)
			(xy 76.081284 -314.779937) (xy 76.096868 -314.826618) (xy 76.104763 -314.875195) (xy 76.105258 -314.899802)
			(xy 76.444106 -314.899802) (xy 76.448066 -314.850748) (xy 76.459843 -314.802964) (xy 76.479134 -314.757688)
			(xy 76.505437 -314.716092) (xy 76.538072 -314.679255) (xy 76.576193 -314.64813) (xy 76.618814 -314.623523)
			(xy 76.66483 -314.606071) (xy 76.713049 -314.596227) (xy 76.762224 -314.594246) (xy 76.811079 -314.600178)
			(xy 76.85835 -314.61387) (xy 76.902812 -314.634968) (xy 76.943315 -314.662924) (xy 76.978808 -314.697016)
			(xy 77.008373 -314.73636) (xy 77.031244 -314.779937) (xy 77.046828 -314.826618) (xy 77.054723 -314.875195)
			(xy 77.055218 -314.899802) (xy 77.394066 -314.899802) (xy 77.398026 -314.850748) (xy 77.409803 -314.802964)
			(xy 77.429094 -314.757688) (xy 77.455397 -314.716092) (xy 77.488032 -314.679255) (xy 77.526153 -314.64813)
			(xy 77.568774 -314.623523) (xy 77.61479 -314.606071) (xy 77.663009 -314.596227) (xy 77.712184 -314.594246)
			(xy 77.761039 -314.600178) (xy 77.80831 -314.61387) (xy 77.852772 -314.634968) (xy 77.893275 -314.662924)
			(xy 77.928768 -314.697016) (xy 77.958333 -314.73636) (xy 77.981204 -314.779937) (xy 77.996788 -314.826618)
			(xy 78.004683 -314.875195) (xy 78.005178 -314.899802) (xy 78.344026 -314.899802) (xy 78.347986 -314.850748)
			(xy 78.359763 -314.802964) (xy 78.379054 -314.757688) (xy 78.405357 -314.716092) (xy 78.437992 -314.679255)
			(xy 78.476113 -314.64813) (xy 78.518734 -314.623523) (xy 78.56475 -314.606071) (xy 78.612969 -314.596227)
			(xy 78.662144 -314.594246) (xy 78.710999 -314.600178) (xy 78.75827 -314.61387) (xy 78.802732 -314.634968)
			(xy 78.843235 -314.662924) (xy 78.878728 -314.697016) (xy 78.908293 -314.73636) (xy 78.931164 -314.779937)
			(xy 78.946748 -314.826618) (xy 78.954643 -314.875195) (xy 78.955138 -314.899802) (xy 79.293986 -314.899802)
			(xy 79.297946 -314.850748) (xy 79.309723 -314.802964) (xy 79.329014 -314.757688) (xy 79.355317 -314.716092)
			(xy 79.387952 -314.679255) (xy 79.426073 -314.64813) (xy 79.468694 -314.623523) (xy 79.51471 -314.606071)
			(xy 79.562929 -314.596227) (xy 79.612104 -314.594246) (xy 79.660959 -314.600178) (xy 79.70823 -314.61387)
			(xy 79.752692 -314.634968) (xy 79.793195 -314.662924) (xy 79.828688 -314.697016) (xy 79.858253 -314.73636)
			(xy 79.881124 -314.779937) (xy 79.896708 -314.826618) (xy 79.904603 -314.875195) (xy 79.905098 -314.899802)
			(xy 80.243946 -314.899802) (xy 80.247906 -314.850748) (xy 80.259683 -314.802964) (xy 80.278974 -314.757688)
			(xy 80.305277 -314.716092) (xy 80.337912 -314.679255) (xy 80.376033 -314.64813) (xy 80.418654 -314.623523)
			(xy 80.46467 -314.606071) (xy 80.512889 -314.596227) (xy 80.562064 -314.594246) (xy 80.610919 -314.600178)
			(xy 80.65819 -314.61387) (xy 80.702652 -314.634968) (xy 80.743155 -314.662924) (xy 80.778648 -314.697016)
			(xy 80.808213 -314.73636) (xy 80.831084 -314.779937) (xy 80.846668 -314.826618) (xy 80.854563 -314.875195)
			(xy 80.855058 -314.899802) (xy 81.19416 -314.899802) (xy 81.19812 -314.850748) (xy 81.209897 -314.802964)
			(xy 81.229188 -314.757688) (xy 81.255491 -314.716092) (xy 81.288126 -314.679255) (xy 81.326247 -314.64813)
			(xy 81.368868 -314.623523) (xy 81.414884 -314.606071) (xy 81.463103 -314.596227) (xy 81.512278 -314.594246)
			(xy 81.561133 -314.600178) (xy 81.608404 -314.61387) (xy 81.652866 -314.634968) (xy 81.693369 -314.662924)
			(xy 81.728862 -314.697016) (xy 81.758427 -314.73636) (xy 81.781298 -314.779937) (xy 81.796882 -314.826618)
			(xy 81.804777 -314.875195) (xy 81.805272 -314.899802) (xy 82.14412 -314.899802) (xy 82.14808 -314.850748)
			(xy 82.159857 -314.802964) (xy 82.179148 -314.757688) (xy 82.205451 -314.716092) (xy 82.238086 -314.679255)
			(xy 82.276207 -314.64813) (xy 82.318828 -314.623523) (xy 82.364844 -314.606071) (xy 82.413063 -314.596227)
			(xy 82.462238 -314.594246) (xy 82.511093 -314.600178) (xy 82.558364 -314.61387) (xy 82.602826 -314.634968)
			(xy 82.643329 -314.662924) (xy 82.678822 -314.697016) (xy 82.708387 -314.73636) (xy 82.731258 -314.779937)
			(xy 82.746842 -314.826618) (xy 82.754737 -314.875195) (xy 82.755227 -314.899548) (xy 83.094334 -314.899548)
			(xy 83.098294 -314.850494) (xy 83.110071 -314.80271) (xy 83.129362 -314.757434) (xy 83.155665 -314.715838)
			(xy 83.1883 -314.679001) (xy 83.226421 -314.647876) (xy 83.269042 -314.623269) (xy 83.315058 -314.605817)
			(xy 83.363277 -314.595973) (xy 83.412452 -314.593992) (xy 83.461307 -314.599924) (xy 83.508578 -314.613616)
			(xy 83.55304 -314.634714) (xy 83.593543 -314.66267) (xy 83.629036 -314.696762) (xy 83.658601 -314.736106)
			(xy 83.681472 -314.779683) (xy 83.697056 -314.826364) (xy 83.704951 -314.874941) (xy 83.705446 -314.899548)
			(xy 83.704951 -314.924155) (xy 83.697056 -314.972732) (xy 83.681472 -315.019413) (xy 83.658601 -315.06299)
			(xy 83.629036 -315.102334) (xy 83.593543 -315.136426) (xy 83.55304 -315.164382) (xy 83.508578 -315.18548)
			(xy 83.461307 -315.199172) (xy 83.412452 -315.205104) (xy 83.363277 -315.203123) (xy 83.315058 -315.193279)
			(xy 83.269042 -315.175827) (xy 83.226421 -315.15122) (xy 83.1883 -315.120095) (xy 83.155665 -315.083258)
			(xy 83.129362 -315.041662) (xy 83.110071 -314.996386) (xy 83.098294 -314.948602) (xy 83.094334 -314.899548)
			(xy 82.755227 -314.899548) (xy 82.755232 -314.899802) (xy 82.754737 -314.924409) (xy 82.746842 -314.972986)
			(xy 82.731258 -315.019667) (xy 82.708387 -315.063244) (xy 82.678822 -315.102588) (xy 82.643329 -315.13668)
			(xy 82.602826 -315.164636) (xy 82.558364 -315.185734) (xy 82.511093 -315.199426) (xy 82.462238 -315.205358)
			(xy 82.413063 -315.203377) (xy 82.364844 -315.193533) (xy 82.318828 -315.176081) (xy 82.276207 -315.151474)
			(xy 82.238086 -315.120349) (xy 82.205451 -315.083512) (xy 82.179148 -315.041916) (xy 82.159857 -314.99664)
			(xy 82.14808 -314.948856) (xy 82.14412 -314.899802) (xy 81.805272 -314.899802) (xy 81.804777 -314.924409)
			(xy 81.796882 -314.972986) (xy 81.781298 -315.019667) (xy 81.758427 -315.063244) (xy 81.728862 -315.102588)
			(xy 81.693369 -315.13668) (xy 81.652866 -315.164636) (xy 81.608404 -315.185734) (xy 81.561133 -315.199426)
			(xy 81.512278 -315.205358) (xy 81.463103 -315.203377) (xy 81.414884 -315.193533) (xy 81.368868 -315.176081)
			(xy 81.326247 -315.151474) (xy 81.288126 -315.120349) (xy 81.255491 -315.083512) (xy 81.229188 -315.041916)
			(xy 81.209897 -314.99664) (xy 81.19812 -314.948856) (xy 81.19416 -314.899802) (xy 80.855058 -314.899802)
			(xy 80.854563 -314.924409) (xy 80.846668 -314.972986) (xy 80.831084 -315.019667) (xy 80.808213 -315.063244)
			(xy 80.778648 -315.102588) (xy 80.743155 -315.13668) (xy 80.702652 -315.164636) (xy 80.65819 -315.185734)
			(xy 80.610919 -315.199426) (xy 80.562064 -315.205358) (xy 80.512889 -315.203377) (xy 80.46467 -315.193533)
			(xy 80.418654 -315.176081) (xy 80.376033 -315.151474) (xy 80.337912 -315.120349) (xy 80.305277 -315.083512)
			(xy 80.278974 -315.041916) (xy 80.259683 -314.99664) (xy 80.247906 -314.948856) (xy 80.243946 -314.899802)
			(xy 79.905098 -314.899802) (xy 79.904603 -314.924409) (xy 79.896708 -314.972986) (xy 79.881124 -315.019667)
			(xy 79.858253 -315.063244) (xy 79.828688 -315.102588) (xy 79.793195 -315.13668) (xy 79.752692 -315.164636)
			(xy 79.70823 -315.185734) (xy 79.660959 -315.199426) (xy 79.612104 -315.205358) (xy 79.562929 -315.203377)
			(xy 79.51471 -315.193533) (xy 79.468694 -315.176081) (xy 79.426073 -315.151474) (xy 79.387952 -315.120349)
			(xy 79.355317 -315.083512) (xy 79.329014 -315.041916) (xy 79.309723 -314.99664) (xy 79.297946 -314.948856)
			(xy 79.293986 -314.899802) (xy 78.955138 -314.899802) (xy 78.954643 -314.924409) (xy 78.946748 -314.972986)
			(xy 78.931164 -315.019667) (xy 78.908293 -315.063244) (xy 78.878728 -315.102588) (xy 78.843235 -315.13668)
			(xy 78.802732 -315.164636) (xy 78.75827 -315.185734) (xy 78.710999 -315.199426) (xy 78.662144 -315.205358)
			(xy 78.612969 -315.203377) (xy 78.56475 -315.193533) (xy 78.518734 -315.176081) (xy 78.476113 -315.151474)
			(xy 78.437992 -315.120349) (xy 78.405357 -315.083512) (xy 78.379054 -315.041916) (xy 78.359763 -314.99664)
			(xy 78.347986 -314.948856) (xy 78.344026 -314.899802) (xy 78.005178 -314.899802) (xy 78.004683 -314.924409)
			(xy 77.996788 -314.972986) (xy 77.981204 -315.019667) (xy 77.958333 -315.063244) (xy 77.928768 -315.102588)
			(xy 77.893275 -315.13668) (xy 77.852772 -315.164636) (xy 77.80831 -315.185734) (xy 77.761039 -315.199426)
			(xy 77.712184 -315.205358) (xy 77.663009 -315.203377) (xy 77.61479 -315.193533) (xy 77.568774 -315.176081)
			(xy 77.526153 -315.151474) (xy 77.488032 -315.120349) (xy 77.455397 -315.083512) (xy 77.429094 -315.041916)
			(xy 77.409803 -314.99664) (xy 77.398026 -314.948856) (xy 77.394066 -314.899802) (xy 77.055218 -314.899802)
			(xy 77.054723 -314.924409) (xy 77.046828 -314.972986) (xy 77.031244 -315.019667) (xy 77.008373 -315.063244)
			(xy 76.978808 -315.102588) (xy 76.943315 -315.13668) (xy 76.902812 -315.164636) (xy 76.85835 -315.185734)
			(xy 76.811079 -315.199426) (xy 76.762224 -315.205358) (xy 76.713049 -315.203377) (xy 76.66483 -315.193533)
			(xy 76.618814 -315.176081) (xy 76.576193 -315.151474) (xy 76.538072 -315.120349) (xy 76.505437 -315.083512)
			(xy 76.479134 -315.041916) (xy 76.459843 -314.99664) (xy 76.448066 -314.948856) (xy 76.444106 -314.899802)
			(xy 76.105258 -314.899802) (xy 76.104763 -314.924409) (xy 76.096868 -314.972986) (xy 76.081284 -315.019667)
			(xy 76.058413 -315.063244) (xy 76.028848 -315.102588) (xy 75.993355 -315.13668) (xy 75.952852 -315.164636)
			(xy 75.90839 -315.185734) (xy 75.861119 -315.199426) (xy 75.812264 -315.205358) (xy 75.763089 -315.203377)
			(xy 75.71487 -315.193533) (xy 75.668854 -315.176081) (xy 75.626233 -315.151474) (xy 75.588112 -315.120349)
			(xy 75.555477 -315.083512) (xy 75.529174 -315.041916) (xy 75.509883 -314.99664) (xy 75.498106 -314.948856)
			(xy 75.494146 -314.899802) (xy 75.155298 -314.899802) (xy 75.154803 -314.924409) (xy 75.146908 -314.972986)
			(xy 75.131324 -315.019667) (xy 75.108453 -315.063244) (xy 75.078888 -315.102588) (xy 75.043395 -315.13668)
			(xy 75.002892 -315.164636) (xy 74.95843 -315.185734) (xy 74.911159 -315.199426) (xy 74.862304 -315.205358)
			(xy 74.813129 -315.203377) (xy 74.76491 -315.193533) (xy 74.718894 -315.176081) (xy 74.676273 -315.151474)
			(xy 74.638152 -315.120349) (xy 74.605517 -315.083512) (xy 74.579214 -315.041916) (xy 74.559923 -314.99664)
			(xy 74.548146 -314.948856) (xy 74.544186 -314.899802) (xy 74.205084 -314.899802) (xy 74.204589 -314.924409)
			(xy 74.196694 -314.972986) (xy 74.18111 -315.019667) (xy 74.158239 -315.063244) (xy 74.128674 -315.102588)
			(xy 74.093181 -315.13668) (xy 74.052678 -315.164636) (xy 74.008216 -315.185734) (xy 73.960945 -315.199426)
			(xy 73.91209 -315.205358) (xy 73.862915 -315.203377) (xy 73.814696 -315.193533) (xy 73.76868 -315.176081)
			(xy 73.726059 -315.151474) (xy 73.687938 -315.120349) (xy 73.655303 -315.083512) (xy 73.629 -315.041916)
			(xy 73.609709 -314.99664) (xy 73.597932 -314.948856) (xy 73.593972 -314.899802) (xy 73.255124 -314.899802)
			(xy 73.254629 -314.924409) (xy 73.246734 -314.972986) (xy 73.23115 -315.019667) (xy 73.208279 -315.063244)
			(xy 73.178714 -315.102588) (xy 73.143221 -315.13668) (xy 73.102718 -315.164636) (xy 73.058256 -315.185734)
			(xy 73.010985 -315.199426) (xy 72.96213 -315.205358) (xy 72.912955 -315.203377) (xy 72.864736 -315.193533)
			(xy 72.81872 -315.176081) (xy 72.776099 -315.151474) (xy 72.737978 -315.120349) (xy 72.705343 -315.083512)
			(xy 72.67904 -315.041916) (xy 72.659749 -314.99664) (xy 72.647972 -314.948856) (xy 72.644012 -314.899802)
			(xy 72.305164 -314.899802) (xy 72.304669 -314.924409) (xy 72.296774 -314.972986) (xy 72.28119 -315.019667)
			(xy 72.258319 -315.063244) (xy 72.228754 -315.102588) (xy 72.193261 -315.13668) (xy 72.152758 -315.164636)
			(xy 72.108296 -315.185734) (xy 72.061025 -315.199426) (xy 72.01217 -315.205358) (xy 71.962995 -315.203377)
			(xy 71.914776 -315.193533) (xy 71.86876 -315.176081) (xy 71.826139 -315.151474) (xy 71.788018 -315.120349)
			(xy 71.755383 -315.083512) (xy 71.72908 -315.041916) (xy 71.709789 -314.99664) (xy 71.698012 -314.948856)
			(xy 71.694052 -314.899802) (xy 71.355204 -314.899802) (xy 71.354709 -314.924409) (xy 71.346814 -314.972986)
			(xy 71.33123 -315.019667) (xy 71.308359 -315.063244) (xy 71.278794 -315.102588) (xy 71.243301 -315.13668)
			(xy 71.202798 -315.164636) (xy 71.158336 -315.185734) (xy 71.111065 -315.199426) (xy 71.06221 -315.205358)
			(xy 71.013035 -315.203377) (xy 70.964816 -315.193533) (xy 70.9188 -315.176081) (xy 70.876179 -315.151474)
			(xy 70.838058 -315.120349) (xy 70.805423 -315.083512) (xy 70.77912 -315.041916) (xy 70.759829 -314.99664)
			(xy 70.748052 -314.948856) (xy 70.744092 -314.899802) (xy 70.405244 -314.899802) (xy 70.404749 -314.924409)
			(xy 70.396854 -314.972986) (xy 70.38127 -315.019667) (xy 70.358399 -315.063244) (xy 70.328834 -315.102588)
			(xy 70.293341 -315.13668) (xy 70.252838 -315.164636) (xy 70.208376 -315.185734) (xy 70.161105 -315.199426)
			(xy 70.11225 -315.205358) (xy 70.063075 -315.203377) (xy 70.014856 -315.193533) (xy 69.96884 -315.176081)
			(xy 69.926219 -315.151474) (xy 69.888098 -315.120349) (xy 69.855463 -315.083512) (xy 69.82916 -315.041916)
			(xy 69.809869 -314.99664) (xy 69.798092 -314.948856) (xy 69.794132 -314.899802) (xy 69.455284 -314.899802)
			(xy 69.454789 -314.924409) (xy 69.446894 -314.972986) (xy 69.43131 -315.019667) (xy 69.408439 -315.063244)
			(xy 69.378874 -315.102588) (xy 69.343381 -315.13668) (xy 69.302878 -315.164636) (xy 69.258416 -315.185734)
			(xy 69.211145 -315.199426) (xy 69.16229 -315.205358) (xy 69.113115 -315.203377) (xy 69.064896 -315.193533)
			(xy 69.01888 -315.176081) (xy 68.976259 -315.151474) (xy 68.938138 -315.120349) (xy 68.905503 -315.083512)
			(xy 68.8792 -315.041916) (xy 68.859909 -314.99664) (xy 68.848132 -314.948856) (xy 68.844172 -314.899802)
			(xy 68.50507 -314.899802) (xy 68.504575 -314.924409) (xy 68.49668 -314.972986) (xy 68.481096 -315.019667)
			(xy 68.458225 -315.063244) (xy 68.42866 -315.102588) (xy 68.393167 -315.13668) (xy 68.352664 -315.164636)
			(xy 68.308202 -315.185734) (xy 68.260931 -315.199426) (xy 68.212076 -315.205358) (xy 68.162901 -315.203377)
			(xy 68.114682 -315.193533) (xy 68.068666 -315.176081) (xy 68.026045 -315.151474) (xy 67.987924 -315.120349)
			(xy 67.955289 -315.083512) (xy 67.928986 -315.041916) (xy 67.909695 -314.99664) (xy 67.897918 -314.948856)
			(xy 67.893958 -314.899802) (xy 67.55511 -314.899802) (xy 67.554615 -314.924409) (xy 67.54672 -314.972986)
			(xy 67.531136 -315.019667) (xy 67.508265 -315.063244) (xy 67.4787 -315.102588) (xy 67.443207 -315.13668)
			(xy 67.402704 -315.164636) (xy 67.358242 -315.185734) (xy 67.310971 -315.199426) (xy 67.262116 -315.205358)
			(xy 67.212941 -315.203377) (xy 67.164722 -315.193533) (xy 67.118706 -315.176081) (xy 67.076085 -315.151474)
			(xy 67.037964 -315.120349) (xy 67.005329 -315.083512) (xy 66.979026 -315.041916) (xy 66.959735 -314.99664)
			(xy 66.947958 -314.948856) (xy 66.943998 -314.899802) (xy 66.60503 -314.899802) (xy 66.605478 -314.908052)
			(xy 66.600116 -314.957395) (xy 66.586843 -315.00522) (xy 66.566007 -315.050269) (xy 66.538158 -315.091353)
			(xy 66.504029 -315.127391) (xy 66.46452 -315.157432) (xy 66.420671 -315.180686) (xy 66.373637 -315.196541)
			(xy 66.324659 -315.204577) (xy 66.299842 -315.20511) (xy 66.285659 -315.204925) (xy 66.257419 -315.202256)
			(xy 66.243454 -315.199776) (xy 66.231008 -315.19749) (xy 66.207386 -315.204856) (xy 66.129916 -315.282326)
			(xy 66.12255 -315.305948) (xy 66.124836 -315.318394) (xy 66.125605 -315.322712) (xy 101.487984 -315.322712)
			(xy 101.492055 -315.26709) (xy 101.504181 -315.212653) (xy 101.524104 -315.160562) (xy 101.5514 -315.111927)
			(xy 101.585486 -315.067784) (xy 101.625635 -315.029075) (xy 101.670993 -314.996624) (xy 101.720593 -314.971123)
			(xy 101.773377 -314.953116) (xy 101.82822 -314.942986) (xy 101.883954 -314.940949) (xy 101.939391 -314.947049)
			(xy 101.993348 -314.961155) (xy 102.044677 -314.982967) (xy 102.092283 -315.012021) (xy 102.135151 -315.047696)
			(xy 102.172368 -315.089233) (xy 102.203141 -315.135746) (xy 102.226813 -315.186243) (xy 102.242881 -315.23965)
			(xy 102.251001 -315.294826) (xy 102.25151 -315.322712) (xy 102.503984 -315.322712) (xy 102.508055 -315.26709)
			(xy 102.520181 -315.212653) (xy 102.540104 -315.160562) (xy 102.5674 -315.111927) (xy 102.601486 -315.067784)
			(xy 102.641635 -315.029075) (xy 102.686993 -314.996624) (xy 102.736593 -314.971123) (xy 102.789377 -314.953116)
			(xy 102.84422 -314.942986) (xy 102.899954 -314.940949) (xy 102.955391 -314.947049) (xy 103.009348 -314.961155)
			(xy 103.060677 -314.982967) (xy 103.108283 -315.012021) (xy 103.151151 -315.047696) (xy 103.188368 -315.089233)
			(xy 103.219141 -315.135746) (xy 103.242813 -315.186243) (xy 103.258881 -315.23965) (xy 103.267001 -315.294826)
			(xy 103.26751 -315.322712) (xy 103.519984 -315.322712) (xy 103.524055 -315.26709) (xy 103.536181 -315.212653)
			(xy 103.556104 -315.160562) (xy 103.5834 -315.111927) (xy 103.617486 -315.067784) (xy 103.657635 -315.029075)
			(xy 103.702993 -314.996624) (xy 103.752593 -314.971123) (xy 103.805377 -314.953116) (xy 103.86022 -314.942986)
			(xy 103.915954 -314.940949) (xy 103.971391 -314.947049) (xy 104.025348 -314.961155) (xy 104.076677 -314.982967)
			(xy 104.124283 -315.012021) (xy 104.167151 -315.047696) (xy 104.204368 -315.089233) (xy 104.235141 -315.135746)
			(xy 104.258813 -315.186243) (xy 104.274881 -315.23965) (xy 104.283001 -315.294826) (xy 104.28351 -315.322712)
			(xy 104.535984 -315.322712) (xy 104.540055 -315.26709) (xy 104.552181 -315.212653) (xy 104.572104 -315.160562)
			(xy 104.5994 -315.111927) (xy 104.633486 -315.067784) (xy 104.673635 -315.029075) (xy 104.718993 -314.996624)
			(xy 104.768593 -314.971123) (xy 104.821377 -314.953116) (xy 104.87622 -314.942986) (xy 104.931954 -314.940949)
			(xy 104.987391 -314.947049) (xy 105.041348 -314.961155) (xy 105.092677 -314.982967) (xy 105.140283 -315.012021)
			(xy 105.183151 -315.047696) (xy 105.220368 -315.089233) (xy 105.251141 -315.135746) (xy 105.274813 -315.186243)
			(xy 105.290881 -315.23965) (xy 105.299001 -315.294826) (xy 105.29951 -315.322712) (xy 105.551984 -315.322712)
			(xy 105.556055 -315.26709) (xy 105.568181 -315.212653) (xy 105.588104 -315.160562) (xy 105.6154 -315.111927)
			(xy 105.649486 -315.067784) (xy 105.689635 -315.029075) (xy 105.734993 -314.996624) (xy 105.784593 -314.971123)
			(xy 105.837377 -314.953116) (xy 105.89222 -314.942986) (xy 105.947954 -314.940949) (xy 106.003391 -314.947049)
			(xy 106.057348 -314.961155) (xy 106.108677 -314.982967) (xy 106.156283 -315.012021) (xy 106.199151 -315.047696)
			(xy 106.236368 -315.089233) (xy 106.267141 -315.135746) (xy 106.290813 -315.186243) (xy 106.306881 -315.23965)
			(xy 106.315001 -315.294826) (xy 106.31551 -315.322712) (xy 106.567984 -315.322712) (xy 106.572055 -315.26709)
			(xy 106.584181 -315.212653) (xy 106.604104 -315.160562) (xy 106.6314 -315.111927) (xy 106.665486 -315.067784)
			(xy 106.705635 -315.029075) (xy 106.750993 -314.996624) (xy 106.800593 -314.971123) (xy 106.853377 -314.953116)
			(xy 106.90822 -314.942986) (xy 106.963954 -314.940949) (xy 107.019391 -314.947049) (xy 107.073348 -314.961155)
			(xy 107.124677 -314.982967) (xy 107.172283 -315.012021) (xy 107.215151 -315.047696) (xy 107.252368 -315.089233)
			(xy 107.283141 -315.135746) (xy 107.306813 -315.186243) (xy 107.322881 -315.23965) (xy 107.331001 -315.294826)
			(xy 107.33151 -315.322712) (xy 107.583984 -315.322712) (xy 107.588055 -315.26709) (xy 107.600181 -315.212653)
			(xy 107.620104 -315.160562) (xy 107.6474 -315.111927) (xy 107.681486 -315.067784) (xy 107.721635 -315.029075)
			(xy 107.766993 -314.996624) (xy 107.816593 -314.971123) (xy 107.869377 -314.953116) (xy 107.92422 -314.942986)
			(xy 107.979954 -314.940949) (xy 108.035391 -314.947049) (xy 108.089348 -314.961155) (xy 108.140677 -314.982967)
			(xy 108.188283 -315.012021) (xy 108.231151 -315.047696) (xy 108.268368 -315.089233) (xy 108.299141 -315.135746)
			(xy 108.322813 -315.186243) (xy 108.338881 -315.23965) (xy 108.347001 -315.294826) (xy 108.34751 -315.322712)
			(xy 108.599984 -315.322712) (xy 108.604055 -315.26709) (xy 108.616181 -315.212653) (xy 108.636104 -315.160562)
			(xy 108.6634 -315.111927) (xy 108.697486 -315.067784) (xy 108.737635 -315.029075) (xy 108.782993 -314.996624)
			(xy 108.832593 -314.971123) (xy 108.885377 -314.953116) (xy 108.94022 -314.942986) (xy 108.995954 -314.940949)
			(xy 109.051391 -314.947049) (xy 109.105348 -314.961155) (xy 109.156677 -314.982967) (xy 109.204283 -315.012021)
			(xy 109.247151 -315.047696) (xy 109.284368 -315.089233) (xy 109.315141 -315.135746) (xy 109.338813 -315.186243)
			(xy 109.354881 -315.23965) (xy 109.363001 -315.294826) (xy 109.36351 -315.322712) (xy 109.615984 -315.322712)
			(xy 109.620055 -315.26709) (xy 109.632181 -315.212653) (xy 109.652104 -315.160562) (xy 109.6794 -315.111927)
			(xy 109.713486 -315.067784) (xy 109.753635 -315.029075) (xy 109.798993 -314.996624) (xy 109.848593 -314.971123)
			(xy 109.901377 -314.953116) (xy 109.95622 -314.942986) (xy 110.011954 -314.940949) (xy 110.067391 -314.947049)
			(xy 110.121348 -314.961155) (xy 110.172677 -314.982967) (xy 110.220283 -315.012021) (xy 110.263151 -315.047696)
			(xy 110.300368 -315.089233) (xy 110.331141 -315.135746) (xy 110.354813 -315.186243) (xy 110.370881 -315.23965)
			(xy 110.379001 -315.294826) (xy 110.37951 -315.322712) (xy 110.379001 -315.350598) (xy 110.370881 -315.405774)
			(xy 110.354813 -315.459181) (xy 110.331141 -315.509678) (xy 110.300368 -315.556191) (xy 110.263151 -315.597728)
			(xy 110.220283 -315.633403) (xy 110.172677 -315.662457) (xy 110.121348 -315.684269) (xy 110.067391 -315.698375)
			(xy 110.011954 -315.704475) (xy 109.95622 -315.702438) (xy 109.901377 -315.692308) (xy 109.848593 -315.674301)
			(xy 109.798993 -315.6488) (xy 109.753635 -315.616349) (xy 109.713486 -315.57764) (xy 109.6794 -315.533497)
			(xy 109.652104 -315.484862) (xy 109.632181 -315.432771) (xy 109.620055 -315.378334) (xy 109.615984 -315.322712)
			(xy 109.36351 -315.322712) (xy 109.363001 -315.350598) (xy 109.354881 -315.405774) (xy 109.338813 -315.459181)
			(xy 109.315141 -315.509678) (xy 109.284368 -315.556191) (xy 109.247151 -315.597728) (xy 109.204283 -315.633403)
			(xy 109.156677 -315.662457) (xy 109.105348 -315.684269) (xy 109.051391 -315.698375) (xy 108.995954 -315.704475)
			(xy 108.94022 -315.702438) (xy 108.885377 -315.692308) (xy 108.832593 -315.674301) (xy 108.782993 -315.6488)
			(xy 108.737635 -315.616349) (xy 108.697486 -315.57764) (xy 108.6634 -315.533497) (xy 108.636104 -315.484862)
			(xy 108.616181 -315.432771) (xy 108.604055 -315.378334) (xy 108.599984 -315.322712) (xy 108.34751 -315.322712)
			(xy 108.347001 -315.350598) (xy 108.338881 -315.405774) (xy 108.322813 -315.459181) (xy 108.299141 -315.509678)
			(xy 108.268368 -315.556191) (xy 108.231151 -315.597728) (xy 108.188283 -315.633403) (xy 108.140677 -315.662457)
			(xy 108.089348 -315.684269) (xy 108.035391 -315.698375) (xy 107.979954 -315.704475) (xy 107.92422 -315.702438)
			(xy 107.869377 -315.692308) (xy 107.816593 -315.674301) (xy 107.766993 -315.6488) (xy 107.721635 -315.616349)
			(xy 107.681486 -315.57764) (xy 107.6474 -315.533497) (xy 107.620104 -315.484862) (xy 107.600181 -315.432771)
			(xy 107.588055 -315.378334) (xy 107.583984 -315.322712) (xy 107.33151 -315.322712) (xy 107.331001 -315.350598)
			(xy 107.322881 -315.405774) (xy 107.306813 -315.459181) (xy 107.283141 -315.509678) (xy 107.252368 -315.556191)
			(xy 107.215151 -315.597728) (xy 107.172283 -315.633403) (xy 107.124677 -315.662457) (xy 107.073348 -315.684269)
			(xy 107.019391 -315.698375) (xy 106.963954 -315.704475) (xy 106.90822 -315.702438) (xy 106.853377 -315.692308)
			(xy 106.800593 -315.674301) (xy 106.750993 -315.6488) (xy 106.705635 -315.616349) (xy 106.665486 -315.57764)
			(xy 106.6314 -315.533497) (xy 106.604104 -315.484862) (xy 106.584181 -315.432771) (xy 106.572055 -315.378334)
			(xy 106.567984 -315.322712) (xy 106.31551 -315.322712) (xy 106.315001 -315.350598) (xy 106.306881 -315.405774)
			(xy 106.290813 -315.459181) (xy 106.267141 -315.509678) (xy 106.236368 -315.556191) (xy 106.199151 -315.597728)
			(xy 106.156283 -315.633403) (xy 106.108677 -315.662457) (xy 106.057348 -315.684269) (xy 106.003391 -315.698375)
			(xy 105.947954 -315.704475) (xy 105.89222 -315.702438) (xy 105.837377 -315.692308) (xy 105.784593 -315.674301)
			(xy 105.734993 -315.6488) (xy 105.689635 -315.616349) (xy 105.649486 -315.57764) (xy 105.6154 -315.533497)
			(xy 105.588104 -315.484862) (xy 105.568181 -315.432771) (xy 105.556055 -315.378334) (xy 105.551984 -315.322712)
			(xy 105.29951 -315.322712) (xy 105.299001 -315.350598) (xy 105.290881 -315.405774) (xy 105.274813 -315.459181)
			(xy 105.251141 -315.509678) (xy 105.220368 -315.556191) (xy 105.183151 -315.597728) (xy 105.140283 -315.633403)
			(xy 105.092677 -315.662457) (xy 105.041348 -315.684269) (xy 104.987391 -315.698375) (xy 104.931954 -315.704475)
			(xy 104.87622 -315.702438) (xy 104.821377 -315.692308) (xy 104.768593 -315.674301) (xy 104.718993 -315.6488)
			(xy 104.673635 -315.616349) (xy 104.633486 -315.57764) (xy 104.5994 -315.533497) (xy 104.572104 -315.484862)
			(xy 104.552181 -315.432771) (xy 104.540055 -315.378334) (xy 104.535984 -315.322712) (xy 104.28351 -315.322712)
			(xy 104.283001 -315.350598) (xy 104.274881 -315.405774) (xy 104.258813 -315.459181) (xy 104.235141 -315.509678)
			(xy 104.204368 -315.556191) (xy 104.167151 -315.597728) (xy 104.124283 -315.633403) (xy 104.076677 -315.662457)
			(xy 104.025348 -315.684269) (xy 103.971391 -315.698375) (xy 103.915954 -315.704475) (xy 103.86022 -315.702438)
			(xy 103.805377 -315.692308) (xy 103.752593 -315.674301) (xy 103.702993 -315.6488) (xy 103.657635 -315.616349)
			(xy 103.617486 -315.57764) (xy 103.5834 -315.533497) (xy 103.556104 -315.484862) (xy 103.536181 -315.432771)
			(xy 103.524055 -315.378334) (xy 103.519984 -315.322712) (xy 103.26751 -315.322712) (xy 103.267001 -315.350598)
			(xy 103.258881 -315.405774) (xy 103.242813 -315.459181) (xy 103.219141 -315.509678) (xy 103.188368 -315.556191)
			(xy 103.151151 -315.597728) (xy 103.108283 -315.633403) (xy 103.060677 -315.662457) (xy 103.009348 -315.684269)
			(xy 102.955391 -315.698375) (xy 102.899954 -315.704475) (xy 102.84422 -315.702438) (xy 102.789377 -315.692308)
			(xy 102.736593 -315.674301) (xy 102.686993 -315.6488) (xy 102.641635 -315.616349) (xy 102.601486 -315.57764)
			(xy 102.5674 -315.533497) (xy 102.540104 -315.484862) (xy 102.520181 -315.432771) (xy 102.508055 -315.378334)
			(xy 102.503984 -315.322712) (xy 102.25151 -315.322712) (xy 102.251001 -315.350598) (xy 102.242881 -315.405774)
			(xy 102.226813 -315.459181) (xy 102.203141 -315.509678) (xy 102.172368 -315.556191) (xy 102.135151 -315.597728)
			(xy 102.092283 -315.633403) (xy 102.044677 -315.662457) (xy 101.993348 -315.684269) (xy 101.939391 -315.698375)
			(xy 101.883954 -315.704475) (xy 101.82822 -315.702438) (xy 101.773377 -315.692308) (xy 101.720593 -315.674301)
			(xy 101.670993 -315.6488) (xy 101.625635 -315.616349) (xy 101.585486 -315.57764) (xy 101.5514 -315.533497)
			(xy 101.524104 -315.484862) (xy 101.504181 -315.432771) (xy 101.492055 -315.378334) (xy 101.487984 -315.322712)
			(xy 66.125605 -315.322712) (xy 66.127322 -315.332359) (xy 66.129996 -315.360599) (xy 66.13017 -315.374782)
			(xy 66.130089 -315.384653) (xy 66.128818 -315.404353) (xy 66.12763 -315.414152) (xy 66.126106 -315.42609)
			(xy 66.13398 -315.448696) (xy 66.210434 -315.522356) (xy 66.233294 -315.529214) (xy 66.245232 -315.527436)
			(xy 66.258783 -315.525297) (xy 66.286124 -315.523004) (xy 66.299842 -315.522864) (xy 66.325529 -315.523371)
			(xy 66.376269 -315.531413) (xy 66.425127 -315.547292) (xy 66.4709 -315.570618) (xy 66.512461 -315.600815)
			(xy 66.548787 -315.637142) (xy 66.578985 -315.678704) (xy 66.60231 -315.724477) (xy 66.618188 -315.773335)
			(xy 66.626229 -315.824075) (xy 66.62674 -315.849762) (xy 66.624962 -315.884306) (xy 66.623692 -315.895736)
			(xy 66.631566 -315.917326) (xy 66.70421 -315.989716) (xy 66.7258 -315.997082) (xy 66.737484 -315.995812)
			(xy 66.746788 -315.994844) (xy 66.765468 -315.993828) (xy 66.774822 -315.99378) (xy 66.788476 -315.99394)
			(xy 66.815689 -315.996226) (xy 66.829178 -315.998352) (xy 66.841116 -316.000384) (xy 66.863722 -315.993272)
			(xy 66.940176 -315.920374) (xy 66.94805 -315.898022) (xy 66.946526 -315.886084) (xy 66.945536 -315.877037)
			(xy 66.944517 -315.858863) (xy 66.944494 -315.849762) (xy 66.944983 -315.824942) (xy 66.95302 -315.775957)
			(xy 66.968875 -315.728917) (xy 66.992132 -315.685062) (xy 67.022177 -315.645547) (xy 67.058219 -315.611414)
			(xy 67.099308 -315.58356) (xy 67.144362 -315.562721) (xy 67.192194 -315.549445) (xy 67.241543 -315.544082)
			(xy 67.29111 -315.546774) (xy 67.339589 -315.557449) (xy 67.385702 -315.575826) (xy 67.428235 -315.60142)
			(xy 67.466067 -315.633559) (xy 67.498201 -315.671395) (xy 67.523791 -315.71393) (xy 67.542162 -315.760046)
			(xy 67.552831 -315.808525) (xy 67.555517 -315.858093) (xy 67.553626 -315.87547) (xy 67.873114 -315.87547)
			(xy 67.873114 -315.824054) (xy 67.881157 -315.773272) (xy 67.897045 -315.724373) (xy 67.920388 -315.678561)
			(xy 67.950609 -315.636965) (xy 67.986965 -315.600609) (xy 68.028561 -315.570388) (xy 68.074373 -315.547045)
			(xy 68.123272 -315.531157) (xy 68.174054 -315.523114) (xy 68.22547 -315.523114) (xy 68.276252 -315.531157)
			(xy 68.325151 -315.547045) (xy 68.370963 -315.570388) (xy 68.412559 -315.600609) (xy 68.448915 -315.636965)
			(xy 68.479136 -315.678561) (xy 68.502479 -315.724373) (xy 68.518367 -315.773272) (xy 68.52641 -315.824054)
			(xy 68.526914 -315.849762) (xy 68.844172 -315.849762) (xy 68.848132 -315.800708) (xy 68.859909 -315.752924)
			(xy 68.8792 -315.707648) (xy 68.905503 -315.666052) (xy 68.938138 -315.629215) (xy 68.976259 -315.59809)
			(xy 69.01888 -315.573483) (xy 69.064896 -315.556031) (xy 69.113115 -315.546187) (xy 69.16229 -315.544206)
			(xy 69.211145 -315.550138) (xy 69.258416 -315.56383) (xy 69.302878 -315.584928) (xy 69.343381 -315.612884)
			(xy 69.378874 -315.646976) (xy 69.408439 -315.68632) (xy 69.43131 -315.729897) (xy 69.446894 -315.776578)
			(xy 69.454789 -315.825155) (xy 69.455284 -315.849762) (xy 69.454789 -315.874369) (xy 69.45461 -315.87547)
			(xy 69.773288 -315.87547) (xy 69.773288 -315.824054) (xy 69.781331 -315.773272) (xy 69.797219 -315.724373)
			(xy 69.820562 -315.678561) (xy 69.850783 -315.636965) (xy 69.887139 -315.600609) (xy 69.928735 -315.570388)
			(xy 69.974547 -315.547045) (xy 70.023446 -315.531157) (xy 70.074228 -315.523114) (xy 70.125644 -315.523114)
			(xy 70.176426 -315.531157) (xy 70.225325 -315.547045) (xy 70.271137 -315.570388) (xy 70.312733 -315.600609)
			(xy 70.349089 -315.636965) (xy 70.37931 -315.678561) (xy 70.402653 -315.724373) (xy 70.418541 -315.773272)
			(xy 70.426584 -315.824054) (xy 70.427088 -315.849762) (xy 70.744092 -315.849762) (xy 70.748052 -315.800708)
			(xy 70.759829 -315.752924) (xy 70.77912 -315.707648) (xy 70.805423 -315.666052) (xy 70.838058 -315.629215)
			(xy 70.876179 -315.59809) (xy 70.9188 -315.573483) (xy 70.964816 -315.556031) (xy 71.013035 -315.546187)
			(xy 71.06221 -315.544206) (xy 71.111065 -315.550138) (xy 71.158336 -315.56383) (xy 71.202798 -315.584928)
			(xy 71.243301 -315.612884) (xy 71.278794 -315.646976) (xy 71.308359 -315.68632) (xy 71.33123 -315.729897)
			(xy 71.346814 -315.776578) (xy 71.354709 -315.825155) (xy 71.355204 -315.849762) (xy 71.354709 -315.874369)
			(xy 71.35453 -315.87547) (xy 71.673208 -315.87547) (xy 71.673208 -315.824054) (xy 71.681251 -315.773272)
			(xy 71.697139 -315.724373) (xy 71.720482 -315.678561) (xy 71.750703 -315.636965) (xy 71.787059 -315.600609)
			(xy 71.828655 -315.570388) (xy 71.874467 -315.547045) (xy 71.923366 -315.531157) (xy 71.974148 -315.523114)
			(xy 72.025564 -315.523114) (xy 72.076346 -315.531157) (xy 72.125245 -315.547045) (xy 72.171057 -315.570388)
			(xy 72.212653 -315.600609) (xy 72.249009 -315.636965) (xy 72.27923 -315.678561) (xy 72.302573 -315.724373)
			(xy 72.318461 -315.773272) (xy 72.326504 -315.824054) (xy 72.327008 -315.849762) (xy 72.644012 -315.849762)
			(xy 72.647972 -315.800708) (xy 72.659749 -315.752924) (xy 72.67904 -315.707648) (xy 72.705343 -315.666052)
			(xy 72.737978 -315.629215) (xy 72.776099 -315.59809) (xy 72.81872 -315.573483) (xy 72.864736 -315.556031)
			(xy 72.912955 -315.546187) (xy 72.96213 -315.544206) (xy 73.010985 -315.550138) (xy 73.058256 -315.56383)
			(xy 73.102718 -315.584928) (xy 73.143221 -315.612884) (xy 73.178714 -315.646976) (xy 73.208279 -315.68632)
			(xy 73.23115 -315.729897) (xy 73.246734 -315.776578) (xy 73.254629 -315.825155) (xy 73.255124 -315.849762)
			(xy 73.593972 -315.849762) (xy 73.597932 -315.800708) (xy 73.609709 -315.752924) (xy 73.629 -315.707648)
			(xy 73.655303 -315.666052) (xy 73.687938 -315.629215) (xy 73.726059 -315.59809) (xy 73.76868 -315.573483)
			(xy 73.814696 -315.556031) (xy 73.862915 -315.546187) (xy 73.91209 -315.544206) (xy 73.960945 -315.550138)
			(xy 74.008216 -315.56383) (xy 74.052678 -315.584928) (xy 74.093181 -315.612884) (xy 74.128674 -315.646976)
			(xy 74.158239 -315.68632) (xy 74.18111 -315.729897) (xy 74.196694 -315.776578) (xy 74.204589 -315.825155)
			(xy 74.205084 -315.849762) (xy 74.544186 -315.849762) (xy 74.548146 -315.800708) (xy 74.559923 -315.752924)
			(xy 74.579214 -315.707648) (xy 74.605517 -315.666052) (xy 74.638152 -315.629215) (xy 74.676273 -315.59809)
			(xy 74.718894 -315.573483) (xy 74.76491 -315.556031) (xy 74.813129 -315.546187) (xy 74.862304 -315.544206)
			(xy 74.911159 -315.550138) (xy 74.95843 -315.56383) (xy 75.002892 -315.584928) (xy 75.043395 -315.612884)
			(xy 75.078888 -315.646976) (xy 75.108453 -315.68632) (xy 75.131324 -315.729897) (xy 75.146908 -315.776578)
			(xy 75.154803 -315.825155) (xy 75.155298 -315.849762) (xy 75.494146 -315.849762) (xy 75.498106 -315.800708)
			(xy 75.509883 -315.752924) (xy 75.529174 -315.707648) (xy 75.555477 -315.666052) (xy 75.588112 -315.629215)
			(xy 75.626233 -315.59809) (xy 75.668854 -315.573483) (xy 75.71487 -315.556031) (xy 75.763089 -315.546187)
			(xy 75.812264 -315.544206) (xy 75.861119 -315.550138) (xy 75.90839 -315.56383) (xy 75.952852 -315.584928)
			(xy 75.993355 -315.612884) (xy 76.028848 -315.646976) (xy 76.058413 -315.68632) (xy 76.081284 -315.729897)
			(xy 76.096868 -315.776578) (xy 76.104763 -315.825155) (xy 76.105258 -315.849762) (xy 76.444106 -315.849762)
			(xy 76.448066 -315.800708) (xy 76.459843 -315.752924) (xy 76.479134 -315.707648) (xy 76.505437 -315.666052)
			(xy 76.538072 -315.629215) (xy 76.576193 -315.59809) (xy 76.618814 -315.573483) (xy 76.66483 -315.556031)
			(xy 76.713049 -315.546187) (xy 76.762224 -315.544206) (xy 76.811079 -315.550138) (xy 76.85835 -315.56383)
			(xy 76.902812 -315.584928) (xy 76.943315 -315.612884) (xy 76.978808 -315.646976) (xy 77.008373 -315.68632)
			(xy 77.031244 -315.729897) (xy 77.046828 -315.776578) (xy 77.054723 -315.825155) (xy 77.055218 -315.849762)
			(xy 77.394066 -315.849762) (xy 77.398026 -315.800708) (xy 77.409803 -315.752924) (xy 77.429094 -315.707648)
			(xy 77.455397 -315.666052) (xy 77.488032 -315.629215) (xy 77.526153 -315.59809) (xy 77.568774 -315.573483)
			(xy 77.61479 -315.556031) (xy 77.663009 -315.546187) (xy 77.712184 -315.544206) (xy 77.761039 -315.550138)
			(xy 77.80831 -315.56383) (xy 77.852772 -315.584928) (xy 77.893275 -315.612884) (xy 77.928768 -315.646976)
			(xy 77.958333 -315.68632) (xy 77.981204 -315.729897) (xy 77.996788 -315.776578) (xy 78.004683 -315.825155)
			(xy 78.005178 -315.849762) (xy 78.344026 -315.849762) (xy 78.347986 -315.800708) (xy 78.359763 -315.752924)
			(xy 78.379054 -315.707648) (xy 78.405357 -315.666052) (xy 78.437992 -315.629215) (xy 78.476113 -315.59809)
			(xy 78.518734 -315.573483) (xy 78.56475 -315.556031) (xy 78.612969 -315.546187) (xy 78.662144 -315.544206)
			(xy 78.710999 -315.550138) (xy 78.75827 -315.56383) (xy 78.802732 -315.584928) (xy 78.843235 -315.612884)
			(xy 78.878728 -315.646976) (xy 78.908293 -315.68632) (xy 78.931164 -315.729897) (xy 78.946748 -315.776578)
			(xy 78.954643 -315.825155) (xy 78.955138 -315.849762) (xy 79.293986 -315.849762) (xy 79.297946 -315.800708)
			(xy 79.309723 -315.752924) (xy 79.329014 -315.707648) (xy 79.355317 -315.666052) (xy 79.387952 -315.629215)
			(xy 79.426073 -315.59809) (xy 79.468694 -315.573483) (xy 79.51471 -315.556031) (xy 79.562929 -315.546187)
			(xy 79.612104 -315.544206) (xy 79.660959 -315.550138) (xy 79.70823 -315.56383) (xy 79.752692 -315.584928)
			(xy 79.793195 -315.612884) (xy 79.828688 -315.646976) (xy 79.858253 -315.68632) (xy 79.881124 -315.729897)
			(xy 79.896708 -315.776578) (xy 79.904603 -315.825155) (xy 79.905098 -315.849762) (xy 80.243946 -315.849762)
			(xy 80.247906 -315.800708) (xy 80.259683 -315.752924) (xy 80.278974 -315.707648) (xy 80.305277 -315.666052)
			(xy 80.337912 -315.629215) (xy 80.376033 -315.59809) (xy 80.418654 -315.573483) (xy 80.46467 -315.556031)
			(xy 80.512889 -315.546187) (xy 80.562064 -315.544206) (xy 80.610919 -315.550138) (xy 80.65819 -315.56383)
			(xy 80.702652 -315.584928) (xy 80.743155 -315.612884) (xy 80.778648 -315.646976) (xy 80.808213 -315.68632)
			(xy 80.831084 -315.729897) (xy 80.846668 -315.776578) (xy 80.854563 -315.825155) (xy 80.855058 -315.849762)
			(xy 81.19416 -315.849762) (xy 81.19812 -315.800708) (xy 81.209897 -315.752924) (xy 81.229188 -315.707648)
			(xy 81.255491 -315.666052) (xy 81.288126 -315.629215) (xy 81.326247 -315.59809) (xy 81.368868 -315.573483)
			(xy 81.414884 -315.556031) (xy 81.463103 -315.546187) (xy 81.512278 -315.544206) (xy 81.561133 -315.550138)
			(xy 81.608404 -315.56383) (xy 81.652866 -315.584928) (xy 81.693369 -315.612884) (xy 81.728862 -315.646976)
			(xy 81.758427 -315.68632) (xy 81.781298 -315.729897) (xy 81.796882 -315.776578) (xy 81.804777 -315.825155)
			(xy 81.805272 -315.849762) (xy 82.14412 -315.849762) (xy 82.14808 -315.800708) (xy 82.159857 -315.752924)
			(xy 82.179148 -315.707648) (xy 82.205451 -315.666052) (xy 82.238086 -315.629215) (xy 82.276207 -315.59809)
			(xy 82.318828 -315.573483) (xy 82.364844 -315.556031) (xy 82.413063 -315.546187) (xy 82.462238 -315.544206)
			(xy 82.511093 -315.550138) (xy 82.558364 -315.56383) (xy 82.602826 -315.584928) (xy 82.643329 -315.612884)
			(xy 82.678822 -315.646976) (xy 82.708387 -315.68632) (xy 82.731258 -315.729897) (xy 82.746842 -315.776578)
			(xy 82.754737 -315.825155) (xy 82.755232 -315.849762) (xy 82.754737 -315.874369) (xy 82.746842 -315.922946)
			(xy 82.731258 -315.969627) (xy 82.708387 -316.013204) (xy 82.678822 -316.052548) (xy 82.643329 -316.08664)
			(xy 82.602826 -316.114596) (xy 82.558364 -316.135694) (xy 82.511093 -316.149386) (xy 82.462238 -316.155318)
			(xy 82.413063 -316.153337) (xy 82.364844 -316.143493) (xy 82.318828 -316.126041) (xy 82.276207 -316.101434)
			(xy 82.238086 -316.070309) (xy 82.205451 -316.033472) (xy 82.179148 -315.991876) (xy 82.159857 -315.9466)
			(xy 82.14808 -315.898816) (xy 82.14412 -315.849762) (xy 81.805272 -315.849762) (xy 81.804777 -315.874369)
			(xy 81.796882 -315.922946) (xy 81.781298 -315.969627) (xy 81.758427 -316.013204) (xy 81.728862 -316.052548)
			(xy 81.693369 -316.08664) (xy 81.652866 -316.114596) (xy 81.608404 -316.135694) (xy 81.561133 -316.149386)
			(xy 81.512278 -316.155318) (xy 81.463103 -316.153337) (xy 81.414884 -316.143493) (xy 81.368868 -316.126041)
			(xy 81.326247 -316.101434) (xy 81.288126 -316.070309) (xy 81.255491 -316.033472) (xy 81.229188 -315.991876)
			(xy 81.209897 -315.9466) (xy 81.19812 -315.898816) (xy 81.19416 -315.849762) (xy 80.855058 -315.849762)
			(xy 80.854563 -315.874369) (xy 80.846668 -315.922946) (xy 80.831084 -315.969627) (xy 80.808213 -316.013204)
			(xy 80.778648 -316.052548) (xy 80.743155 -316.08664) (xy 80.702652 -316.114596) (xy 80.65819 -316.135694)
			(xy 80.610919 -316.149386) (xy 80.562064 -316.155318) (xy 80.512889 -316.153337) (xy 80.46467 -316.143493)
			(xy 80.418654 -316.126041) (xy 80.376033 -316.101434) (xy 80.337912 -316.070309) (xy 80.305277 -316.033472)
			(xy 80.278974 -315.991876) (xy 80.259683 -315.9466) (xy 80.247906 -315.898816) (xy 80.243946 -315.849762)
			(xy 79.905098 -315.849762) (xy 79.904603 -315.874369) (xy 79.896708 -315.922946) (xy 79.881124 -315.969627)
			(xy 79.858253 -316.013204) (xy 79.828688 -316.052548) (xy 79.793195 -316.08664) (xy 79.752692 -316.114596)
			(xy 79.70823 -316.135694) (xy 79.660959 -316.149386) (xy 79.612104 -316.155318) (xy 79.562929 -316.153337)
			(xy 79.51471 -316.143493) (xy 79.468694 -316.126041) (xy 79.426073 -316.101434) (xy 79.387952 -316.070309)
			(xy 79.355317 -316.033472) (xy 79.329014 -315.991876) (xy 79.309723 -315.9466) (xy 79.297946 -315.898816)
			(xy 79.293986 -315.849762) (xy 78.955138 -315.849762) (xy 78.954643 -315.874369) (xy 78.946748 -315.922946)
			(xy 78.931164 -315.969627) (xy 78.908293 -316.013204) (xy 78.878728 -316.052548) (xy 78.843235 -316.08664)
			(xy 78.802732 -316.114596) (xy 78.75827 -316.135694) (xy 78.710999 -316.149386) (xy 78.662144 -316.155318)
			(xy 78.612969 -316.153337) (xy 78.56475 -316.143493) (xy 78.518734 -316.126041) (xy 78.476113 -316.101434)
			(xy 78.437992 -316.070309) (xy 78.405357 -316.033472) (xy 78.379054 -315.991876) (xy 78.359763 -315.9466)
			(xy 78.347986 -315.898816) (xy 78.344026 -315.849762) (xy 78.005178 -315.849762) (xy 78.004683 -315.874369)
			(xy 77.996788 -315.922946) (xy 77.981204 -315.969627) (xy 77.958333 -316.013204) (xy 77.928768 -316.052548)
			(xy 77.893275 -316.08664) (xy 77.852772 -316.114596) (xy 77.80831 -316.135694) (xy 77.761039 -316.149386)
			(xy 77.712184 -316.155318) (xy 77.663009 -316.153337) (xy 77.61479 -316.143493) (xy 77.568774 -316.126041)
			(xy 77.526153 -316.101434) (xy 77.488032 -316.070309) (xy 77.455397 -316.033472) (xy 77.429094 -315.991876)
			(xy 77.409803 -315.9466) (xy 77.398026 -315.898816) (xy 77.394066 -315.849762) (xy 77.055218 -315.849762)
			(xy 77.054723 -315.874369) (xy 77.046828 -315.922946) (xy 77.031244 -315.969627) (xy 77.008373 -316.013204)
			(xy 76.978808 -316.052548) (xy 76.943315 -316.08664) (xy 76.902812 -316.114596) (xy 76.85835 -316.135694)
			(xy 76.811079 -316.149386) (xy 76.762224 -316.155318) (xy 76.713049 -316.153337) (xy 76.66483 -316.143493)
			(xy 76.618814 -316.126041) (xy 76.576193 -316.101434) (xy 76.538072 -316.070309) (xy 76.505437 -316.033472)
			(xy 76.479134 -315.991876) (xy 76.459843 -315.9466) (xy 76.448066 -315.898816) (xy 76.444106 -315.849762)
			(xy 76.105258 -315.849762) (xy 76.104763 -315.874369) (xy 76.096868 -315.922946) (xy 76.081284 -315.969627)
			(xy 76.058413 -316.013204) (xy 76.028848 -316.052548) (xy 75.993355 -316.08664) (xy 75.952852 -316.114596)
			(xy 75.90839 -316.135694) (xy 75.861119 -316.149386) (xy 75.812264 -316.155318) (xy 75.763089 -316.153337)
			(xy 75.71487 -316.143493) (xy 75.668854 -316.126041) (xy 75.626233 -316.101434) (xy 75.588112 -316.070309)
			(xy 75.555477 -316.033472) (xy 75.529174 -315.991876) (xy 75.509883 -315.9466) (xy 75.498106 -315.898816)
			(xy 75.494146 -315.849762) (xy 75.155298 -315.849762) (xy 75.154803 -315.874369) (xy 75.146908 -315.922946)
			(xy 75.131324 -315.969627) (xy 75.108453 -316.013204) (xy 75.078888 -316.052548) (xy 75.043395 -316.08664)
			(xy 75.002892 -316.114596) (xy 74.95843 -316.135694) (xy 74.911159 -316.149386) (xy 74.862304 -316.155318)
			(xy 74.813129 -316.153337) (xy 74.76491 -316.143493) (xy 74.718894 -316.126041) (xy 74.676273 -316.101434)
			(xy 74.638152 -316.070309) (xy 74.605517 -316.033472) (xy 74.579214 -315.991876) (xy 74.559923 -315.9466)
			(xy 74.548146 -315.898816) (xy 74.544186 -315.849762) (xy 74.205084 -315.849762) (xy 74.204589 -315.874369)
			(xy 74.196694 -315.922946) (xy 74.18111 -315.969627) (xy 74.158239 -316.013204) (xy 74.128674 -316.052548)
			(xy 74.093181 -316.08664) (xy 74.052678 -316.114596) (xy 74.008216 -316.135694) (xy 73.960945 -316.149386)
			(xy 73.91209 -316.155318) (xy 73.862915 -316.153337) (xy 73.814696 -316.143493) (xy 73.76868 -316.126041)
			(xy 73.726059 -316.101434) (xy 73.687938 -316.070309) (xy 73.655303 -316.033472) (xy 73.629 -315.991876)
			(xy 73.609709 -315.9466) (xy 73.597932 -315.898816) (xy 73.593972 -315.849762) (xy 73.255124 -315.849762)
			(xy 73.254629 -315.874369) (xy 73.246734 -315.922946) (xy 73.23115 -315.969627) (xy 73.208279 -316.013204)
			(xy 73.178714 -316.052548) (xy 73.143221 -316.08664) (xy 73.102718 -316.114596) (xy 73.058256 -316.135694)
			(xy 73.010985 -316.149386) (xy 72.96213 -316.155318) (xy 72.912955 -316.153337) (xy 72.864736 -316.143493)
			(xy 72.81872 -316.126041) (xy 72.776099 -316.101434) (xy 72.737978 -316.070309) (xy 72.705343 -316.033472)
			(xy 72.67904 -315.991876) (xy 72.659749 -315.9466) (xy 72.647972 -315.898816) (xy 72.644012 -315.849762)
			(xy 72.327008 -315.849762) (xy 72.326504 -315.87547) (xy 72.318461 -315.926252) (xy 72.302573 -315.975151)
			(xy 72.27923 -316.020963) (xy 72.249009 -316.062559) (xy 72.212653 -316.098915) (xy 72.171057 -316.129136)
			(xy 72.125245 -316.152479) (xy 72.076346 -316.168367) (xy 72.025564 -316.17641) (xy 71.974148 -316.17641)
			(xy 71.923366 -316.168367) (xy 71.874467 -316.152479) (xy 71.828655 -316.129136) (xy 71.787059 -316.098915)
			(xy 71.750703 -316.062559) (xy 71.720482 -316.020963) (xy 71.697139 -315.975151) (xy 71.681251 -315.926252)
			(xy 71.673208 -315.87547) (xy 71.35453 -315.87547) (xy 71.346814 -315.922946) (xy 71.33123 -315.969627)
			(xy 71.308359 -316.013204) (xy 71.278794 -316.052548) (xy 71.243301 -316.08664) (xy 71.202798 -316.114596)
			(xy 71.158336 -316.135694) (xy 71.111065 -316.149386) (xy 71.06221 -316.155318) (xy 71.013035 -316.153337)
			(xy 70.964816 -316.143493) (xy 70.9188 -316.126041) (xy 70.876179 -316.101434) (xy 70.838058 -316.070309)
			(xy 70.805423 -316.033472) (xy 70.77912 -315.991876) (xy 70.759829 -315.9466) (xy 70.748052 -315.898816)
			(xy 70.744092 -315.849762) (xy 70.427088 -315.849762) (xy 70.426584 -315.87547) (xy 70.418541 -315.926252)
			(xy 70.402653 -315.975151) (xy 70.37931 -316.020963) (xy 70.349089 -316.062559) (xy 70.312733 -316.098915)
			(xy 70.271137 -316.129136) (xy 70.225325 -316.152479) (xy 70.176426 -316.168367) (xy 70.125644 -316.17641)
			(xy 70.074228 -316.17641) (xy 70.023446 -316.168367) (xy 69.974547 -316.152479) (xy 69.928735 -316.129136)
			(xy 69.887139 -316.098915) (xy 69.850783 -316.062559) (xy 69.820562 -316.020963) (xy 69.797219 -315.975151)
			(xy 69.781331 -315.926252) (xy 69.773288 -315.87547) (xy 69.45461 -315.87547) (xy 69.446894 -315.922946)
			(xy 69.43131 -315.969627) (xy 69.408439 -316.013204) (xy 69.378874 -316.052548) (xy 69.343381 -316.08664)
			(xy 69.302878 -316.114596) (xy 69.258416 -316.135694) (xy 69.211145 -316.149386) (xy 69.16229 -316.155318)
			(xy 69.113115 -316.153337) (xy 69.064896 -316.143493) (xy 69.01888 -316.126041) (xy 68.976259 -316.101434)
			(xy 68.938138 -316.070309) (xy 68.905503 -316.033472) (xy 68.8792 -315.991876) (xy 68.859909 -315.9466)
			(xy 68.848132 -315.898816) (xy 68.844172 -315.849762) (xy 68.526914 -315.849762) (xy 68.52641 -315.87547)
			(xy 68.518367 -315.926252) (xy 68.502479 -315.975151) (xy 68.479136 -316.020963) (xy 68.448915 -316.062559)
			(xy 68.412559 -316.098915) (xy 68.370963 -316.129136) (xy 68.325151 -316.152479) (xy 68.276252 -316.168367)
			(xy 68.22547 -316.17641) (xy 68.174054 -316.17641) (xy 68.123272 -316.168367) (xy 68.074373 -316.152479)
			(xy 68.028561 -316.129136) (xy 67.986965 -316.098915) (xy 67.950609 -316.062559) (xy 67.920388 -316.020963)
			(xy 67.897045 -315.975151) (xy 67.881157 -315.926252) (xy 67.873114 -315.87547) (xy 67.553626 -315.87547)
			(xy 67.550148 -315.907442) (xy 67.536866 -315.955272) (xy 67.516022 -316.000323) (xy 67.488164 -316.041409)
			(xy 67.454026 -316.077447) (xy 67.414507 -316.107488) (xy 67.37065 -316.130739) (xy 67.323608 -316.146589)
			(xy 67.274622 -316.15462) (xy 67.249802 -316.15507) (xy 67.240701 -316.155031) (xy 67.222528 -316.154014)
			(xy 67.21348 -316.153038) (xy 67.201542 -316.151514) (xy 67.17919 -316.159388) (xy 67.106292 -316.235842)
			(xy 67.09918 -316.258448) (xy 67.101212 -316.270386) (xy 67.10334 -316.283874) (xy 67.105627 -316.311088)
			(xy 67.105784 -316.324742) (xy 67.105784 -316.3951) (xy 67.106243 -316.405759) (xy 67.114924 -316.425229)
			(xy 67.122548 -316.432692) (xy 67.18681 -316.490604) (xy 67.20713 -316.497208) (xy 67.218052 -316.496192)
			(xy 67.249802 -316.494414) (xy 67.273794 -316.49486) (xy 67.321188 -316.502367) (xy 67.366824 -316.517196)
			(xy 67.409579 -316.538982) (xy 67.448398 -316.567188) (xy 67.482327 -316.60112) (xy 67.51053 -316.639942)
			(xy 67.532313 -316.682698) (xy 67.547138 -316.728335) (xy 67.554642 -316.77573) (xy 67.55511 -316.799722)
			(xy 67.554934 -316.813968) (xy 67.552264 -316.842336) (xy 67.549776 -316.856364) (xy 67.54749 -316.868556)
			(xy 67.554856 -316.892686) (xy 67.632072 -316.969902) (xy 67.655948 -316.977268) (xy 67.668394 -316.974982)
			(xy 67.682359 -316.972496) (xy 67.710599 -316.969823) (xy 67.724782 -316.969648) (xy 67.734653 -316.969729)
			(xy 67.754353 -316.971) (xy 67.764152 -316.972188) (xy 67.77609 -316.973712) (xy 67.79895 -316.965838)
			(xy 67.872356 -316.889384) (xy 67.879468 -316.866524) (xy 67.877436 -316.854332) (xy 67.875298 -316.840781)
			(xy 67.873009 -316.81344) (xy 67.872864 -316.799722) (xy 67.87334 -316.774028) (xy 67.881376 -316.723273)
			(xy 67.897253 -316.674399) (xy 67.92058 -316.628611) (xy 67.950783 -316.587036) (xy 67.987118 -316.550699)
			(xy 68.028691 -316.520492) (xy 68.074477 -316.497162) (xy 68.123349 -316.481281) (xy 68.174104 -316.473242)
			(xy 68.225492 -316.473241) (xy 68.276247 -316.48128) (xy 68.325119 -316.49716) (xy 68.370906 -316.52049)
			(xy 68.412479 -316.550696) (xy 68.448814 -316.587033) (xy 68.479018 -316.628608) (xy 68.502346 -316.674395)
			(xy 68.518224 -316.723269) (xy 68.52626 -316.774024) (xy 68.526258 -316.799722) (xy 68.844172 -316.799722)
			(xy 68.848132 -316.750668) (xy 68.859909 -316.702884) (xy 68.8792 -316.657608) (xy 68.905503 -316.616012)
			(xy 68.938138 -316.579175) (xy 68.976259 -316.54805) (xy 69.01888 -316.523443) (xy 69.064896 -316.505991)
			(xy 69.113115 -316.496147) (xy 69.16229 -316.494166) (xy 69.211145 -316.500098) (xy 69.258416 -316.51379)
			(xy 69.302878 -316.534888) (xy 69.343381 -316.562844) (xy 69.378874 -316.596936) (xy 69.408439 -316.63628)
			(xy 69.43131 -316.679857) (xy 69.446894 -316.726538) (xy 69.454789 -316.775115) (xy 69.455284 -316.799722)
			(xy 69.454789 -316.824329) (xy 69.45461 -316.82543) (xy 69.773288 -316.82543) (xy 69.773288 -316.774014)
			(xy 69.781331 -316.723232) (xy 69.797219 -316.674333) (xy 69.820562 -316.628521) (xy 69.850783 -316.586925)
			(xy 69.887139 -316.550569) (xy 69.928735 -316.520348) (xy 69.974547 -316.497005) (xy 70.023446 -316.481117)
			(xy 70.074228 -316.473074) (xy 70.125644 -316.473074) (xy 70.176426 -316.481117) (xy 70.225325 -316.497005)
			(xy 70.271137 -316.520348) (xy 70.312733 -316.550569) (xy 70.349089 -316.586925) (xy 70.37931 -316.628521)
			(xy 70.402653 -316.674333) (xy 70.418541 -316.723232) (xy 70.426584 -316.774014) (xy 70.427088 -316.799722)
			(xy 70.744092 -316.799722) (xy 70.748052 -316.750668) (xy 70.759829 -316.702884) (xy 70.77912 -316.657608)
			(xy 70.805423 -316.616012) (xy 70.838058 -316.579175) (xy 70.876179 -316.54805) (xy 70.9188 -316.523443)
			(xy 70.964816 -316.505991) (xy 71.013035 -316.496147) (xy 71.06221 -316.494166) (xy 71.111065 -316.500098)
			(xy 71.158336 -316.51379) (xy 71.202798 -316.534888) (xy 71.243301 -316.562844) (xy 71.278794 -316.596936)
			(xy 71.308359 -316.63628) (xy 71.33123 -316.679857) (xy 71.346814 -316.726538) (xy 71.354709 -316.775115)
			(xy 71.355204 -316.799722) (xy 71.354709 -316.824329) (xy 71.35453 -316.82543) (xy 71.673208 -316.82543)
			(xy 71.673208 -316.774014) (xy 71.681251 -316.723232) (xy 71.697139 -316.674333) (xy 71.720482 -316.628521)
			(xy 71.750703 -316.586925) (xy 71.787059 -316.550569) (xy 71.828655 -316.520348) (xy 71.874467 -316.497005)
			(xy 71.923366 -316.481117) (xy 71.974148 -316.473074) (xy 72.025564 -316.473074) (xy 72.076346 -316.481117)
			(xy 72.125245 -316.497005) (xy 72.171057 -316.520348) (xy 72.212653 -316.550569) (xy 72.249009 -316.586925)
			(xy 72.27923 -316.628521) (xy 72.302573 -316.674333) (xy 72.318461 -316.723232) (xy 72.326504 -316.774014)
			(xy 72.327008 -316.799722) (xy 72.644012 -316.799722) (xy 72.647972 -316.750668) (xy 72.659749 -316.702884)
			(xy 72.67904 -316.657608) (xy 72.705343 -316.616012) (xy 72.737978 -316.579175) (xy 72.776099 -316.54805)
			(xy 72.81872 -316.523443) (xy 72.864736 -316.505991) (xy 72.912955 -316.496147) (xy 72.96213 -316.494166)
			(xy 73.010985 -316.500098) (xy 73.058256 -316.51379) (xy 73.102718 -316.534888) (xy 73.143221 -316.562844)
			(xy 73.178714 -316.596936) (xy 73.208279 -316.63628) (xy 73.23115 -316.679857) (xy 73.246734 -316.726538)
			(xy 73.254629 -316.775115) (xy 73.255124 -316.799722) (xy 73.593972 -316.799722) (xy 73.597932 -316.750668)
			(xy 73.609709 -316.702884) (xy 73.629 -316.657608) (xy 73.655303 -316.616012) (xy 73.687938 -316.579175)
			(xy 73.726059 -316.54805) (xy 73.76868 -316.523443) (xy 73.814696 -316.505991) (xy 73.862915 -316.496147)
			(xy 73.91209 -316.494166) (xy 73.960945 -316.500098) (xy 74.008216 -316.51379) (xy 74.052678 -316.534888)
			(xy 74.093181 -316.562844) (xy 74.128674 -316.596936) (xy 74.158239 -316.63628) (xy 74.18111 -316.679857)
			(xy 74.196694 -316.726538) (xy 74.204589 -316.775115) (xy 74.205084 -316.799722) (xy 74.544186 -316.799722)
			(xy 74.548146 -316.750668) (xy 74.559923 -316.702884) (xy 74.579214 -316.657608) (xy 74.605517 -316.616012)
			(xy 74.638152 -316.579175) (xy 74.676273 -316.54805) (xy 74.718894 -316.523443) (xy 74.76491 -316.505991)
			(xy 74.813129 -316.496147) (xy 74.862304 -316.494166) (xy 74.911159 -316.500098) (xy 74.95843 -316.51379)
			(xy 75.002892 -316.534888) (xy 75.043395 -316.562844) (xy 75.078888 -316.596936) (xy 75.108453 -316.63628)
			(xy 75.131324 -316.679857) (xy 75.146908 -316.726538) (xy 75.154803 -316.775115) (xy 75.155298 -316.799722)
			(xy 75.494146 -316.799722) (xy 75.498106 -316.750668) (xy 75.509883 -316.702884) (xy 75.529174 -316.657608)
			(xy 75.555477 -316.616012) (xy 75.588112 -316.579175) (xy 75.626233 -316.54805) (xy 75.668854 -316.523443)
			(xy 75.71487 -316.505991) (xy 75.763089 -316.496147) (xy 75.812264 -316.494166) (xy 75.861119 -316.500098)
			(xy 75.90839 -316.51379) (xy 75.952852 -316.534888) (xy 75.993355 -316.562844) (xy 76.028848 -316.596936)
			(xy 76.058413 -316.63628) (xy 76.081284 -316.679857) (xy 76.096868 -316.726538) (xy 76.104763 -316.775115)
			(xy 76.105258 -316.799722) (xy 76.444106 -316.799722) (xy 76.448066 -316.750668) (xy 76.459843 -316.702884)
			(xy 76.479134 -316.657608) (xy 76.505437 -316.616012) (xy 76.538072 -316.579175) (xy 76.576193 -316.54805)
			(xy 76.618814 -316.523443) (xy 76.66483 -316.505991) (xy 76.713049 -316.496147) (xy 76.762224 -316.494166)
			(xy 76.811079 -316.500098) (xy 76.85835 -316.51379) (xy 76.902812 -316.534888) (xy 76.943315 -316.562844)
			(xy 76.978808 -316.596936) (xy 77.008373 -316.63628) (xy 77.031244 -316.679857) (xy 77.046828 -316.726538)
			(xy 77.054723 -316.775115) (xy 77.055218 -316.799722) (xy 77.394066 -316.799722) (xy 77.398026 -316.750668)
			(xy 77.409803 -316.702884) (xy 77.429094 -316.657608) (xy 77.455397 -316.616012) (xy 77.488032 -316.579175)
			(xy 77.526153 -316.54805) (xy 77.568774 -316.523443) (xy 77.61479 -316.505991) (xy 77.663009 -316.496147)
			(xy 77.712184 -316.494166) (xy 77.761039 -316.500098) (xy 77.80831 -316.51379) (xy 77.852772 -316.534888)
			(xy 77.893275 -316.562844) (xy 77.928768 -316.596936) (xy 77.958333 -316.63628) (xy 77.981204 -316.679857)
			(xy 77.996788 -316.726538) (xy 78.004683 -316.775115) (xy 78.005178 -316.799722) (xy 78.344026 -316.799722)
			(xy 78.347986 -316.750668) (xy 78.359763 -316.702884) (xy 78.379054 -316.657608) (xy 78.405357 -316.616012)
			(xy 78.437992 -316.579175) (xy 78.476113 -316.54805) (xy 78.518734 -316.523443) (xy 78.56475 -316.505991)
			(xy 78.612969 -316.496147) (xy 78.662144 -316.494166) (xy 78.710999 -316.500098) (xy 78.75827 -316.51379)
			(xy 78.802732 -316.534888) (xy 78.843235 -316.562844) (xy 78.878728 -316.596936) (xy 78.908293 -316.63628)
			(xy 78.931164 -316.679857) (xy 78.946748 -316.726538) (xy 78.954643 -316.775115) (xy 78.955138 -316.799722)
			(xy 79.293986 -316.799722) (xy 79.297946 -316.750668) (xy 79.309723 -316.702884) (xy 79.329014 -316.657608)
			(xy 79.355317 -316.616012) (xy 79.387952 -316.579175) (xy 79.426073 -316.54805) (xy 79.468694 -316.523443)
			(xy 79.51471 -316.505991) (xy 79.562929 -316.496147) (xy 79.612104 -316.494166) (xy 79.660959 -316.500098)
			(xy 79.70823 -316.51379) (xy 79.752692 -316.534888) (xy 79.793195 -316.562844) (xy 79.828688 -316.596936)
			(xy 79.858253 -316.63628) (xy 79.881124 -316.679857) (xy 79.896708 -316.726538) (xy 79.904603 -316.775115)
			(xy 79.905098 -316.799722) (xy 80.243946 -316.799722) (xy 80.247906 -316.750668) (xy 80.259683 -316.702884)
			(xy 80.278974 -316.657608) (xy 80.305277 -316.616012) (xy 80.337912 -316.579175) (xy 80.376033 -316.54805)
			(xy 80.418654 -316.523443) (xy 80.46467 -316.505991) (xy 80.512889 -316.496147) (xy 80.562064 -316.494166)
			(xy 80.610919 -316.500098) (xy 80.65819 -316.51379) (xy 80.702652 -316.534888) (xy 80.743155 -316.562844)
			(xy 80.778648 -316.596936) (xy 80.808213 -316.63628) (xy 80.831084 -316.679857) (xy 80.846668 -316.726538)
			(xy 80.854563 -316.775115) (xy 80.855058 -316.799722) (xy 81.19416 -316.799722) (xy 81.19812 -316.750668)
			(xy 81.209897 -316.702884) (xy 81.229188 -316.657608) (xy 81.255491 -316.616012) (xy 81.288126 -316.579175)
			(xy 81.326247 -316.54805) (xy 81.368868 -316.523443) (xy 81.414884 -316.505991) (xy 81.463103 -316.496147)
			(xy 81.512278 -316.494166) (xy 81.561133 -316.500098) (xy 81.608404 -316.51379) (xy 81.652866 -316.534888)
			(xy 81.693369 -316.562844) (xy 81.728862 -316.596936) (xy 81.758427 -316.63628) (xy 81.781298 -316.679857)
			(xy 81.796882 -316.726538) (xy 81.804777 -316.775115) (xy 81.805272 -316.799722) (xy 82.14412 -316.799722)
			(xy 82.14808 -316.750668) (xy 82.159857 -316.702884) (xy 82.179148 -316.657608) (xy 82.205451 -316.616012)
			(xy 82.238086 -316.579175) (xy 82.276207 -316.54805) (xy 82.318828 -316.523443) (xy 82.364844 -316.505991)
			(xy 82.413063 -316.496147) (xy 82.462238 -316.494166) (xy 82.511093 -316.500098) (xy 82.558364 -316.51379)
			(xy 82.602826 -316.534888) (xy 82.643329 -316.562844) (xy 82.678822 -316.596936) (xy 82.708387 -316.63628)
			(xy 82.731258 -316.679857) (xy 82.746842 -316.726538) (xy 82.754737 -316.775115) (xy 82.755232 -316.799722)
			(xy 83.094334 -316.799722) (xy 83.098294 -316.750668) (xy 83.110071 -316.702884) (xy 83.129362 -316.657608)
			(xy 83.155665 -316.616012) (xy 83.1883 -316.579175) (xy 83.226421 -316.54805) (xy 83.269042 -316.523443)
			(xy 83.315058 -316.505991) (xy 83.363277 -316.496147) (xy 83.412452 -316.494166) (xy 83.461307 -316.500098)
			(xy 83.508578 -316.51379) (xy 83.55304 -316.534888) (xy 83.593543 -316.562844) (xy 83.629036 -316.596936)
			(xy 83.658601 -316.63628) (xy 83.681472 -316.679857) (xy 83.697056 -316.726538) (xy 83.704951 -316.775115)
			(xy 83.705446 -316.799722) (xy 83.704951 -316.824329) (xy 83.697056 -316.872906) (xy 83.681472 -316.919587)
			(xy 83.658601 -316.963164) (xy 83.629036 -317.002508) (xy 83.593543 -317.0366) (xy 83.55304 -317.064556)
			(xy 83.508578 -317.085654) (xy 83.461307 -317.099346) (xy 83.412452 -317.105278) (xy 83.363277 -317.103297)
			(xy 83.315058 -317.093453) (xy 83.269042 -317.076001) (xy 83.226421 -317.051394) (xy 83.1883 -317.020269)
			(xy 83.155665 -316.983432) (xy 83.129362 -316.941836) (xy 83.110071 -316.89656) (xy 83.098294 -316.848776)
			(xy 83.094334 -316.799722) (xy 82.755232 -316.799722) (xy 82.754737 -316.824329) (xy 82.746842 -316.872906)
			(xy 82.731258 -316.919587) (xy 82.708387 -316.963164) (xy 82.678822 -317.002508) (xy 82.643329 -317.0366)
			(xy 82.602826 -317.064556) (xy 82.558364 -317.085654) (xy 82.511093 -317.099346) (xy 82.462238 -317.105278)
			(xy 82.413063 -317.103297) (xy 82.364844 -317.093453) (xy 82.318828 -317.076001) (xy 82.276207 -317.051394)
			(xy 82.238086 -317.020269) (xy 82.205451 -316.983432) (xy 82.179148 -316.941836) (xy 82.159857 -316.89656)
			(xy 82.14808 -316.848776) (xy 82.14412 -316.799722) (xy 81.805272 -316.799722) (xy 81.804777 -316.824329)
			(xy 81.796882 -316.872906) (xy 81.781298 -316.919587) (xy 81.758427 -316.963164) (xy 81.728862 -317.002508)
			(xy 81.693369 -317.0366) (xy 81.652866 -317.064556) (xy 81.608404 -317.085654) (xy 81.561133 -317.099346)
			(xy 81.512278 -317.105278) (xy 81.463103 -317.103297) (xy 81.414884 -317.093453) (xy 81.368868 -317.076001)
			(xy 81.326247 -317.051394) (xy 81.288126 -317.020269) (xy 81.255491 -316.983432) (xy 81.229188 -316.941836)
			(xy 81.209897 -316.89656) (xy 81.19812 -316.848776) (xy 81.19416 -316.799722) (xy 80.855058 -316.799722)
			(xy 80.854563 -316.824329) (xy 80.846668 -316.872906) (xy 80.831084 -316.919587) (xy 80.808213 -316.963164)
			(xy 80.778648 -317.002508) (xy 80.743155 -317.0366) (xy 80.702652 -317.064556) (xy 80.65819 -317.085654)
			(xy 80.610919 -317.099346) (xy 80.562064 -317.105278) (xy 80.512889 -317.103297) (xy 80.46467 -317.093453)
			(xy 80.418654 -317.076001) (xy 80.376033 -317.051394) (xy 80.337912 -317.020269) (xy 80.305277 -316.983432)
			(xy 80.278974 -316.941836) (xy 80.259683 -316.89656) (xy 80.247906 -316.848776) (xy 80.243946 -316.799722)
			(xy 79.905098 -316.799722) (xy 79.904603 -316.824329) (xy 79.896708 -316.872906) (xy 79.881124 -316.919587)
			(xy 79.858253 -316.963164) (xy 79.828688 -317.002508) (xy 79.793195 -317.0366) (xy 79.752692 -317.064556)
			(xy 79.70823 -317.085654) (xy 79.660959 -317.099346) (xy 79.612104 -317.105278) (xy 79.562929 -317.103297)
			(xy 79.51471 -317.093453) (xy 79.468694 -317.076001) (xy 79.426073 -317.051394) (xy 79.387952 -317.020269)
			(xy 79.355317 -316.983432) (xy 79.329014 -316.941836) (xy 79.309723 -316.89656) (xy 79.297946 -316.848776)
			(xy 79.293986 -316.799722) (xy 78.955138 -316.799722) (xy 78.954643 -316.824329) (xy 78.946748 -316.872906)
			(xy 78.931164 -316.919587) (xy 78.908293 -316.963164) (xy 78.878728 -317.002508) (xy 78.843235 -317.0366)
			(xy 78.802732 -317.064556) (xy 78.75827 -317.085654) (xy 78.710999 -317.099346) (xy 78.662144 -317.105278)
			(xy 78.612969 -317.103297) (xy 78.56475 -317.093453) (xy 78.518734 -317.076001) (xy 78.476113 -317.051394)
			(xy 78.437992 -317.020269) (xy 78.405357 -316.983432) (xy 78.379054 -316.941836) (xy 78.359763 -316.89656)
			(xy 78.347986 -316.848776) (xy 78.344026 -316.799722) (xy 78.005178 -316.799722) (xy 78.004683 -316.824329)
			(xy 77.996788 -316.872906) (xy 77.981204 -316.919587) (xy 77.958333 -316.963164) (xy 77.928768 -317.002508)
			(xy 77.893275 -317.0366) (xy 77.852772 -317.064556) (xy 77.80831 -317.085654) (xy 77.761039 -317.099346)
			(xy 77.712184 -317.105278) (xy 77.663009 -317.103297) (xy 77.61479 -317.093453) (xy 77.568774 -317.076001)
			(xy 77.526153 -317.051394) (xy 77.488032 -317.020269) (xy 77.455397 -316.983432) (xy 77.429094 -316.941836)
			(xy 77.409803 -316.89656) (xy 77.398026 -316.848776) (xy 77.394066 -316.799722) (xy 77.055218 -316.799722)
			(xy 77.054723 -316.824329) (xy 77.046828 -316.872906) (xy 77.031244 -316.919587) (xy 77.008373 -316.963164)
			(xy 76.978808 -317.002508) (xy 76.943315 -317.0366) (xy 76.902812 -317.064556) (xy 76.85835 -317.085654)
			(xy 76.811079 -317.099346) (xy 76.762224 -317.105278) (xy 76.713049 -317.103297) (xy 76.66483 -317.093453)
			(xy 76.618814 -317.076001) (xy 76.576193 -317.051394) (xy 76.538072 -317.020269) (xy 76.505437 -316.983432)
			(xy 76.479134 -316.941836) (xy 76.459843 -316.89656) (xy 76.448066 -316.848776) (xy 76.444106 -316.799722)
			(xy 76.105258 -316.799722) (xy 76.104763 -316.824329) (xy 76.096868 -316.872906) (xy 76.081284 -316.919587)
			(xy 76.058413 -316.963164) (xy 76.028848 -317.002508) (xy 75.993355 -317.0366) (xy 75.952852 -317.064556)
			(xy 75.90839 -317.085654) (xy 75.861119 -317.099346) (xy 75.812264 -317.105278) (xy 75.763089 -317.103297)
			(xy 75.71487 -317.093453) (xy 75.668854 -317.076001) (xy 75.626233 -317.051394) (xy 75.588112 -317.020269)
			(xy 75.555477 -316.983432) (xy 75.529174 -316.941836) (xy 75.509883 -316.89656) (xy 75.498106 -316.848776)
			(xy 75.494146 -316.799722) (xy 75.155298 -316.799722) (xy 75.154803 -316.824329) (xy 75.146908 -316.872906)
			(xy 75.131324 -316.919587) (xy 75.108453 -316.963164) (xy 75.078888 -317.002508) (xy 75.043395 -317.0366)
			(xy 75.002892 -317.064556) (xy 74.95843 -317.085654) (xy 74.911159 -317.099346) (xy 74.862304 -317.105278)
			(xy 74.813129 -317.103297) (xy 74.76491 -317.093453) (xy 74.718894 -317.076001) (xy 74.676273 -317.051394)
			(xy 74.638152 -317.020269) (xy 74.605517 -316.983432) (xy 74.579214 -316.941836) (xy 74.559923 -316.89656)
			(xy 74.548146 -316.848776) (xy 74.544186 -316.799722) (xy 74.205084 -316.799722) (xy 74.204589 -316.824329)
			(xy 74.196694 -316.872906) (xy 74.18111 -316.919587) (xy 74.158239 -316.963164) (xy 74.128674 -317.002508)
			(xy 74.093181 -317.0366) (xy 74.052678 -317.064556) (xy 74.008216 -317.085654) (xy 73.960945 -317.099346)
			(xy 73.91209 -317.105278) (xy 73.862915 -317.103297) (xy 73.814696 -317.093453) (xy 73.76868 -317.076001)
			(xy 73.726059 -317.051394) (xy 73.687938 -317.020269) (xy 73.655303 -316.983432) (xy 73.629 -316.941836)
			(xy 73.609709 -316.89656) (xy 73.597932 -316.848776) (xy 73.593972 -316.799722) (xy 73.255124 -316.799722)
			(xy 73.254629 -316.824329) (xy 73.246734 -316.872906) (xy 73.23115 -316.919587) (xy 73.208279 -316.963164)
			(xy 73.178714 -317.002508) (xy 73.143221 -317.0366) (xy 73.102718 -317.064556) (xy 73.058256 -317.085654)
			(xy 73.010985 -317.099346) (xy 72.96213 -317.105278) (xy 72.912955 -317.103297) (xy 72.864736 -317.093453)
			(xy 72.81872 -317.076001) (xy 72.776099 -317.051394) (xy 72.737978 -317.020269) (xy 72.705343 -316.983432)
			(xy 72.67904 -316.941836) (xy 72.659749 -316.89656) (xy 72.647972 -316.848776) (xy 72.644012 -316.799722)
			(xy 72.327008 -316.799722) (xy 72.326504 -316.82543) (xy 72.318461 -316.876212) (xy 72.302573 -316.925111)
			(xy 72.27923 -316.970923) (xy 72.249009 -317.012519) (xy 72.212653 -317.048875) (xy 72.171057 -317.079096)
			(xy 72.125245 -317.102439) (xy 72.076346 -317.118327) (xy 72.025564 -317.12637) (xy 71.974148 -317.12637)
			(xy 71.923366 -317.118327) (xy 71.874467 -317.102439) (xy 71.828655 -317.079096) (xy 71.787059 -317.048875)
			(xy 71.750703 -317.012519) (xy 71.720482 -316.970923) (xy 71.697139 -316.925111) (xy 71.681251 -316.876212)
			(xy 71.673208 -316.82543) (xy 71.35453 -316.82543) (xy 71.346814 -316.872906) (xy 71.33123 -316.919587)
			(xy 71.308359 -316.963164) (xy 71.278794 -317.002508) (xy 71.243301 -317.0366) (xy 71.202798 -317.064556)
			(xy 71.158336 -317.085654) (xy 71.111065 -317.099346) (xy 71.06221 -317.105278) (xy 71.013035 -317.103297)
			(xy 70.964816 -317.093453) (xy 70.9188 -317.076001) (xy 70.876179 -317.051394) (xy 70.838058 -317.020269)
			(xy 70.805423 -316.983432) (xy 70.77912 -316.941836) (xy 70.759829 -316.89656) (xy 70.748052 -316.848776)
			(xy 70.744092 -316.799722) (xy 70.427088 -316.799722) (xy 70.426584 -316.82543) (xy 70.418541 -316.876212)
			(xy 70.402653 -316.925111) (xy 70.37931 -316.970923) (xy 70.349089 -317.012519) (xy 70.312733 -317.048875)
			(xy 70.271137 -317.079096) (xy 70.225325 -317.102439) (xy 70.176426 -317.118327) (xy 70.125644 -317.12637)
			(xy 70.074228 -317.12637) (xy 70.023446 -317.118327) (xy 69.974547 -317.102439) (xy 69.928735 -317.079096)
			(xy 69.887139 -317.048875) (xy 69.850783 -317.012519) (xy 69.820562 -316.970923) (xy 69.797219 -316.925111)
			(xy 69.781331 -316.876212) (xy 69.773288 -316.82543) (xy 69.45461 -316.82543) (xy 69.446894 -316.872906)
			(xy 69.43131 -316.919587) (xy 69.408439 -316.963164) (xy 69.378874 -317.002508) (xy 69.343381 -317.0366)
			(xy 69.302878 -317.064556) (xy 69.258416 -317.085654) (xy 69.211145 -317.099346) (xy 69.16229 -317.105278)
			(xy 69.113115 -317.103297) (xy 69.064896 -317.093453) (xy 69.01888 -317.076001) (xy 68.976259 -317.051394)
			(xy 68.938138 -317.020269) (xy 68.905503 -316.983432) (xy 68.8792 -316.941836) (xy 68.859909 -316.89656)
			(xy 68.848132 -316.848776) (xy 68.844172 -316.799722) (xy 68.526258 -316.799722) (xy 68.526257 -316.825412)
			(xy 68.518215 -316.876166) (xy 68.502332 -316.925038) (xy 68.478999 -316.970823) (xy 68.448791 -317.012394)
			(xy 68.412451 -317.048727) (xy 68.370875 -317.078929) (xy 68.325086 -317.102254) (xy 68.276212 -317.118128)
			(xy 68.225456 -317.126161) (xy 68.199762 -317.12662) (xy 68.186043 -317.126491) (xy 68.158702 -317.1242)
			(xy 68.145152 -317.122048) (xy 68.133214 -317.120016) (xy 68.110354 -317.127128) (xy 68.0339 -317.200788)
			(xy 68.026026 -317.223394) (xy 68.02755 -317.235586) (xy 68.028748 -317.245384) (xy 68.030022 -317.265085)
			(xy 68.03009 -317.274956) (xy 68.02989 -317.289075) (xy 68.027217 -317.317186) (xy 68.024756 -317.33109)
			(xy 68.02247 -317.343536) (xy 68.029836 -317.367666) (xy 68.107052 -317.444882) (xy 68.130928 -317.452248)
			(xy 68.143374 -317.449962) (xy 68.157339 -317.447475) (xy 68.185579 -317.444799) (xy 68.199762 -317.444628)
			(xy 68.223756 -317.445071) (xy 68.271154 -317.452574) (xy 68.316794 -317.467399) (xy 68.359553 -317.489183)
			(xy 68.398377 -317.517389) (xy 68.43231 -317.551321) (xy 68.460516 -317.590145) (xy 68.4823 -317.632904)
			(xy 68.497126 -317.678544) (xy 68.504628 -317.725942) (xy 68.50507 -317.749936) (xy 68.504886 -317.764119)
			(xy 68.502218 -317.792359) (xy 68.499736 -317.806324) (xy 68.49745 -317.81877) (xy 68.504816 -317.842392)
			(xy 68.582286 -317.919862) (xy 68.605908 -317.927228) (xy 68.618354 -317.924942) (xy 68.632256 -317.922468)
			(xy 68.660369 -317.919796) (xy 68.674488 -317.919608) (xy 68.674742 -317.919608) (xy 68.684613 -317.919687)
			(xy 68.704313 -317.920956) (xy 68.714112 -317.922148) (xy 68.726304 -317.923672) (xy 68.74891 -317.915798)
			(xy 68.82257 -317.839344) (xy 68.829682 -317.816484) (xy 68.82765 -317.804546) (xy 68.825449 -317.790999)
			(xy 68.823033 -317.763659) (xy 68.822824 -317.749936) (xy 68.823328 -317.724228) (xy 68.831371 -317.673446)
			(xy 68.847259 -317.624547) (xy 68.870602 -317.578735) (xy 68.900823 -317.537139) (xy 68.937179 -317.500783)
			(xy 68.978775 -317.470562) (xy 69.024587 -317.447219) (xy 69.073486 -317.431331) (xy 69.124268 -317.423288)
			(xy 69.175684 -317.423288) (xy 69.226466 -317.431331) (xy 69.275365 -317.447219) (xy 69.321177 -317.470562)
			(xy 69.362773 -317.500783) (xy 69.399129 -317.537139) (xy 69.42935 -317.578735) (xy 69.452693 -317.624547)
			(xy 69.468581 -317.673446) (xy 69.476624 -317.724228) (xy 69.477128 -317.749936) (xy 69.475096 -317.78448)
			(xy 69.473826 -317.796164) (xy 69.4817 -317.817754) (xy 69.554344 -317.890144) (xy 69.575934 -317.897764)
			(xy 69.587618 -317.89624) (xy 69.596922 -317.895272) (xy 69.615602 -317.894255) (xy 69.624956 -317.894208)
			(xy 69.63861 -317.89437) (xy 69.665823 -317.896658) (xy 69.679312 -317.89878) (xy 69.69125 -317.900812)
			(xy 69.713856 -317.8937) (xy 69.79031 -317.820802) (xy 69.798184 -317.79845) (xy 69.796914 -317.786258)
			(xy 69.795865 -317.777214) (xy 69.794719 -317.75904) (xy 69.794628 -317.749936) (xy 69.795111 -317.725118)
			(xy 69.803135 -317.676135) (xy 69.818979 -317.629096) (xy 69.842223 -317.585239) (xy 69.872257 -317.545721)
			(xy 69.908288 -317.511582) (xy 69.949368 -317.483722) (xy 69.994414 -317.462875) (xy 70.042239 -317.449591)
			(xy 70.091583 -317.444218) (xy 70.141147 -317.4469) (xy 70.189623 -317.457564) (xy 70.235736 -317.475931)
			(xy 70.27827 -317.501516) (xy 70.316104 -317.533645) (xy 70.348242 -317.571472) (xy 70.373837 -317.613999)
			(xy 70.392215 -317.660108) (xy 70.402891 -317.708582) (xy 70.405584 -317.758145) (xy 70.400223 -317.80749)
			(xy 70.38695 -317.855318) (xy 70.366113 -317.900369) (xy 70.338263 -317.941456) (xy 70.304133 -317.977495)
			(xy 70.264622 -318.007538) (xy 70.220771 -318.030793) (xy 70.173735 -318.046647) (xy 70.124754 -318.054683)
			(xy 70.099936 -318.055244) (xy 70.090832 -318.055146) (xy 70.072659 -318.054) (xy 70.063614 -318.052958)
			(xy 70.051422 -318.051688) (xy 70.02907 -318.059562) (xy 69.956172 -318.136016) (xy 69.94906 -318.158622)
			(xy 69.951092 -318.17056) (xy 69.953222 -318.184048) (xy 69.955508 -318.211262) (xy 69.955664 -318.224916)
			(xy 69.955664 -318.295274) (xy 69.95622 -318.305969) (xy 69.964874 -318.325531) (xy 69.972428 -318.33312)
			(xy 70.03669 -318.390778) (xy 70.05701 -318.397382) (xy 70.067932 -318.396366) (xy 70.099936 -318.394588)
			(xy 70.123925 -318.395061) (xy 70.171313 -318.402572) (xy 70.216943 -318.417402) (xy 70.25969 -318.439188)
			(xy 70.298505 -318.467392) (xy 70.332429 -318.50132) (xy 70.360629 -318.540137) (xy 70.38241 -318.582887)
			(xy 70.397236 -318.628518) (xy 70.404741 -318.675906) (xy 70.405244 -318.699896) (xy 70.405058 -318.714078)
			(xy 70.402385 -318.742318) (xy 70.39991 -318.756284) (xy 70.397624 -318.76873) (xy 70.40499 -318.792352)
			(xy 70.48246 -318.869822) (xy 70.506082 -318.877188) (xy 70.518528 -318.874902) (xy 70.532493 -318.872418)
			(xy 70.560733 -318.869747) (xy 70.574916 -318.869568) (xy 70.584787 -318.86965) (xy 70.604486 -318.870923)
			(xy 70.614286 -318.872108) (xy 70.626224 -318.873632) (xy 70.64883 -318.865758) (xy 70.72249 -318.789304)
			(xy 70.729348 -318.766444) (xy 70.72757 -318.754506) (xy 70.725371 -318.740959) (xy 70.722958 -318.713619)
			(xy 70.722744 -318.699896) (xy 70.723248 -318.674188) (xy 70.731292 -318.623406) (xy 70.747181 -318.574507)
			(xy 70.770523 -318.528696) (xy 70.800744 -318.4871) (xy 70.8371 -318.450744) (xy 70.878696 -318.420523)
			(xy 70.924507 -318.397181) (xy 70.973406 -318.381292) (xy 71.024188 -318.373248) (xy 71.049896 -318.372744)
			(xy 71.082408 -318.374522) (xy 71.09333 -318.375538) (xy 71.11365 -318.368934) (xy 71.177404 -318.311022)
			(xy 71.184911 -318.303476) (xy 71.193571 -318.284057) (xy 71.194168 -318.27343) (xy 71.194168 -318.224916)
			(xy 71.194211 -318.215562) (xy 71.195226 -318.196881) (xy 71.1962 -318.187578) (xy 71.197724 -318.175894)
			(xy 71.190104 -318.154304) (xy 71.117714 -318.08166) (xy 71.096124 -318.073786) (xy 71.08444 -318.075056)
			(xy 71.049896 -318.077088) (xy 71.024183 -318.076609) (xy 70.97339 -318.068564) (xy 70.924481 -318.052671)
			(xy 70.87866 -318.029323) (xy 70.837056 -317.999095) (xy 70.800693 -317.96273) (xy 70.770467 -317.921124)
			(xy 70.747122 -317.875302) (xy 70.731232 -317.826392) (xy 70.723189 -317.775599) (xy 70.723191 -317.724172)
			(xy 70.731239 -317.673379) (xy 70.747133 -317.624471) (xy 70.770482 -317.578651) (xy 70.800712 -317.537048)
			(xy 70.837079 -317.500686) (xy 70.878685 -317.470461) (xy 70.924508 -317.447118) (xy 70.973418 -317.431229)
			(xy 71.024212 -317.423188) (xy 71.075638 -317.423192) (xy 71.126431 -317.431241) (xy 71.175339 -317.447137)
			(xy 71.221158 -317.470488) (xy 71.26276 -317.500719) (xy 71.299121 -317.537087) (xy 71.329344 -317.578694)
			(xy 71.352687 -317.624518) (xy 71.368573 -317.673429) (xy 71.376613 -317.724223) (xy 71.377048 -317.749936)
			(xy 71.375016 -317.78448) (xy 71.373746 -317.796164) (xy 71.38162 -317.817754) (xy 71.454264 -317.890144)
			(xy 71.475854 -317.897764) (xy 71.487538 -317.89624) (xy 71.496842 -317.895272) (xy 71.515522 -317.894257)
			(xy 71.524876 -317.894208) (xy 71.53853 -317.89437) (xy 71.565742 -317.89666) (xy 71.579232 -317.89878)
			(xy 71.59117 -317.900812) (xy 71.613776 -317.8937) (xy 71.69023 -317.820802) (xy 71.698104 -317.79845)
			(xy 71.696834 -317.786258) (xy 71.695785 -317.777214) (xy 71.694639 -317.75904) (xy 71.694548 -317.749936)
			(xy 71.695031 -317.72511) (xy 71.703058 -317.676112) (xy 71.718907 -317.629057) (xy 71.742161 -317.585187)
			(xy 71.772205 -317.545658) (xy 71.80825 -317.51151) (xy 71.849344 -317.483643) (xy 71.894406 -317.462792)
			(xy 71.942247 -317.449507) (xy 71.991607 -317.444137) (xy 72.041186 -317.446824) (xy 72.089677 -317.457496)
			(xy 72.135803 -317.475874) (xy 72.178347 -317.501472) (xy 72.216189 -317.533616) (xy 72.248333 -317.571459)
			(xy 72.27393 -317.614004) (xy 72.292306 -317.66013) (xy 72.302977 -317.708622) (xy 72.305663 -317.758201)
			(xy 72.303765 -317.775644) (xy 72.623168 -317.775644) (xy 72.623168 -317.724228) (xy 72.631211 -317.673446)
			(xy 72.647099 -317.624547) (xy 72.670442 -317.578735) (xy 72.700663 -317.537139) (xy 72.737019 -317.500783)
			(xy 72.778615 -317.470562) (xy 72.824427 -317.447219) (xy 72.873326 -317.431331) (xy 72.924108 -317.423288)
			(xy 72.975524 -317.423288) (xy 73.026306 -317.431331) (xy 73.075205 -317.447219) (xy 73.121017 -317.470562)
			(xy 73.162613 -317.500783) (xy 73.198969 -317.537139) (xy 73.22919 -317.578735) (xy 73.252533 -317.624547)
			(xy 73.268421 -317.673446) (xy 73.276464 -317.724228) (xy 73.276968 -317.749936) (xy 73.593972 -317.749936)
			(xy 73.597932 -317.700882) (xy 73.609709 -317.653098) (xy 73.629 -317.607822) (xy 73.655303 -317.566226)
			(xy 73.687938 -317.529389) (xy 73.726059 -317.498264) (xy 73.76868 -317.473657) (xy 73.814696 -317.456205)
			(xy 73.862915 -317.446361) (xy 73.91209 -317.44438) (xy 73.960945 -317.450312) (xy 74.008216 -317.464004)
			(xy 74.052678 -317.485102) (xy 74.093181 -317.513058) (xy 74.128674 -317.54715) (xy 74.158239 -317.586494)
			(xy 74.18111 -317.630071) (xy 74.196694 -317.676752) (xy 74.204589 -317.725329) (xy 74.205084 -317.749936)
			(xy 74.544186 -317.749936) (xy 74.548146 -317.700882) (xy 74.559923 -317.653098) (xy 74.579214 -317.607822)
			(xy 74.605517 -317.566226) (xy 74.638152 -317.529389) (xy 74.676273 -317.498264) (xy 74.718894 -317.473657)
			(xy 74.76491 -317.456205) (xy 74.813129 -317.446361) (xy 74.862304 -317.44438) (xy 74.911159 -317.450312)
			(xy 74.95843 -317.464004) (xy 75.002892 -317.485102) (xy 75.043395 -317.513058) (xy 75.078888 -317.54715)
			(xy 75.108453 -317.586494) (xy 75.131324 -317.630071) (xy 75.146908 -317.676752) (xy 75.154803 -317.725329)
			(xy 75.155298 -317.749936) (xy 75.494146 -317.749936) (xy 75.498106 -317.700882) (xy 75.509883 -317.653098)
			(xy 75.529174 -317.607822) (xy 75.555477 -317.566226) (xy 75.588112 -317.529389) (xy 75.626233 -317.498264)
			(xy 75.668854 -317.473657) (xy 75.71487 -317.456205) (xy 75.763089 -317.446361) (xy 75.812264 -317.44438)
			(xy 75.861119 -317.450312) (xy 75.90839 -317.464004) (xy 75.952852 -317.485102) (xy 75.993355 -317.513058)
			(xy 76.028848 -317.54715) (xy 76.058413 -317.586494) (xy 76.081284 -317.630071) (xy 76.096868 -317.676752)
			(xy 76.104763 -317.725329) (xy 76.105258 -317.749936) (xy 76.444106 -317.749936) (xy 76.448066 -317.700882)
			(xy 76.459843 -317.653098) (xy 76.479134 -317.607822) (xy 76.505437 -317.566226) (xy 76.538072 -317.529389)
			(xy 76.576193 -317.498264) (xy 76.618814 -317.473657) (xy 76.66483 -317.456205) (xy 76.713049 -317.446361)
			(xy 76.762224 -317.44438) (xy 76.811079 -317.450312) (xy 76.85835 -317.464004) (xy 76.902812 -317.485102)
			(xy 76.943315 -317.513058) (xy 76.978808 -317.54715) (xy 77.008373 -317.586494) (xy 77.031244 -317.630071)
			(xy 77.046828 -317.676752) (xy 77.054723 -317.725329) (xy 77.055218 -317.749936) (xy 77.394066 -317.749936)
			(xy 77.398026 -317.700882) (xy 77.409803 -317.653098) (xy 77.429094 -317.607822) (xy 77.455397 -317.566226)
			(xy 77.488032 -317.529389) (xy 77.526153 -317.498264) (xy 77.568774 -317.473657) (xy 77.61479 -317.456205)
			(xy 77.663009 -317.446361) (xy 77.712184 -317.44438) (xy 77.761039 -317.450312) (xy 77.80831 -317.464004)
			(xy 77.852772 -317.485102) (xy 77.893275 -317.513058) (xy 77.928768 -317.54715) (xy 77.958333 -317.586494)
			(xy 77.981204 -317.630071) (xy 77.996788 -317.676752) (xy 78.004683 -317.725329) (xy 78.005178 -317.749936)
			(xy 78.344026 -317.749936) (xy 78.347986 -317.700882) (xy 78.359763 -317.653098) (xy 78.379054 -317.607822)
			(xy 78.405357 -317.566226) (xy 78.437992 -317.529389) (xy 78.476113 -317.498264) (xy 78.518734 -317.473657)
			(xy 78.56475 -317.456205) (xy 78.612969 -317.446361) (xy 78.662144 -317.44438) (xy 78.710999 -317.450312)
			(xy 78.75827 -317.464004) (xy 78.802732 -317.485102) (xy 78.843235 -317.513058) (xy 78.878728 -317.54715)
			(xy 78.908293 -317.586494) (xy 78.931164 -317.630071) (xy 78.946748 -317.676752) (xy 78.954643 -317.725329)
			(xy 78.955138 -317.749936) (xy 79.293986 -317.749936) (xy 79.297946 -317.700882) (xy 79.309723 -317.653098)
			(xy 79.329014 -317.607822) (xy 79.355317 -317.566226) (xy 79.387952 -317.529389) (xy 79.426073 -317.498264)
			(xy 79.468694 -317.473657) (xy 79.51471 -317.456205) (xy 79.562929 -317.446361) (xy 79.612104 -317.44438)
			(xy 79.660959 -317.450312) (xy 79.70823 -317.464004) (xy 79.752692 -317.485102) (xy 79.793195 -317.513058)
			(xy 79.828688 -317.54715) (xy 79.858253 -317.586494) (xy 79.881124 -317.630071) (xy 79.896708 -317.676752)
			(xy 79.904603 -317.725329) (xy 79.905098 -317.749936) (xy 80.243946 -317.749936) (xy 80.247906 -317.700882)
			(xy 80.259683 -317.653098) (xy 80.278974 -317.607822) (xy 80.305277 -317.566226) (xy 80.337912 -317.529389)
			(xy 80.376033 -317.498264) (xy 80.418654 -317.473657) (xy 80.46467 -317.456205) (xy 80.512889 -317.446361)
			(xy 80.562064 -317.44438) (xy 80.610919 -317.450312) (xy 80.65819 -317.464004) (xy 80.702652 -317.485102)
			(xy 80.743155 -317.513058) (xy 80.778648 -317.54715) (xy 80.808213 -317.586494) (xy 80.831084 -317.630071)
			(xy 80.846668 -317.676752) (xy 80.854563 -317.725329) (xy 80.855058 -317.749936) (xy 81.19416 -317.749936)
			(xy 81.19812 -317.700882) (xy 81.209897 -317.653098) (xy 81.229188 -317.607822) (xy 81.255491 -317.566226)
			(xy 81.288126 -317.529389) (xy 81.326247 -317.498264) (xy 81.368868 -317.473657) (xy 81.414884 -317.456205)
			(xy 81.463103 -317.446361) (xy 81.512278 -317.44438) (xy 81.561133 -317.450312) (xy 81.608404 -317.464004)
			(xy 81.652866 -317.485102) (xy 81.693369 -317.513058) (xy 81.728862 -317.54715) (xy 81.758427 -317.586494)
			(xy 81.781298 -317.630071) (xy 81.796882 -317.676752) (xy 81.804777 -317.725329) (xy 81.805272 -317.749936)
			(xy 82.14412 -317.749936) (xy 82.14808 -317.700882) (xy 82.159857 -317.653098) (xy 82.179148 -317.607822)
			(xy 82.205451 -317.566226) (xy 82.238086 -317.529389) (xy 82.276207 -317.498264) (xy 82.318828 -317.473657)
			(xy 82.364844 -317.456205) (xy 82.413063 -317.446361) (xy 82.462238 -317.44438) (xy 82.511093 -317.450312)
			(xy 82.558364 -317.464004) (xy 82.602826 -317.485102) (xy 82.643329 -317.513058) (xy 82.678822 -317.54715)
			(xy 82.708387 -317.586494) (xy 82.731258 -317.630071) (xy 82.746842 -317.676752) (xy 82.754737 -317.725329)
			(xy 82.755232 -317.749936) (xy 82.754737 -317.774543) (xy 82.746842 -317.82312) (xy 82.731258 -317.869801)
			(xy 82.708387 -317.913378) (xy 82.678822 -317.952722) (xy 82.643329 -317.986814) (xy 82.602826 -318.01477)
			(xy 82.558364 -318.035868) (xy 82.511093 -318.04956) (xy 82.462238 -318.055492) (xy 82.413063 -318.053511)
			(xy 82.364844 -318.043667) (xy 82.318828 -318.026215) (xy 82.276207 -318.001608) (xy 82.238086 -317.970483)
			(xy 82.205451 -317.933646) (xy 82.179148 -317.89205) (xy 82.159857 -317.846774) (xy 82.14808 -317.79899)
			(xy 82.14412 -317.749936) (xy 81.805272 -317.749936) (xy 81.804777 -317.774543) (xy 81.796882 -317.82312)
			(xy 81.781298 -317.869801) (xy 81.758427 -317.913378) (xy 81.728862 -317.952722) (xy 81.693369 -317.986814)
			(xy 81.652866 -318.01477) (xy 81.608404 -318.035868) (xy 81.561133 -318.04956) (xy 81.512278 -318.055492)
			(xy 81.463103 -318.053511) (xy 81.414884 -318.043667) (xy 81.368868 -318.026215) (xy 81.326247 -318.001608)
			(xy 81.288126 -317.970483) (xy 81.255491 -317.933646) (xy 81.229188 -317.89205) (xy 81.209897 -317.846774)
			(xy 81.19812 -317.79899) (xy 81.19416 -317.749936) (xy 80.855058 -317.749936) (xy 80.854563 -317.774543)
			(xy 80.846668 -317.82312) (xy 80.831084 -317.869801) (xy 80.808213 -317.913378) (xy 80.778648 -317.952722)
			(xy 80.743155 -317.986814) (xy 80.702652 -318.01477) (xy 80.65819 -318.035868) (xy 80.610919 -318.04956)
			(xy 80.562064 -318.055492) (xy 80.512889 -318.053511) (xy 80.46467 -318.043667) (xy 80.418654 -318.026215)
			(xy 80.376033 -318.001608) (xy 80.337912 -317.970483) (xy 80.305277 -317.933646) (xy 80.278974 -317.89205)
			(xy 80.259683 -317.846774) (xy 80.247906 -317.79899) (xy 80.243946 -317.749936) (xy 79.905098 -317.749936)
			(xy 79.904603 -317.774543) (xy 79.896708 -317.82312) (xy 79.881124 -317.869801) (xy 79.858253 -317.913378)
			(xy 79.828688 -317.952722) (xy 79.793195 -317.986814) (xy 79.752692 -318.01477) (xy 79.70823 -318.035868)
			(xy 79.660959 -318.04956) (xy 79.612104 -318.055492) (xy 79.562929 -318.053511) (xy 79.51471 -318.043667)
			(xy 79.468694 -318.026215) (xy 79.426073 -318.001608) (xy 79.387952 -317.970483) (xy 79.355317 -317.933646)
			(xy 79.329014 -317.89205) (xy 79.309723 -317.846774) (xy 79.297946 -317.79899) (xy 79.293986 -317.749936)
			(xy 78.955138 -317.749936) (xy 78.954643 -317.774543) (xy 78.946748 -317.82312) (xy 78.931164 -317.869801)
			(xy 78.908293 -317.913378) (xy 78.878728 -317.952722) (xy 78.843235 -317.986814) (xy 78.802732 -318.01477)
			(xy 78.75827 -318.035868) (xy 78.710999 -318.04956) (xy 78.662144 -318.055492) (xy 78.612969 -318.053511)
			(xy 78.56475 -318.043667) (xy 78.518734 -318.026215) (xy 78.476113 -318.001608) (xy 78.437992 -317.970483)
			(xy 78.405357 -317.933646) (xy 78.379054 -317.89205) (xy 78.359763 -317.846774) (xy 78.347986 -317.79899)
			(xy 78.344026 -317.749936) (xy 78.005178 -317.749936) (xy 78.004683 -317.774543) (xy 77.996788 -317.82312)
			(xy 77.981204 -317.869801) (xy 77.958333 -317.913378) (xy 77.928768 -317.952722) (xy 77.893275 -317.986814)
			(xy 77.852772 -318.01477) (xy 77.80831 -318.035868) (xy 77.761039 -318.04956) (xy 77.712184 -318.055492)
			(xy 77.663009 -318.053511) (xy 77.61479 -318.043667) (xy 77.568774 -318.026215) (xy 77.526153 -318.001608)
			(xy 77.488032 -317.970483) (xy 77.455397 -317.933646) (xy 77.429094 -317.89205) (xy 77.409803 -317.846774)
			(xy 77.398026 -317.79899) (xy 77.394066 -317.749936) (xy 77.055218 -317.749936) (xy 77.054723 -317.774543)
			(xy 77.046828 -317.82312) (xy 77.031244 -317.869801) (xy 77.008373 -317.913378) (xy 76.978808 -317.952722)
			(xy 76.943315 -317.986814) (xy 76.902812 -318.01477) (xy 76.85835 -318.035868) (xy 76.811079 -318.04956)
			(xy 76.762224 -318.055492) (xy 76.713049 -318.053511) (xy 76.66483 -318.043667) (xy 76.618814 -318.026215)
			(xy 76.576193 -318.001608) (xy 76.538072 -317.970483) (xy 76.505437 -317.933646) (xy 76.479134 -317.89205)
			(xy 76.459843 -317.846774) (xy 76.448066 -317.79899) (xy 76.444106 -317.749936) (xy 76.105258 -317.749936)
			(xy 76.104763 -317.774543) (xy 76.096868 -317.82312) (xy 76.081284 -317.869801) (xy 76.058413 -317.913378)
			(xy 76.028848 -317.952722) (xy 75.993355 -317.986814) (xy 75.952852 -318.01477) (xy 75.90839 -318.035868)
			(xy 75.861119 -318.04956) (xy 75.812264 -318.055492) (xy 75.763089 -318.053511) (xy 75.71487 -318.043667)
			(xy 75.668854 -318.026215) (xy 75.626233 -318.001608) (xy 75.588112 -317.970483) (xy 75.555477 -317.933646)
			(xy 75.529174 -317.89205) (xy 75.509883 -317.846774) (xy 75.498106 -317.79899) (xy 75.494146 -317.749936)
			(xy 75.155298 -317.749936) (xy 75.154803 -317.774543) (xy 75.146908 -317.82312) (xy 75.131324 -317.869801)
			(xy 75.108453 -317.913378) (xy 75.078888 -317.952722) (xy 75.043395 -317.986814) (xy 75.002892 -318.01477)
			(xy 74.95843 -318.035868) (xy 74.911159 -318.04956) (xy 74.862304 -318.055492) (xy 74.813129 -318.053511)
			(xy 74.76491 -318.043667) (xy 74.718894 -318.026215) (xy 74.676273 -318.001608) (xy 74.638152 -317.970483)
			(xy 74.605517 -317.933646) (xy 74.579214 -317.89205) (xy 74.559923 -317.846774) (xy 74.548146 -317.79899)
			(xy 74.544186 -317.749936) (xy 74.205084 -317.749936) (xy 74.204589 -317.774543) (xy 74.196694 -317.82312)
			(xy 74.18111 -317.869801) (xy 74.158239 -317.913378) (xy 74.128674 -317.952722) (xy 74.093181 -317.986814)
			(xy 74.052678 -318.01477) (xy 74.008216 -318.035868) (xy 73.960945 -318.04956) (xy 73.91209 -318.055492)
			(xy 73.862915 -318.053511) (xy 73.814696 -318.043667) (xy 73.76868 -318.026215) (xy 73.726059 -318.001608)
			(xy 73.687938 -317.970483) (xy 73.655303 -317.933646) (xy 73.629 -317.89205) (xy 73.609709 -317.846774)
			(xy 73.597932 -317.79899) (xy 73.593972 -317.749936) (xy 73.276968 -317.749936) (xy 73.276464 -317.775644)
			(xy 73.268421 -317.826426) (xy 73.252533 -317.875325) (xy 73.22919 -317.921137) (xy 73.198969 -317.962733)
			(xy 73.162613 -317.999089) (xy 73.121017 -318.02931) (xy 73.075205 -318.052653) (xy 73.026306 -318.068541)
			(xy 72.975524 -318.076584) (xy 72.924108 -318.076584) (xy 72.873326 -318.068541) (xy 72.824427 -318.052653)
			(xy 72.778615 -318.02931) (xy 72.737019 -317.999089) (xy 72.700663 -317.962733) (xy 72.670442 -317.921137)
			(xy 72.647099 -317.875325) (xy 72.631211 -317.826426) (xy 72.623168 -317.775644) (xy 72.303765 -317.775644)
			(xy 72.300291 -317.807561) (xy 72.287005 -317.855402) (xy 72.266153 -317.900463) (xy 72.238285 -317.941557)
			(xy 72.204136 -317.9776) (xy 72.164606 -318.007644) (xy 72.120735 -318.030896) (xy 72.073681 -318.046744)
			(xy 72.024682 -318.05477) (xy 71.999856 -318.055244) (xy 71.990752 -318.055146) (xy 71.972579 -318.054002)
			(xy 71.963534 -318.052958) (xy 71.951342 -318.051688) (xy 71.92899 -318.059562) (xy 71.856092 -318.136016)
			(xy 71.84898 -318.158622) (xy 71.851012 -318.17056) (xy 71.853142 -318.184048) (xy 71.855429 -318.211261)
			(xy 71.855584 -318.224916) (xy 71.855584 -318.295274) (xy 71.856137 -318.305971) (xy 71.864782 -318.325542)
			(xy 71.872348 -318.33312) (xy 71.93661 -318.390778) (xy 71.95693 -318.397382) (xy 71.967852 -318.396366)
			(xy 71.999856 -318.394588) (xy 72.025116 -318.395077) (xy 72.074949 -318.403386) (xy 72.122734 -318.419785)
			(xy 72.167168 -318.443826) (xy 72.207039 -318.474853) (xy 72.241258 -318.51202) (xy 72.268893 -318.554313)
			(xy 72.289188 -318.600577) (xy 72.301592 -318.649552) (xy 72.305764 -318.6999) (xy 72.303634 -318.725604)
			(xy 72.623168 -318.725604) (xy 72.623168 -318.674188) (xy 72.631211 -318.623406) (xy 72.647099 -318.574507)
			(xy 72.670442 -318.528695) (xy 72.700663 -318.487099) (xy 72.737019 -318.450743) (xy 72.778615 -318.420522)
			(xy 72.824427 -318.397179) (xy 72.873326 -318.381291) (xy 72.924108 -318.373248) (xy 72.975524 -318.373248)
			(xy 73.026306 -318.381291) (xy 73.075205 -318.397179) (xy 73.121017 -318.420522) (xy 73.162613 -318.450743)
			(xy 73.198969 -318.487099) (xy 73.22919 -318.528695) (xy 73.252533 -318.574507) (xy 73.268421 -318.623406)
			(xy 73.276464 -318.674188) (xy 73.276968 -318.699896) (xy 73.593972 -318.699896) (xy 73.597932 -318.650842)
			(xy 73.609709 -318.603058) (xy 73.629 -318.557782) (xy 73.655303 -318.516186) (xy 73.687938 -318.479349)
			(xy 73.726059 -318.448224) (xy 73.76868 -318.423617) (xy 73.814696 -318.406165) (xy 73.862915 -318.396321)
			(xy 73.91209 -318.39434) (xy 73.960945 -318.400272) (xy 74.008216 -318.413964) (xy 74.052678 -318.435062)
			(xy 74.093181 -318.463018) (xy 74.128674 -318.49711) (xy 74.158239 -318.536454) (xy 74.18111 -318.580031)
			(xy 74.196694 -318.626712) (xy 74.204589 -318.675289) (xy 74.205084 -318.699896) (xy 74.544186 -318.699896)
			(xy 74.548146 -318.650842) (xy 74.559923 -318.603058) (xy 74.579214 -318.557782) (xy 74.605517 -318.516186)
			(xy 74.638152 -318.479349) (xy 74.676273 -318.448224) (xy 74.718894 -318.423617) (xy 74.76491 -318.406165)
			(xy 74.813129 -318.396321) (xy 74.862304 -318.39434) (xy 74.911159 -318.400272) (xy 74.95843 -318.413964)
			(xy 75.002892 -318.435062) (xy 75.043395 -318.463018) (xy 75.078888 -318.49711) (xy 75.108453 -318.536454)
			(xy 75.131324 -318.580031) (xy 75.146908 -318.626712) (xy 75.154803 -318.675289) (xy 75.155298 -318.699896)
			(xy 75.494146 -318.699896) (xy 75.498106 -318.650842) (xy 75.509883 -318.603058) (xy 75.529174 -318.557782)
			(xy 75.555477 -318.516186) (xy 75.588112 -318.479349) (xy 75.626233 -318.448224) (xy 75.668854 -318.423617)
			(xy 75.71487 -318.406165) (xy 75.763089 -318.396321) (xy 75.812264 -318.39434) (xy 75.861119 -318.400272)
			(xy 75.90839 -318.413964) (xy 75.952852 -318.435062) (xy 75.993355 -318.463018) (xy 76.028848 -318.49711)
			(xy 76.058413 -318.536454) (xy 76.081284 -318.580031) (xy 76.096868 -318.626712) (xy 76.104763 -318.675289)
			(xy 76.105258 -318.699896) (xy 76.444106 -318.699896) (xy 76.448066 -318.650842) (xy 76.459843 -318.603058)
			(xy 76.479134 -318.557782) (xy 76.505437 -318.516186) (xy 76.538072 -318.479349) (xy 76.576193 -318.448224)
			(xy 76.618814 -318.423617) (xy 76.66483 -318.406165) (xy 76.713049 -318.396321) (xy 76.762224 -318.39434)
			(xy 76.811079 -318.400272) (xy 76.85835 -318.413964) (xy 76.902812 -318.435062) (xy 76.943315 -318.463018)
			(xy 76.978808 -318.49711) (xy 77.008373 -318.536454) (xy 77.031244 -318.580031) (xy 77.046828 -318.626712)
			(xy 77.054723 -318.675289) (xy 77.055218 -318.699896) (xy 77.394066 -318.699896) (xy 77.398026 -318.650842)
			(xy 77.409803 -318.603058) (xy 77.429094 -318.557782) (xy 77.455397 -318.516186) (xy 77.488032 -318.479349)
			(xy 77.526153 -318.448224) (xy 77.568774 -318.423617) (xy 77.61479 -318.406165) (xy 77.663009 -318.396321)
			(xy 77.712184 -318.39434) (xy 77.761039 -318.400272) (xy 77.80831 -318.413964) (xy 77.852772 -318.435062)
			(xy 77.893275 -318.463018) (xy 77.928768 -318.49711) (xy 77.958333 -318.536454) (xy 77.981204 -318.580031)
			(xy 77.996788 -318.626712) (xy 78.004683 -318.675289) (xy 78.005178 -318.699896) (xy 78.344026 -318.699896)
			(xy 78.347986 -318.650842) (xy 78.359763 -318.603058) (xy 78.379054 -318.557782) (xy 78.405357 -318.516186)
			(xy 78.437992 -318.479349) (xy 78.476113 -318.448224) (xy 78.518734 -318.423617) (xy 78.56475 -318.406165)
			(xy 78.612969 -318.396321) (xy 78.662144 -318.39434) (xy 78.710999 -318.400272) (xy 78.75827 -318.413964)
			(xy 78.802732 -318.435062) (xy 78.843235 -318.463018) (xy 78.878728 -318.49711) (xy 78.908293 -318.536454)
			(xy 78.931164 -318.580031) (xy 78.946748 -318.626712) (xy 78.954643 -318.675289) (xy 78.955138 -318.699896)
			(xy 79.293986 -318.699896) (xy 79.297946 -318.650842) (xy 79.309723 -318.603058) (xy 79.329014 -318.557782)
			(xy 79.355317 -318.516186) (xy 79.387952 -318.479349) (xy 79.426073 -318.448224) (xy 79.468694 -318.423617)
			(xy 79.51471 -318.406165) (xy 79.562929 -318.396321) (xy 79.612104 -318.39434) (xy 79.660959 -318.400272)
			(xy 79.70823 -318.413964) (xy 79.752692 -318.435062) (xy 79.793195 -318.463018) (xy 79.828688 -318.49711)
			(xy 79.858253 -318.536454) (xy 79.881124 -318.580031) (xy 79.896708 -318.626712) (xy 79.904603 -318.675289)
			(xy 79.905098 -318.699896) (xy 80.243946 -318.699896) (xy 80.247906 -318.650842) (xy 80.259683 -318.603058)
			(xy 80.278974 -318.557782) (xy 80.305277 -318.516186) (xy 80.337912 -318.479349) (xy 80.376033 -318.448224)
			(xy 80.418654 -318.423617) (xy 80.46467 -318.406165) (xy 80.512889 -318.396321) (xy 80.562064 -318.39434)
			(xy 80.610919 -318.400272) (xy 80.65819 -318.413964) (xy 80.702652 -318.435062) (xy 80.743155 -318.463018)
			(xy 80.778648 -318.49711) (xy 80.808213 -318.536454) (xy 80.831084 -318.580031) (xy 80.846668 -318.626712)
			(xy 80.854563 -318.675289) (xy 80.855058 -318.699896) (xy 81.19416 -318.699896) (xy 81.19812 -318.650842)
			(xy 81.209897 -318.603058) (xy 81.229188 -318.557782) (xy 81.255491 -318.516186) (xy 81.288126 -318.479349)
			(xy 81.326247 -318.448224) (xy 81.368868 -318.423617) (xy 81.414884 -318.406165) (xy 81.463103 -318.396321)
			(xy 81.512278 -318.39434) (xy 81.561133 -318.400272) (xy 81.608404 -318.413964) (xy 81.652866 -318.435062)
			(xy 81.693369 -318.463018) (xy 81.728862 -318.49711) (xy 81.758427 -318.536454) (xy 81.781298 -318.580031)
			(xy 81.796882 -318.626712) (xy 81.804777 -318.675289) (xy 81.805272 -318.699896) (xy 81.804777 -318.724503)
			(xy 81.796882 -318.77308) (xy 81.781298 -318.819761) (xy 81.758427 -318.863338) (xy 81.728862 -318.902682)
			(xy 81.693369 -318.936774) (xy 81.652866 -318.96473) (xy 81.608404 -318.985828) (xy 81.561133 -318.99952)
			(xy 81.512278 -319.005452) (xy 81.463103 -319.003471) (xy 81.414884 -318.993627) (xy 81.368868 -318.976175)
			(xy 81.326247 -318.951568) (xy 81.288126 -318.920443) (xy 81.255491 -318.883606) (xy 81.229188 -318.84201)
			(xy 81.209897 -318.796734) (xy 81.19812 -318.74895) (xy 81.19416 -318.699896) (xy 80.855058 -318.699896)
			(xy 80.854563 -318.724503) (xy 80.846668 -318.77308) (xy 80.831084 -318.819761) (xy 80.808213 -318.863338)
			(xy 80.778648 -318.902682) (xy 80.743155 -318.936774) (xy 80.702652 -318.96473) (xy 80.65819 -318.985828)
			(xy 80.610919 -318.99952) (xy 80.562064 -319.005452) (xy 80.512889 -319.003471) (xy 80.46467 -318.993627)
			(xy 80.418654 -318.976175) (xy 80.376033 -318.951568) (xy 80.337912 -318.920443) (xy 80.305277 -318.883606)
			(xy 80.278974 -318.84201) (xy 80.259683 -318.796734) (xy 80.247906 -318.74895) (xy 80.243946 -318.699896)
			(xy 79.905098 -318.699896) (xy 79.904603 -318.724503) (xy 79.896708 -318.77308) (xy 79.881124 -318.819761)
			(xy 79.858253 -318.863338) (xy 79.828688 -318.902682) (xy 79.793195 -318.936774) (xy 79.752692 -318.96473)
			(xy 79.70823 -318.985828) (xy 79.660959 -318.99952) (xy 79.612104 -319.005452) (xy 79.562929 -319.003471)
			(xy 79.51471 -318.993627) (xy 79.468694 -318.976175) (xy 79.426073 -318.951568) (xy 79.387952 -318.920443)
			(xy 79.355317 -318.883606) (xy 79.329014 -318.84201) (xy 79.309723 -318.796734) (xy 79.297946 -318.74895)
			(xy 79.293986 -318.699896) (xy 78.955138 -318.699896) (xy 78.954643 -318.724503) (xy 78.946748 -318.77308)
			(xy 78.931164 -318.819761) (xy 78.908293 -318.863338) (xy 78.878728 -318.902682) (xy 78.843235 -318.936774)
			(xy 78.802732 -318.96473) (xy 78.75827 -318.985828) (xy 78.710999 -318.99952) (xy 78.662144 -319.005452)
			(xy 78.612969 -319.003471) (xy 78.56475 -318.993627) (xy 78.518734 -318.976175) (xy 78.476113 -318.951568)
			(xy 78.437992 -318.920443) (xy 78.405357 -318.883606) (xy 78.379054 -318.84201) (xy 78.359763 -318.796734)
			(xy 78.347986 -318.74895) (xy 78.344026 -318.699896) (xy 78.005178 -318.699896) (xy 78.004683 -318.724503)
			(xy 77.996788 -318.77308) (xy 77.981204 -318.819761) (xy 77.958333 -318.863338) (xy 77.928768 -318.902682)
			(xy 77.893275 -318.936774) (xy 77.852772 -318.96473) (xy 77.80831 -318.985828) (xy 77.761039 -318.99952)
			(xy 77.712184 -319.005452) (xy 77.663009 -319.003471) (xy 77.61479 -318.993627) (xy 77.568774 -318.976175)
			(xy 77.526153 -318.951568) (xy 77.488032 -318.920443) (xy 77.455397 -318.883606) (xy 77.429094 -318.84201)
			(xy 77.409803 -318.796734) (xy 77.398026 -318.74895) (xy 77.394066 -318.699896) (xy 77.055218 -318.699896)
			(xy 77.054723 -318.724503) (xy 77.046828 -318.77308) (xy 77.031244 -318.819761) (xy 77.008373 -318.863338)
			(xy 76.978808 -318.902682) (xy 76.943315 -318.936774) (xy 76.902812 -318.96473) (xy 76.85835 -318.985828)
			(xy 76.811079 -318.99952) (xy 76.762224 -319.005452) (xy 76.713049 -319.003471) (xy 76.66483 -318.993627)
			(xy 76.618814 -318.976175) (xy 76.576193 -318.951568) (xy 76.538072 -318.920443) (xy 76.505437 -318.883606)
			(xy 76.479134 -318.84201) (xy 76.459843 -318.796734) (xy 76.448066 -318.74895) (xy 76.444106 -318.699896)
			(xy 76.105258 -318.699896) (xy 76.104763 -318.724503) (xy 76.096868 -318.77308) (xy 76.081284 -318.819761)
			(xy 76.058413 -318.863338) (xy 76.028848 -318.902682) (xy 75.993355 -318.936774) (xy 75.952852 -318.96473)
			(xy 75.90839 -318.985828) (xy 75.861119 -318.99952) (xy 75.812264 -319.005452) (xy 75.763089 -319.003471)
			(xy 75.71487 -318.993627) (xy 75.668854 -318.976175) (xy 75.626233 -318.951568) (xy 75.588112 -318.920443)
			(xy 75.555477 -318.883606) (xy 75.529174 -318.84201) (xy 75.509883 -318.796734) (xy 75.498106 -318.74895)
			(xy 75.494146 -318.699896) (xy 75.155298 -318.699896) (xy 75.154803 -318.724503) (xy 75.146908 -318.77308)
			(xy 75.131324 -318.819761) (xy 75.108453 -318.863338) (xy 75.078888 -318.902682) (xy 75.043395 -318.936774)
			(xy 75.002892 -318.96473) (xy 74.95843 -318.985828) (xy 74.911159 -318.99952) (xy 74.862304 -319.005452)
			(xy 74.813129 -319.003471) (xy 74.76491 -318.993627) (xy 74.718894 -318.976175) (xy 74.676273 -318.951568)
			(xy 74.638152 -318.920443) (xy 74.605517 -318.883606) (xy 74.579214 -318.84201) (xy 74.559923 -318.796734)
			(xy 74.548146 -318.74895) (xy 74.544186 -318.699896) (xy 74.205084 -318.699896) (xy 74.204589 -318.724503)
			(xy 74.196694 -318.77308) (xy 74.18111 -318.819761) (xy 74.158239 -318.863338) (xy 74.128674 -318.902682)
			(xy 74.093181 -318.936774) (xy 74.052678 -318.96473) (xy 74.008216 -318.985828) (xy 73.960945 -318.99952)
			(xy 73.91209 -319.005452) (xy 73.862915 -319.003471) (xy 73.814696 -318.993627) (xy 73.76868 -318.976175)
			(xy 73.726059 -318.951568) (xy 73.687938 -318.920443) (xy 73.655303 -318.883606) (xy 73.629 -318.84201)
			(xy 73.609709 -318.796734) (xy 73.597932 -318.74895) (xy 73.593972 -318.699896) (xy 73.276968 -318.699896)
			(xy 73.276464 -318.725604) (xy 73.268421 -318.776386) (xy 73.252533 -318.825285) (xy 73.22919 -318.871097)
			(xy 73.198969 -318.912693) (xy 73.162613 -318.949049) (xy 73.121017 -318.97927) (xy 73.075205 -319.002613)
			(xy 73.026306 -319.018501) (xy 72.975524 -319.026544) (xy 72.924108 -319.026544) (xy 72.873326 -319.018501)
			(xy 72.824427 -319.002613) (xy 72.778615 -318.97927) (xy 72.737019 -318.949049) (xy 72.700663 -318.912693)
			(xy 72.670442 -318.871097) (xy 72.647099 -318.825285) (xy 72.631211 -318.776386) (xy 72.623168 -318.725604)
			(xy 72.303634 -318.725604) (xy 72.301592 -318.750248) (xy 72.289188 -318.799223) (xy 72.268893 -318.845487)
			(xy 72.241258 -318.88778) (xy 72.207039 -318.924947) (xy 72.167168 -318.955974) (xy 72.122734 -318.980015)
			(xy 72.074949 -318.996414) (xy 72.025116 -319.004723) (xy 71.999856 -319.005204) (xy 71.968106 -319.003426)
			(xy 71.957184 -319.00241) (xy 71.936864 -319.009014) (xy 71.872602 -319.066926) (xy 71.865101 -319.074474)
			(xy 71.856458 -319.093893) (xy 71.855838 -319.104518) (xy 71.855838 -319.17513) (xy 71.855289 -319.202341)
			(xy 71.846383 -319.25603) (xy 71.8288 -319.307533) (xy 71.803015 -319.355459) (xy 71.769726 -319.398512)
			(xy 71.750174 -319.417446) (xy 71.746618 -319.420748) (xy 71.7423 -319.424558) (xy 71.735442 -319.43294)
			(xy 71.731632 -319.437512) (xy 71.721218 -319.45834) (xy 71.718913 -319.463316) (xy 71.716226 -319.473948)
			(xy 71.715884 -319.479422) (xy 71.714106 -319.53835) (xy 71.714105 -319.545034) (xy 71.717195 -319.558034)
			(xy 71.720202 -319.564004) (xy 71.730362 -319.5828) (xy 71.736204 -319.588388) (xy 71.753783 -319.605848)
			(xy 71.783626 -319.645395) (xy 71.78611 -319.65011) (xy 72.644012 -319.65011) (xy 72.647972 -319.601056)
			(xy 72.659749 -319.553272) (xy 72.67904 -319.507996) (xy 72.705343 -319.4664) (xy 72.737978 -319.429563)
			(xy 72.776099 -319.398438) (xy 72.81872 -319.373831) (xy 72.864736 -319.356379) (xy 72.912955 -319.346535)
			(xy 72.96213 -319.344554) (xy 73.010985 -319.350486) (xy 73.058256 -319.364178) (xy 73.102718 -319.385276)
			(xy 73.143221 -319.413232) (xy 73.178714 -319.447324) (xy 73.208279 -319.486668) (xy 73.23115 -319.530245)
			(xy 73.246734 -319.576926) (xy 73.254629 -319.625503) (xy 73.255124 -319.65011) (xy 74.544186 -319.65011)
			(xy 74.548146 -319.601056) (xy 74.559923 -319.553272) (xy 74.579214 -319.507996) (xy 74.605517 -319.4664)
			(xy 74.638152 -319.429563) (xy 74.676273 -319.398438) (xy 74.718894 -319.373831) (xy 74.76491 -319.356379)
			(xy 74.813129 -319.346535) (xy 74.862304 -319.344554) (xy 74.911159 -319.350486) (xy 74.95843 -319.364178)
			(xy 75.002892 -319.385276) (xy 75.043395 -319.413232) (xy 75.078888 -319.447324) (xy 75.108453 -319.486668)
			(xy 75.131324 -319.530245) (xy 75.146908 -319.576926) (xy 75.154803 -319.625503) (xy 75.155298 -319.65011)
			(xy 76.444106 -319.65011) (xy 76.448066 -319.601056) (xy 76.459843 -319.553272) (xy 76.479134 -319.507996)
			(xy 76.505437 -319.4664) (xy 76.538072 -319.429563) (xy 76.576193 -319.398438) (xy 76.618814 -319.373831)
			(xy 76.66483 -319.356379) (xy 76.713049 -319.346535) (xy 76.762224 -319.344554) (xy 76.811079 -319.350486)
			(xy 76.85835 -319.364178) (xy 76.902812 -319.385276) (xy 76.943315 -319.413232) (xy 76.978808 -319.447324)
			(xy 77.008373 -319.486668) (xy 77.031244 -319.530245) (xy 77.046828 -319.576926) (xy 77.054723 -319.625503)
			(xy 77.055218 -319.65011) (xy 78.344026 -319.65011) (xy 78.347986 -319.601056) (xy 78.359763 -319.553272)
			(xy 78.379054 -319.507996) (xy 78.405357 -319.4664) (xy 78.437992 -319.429563) (xy 78.476113 -319.398438)
			(xy 78.518734 -319.373831) (xy 78.56475 -319.356379) (xy 78.612969 -319.346535) (xy 78.662144 -319.344554)
			(xy 78.710999 -319.350486) (xy 78.75827 -319.364178) (xy 78.802732 -319.385276) (xy 78.843235 -319.413232)
			(xy 78.878728 -319.447324) (xy 78.908293 -319.486668) (xy 78.931164 -319.530245) (xy 78.946748 -319.576926)
			(xy 78.954643 -319.625503) (xy 78.955138 -319.65011) (xy 80.243946 -319.65011) (xy 80.247906 -319.601056)
			(xy 80.259683 -319.553272) (xy 80.278974 -319.507996) (xy 80.305277 -319.4664) (xy 80.337912 -319.429563)
			(xy 80.376033 -319.398438) (xy 80.418654 -319.373831) (xy 80.46467 -319.356379) (xy 80.512889 -319.346535)
			(xy 80.562064 -319.344554) (xy 80.610919 -319.350486) (xy 80.65819 -319.364178) (xy 80.702652 -319.385276)
			(xy 80.743155 -319.413232) (xy 80.778648 -319.447324) (xy 80.808213 -319.486668) (xy 80.831084 -319.530245)
			(xy 80.846668 -319.576926) (xy 80.854563 -319.625503) (xy 80.855058 -319.65011) (xy 80.854563 -319.674717)
			(xy 80.846668 -319.723294) (xy 80.831084 -319.769975) (xy 80.808213 -319.813552) (xy 80.778648 -319.852896)
			(xy 80.743155 -319.886988) (xy 80.702652 -319.914944) (xy 80.65819 -319.936042) (xy 80.610919 -319.949734)
			(xy 80.562064 -319.955666) (xy 80.512889 -319.953685) (xy 80.46467 -319.943841) (xy 80.418654 -319.926389)
			(xy 80.376033 -319.901782) (xy 80.337912 -319.870657) (xy 80.305277 -319.83382) (xy 80.278974 -319.792224)
			(xy 80.259683 -319.746948) (xy 80.247906 -319.699164) (xy 80.243946 -319.65011) (xy 78.955138 -319.65011)
			(xy 78.954643 -319.674717) (xy 78.946748 -319.723294) (xy 78.931164 -319.769975) (xy 78.908293 -319.813552)
			(xy 78.878728 -319.852896) (xy 78.843235 -319.886988) (xy 78.802732 -319.914944) (xy 78.75827 -319.936042)
			(xy 78.710999 -319.949734) (xy 78.662144 -319.955666) (xy 78.612969 -319.953685) (xy 78.56475 -319.943841)
			(xy 78.518734 -319.926389) (xy 78.476113 -319.901782) (xy 78.437992 -319.870657) (xy 78.405357 -319.83382)
			(xy 78.379054 -319.792224) (xy 78.359763 -319.746948) (xy 78.347986 -319.699164) (xy 78.344026 -319.65011)
			(xy 77.055218 -319.65011) (xy 77.054723 -319.674717) (xy 77.046828 -319.723294) (xy 77.031244 -319.769975)
			(xy 77.008373 -319.813552) (xy 76.978808 -319.852896) (xy 76.943315 -319.886988) (xy 76.902812 -319.914944)
			(xy 76.85835 -319.936042) (xy 76.811079 -319.949734) (xy 76.762224 -319.955666) (xy 76.713049 -319.953685)
			(xy 76.66483 -319.943841) (xy 76.618814 -319.926389) (xy 76.576193 -319.901782) (xy 76.538072 -319.870657)
			(xy 76.505437 -319.83382) (xy 76.479134 -319.792224) (xy 76.459843 -319.746948) (xy 76.448066 -319.699164)
			(xy 76.444106 -319.65011) (xy 75.155298 -319.65011) (xy 75.154803 -319.674717) (xy 75.146908 -319.723294)
			(xy 75.131324 -319.769975) (xy 75.108453 -319.813552) (xy 75.078888 -319.852896) (xy 75.043395 -319.886988)
			(xy 75.002892 -319.914944) (xy 74.95843 -319.936042) (xy 74.911159 -319.949734) (xy 74.862304 -319.955666)
			(xy 74.813129 -319.953685) (xy 74.76491 -319.943841) (xy 74.718894 -319.926389) (xy 74.676273 -319.901782)
			(xy 74.638152 -319.870657) (xy 74.605517 -319.83382) (xy 74.579214 -319.792224) (xy 74.559923 -319.746948)
			(xy 74.548146 -319.699164) (xy 74.544186 -319.65011) (xy 73.255124 -319.65011) (xy 73.254629 -319.674717)
			(xy 73.246734 -319.723294) (xy 73.23115 -319.769975) (xy 73.208279 -319.813552) (xy 73.178714 -319.852896)
			(xy 73.143221 -319.886988) (xy 73.102718 -319.914944) (xy 73.058256 -319.936042) (xy 73.010985 -319.949734)
			(xy 72.96213 -319.955666) (xy 72.912955 -319.953685) (xy 72.864736 -319.943841) (xy 72.81872 -319.926389)
			(xy 72.776099 -319.901782) (xy 72.737978 -319.870657) (xy 72.705343 -319.83382) (xy 72.67904 -319.792224)
			(xy 72.659749 -319.746948) (xy 72.647972 -319.699164) (xy 72.644012 -319.65011) (xy 71.78611 -319.65011)
			(xy 71.806717 -319.689229) (xy 71.822455 -319.736206) (xy 71.83043 -319.785104) (xy 71.830946 -319.809876)
			(xy 71.830369 -319.836572) (xy 71.821115 -319.889154) (xy 71.802883 -319.939336) (xy 71.776225 -319.985596)
			(xy 71.74195 -320.026532) (xy 71.701095 -320.060905) (xy 71.678292 -320.074798) (xy 71.667669 -320.081749)
			(xy 71.654363 -320.103334) (xy 71.652892 -320.115946) (xy 71.649082 -320.183002) (xy 71.649082 -320.202306)
			(xy 71.649539 -320.212184) (xy 71.656977 -320.230488) (xy 71.66356 -320.237866) (xy 71.663814 -320.23812)
			(xy 71.66991 -320.244216) (xy 72.600864 -320.900044) (xy 84.898745 -320.900044) (xy 84.902751 -320.704989)
			(xy 84.914761 -320.510263) (xy 84.934756 -320.316194) (xy 84.962701 -320.12311) (xy 84.99855 -319.931335)
			(xy 85.042242 -319.741195) (xy 85.093703 -319.553008) (xy 85.152847 -319.367093) (xy 85.219574 -319.183762)
			(xy 85.293771 -319.003326) (xy 85.375313 -318.826088) (xy 85.464064 -318.652347) (xy 85.559872 -318.482396)
			(xy 85.662577 -318.316522) (xy 85.772005 -318.155004) (xy 85.887972 -317.998115) (xy 86.010283 -317.84612)
			(xy 86.13873 -317.699274) (xy 86.273098 -317.557825) (xy 86.41316 -317.422012) (xy 86.558679 -317.292063)
			(xy 86.709411 -317.168199) (xy 86.865101 -317.050627) (xy 87.025487 -316.939547) (xy 87.190298 -316.835144)
			(xy 87.359256 -316.737596) (xy 87.532077 -316.647067) (xy 87.708469 -316.563709) (xy 87.888134 -316.487663)
			(xy 88.070769 -316.419058) (xy 88.256068 -316.358008) (xy 88.443716 -316.304618) (xy 88.633398 -316.258976)
			(xy 88.824795 -316.22116) (xy 89.017582 -316.191234) (xy 89.211435 -316.169248) (xy 89.406028 -316.155239)
			(xy 89.601031 -316.149231) (xy 89.796117 -316.151234) (xy 89.990956 -316.161245) (xy 90.18522 -316.179246)
			(xy 90.378581 -316.205208) (xy 90.570714 -316.239086) (xy 90.761293 -316.280823) (xy 90.949998 -316.33035)
			(xy 90.977249 -316.338712) (xy 102.503984 -316.338712) (xy 102.508055 -316.28309) (xy 102.520181 -316.228653)
			(xy 102.540104 -316.176562) (xy 102.5674 -316.127927) (xy 102.601486 -316.083784) (xy 102.641635 -316.045075)
			(xy 102.686993 -316.012624) (xy 102.736593 -315.987123) (xy 102.789377 -315.969116) (xy 102.84422 -315.958986)
			(xy 102.899954 -315.956949) (xy 102.955391 -315.963049) (xy 103.009348 -315.977155) (xy 103.060677 -315.998967)
			(xy 103.108283 -316.028021) (xy 103.151151 -316.063696) (xy 103.188368 -316.105233) (xy 103.219141 -316.151746)
			(xy 103.242813 -316.202243) (xy 103.258881 -316.25565) (xy 103.267001 -316.310826) (xy 103.26751 -316.338712)
			(xy 103.519984 -316.338712) (xy 103.524055 -316.28309) (xy 103.536181 -316.228653) (xy 103.556104 -316.176562)
			(xy 103.5834 -316.127927) (xy 103.617486 -316.083784) (xy 103.657635 -316.045075) (xy 103.702993 -316.012624)
			(xy 103.752593 -315.987123) (xy 103.805377 -315.969116) (xy 103.86022 -315.958986) (xy 103.915954 -315.956949)
			(xy 103.971391 -315.963049) (xy 104.025348 -315.977155) (xy 104.076677 -315.998967) (xy 104.124283 -316.028021)
			(xy 104.167151 -316.063696) (xy 104.204368 -316.105233) (xy 104.235141 -316.151746) (xy 104.258813 -316.202243)
			(xy 104.274881 -316.25565) (xy 104.283001 -316.310826) (xy 104.28351 -316.338712) (xy 104.535984 -316.338712)
			(xy 104.540055 -316.28309) (xy 104.552181 -316.228653) (xy 104.572104 -316.176562) (xy 104.5994 -316.127927)
			(xy 104.633486 -316.083784) (xy 104.673635 -316.045075) (xy 104.718993 -316.012624) (xy 104.768593 -315.987123)
			(xy 104.821377 -315.969116) (xy 104.87622 -315.958986) (xy 104.931954 -315.956949) (xy 104.987391 -315.963049)
			(xy 105.041348 -315.977155) (xy 105.092677 -315.998967) (xy 105.140283 -316.028021) (xy 105.183151 -316.063696)
			(xy 105.220368 -316.105233) (xy 105.251141 -316.151746) (xy 105.274813 -316.202243) (xy 105.290881 -316.25565)
			(xy 105.299001 -316.310826) (xy 105.29951 -316.338712) (xy 105.551984 -316.338712) (xy 105.556055 -316.28309)
			(xy 105.568181 -316.228653) (xy 105.588104 -316.176562) (xy 105.6154 -316.127927) (xy 105.649486 -316.083784)
			(xy 105.689635 -316.045075) (xy 105.734993 -316.012624) (xy 105.784593 -315.987123) (xy 105.837377 -315.969116)
			(xy 105.89222 -315.958986) (xy 105.947954 -315.956949) (xy 106.003391 -315.963049) (xy 106.057348 -315.977155)
			(xy 106.108677 -315.998967) (xy 106.156283 -316.028021) (xy 106.199151 -316.063696) (xy 106.236368 -316.105233)
			(xy 106.267141 -316.151746) (xy 106.290813 -316.202243) (xy 106.306881 -316.25565) (xy 106.315001 -316.310826)
			(xy 106.31551 -316.338712) (xy 106.567984 -316.338712) (xy 106.572055 -316.28309) (xy 106.584181 -316.228653)
			(xy 106.604104 -316.176562) (xy 106.6314 -316.127927) (xy 106.665486 -316.083784) (xy 106.705635 -316.045075)
			(xy 106.750993 -316.012624) (xy 106.800593 -315.987123) (xy 106.853377 -315.969116) (xy 106.90822 -315.958986)
			(xy 106.963954 -315.956949) (xy 107.019391 -315.963049) (xy 107.073348 -315.977155) (xy 107.124677 -315.998967)
			(xy 107.172283 -316.028021) (xy 107.215151 -316.063696) (xy 107.252368 -316.105233) (xy 107.283141 -316.151746)
			(xy 107.306813 -316.202243) (xy 107.322881 -316.25565) (xy 107.331001 -316.310826) (xy 107.33151 -316.338712)
			(xy 107.583984 -316.338712) (xy 107.588055 -316.28309) (xy 107.600181 -316.228653) (xy 107.620104 -316.176562)
			(xy 107.6474 -316.127927) (xy 107.681486 -316.083784) (xy 107.721635 -316.045075) (xy 107.766993 -316.012624)
			(xy 107.816593 -315.987123) (xy 107.869377 -315.969116) (xy 107.92422 -315.958986) (xy 107.979954 -315.956949)
			(xy 108.035391 -315.963049) (xy 108.089348 -315.977155) (xy 108.140677 -315.998967) (xy 108.188283 -316.028021)
			(xy 108.231151 -316.063696) (xy 108.268368 -316.105233) (xy 108.299141 -316.151746) (xy 108.322813 -316.202243)
			(xy 108.338881 -316.25565) (xy 108.347001 -316.310826) (xy 108.34751 -316.338712) (xy 108.599984 -316.338712)
			(xy 108.604055 -316.28309) (xy 108.616181 -316.228653) (xy 108.636104 -316.176562) (xy 108.6634 -316.127927)
			(xy 108.697486 -316.083784) (xy 108.737635 -316.045075) (xy 108.782993 -316.012624) (xy 108.832593 -315.987123)
			(xy 108.885377 -315.969116) (xy 108.94022 -315.958986) (xy 108.995954 -315.956949) (xy 109.051391 -315.963049)
			(xy 109.105348 -315.977155) (xy 109.156677 -315.998967) (xy 109.204283 -316.028021) (xy 109.247151 -316.063696)
			(xy 109.284368 -316.105233) (xy 109.315141 -316.151746) (xy 109.338813 -316.202243) (xy 109.354881 -316.25565)
			(xy 109.363001 -316.310826) (xy 109.36351 -316.338712) (xy 109.615984 -316.338712) (xy 109.620055 -316.28309)
			(xy 109.632181 -316.228653) (xy 109.652104 -316.176562) (xy 109.6794 -316.127927) (xy 109.713486 -316.083784)
			(xy 109.753635 -316.045075) (xy 109.798993 -316.012624) (xy 109.848593 -315.987123) (xy 109.901377 -315.969116)
			(xy 109.95622 -315.958986) (xy 110.011954 -315.956949) (xy 110.067391 -315.963049) (xy 110.121348 -315.977155)
			(xy 110.172677 -315.998967) (xy 110.220283 -316.028021) (xy 110.263151 -316.063696) (xy 110.300368 -316.105233)
			(xy 110.331141 -316.151746) (xy 110.354813 -316.202243) (xy 110.370881 -316.25565) (xy 110.379001 -316.310826)
			(xy 110.37951 -316.338712) (xy 110.379001 -316.366598) (xy 110.370881 -316.421774) (xy 110.354813 -316.475181)
			(xy 110.331141 -316.525678) (xy 110.300368 -316.572191) (xy 110.263151 -316.613728) (xy 110.220283 -316.649403)
			(xy 110.172677 -316.678457) (xy 110.121348 -316.700269) (xy 110.067391 -316.714375) (xy 110.011954 -316.720475)
			(xy 109.95622 -316.718438) (xy 109.901377 -316.708308) (xy 109.848593 -316.690301) (xy 109.798993 -316.6648)
			(xy 109.753635 -316.632349) (xy 109.713486 -316.59364) (xy 109.6794 -316.549497) (xy 109.652104 -316.500862)
			(xy 109.632181 -316.448771) (xy 109.620055 -316.394334) (xy 109.615984 -316.338712) (xy 109.36351 -316.338712)
			(xy 109.363001 -316.366598) (xy 109.354881 -316.421774) (xy 109.338813 -316.475181) (xy 109.315141 -316.525678)
			(xy 109.284368 -316.572191) (xy 109.247151 -316.613728) (xy 109.204283 -316.649403) (xy 109.156677 -316.678457)
			(xy 109.105348 -316.700269) (xy 109.051391 -316.714375) (xy 108.995954 -316.720475) (xy 108.94022 -316.718438)
			(xy 108.885377 -316.708308) (xy 108.832593 -316.690301) (xy 108.782993 -316.6648) (xy 108.737635 -316.632349)
			(xy 108.697486 -316.59364) (xy 108.6634 -316.549497) (xy 108.636104 -316.500862) (xy 108.616181 -316.448771)
			(xy 108.604055 -316.394334) (xy 108.599984 -316.338712) (xy 108.34751 -316.338712) (xy 108.347001 -316.366598)
			(xy 108.338881 -316.421774) (xy 108.322813 -316.475181) (xy 108.299141 -316.525678) (xy 108.268368 -316.572191)
			(xy 108.231151 -316.613728) (xy 108.188283 -316.649403) (xy 108.140677 -316.678457) (xy 108.089348 -316.700269)
			(xy 108.035391 -316.714375) (xy 107.979954 -316.720475) (xy 107.92422 -316.718438) (xy 107.869377 -316.708308)
			(xy 107.816593 -316.690301) (xy 107.766993 -316.6648) (xy 107.721635 -316.632349) (xy 107.681486 -316.59364)
			(xy 107.6474 -316.549497) (xy 107.620104 -316.500862) (xy 107.600181 -316.448771) (xy 107.588055 -316.394334)
			(xy 107.583984 -316.338712) (xy 107.33151 -316.338712) (xy 107.331001 -316.366598) (xy 107.322881 -316.421774)
			(xy 107.306813 -316.475181) (xy 107.283141 -316.525678) (xy 107.252368 -316.572191) (xy 107.215151 -316.613728)
			(xy 107.172283 -316.649403) (xy 107.124677 -316.678457) (xy 107.073348 -316.700269) (xy 107.019391 -316.714375)
			(xy 106.963954 -316.720475) (xy 106.90822 -316.718438) (xy 106.853377 -316.708308) (xy 106.800593 -316.690301)
			(xy 106.750993 -316.6648) (xy 106.705635 -316.632349) (xy 106.665486 -316.59364) (xy 106.6314 -316.549497)
			(xy 106.604104 -316.500862) (xy 106.584181 -316.448771) (xy 106.572055 -316.394334) (xy 106.567984 -316.338712)
			(xy 106.31551 -316.338712) (xy 106.315001 -316.366598) (xy 106.306881 -316.421774) (xy 106.290813 -316.475181)
			(xy 106.267141 -316.525678) (xy 106.236368 -316.572191) (xy 106.199151 -316.613728) (xy 106.156283 -316.649403)
			(xy 106.108677 -316.678457) (xy 106.057348 -316.700269) (xy 106.003391 -316.714375) (xy 105.947954 -316.720475)
			(xy 105.89222 -316.718438) (xy 105.837377 -316.708308) (xy 105.784593 -316.690301) (xy 105.734993 -316.6648)
			(xy 105.689635 -316.632349) (xy 105.649486 -316.59364) (xy 105.6154 -316.549497) (xy 105.588104 -316.500862)
			(xy 105.568181 -316.448771) (xy 105.556055 -316.394334) (xy 105.551984 -316.338712) (xy 105.29951 -316.338712)
			(xy 105.299001 -316.366598) (xy 105.290881 -316.421774) (xy 105.274813 -316.475181) (xy 105.251141 -316.525678)
			(xy 105.220368 -316.572191) (xy 105.183151 -316.613728) (xy 105.140283 -316.649403) (xy 105.092677 -316.678457)
			(xy 105.041348 -316.700269) (xy 104.987391 -316.714375) (xy 104.931954 -316.720475) (xy 104.87622 -316.718438)
			(xy 104.821377 -316.708308) (xy 104.768593 -316.690301) (xy 104.718993 -316.6648) (xy 104.673635 -316.632349)
			(xy 104.633486 -316.59364) (xy 104.5994 -316.549497) (xy 104.572104 -316.500862) (xy 104.552181 -316.448771)
			(xy 104.540055 -316.394334) (xy 104.535984 -316.338712) (xy 104.28351 -316.338712) (xy 104.283001 -316.366598)
			(xy 104.274881 -316.421774) (xy 104.258813 -316.475181) (xy 104.235141 -316.525678) (xy 104.204368 -316.572191)
			(xy 104.167151 -316.613728) (xy 104.124283 -316.649403) (xy 104.076677 -316.678457) (xy 104.025348 -316.700269)
			(xy 103.971391 -316.714375) (xy 103.915954 -316.720475) (xy 103.86022 -316.718438) (xy 103.805377 -316.708308)
			(xy 103.752593 -316.690301) (xy 103.702993 -316.6648) (xy 103.657635 -316.632349) (xy 103.617486 -316.59364)
			(xy 103.5834 -316.549497) (xy 103.556104 -316.500862) (xy 103.536181 -316.448771) (xy 103.524055 -316.394334)
			(xy 103.519984 -316.338712) (xy 103.26751 -316.338712) (xy 103.267001 -316.366598) (xy 103.258881 -316.421774)
			(xy 103.242813 -316.475181) (xy 103.219141 -316.525678) (xy 103.188368 -316.572191) (xy 103.151151 -316.613728)
			(xy 103.108283 -316.649403) (xy 103.060677 -316.678457) (xy 103.009348 -316.700269) (xy 102.955391 -316.714375)
			(xy 102.899954 -316.720475) (xy 102.84422 -316.718438) (xy 102.789377 -316.708308) (xy 102.736593 -316.690301)
			(xy 102.686993 -316.6648) (xy 102.641635 -316.632349) (xy 102.601486 -316.59364) (xy 102.5674 -316.549497)
			(xy 102.540104 -316.500862) (xy 102.520181 -316.448771) (xy 102.508055 -316.394334) (xy 102.503984 -316.338712)
			(xy 90.977249 -316.338712) (xy 91.136511 -316.387582) (xy 91.320517 -316.452423) (xy 91.501705 -316.524764)
			(xy 91.679771 -316.604482) (xy 91.854414 -316.691444) (xy 92.02534 -316.785503) (xy 92.192259 -316.886499)
			(xy 92.354892 -316.994264) (xy 92.512963 -317.108614) (xy 92.666206 -317.229357) (xy 92.814363 -317.356291)
			(xy 92.957184 -317.489199) (xy 93.094428 -317.627859) (xy 93.225864 -317.772037) (xy 93.351269 -317.92149)
			(xy 93.470433 -318.075964) (xy 93.583154 -318.235201) (xy 93.689243 -318.398932) (xy 93.788521 -318.566879)
			(xy 93.880819 -318.738762) (xy 93.965984 -318.914288) (xy 94.04387 -319.093163) (xy 94.114347 -319.275085)
			(xy 94.177295 -319.459747) (xy 94.23261 -319.646837) (xy 94.280196 -319.836041) (xy 94.319975 -320.027038)
			(xy 94.351879 -320.219508) (xy 94.375854 -320.413126) (xy 94.39186 -320.607564) (xy 94.399869 -320.802496)
			(xy 94.40037 -320.900044) (xy 94.399869 -320.997592) (xy 94.39186 -321.192524) (xy 94.375854 -321.386962)
			(xy 94.351879 -321.58058) (xy 94.319975 -321.77305) (xy 94.280196 -321.964047) (xy 94.23261 -322.153251)
			(xy 94.177295 -322.340341) (xy 94.139065 -322.452492) (xy 114.964462 -322.452492) (xy 114.968533 -322.39687)
			(xy 114.980659 -322.342433) (xy 115.000582 -322.290342) (xy 115.027878 -322.241707) (xy 115.061964 -322.197564)
			(xy 115.102113 -322.158855) (xy 115.147471 -322.126404) (xy 115.197071 -322.100903) (xy 115.249855 -322.082896)
			(xy 115.304698 -322.072766) (xy 115.360432 -322.070729) (xy 115.415869 -322.076829) (xy 115.469826 -322.090935)
			(xy 115.521155 -322.112747) (xy 115.568761 -322.141801) (xy 115.611629 -322.177476) (xy 115.648846 -322.219013)
			(xy 115.679619 -322.265526) (xy 115.703291 -322.316023) (xy 115.719359 -322.36943) (xy 115.727479 -322.424606)
			(xy 115.727988 -322.452492) (xy 115.727479 -322.480378) (xy 115.719359 -322.535554) (xy 115.703291 -322.588961)
			(xy 115.679619 -322.639458) (xy 115.648846 -322.685971) (xy 115.611629 -322.727508) (xy 115.568761 -322.763183)
			(xy 115.521155 -322.792237) (xy 115.469826 -322.814049) (xy 115.415869 -322.828155) (xy 115.360432 -322.834255)
			(xy 115.304698 -322.832218) (xy 115.249855 -322.822088) (xy 115.197071 -322.804081) (xy 115.147471 -322.77858)
			(xy 115.102113 -322.746129) (xy 115.061964 -322.70742) (xy 115.027878 -322.663277) (xy 115.000582 -322.614642)
			(xy 114.980659 -322.562551) (xy 114.968533 -322.508114) (xy 114.964462 -322.452492) (xy 94.139065 -322.452492)
			(xy 94.114347 -322.525003) (xy 94.04387 -322.706925) (xy 93.965984 -322.8858) (xy 93.881557 -323.059806)
			(xy 102.316278 -323.059806) (xy 102.320349 -323.004184) (xy 102.332475 -322.949747) (xy 102.352398 -322.897656)
			(xy 102.379694 -322.849021) (xy 102.41378 -322.804878) (xy 102.453929 -322.766169) (xy 102.499287 -322.733718)
			(xy 102.548887 -322.708217) (xy 102.601671 -322.69021) (xy 102.656514 -322.68008) (xy 102.712248 -322.678043)
			(xy 102.767685 -322.684143) (xy 102.821642 -322.698249) (xy 102.872971 -322.720061) (xy 102.920577 -322.749115)
			(xy 102.963445 -322.78479) (xy 103.000662 -322.826327) (xy 103.031435 -322.87284) (xy 103.055107 -322.923337)
			(xy 103.071175 -322.976744) (xy 103.079295 -323.03192) (xy 103.079804 -323.059806) (xy 103.079295 -323.087692)
			(xy 103.071175 -323.142868) (xy 103.055107 -323.196275) (xy 103.031435 -323.246772) (xy 103.000662 -323.293285)
			(xy 102.963445 -323.334822) (xy 102.920577 -323.370497) (xy 102.872971 -323.399551) (xy 102.821642 -323.421363)
			(xy 102.767685 -323.435469) (xy 102.712248 -323.441569) (xy 102.656514 -323.439532) (xy 102.601671 -323.429402)
			(xy 102.548887 -323.411395) (xy 102.499287 -323.385894) (xy 102.453929 -323.353443) (xy 102.41378 -323.314734)
			(xy 102.379694 -323.270591) (xy 102.352398 -323.221956) (xy 102.332475 -323.169865) (xy 102.320349 -323.115428)
			(xy 102.316278 -323.059806) (xy 93.881557 -323.059806) (xy 93.880819 -323.061326) (xy 93.788521 -323.233209)
			(xy 93.689243 -323.401156) (xy 93.583154 -323.564887) (xy 93.470433 -323.724124) (xy 93.351269 -323.878598)
			(xy 93.225864 -324.028051) (xy 93.182329 -324.075806) (xy 102.316278 -324.075806) (xy 102.320349 -324.020184)
			(xy 102.332475 -323.965747) (xy 102.352398 -323.913656) (xy 102.379694 -323.865021) (xy 102.41378 -323.820878)
			(xy 102.453929 -323.782169) (xy 102.499287 -323.749718) (xy 102.548887 -323.724217) (xy 102.601671 -323.70621)
			(xy 102.656514 -323.69608) (xy 102.712248 -323.694043) (xy 102.767685 -323.700143) (xy 102.821642 -323.714249)
			(xy 102.872971 -323.736061) (xy 102.920577 -323.765115) (xy 102.963445 -323.80079) (xy 103.000662 -323.842327)
			(xy 103.031435 -323.88884) (xy 103.055107 -323.939337) (xy 103.071175 -323.992744) (xy 103.079295 -324.04792)
			(xy 103.079804 -324.075806) (xy 103.079295 -324.103692) (xy 103.071175 -324.158868) (xy 103.055107 -324.212275)
			(xy 103.031435 -324.262772) (xy 103.000662 -324.309285) (xy 102.963445 -324.350822) (xy 102.920577 -324.386497)
			(xy 102.872971 -324.415551) (xy 102.821642 -324.437363) (xy 102.767685 -324.451469) (xy 102.712248 -324.457569)
			(xy 102.656514 -324.455532) (xy 102.601671 -324.445402) (xy 102.548887 -324.427395) (xy 102.499287 -324.401894)
			(xy 102.453929 -324.369443) (xy 102.41378 -324.330734) (xy 102.379694 -324.286591) (xy 102.352398 -324.237956)
			(xy 102.332475 -324.185865) (xy 102.320349 -324.131428) (xy 102.316278 -324.075806) (xy 93.182329 -324.075806)
			(xy 93.094428 -324.172229) (xy 92.957184 -324.310889) (xy 92.814363 -324.443797) (xy 92.666206 -324.570731)
			(xy 92.512963 -324.691474) (xy 92.354892 -324.805824) (xy 92.192259 -324.913589) (xy 92.02534 -325.014585)
			(xy 91.854414 -325.108644) (xy 91.679771 -325.195606) (xy 91.501705 -325.275324) (xy 91.320517 -325.347665)
			(xy 91.136511 -325.412506) (xy 90.949998 -325.469738) (xy 90.761293 -325.519265) (xy 90.570714 -325.561002)
			(xy 90.378581 -325.59488) (xy 90.18522 -325.620842) (xy 89.990956 -325.638843) (xy 89.796117 -325.648854)
			(xy 89.601031 -325.650857) (xy 89.406028 -325.644849) (xy 89.211435 -325.63084) (xy 89.017582 -325.608854)
			(xy 88.824795 -325.578928) (xy 88.633398 -325.541112) (xy 88.443716 -325.49547) (xy 88.256068 -325.44208)
			(xy 88.070769 -325.38103) (xy 87.888134 -325.312425) (xy 87.708469 -325.236379) (xy 87.532077 -325.153021)
			(xy 87.359256 -325.062492) (xy 87.190298 -324.964944) (xy 87.025487 -324.860541) (xy 86.865101 -324.749461)
			(xy 86.709411 -324.631889) (xy 86.558679 -324.508025) (xy 86.41316 -324.378076) (xy 86.273098 -324.242263)
			(xy 86.13873 -324.100814) (xy 86.010283 -323.953968) (xy 85.887972 -323.801973) (xy 85.772005 -323.645084)
			(xy 85.662577 -323.483566) (xy 85.559872 -323.317692) (xy 85.464064 -323.147741) (xy 85.375313 -322.974)
			(xy 85.293771 -322.796762) (xy 85.219574 -322.616326) (xy 85.152847 -322.432995) (xy 85.093703 -322.24708)
			(xy 85.042242 -322.058893) (xy 84.99855 -321.868753) (xy 84.962701 -321.676978) (xy 84.934756 -321.483894)
			(xy 84.914761 -321.289825) (xy 84.902751 -321.095099) (xy 84.898745 -320.900044) (xy 72.600864 -320.900044)
			(xy 90.02903 -333.177642) (xy 90.035588 -333.18185) (xy 90.050453 -333.186497) (xy 90.05824 -333.186786)
		)
		(stroke
			(width 0)
			(type solid)
		)
		(fill yes)
		(layer "In9.Cu")
		(net "P0V8_SERDES_VDDA_PEX0")
	)
	(gr_poly
		(pts
			(xy 316.027562 -315.16066) (xy 316.037565 -315.160264) (xy 316.056117 -315.1528) (xy 316.06363 -315.146182)
			(xy 316.063884 -315.145928) (xy 317.76289 -313.446922) (xy 317.763398 -313.446414) (xy 317.769981 -313.439034)
			(xy 317.777428 -313.420734) (xy 317.777876 -313.410854) (xy 317.777876 -304.072036) (xy 317.75273 -304.043588)
			(xy 317.73368 -304.041048) (xy 317.706418 -304.037065) (xy 317.653348 -304.022272) (xy 317.602956 -304)
			(xy 317.556292 -303.970711) (xy 317.514326 -303.935016) (xy 317.47793 -303.893656) (xy 317.447861 -303.847491)
			(xy 317.424745 -303.797481) (xy 317.409062 -303.744666) (xy 317.401138 -303.690145) (xy 317.401138 -303.635052)
			(xy 317.409063 -303.580531) (xy 317.424746 -303.527716) (xy 317.447863 -303.477707) (xy 317.477932 -303.431542)
			(xy 317.514328 -303.390182) (xy 317.556295 -303.354487) (xy 317.602959 -303.325199) (xy 317.65335 -303.302927)
			(xy 317.706421 -303.288134) (xy 317.73368 -303.284128) (xy 317.75273 -303.281588) (xy 317.777876 -303.25314)
			(xy 317.777876 -301.627794) (xy 317.777591 -301.619202) (xy 317.771998 -301.602956) (xy 317.761342 -301.589478)
			(xy 317.754254 -301.584614) (xy 317.731258 -301.569559) (xy 317.689442 -301.533888) (xy 317.653181 -301.492582)
			(xy 317.623227 -301.446498) (xy 317.6002 -301.39659) (xy 317.584577 -301.343894) (xy 317.576683 -301.2895)
			(xy 317.57668 -301.234536) (xy 317.58457 -301.180142) (xy 317.600187 -301.127444) (xy 317.623209 -301.077534)
			(xy 317.653159 -301.031447) (xy 317.689416 -300.990138) (xy 317.731229 -300.954463) (xy 317.754254 -300.939454)
			(xy 317.761338 -300.93458) (xy 317.772008 -300.92111) (xy 317.777621 -300.904868) (xy 317.777876 -300.896274)
			(xy 317.777876 -298.303442) (xy 317.777626 -298.296029) (xy 317.77337 -298.281826) (xy 317.769494 -298.275502)
			(xy 317.765262 -298.269512) (xy 317.754028 -298.260093) (xy 317.747396 -298.25696) (xy 317.746888 -298.256706)
			(xy 317.665354 -298.22267) (xy 317.664846 -298.22267) (xy 317.65621 -298.21886) (xy 317.635636 -298.218606)
			(xy 317.60541 -298.231052) (xy 317.598552 -298.237402) (xy 317.577243 -298.256586) (xy 317.529947 -298.288996)
			(xy 317.478332 -298.31396) (xy 317.423561 -298.330918) (xy 317.36687 -298.339485) (xy 317.338202 -298.340018)
			(xy 317.310948 -298.339555) (xy 317.256996 -298.331798) (xy 317.204696 -298.316442) (xy 317.155114 -298.293799)
			(xy 317.10926 -298.26433) (xy 317.068066 -298.228636) (xy 317.032371 -298.187442) (xy 317.002902 -298.141587)
			(xy 316.980259 -298.092006) (xy 316.964902 -298.039706) (xy 316.957145 -297.985754) (xy 316.957145 -297.931246)
			(xy 316.964902 -297.877294) (xy 316.980259 -297.824994) (xy 317.002902 -297.775413) (xy 317.032371 -297.729558)
			(xy 317.068066 -297.688364) (xy 317.10926 -297.65267) (xy 317.155114 -297.623201) (xy 317.204696 -297.600558)
			(xy 317.256996 -297.585202) (xy 317.310948 -297.577445) (xy 317.338202 -297.577002) (xy 317.366871 -297.577517)
			(xy 317.423563 -297.586094) (xy 317.478335 -297.603053) (xy 317.529954 -297.628015) (xy 317.577259 -297.660416)
			(xy 317.598552 -297.679618) (xy 317.60541 -297.685968) (xy 317.626492 -297.694604) (xy 317.635883 -297.697887)
			(xy 317.655755 -297.697761) (xy 317.6651 -297.69435) (xy 317.74638 -297.660568) (xy 317.74765 -297.66006)
			(xy 317.754314 -297.656801) (xy 317.765548 -297.647124) (xy 317.769748 -297.64101) (xy 317.773456 -297.634761)
			(xy 317.777585 -297.620838) (xy 317.777876 -297.613578) (xy 317.777876 -296.525442) (xy 317.777626 -296.518029)
			(xy 317.77337 -296.503826) (xy 317.769494 -296.497502) (xy 317.765262 -296.491512) (xy 317.754028 -296.482093)
			(xy 317.747396 -296.47896) (xy 317.746888 -296.478706) (xy 317.665354 -296.44467) (xy 317.664846 -296.44467)
			(xy 317.65621 -296.44086) (xy 317.635636 -296.440606) (xy 317.60541 -296.453052) (xy 317.598552 -296.459402)
			(xy 317.577243 -296.478586) (xy 317.529947 -296.510996) (xy 317.478332 -296.53596) (xy 317.423561 -296.552918)
			(xy 317.36687 -296.561485) (xy 317.338202 -296.562018) (xy 317.311271 -296.561555) (xy 317.257943 -296.553982)
			(xy 317.206211 -296.538985) (xy 317.157101 -296.516863) (xy 317.111589 -296.488056) (xy 317.07058 -296.453135)
			(xy 317.03489 -296.412795) (xy 317.005225 -296.367837) (xy 316.982178 -296.319155) (xy 316.966204 -296.267715)
			(xy 316.957623 -296.214541) (xy 316.956694 -296.187622) (xy 316.956694 -296.183812) (xy 316.956694 -296.18051)
			(xy 316.95718 -296.152605) (xy 316.965314 -296.09739) (xy 316.98141 -296.043951) (xy 317.005124 -295.993429)
			(xy 317.035949 -295.946904) (xy 317.073227 -295.905369) (xy 317.094362 -295.88714) (xy 317.104014 -295.879012)
			(xy 317.113666 -295.85539) (xy 317.101474 -295.745662) (xy 317.08725 -295.724834) (xy 317.07582 -295.718992)
			(xy 317.052933 -295.706576) (xy 317.010448 -295.676474) (xy 316.972447 -295.640879) (xy 316.939635 -295.60045)
			(xy 316.912621 -295.555938) (xy 316.891905 -295.508169) (xy 316.877872 -295.458027) (xy 316.870782 -295.406444)
			(xy 316.870334 -295.38041) (xy 316.870797 -295.353158) (xy 316.878553 -295.299208) (xy 316.893908 -295.246911)
			(xy 316.916551 -295.197333) (xy 316.946019 -295.151481) (xy 316.981714 -295.110291) (xy 317.022907 -295.0746)
			(xy 317.068761 -295.045135) (xy 317.118341 -295.022497) (xy 317.170639 -295.007146) (xy 317.22459 -294.999394)
			(xy 317.251842 -294.998902) (xy 317.278539 -294.999345) (xy 317.331413 -295.006785) (xy 317.382733 -295.021526)
			(xy 317.431495 -295.043281) (xy 317.476746 -295.071624) (xy 317.517601 -295.106002) (xy 317.553262 -295.145743)
			(xy 317.583032 -295.190069) (xy 317.606328 -295.238113) (xy 317.622695 -295.288937) (xy 317.631814 -295.341548)
			(xy 317.633096 -295.368218) (xy 317.63335 -295.37533) (xy 317.63335 -295.38041) (xy 317.632841 -295.408283)
			(xy 317.624722 -295.463436) (xy 317.608661 -295.516819) (xy 317.584998 -295.567295) (xy 317.554237 -295.613787)
			(xy 317.517036 -295.655306) (xy 317.495936 -295.673526) (xy 317.48664 -295.682127) (xy 317.477182 -295.705585)
			(xy 317.477902 -295.71823) (xy 317.48857 -295.815258) (xy 317.502794 -295.836086) (xy 317.514224 -295.841928)
			(xy 317.537009 -295.854289) (xy 317.579322 -295.884235) (xy 317.598552 -295.901618) (xy 317.60541 -295.907968)
			(xy 317.626492 -295.916604) (xy 317.635883 -295.919887) (xy 317.655755 -295.919761) (xy 317.6651 -295.91635)
			(xy 317.74638 -295.882568) (xy 317.74765 -295.88206) (xy 317.754314 -295.878801) (xy 317.765548 -295.869124)
			(xy 317.769748 -295.86301) (xy 317.773456 -295.856761) (xy 317.777585 -295.842838) (xy 317.777876 -295.835578)
			(xy 317.777876 -290.924742) (xy 317.777314 -290.913147) (xy 317.767178 -290.892288) (xy 317.748962 -290.877935)
			(xy 317.737744 -290.874958) (xy 317.73749 -290.874958) (xy 317.710755 -290.868799) (xy 317.659273 -290.849841)
			(xy 317.611036 -290.823706) (xy 317.56704 -290.790933) (xy 317.528191 -290.752196) (xy 317.49529 -290.708294)
			(xy 317.469016 -290.660133) (xy 317.449909 -290.608706) (xy 317.438366 -290.555073) (xy 317.435992 -290.52774)
			(xy 317.435242 -290.520698) (xy 317.43035 -290.507415) (xy 317.42634 -290.501578) (xy 317.409353 -290.477054)
			(xy 317.382402 -290.423835) (xy 317.364065 -290.367068) (xy 317.354791 -290.308139) (xy 317.354204 -290.278312)
			(xy 317.35482 -290.246535) (xy 317.365292 -290.183852) (xy 317.375032 -290.153598) (xy 317.379858 -290.139882)
			(xy 317.373508 -290.111688) (xy 316.702186 -289.440366) (xy 316.69479 -289.433515) (xy 316.676191 -289.425775)
			(xy 316.666118 -289.42538) (xy 316.127638 -289.42538) (xy 316.082228 -289.42485) (xy 315.991792 -289.416497)
			(xy 315.902501 -289.399893) (xy 315.815107 -289.375179) (xy 315.772546 -289.35934) (xy 315.768482 -289.357816)
			(xy 315.754766 -289.355276) (xy 315.745114 -289.35426) (xy 315.424058 -289.35426) (xy 315.417708 -289.355784)
			(xy 315.406779 -289.35919) (xy 315.389223 -289.373831) (xy 315.383926 -289.383978) (xy 315.383926 -289.384232)
			(xy 315.347858 -289.464496) (xy 315.344221 -289.473755) (xy 315.343584 -289.493619) (xy 315.346588 -289.503104)
			(xy 315.3537 -289.522408) (xy 315.359288 -289.529266) (xy 315.359542 -289.52952) (xy 315.376046 -289.550267)
			(xy 315.402387 -289.59627) (xy 315.420402 -289.646126) (xy 315.429551 -289.698341) (xy 315.430154 -289.724846)
			(xy 315.429632 -289.750101) (xy 315.421319 -289.799923) (xy 315.404918 -289.847697) (xy 315.380877 -289.89212)
			(xy 315.349853 -289.93198) (xy 315.312691 -289.96619) (xy 315.270405 -289.993816) (xy 315.224149 -290.014106)
			(xy 315.175184 -290.026506) (xy 315.124846 -290.030677) (xy 315.074508 -290.026506) (xy 315.025543 -290.014106)
			(xy 314.979287 -289.993816) (xy 314.937001 -289.96619) (xy 314.899839 -289.93198) (xy 314.868815 -289.89212)
			(xy 314.844774 -289.847697) (xy 314.828373 -289.799923) (xy 314.82006 -289.750101) (xy 314.819538 -289.724846)
			(xy 314.820102 -289.698338) (xy 314.829246 -289.646116) (xy 314.847269 -289.596257) (xy 314.873629 -289.550258)
			(xy 314.89015 -289.52952) (xy 314.890404 -289.529266) (xy 314.895992 -289.522408) (xy 314.903104 -289.503104)
			(xy 314.906151 -289.493626) (xy 314.905511 -289.473747) (xy 314.901834 -289.464496) (xy 314.865766 -289.384232)
			(xy 314.865766 -289.383978) (xy 314.860449 -289.373846) (xy 314.842902 -289.359209) (xy 314.831984 -289.355784)
			(xy 314.825634 -289.35426) (xy 314.474098 -289.35426) (xy 314.467748 -289.355784) (xy 314.456827 -289.359199)
			(xy 314.439291 -289.373848) (xy 314.433966 -289.383978) (xy 314.433966 -289.384232) (xy 314.397898 -289.464496)
			(xy 314.394259 -289.473755) (xy 314.393622 -289.493619) (xy 314.396628 -289.503104) (xy 314.40374 -289.522408)
			(xy 314.409328 -289.529266) (xy 314.409582 -289.52952) (xy 314.426089 -289.550266) (xy 314.452435 -289.596268)
			(xy 314.470454 -289.646124) (xy 314.479605 -289.69834) (xy 314.480194 -289.724846) (xy 314.479672 -289.750101)
			(xy 314.471359 -289.799923) (xy 314.454958 -289.847697) (xy 314.430917 -289.89212) (xy 314.399893 -289.93198)
			(xy 314.362731 -289.96619) (xy 314.320445 -289.993816) (xy 314.274189 -290.014106) (xy 314.225224 -290.026506)
			(xy 314.174886 -290.030677) (xy 314.124548 -290.026506) (xy 314.075583 -290.014106) (xy 314.029327 -289.993816)
			(xy 313.987041 -289.96619) (xy 313.949879 -289.93198) (xy 313.918855 -289.89212) (xy 313.894814 -289.847697)
			(xy 313.878413 -289.799923) (xy 313.8701 -289.750101) (xy 313.869578 -289.724846) (xy 313.870142 -289.698338)
			(xy 313.879287 -289.646117) (xy 313.897312 -289.596259) (xy 313.923674 -289.550262) (xy 313.94019 -289.52952)
			(xy 313.940444 -289.529266) (xy 313.946032 -289.522408) (xy 313.953144 -289.503104) (xy 313.956189 -289.493625)
			(xy 313.95555 -289.473747) (xy 313.951874 -289.464496) (xy 313.915806 -289.384232) (xy 313.915806 -289.383978)
			(xy 313.910492 -289.373842) (xy 313.892949 -289.359192) (xy 313.882024 -289.355784) (xy 313.875674 -289.35426)
			(xy 313.524138 -289.35426) (xy 313.517788 -289.355784) (xy 313.506862 -289.359193) (xy 313.489312 -289.373837)
			(xy 313.484006 -289.383978) (xy 313.484006 -289.384232) (xy 313.447938 -289.464496) (xy 313.444297 -289.473755)
			(xy 313.443659 -289.493619) (xy 313.446668 -289.503104) (xy 313.45378 -289.522408) (xy 313.459368 -289.529266)
			(xy 313.459622 -289.52952) (xy 313.476127 -289.550267) (xy 313.50247 -289.596269) (xy 313.520486 -289.646125)
			(xy 313.529636 -289.698341) (xy 313.530234 -289.724846) (xy 313.529712 -289.750101) (xy 313.521399 -289.799923)
			(xy 313.504998 -289.847697) (xy 313.480957 -289.89212) (xy 313.449933 -289.93198) (xy 313.412771 -289.96619)
			(xy 313.370485 -289.993816) (xy 313.324229 -290.014106) (xy 313.275264 -290.026506) (xy 313.224926 -290.030677)
			(xy 313.174588 -290.026506) (xy 313.125623 -290.014106) (xy 313.079367 -289.993816) (xy 313.037081 -289.96619)
			(xy 312.999919 -289.93198) (xy 312.968895 -289.89212) (xy 312.944854 -289.847697) (xy 312.928453 -289.799923)
			(xy 312.92014 -289.750101) (xy 312.919618 -289.724846) (xy 312.920181 -289.698337) (xy 312.929325 -289.646115)
			(xy 312.947347 -289.596255) (xy 312.973705 -289.550255) (xy 312.99023 -289.52952) (xy 312.990484 -289.529266)
			(xy 312.996072 -289.522408) (xy 313.003184 -289.503104) (xy 313.006232 -289.493626) (xy 313.005592 -289.473747)
			(xy 313.001914 -289.464496) (xy 312.965846 -289.384232) (xy 312.965846 -289.383978) (xy 312.960527 -289.373848)
			(xy 312.942979 -289.359218) (xy 312.932064 -289.355784) (xy 312.925714 -289.35426) (xy 312.573924 -289.35426)
			(xy 312.567574 -289.355784) (xy 312.55665 -289.359196) (xy 312.539105 -289.373841) (xy 312.533792 -289.383978)
			(xy 312.533792 -289.384232) (xy 312.497724 -289.464496) (xy 312.494083 -289.473755) (xy 312.493446 -289.493619)
			(xy 312.496454 -289.503104) (xy 312.503566 -289.522408) (xy 312.509154 -289.529266) (xy 312.509408 -289.52952)
			(xy 312.525914 -289.550267) (xy 312.552258 -289.596269) (xy 312.570275 -289.646125) (xy 312.579425 -289.69834)
			(xy 312.58002 -289.724846) (xy 312.579498 -289.750101) (xy 312.571185 -289.799923) (xy 312.554784 -289.847697)
			(xy 312.530743 -289.89212) (xy 312.499719 -289.93198) (xy 312.462557 -289.96619) (xy 312.420271 -289.993816)
			(xy 312.374015 -290.014106) (xy 312.32505 -290.026506) (xy 312.274712 -290.030677) (xy 312.224374 -290.026506)
			(xy 312.175409 -290.014106) (xy 312.129153 -289.993816) (xy 312.086867 -289.96619) (xy 312.049705 -289.93198)
			(xy 312.018681 -289.89212) (xy 311.99464 -289.847697) (xy 311.978239 -289.799923) (xy 311.969926 -289.750101)
			(xy 311.969404 -289.724846) (xy 311.969967 -289.698337) (xy 311.979111 -289.646115) (xy 311.997132 -289.596255)
			(xy 312.023489 -289.550254) (xy 312.040016 -289.52952) (xy 312.04027 -289.529266) (xy 312.045858 -289.522408)
			(xy 312.05297 -289.503104) (xy 312.056018 -289.493626) (xy 312.055378 -289.473747) (xy 312.0517 -289.464496)
			(xy 312.015632 -289.384232) (xy 312.015632 -289.383978) (xy 312.01032 -289.373839) (xy 311.992779 -289.359181)
			(xy 311.98185 -289.355784) (xy 311.9755 -289.35426) (xy 311.623964 -289.35426) (xy 311.617614 -289.355784)
			(xy 311.606684 -289.359189) (xy 311.589126 -289.373829) (xy 311.583832 -289.383978) (xy 311.583832 -289.384232)
			(xy 311.547764 -289.464496) (xy 311.544127 -289.473755) (xy 311.54349 -289.493619) (xy 311.546494 -289.503104)
			(xy 311.553606 -289.522408) (xy 311.559194 -289.529266) (xy 311.559448 -289.52952) (xy 311.575952 -289.550267)
			(xy 311.602292 -289.59627) (xy 311.620307 -289.646126) (xy 311.629456 -289.698341) (xy 311.63006 -289.724846)
			(xy 311.629538 -289.750101) (xy 311.621225 -289.799923) (xy 311.604824 -289.847697) (xy 311.580783 -289.89212)
			(xy 311.549759 -289.93198) (xy 311.512597 -289.96619) (xy 311.470311 -289.993816) (xy 311.424055 -290.014106)
			(xy 311.37509 -290.026506) (xy 311.324752 -290.030677) (xy 311.274414 -290.026506) (xy 311.225449 -290.014106)
			(xy 311.179193 -289.993816) (xy 311.136907 -289.96619) (xy 311.099745 -289.93198) (xy 311.068721 -289.89212)
			(xy 311.04468 -289.847697) (xy 311.028279 -289.799923) (xy 311.019966 -289.750101) (xy 311.019444 -289.724846)
			(xy 311.020968 -289.695128) (xy 311.022238 -289.680904) (xy 311.009792 -289.654996) (xy 310.922924 -289.599878)
			(xy 310.917517 -289.596645) (xy 310.905568 -289.592663) (xy 310.899302 -289.592004) (xy 310.894877 -289.591762)
			(xy 310.886063 -289.59266) (xy 310.881776 -289.593782) (xy 310.867806 -289.597846) (xy 310.861964 -289.601148)
			(xy 310.86171 -289.601402) (xy 310.850534 -289.607752) (xy 310.820635 -289.624534) (xy 310.758855 -289.654284)
			(xy 310.72709 -289.667188) (xy 310.719978 -289.669982) (xy 310.708548 -289.679126) (xy 310.684672 -289.713416)
			(xy 310.6801 -289.727386) (xy 310.679846 -289.734752) (xy 310.678463 -289.760827) (xy 310.667915 -289.811963)
			(xy 310.648826 -289.860561) (xy 310.621753 -289.905206) (xy 310.587483 -289.944599) (xy 310.547016 -289.977592)
			(xy 310.501528 -290.003224) (xy 310.452345 -290.02075) (xy 310.400898 -290.02966) (xy 310.374792 -290.030154)
			(xy 310.349052 -290.029612) (xy 310.298305 -290.020958) (xy 310.249729 -290.003915) (xy 310.204699 -289.978965)
			(xy 310.164493 -289.946815) (xy 310.13025 -289.908376) (xy 310.102939 -289.864738) (xy 310.083336 -289.817137)
			(xy 310.077104 -289.792156) (xy 310.075834 -289.784536) (xy 310.070754 -289.775392) (xy 310.0687 -289.772023)
			(xy 310.063731 -289.765893) (xy 310.060848 -289.7632) (xy 310.03367 -289.738562) (xy 310.018176 -289.731958)
			(xy 310.009794 -289.731196) (xy 309.970678 -289.727386) (xy 309.955184 -289.725475) (xy 309.924317 -289.720775)
			(xy 309.908956 -289.717988) (xy 309.904413 -289.717258) (xy 309.895211 -289.717258) (xy 309.890668 -289.717988)
			(xy 309.875308 -289.720779) (xy 309.844441 -289.725478) (xy 309.828946 -289.727386) (xy 309.78983 -289.731196)
			(xy 309.781448 -289.731958) (xy 309.765954 -289.738562) (xy 309.738776 -289.7632) (xy 309.735889 -289.765891)
			(xy 309.730909 -289.772013) (xy 309.72887 -289.775392) (xy 309.72379 -289.784282) (xy 309.722774 -289.791902)
			(xy 309.716601 -289.816931) (xy 309.697013 -289.864611) (xy 309.669693 -289.908323) (xy 309.635419 -289.946824)
			(xy 309.595164 -289.979021) (xy 309.550072 -290.003997) (xy 309.501425 -290.021043) (xy 309.450606 -290.029674)
			(xy 309.424832 -290.030154) (xy 309.401338 -290.029724) (xy 309.354905 -290.022526) (xy 309.310124 -290.008296)
			(xy 309.268054 -289.98737) (xy 309.229688 -289.960242) (xy 309.195935 -289.927553) (xy 309.16759 -289.890077)
			(xy 309.145326 -289.848699) (xy 309.129667 -289.804398) (xy 309.120985 -289.758219) (xy 309.119778 -289.734752)
			(xy 309.119524 -289.727386) (xy 309.114952 -289.713416) (xy 309.091076 -289.679126) (xy 309.079646 -289.669982)
			(xy 309.072534 -289.667188) (xy 309.040769 -289.654283) (xy 308.978986 -289.624539) (xy 308.94909 -289.607752)
			(xy 308.937914 -289.601402) (xy 308.93766 -289.601148) (xy 308.931818 -289.597846) (xy 308.917848 -289.593782)
			(xy 308.913556 -289.592688) (xy 308.904746 -289.591794) (xy 308.900322 -289.592004) (xy 308.894055 -289.592658)
			(xy 308.882102 -289.596634) (xy 308.8767 -289.599878) (xy 308.789832 -289.654996) (xy 308.777386 -289.680904)
			(xy 308.778656 -289.695128) (xy 308.78018 -289.724846) (xy 308.779658 -289.750101) (xy 308.771345 -289.799923)
			(xy 308.754944 -289.847697) (xy 308.730903 -289.89212) (xy 308.699879 -289.93198) (xy 308.662717 -289.96619)
			(xy 308.620431 -289.993816) (xy 308.574175 -290.014106) (xy 308.52521 -290.026506) (xy 308.474872 -290.030677)
			(xy 308.424534 -290.026506) (xy 308.375569 -290.014106) (xy 308.329313 -289.993816) (xy 308.287027 -289.96619)
			(xy 308.249865 -289.93198) (xy 308.218841 -289.89212) (xy 308.1948 -289.847697) (xy 308.178399 -289.799923)
			(xy 308.170086 -289.750101) (xy 308.169564 -289.724846) (xy 308.170093 -289.698744) (xy 308.178964 -289.6473)
			(xy 308.196455 -289.598115) (xy 308.222056 -289.55262) (xy 308.238144 -289.53206) (xy 308.247542 -289.52063)
			(xy 308.251098 -289.49142) (xy 308.205378 -289.395154) (xy 308.200897 -289.386665) (xy 308.186865 -289.373587)
			(xy 308.168997 -289.366612) (xy 308.159404 -289.366198) (xy 306.89042 -289.366198) (xy 306.880836 -289.366611)
			(xy 306.862999 -289.373636) (xy 306.848958 -289.386688) (xy 306.844446 -289.395154) (xy 306.798726 -289.49142)
			(xy 306.802282 -289.52063) (xy 306.81168 -289.53206) (xy 306.82775 -289.552634) (xy 306.853354 -289.598125)
			(xy 306.870852 -289.647306) (xy 306.879735 -289.698746) (xy 306.88026 -289.724846) (xy 306.879738 -289.750101)
			(xy 306.871425 -289.799923) (xy 306.855024 -289.847697) (xy 306.830983 -289.89212) (xy 306.799959 -289.93198)
			(xy 306.762797 -289.96619) (xy 306.720511 -289.993816) (xy 306.674255 -290.014106) (xy 306.62529 -290.026506)
			(xy 306.574952 -290.030677) (xy 306.524614 -290.026506) (xy 306.475649 -290.014106) (xy 306.429393 -289.993816)
			(xy 306.387107 -289.96619) (xy 306.349945 -289.93198) (xy 306.318921 -289.89212) (xy 306.29488 -289.847697)
			(xy 306.278479 -289.799923) (xy 306.270166 -289.750101) (xy 306.269644 -289.724846) (xy 306.270173 -289.698744)
			(xy 306.279043 -289.6473) (xy 306.296533 -289.598114) (xy 306.322133 -289.552618) (xy 306.338224 -289.53206)
			(xy 306.347622 -289.52063) (xy 306.351178 -289.49142) (xy 306.305458 -289.395154) (xy 306.300981 -289.386655)
			(xy 306.286953 -289.373556) (xy 306.269082 -289.366553) (xy 306.259484 -289.366198) (xy 305.940206 -289.366198)
			(xy 305.930623 -289.366613) (xy 305.912791 -289.373642) (xy 305.898754 -289.386694) (xy 305.894232 -289.395154)
			(xy 305.848512 -289.49142) (xy 305.852068 -289.52063) (xy 305.861466 -289.53206) (xy 305.877536 -289.552634)
			(xy 305.903142 -289.598124) (xy 305.920641 -289.647305) (xy 305.929524 -289.698745) (xy 305.930046 -289.724846)
			(xy 305.929524 -289.750101) (xy 305.921211 -289.799923) (xy 305.90481 -289.847697) (xy 305.880769 -289.89212)
			(xy 305.849745 -289.93198) (xy 305.812583 -289.96619) (xy 305.770297 -289.993816) (xy 305.724041 -290.014106)
			(xy 305.675076 -290.026506) (xy 305.624738 -290.030677) (xy 305.5744 -290.026506) (xy 305.525435 -290.014106)
			(xy 305.479179 -289.993816) (xy 305.436893 -289.96619) (xy 305.399731 -289.93198) (xy 305.368707 -289.89212)
			(xy 305.344666 -289.847697) (xy 305.328265 -289.799923) (xy 305.319952 -289.750101) (xy 305.31943 -289.724846)
			(xy 305.319569 -289.712083) (xy 305.321733 -289.686649) (xy 305.323748 -289.674046) (xy 305.323494 -289.674046)
			(xy 305.327941 -289.650367) (xy 305.343304 -289.604706) (xy 305.365652 -289.562026) (xy 305.394428 -289.523388)
			(xy 305.428919 -289.489752) (xy 305.468267 -289.461953) (xy 305.511494 -289.440683) (xy 305.557526 -289.42647)
			(xy 305.581304 -289.422586) (xy 305.594004 -289.420808) (xy 305.62423 -289.419284) (xy 305.624738 -289.419284)
			(xy 305.650176 -289.419793) (xy 305.700349 -289.428224) (xy 305.72456 -289.436048) (xy 305.732434 -289.438842)
			(xy 305.74107 -289.438842) (xy 305.751085 -289.43836) (xy 305.769594 -289.430707) (xy 305.783767 -289.416554)
			(xy 305.791446 -289.398056) (xy 305.79187 -289.388042) (xy 305.79187 -289.378898) (xy 305.80584 -289.349434)
			(xy 305.808078 -289.344319) (xy 305.810511 -289.333425) (xy 305.810666 -289.327844) (xy 305.810666 -289.172904)
			(xy 305.810412 -289.16757) (xy 305.80959 -289.161612) (xy 305.805485 -289.15031) (xy 305.802284 -289.145218)
			(xy 305.800043 -289.141878) (xy 305.794684 -289.135881) (xy 305.791616 -289.13328) (xy 305.774344 -289.119564)
			(xy 305.773582 -289.118802) (xy 305.731418 -289.084512) (xy 305.724456 -289.079307) (xy 305.708098 -289.073455)
			(xy 305.699414 -289.073082) (xy 305.691286 -289.073082) (xy 305.686206 -289.074098) (xy 305.671254 -289.076939)
			(xy 305.640972 -289.079994) (xy 305.625754 -289.080194) (xy 305.603148 -289.080194) (xy 305.594766 -289.079432)
			(xy 305.57343 -289.075876) (xy 305.567588 -289.074606) (xy 305.566572 -289.074606) (xy 305.543675 -289.069732)
			(xy 305.499617 -289.053908) (xy 305.458492 -289.031543) (xy 305.421262 -289.003163) (xy 305.388802 -288.969433)
			(xy 305.36187 -288.931142) (xy 305.3411 -288.889189) (xy 305.326977 -288.844557) (xy 305.319833 -288.798293)
			(xy 305.31943 -288.774886) (xy 305.319877 -288.750895) (xy 305.327386 -288.703503) (xy 305.342216 -288.65787)
			(xy 305.364003 -288.615118) (xy 305.392209 -288.576302) (xy 305.426141 -288.542376) (xy 305.464963 -288.514176)
			(xy 305.507718 -288.492396) (xy 305.553354 -288.477574) (xy 305.600747 -288.470073) (xy 305.624738 -288.469578)
			(xy 305.647829 -288.469963) (xy 305.693493 -288.476851) (xy 305.71567 -288.483294) (xy 305.718718 -288.48431)
			(xy 305.721258 -288.484818) (xy 305.726338 -288.486342) (xy 305.72964 -288.487612) (xy 305.750722 -288.492184)
			(xy 305.759866 -288.492184) (xy 305.769891 -288.49177) (xy 305.788417 -288.484106) (xy 305.802596 -288.469932)
			(xy 305.810267 -288.451409) (xy 305.810666 -288.441384) (xy 305.810666 -288.422588) (xy 305.805586 -288.406332)
			(xy 305.800506 -288.399474) (xy 305.790978 -288.386536) (xy 305.772687 -288.360114) (xy 305.76393 -288.346642)
			(xy 305.746431 -288.318967) (xy 305.71478 -288.261641) (xy 305.700684 -288.232088) (xy 305.694334 -288.218118)
			(xy 305.677824 -288.178494) (xy 305.67757 -288.177732) (xy 305.676808 -288.175954) (xy 305.673976 -288.169465)
			(xy 305.665338 -288.158254) (xy 305.65979 -288.153856) (xy 305.652678 -288.148776) (xy 305.641502 -288.141664)
			(xy 305.629818 -288.136076) (xy 305.611022 -288.12998) (xy 305.604672 -288.129726) (xy 305.57922 -288.127505)
			(xy 305.529526 -288.115662) (xy 305.482492 -288.095721) (xy 305.439429 -288.068237) (xy 305.401535 -288.033975)
			(xy 305.369866 -287.993889) (xy 305.345304 -287.949095) (xy 305.328531 -287.900841) (xy 305.320016 -287.850469)
			(xy 305.31943 -287.824926) (xy 305.319943 -287.79939) (xy 305.328433 -287.749027) (xy 305.34518 -287.700779)
			(xy 305.369718 -287.655987) (xy 305.401364 -287.6159) (xy 305.439236 -287.581634) (xy 305.482279 -287.554144)
			(xy 305.529295 -287.534196) (xy 305.578973 -287.522344) (xy 305.604418 -287.520126) (xy 305.611022 -287.519872)
			(xy 305.628802 -287.51403) (xy 305.637184 -287.510982) (xy 305.659282 -287.495996) (xy 305.664362 -287.488884)
			(xy 305.67503 -287.476184) (xy 305.679602 -287.466786) (xy 305.680364 -287.465008) (xy 305.680618 -287.4645)
			(xy 305.688685 -287.444733) (xy 305.706345 -287.405857) (xy 305.715924 -287.386776) (xy 305.72075 -287.377378)
			(xy 305.737593 -287.346163) (xy 305.775224 -287.286031) (xy 305.795934 -287.257236) (xy 305.800506 -287.250886)
			(xy 305.810666 -287.220406) (xy 305.810666 -287.204658) (xy 305.809997 -287.192588) (xy 305.798987 -287.171107)
			(xy 305.789584 -287.16351) (xy 305.779678 -287.156398) (xy 305.755548 -287.152588) (xy 305.740562 -287.157668)
			(xy 305.739038 -287.158176) (xy 305.711955 -287.168354) (xy 305.655184 -287.179478) (xy 305.626262 -287.180274)
			(xy 305.620674 -287.180274) (xy 305.591718 -287.178496) (xy 305.567094 -287.175331) (xy 305.519258 -287.162053)
			(xy 305.474202 -287.141209) (xy 305.433111 -287.11335) (xy 305.39707 -287.07921) (xy 305.367027 -287.039688)
			(xy 305.343776 -286.995826) (xy 305.327928 -286.948779) (xy 305.3199 -286.899788) (xy 305.31943 -286.874966)
			(xy 305.319879 -286.850976) (xy 305.32739 -286.803587) (xy 305.342222 -286.757956) (xy 305.36401 -286.715207)
			(xy 305.392217 -286.676393) (xy 305.426148 -286.64247) (xy 305.464969 -286.614272) (xy 305.507722 -286.592494)
			(xy 305.553357 -286.577673) (xy 305.600748 -286.570173) (xy 305.624738 -286.569658) (xy 305.647829 -286.570043)
			(xy 305.693493 -286.576931) (xy 305.71567 -286.583374) (xy 305.718718 -286.58439) (xy 305.721258 -286.584898)
			(xy 305.726338 -286.586422) (xy 305.72964 -286.587692) (xy 305.750722 -286.592264) (xy 305.759866 -286.592264)
			(xy 305.769889 -286.59185) (xy 305.788411 -286.584185) (xy 305.802586 -286.57001) (xy 305.81025 -286.551487)
			(xy 305.810666 -286.541464) (xy 305.810666 -286.522414) (xy 305.805586 -286.506158) (xy 305.800506 -286.4993)
			(xy 305.790978 -286.486362) (xy 305.772686 -286.45994) (xy 305.76393 -286.446468) (xy 305.74643 -286.418794)
			(xy 305.714778 -286.361468) (xy 305.700684 -286.331914) (xy 305.694334 -286.317944) (xy 305.677824 -286.27832)
			(xy 305.67757 -286.277558) (xy 305.676808 -286.27578) (xy 305.673979 -286.269289) (xy 305.665344 -286.258074)
			(xy 305.65979 -286.253682) (xy 305.652678 -286.248602) (xy 305.641502 -286.24149) (xy 305.629818 -286.235902)
			(xy 305.611022 -286.229806) (xy 305.604672 -286.229552) (xy 305.57922 -286.227331) (xy 305.529523 -286.215489)
			(xy 305.482488 -286.195548) (xy 305.439422 -286.168064) (xy 305.401526 -286.133803) (xy 305.369854 -286.093717)
			(xy 305.345288 -286.048923) (xy 305.328512 -286.000668) (xy 305.319992 -285.950296) (xy 305.31943 -285.924752)
			(xy 305.319941 -285.899214) (xy 305.328427 -285.848849) (xy 305.345172 -285.800596) (xy 305.369709 -285.755801)
			(xy 305.401354 -285.71571) (xy 305.439227 -285.681441) (xy 305.482271 -285.653948) (xy 305.529289 -285.633997)
			(xy 305.57897 -285.622144) (xy 305.604418 -285.619952) (xy 305.611022 -285.619698) (xy 305.628802 -285.613856)
			(xy 305.637184 -285.610808) (xy 305.659282 -285.595822) (xy 305.664362 -285.58871) (xy 305.67503 -285.57601)
			(xy 305.679602 -285.566612) (xy 305.680364 -285.564834) (xy 305.680618 -285.564326) (xy 305.688685 -285.544559)
			(xy 305.706344 -285.505682) (xy 305.715924 -285.486602) (xy 305.72075 -285.477204) (xy 305.737593 -285.445989)
			(xy 305.775222 -285.385856) (xy 305.795934 -285.357062) (xy 305.800506 -285.350712) (xy 305.810666 -285.320232)
			(xy 305.810666 -285.304484) (xy 305.810003 -285.292411) (xy 305.798999 -285.270921) (xy 305.789584 -285.263336)
			(xy 305.779678 -285.256224) (xy 305.755548 -285.252414) (xy 305.740562 -285.257494) (xy 305.739038 -285.258002)
			(xy 305.711954 -285.268179) (xy 305.655184 -285.279302) (xy 305.626262 -285.2801) (xy 305.620674 -285.2801)
			(xy 305.591718 -285.278322) (xy 305.567093 -285.275157) (xy 305.519256 -285.261879) (xy 305.474197 -285.241037)
			(xy 305.433104 -285.213178) (xy 305.39706 -285.179038) (xy 305.367015 -285.139516) (xy 305.34376 -285.095654)
			(xy 305.327908 -285.048607) (xy 305.319877 -284.999615) (xy 305.31943 -284.974792) (xy 305.319877 -284.9508)
			(xy 305.327385 -284.903408) (xy 305.342215 -284.857774) (xy 305.364001 -284.815022) (xy 305.392207 -284.776204)
			(xy 305.426139 -284.742277) (xy 305.464961 -284.714077) (xy 305.507716 -284.692297) (xy 305.553353 -284.677474)
			(xy 305.600746 -284.669973) (xy 305.624738 -284.669484) (xy 305.647829 -284.669869) (xy 305.693493 -284.676757)
			(xy 305.71567 -284.6832) (xy 305.718718 -284.684216) (xy 305.721258 -284.684724) (xy 305.726338 -284.686248)
			(xy 305.72964 -284.687518) (xy 305.750722 -284.69209) (xy 305.759866 -284.69209) (xy 305.769891 -284.691676)
			(xy 305.788418 -284.684012) (xy 305.802599 -284.669838) (xy 305.810272 -284.651315) (xy 305.810666 -284.64129)
			(xy 305.810666 -284.622494) (xy 305.805586 -284.606238) (xy 305.800506 -284.59938) (xy 305.790978 -284.586442)
			(xy 305.772687 -284.56002) (xy 305.76393 -284.546548) (xy 305.746431 -284.518873) (xy 305.714779 -284.461548)
			(xy 305.700684 -284.431994) (xy 305.694334 -284.418024) (xy 305.677824 -284.3784) (xy 305.67757 -284.377638)
			(xy 305.676808 -284.37586) (xy 305.673977 -284.369371) (xy 305.66534 -284.358159) (xy 305.65979 -284.353762)
			(xy 305.652678 -284.348682) (xy 305.641502 -284.34157) (xy 305.629818 -284.335982) (xy 305.611022 -284.329886)
			(xy 305.604672 -284.329632) (xy 305.57922 -284.327411) (xy 305.529525 -284.315568) (xy 305.482491 -284.295627)
			(xy 305.439427 -284.268143) (xy 305.401533 -284.233881) (xy 305.369864 -284.193795) (xy 305.3453 -284.149001)
			(xy 305.328527 -284.100747) (xy 305.32001 -284.050375) (xy 305.31943 -284.024832) (xy 305.319943 -283.999295)
			(xy 305.328432 -283.948932) (xy 305.345178 -283.900683) (xy 305.369716 -283.85589) (xy 305.401362 -283.815802)
			(xy 305.439234 -283.781536) (xy 305.482277 -283.754045) (xy 305.529293 -283.734096) (xy 305.578972 -283.722244)
			(xy 305.604418 -283.720032) (xy 305.611022 -283.719778) (xy 305.628802 -283.713936) (xy 305.637184 -283.710888)
			(xy 305.659282 -283.695902) (xy 305.664362 -283.68879) (xy 305.67503 -283.67609) (xy 305.679602 -283.666692)
			(xy 305.680364 -283.664914) (xy 305.680618 -283.664406) (xy 305.688685 -283.644639) (xy 305.706345 -283.605762)
			(xy 305.715924 -283.586682) (xy 305.72075 -283.577284) (xy 305.737593 -283.546069) (xy 305.775224 -283.485937)
			(xy 305.795934 -283.457142) (xy 305.800506 -283.450792) (xy 305.810666 -283.420312) (xy 305.810666 -283.404564)
			(xy 305.809998 -283.392493) (xy 305.79899 -283.37101) (xy 305.789584 -283.363416) (xy 305.779678 -283.356304)
			(xy 305.755548 -283.352494) (xy 305.740562 -283.357574) (xy 305.739038 -283.358082) (xy 305.711954 -283.36826)
			(xy 305.655184 -283.379383) (xy 305.626262 -283.38018) (xy 305.62042 -283.38018) (xy 305.596078 -283.379357)
			(xy 305.548108 -283.370939) (xy 305.502082 -283.355015) (xy 305.459166 -283.331988) (xy 305.420449 -283.302442)
			(xy 305.386912 -283.267126) (xy 305.359404 -283.226935) (xy 305.338624 -283.182888) (xy 305.325097 -283.136101)
			(xy 305.319166 -283.087761) (xy 305.320983 -283.039091) (xy 305.3305 -282.991328) (xy 305.347477 -282.945679)
			(xy 305.359054 -282.92425) (xy 305.371825 -282.902742) (xy 305.403252 -282.863831) (xy 305.440597 -282.830557)
			(xy 305.482861 -282.803809) (xy 305.528917 -282.784299) (xy 305.55311 -282.777946) (xy 305.559968 -282.777946)
			(xy 305.57597 -282.773628) (xy 305.580796 -282.772612) (xy 305.594766 -282.770326) (xy 305.603148 -282.769564)
			(xy 305.625754 -282.769564) (xy 305.639937 -282.769748) (xy 305.668177 -282.772417) (xy 305.682142 -282.774898)
			(xy 305.685952 -282.77566) (xy 305.688746 -282.776168) (xy 305.699668 -282.778454) (xy 305.721512 -282.77312)
			(xy 305.773582 -282.730956) (xy 305.774344 -282.730194) (xy 305.791616 -282.716478) (xy 305.800422 -282.708804)
			(xy 305.810502 -282.687763) (xy 305.81092 -282.676092) (xy 305.810666 -282.653486) (xy 305.810666 -282.52293)
			(xy 305.810128 -282.511392) (xy 305.800088 -282.490617) (xy 305.791362 -282.483052) (xy 305.785266 -282.478226)
			(xy 305.72075 -282.425648) (xy 305.70932 -282.42387) (xy 305.698906 -282.42133) (xy 305.687476 -282.423616)
			(xy 305.672161 -282.426656) (xy 305.641112 -282.42996) (xy 305.6255 -282.43022) (xy 305.623214 -282.43022)
			(xy 305.622452 -282.43022) (xy 305.596697 -282.429513) (xy 305.545969 -282.420529) (xy 305.497466 -282.403162)
			(xy 305.452565 -282.377904) (xy 305.412538 -282.34547) (xy 305.37852 -282.306781) (xy 305.351475 -282.262933)
			(xy 305.33217 -282.215168) (xy 305.321153 -282.164842) (xy 305.31943 -282.139136) (xy 305.319176 -282.13177)
			(xy 305.31435 -282.1178) (xy 305.294538 -282.090114) (xy 305.290089 -282.084319) (xy 305.278611 -282.075293)
			(xy 305.271932 -282.072334) (xy 305.271678 -282.072334) (xy 305.215544 -282.04795) (xy 305.215036 -282.04795)
			(xy 305.178714 -282.03017) (xy 305.173126 -282.027122) (xy 305.162204 -282.024836) (xy 305.151028 -282.022042)
			(xy 305.12639 -282.027376) (xy 305.119786 -282.030678) (xy 305.119532 -282.030932) (xy 305.097036 -282.042398)
			(xy 305.051038 -282.063237) (xy 305.027584 -282.072588) (xy 305.016662 -282.076906) (xy 305.004978 -282.089606)
			(xy 305.002946 -282.0924) (xy 304.991262 -282.10891) (xy 304.988514 -282.112854) (xy 304.984418 -282.12155)
			(xy 304.983134 -282.126182) (xy 304.979832 -282.13939) (xy 304.979578 -282.143962) (xy 304.977443 -282.169468)
			(xy 304.965737 -282.219292) (xy 304.945884 -282.266466) (xy 304.91844 -282.309666) (xy 304.884175 -282.347684)
			(xy 304.844047 -282.379452) (xy 304.799183 -282.404082) (xy 304.750838 -282.420883) (xy 304.700369 -282.429384)
			(xy 304.674778 -282.429966) (xy 304.674524 -282.429966) (xy 304.648697 -282.42942) (xy 304.597781 -282.420719)
			(xy 304.549054 -282.403579) (xy 304.503903 -282.378488) (xy 304.463616 -282.346159) (xy 304.429341 -282.307516)
			(xy 304.402053 -282.263658) (xy 304.38253 -282.215836) (xy 304.371329 -282.165411) (xy 304.36947 -282.139644)
			(xy 304.368708 -282.125166) (xy 304.34788 -282.094686) (xy 304.344832 -282.090876) (xy 304.342038 -282.08732)
			(xy 304.338588 -282.083378) (xy 304.330393 -282.076854) (xy 304.325782 -282.074366) (xy 304.321464 -282.072334)
			(xy 304.300648 -282.063968) (xy 304.259737 -282.045547) (xy 304.239676 -282.035504) (xy 304.237898 -282.03398)
			(xy 304.23231 -282.03144) (xy 304.230278 -282.030424) (xy 304.22977 -282.03017) (xy 304.22342 -282.026868)
			(xy 304.211482 -282.024074) (xy 304.205564 -282.022888) (xy 304.193499 -282.023024) (xy 304.187606 -282.024328)
			(xy 304.175922 -282.027376) (xy 304.170842 -282.03017) (xy 304.149506 -282.040838) (xy 304.138584 -282.046172)
			(xy 304.12817 -282.050998) (xy 304.116232 -282.056332) (xy 304.115978 -282.056332) (xy 304.046636 -282.086812)
			(xy 304.030126 -282.111704) (xy 304.030126 -282.126944) (xy 304.029489 -282.15082) (xy 304.021706 -282.197943)
			(xy 304.006681 -282.243278) (xy 303.98478 -282.285722) (xy 303.956537 -282.324237) (xy 303.922643 -282.357886)
			(xy 303.883922 -282.385847) (xy 303.84132 -282.407438) (xy 303.795876 -282.422132) (xy 303.748698 -282.429571)
			(xy 303.724818 -282.429966) (xy 303.724564 -282.429966) (xy 303.698721 -282.429422) (xy 303.647773 -282.420717)
			(xy 303.599016 -282.403562) (xy 303.553842 -282.378446) (xy 303.51354 -282.346086) (xy 303.479258 -282.307405)
			(xy 303.451975 -282.263506) (xy 303.432469 -282.215641) (xy 303.421297 -282.165177) (xy 303.41951 -282.13939)
			(xy 303.419002 -282.124912) (xy 303.391062 -282.084526) (xy 303.379632 -282.075636) (xy 303.37252 -282.072588)
			(xy 303.3395 -282.058872) (xy 303.31156 -282.046172) (xy 303.28743 -282.034234) (xy 303.249838 -282.013914)
			(xy 303.229518 -282.02509) (xy 303.204617 -282.038267) (xy 303.15353 -282.062031) (xy 303.12741 -282.072588)
			(xy 303.126902 -282.072842) (xy 303.120283 -282.07572) (xy 303.108939 -282.084636) (xy 303.10455 -282.090368)
			(xy 303.084992 -282.117546) (xy 303.080166 -282.131262) (xy 303.079912 -282.138628) (xy 303.078709 -282.158123)
			(xy 303.071956 -282.196596) (xy 303.06645 -282.215336) (xy 303.064672 -282.22067) (xy 303.064418 -282.221178)
			(xy 303.056613 -282.243209) (xy 303.035261 -282.284785) (xy 303.007823 -282.322622) (xy 302.974939 -282.355835)
			(xy 302.937379 -282.38365) (xy 302.896018 -282.405415) (xy 302.851824 -282.420624) (xy 302.805828 -282.428921)
			(xy 302.782478 -282.429966) (xy 302.774604 -282.429966) (xy 302.74875 -282.429416) (xy 302.697783 -282.420694)
			(xy 302.649012 -282.403515) (xy 302.603829 -282.37837) (xy 302.563525 -282.345977) (xy 302.52925 -282.30726)
			(xy 302.501983 -282.263326) (xy 302.482503 -282.215427) (xy 302.471365 -282.164933) (xy 302.46955 -282.139136)
			(xy 302.469296 -282.13177) (xy 302.464724 -282.118054) (xy 302.44161 -282.08478) (xy 302.43018 -282.07589)
			(xy 302.423068 -282.073096) (xy 302.399471 -282.063435) (xy 302.353219 -282.041961) (xy 302.330612 -282.03017)
			(xy 302.326548 -282.028138) (xy 302.3235 -282.026868) (xy 302.312591 -282.022013) (xy 302.288745 -282.021886)
			(xy 302.27778 -282.026614) (xy 302.267112 -282.031948) (xy 302.26635 -282.03271) (xy 302.250713 -282.040579)
			(xy 302.218955 -282.055315) (xy 302.20285 -282.062174) (xy 302.197262 -282.06446) (xy 302.194722 -282.06573)
			(xy 302.177196 -282.073096) (xy 302.170338 -282.07589) (xy 302.158908 -282.085034) (xy 302.142652 -282.10891)
			(xy 302.136302 -282.121356) (xy 302.130206 -282.138882) (xy 302.129698 -282.145994) (xy 302.12752 -282.170211)
			(xy 302.116466 -282.217559) (xy 302.098056 -282.262559) (xy 302.072753 -282.304077) (xy 302.041197 -282.341066)
			(xy 302.004184 -282.372593) (xy 301.962646 -282.397863) (xy 301.917631 -282.416238) (xy 301.870275 -282.427255)
			(xy 301.821772 -282.430637) (xy 301.773345 -282.426297) (xy 301.726217 -282.414345) (xy 301.70374 -282.405074)
			(xy 301.703232 -282.40482) (xy 301.699422 -282.403042) (xy 301.699168 -282.402788) (xy 301.677227 -282.392364)
			(xy 301.636681 -282.365617) (xy 301.600879 -282.332791) (xy 301.570723 -282.294712) (xy 301.546973 -282.252341)
			(xy 301.530228 -282.206745) (xy 301.52091 -282.159074) (xy 301.51959 -282.134818) (xy 301.519082 -282.122626)
			(xy 301.501302 -282.090368) (xy 301.488348 -282.078938) (xy 301.48022 -282.075636) (xy 301.474124 -282.073096)
			(xy 301.473616 -282.072842) (xy 301.461678 -282.06827) (xy 301.460662 -282.067762) (xy 301.459646 -282.067254)
			(xy 301.457868 -282.066492) (xy 301.43644 -282.057478) (xy 301.394384 -282.037659) (xy 301.373794 -282.026868)
			(xy 301.368206 -282.024074) (xy 301.356268 -282.021026) (xy 301.34306 -282.021026) (xy 301.331122 -282.024074)
			(xy 301.325534 -282.026868) (xy 301.298204 -282.041138) (xy 301.242025 -282.066556) (xy 301.213266 -282.077668)
			(xy 301.203789 -282.081731) (xy 301.18888 -282.095948) (xy 301.180728 -282.114868) (xy 301.180246 -282.125166)
			(xy 301.179678 -282.151203) (xy 301.170762 -282.202509) (xy 301.153268 -282.251558) (xy 301.127704 -282.296926)
			(xy 301.094811 -282.337298) (xy 301.055543 -282.371501) (xy 301.01104 -282.398544) (xy 300.962594 -282.417643)
			(xy 300.911608 -282.428242) (xy 300.885606 -282.429712) (xy 300.876716 -282.429966) (xy 300.874684 -282.429966)
			(xy 300.848654 -282.429439) (xy 300.797346 -282.420613) (xy 300.748277 -282.403218) (xy 300.702867 -282.377758)
			(xy 300.662428 -282.34497) (xy 300.628132 -282.305802) (xy 300.60097 -282.261388) (xy 300.581729 -282.213013)
			(xy 300.570966 -282.162077) (xy 300.569376 -282.136088) (xy 300.569122 -282.128214) (xy 300.563788 -282.113482)
			(xy 300.546008 -282.090114) (xy 300.536356 -282.080462) (xy 300.529498 -282.075128) (xy 300.523148 -282.072588)
			(xy 300.499427 -282.063068) (xy 300.45292 -282.041848) (xy 300.430184 -282.03017) (xy 300.424596 -282.027122)
			(xy 300.411896 -282.024328) (xy 300.406313 -282.023126) (xy 300.394896 -282.022989) (xy 300.38929 -282.024074)
			(xy 300.376336 -282.027122) (xy 300.370494 -282.03017) (xy 300.354434 -282.038511) (xy 300.321786 -282.054136)
			(xy 300.305216 -282.061412) (xy 300.277022 -282.073096) (xy 300.26991 -282.07589) (xy 300.25848 -282.085034)
			(xy 300.234858 -282.118562) (xy 300.230286 -282.132024) (xy 300.230032 -282.13939) (xy 300.228322 -282.164751)
			(xy 300.217542 -282.21442) (xy 300.198689 -282.261621) (xy 300.172285 -282.30505) (xy 300.139056 -282.34351)
			(xy 300.09992 -282.37594) (xy 300.055957 -282.401445) (xy 300.008379 -282.419322) (xy 299.958498 -282.429078)
			(xy 299.933106 -282.43022) (xy 299.925486 -282.43022) (xy 299.899561 -282.42973) (xy 299.848437 -282.42109)
			(xy 299.799506 -282.403943) (xy 299.754173 -282.37878) (xy 299.713739 -282.346324) (xy 299.679366 -282.307506)
			(xy 299.652041 -282.263443) (xy 299.632548 -282.215398) (xy 299.621447 -282.164752) (xy 299.61967 -282.138882)
			(xy 299.619416 -282.131516) (xy 299.614844 -282.118054) (xy 299.596048 -282.091638) (xy 299.592238 -282.086304)
			(xy 299.583094 -282.078176) (xy 299.574204 -282.073858) (xy 299.57141 -282.072588) (xy 299.570394 -282.07208)
			(xy 299.547065 -282.062586) (xy 299.501323 -282.041491) (xy 299.478954 -282.029916) (xy 299.47362 -282.027122)
			(xy 299.450506 -282.021534) (xy 299.432218 -282.023566) (xy 299.423836 -282.028138) (xy 299.378116 -282.050998)
			(xy 299.377608 -282.050998) (xy 299.328332 -282.07208) (xy 299.321474 -282.07462) (xy 299.31487 -282.0797)
			(xy 299.311985 -282.082017) (xy 299.306881 -282.087372) (xy 299.30471 -282.090368) (xy 299.28947 -282.111704)
			(xy 299.285152 -282.117546) (xy 299.280072 -282.132024) (xy 299.279818 -282.139644) (xy 299.27806 -282.165255)
			(xy 299.267057 -282.215394) (xy 299.247822 -282.262987) (xy 299.220898 -282.306691) (xy 299.187043 -282.345277)
			(xy 299.147211 -282.377657) (xy 299.102525 -282.402918) (xy 299.054243 -282.42035) (xy 299.003726 -282.42946)
			(xy 298.978066 -282.43022) (xy 298.974764 -282.43022) (xy 298.94888 -282.429672) (xy 298.897854 -282.420939)
			(xy 298.84903 -282.403728) (xy 298.803807 -282.378533) (xy 298.763479 -282.346074) (xy 298.7292 -282.307281)
			(xy 298.701951 -282.263265) (xy 298.682513 -282.215284) (xy 298.671443 -282.164714) (xy 298.66971 -282.138882)
			(xy 298.669168 -282.131146) (xy 298.663998 -282.116532) (xy 298.65955 -282.11018) (xy 298.648882 -282.095702)
			(xy 298.648882 -282.095194) (xy 298.63542 -282.07716) (xy 298.627857 -282.067978) (xy 298.606658 -282.057253)
			(xy 298.59478 -282.056586) (xy 298.584874 -282.056586) (xy 298.529248 -282.029916) (xy 298.528994 -282.029662)
			(xy 298.521374 -282.025852) (xy 298.513246 -282.02382) (xy 298.507663 -282.022624) (xy 298.496249 -282.022498)
			(xy 298.49064 -282.023566) (xy 298.47794 -282.02636) (xy 298.47159 -282.029662) (xy 298.455412 -282.038144)
			(xy 298.42251 -282.054023) (xy 298.405804 -282.061412) (xy 298.377102 -282.07335) (xy 298.36999 -282.076144)
			(xy 298.35856 -282.085288) (xy 298.334938 -282.11907) (xy 298.330366 -282.132278) (xy 298.330112 -282.139644)
			(xy 298.328434 -282.164172) (xy 298.318228 -282.212261) (xy 298.300452 -282.258095) (xy 298.275564 -282.300491)
			(xy 298.244209 -282.338353) (xy 298.207194 -282.370705) (xy 298.165475 -282.396711) (xy 298.120131 -282.4157)
			(xy 298.07233 -282.427182) (xy 298.023307 -282.43086) (xy 297.974328 -282.42664) (xy 297.926657 -282.41463)
			(xy 297.9039 -282.405328) (xy 297.881717 -282.395243) (xy 297.840606 -282.369088) (xy 297.804167 -282.336739)
			(xy 297.773326 -282.299016) (xy 297.748862 -282.256876) (xy 297.731398 -282.211387) (xy 297.721375 -282.163703)
			(xy 297.71975 -282.13939) (xy 297.719496 -282.132024) (xy 297.714924 -282.118816) (xy 297.696382 -282.092146)
			(xy 297.695874 -282.091638) (xy 297.692572 -282.086558) (xy 297.68292 -282.078176) (xy 297.674284 -282.073858)
			(xy 297.67149 -282.072588) (xy 297.670474 -282.07208) (xy 297.647144 -282.062588) (xy 297.601401 -282.041496)
			(xy 297.579034 -282.029916) (xy 297.5737 -282.027122) (xy 297.550586 -282.021534) (xy 297.532298 -282.023566)
			(xy 297.523916 -282.028138) (xy 297.478196 -282.050998) (xy 297.477688 -282.050998) (xy 297.428412 -282.07208)
			(xy 297.421554 -282.07462) (xy 297.41495 -282.0797) (xy 297.412066 -282.082018) (xy 297.406964 -282.087374)
			(xy 297.40479 -282.090368) (xy 297.38955 -282.111704) (xy 297.385232 -282.117546) (xy 297.380152 -282.132024)
			(xy 297.379898 -282.139644) (xy 297.37814 -282.165255) (xy 297.367137 -282.215392) (xy 297.347901 -282.262983)
			(xy 297.320977 -282.306686) (xy 297.287122 -282.34527) (xy 297.24729 -282.377648) (xy 297.202603 -282.402906)
			(xy 297.154322 -282.420335) (xy 297.103805 -282.429442) (xy 297.078146 -282.43022) (xy 297.074844 -282.43022)
			(xy 297.048961 -282.429671) (xy 296.997938 -282.420935) (xy 296.949117 -282.403722) (xy 296.903897 -282.378526)
			(xy 296.863571 -282.346067) (xy 296.829295 -282.307274) (xy 296.802048 -282.263259) (xy 296.782612 -282.21528)
			(xy 296.771542 -282.164712) (xy 296.76979 -282.138882) (xy 296.769315 -282.13131) (xy 296.764398 -282.116966)
			(xy 296.760138 -282.110688) (xy 296.745406 -282.090622) (xy 296.744644 -282.08986) (xy 296.737278 -282.079192)
			(xy 296.729665 -282.069523) (xy 296.707905 -282.05811) (xy 296.695622 -282.057348) (xy 296.68597 -282.057348)
			(xy 296.630344 -282.03017) (xy 296.624502 -282.027122) (xy 296.611802 -282.024328) (xy 296.58818 -282.024328)
			(xy 296.575988 -282.027376) (xy 296.570146 -282.030424) (xy 296.569892 -282.030424) (xy 296.526966 -282.052014)
			(xy 296.520362 -282.055062) (xy 296.509694 -282.064206) (xy 296.492422 -282.090876) (xy 296.488635 -282.097158)
			(xy 296.484514 -282.111229) (xy 296.484294 -282.118562) (xy 296.484294 -282.124912) (xy 296.483818 -282.151841)
			(xy 296.475784 -282.205097) (xy 296.459881 -282.256554) (xy 296.436469 -282.305057) (xy 296.406071 -282.349517)
			(xy 296.369372 -282.388936) (xy 296.327194 -282.422428) (xy 296.280485 -282.449242) (xy 296.230294 -282.468775)
			(xy 296.204132 -282.475178) (xy 296.203624 -282.475178) (xy 296.194226 -282.477464) (xy 296.186606 -282.482544)
			(xy 296.18264 -282.485316) (xy 296.175735 -282.492092) (xy 296.17289 -282.496006) (xy 296.12336 -282.567634)
			(xy 296.046652 -282.677616) (xy 296.041712 -282.685451) (xy 296.037253 -282.703413) (xy 296.039452 -282.72179)
			(xy 296.04335 -282.730194) (xy 296.049954 -282.74264) (xy 296.074084 -282.757372) (xy 296.09288 -282.757372)
			(xy 296.098468 -282.756864) (xy 296.12463 -282.755848) (xy 296.125138 -282.755848) (xy 296.150209 -282.756343)
			(xy 296.199733 -282.764192) (xy 296.247419 -282.779693) (xy 296.292094 -282.802462) (xy 296.332656 -282.831939)
			(xy 296.368108 -282.867399) (xy 296.397576 -282.907969) (xy 296.420335 -282.952648) (xy 296.435825 -283.000338)
			(xy 296.443663 -283.049864) (xy 296.443661 -283.074872) (xy 296.76904 -283.074872) (xy 296.773 -283.025818)
			(xy 296.784777 -282.978034) (xy 296.804068 -282.932758) (xy 296.830371 -282.891162) (xy 296.863006 -282.854325)
			(xy 296.901127 -282.8232) (xy 296.943748 -282.798593) (xy 296.989764 -282.781141) (xy 297.037983 -282.771297)
			(xy 297.087158 -282.769316) (xy 297.136013 -282.775248) (xy 297.183284 -282.78894) (xy 297.227746 -282.810038)
			(xy 297.268249 -282.837994) (xy 297.303742 -282.872086) (xy 297.333307 -282.91143) (xy 297.356178 -282.955007)
			(xy 297.371762 -283.001688) (xy 297.379657 -283.050265) (xy 297.380152 -283.074872) (xy 297.719 -283.074872)
			(xy 297.72296 -283.025818) (xy 297.734737 -282.978034) (xy 297.754028 -282.932758) (xy 297.780331 -282.891162)
			(xy 297.812966 -282.854325) (xy 297.851087 -282.8232) (xy 297.893708 -282.798593) (xy 297.939724 -282.781141)
			(xy 297.987943 -282.771297) (xy 298.037118 -282.769316) (xy 298.085973 -282.775248) (xy 298.133244 -282.78894)
			(xy 298.177706 -282.810038) (xy 298.218209 -282.837994) (xy 298.253702 -282.872086) (xy 298.283267 -282.91143)
			(xy 298.306138 -282.955007) (xy 298.321722 -283.001688) (xy 298.329617 -283.050265) (xy 298.330112 -283.074872)
			(xy 298.66896 -283.074872) (xy 298.67292 -283.025818) (xy 298.684697 -282.978034) (xy 298.703988 -282.932758)
			(xy 298.730291 -282.891162) (xy 298.762926 -282.854325) (xy 298.801047 -282.8232) (xy 298.843668 -282.798593)
			(xy 298.889684 -282.781141) (xy 298.937903 -282.771297) (xy 298.987078 -282.769316) (xy 299.035933 -282.775248)
			(xy 299.083204 -282.78894) (xy 299.127666 -282.810038) (xy 299.168169 -282.837994) (xy 299.203662 -282.872086)
			(xy 299.233227 -282.91143) (xy 299.256098 -282.955007) (xy 299.271682 -283.001688) (xy 299.279577 -283.050265)
			(xy 299.280072 -283.074872) (xy 300.56888 -283.074872) (xy 300.57284 -283.025818) (xy 300.584617 -282.978034)
			(xy 300.603908 -282.932758) (xy 300.630211 -282.891162) (xy 300.662846 -282.854325) (xy 300.700967 -282.8232)
			(xy 300.743588 -282.798593) (xy 300.789604 -282.781141) (xy 300.837823 -282.771297) (xy 300.886998 -282.769316)
			(xy 300.935853 -282.775248) (xy 300.983124 -282.78894) (xy 301.027586 -282.810038) (xy 301.068089 -282.837994)
			(xy 301.103582 -282.872086) (xy 301.133147 -282.91143) (xy 301.156018 -282.955007) (xy 301.171602 -283.001688)
			(xy 301.179497 -283.050265) (xy 301.179992 -283.074872) (xy 301.519094 -283.074872) (xy 301.523054 -283.025818)
			(xy 301.534831 -282.978034) (xy 301.554122 -282.932758) (xy 301.580425 -282.891162) (xy 301.61306 -282.854325)
			(xy 301.651181 -282.8232) (xy 301.693802 -282.798593) (xy 301.739818 -282.781141) (xy 301.788037 -282.771297)
			(xy 301.837212 -282.769316) (xy 301.886067 -282.775248) (xy 301.933338 -282.78894) (xy 301.9778 -282.810038)
			(xy 302.018303 -282.837994) (xy 302.053796 -282.872086) (xy 302.083361 -282.91143) (xy 302.106232 -282.955007)
			(xy 302.121816 -283.001688) (xy 302.129711 -283.050265) (xy 302.130206 -283.074872) (xy 302.469054 -283.074872)
			(xy 302.473014 -283.025818) (xy 302.484791 -282.978034) (xy 302.504082 -282.932758) (xy 302.530385 -282.891162)
			(xy 302.56302 -282.854325) (xy 302.601141 -282.8232) (xy 302.643762 -282.798593) (xy 302.689778 -282.781141)
			(xy 302.737997 -282.771297) (xy 302.787172 -282.769316) (xy 302.836027 -282.775248) (xy 302.883298 -282.78894)
			(xy 302.92776 -282.810038) (xy 302.968263 -282.837994) (xy 303.003756 -282.872086) (xy 303.033321 -282.91143)
			(xy 303.056192 -282.955007) (xy 303.071776 -283.001688) (xy 303.079671 -283.050265) (xy 303.080166 -283.074872)
			(xy 303.419014 -283.074872) (xy 303.422974 -283.025818) (xy 303.434751 -282.978034) (xy 303.454042 -282.932758)
			(xy 303.480345 -282.891162) (xy 303.51298 -282.854325) (xy 303.551101 -282.8232) (xy 303.593722 -282.798593)
			(xy 303.639738 -282.781141) (xy 303.687957 -282.771297) (xy 303.737132 -282.769316) (xy 303.785987 -282.775248)
			(xy 303.833258 -282.78894) (xy 303.87772 -282.810038) (xy 303.918223 -282.837994) (xy 303.953716 -282.872086)
			(xy 303.983281 -282.91143) (xy 304.006152 -282.955007) (xy 304.021736 -283.001688) (xy 304.029631 -283.050265)
			(xy 304.030126 -283.074872) (xy 304.368974 -283.074872) (xy 304.372934 -283.025818) (xy 304.384711 -282.978034)
			(xy 304.404002 -282.932758) (xy 304.430305 -282.891162) (xy 304.46294 -282.854325) (xy 304.501061 -282.8232)
			(xy 304.543682 -282.798593) (xy 304.589698 -282.781141) (xy 304.637917 -282.771297) (xy 304.687092 -282.769316)
			(xy 304.735947 -282.775248) (xy 304.783218 -282.78894) (xy 304.82768 -282.810038) (xy 304.868183 -282.837994)
			(xy 304.903676 -282.872086) (xy 304.933241 -282.91143) (xy 304.956112 -282.955007) (xy 304.971696 -283.001688)
			(xy 304.979591 -283.050265) (xy 304.980086 -283.074872) (xy 304.979591 -283.099479) (xy 304.971696 -283.148056)
			(xy 304.956112 -283.194737) (xy 304.933241 -283.238314) (xy 304.903676 -283.277658) (xy 304.868183 -283.31175)
			(xy 304.82768 -283.339706) (xy 304.783218 -283.360804) (xy 304.735947 -283.374496) (xy 304.687092 -283.380428)
			(xy 304.637917 -283.378447) (xy 304.589698 -283.368603) (xy 304.543682 -283.351151) (xy 304.501061 -283.326544)
			(xy 304.46294 -283.295419) (xy 304.430305 -283.258582) (xy 304.404002 -283.216986) (xy 304.384711 -283.17171)
			(xy 304.372934 -283.123926) (xy 304.368974 -283.074872) (xy 304.030126 -283.074872) (xy 304.029631 -283.099479)
			(xy 304.021736 -283.148056) (xy 304.006152 -283.194737) (xy 303.983281 -283.238314) (xy 303.953716 -283.277658)
			(xy 303.918223 -283.31175) (xy 303.87772 -283.339706) (xy 303.833258 -283.360804) (xy 303.785987 -283.374496)
			(xy 303.737132 -283.380428) (xy 303.687957 -283.378447) (xy 303.639738 -283.368603) (xy 303.593722 -283.351151)
			(xy 303.551101 -283.326544) (xy 303.51298 -283.295419) (xy 303.480345 -283.258582) (xy 303.454042 -283.216986)
			(xy 303.434751 -283.17171) (xy 303.422974 -283.123926) (xy 303.419014 -283.074872) (xy 303.080166 -283.074872)
			(xy 303.079671 -283.099479) (xy 303.071776 -283.148056) (xy 303.056192 -283.194737) (xy 303.033321 -283.238314)
			(xy 303.003756 -283.277658) (xy 302.968263 -283.31175) (xy 302.92776 -283.339706) (xy 302.883298 -283.360804)
			(xy 302.836027 -283.374496) (xy 302.787172 -283.380428) (xy 302.737997 -283.378447) (xy 302.689778 -283.368603)
			(xy 302.643762 -283.351151) (xy 302.601141 -283.326544) (xy 302.56302 -283.295419) (xy 302.530385 -283.258582)
			(xy 302.504082 -283.216986) (xy 302.484791 -283.17171) (xy 302.473014 -283.123926) (xy 302.469054 -283.074872)
			(xy 302.130206 -283.074872) (xy 302.129711 -283.099479) (xy 302.121816 -283.148056) (xy 302.106232 -283.194737)
			(xy 302.083361 -283.238314) (xy 302.053796 -283.277658) (xy 302.018303 -283.31175) (xy 301.9778 -283.339706)
			(xy 301.933338 -283.360804) (xy 301.886067 -283.374496) (xy 301.837212 -283.380428) (xy 301.788037 -283.378447)
			(xy 301.739818 -283.368603) (xy 301.693802 -283.351151) (xy 301.651181 -283.326544) (xy 301.61306 -283.295419)
			(xy 301.580425 -283.258582) (xy 301.554122 -283.216986) (xy 301.534831 -283.17171) (xy 301.523054 -283.123926)
			(xy 301.519094 -283.074872) (xy 301.179992 -283.074872) (xy 301.179497 -283.099479) (xy 301.171602 -283.148056)
			(xy 301.156018 -283.194737) (xy 301.133147 -283.238314) (xy 301.103582 -283.277658) (xy 301.068089 -283.31175)
			(xy 301.027586 -283.339706) (xy 300.983124 -283.360804) (xy 300.935853 -283.374496) (xy 300.886998 -283.380428)
			(xy 300.837823 -283.378447) (xy 300.789604 -283.368603) (xy 300.743588 -283.351151) (xy 300.700967 -283.326544)
			(xy 300.662846 -283.295419) (xy 300.630211 -283.258582) (xy 300.603908 -283.216986) (xy 300.584617 -283.17171)
			(xy 300.57284 -283.123926) (xy 300.56888 -283.074872) (xy 299.280072 -283.074872) (xy 299.279577 -283.099479)
			(xy 299.271682 -283.148056) (xy 299.256098 -283.194737) (xy 299.233227 -283.238314) (xy 299.203662 -283.277658)
			(xy 299.168169 -283.31175) (xy 299.127666 -283.339706) (xy 299.083204 -283.360804) (xy 299.035933 -283.374496)
			(xy 298.987078 -283.380428) (xy 298.937903 -283.378447) (xy 298.889684 -283.368603) (xy 298.843668 -283.351151)
			(xy 298.801047 -283.326544) (xy 298.762926 -283.295419) (xy 298.730291 -283.258582) (xy 298.703988 -283.216986)
			(xy 298.684697 -283.17171) (xy 298.67292 -283.123926) (xy 298.66896 -283.074872) (xy 298.330112 -283.074872)
			(xy 298.329617 -283.099479) (xy 298.321722 -283.148056) (xy 298.306138 -283.194737) (xy 298.283267 -283.238314)
			(xy 298.253702 -283.277658) (xy 298.218209 -283.31175) (xy 298.177706 -283.339706) (xy 298.133244 -283.360804)
			(xy 298.085973 -283.374496) (xy 298.037118 -283.380428) (xy 297.987943 -283.378447) (xy 297.939724 -283.368603)
			(xy 297.893708 -283.351151) (xy 297.851087 -283.326544) (xy 297.812966 -283.295419) (xy 297.780331 -283.258582)
			(xy 297.754028 -283.216986) (xy 297.734737 -283.17171) (xy 297.72296 -283.123926) (xy 297.719 -283.074872)
			(xy 297.380152 -283.074872) (xy 297.379657 -283.099479) (xy 297.371762 -283.148056) (xy 297.356178 -283.194737)
			(xy 297.333307 -283.238314) (xy 297.303742 -283.277658) (xy 297.268249 -283.31175) (xy 297.227746 -283.339706)
			(xy 297.183284 -283.360804) (xy 297.136013 -283.374496) (xy 297.087158 -283.380428) (xy 297.037983 -283.378447)
			(xy 296.989764 -283.368603) (xy 296.943748 -283.351151) (xy 296.901127 -283.326544) (xy 296.863006 -283.295419)
			(xy 296.830371 -283.258582) (xy 296.804068 -283.216986) (xy 296.784777 -283.17171) (xy 296.773 -283.123926)
			(xy 296.76904 -283.074872) (xy 296.443661 -283.074872) (xy 296.443658 -283.100006) (xy 296.435808 -283.14953)
			(xy 296.420309 -283.197216) (xy 296.39754 -283.241891) (xy 296.368063 -283.282453) (xy 296.332603 -283.317906)
			(xy 296.292034 -283.347374) (xy 296.247355 -283.370134) (xy 296.199665 -283.385624) (xy 296.15014 -283.393463)
			(xy 296.099998 -283.393458) (xy 296.050474 -283.385609) (xy 296.002787 -283.37011) (xy 295.958112 -283.347342)
			(xy 295.917549 -283.317865) (xy 295.882097 -283.282406) (xy 295.852627 -283.241837) (xy 295.829867 -283.197158)
			(xy 295.814377 -283.149469) (xy 295.806537 -283.099943) (xy 295.806114 -283.074872) (xy 295.806114 -283.074618)
			(xy 295.806486 -283.053067) (xy 295.812319 -283.010362) (xy 295.82384 -282.968828) (xy 295.832022 -282.948888)
			(xy 295.834054 -282.944062) (xy 295.836848 -282.930346) (xy 295.837547 -282.926319) (xy 295.837808 -282.918152)
			(xy 295.837356 -282.91409) (xy 295.83253 -282.877006) (xy 295.826942 -282.867862) (xy 295.823679 -282.861954)
			(xy 295.82007 -282.848953) (xy 295.81983 -282.842208) (xy 295.81983 -282.327604) (xy 295.813988 -282.304744)
			(xy 295.810432 -282.29814) (xy 295.796441 -282.271434) (xy 295.776614 -282.214501) (xy 295.766584 -282.155055)
			(xy 295.765982 -282.124912) (xy 295.76649 -282.107386) (xy 295.76649 -282.106624) (xy 295.766998 -282.089352)
			(xy 295.750488 -282.063698) (xy 295.736264 -282.057348) (xy 295.721909 -282.050898) (xy 295.693583 -282.037179)
			(xy 295.679622 -282.029916) (xy 295.673526 -282.026868) (xy 295.649396 -282.021534) (xy 295.637712 -282.024328)
			(xy 295.626282 -282.027122) (xy 295.620948 -282.029916) (xy 295.594746 -282.043342) (xy 295.540988 -282.067361)
			(xy 295.513506 -282.077922) (xy 295.504029 -282.081982) (xy 295.489123 -282.0962) (xy 295.480983 -282.115122)
			(xy 295.480486 -282.12542) (xy 295.479922 -282.15146) (xy 295.471012 -282.202775) (xy 295.453523 -282.251833)
			(xy 295.427962 -282.297212) (xy 295.39507 -282.337594) (xy 295.355802 -282.371808) (xy 295.311296 -282.398861)
			(xy 295.262846 -282.417969) (xy 295.211855 -282.428576) (xy 295.185846 -282.429966) (xy 295.176956 -282.43022)
			(xy 295.174924 -282.43022) (xy 295.14889 -282.429696) (xy 295.097574 -282.420876) (xy 295.048495 -282.403485)
			(xy 295.003074 -282.378028) (xy 294.962625 -282.345242) (xy 294.928318 -282.306074) (xy 294.901145 -282.261658)
			(xy 294.881893 -282.213279) (xy 294.871119 -282.162338) (xy 294.869616 -282.136342) (xy 294.869362 -282.128468)
			(xy 294.864028 -282.113736) (xy 294.845232 -282.089352) (xy 294.839136 -282.082494) (xy 294.83541 -282.079256)
			(xy 294.826965 -282.074144) (xy 294.822372 -282.072334) (xy 294.81018 -282.067762) (xy 294.809672 -282.067254)
			(xy 294.789769 -282.059006) (xy 294.750637 -282.040967) (xy 294.73144 -282.031186) (xy 294.728392 -282.029408)
			(xy 294.721026 -282.026868) (xy 294.716962 -282.025344) (xy 294.709342 -282.023566) (xy 294.705387 -282.022819)
			(xy 294.697348 -282.022441) (xy 294.69334 -282.022804) (xy 294.682418 -282.02382) (xy 294.673528 -282.028646)
			(xy 294.659558 -282.036012) (xy 294.659304 -282.036012) (xy 294.648636 -282.041346) (xy 294.631021 -282.049985)
			(xy 294.595195 -282.06599) (xy 294.577008 -282.07335) (xy 294.57015 -282.07589) (xy 294.558466 -282.085034)
			(xy 294.554402 -282.090876) (xy 294.53967 -282.110942) (xy 294.53713 -282.118816) (xy 294.533574 -282.129484)
			(xy 294.53205 -282.134818) (xy 294.529764 -282.145486) (xy 294.52951 -282.149042) (xy 294.52697 -282.174182)
			(xy 294.5147 -282.223195) (xy 294.494534 -282.269522) (xy 294.467022 -282.311901) (xy 294.432915 -282.349177)
			(xy 294.39314 -282.380335) (xy 294.348782 -282.404525) (xy 294.301048 -282.42109) (xy 294.251241 -282.429577)
			(xy 294.22598 -282.43022) (xy 294.224202 -282.43022) (xy 294.198364 -282.429628) (xy 294.14744 -282.420832)
			(xy 294.098723 -282.40359) (xy 294.053603 -282.378396) (xy 294.013366 -282.345967) (xy 293.97916 -282.307229)
			(xy 293.951962 -282.263287) (xy 293.932547 -282.215395) (xy 293.921469 -282.164918) (xy 293.919656 -282.139136)
			(xy 293.919402 -282.13177) (xy 293.914576 -282.118308) (xy 293.89959 -282.096972) (xy 293.897407 -282.093986)
			(xy 293.892309 -282.088627) (xy 293.88943 -282.086304) (xy 293.872158 -282.072588) (xy 293.865554 -282.069794)
			(xy 293.844135 -282.060969) (xy 293.80208 -282.041529) (xy 293.78148 -282.030932) (xy 293.780464 -282.030424)
			(xy 293.772844 -282.026868) (xy 293.767002 -282.025598) (xy 293.761414 -282.024328) (xy 293.755446 -282.023072)
			(xy 293.743252 -282.023072) (xy 293.737284 -282.024328) (xy 293.726108 -282.027122) (xy 293.720774 -282.029916)
			(xy 293.694573 -282.043343) (xy 293.640814 -282.067363) (xy 293.613332 -282.077922) (xy 293.603866 -282.081991)
			(xy 293.588982 -282.096214) (xy 293.580855 -282.115129) (xy 293.580312 -282.12542) (xy 293.579748 -282.151461)
			(xy 293.570839 -282.202778) (xy 293.55335 -282.251838) (xy 293.527789 -282.297218) (xy 293.494897 -282.337603)
			(xy 293.45563 -282.371819) (xy 293.411125 -282.398876) (xy 293.362674 -282.417987) (xy 293.311682 -282.428599)
			(xy 293.285672 -282.429966) (xy 293.276782 -282.43022) (xy 293.27475 -282.43022) (xy 293.248714 -282.429699)
			(xy 293.197395 -282.420881) (xy 293.148313 -282.403493) (xy 293.102888 -282.378038) (xy 293.062435 -282.345251)
			(xy 293.028124 -282.306082) (xy 293.000948 -282.261665) (xy 292.981695 -282.213284) (xy 292.97092 -282.16234)
			(xy 292.969442 -282.136342) (xy 292.969188 -282.128468) (xy 292.963854 -282.113736) (xy 292.945058 -282.089098)
			(xy 292.940894 -282.083974) (xy 292.930476 -282.075868) (xy 292.924484 -282.073096) (xy 292.921436 -282.071826)
			(xy 292.920928 -282.071572) (xy 292.89761 -282.062265) (xy 292.851867 -282.041553) (xy 292.829488 -282.03017)
			(xy 292.823138 -282.026868) (xy 292.810184 -282.024074) (xy 292.805194 -282.02326) (xy 292.795086 -282.023391)
			(xy 292.790118 -282.024328) (xy 292.77691 -282.026868) (xy 292.77056 -282.03017) (xy 292.75151 -282.039822)
			(xy 292.751002 -282.039822) (xy 292.729517 -282.050291) (xy 292.685681 -282.069348) (xy 292.663372 -282.077922)
			(xy 292.648386 -282.08351) (xy 292.630352 -282.109418) (xy 292.630352 -282.125928) (xy 292.629805 -282.149868)
			(xy 292.622172 -282.197138) (xy 292.607254 -282.242637) (xy 292.585417 -282.285251) (xy 292.557196 -282.323933)
			(xy 292.523284 -282.357737) (xy 292.484511 -282.385832) (xy 292.441827 -282.407532) (xy 292.39628 -282.422303)
			(xy 292.348985 -282.429784) (xy 292.325044 -282.43022) (xy 292.32479 -282.43022) (xy 292.298935 -282.429669)
			(xy 292.247966 -282.420946) (xy 292.199193 -282.403767) (xy 292.154009 -282.378622) (xy 292.113701 -282.34623)
			(xy 292.079423 -282.307515) (xy 292.05215 -282.263581) (xy 292.032663 -282.215684) (xy 292.021517 -282.165189)
			(xy 292.019736 -282.13939) (xy 292.018974 -282.124912) (xy 291.991288 -282.084526) (xy 291.97935 -282.075382)
			(xy 291.972238 -282.072588) (xy 291.928081 -282.05461) (xy 291.843217 -282.011149) (xy 291.76305 -281.959532)
			(xy 291.72535 -281.930348) (xy 291.715952 -281.924252) (xy 291.693381 -281.912692) (xy 291.652096 -281.883248)
			(xy 291.616241 -281.847391) (xy 291.5868 -281.806105) (xy 291.575236 -281.783536) (xy 291.569394 -281.774138)
			(xy 291.540312 -281.736552) (xy 291.488875 -281.656633) (xy 291.445568 -281.572033) (xy 291.427662 -281.528012)
			(xy 291.424614 -281.520138) (xy 291.41928 -281.513788) (xy 291.414708 -281.5082) (xy 291.388292 -281.489404)
			(xy 291.381434 -281.484578) (xy 291.366956 -281.480006) (xy 291.35451 -281.479498) (xy 291.348922 -281.47899)
			(xy 291.348414 -281.47899) (xy 291.345874 -281.478736) (xy 291.318442 -281.474926) (xy 291.30625 -281.47264)
			(xy 291.28212 -281.480006) (xy 291.204904 -281.556968) (xy 291.197538 -281.581098) (xy 291.199824 -281.593544)
			(xy 291.202308 -281.607509) (xy 291.204978 -281.635749) (xy 291.205158 -281.649932) (xy 291.204636 -281.675187)
			(xy 291.196323 -281.725009) (xy 291.179922 -281.772783) (xy 291.155881 -281.817206) (xy 291.124857 -281.857066)
			(xy 291.087695 -281.891276) (xy 291.045409 -281.918902) (xy 290.999153 -281.939192) (xy 290.950188 -281.951592)
			(xy 290.89985 -281.955763) (xy 290.849512 -281.951592) (xy 290.800547 -281.939192) (xy 290.754291 -281.918902)
			(xy 290.712005 -281.891276) (xy 290.674843 -281.857066) (xy 290.643819 -281.817206) (xy 290.619778 -281.772783)
			(xy 290.603377 -281.725009) (xy 290.595064 -281.675187) (xy 290.594542 -281.649932) (xy 290.594634 -281.640764)
			(xy 290.595775 -281.622464) (xy 290.596828 -281.613356) (xy 290.598098 -281.601418) (xy 290.590224 -281.579066)
			(xy 290.51377 -281.505914) (xy 290.491164 -281.499056) (xy 290.478972 -281.501088) (xy 290.465421 -281.503228)
			(xy 290.43808 -281.50552) (xy 290.424362 -281.50566) (xy 290.41084 -281.505542) (xy 290.383882 -281.503382)
			(xy 290.370514 -281.501342) (xy 290.358322 -281.49931) (xy 290.33597 -281.506168) (xy 290.259516 -281.57932)
			(xy 290.251642 -281.601418) (xy 290.252912 -281.61361) (xy 290.253959 -281.622654) (xy 290.255101 -281.640828)
			(xy 290.255198 -281.649932) (xy 290.25471 -281.674751) (xy 290.246674 -281.723735) (xy 290.23082 -281.770774)
			(xy 290.207565 -281.814628) (xy 290.177521 -281.854143) (xy 290.141481 -281.888276) (xy 290.100394 -281.916129)
			(xy 290.055341 -281.936969) (xy 290.007511 -281.950246) (xy 289.958163 -281.955609) (xy 289.908597 -281.952919)
			(xy 289.86012 -281.942246) (xy 289.814008 -281.92387) (xy 289.771476 -281.898277) (xy 289.733644 -281.86614)
			(xy 289.70151 -281.828307) (xy 289.67592 -281.785773) (xy 289.657548 -281.739659) (xy 289.646878 -281.691181)
			(xy 289.644191 -281.641615) (xy 289.649559 -281.592267) (xy 289.662839 -281.544438) (xy 289.683681 -281.499387)
			(xy 289.711538 -281.458302) (xy 289.745674 -281.422264) (xy 289.78519 -281.392223) (xy 289.829046 -281.368971)
			(xy 289.876086 -281.353121) (xy 289.925071 -281.345089) (xy 289.94989 -281.344624) (xy 289.958864 -281.344666)
			(xy 289.976783 -281.345685) (xy 289.985704 -281.346656) (xy 289.997896 -281.34818) (xy 290.019994 -281.340052)
			(xy 290.092892 -281.263852) (xy 290.100004 -281.241246) (xy 290.097972 -281.229054) (xy 290.095842 -281.215566)
			(xy 290.093552 -281.188353) (xy 290.0934 -281.174698) (xy 290.0934 -281.10434) (xy 290.092949 -281.093677)
			(xy 290.084276 -281.074198) (xy 290.076636 -281.066748) (xy 290.012374 -281.008836) (xy 289.992308 -281.002232)
			(xy 289.981386 -281.003502) (xy 289.94989 -281.005026) (xy 289.924634 -281.004504) (xy 289.87481 -280.996188)
			(xy 289.827035 -280.979785) (xy 289.782611 -280.955743) (xy 289.74275 -280.924717) (xy 289.70854 -280.887553)
			(xy 289.680912 -280.845265) (xy 289.660622 -280.799007) (xy 289.648222 -280.75004) (xy 289.644051 -280.6997)
			(xy 289.648222 -280.64936) (xy 289.660622 -280.600393) (xy 289.680912 -280.554135) (xy 289.70854 -280.511847)
			(xy 289.74275 -280.474683) (xy 289.782611 -280.443657) (xy 289.827035 -280.419615) (xy 289.87481 -280.403212)
			(xy 289.924634 -280.394896) (xy 289.94989 -280.39441) (xy 289.981386 -280.395934) (xy 289.992308 -280.397204)
			(xy 290.012374 -280.3906) (xy 290.076636 -280.332688) (xy 290.084146 -280.325144) (xy 290.092805 -280.305724)
			(xy 290.0934 -280.295096) (xy 290.0934 -280.224738) (xy 290.093562 -280.211084) (xy 290.095851 -280.183871)
			(xy 290.097972 -280.170382) (xy 290.09975 -280.158444) (xy 290.092892 -280.135838) (xy 290.019994 -280.059638)
			(xy 289.997896 -280.05151) (xy 289.985704 -280.053034) (xy 289.976782 -280.053996) (xy 289.958864 -280.055012)
			(xy 289.94989 -280.055066) (xy 289.924639 -280.054544) (xy 289.874825 -280.04623) (xy 289.827059 -280.02983)
			(xy 289.782644 -280.005793) (xy 289.742791 -279.974773) (xy 289.708587 -279.937616) (xy 289.680965 -279.895337)
			(xy 289.660679 -279.849088) (xy 289.648281 -279.80013) (xy 289.644111 -279.7498) (xy 289.648281 -279.69947)
			(xy 289.660679 -279.650512) (xy 289.680965 -279.604263) (xy 289.708587 -279.561984) (xy 289.742791 -279.524827)
			(xy 289.782644 -279.493807) (xy 289.827059 -279.46977) (xy 289.874825 -279.45337) (xy 289.924639 -279.445056)
			(xy 289.94989 -279.44445) (xy 289.964072 -279.444636) (xy 289.992312 -279.447308) (xy 290.006278 -279.449784)
			(xy 290.018724 -279.45207) (xy 290.042346 -279.444704) (xy 290.119816 -279.367234) (xy 290.127182 -279.343612)
			(xy 290.124896 -279.331166) (xy 290.12027 -279.303159) (xy 290.120274 -279.246398) (xy 290.124896 -279.21839)
			(xy 290.127182 -279.205944) (xy 290.119816 -279.182322) (xy 290.042346 -279.104852) (xy 290.018724 -279.097486)
			(xy 290.006278 -279.099772) (xy 289.992313 -279.102257) (xy 289.964073 -279.104928) (xy 289.94989 -279.105106)
			(xy 289.924635 -279.104584) (xy 289.874815 -279.096269) (xy 289.827043 -279.079867) (xy 289.782622 -279.055826)
			(xy 289.742764 -279.024802) (xy 289.708555 -278.987641) (xy 289.68093 -278.945356) (xy 289.660641 -278.899101)
			(xy 289.648242 -278.850137) (xy 289.644071 -278.7998) (xy 289.648242 -278.749463) (xy 289.660641 -278.700499)
			(xy 289.68093 -278.654244) (xy 289.708555 -278.611959) (xy 289.742764 -278.574798) (xy 289.782622 -278.543774)
			(xy 289.827043 -278.519733) (xy 289.874815 -278.503331) (xy 289.924635 -278.495016) (xy 289.94989 -278.49449)
			(xy 289.964072 -278.494676) (xy 289.992312 -278.497349) (xy 290.006278 -278.499824) (xy 290.018724 -278.50211)
			(xy 290.042346 -278.494744) (xy 290.119816 -278.417274) (xy 290.127182 -278.393652) (xy 290.124896 -278.381206)
			(xy 290.120266 -278.353198) (xy 290.120262 -278.296437) (xy 290.124896 -278.26843) (xy 290.127182 -278.255984)
			(xy 290.119816 -278.232362) (xy 290.042346 -278.154892) (xy 290.018724 -278.147526) (xy 290.006278 -278.149812)
			(xy 289.992313 -278.152297) (xy 289.964073 -278.154967) (xy 289.94989 -278.155146) (xy 289.924632 -278.154624)
			(xy 289.874805 -278.146307) (xy 289.827027 -278.129904) (xy 289.7826 -278.10586) (xy 289.742737 -278.074832)
			(xy 289.708524 -278.037665) (xy 289.680895 -277.995375) (xy 289.660603 -277.949114) (xy 289.648202 -277.900143)
			(xy 289.644031 -277.8498) (xy 289.648202 -277.799457) (xy 289.660603 -277.750486) (xy 289.680895 -277.704225)
			(xy 289.708524 -277.661935) (xy 289.742737 -277.624768) (xy 289.7826 -277.59374) (xy 289.827027 -277.569696)
			(xy 289.874805 -277.553293) (xy 289.924632 -277.544976) (xy 289.94989 -277.54453) (xy 289.964072 -277.544716)
			(xy 289.992312 -277.547389) (xy 290.006278 -277.549864) (xy 290.018724 -277.55215) (xy 290.042346 -277.544784)
			(xy 290.119816 -277.467314) (xy 290.127182 -277.443692) (xy 290.124896 -277.431246) (xy 290.120272 -277.403239)
			(xy 290.120279 -277.346479) (xy 290.124896 -277.31847) (xy 290.127182 -277.306024) (xy 290.119816 -277.282402)
			(xy 290.042346 -277.204932) (xy 290.018724 -277.197566) (xy 290.006278 -277.199852) (xy 289.992313 -277.202337)
			(xy 289.964073 -277.205008) (xy 289.94989 -277.205186) (xy 289.924637 -277.204664) (xy 289.87482 -277.196349)
			(xy 289.827051 -277.179949) (xy 289.782633 -277.15591) (xy 289.742777 -277.124887) (xy 289.708571 -277.087728)
			(xy 289.680948 -277.045446) (xy 289.66066 -276.999194) (xy 289.648262 -276.950233) (xy 289.644091 -276.8999)
			(xy 289.648262 -276.849567) (xy 289.66066 -276.800606) (xy 289.680948 -276.754354) (xy 289.708571 -276.712072)
			(xy 289.742777 -276.674913) (xy 289.782633 -276.64389) (xy 289.827051 -276.619851) (xy 289.87482 -276.603451)
			(xy 289.924637 -276.595136) (xy 289.94989 -276.59457) (xy 289.964072 -276.594756) (xy 289.992312 -276.597428)
			(xy 290.006278 -276.599904) (xy 290.018724 -276.60219) (xy 290.042346 -276.594824) (xy 290.119816 -276.517354)
			(xy 290.127182 -276.493732) (xy 290.124896 -276.481286) (xy 290.120268 -276.453279) (xy 290.120268 -276.396518)
			(xy 290.124896 -276.36851) (xy 290.127182 -276.356064) (xy 290.119816 -276.332442) (xy 290.042346 -276.254972)
			(xy 290.018724 -276.247606) (xy 290.006278 -276.249892) (xy 289.992313 -276.252377) (xy 289.964073 -276.255048)
			(xy 289.94989 -276.255226) (xy 289.924634 -276.254704) (xy 289.87481 -276.246388) (xy 289.827035 -276.229985)
			(xy 289.782611 -276.205943) (xy 289.74275 -276.174917) (xy 289.70854 -276.137753) (xy 289.680912 -276.095465)
			(xy 289.660622 -276.049207) (xy 289.648222 -276.00024) (xy 289.644051 -275.9499) (xy 289.648222 -275.89956)
			(xy 289.660622 -275.850593) (xy 289.680912 -275.804335) (xy 289.70854 -275.762047) (xy 289.74275 -275.724883)
			(xy 289.782611 -275.693857) (xy 289.827035 -275.669815) (xy 289.87481 -275.653412) (xy 289.924634 -275.645096)
			(xy 289.94989 -275.64461) (xy 289.958864 -275.644652) (xy 289.976783 -275.645671) (xy 289.985704 -275.646642)
			(xy 289.997896 -275.648166) (xy 290.019994 -275.640038) (xy 290.092892 -275.563838) (xy 290.100004 -275.541232)
			(xy 290.097972 -275.52904) (xy 290.095856 -275.515614) (xy 290.093569 -275.488529) (xy 290.0934 -275.474938)
			(xy 290.0934 -275.40458) (xy 290.092937 -275.393923) (xy 290.084249 -275.374461) (xy 290.076636 -275.366988)
			(xy 290.012374 -275.309076) (xy 289.992308 -275.302472) (xy 289.981386 -275.303742) (xy 289.94989 -275.305266)
			(xy 289.924639 -275.304744) (xy 289.874825 -275.29643) (xy 289.827059 -275.28003) (xy 289.782644 -275.255993)
			(xy 289.742791 -275.224973) (xy 289.708587 -275.187816) (xy 289.680965 -275.145537) (xy 289.660679 -275.099288)
			(xy 289.648281 -275.05033) (xy 289.644111 -275) (xy 289.648281 -274.94967) (xy 289.660679 -274.900712)
			(xy 289.680965 -274.854463) (xy 289.708587 -274.812184) (xy 289.742791 -274.775027) (xy 289.782644 -274.744007)
			(xy 289.827059 -274.71997) (xy 289.874825 -274.70357) (xy 289.924639 -274.695256) (xy 289.94989 -274.69465)
			(xy 289.981386 -274.696174) (xy 289.992308 -274.697444) (xy 290.012374 -274.69084) (xy 290.076636 -274.632928)
			(xy 290.084152 -274.625386) (xy 290.092826 -274.605967) (xy 290.0934 -274.595336) (xy 290.0934 -274.524724)
			(xy 290.093442 -274.51537) (xy 290.094457 -274.496689) (xy 290.095432 -274.487386) (xy 290.096702 -274.475956)
			(xy 290.089336 -274.454366) (xy 290.0172 -274.381468) (xy 289.99561 -274.373848) (xy 289.983926 -274.374864)
			(xy 289.94989 -274.376896) (xy 289.924179 -274.376391) (xy 289.873391 -274.368346) (xy 289.824487 -274.352454)
			(xy 289.778671 -274.329108) (xy 289.73707 -274.298883) (xy 289.700711 -274.262522) (xy 289.670486 -274.220921)
			(xy 289.647142 -274.175104) (xy 289.631252 -274.126199) (xy 289.623208 -274.075411) (xy 289.623208 -274.023989)
			(xy 289.631252 -273.973201) (xy 289.647142 -273.924296) (xy 289.670486 -273.878479) (xy 289.700711 -273.836878)
			(xy 289.73707 -273.800517) (xy 289.778671 -273.770292) (xy 289.824487 -273.746946) (xy 289.873391 -273.731054)
			(xy 289.924179 -273.723009) (xy 289.94989 -273.722592) (xy 289.963614 -273.722783) (xy 289.990956 -273.725194)
			(xy 290.0045 -273.727418) (xy 290.016438 -273.729196) (xy 290.039298 -273.722338) (xy 290.115752 -273.648678)
			(xy 290.123626 -273.626072) (xy 290.122102 -273.614134) (xy 290.119867 -273.594511) (xy 290.119871 -273.555017)
			(xy 290.122102 -273.535394) (xy 290.123626 -273.523456) (xy 290.115752 -273.50085) (xy 290.039298 -273.42719)
			(xy 290.016438 -273.420332) (xy 290.0045 -273.42211) (xy 289.990954 -273.424313) (xy 289.963613 -273.426734)
			(xy 289.94989 -273.426936) (xy 289.924184 -273.426431) (xy 289.873405 -273.418387) (xy 289.82451 -273.402499)
			(xy 289.778702 -273.379157) (xy 289.737109 -273.348937) (xy 289.700756 -273.312583) (xy 289.670537 -273.270989)
			(xy 289.647197 -273.225181) (xy 289.63131 -273.176285) (xy 289.623268 -273.125506) (xy 289.623268 -273.074094)
			(xy 289.63131 -273.023315) (xy 289.647197 -272.974419) (xy 289.670537 -272.928611) (xy 289.700756 -272.887017)
			(xy 289.737109 -272.850663) (xy 289.778702 -272.820443) (xy 289.82451 -272.797101) (xy 289.873405 -272.781213)
			(xy 289.924184 -272.773169) (xy 289.94989 -272.772632) (xy 289.963614 -272.772823) (xy 289.990956 -272.775235)
			(xy 290.0045 -272.777458) (xy 290.016438 -272.779236) (xy 290.039298 -272.772378) (xy 290.115752 -272.698718)
			(xy 290.123626 -272.676112) (xy 290.122102 -272.664174) (xy 290.119467 -272.640188) (xy 290.120874 -272.591955)
			(xy 290.124896 -272.568162) (xy 290.127182 -272.55597) (xy 290.119816 -272.53184) (xy 290.0426 -272.454624)
			(xy 290.01847 -272.447258) (xy 290.006278 -272.449544) (xy 289.992251 -272.452043) (xy 289.963883 -272.454714)
			(xy 289.949636 -272.454878) (xy 289.924379 -272.454388) (xy 289.874553 -272.446079) (xy 289.826774 -272.429682)
			(xy 289.782346 -272.405643) (xy 289.742481 -272.374619) (xy 289.708266 -272.337457) (xy 289.680636 -272.295169)
			(xy 289.660343 -272.24891) (xy 289.647942 -272.199942) (xy 289.64377 -272.1496) (xy 289.647942 -272.099258)
			(xy 289.660343 -272.05029) (xy 289.680636 -272.004031) (xy 289.708266 -271.961743) (xy 289.742481 -271.924581)
			(xy 289.782346 -271.893557) (xy 289.826774 -271.869518) (xy 289.874553 -271.853121) (xy 289.924379 -271.844812)
			(xy 289.949636 -271.844262) (xy 289.976127 -271.84483) (xy 290.028313 -271.853975) (xy 290.07814 -271.871983)
			(xy 290.124114 -271.898316) (xy 290.164857 -271.932184) (xy 290.199149 -271.972571) (xy 290.213034 -271.995138)
			(xy 290.219892 -272.006822) (xy 290.24326 -272.020284) (xy 290.256976 -272.020284) (xy 290.266999 -272.019869)
			(xy 290.285522 -272.012202) (xy 290.299698 -271.998029) (xy 290.307367 -271.979507) (xy 290.307776 -271.969484)
			(xy 290.307776 -271.841976) (xy 290.30422 -271.833086) (xy 290.28798 -271.789826) (xy 290.262646 -271.700956)
			(xy 290.245653 -271.610122) (xy 290.237148 -271.518103) (xy 290.236656 -271.471898) (xy 290.236656 -266.15644)
			(xy 290.236559 -266.152295) (xy 290.235153 -266.144124) (xy 290.233862 -266.140184) (xy 287.418526 -257.822446)
			(xy 287.416467 -257.817004) (xy 287.410312 -257.807134) (xy 287.406334 -257.802888) (xy 283.764228 -254.160782)
			(xy 283.75683 -254.153938) (xy 283.73823 -254.146217) (xy 283.72816 -254.145796) (xy 278.763984 -254.145796)
			(xy 278.757007 -254.145553) (xy 278.743594 -254.141699) (xy 278.737568 -254.138176) (xy 278.731472 -254.13462)
			(xy 278.725122 -254.132842) (xy 278.711152 -254.13081) (xy 249.759978 -254.13081) (xy 249.756168 -254.131318)
			(xy 249.745181 -254.132833) (xy 249.723062 -254.134487) (xy 249.711972 -254.13462) (xy 248.66092 -254.13462)
			(xy 248.63425 -254.13335) (xy 248.616978 -254.131318) (xy 248.613168 -254.13081) (xy 247.745758 -254.13081)
			(xy 247.742202 -254.131318) (xy 247.724676 -254.13335) (xy 247.69826 -254.13462) (xy 234.263438 -254.13462)
			(xy 234.254218 -254.135163) (xy 234.237223 -254.142347) (xy 234.230418 -254.14859) (xy 234.01909 -254.359664)
			(xy 234.012244 -254.367062) (xy 234.004519 -254.385661) (xy 234.004104 -254.395732) (xy 234.004104 -255.28524)
			(xy 234.003603 -255.310098) (xy 233.995634 -255.359173) (xy 233.979907 -255.406337) (xy 233.95683 -255.450374)
			(xy 233.926997 -255.490145) (xy 233.891179 -255.524625) (xy 233.850301 -255.552924) (xy 233.805419 -255.574309)
			(xy 233.75769 -255.58823) (xy 233.733086 -255.591818) (xy 233.723688 -255.593088) (xy 233.709972 -255.600454)
			(xy 233.706253 -255.602489) (xy 233.699494 -255.607602) (xy 233.69651 -255.610614) (xy 233.682286 -255.625854)
			(xy 233.675428 -255.632966) (xy 233.66857 -255.650746) (xy 233.66857 -255.910588) (xy 254.076452 -255.910588)
			(xy 254.080523 -255.854966) (xy 254.092649 -255.800529) (xy 254.112572 -255.748438) (xy 254.139868 -255.699803)
			(xy 254.173954 -255.65566) (xy 254.214103 -255.616951) (xy 254.259461 -255.5845) (xy 254.309061 -255.558999)
			(xy 254.361845 -255.540992) (xy 254.416688 -255.530862) (xy 254.472422 -255.528825) (xy 254.527859 -255.534925)
			(xy 254.581816 -255.549031) (xy 254.633145 -255.570843) (xy 254.680751 -255.599897) (xy 254.723619 -255.635572)
			(xy 254.760836 -255.677109) (xy 254.771645 -255.693446) (xy 254.965518 -255.693446) (xy 254.965518 -255.638954)
			(xy 254.973273 -255.585016) (xy 254.988624 -255.53273) (xy 255.011259 -255.483161) (xy 255.040718 -255.437318)
			(xy 255.076401 -255.396133) (xy 255.117581 -255.360446) (xy 255.163421 -255.330981) (xy 255.212987 -255.30834)
			(xy 255.265271 -255.292982) (xy 255.319208 -255.285221) (xy 255.346454 -255.284732) (xy 255.375406 -255.285311)
			(xy 255.432644 -255.294062) (xy 255.487905 -255.311355) (xy 255.539922 -255.336794) (xy 255.587501 -255.369795)
			(xy 255.629551 -255.409601) (xy 255.665109 -255.455301) (xy 255.679702 -255.480312) (xy 255.687514 -255.493171)
			(xy 255.709168 -255.514037) (xy 255.735961 -255.527688) (xy 255.76557 -255.53294) (xy 255.795424 -255.529337)
			(xy 255.822933 -255.517192) (xy 255.84571 -255.497559) (xy 255.8542 -255.485138) (xy 255.86928 -255.462141)
			(xy 255.904987 -255.420317) (xy 255.946327 -255.384051) (xy 255.992445 -255.354095) (xy 256.042385 -255.33107)
			(xy 256.095113 -255.31545) (xy 256.149538 -255.307562) (xy 256.177034 -255.307084) (xy 256.204283 -255.307588)
			(xy 256.258226 -255.315348) (xy 256.310516 -255.330706) (xy 256.360087 -255.353349) (xy 256.405933 -255.382815)
			(xy 256.447118 -255.418506) (xy 256.482805 -255.459695) (xy 256.512268 -255.505542) (xy 256.534906 -255.555116)
			(xy 256.550259 -255.607407) (xy 256.558014 -255.661351) (xy 256.558014 -255.715849) (xy 256.550259 -255.769793)
			(xy 256.534906 -255.822084) (xy 256.512268 -255.871658) (xy 256.482805 -255.917505) (xy 256.447118 -255.958694)
			(xy 256.405933 -255.994385) (xy 256.360087 -256.023851) (xy 256.310516 -256.046494) (xy 256.258226 -256.061852)
			(xy 256.204283 -256.069612) (xy 256.177034 -256.0701) (xy 256.14808 -256.069566) (xy 256.090838 -256.060811)
			(xy 256.035574 -256.043513) (xy 255.983556 -256.018067) (xy 255.935978 -255.985059) (xy 255.893929 -255.945243)
			(xy 255.858376 -255.899535) (xy 255.843786 -255.87452) (xy 255.835988 -255.861655) (xy 255.814326 -255.840802)
			(xy 255.787531 -255.82716) (xy 255.757924 -255.821913) (xy 255.728073 -255.825516) (xy 255.700564 -255.837655)
			(xy 255.677783 -255.857279) (xy 255.669288 -255.869694) (xy 255.654227 -255.892704) (xy 255.618516 -255.934526)
			(xy 255.577171 -255.97079) (xy 255.53105 -256.000744) (xy 255.481107 -256.023767) (xy 255.428377 -256.039384)
			(xy 255.373951 -256.047271) (xy 255.346454 -256.047748) (xy 255.319208 -256.047179) (xy 255.265271 -256.039418)
			(xy 255.212987 -256.02406) (xy 255.163421 -256.001419) (xy 255.117581 -255.971954) (xy 255.076401 -255.936267)
			(xy 255.040718 -255.895082) (xy 255.011259 -255.849239) (xy 254.988624 -255.79967) (xy 254.973273 -255.747384)
			(xy 254.965518 -255.693446) (xy 254.771645 -255.693446) (xy 254.791609 -255.723622) (xy 254.815281 -255.774119)
			(xy 254.831349 -255.827526) (xy 254.839469 -255.882702) (xy 254.839978 -255.910588) (xy 254.839469 -255.938474)
			(xy 254.831349 -255.99365) (xy 254.815281 -256.047057) (xy 254.791609 -256.097554) (xy 254.760836 -256.144067)
			(xy 254.723619 -256.185604) (xy 254.680751 -256.221279) (xy 254.633145 -256.250333) (xy 254.581816 -256.272145)
			(xy 254.527859 -256.286251) (xy 254.472422 -256.292351) (xy 254.416688 -256.290314) (xy 254.361845 -256.280184)
			(xy 254.309061 -256.262177) (xy 254.259461 -256.236676) (xy 254.214103 -256.204225) (xy 254.173954 -256.165516)
			(xy 254.139868 -256.121373) (xy 254.112572 -256.072738) (xy 254.092649 -256.020647) (xy 254.080523 -255.96621)
			(xy 254.076452 -255.910588) (xy 233.66857 -255.910588) (xy 233.66857 -256.479653) (xy 257.479248 -256.479653)
			(xy 257.479248 -256.425147) (xy 257.487005 -256.371196) (xy 257.502361 -256.318897) (xy 257.525003 -256.269317)
			(xy 257.554471 -256.223463) (xy 257.590164 -256.18227) (xy 257.631357 -256.146576) (xy 257.67721 -256.117107)
			(xy 257.72679 -256.094463) (xy 257.779088 -256.079106) (xy 257.833039 -256.071348) (xy 257.860292 -256.070862)
			(xy 257.886609 -256.071286) (xy 257.938744 -256.078514) (xy 257.989392 -256.092833) (xy 258.037593 -256.113973)
			(xy 258.082435 -256.141533) (xy 258.123066 -256.17499) (xy 258.141216 -256.194052) (xy 258.148736 -256.201455)
			(xy 258.168017 -256.20998) (xy 258.178554 -256.210562) (xy 258.25323 -256.210562) (xy 258.263778 -256.21002)
			(xy 258.283075 -256.201495) (xy 258.290568 -256.194052) (xy 258.308729 -256.174998) (xy 258.349342 -256.141516)
			(xy 258.394177 -256.113941) (xy 258.44238 -256.092797) (xy 258.493033 -256.078488) (xy 258.545174 -256.071285)
			(xy 258.571492 -256.070862) (xy 258.598743 -256.071385) (xy 258.652691 -256.07914) (xy 258.704985 -256.094494)
			(xy 258.713862 -256.098548) (xy 260.081774 -256.098548) (xy 260.085845 -256.042926) (xy 260.097971 -255.988489)
			(xy 260.117894 -255.936398) (xy 260.14519 -255.887763) (xy 260.179276 -255.84362) (xy 260.219425 -255.804911)
			(xy 260.264783 -255.77246) (xy 260.314383 -255.746959) (xy 260.367167 -255.728952) (xy 260.42201 -255.718822)
			(xy 260.477744 -255.716785) (xy 260.533181 -255.722885) (xy 260.587138 -255.736991) (xy 260.638467 -255.758803)
			(xy 260.686073 -255.787857) (xy 260.728941 -255.823532) (xy 260.766158 -255.865069) (xy 260.796931 -255.911582)
			(xy 260.820603 -255.962079) (xy 260.836671 -256.015486) (xy 260.844791 -256.070662) (xy 260.8453 -256.098548)
			(xy 260.844791 -256.126434) (xy 260.836671 -256.18161) (xy 260.820603 -256.235017) (xy 260.796931 -256.285514)
			(xy 260.766158 -256.332027) (xy 260.728941 -256.373564) (xy 260.726115 -256.375916) (xy 260.969504 -256.375916)
			(xy 260.973575 -256.320294) (xy 260.985701 -256.265857) (xy 261.005624 -256.213766) (xy 261.03292 -256.165131)
			(xy 261.067006 -256.120988) (xy 261.107155 -256.082279) (xy 261.152513 -256.049828) (xy 261.202113 -256.024327)
			(xy 261.254897 -256.00632) (xy 261.30974 -255.99619) (xy 261.365474 -255.994153) (xy 261.420911 -256.000253)
			(xy 261.474868 -256.014359) (xy 261.526197 -256.036171) (xy 261.573803 -256.065225) (xy 261.616671 -256.1009)
			(xy 261.653888 -256.142437) (xy 261.684661 -256.18895) (xy 261.708333 -256.239447) (xy 261.724401 -256.292854)
			(xy 261.732521 -256.34803) (xy 261.73303 -256.375916) (xy 262.44499 -256.375916) (xy 262.449061 -256.320294)
			(xy 262.461187 -256.265857) (xy 262.48111 -256.213766) (xy 262.508406 -256.165131) (xy 262.542492 -256.120988)
			(xy 262.582641 -256.082279) (xy 262.627999 -256.049828) (xy 262.677599 -256.024327) (xy 262.730383 -256.00632)
			(xy 262.785226 -255.99619) (xy 262.84096 -255.994153) (xy 262.896397 -256.000253) (xy 262.950354 -256.014359)
			(xy 263.001683 -256.036171) (xy 263.049289 -256.065225) (xy 263.092157 -256.1009) (xy 263.129374 -256.142437)
			(xy 263.160147 -256.18895) (xy 263.183819 -256.239447) (xy 263.199887 -256.292854) (xy 263.208007 -256.34803)
			(xy 263.208516 -256.375916) (xy 263.33399 -256.375916) (xy 263.338061 -256.320294) (xy 263.350187 -256.265857)
			(xy 263.37011 -256.213766) (xy 263.397406 -256.165131) (xy 263.431492 -256.120988) (xy 263.471641 -256.082279)
			(xy 263.516999 -256.049828) (xy 263.566599 -256.024327) (xy 263.619383 -256.00632) (xy 263.674226 -255.99619)
			(xy 263.72996 -255.994153) (xy 263.785397 -256.000253) (xy 263.839354 -256.014359) (xy 263.890683 -256.036171)
			(xy 263.938289 -256.065225) (xy 263.981157 -256.1009) (xy 264.018374 -256.142437) (xy 264.049147 -256.18895)
			(xy 264.072819 -256.239447) (xy 264.088887 -256.292854) (xy 264.097007 -256.34803) (xy 264.097516 -256.375916)
			(xy 264.097007 -256.403802) (xy 264.088887 -256.458978) (xy 264.072819 -256.512385) (xy 264.049147 -256.562882)
			(xy 264.018374 -256.609395) (xy 263.981157 -256.650932) (xy 263.938289 -256.686607) (xy 263.890683 -256.715661)
			(xy 263.839354 -256.737473) (xy 263.785397 -256.751579) (xy 263.72996 -256.757679) (xy 263.674226 -256.755642)
			(xy 263.619383 -256.745512) (xy 263.566599 -256.727505) (xy 263.516999 -256.702004) (xy 263.471641 -256.669553)
			(xy 263.431492 -256.630844) (xy 263.397406 -256.586701) (xy 263.37011 -256.538066) (xy 263.350187 -256.485975)
			(xy 263.338061 -256.431538) (xy 263.33399 -256.375916) (xy 263.208516 -256.375916) (xy 263.208007 -256.403802)
			(xy 263.199887 -256.458978) (xy 263.183819 -256.512385) (xy 263.160147 -256.562882) (xy 263.129374 -256.609395)
			(xy 263.092157 -256.650932) (xy 263.049289 -256.686607) (xy 263.001683 -256.715661) (xy 262.950354 -256.737473)
			(xy 262.896397 -256.751579) (xy 262.84096 -256.757679) (xy 262.785226 -256.755642) (xy 262.730383 -256.745512)
			(xy 262.677599 -256.727505) (xy 262.627999 -256.702004) (xy 262.582641 -256.669553) (xy 262.542492 -256.630844)
			(xy 262.508406 -256.586701) (xy 262.48111 -256.538066) (xy 262.461187 -256.485975) (xy 262.449061 -256.431538)
			(xy 262.44499 -256.375916) (xy 261.73303 -256.375916) (xy 261.732521 -256.403802) (xy 261.724401 -256.458978)
			(xy 261.708333 -256.512385) (xy 261.684661 -256.562882) (xy 261.653888 -256.609395) (xy 261.616671 -256.650932)
			(xy 261.573803 -256.686607) (xy 261.526197 -256.715661) (xy 261.474868 -256.737473) (xy 261.420911 -256.751579)
			(xy 261.365474 -256.757679) (xy 261.30974 -256.755642) (xy 261.254897 -256.745512) (xy 261.202113 -256.727505)
			(xy 261.152513 -256.702004) (xy 261.107155 -256.669553) (xy 261.067006 -256.630844) (xy 261.03292 -256.586701)
			(xy 261.005624 -256.538066) (xy 260.985701 -256.485975) (xy 260.973575 -256.431538) (xy 260.969504 -256.375916)
			(xy 260.726115 -256.375916) (xy 260.686073 -256.409239) (xy 260.638467 -256.438293) (xy 260.587138 -256.460105)
			(xy 260.533181 -256.474211) (xy 260.477744 -256.480311) (xy 260.42201 -256.478274) (xy 260.367167 -256.468144)
			(xy 260.314383 -256.450137) (xy 260.264783 -256.424636) (xy 260.219425 -256.392185) (xy 260.179276 -256.353476)
			(xy 260.14519 -256.309333) (xy 260.117894 -256.260698) (xy 260.097971 -256.208607) (xy 260.085845 -256.15417)
			(xy 260.081774 -256.098548) (xy 258.713862 -256.098548) (xy 258.754563 -256.117135) (xy 258.800413 -256.1466)
			(xy 258.841603 -256.182291) (xy 258.877295 -256.22348) (xy 258.906762 -256.26933) (xy 258.929403 -256.318907)
			(xy 258.944758 -256.371202) (xy 258.952515 -256.425149) (xy 258.952515 -256.479651) (xy 258.944758 -256.533598)
			(xy 258.929403 -256.585893) (xy 258.906762 -256.63547) (xy 258.877295 -256.68132) (xy 258.841603 -256.722509)
			(xy 258.800413 -256.7582) (xy 258.754563 -256.787665) (xy 258.704985 -256.810306) (xy 258.652691 -256.82566)
			(xy 258.598743 -256.833415) (xy 258.571492 -256.833878) (xy 258.545176 -256.833417) (xy 258.493042 -256.826199)
			(xy 258.442394 -256.811889) (xy 258.394192 -256.790756) (xy 258.34935 -256.763201) (xy 258.308718 -256.729748)
			(xy 258.290568 -256.710688) (xy 258.283062 -256.703268) (xy 258.26377 -256.694755) (xy 258.25323 -256.694178)
			(xy 258.178554 -256.694178) (xy 258.168007 -256.694729) (xy 258.148712 -256.70325) (xy 258.141216 -256.710688)
			(xy 258.123071 -256.729757) (xy 258.082453 -256.763237) (xy 258.037615 -256.790809) (xy 257.989409 -256.811949)
			(xy 257.938754 -256.826256) (xy 257.886611 -256.833456) (xy 257.860292 -256.833878) (xy 257.833039 -256.833452)
			(xy 257.779088 -256.825694) (xy 257.72679 -256.810337) (xy 257.67721 -256.787693) (xy 257.631357 -256.758224)
			(xy 257.590164 -256.72253) (xy 257.554471 -256.681337) (xy 257.525003 -256.635483) (xy 257.502361 -256.585903)
			(xy 257.487005 -256.533604) (xy 257.479248 -256.479653) (xy 233.66857 -256.479653) (xy 233.66857 -256.987548)
			(xy 260.081774 -256.987548) (xy 260.085845 -256.931926) (xy 260.097971 -256.877489) (xy 260.117894 -256.825398)
			(xy 260.14519 -256.776763) (xy 260.179276 -256.73262) (xy 260.219425 -256.693911) (xy 260.264783 -256.66146)
			(xy 260.314383 -256.635959) (xy 260.367167 -256.617952) (xy 260.42201 -256.607822) (xy 260.477744 -256.605785)
			(xy 260.533181 -256.611885) (xy 260.587138 -256.625991) (xy 260.638467 -256.647803) (xy 260.686073 -256.676857)
			(xy 260.728941 -256.712532) (xy 260.766158 -256.754069) (xy 260.796931 -256.800582) (xy 260.820603 -256.851079)
			(xy 260.836671 -256.904486) (xy 260.844791 -256.959662) (xy 260.8453 -256.987548) (xy 260.844791 -257.015434)
			(xy 260.836671 -257.07061) (xy 260.820603 -257.124017) (xy 260.814087 -257.137916) (xy 266.496038 -257.137916)
			(xy 266.496612 -257.108535) (xy 266.505639 -257.050471) (xy 266.523466 -256.994479) (xy 266.549671 -256.941884)
			(xy 266.583634 -256.893931) (xy 266.624551 -256.851756) (xy 266.647676 -256.833624) (xy 266.657074 -256.826258)
			(xy 266.667488 -256.805684) (xy 266.669012 -256.701798) (xy 266.659106 -256.680716) (xy 266.649962 -256.67335)
			(xy 266.6281 -256.65516) (xy 266.589562 -256.613337) (xy 266.557658 -256.566258) (xy 266.533094 -256.514965)
			(xy 266.516413 -256.460595) (xy 266.507986 -256.404352) (xy 266.507468 -256.375916) (xy 266.507954 -256.348665)
			(xy 266.51571 -256.294717) (xy 266.531065 -256.242422) (xy 266.553707 -256.192845) (xy 266.583173 -256.146995)
			(xy 266.618864 -256.105804) (xy 266.660055 -256.070113) (xy 266.705905 -256.040647) (xy 266.755482 -256.018005)
			(xy 266.807777 -256.00265) (xy 266.861725 -255.994894) (xy 266.916227 -255.994894) (xy 266.970175 -256.00265)
			(xy 267.02247 -256.018005) (xy 267.072047 -256.040647) (xy 267.117897 -256.070113) (xy 267.159088 -256.105804)
			(xy 267.194779 -256.146995) (xy 267.224245 -256.192845) (xy 267.246887 -256.242422) (xy 267.262242 -256.294717)
			(xy 267.269998 -256.348665) (xy 267.270484 -256.375916) (xy 267.269964 -256.405299) (xy 267.26093 -256.463367)
			(xy 267.243095 -256.519362) (xy 267.216879 -256.571957) (xy 267.182905 -256.619908) (xy 267.141976 -256.662079)
			(xy 267.118846 -256.680208) (xy 267.109448 -256.687574) (xy 267.099034 -256.708148) (xy 267.09751 -256.812034)
			(xy 267.107416 -256.833116) (xy 267.11656 -256.840482) (xy 267.138373 -256.858728) (xy 267.176918 -256.900537)
			(xy 267.20883 -256.947604) (xy 267.233403 -256.998886) (xy 267.250093 -257.053247) (xy 267.258531 -257.109483)
			(xy 267.259054 -257.137916) (xy 267.892528 -257.137916) (xy 267.896599 -257.082294) (xy 267.908725 -257.027857)
			(xy 267.928648 -256.975766) (xy 267.955944 -256.927131) (xy 267.99003 -256.882988) (xy 268.030179 -256.844279)
			(xy 268.075537 -256.811828) (xy 268.125137 -256.786327) (xy 268.177921 -256.76832) (xy 268.232764 -256.75819)
			(xy 268.288498 -256.756153) (xy 268.343935 -256.762253) (xy 268.397892 -256.776359) (xy 268.449221 -256.798171)
			(xy 268.496827 -256.827225) (xy 268.539695 -256.8629) (xy 268.576912 -256.904437) (xy 268.607685 -256.95095)
			(xy 268.631357 -257.001447) (xy 268.647425 -257.054854) (xy 268.655545 -257.11003) (xy 268.656054 -257.137916)
			(xy 268.778988 -257.137916) (xy 268.783059 -257.082294) (xy 268.795185 -257.027857) (xy 268.815108 -256.975766)
			(xy 268.842404 -256.927131) (xy 268.87649 -256.882988) (xy 268.916639 -256.844279) (xy 268.961997 -256.811828)
			(xy 269.011597 -256.786327) (xy 269.064381 -256.76832) (xy 269.119224 -256.75819) (xy 269.174958 -256.756153)
			(xy 269.230395 -256.762253) (xy 269.284352 -256.776359) (xy 269.335681 -256.798171) (xy 269.383287 -256.827225)
			(xy 269.426155 -256.8629) (xy 269.463372 -256.904437) (xy 269.494145 -256.95095) (xy 269.517817 -257.001447)
			(xy 269.533885 -257.054854) (xy 269.542005 -257.11003) (xy 269.542514 -257.137916) (xy 269.54249 -257.139253)
			(xy 271.596563 -257.139253) (xy 271.596563 -257.084747) (xy 271.60432 -257.030796) (xy 271.619677 -256.978499)
			(xy 271.64232 -256.928919) (xy 271.671788 -256.883066) (xy 271.707482 -256.841874) (xy 271.748676 -256.806181)
			(xy 271.794529 -256.776714) (xy 271.84411 -256.754073) (xy 271.896408 -256.738718) (xy 271.950359 -256.730962)
			(xy 271.977612 -256.7305) (xy 272.005382 -256.730988) (xy 272.060336 -256.739043) (xy 272.11354 -256.754981)
			(xy 272.163871 -256.778465) (xy 272.210265 -256.809) (xy 272.251741 -256.845938) (xy 272.269966 -256.866898)
			(xy 272.276824 -256.875026) (xy 272.295112 -256.88417) (xy 272.3896 -256.890266) (xy 272.408904 -256.883408)
			(xy 272.416778 -256.876296) (xy 272.438011 -256.857382) (xy 272.485061 -256.825451) (xy 272.536332 -256.800864)
			(xy 272.590687 -256.784165) (xy 272.646919 -256.775726) (xy 272.67535 -256.775204) (xy 272.703937 -256.775651)
			(xy 272.760472 -256.784176) (xy 272.815102 -256.801044) (xy 272.866602 -256.825876) (xy 272.913819 -256.858116)
			(xy 272.955696 -256.897042) (xy 272.991295 -256.941781) (xy 273.019817 -256.991333) (xy 273.030696 -257.017774)
			(xy 273.035776 -257.030728) (xy 273.057112 -257.047492) (xy 273.17192 -257.064002) (xy 273.197066 -257.053842)
			(xy 273.205702 -257.04292) (xy 273.223904 -257.020351) (xy 273.265939 -256.980421) (xy 273.313532 -256.947311)
			(xy 273.365586 -256.921784) (xy 273.420904 -256.904427) (xy 273.478212 -256.895639) (xy 273.5072 -256.895092)
			(xy 273.534451 -256.895578) (xy 273.588399 -256.903334) (xy 273.640694 -256.918689) (xy 273.690271 -256.941331)
			(xy 273.736121 -256.970797) (xy 273.777312 -257.006488) (xy 273.813003 -257.047679) (xy 273.842469 -257.093529)
			(xy 273.865111 -257.143106) (xy 273.880466 -257.195401) (xy 273.888222 -257.249349) (xy 273.888222 -257.303851)
			(xy 273.880466 -257.357799) (xy 273.865111 -257.410094) (xy 273.842469 -257.459671) (xy 273.813003 -257.505521)
			(xy 273.777312 -257.546712) (xy 273.736121 -257.582403) (xy 273.690271 -257.611869) (xy 273.640694 -257.634511)
			(xy 273.588399 -257.649866) (xy 273.534451 -257.657622) (xy 273.5072 -257.658108) (xy 273.478615 -257.65761)
			(xy 273.422082 -257.649092) (xy 273.367455 -257.632232) (xy 273.315955 -257.607408) (xy 273.268737 -257.575175)
			(xy 273.226859 -257.536256) (xy 273.191259 -257.491522) (xy 273.162734 -257.441976) (xy 273.151854 -257.415538)
			(xy 273.146774 -257.402584) (xy 273.125438 -257.38582) (xy 273.01063 -257.36931) (xy 272.985484 -257.37947)
			(xy 272.976848 -257.390392) (xy 272.958678 -257.412987) (xy 272.916636 -257.452915) (xy 272.869036 -257.486021)
			(xy 272.816975 -257.511544) (xy 272.761652 -257.528896) (xy 272.70434 -257.537676) (xy 272.67535 -257.53822)
			(xy 272.647582 -257.537682) (xy 272.592631 -257.529636) (xy 272.539428 -257.513708) (xy 272.489096 -257.490233)
			(xy 272.442701 -257.459707) (xy 272.401222 -257.422777) (xy 272.382996 -257.401822) (xy 272.376138 -257.393694)
			(xy 272.35785 -257.38455) (xy 272.263362 -257.378454) (xy 272.244058 -257.385312) (xy 272.236184 -257.392424)
			(xy 272.214929 -257.411312) (xy 272.167885 -257.443246) (xy 272.116619 -257.467838) (xy 272.062269 -257.484543)
			(xy 272.006041 -257.49299) (xy 271.977612 -257.493516) (xy 271.950359 -257.493038) (xy 271.896408 -257.485282)
			(xy 271.84411 -257.469927) (xy 271.794529 -257.447286) (xy 271.748676 -257.417819) (xy 271.707482 -257.382126)
			(xy 271.671788 -257.340934) (xy 271.64232 -257.295081) (xy 271.619677 -257.245501) (xy 271.60432 -257.193204)
			(xy 271.596563 -257.139253) (xy 269.54249 -257.139253) (xy 269.542005 -257.165802) (xy 269.533885 -257.220978)
			(xy 269.517817 -257.274385) (xy 269.494145 -257.324882) (xy 269.463372 -257.371395) (xy 269.426155 -257.412932)
			(xy 269.383287 -257.448607) (xy 269.335681 -257.477661) (xy 269.284352 -257.499473) (xy 269.230395 -257.513579)
			(xy 269.174958 -257.519679) (xy 269.119224 -257.517642) (xy 269.064381 -257.507512) (xy 269.011597 -257.489505)
			(xy 268.961997 -257.464004) (xy 268.916639 -257.431553) (xy 268.87649 -257.392844) (xy 268.842404 -257.348701)
			(xy 268.815108 -257.300066) (xy 268.795185 -257.247975) (xy 268.783059 -257.193538) (xy 268.778988 -257.137916)
			(xy 268.656054 -257.137916) (xy 268.655545 -257.165802) (xy 268.647425 -257.220978) (xy 268.631357 -257.274385)
			(xy 268.607685 -257.324882) (xy 268.576912 -257.371395) (xy 268.539695 -257.412932) (xy 268.496827 -257.448607)
			(xy 268.449221 -257.477661) (xy 268.397892 -257.499473) (xy 268.343935 -257.513579) (xy 268.288498 -257.519679)
			(xy 268.232764 -257.517642) (xy 268.177921 -257.507512) (xy 268.125137 -257.489505) (xy 268.075537 -257.464004)
			(xy 268.030179 -257.431553) (xy 267.99003 -257.392844) (xy 267.955944 -257.348701) (xy 267.928648 -257.300066)
			(xy 267.908725 -257.247975) (xy 267.896599 -257.193538) (xy 267.892528 -257.137916) (xy 267.259054 -257.137916)
			(xy 267.258568 -257.165167) (xy 267.250812 -257.219115) (xy 267.235457 -257.27141) (xy 267.212815 -257.320987)
			(xy 267.183349 -257.366837) (xy 267.147658 -257.408028) (xy 267.106467 -257.443719) (xy 267.060617 -257.473185)
			(xy 267.01104 -257.495827) (xy 266.958745 -257.511182) (xy 266.904797 -257.518938) (xy 266.850295 -257.518938)
			(xy 266.796347 -257.511182) (xy 266.744052 -257.495827) (xy 266.694475 -257.473185) (xy 266.648625 -257.443719)
			(xy 266.607434 -257.408028) (xy 266.571743 -257.366837) (xy 266.542277 -257.320987) (xy 266.519635 -257.27141)
			(xy 266.50428 -257.219115) (xy 266.496524 -257.165167) (xy 266.496038 -257.137916) (xy 260.814087 -257.137916)
			(xy 260.796931 -257.174514) (xy 260.766158 -257.221027) (xy 260.728941 -257.262564) (xy 260.686073 -257.298239)
			(xy 260.638467 -257.327293) (xy 260.587138 -257.349105) (xy 260.533181 -257.363211) (xy 260.477744 -257.369311)
			(xy 260.42201 -257.367274) (xy 260.367167 -257.357144) (xy 260.314383 -257.339137) (xy 260.264783 -257.313636)
			(xy 260.219425 -257.281185) (xy 260.179276 -257.242476) (xy 260.14519 -257.198333) (xy 260.117894 -257.149698)
			(xy 260.097971 -257.097607) (xy 260.085845 -257.04317) (xy 260.081774 -256.987548) (xy 233.66857 -256.987548)
			(xy 233.66857 -259.08381) (xy 250.631452 -259.08381) (xy 250.63186 -259.057936) (xy 250.638843 -259.006661)
			(xy 250.652695 -258.956802) (xy 250.673162 -258.909273) (xy 250.699868 -258.864949) (xy 250.732322 -258.824643)
			(xy 250.769928 -258.789095) (xy 250.79071 -258.773676) (xy 250.800183 -258.766118) (xy 250.811314 -258.744626)
			(xy 250.812046 -258.732528) (xy 250.812046 -258.649724) (xy 250.811296 -258.63763) (xy 250.80017 -258.616146)
			(xy 250.79071 -258.608576) (xy 250.769944 -258.593139) (xy 250.732352 -258.557584) (xy 250.699909 -258.517277)
			(xy 250.673208 -258.472955) (xy 250.652741 -258.425433) (xy 250.638882 -258.375581) (xy 250.631886 -258.324313)
			(xy 250.631452 -258.298442) (xy 250.631904 -258.27064) (xy 250.639966 -258.215624) (xy 250.655925 -258.162359)
			(xy 250.679444 -258.111974) (xy 250.710025 -258.065534) (xy 250.74702 -258.024024) (xy 250.789647 -257.98832)
			(xy 250.813062 -257.973322) (xy 250.82373 -257.966972) (xy 250.83643 -257.946144) (xy 250.84405 -257.83921)
			(xy 250.834398 -257.816604) (xy 250.825 -257.80873) (xy 250.803889 -257.790522) (xy 250.766691 -257.748999)
			(xy 250.735934 -257.702504) (xy 250.712273 -257.652026) (xy 250.696213 -257.598642) (xy 250.688096 -257.543488)
			(xy 250.687586 -257.515614) (xy 250.688072 -257.488363) (xy 250.695828 -257.434415) (xy 250.711183 -257.38212)
			(xy 250.733825 -257.332543) (xy 250.763291 -257.286693) (xy 250.798982 -257.245502) (xy 250.840173 -257.209811)
			(xy 250.886023 -257.180345) (xy 250.9356 -257.157703) (xy 250.987895 -257.142348) (xy 251.041843 -257.134592)
			(xy 251.096345 -257.134592) (xy 251.150293 -257.142348) (xy 251.202588 -257.157703) (xy 251.252165 -257.180345)
			(xy 251.298015 -257.209811) (xy 251.339206 -257.245502) (xy 251.374897 -257.286693) (xy 251.404363 -257.332543)
			(xy 251.427005 -257.38212) (xy 251.44236 -257.434415) (xy 251.448082 -257.474212) (xy 254.171702 -257.474212)
			(xy 254.175773 -257.41859) (xy 254.187899 -257.364153) (xy 254.207822 -257.312062) (xy 254.235118 -257.263427)
			(xy 254.269204 -257.219284) (xy 254.309353 -257.180575) (xy 254.354711 -257.148124) (xy 254.404311 -257.122623)
			(xy 254.457095 -257.104616) (xy 254.511938 -257.094486) (xy 254.567672 -257.092449) (xy 254.623109 -257.098549)
			(xy 254.677066 -257.112655) (xy 254.728395 -257.134467) (xy 254.776001 -257.163521) (xy 254.818869 -257.199196)
			(xy 254.856086 -257.240733) (xy 254.886859 -257.287246) (xy 254.910531 -257.337743) (xy 254.926599 -257.39115)
			(xy 254.934719 -257.446326) (xy 254.935228 -257.474212) (xy 254.934719 -257.502098) (xy 254.926599 -257.557274)
			(xy 254.910531 -257.610681) (xy 254.886859 -257.661178) (xy 254.856086 -257.707691) (xy 254.818869 -257.749228)
			(xy 254.776001 -257.784903) (xy 254.728395 -257.813957) (xy 254.677066 -257.835769) (xy 254.623109 -257.849875)
			(xy 254.567672 -257.855975) (xy 254.511938 -257.853938) (xy 254.457095 -257.843808) (xy 254.404311 -257.825801)
			(xy 254.354711 -257.8003) (xy 254.309353 -257.767849) (xy 254.269204 -257.72914) (xy 254.235118 -257.684997)
			(xy 254.207822 -257.636362) (xy 254.187899 -257.584271) (xy 254.175773 -257.529834) (xy 254.171702 -257.474212)
			(xy 251.448082 -257.474212) (xy 251.450116 -257.488363) (xy 251.450602 -257.515614) (xy 251.45009 -257.543414)
			(xy 251.442036 -257.598426) (xy 251.426085 -257.651688) (xy 251.402575 -257.702072) (xy 251.372005 -257.748512)
			(xy 251.335019 -257.790025) (xy 251.292402 -257.825733) (xy 251.268992 -257.840734) (xy 251.258324 -257.847084)
			(xy 251.245624 -257.867912) (xy 251.238004 -257.974846) (xy 251.247656 -257.997452) (xy 251.257054 -258.005326)
			(xy 251.278134 -258.023568) (xy 251.315337 -258.065082) (xy 251.346099 -258.11157) (xy 251.369765 -258.162042)
			(xy 251.385438 -258.214114) (xy 256.61061 -258.214114) (xy 256.614681 -258.158492) (xy 256.626807 -258.104055)
			(xy 256.64673 -258.051964) (xy 256.674026 -258.003329) (xy 256.708112 -257.959186) (xy 256.748261 -257.920477)
			(xy 256.793619 -257.888026) (xy 256.843219 -257.862525) (xy 256.896003 -257.844518) (xy 256.950846 -257.834388)
			(xy 257.00658 -257.832351) (xy 257.062017 -257.838451) (xy 257.115974 -257.852557) (xy 257.167303 -257.874369)
			(xy 257.214909 -257.903423) (xy 257.257777 -257.939098) (xy 257.294994 -257.980635) (xy 257.325767 -258.027148)
			(xy 257.349439 -258.077645) (xy 257.365507 -258.131052) (xy 257.373627 -258.186228) (xy 257.374136 -258.214114)
			(xy 257.373627 -258.242) (xy 257.368909 -258.274058) (xy 260.969504 -258.274058) (xy 260.973575 -258.218436)
			(xy 260.985701 -258.163999) (xy 261.005624 -258.111908) (xy 261.03292 -258.063273) (xy 261.067006 -258.01913)
			(xy 261.107155 -257.980421) (xy 261.152513 -257.94797) (xy 261.202113 -257.922469) (xy 261.254897 -257.904462)
			(xy 261.30974 -257.894332) (xy 261.365474 -257.892295) (xy 261.420911 -257.898395) (xy 261.474868 -257.912501)
			(xy 261.526197 -257.934313) (xy 261.573803 -257.963367) (xy 261.616671 -257.999042) (xy 261.653888 -258.040579)
			(xy 261.684661 -258.087092) (xy 261.708333 -258.137589) (xy 261.724401 -258.190996) (xy 261.732521 -258.246172)
			(xy 261.73303 -258.274058) (xy 262.454642 -258.274058) (xy 262.458713 -258.218436) (xy 262.470839 -258.163999)
			(xy 262.490762 -258.111908) (xy 262.518058 -258.063273) (xy 262.552144 -258.01913) (xy 262.592293 -257.980421)
			(xy 262.637651 -257.94797) (xy 262.687251 -257.922469) (xy 262.740035 -257.904462) (xy 262.794878 -257.894332)
			(xy 262.850612 -257.892295) (xy 262.906049 -257.898395) (xy 262.960006 -257.912501) (xy 263.011335 -257.934313)
			(xy 263.058941 -257.963367) (xy 263.101809 -257.999042) (xy 263.139026 -258.040579) (xy 263.169799 -258.087092)
			(xy 263.193471 -258.137589) (xy 263.209539 -258.190996) (xy 263.217659 -258.246172) (xy 263.218168 -258.274058)
			(xy 263.217659 -258.301944) (xy 263.209539 -258.35712) (xy 263.193471 -258.410527) (xy 263.169799 -258.461024)
			(xy 263.139026 -258.507537) (xy 263.101809 -258.549074) (xy 263.058941 -258.584749) (xy 263.011335 -258.613803)
			(xy 262.960006 -258.635615) (xy 262.906049 -258.649721) (xy 262.850612 -258.655821) (xy 262.794878 -258.653784)
			(xy 262.740035 -258.643654) (xy 262.687251 -258.625647) (xy 262.637651 -258.600146) (xy 262.592293 -258.567695)
			(xy 262.552144 -258.528986) (xy 262.518058 -258.484843) (xy 262.490762 -258.436208) (xy 262.470839 -258.384117)
			(xy 262.458713 -258.32968) (xy 262.454642 -258.274058) (xy 261.73303 -258.274058) (xy 261.732521 -258.301944)
			(xy 261.724401 -258.35712) (xy 261.708333 -258.410527) (xy 261.684661 -258.461024) (xy 261.653888 -258.507537)
			(xy 261.616671 -258.549074) (xy 261.573803 -258.584749) (xy 261.526197 -258.613803) (xy 261.474868 -258.635615)
			(xy 261.420911 -258.649721) (xy 261.365474 -258.655821) (xy 261.30974 -258.653784) (xy 261.254897 -258.643654)
			(xy 261.202113 -258.625647) (xy 261.152513 -258.600146) (xy 261.107155 -258.567695) (xy 261.067006 -258.528986)
			(xy 261.03292 -258.484843) (xy 261.005624 -258.436208) (xy 260.985701 -258.384117) (xy 260.973575 -258.32968)
			(xy 260.969504 -258.274058) (xy 257.368909 -258.274058) (xy 257.365507 -258.297176) (xy 257.349439 -258.350583)
			(xy 257.325767 -258.40108) (xy 257.294994 -258.447593) (xy 257.257777 -258.48913) (xy 257.214909 -258.524805)
			(xy 257.167303 -258.553859) (xy 257.115974 -258.575671) (xy 257.062017 -258.589777) (xy 257.00658 -258.595877)
			(xy 256.950846 -258.59384) (xy 256.896003 -258.58371) (xy 256.843219 -258.565703) (xy 256.793619 -258.540202)
			(xy 256.748261 -258.507751) (xy 256.708112 -258.469042) (xy 256.674026 -258.424899) (xy 256.64673 -258.376264)
			(xy 256.626807 -258.324173) (xy 256.614681 -258.269736) (xy 256.61061 -258.214114) (xy 251.385438 -258.214114)
			(xy 251.385831 -258.215421) (xy 251.393955 -258.27057) (xy 251.394468 -258.298442) (xy 251.394016 -258.324315)
			(xy 251.38704 -258.375587) (xy 251.373195 -258.425445) (xy 251.352735 -258.472973) (xy 251.326036 -258.517298)
			(xy 251.293589 -258.557606) (xy 251.255989 -258.593155) (xy 251.23521 -258.608576) (xy 251.225762 -258.616161)
			(xy 251.214617 -258.637632) (xy 251.213874 -258.649724) (xy 251.213874 -258.6736) (xy 253.541782 -258.6736)
			(xy 253.545853 -258.617978) (xy 253.557979 -258.563541) (xy 253.577902 -258.51145) (xy 253.605198 -258.462815)
			(xy 253.639284 -258.418672) (xy 253.679433 -258.379963) (xy 253.724791 -258.347512) (xy 253.774391 -258.322011)
			(xy 253.827175 -258.304004) (xy 253.882018 -258.293874) (xy 253.937752 -258.291837) (xy 253.993189 -258.297937)
			(xy 254.047146 -258.312043) (xy 254.098475 -258.333855) (xy 254.146081 -258.362909) (xy 254.188949 -258.398584)
			(xy 254.226166 -258.440121) (xy 254.256939 -258.486634) (xy 254.280611 -258.537131) (xy 254.296679 -258.590538)
			(xy 254.304799 -258.645714) (xy 254.304877 -258.649978) (xy 255.126234 -258.649978) (xy 255.130305 -258.594356)
			(xy 255.142431 -258.539919) (xy 255.162354 -258.487828) (xy 255.18965 -258.439193) (xy 255.223736 -258.39505)
			(xy 255.263885 -258.356341) (xy 255.309243 -258.32389) (xy 255.358843 -258.298389) (xy 255.411627 -258.280382)
			(xy 255.46647 -258.270252) (xy 255.522204 -258.268215) (xy 255.577641 -258.274315) (xy 255.631598 -258.288421)
			(xy 255.682927 -258.310233) (xy 255.730533 -258.339287) (xy 255.773401 -258.374962) (xy 255.810618 -258.416499)
			(xy 255.841391 -258.463012) (xy 255.865063 -258.513509) (xy 255.881131 -258.566916) (xy 255.889251 -258.622092)
			(xy 255.88976 -258.649978) (xy 255.889251 -258.677864) (xy 255.881131 -258.73304) (xy 255.865063 -258.786447)
			(xy 255.841391 -258.836944) (xy 255.810618 -258.883457) (xy 255.773401 -258.924994) (xy 255.730533 -258.960669)
			(xy 255.682927 -258.989723) (xy 255.631598 -259.011535) (xy 255.577641 -259.025641) (xy 255.522204 -259.031741)
			(xy 255.46647 -259.029704) (xy 255.411627 -259.019574) (xy 255.358843 -259.001567) (xy 255.309243 -258.976066)
			(xy 255.263885 -258.943615) (xy 255.223736 -258.904906) (xy 255.18965 -258.860763) (xy 255.162354 -258.812128)
			(xy 255.142431 -258.760037) (xy 255.130305 -258.7056) (xy 255.126234 -258.649978) (xy 254.304877 -258.649978)
			(xy 254.305308 -258.6736) (xy 254.304799 -258.701486) (xy 254.296679 -258.756662) (xy 254.280611 -258.810069)
			(xy 254.256939 -258.860566) (xy 254.226166 -258.907079) (xy 254.188949 -258.948616) (xy 254.146081 -258.984291)
			(xy 254.098475 -259.013345) (xy 254.047146 -259.035157) (xy 253.993189 -259.049263) (xy 253.937752 -259.055363)
			(xy 253.882018 -259.053326) (xy 253.827175 -259.043196) (xy 253.774391 -259.025189) (xy 253.724791 -258.999688)
			(xy 253.679433 -258.967237) (xy 253.639284 -258.928528) (xy 253.605198 -258.884385) (xy 253.577902 -258.83575)
			(xy 253.557979 -258.783659) (xy 253.545853 -258.729222) (xy 253.541782 -258.6736) (xy 251.213874 -258.6736)
			(xy 251.213874 -258.732528) (xy 251.214586 -258.744628) (xy 251.225738 -258.766111) (xy 251.23521 -258.773676)
			(xy 251.255958 -258.789136) (xy 251.293549 -258.824688) (xy 251.325994 -258.864992) (xy 251.352696 -258.909309)
			(xy 251.373166 -258.956828) (xy 251.387029 -259.006676) (xy 251.394031 -259.05794) (xy 251.394468 -259.08381)
			(xy 251.393982 -259.111061) (xy 251.386226 -259.165009) (xy 251.370871 -259.217304) (xy 251.348229 -259.266881)
			(xy 251.318763 -259.312731) (xy 251.283072 -259.353922) (xy 251.241881 -259.389613) (xy 251.196031 -259.419079)
			(xy 251.146454 -259.441721) (xy 251.094159 -259.457076) (xy 251.040211 -259.464832) (xy 250.985709 -259.464832)
			(xy 250.931761 -259.457076) (xy 250.879466 -259.441721) (xy 250.829889 -259.419079) (xy 250.784039 -259.389613)
			(xy 250.742848 -259.353922) (xy 250.707157 -259.312731) (xy 250.677691 -259.266881) (xy 250.655049 -259.217304)
			(xy 250.639694 -259.165009) (xy 250.631938 -259.111061) (xy 250.631452 -259.08381) (xy 233.66857 -259.08381)
			(xy 233.66857 -259.576316) (xy 262.44499 -259.576316) (xy 262.449061 -259.520694) (xy 262.461187 -259.466257)
			(xy 262.48111 -259.414166) (xy 262.508406 -259.365531) (xy 262.542492 -259.321388) (xy 262.582641 -259.282679)
			(xy 262.627999 -259.250228) (xy 262.677599 -259.224727) (xy 262.730383 -259.20672) (xy 262.785226 -259.19659)
			(xy 262.84096 -259.194553) (xy 262.896397 -259.200653) (xy 262.950354 -259.214759) (xy 263.001683 -259.236571)
			(xy 263.049289 -259.265625) (xy 263.092157 -259.3013) (xy 263.129374 -259.342837) (xy 263.160147 -259.38935)
			(xy 263.183819 -259.439847) (xy 263.199887 -259.493254) (xy 263.208007 -259.54843) (xy 263.208516 -259.576316)
			(xy 263.33399 -259.576316) (xy 263.338061 -259.520694) (xy 263.350187 -259.466257) (xy 263.37011 -259.414166)
			(xy 263.397406 -259.365531) (xy 263.431492 -259.321388) (xy 263.471641 -259.282679) (xy 263.516999 -259.250228)
			(xy 263.566599 -259.224727) (xy 263.619383 -259.20672) (xy 263.674226 -259.19659) (xy 263.72996 -259.194553)
			(xy 263.785397 -259.200653) (xy 263.839354 -259.214759) (xy 263.890683 -259.236571) (xy 263.938289 -259.265625)
			(xy 263.981157 -259.3013) (xy 264.018374 -259.342837) (xy 264.049147 -259.38935) (xy 264.072819 -259.439847)
			(xy 264.088887 -259.493254) (xy 264.097007 -259.54843) (xy 264.097516 -259.576316) (xy 264.097007 -259.604202)
			(xy 264.088887 -259.659378) (xy 264.072819 -259.712785) (xy 264.049147 -259.763282) (xy 264.018374 -259.809795)
			(xy 263.981157 -259.851332) (xy 263.938289 -259.887007) (xy 263.890683 -259.916061) (xy 263.839354 -259.937873)
			(xy 263.785397 -259.951979) (xy 263.72996 -259.958079) (xy 263.674226 -259.956042) (xy 263.619383 -259.945912)
			(xy 263.566599 -259.927905) (xy 263.516999 -259.902404) (xy 263.471641 -259.869953) (xy 263.431492 -259.831244)
			(xy 263.397406 -259.787101) (xy 263.37011 -259.738466) (xy 263.350187 -259.686375) (xy 263.338061 -259.631938)
			(xy 263.33399 -259.576316) (xy 263.208516 -259.576316) (xy 263.208007 -259.604202) (xy 263.199887 -259.659378)
			(xy 263.183819 -259.712785) (xy 263.160147 -259.763282) (xy 263.129374 -259.809795) (xy 263.092157 -259.851332)
			(xy 263.049289 -259.887007) (xy 263.001683 -259.916061) (xy 262.950354 -259.937873) (xy 262.896397 -259.951979)
			(xy 262.84096 -259.958079) (xy 262.785226 -259.956042) (xy 262.730383 -259.945912) (xy 262.677599 -259.927905)
			(xy 262.627999 -259.902404) (xy 262.582641 -259.869953) (xy 262.542492 -259.831244) (xy 262.508406 -259.787101)
			(xy 262.48111 -259.738466) (xy 262.461187 -259.686375) (xy 262.449061 -259.631938) (xy 262.44499 -259.576316)
			(xy 233.66857 -259.576316) (xy 233.66857 -260.087872) (xy 250.630942 -260.087872) (xy 250.635013 -260.03225)
			(xy 250.647139 -259.977813) (xy 250.667062 -259.925722) (xy 250.694358 -259.877087) (xy 250.728444 -259.832944)
			(xy 250.768593 -259.794235) (xy 250.813951 -259.761784) (xy 250.863551 -259.736283) (xy 250.916335 -259.718276)
			(xy 250.971178 -259.708146) (xy 251.026912 -259.706109) (xy 251.082349 -259.712209) (xy 251.136306 -259.726315)
			(xy 251.187635 -259.748127) (xy 251.235241 -259.777181) (xy 251.278109 -259.812856) (xy 251.315326 -259.854393)
			(xy 251.346099 -259.900906) (xy 251.369771 -259.951403) (xy 251.385839 -260.00481) (xy 251.389204 -260.027674)
			(xy 254.29159 -260.027674) (xy 254.295661 -259.972052) (xy 254.307787 -259.917615) (xy 254.32771 -259.865524)
			(xy 254.355006 -259.816889) (xy 254.389092 -259.772746) (xy 254.429241 -259.734037) (xy 254.474599 -259.701586)
			(xy 254.524199 -259.676085) (xy 254.576983 -259.658078) (xy 254.631826 -259.647948) (xy 254.68756 -259.645911)
			(xy 254.742997 -259.652011) (xy 254.796954 -259.666117) (xy 254.848283 -259.687929) (xy 254.895889 -259.716983)
			(xy 254.938757 -259.752658) (xy 254.975974 -259.794195) (xy 255.006747 -259.840708) (xy 255.030419 -259.891205)
			(xy 255.046487 -259.944612) (xy 255.054607 -259.999788) (xy 255.055116 -260.027674) (xy 255.054607 -260.05556)
			(xy 255.052394 -260.0706) (xy 255.842768 -260.0706) (xy 255.846839 -260.014978) (xy 255.858965 -259.960541)
			(xy 255.878888 -259.90845) (xy 255.906184 -259.859815) (xy 255.94027 -259.815672) (xy 255.980419 -259.776963)
			(xy 256.025777 -259.744512) (xy 256.075377 -259.719011) (xy 256.128161 -259.701004) (xy 256.183004 -259.690874)
			(xy 256.238738 -259.688837) (xy 256.294175 -259.694937) (xy 256.348132 -259.709043) (xy 256.399461 -259.730855)
			(xy 256.447067 -259.759909) (xy 256.489935 -259.795584) (xy 256.527152 -259.837121) (xy 256.557925 -259.883634)
			(xy 256.581597 -259.934131) (xy 256.597665 -259.987538) (xy 256.605785 -260.042714) (xy 256.606294 -260.0706)
			(xy 256.605816 -260.096762) (xy 259.858762 -260.096762) (xy 259.862833 -260.04114) (xy 259.874959 -259.986703)
			(xy 259.894882 -259.934612) (xy 259.922178 -259.885977) (xy 259.956264 -259.841834) (xy 259.996413 -259.803125)
			(xy 260.041771 -259.770674) (xy 260.091371 -259.745173) (xy 260.144155 -259.727166) (xy 260.198998 -259.717036)
			(xy 260.254732 -259.714999) (xy 260.310169 -259.721099) (xy 260.364126 -259.735205) (xy 260.415455 -259.757017)
			(xy 260.463061 -259.786071) (xy 260.505929 -259.821746) (xy 260.543146 -259.863283) (xy 260.573919 -259.909796)
			(xy 260.597591 -259.960293) (xy 260.613659 -260.0137) (xy 260.621779 -260.068876) (xy 260.622288 -260.096762)
			(xy 260.621779 -260.124648) (xy 260.613659 -260.179824) (xy 260.597591 -260.233231) (xy 260.573919 -260.283728)
			(xy 260.543146 -260.330241) (xy 260.535911 -260.338316) (xy 266.496038 -260.338316) (xy 266.496612 -260.308935)
			(xy 266.505639 -260.250871) (xy 266.523466 -260.194879) (xy 266.549671 -260.142284) (xy 266.583634 -260.094331)
			(xy 266.624551 -260.052156) (xy 266.647676 -260.034024) (xy 266.657074 -260.026658) (xy 266.667488 -260.006084)
			(xy 266.669012 -259.902198) (xy 266.659106 -259.881116) (xy 266.649962 -259.87375) (xy 266.6281 -259.85556)
			(xy 266.589562 -259.813737) (xy 266.557658 -259.766658) (xy 266.533094 -259.715365) (xy 266.516413 -259.660995)
			(xy 266.507986 -259.604752) (xy 266.507468 -259.576316) (xy 266.507954 -259.549065) (xy 266.51571 -259.495117)
			(xy 266.531065 -259.442822) (xy 266.553707 -259.393245) (xy 266.583173 -259.347395) (xy 266.618864 -259.306204)
			(xy 266.660055 -259.270513) (xy 266.705905 -259.241047) (xy 266.755482 -259.218405) (xy 266.807777 -259.20305)
			(xy 266.861725 -259.195294) (xy 266.916227 -259.195294) (xy 266.970175 -259.20305) (xy 267.02247 -259.218405)
			(xy 267.072047 -259.241047) (xy 267.117897 -259.270513) (xy 267.159088 -259.306204) (xy 267.194779 -259.347395)
			(xy 267.224245 -259.393245) (xy 267.246887 -259.442822) (xy 267.262242 -259.495117) (xy 267.269998 -259.549065)
			(xy 267.270484 -259.576316) (xy 267.269964 -259.605699) (xy 267.26093 -259.663767) (xy 267.243095 -259.719762)
			(xy 267.216879 -259.772357) (xy 267.182905 -259.820308) (xy 267.141976 -259.862479) (xy 267.118846 -259.880608)
			(xy 267.109448 -259.887974) (xy 267.099034 -259.908548) (xy 267.09751 -260.012434) (xy 267.107416 -260.033516)
			(xy 267.11656 -260.040882) (xy 267.138373 -260.059128) (xy 267.176918 -260.100937) (xy 267.20883 -260.148004)
			(xy 267.233403 -260.199286) (xy 267.250093 -260.253647) (xy 267.258531 -260.309883) (xy 267.259054 -260.338316)
			(xy 267.892528 -260.338316) (xy 267.896599 -260.282694) (xy 267.908725 -260.228257) (xy 267.928648 -260.176166)
			(xy 267.955944 -260.127531) (xy 267.99003 -260.083388) (xy 268.030179 -260.044679) (xy 268.075537 -260.012228)
			(xy 268.125137 -259.986727) (xy 268.177921 -259.96872) (xy 268.232764 -259.95859) (xy 268.288498 -259.956553)
			(xy 268.343935 -259.962653) (xy 268.397892 -259.976759) (xy 268.449221 -259.998571) (xy 268.496827 -260.027625)
			(xy 268.539695 -260.0633) (xy 268.576912 -260.104837) (xy 268.607685 -260.15135) (xy 268.631357 -260.201847)
			(xy 268.647425 -260.255254) (xy 268.655545 -260.31043) (xy 268.656054 -260.338316) (xy 268.778988 -260.338316)
			(xy 268.783059 -260.282694) (xy 268.795185 -260.228257) (xy 268.815108 -260.176166) (xy 268.842404 -260.127531)
			(xy 268.87649 -260.083388) (xy 268.916639 -260.044679) (xy 268.961997 -260.012228) (xy 269.011597 -259.986727)
			(xy 269.064381 -259.96872) (xy 269.119224 -259.95859) (xy 269.174958 -259.956553) (xy 269.230395 -259.962653)
			(xy 269.284352 -259.976759) (xy 269.335681 -259.998571) (xy 269.383287 -260.027625) (xy 269.426155 -260.0633)
			(xy 269.463372 -260.104837) (xy 269.494145 -260.15135) (xy 269.517817 -260.201847) (xy 269.533885 -260.255254)
			(xy 269.542005 -260.31043) (xy 269.542514 -260.338316) (xy 269.542005 -260.366202) (xy 269.533885 -260.421378)
			(xy 269.517817 -260.474785) (xy 269.494145 -260.525282) (xy 269.463372 -260.571795) (xy 269.426155 -260.613332)
			(xy 269.383287 -260.649007) (xy 269.335681 -260.678061) (xy 269.284352 -260.699873) (xy 269.230395 -260.713979)
			(xy 269.174958 -260.720079) (xy 269.119224 -260.718042) (xy 269.064381 -260.707912) (xy 269.011597 -260.689905)
			(xy 268.961997 -260.664404) (xy 268.916639 -260.631953) (xy 268.87649 -260.593244) (xy 268.842404 -260.549101)
			(xy 268.815108 -260.500466) (xy 268.795185 -260.448375) (xy 268.783059 -260.393938) (xy 268.778988 -260.338316)
			(xy 268.656054 -260.338316) (xy 268.655545 -260.366202) (xy 268.647425 -260.421378) (xy 268.631357 -260.474785)
			(xy 268.607685 -260.525282) (xy 268.576912 -260.571795) (xy 268.539695 -260.613332) (xy 268.496827 -260.649007)
			(xy 268.449221 -260.678061) (xy 268.397892 -260.699873) (xy 268.343935 -260.713979) (xy 268.288498 -260.720079)
			(xy 268.232764 -260.718042) (xy 268.177921 -260.707912) (xy 268.125137 -260.689905) (xy 268.075537 -260.664404)
			(xy 268.030179 -260.631953) (xy 267.99003 -260.593244) (xy 267.955944 -260.549101) (xy 267.928648 -260.500466)
			(xy 267.908725 -260.448375) (xy 267.896599 -260.393938) (xy 267.892528 -260.338316) (xy 267.259054 -260.338316)
			(xy 267.258568 -260.365567) (xy 267.250812 -260.419515) (xy 267.235457 -260.47181) (xy 267.212815 -260.521387)
			(xy 267.183349 -260.567237) (xy 267.147658 -260.608428) (xy 267.106467 -260.644119) (xy 267.060617 -260.673585)
			(xy 267.01104 -260.696227) (xy 266.958745 -260.711582) (xy 266.904797 -260.719338) (xy 266.850295 -260.719338)
			(xy 266.796347 -260.711582) (xy 266.744052 -260.696227) (xy 266.694475 -260.673585) (xy 266.648625 -260.644119)
			(xy 266.607434 -260.608428) (xy 266.571743 -260.567237) (xy 266.542277 -260.521387) (xy 266.519635 -260.47181)
			(xy 266.50428 -260.419515) (xy 266.496524 -260.365567) (xy 266.496038 -260.338316) (xy 260.535911 -260.338316)
			(xy 260.505929 -260.371778) (xy 260.463061 -260.407453) (xy 260.415455 -260.436507) (xy 260.364126 -260.458319)
			(xy 260.310169 -260.472425) (xy 260.254732 -260.478525) (xy 260.198998 -260.476488) (xy 260.144155 -260.466358)
			(xy 260.091371 -260.448351) (xy 260.041771 -260.42285) (xy 259.996413 -260.390399) (xy 259.956264 -260.35169)
			(xy 259.922178 -260.307547) (xy 259.894882 -260.258912) (xy 259.874959 -260.206821) (xy 259.862833 -260.152384)
			(xy 259.858762 -260.096762) (xy 256.605816 -260.096762) (xy 256.605785 -260.098486) (xy 256.597665 -260.153662)
			(xy 256.581597 -260.207069) (xy 256.557925 -260.257566) (xy 256.527152 -260.304079) (xy 256.489935 -260.345616)
			(xy 256.447067 -260.381291) (xy 256.399461 -260.410345) (xy 256.348132 -260.432157) (xy 256.294175 -260.446263)
			(xy 256.238738 -260.452363) (xy 256.183004 -260.450326) (xy 256.128161 -260.440196) (xy 256.075377 -260.422189)
			(xy 256.025777 -260.396688) (xy 255.980419 -260.364237) (xy 255.94027 -260.325528) (xy 255.906184 -260.281385)
			(xy 255.878888 -260.23275) (xy 255.858965 -260.180659) (xy 255.846839 -260.126222) (xy 255.842768 -260.0706)
			(xy 255.052394 -260.0706) (xy 255.046487 -260.110736) (xy 255.030419 -260.164143) (xy 255.006747 -260.21464)
			(xy 254.975974 -260.261153) (xy 254.938757 -260.30269) (xy 254.895889 -260.338365) (xy 254.848283 -260.367419)
			(xy 254.796954 -260.389231) (xy 254.742997 -260.403337) (xy 254.68756 -260.409437) (xy 254.631826 -260.4074)
			(xy 254.576983 -260.39727) (xy 254.524199 -260.379263) (xy 254.474599 -260.353762) (xy 254.429241 -260.321311)
			(xy 254.389092 -260.282602) (xy 254.355006 -260.238459) (xy 254.32771 -260.189824) (xy 254.307787 -260.137733)
			(xy 254.295661 -260.083296) (xy 254.29159 -260.027674) (xy 251.389204 -260.027674) (xy 251.393959 -260.059986)
			(xy 251.394468 -260.087872) (xy 251.393959 -260.115758) (xy 251.385839 -260.170934) (xy 251.369771 -260.224341)
			(xy 251.346099 -260.274838) (xy 251.315326 -260.321351) (xy 251.278109 -260.362888) (xy 251.235241 -260.398563)
			(xy 251.187635 -260.427617) (xy 251.136306 -260.449429) (xy 251.082349 -260.463535) (xy 251.026912 -260.469635)
			(xy 250.971178 -260.467598) (xy 250.916335 -260.457468) (xy 250.863551 -260.439461) (xy 250.813951 -260.41396)
			(xy 250.768593 -260.381509) (xy 250.728444 -260.3428) (xy 250.694358 -260.298657) (xy 250.667062 -260.250022)
			(xy 250.647139 -260.197931) (xy 250.635013 -260.143494) (xy 250.630942 -260.087872) (xy 233.66857 -260.087872)
			(xy 233.66857 -261.817955) (xy 257.719243 -261.817955) (xy 257.719243 -261.763445) (xy 257.727001 -261.709491)
			(xy 257.742358 -261.657189) (xy 257.765003 -261.607606) (xy 257.794474 -261.56175) (xy 257.830171 -261.520556)
			(xy 257.871368 -261.484861) (xy 257.917225 -261.455393) (xy 257.96681 -261.432751) (xy 258.019112 -261.417396)
			(xy 258.073067 -261.409641) (xy 258.100322 -261.40918) (xy 258.129238 -261.409724) (xy 258.18641 -261.418444)
			(xy 258.241609 -261.435694) (xy 258.293572 -261.461081) (xy 258.341106 -261.494022) (xy 258.383122 -261.533761)
			(xy 258.401312 -261.556246) (xy 258.408865 -261.565016) (xy 258.429631 -261.575193) (xy 258.44119 -261.575804)
			(xy 258.521454 -261.575804) (xy 258.533018 -261.575206) (xy 258.55379 -261.565031) (xy 258.561332 -261.556246)
			(xy 258.578085 -261.535463) (xy 258.616439 -261.498333) (xy 258.659593 -261.466911) (xy 258.706707 -261.441812)
			(xy 258.756859 -261.423526) (xy 258.80907 -261.412409) (xy 258.862322 -261.408679) (xy 258.915574 -261.412409)
			(xy 258.967785 -261.423526) (xy 259.017937 -261.441812) (xy 259.065051 -261.466911) (xy 259.108205 -261.498333)
			(xy 259.146559 -261.535463) (xy 259.163312 -261.556246) (xy 259.170865 -261.565016) (xy 259.191631 -261.575193)
			(xy 259.20319 -261.575804) (xy 259.283454 -261.575804) (xy 259.295018 -261.575206) (xy 259.31579 -261.565031)
			(xy 259.323332 -261.556246) (xy 259.340085 -261.535463) (xy 259.378439 -261.498333) (xy 259.421593 -261.466911)
			(xy 259.468707 -261.441812) (xy 259.518859 -261.423526) (xy 259.57107 -261.412409) (xy 259.624322 -261.408679)
			(xy 259.677574 -261.412409) (xy 259.729785 -261.423526) (xy 259.779937 -261.441812) (xy 259.827051 -261.466911)
			(xy 259.870205 -261.498333) (xy 259.908559 -261.535463) (xy 259.925312 -261.556246) (xy 259.932865 -261.565016)
			(xy 259.953631 -261.575193) (xy 259.96519 -261.575804) (xy 260.045454 -261.575804) (xy 260.057018 -261.575206)
			(xy 260.07779 -261.565031) (xy 260.085332 -261.556246) (xy 260.103491 -261.533736) (xy 260.145519 -261.494005)
			(xy 260.193061 -261.461071) (xy 260.245029 -261.435687) (xy 260.300231 -261.418436) (xy 260.357404 -261.409712)
			(xy 260.386322 -261.40918) (xy 260.413571 -261.409692) (xy 260.467515 -261.417451) (xy 260.519805 -261.432807)
			(xy 260.569378 -261.455449) (xy 260.598954 -261.474458) (xy 260.969504 -261.474458) (xy 260.973575 -261.418836)
			(xy 260.985701 -261.364399) (xy 261.005624 -261.312308) (xy 261.03292 -261.263673) (xy 261.067006 -261.21953)
			(xy 261.107155 -261.180821) (xy 261.152513 -261.14837) (xy 261.202113 -261.122869) (xy 261.254897 -261.104862)
			(xy 261.30974 -261.094732) (xy 261.365474 -261.092695) (xy 261.420911 -261.098795) (xy 261.474868 -261.112901)
			(xy 261.526197 -261.134713) (xy 261.573803 -261.163767) (xy 261.616671 -261.199442) (xy 261.653888 -261.240979)
			(xy 261.684661 -261.287492) (xy 261.708333 -261.337989) (xy 261.724401 -261.391396) (xy 261.732521 -261.446572)
			(xy 261.73303 -261.474458) (xy 262.454642 -261.474458) (xy 262.458713 -261.418836) (xy 262.470839 -261.364399)
			(xy 262.490762 -261.312308) (xy 262.518058 -261.263673) (xy 262.552144 -261.21953) (xy 262.592293 -261.180821)
			(xy 262.637651 -261.14837) (xy 262.687251 -261.122869) (xy 262.740035 -261.104862) (xy 262.794878 -261.094732)
			(xy 262.850612 -261.092695) (xy 262.906049 -261.098795) (xy 262.960006 -261.112901) (xy 263.011335 -261.134713)
			(xy 263.058941 -261.163767) (xy 263.101809 -261.199442) (xy 263.139026 -261.240979) (xy 263.169799 -261.287492)
			(xy 263.193471 -261.337989) (xy 263.209539 -261.391396) (xy 263.217659 -261.446572) (xy 263.218168 -261.474458)
			(xy 263.218164 -261.474674) (xy 272.950813 -261.474674) (xy 272.958567 -261.420716) (xy 272.973921 -261.36841)
			(xy 272.996562 -261.318822) (xy 273.026031 -261.272962) (xy 273.061726 -261.231762) (xy 273.102922 -261.196061)
			(xy 273.148778 -261.166586) (xy 273.198363 -261.143938) (xy 273.250667 -261.128577) (xy 273.304624 -261.120816)
			(xy 273.359136 -261.120814) (xy 273.413094 -261.128569) (xy 273.465399 -261.143924) (xy 273.514986 -261.166567)
			(xy 273.560846 -261.196037) (xy 273.602046 -261.231733) (xy 273.637745 -261.27293) (xy 273.667218 -261.318787)
			(xy 273.689865 -261.368373) (xy 273.705225 -261.420677) (xy 273.712984 -261.474634) (xy 273.713448 -261.50189)
			(xy 273.713333 -261.513861) (xy 273.71181 -261.537754) (xy 273.7104 -261.549642) (xy 273.708622 -261.563358)
			(xy 273.71929 -261.588504) (xy 273.812 -261.6581) (xy 273.839178 -261.661148) (xy 273.851624 -261.65556)
			(xy 273.875736 -261.645592) (xy 273.925989 -261.631563) (xy 273.977683 -261.624495) (xy 274.00377 -261.624064)
			(xy 274.031021 -261.624583) (xy 274.084968 -261.632335) (xy 274.137263 -261.647686) (xy 274.186842 -261.670323)
			(xy 274.232693 -261.699785) (xy 274.273886 -261.735473) (xy 274.30958 -261.77666) (xy 274.339049 -261.822507)
			(xy 274.361694 -261.872082) (xy 274.377052 -261.924375) (xy 274.384813 -261.978321) (xy 274.385278 -262.005572)
			(xy 274.384769 -262.033274) (xy 274.376764 -262.088097) (xy 274.360919 -262.141186) (xy 274.337566 -262.191428)
			(xy 274.322794 -262.214868) (xy 274.31619 -262.225028) (xy 274.313396 -262.248904) (xy 274.349972 -262.348218)
			(xy 274.367498 -262.364728) (xy 274.379182 -262.36803) (xy 274.405171 -262.376201) (xy 274.454711 -262.398864)
			(xy 274.500524 -262.428341) (xy 274.541679 -262.464034) (xy 274.57734 -262.505218) (xy 274.606781 -262.551054)
			(xy 274.629404 -262.600612) (xy 274.64475 -262.652883) (xy 274.652505 -262.706805) (xy 274.652994 -262.734044)
			(xy 274.652508 -262.761295) (xy 274.644752 -262.815243) (xy 274.629397 -262.867538) (xy 274.606755 -262.917115)
			(xy 274.577289 -262.962965) (xy 274.541598 -263.004156) (xy 274.500407 -263.039847) (xy 274.454557 -263.069313)
			(xy 274.40498 -263.091955) (xy 274.352685 -263.10731) (xy 274.298737 -263.115066) (xy 274.244235 -263.115066)
			(xy 274.190287 -263.10731) (xy 274.137992 -263.091955) (xy 274.088415 -263.069313) (xy 274.042565 -263.039847)
			(xy 274.001374 -263.004156) (xy 273.965683 -262.962965) (xy 273.936217 -262.917115) (xy 273.913575 -262.867538)
			(xy 273.89822 -262.815243) (xy 273.890464 -262.761295) (xy 273.889978 -262.734044) (xy 273.890486 -262.706342)
			(xy 273.898489 -262.651519) (xy 273.914335 -262.598429) (xy 273.937689 -262.548188) (xy 273.952462 -262.524748)
			(xy 273.959066 -262.514588) (xy 273.96186 -262.490712) (xy 273.925284 -262.391398) (xy 273.907758 -262.374888)
			(xy 273.896074 -262.371586) (xy 273.870071 -262.363455) (xy 273.820526 -262.340793) (xy 273.774708 -262.311313)
			(xy 273.73355 -262.275616) (xy 273.697889 -262.234427) (xy 273.668449 -262.188584) (xy 273.64583 -262.13902)
			(xy 273.630491 -262.086741) (xy 273.622745 -262.032813) (xy 273.622262 -262.005572) (xy 273.622373 -261.993601)
			(xy 273.623899 -261.969708) (xy 273.62531 -261.95782) (xy 273.627088 -261.944104) (xy 273.61642 -261.918958)
			(xy 273.52371 -261.849362) (xy 273.496532 -261.846314) (xy 273.484086 -261.851902) (xy 273.459972 -261.861865)
			(xy 273.40972 -261.875896) (xy 273.358027 -261.882966) (xy 273.33194 -261.883398) (xy 273.304684 -261.882988)
			(xy 273.250725 -261.875235) (xy 273.19842 -261.859883) (xy 273.148831 -261.837242) (xy 273.10297 -261.807775)
			(xy 273.061769 -261.772081) (xy 273.026067 -261.730886) (xy 272.996591 -261.68503) (xy 272.973942 -261.635446)
			(xy 272.958579 -261.583143) (xy 272.950817 -261.529186) (xy 272.950813 -261.474674) (xy 263.218164 -261.474674)
			(xy 263.217659 -261.502344) (xy 263.209539 -261.55752) (xy 263.193471 -261.610927) (xy 263.169799 -261.661424)
			(xy 263.139026 -261.707937) (xy 263.101809 -261.749474) (xy 263.058941 -261.785149) (xy 263.011335 -261.814203)
			(xy 262.960006 -261.836015) (xy 262.906049 -261.850121) (xy 262.850612 -261.856221) (xy 262.794878 -261.854184)
			(xy 262.740035 -261.844054) (xy 262.687251 -261.826047) (xy 262.637651 -261.800546) (xy 262.592293 -261.768095)
			(xy 262.552144 -261.729386) (xy 262.518058 -261.685243) (xy 262.490762 -261.636608) (xy 262.470839 -261.584517)
			(xy 262.458713 -261.53008) (xy 262.454642 -261.474458) (xy 261.73303 -261.474458) (xy 261.732521 -261.502344)
			(xy 261.724401 -261.55752) (xy 261.708333 -261.610927) (xy 261.684661 -261.661424) (xy 261.653888 -261.707937)
			(xy 261.616671 -261.749474) (xy 261.573803 -261.785149) (xy 261.526197 -261.814203) (xy 261.474868 -261.836015)
			(xy 261.420911 -261.850121) (xy 261.365474 -261.856221) (xy 261.30974 -261.854184) (xy 261.254897 -261.844054)
			(xy 261.202113 -261.826047) (xy 261.152513 -261.800546) (xy 261.107155 -261.768095) (xy 261.067006 -261.729386)
			(xy 261.03292 -261.685243) (xy 261.005624 -261.636608) (xy 260.985701 -261.584517) (xy 260.973575 -261.53008)
			(xy 260.969504 -261.474458) (xy 260.598954 -261.474458) (xy 260.615224 -261.484915) (xy 260.656411 -261.520605)
			(xy 260.692099 -261.561793) (xy 260.721562 -261.607641) (xy 260.744201 -261.657215) (xy 260.759554 -261.709507)
			(xy 260.76731 -261.763451) (xy 260.76731 -261.817949) (xy 260.759554 -261.871893) (xy 260.744201 -261.924185)
			(xy 260.721562 -261.973759) (xy 260.692099 -262.019607) (xy 260.656411 -262.060795) (xy 260.615224 -262.096485)
			(xy 260.569378 -262.125951) (xy 260.519805 -262.148593) (xy 260.467515 -262.163949) (xy 260.413571 -262.171708)
			(xy 260.386322 -262.172196) (xy 260.357406 -262.171663) (xy 260.300235 -262.162937) (xy 260.245036 -262.145682)
			(xy 260.193075 -262.120294) (xy 260.14554 -262.087353) (xy 260.103523 -262.047614) (xy 260.085332 -262.02513)
			(xy 260.077764 -262.016375) (xy 260.057009 -262.006191) (xy 260.045454 -262.005572) (xy 259.96519 -262.005572)
			(xy 259.953617 -262.006112) (xy 259.932845 -262.016325) (xy 259.925312 -262.02513) (xy 259.908559 -262.045913)
			(xy 259.870205 -262.083043) (xy 259.827051 -262.114465) (xy 259.779937 -262.139564) (xy 259.729785 -262.15785)
			(xy 259.677574 -262.168967) (xy 259.624322 -262.172697) (xy 259.57107 -262.168967) (xy 259.518859 -262.15785)
			(xy 259.468707 -262.139564) (xy 259.421593 -262.114465) (xy 259.378439 -262.083043) (xy 259.340085 -262.045913)
			(xy 259.323332 -262.02513) (xy 259.315764 -262.016375) (xy 259.295009 -262.006191) (xy 259.283454 -262.005572)
			(xy 259.20319 -262.005572) (xy 259.191617 -262.006112) (xy 259.170845 -262.016325) (xy 259.163312 -262.02513)
			(xy 259.146559 -262.045913) (xy 259.108205 -262.083043) (xy 259.065051 -262.114465) (xy 259.017937 -262.139564)
			(xy 258.967785 -262.15785) (xy 258.915574 -262.168967) (xy 258.862322 -262.172697) (xy 258.80907 -262.168967)
			(xy 258.756859 -262.15785) (xy 258.706707 -262.139564) (xy 258.659593 -262.114465) (xy 258.616439 -262.083043)
			(xy 258.578085 -262.045913) (xy 258.561332 -262.02513) (xy 258.553764 -262.016375) (xy 258.533009 -262.006191)
			(xy 258.521454 -262.005572) (xy 258.44119 -262.005572) (xy 258.429617 -262.006112) (xy 258.408845 -262.016325)
			(xy 258.401312 -262.02513) (xy 258.383122 -262.047614) (xy 258.341101 -262.087348) (xy 258.293566 -262.120286)
			(xy 258.241604 -262.145674) (xy 258.186407 -262.16293) (xy 258.129238 -262.17166) (xy 258.100322 -262.172196)
			(xy 258.073067 -262.171759) (xy 258.019112 -262.164004) (xy 257.96681 -262.148649) (xy 257.917225 -262.126007)
			(xy 257.871368 -262.096539) (xy 257.830171 -262.060844) (xy 257.794474 -262.01965) (xy 257.765003 -261.973794)
			(xy 257.742358 -261.924211) (xy 257.727001 -261.871909) (xy 257.719243 -261.817955) (xy 233.66857 -261.817955)
			(xy 233.66857 -262.912352) (xy 257.3688 -262.912352) (xy 257.372871 -262.85673) (xy 257.384997 -262.802293)
			(xy 257.40492 -262.750202) (xy 257.432216 -262.701567) (xy 257.466302 -262.657424) (xy 257.506451 -262.618715)
			(xy 257.551809 -262.586264) (xy 257.601409 -262.560763) (xy 257.654193 -262.542756) (xy 257.709036 -262.532626)
			(xy 257.76477 -262.530589) (xy 257.820207 -262.536689) (xy 257.874164 -262.550795) (xy 257.925493 -262.572607)
			(xy 257.973099 -262.601661) (xy 258.015967 -262.637336) (xy 258.053184 -262.678873) (xy 258.083957 -262.725386)
			(xy 258.107629 -262.775883) (xy 258.123697 -262.82929) (xy 258.131817 -262.884466) (xy 258.132326 -262.912352)
			(xy 258.132205 -262.918956) (xy 259.356858 -262.918956) (xy 259.360929 -262.863334) (xy 259.373055 -262.808897)
			(xy 259.392978 -262.756806) (xy 259.420274 -262.708171) (xy 259.45436 -262.664028) (xy 259.494509 -262.625319)
			(xy 259.539867 -262.592868) (xy 259.589467 -262.567367) (xy 259.642251 -262.54936) (xy 259.697094 -262.53923)
			(xy 259.752828 -262.537193) (xy 259.808265 -262.543293) (xy 259.862222 -262.557399) (xy 259.913551 -262.579211)
			(xy 259.961157 -262.608265) (xy 260.004025 -262.64394) (xy 260.041242 -262.685477) (xy 260.072015 -262.73199)
			(xy 260.095687 -262.782487) (xy 260.111755 -262.835894) (xy 260.119875 -262.89107) (xy 260.120384 -262.918956)
			(xy 260.119875 -262.946842) (xy 260.111755 -263.002018) (xy 260.107925 -263.014747) (xy 264.681514 -263.014747)
			(xy 264.681514 -262.960253) (xy 264.689269 -262.906314) (xy 264.704621 -262.854027) (xy 264.727257 -262.804457)
			(xy 264.756717 -262.758613) (xy 264.792401 -262.717428) (xy 264.833583 -262.68174) (xy 264.879424 -262.652275)
			(xy 264.928991 -262.629634) (xy 264.981277 -262.614277) (xy 265.035215 -262.606517) (xy 265.062462 -262.606028)
			(xy 265.093475 -262.606629) (xy 265.154687 -262.616652) (xy 265.213472 -262.636442) (xy 265.268284 -262.665477)
			(xy 265.293348 -262.683752) (xy 265.304384 -262.691639) (xy 265.329499 -262.701857) (xy 265.35642 -262.705089)
			(xy 265.38324 -262.701108) (xy 265.40806 -262.690194) (xy 265.429124 -262.673122) (xy 265.44494 -262.651098)
			(xy 265.450066 -262.63854) (xy 265.460733 -262.611673) (xy 265.48898 -262.56124) (xy 265.524513 -262.515646)
			(xy 265.566518 -262.475936) (xy 265.614034 -262.443018) (xy 265.665973 -262.417646) (xy 265.721145 -262.400401)
			(xy 265.778288 -262.391678) (xy 265.80719 -262.391144) (xy 265.83444 -262.391703) (xy 265.888385 -262.399457)
			(xy 265.940678 -262.414811) (xy 265.990253 -262.43745) (xy 266.036101 -262.466914) (xy 266.07729 -262.502603)
			(xy 266.11298 -262.543791) (xy 266.142446 -262.589638) (xy 266.165086 -262.639213) (xy 266.18044 -262.691505)
			(xy 266.188197 -262.74545) (xy 266.188197 -262.79995) (xy 266.18044 -262.853895) (xy 266.165086 -262.906187)
			(xy 266.142446 -262.955762) (xy 266.11298 -263.001609) (xy 266.07729 -263.042797) (xy 266.036101 -263.078486)
			(xy 265.990253 -263.10795) (xy 265.940678 -263.130589) (xy 265.888385 -263.145943) (xy 265.83444 -263.153697)
			(xy 265.80719 -263.15416) (xy 265.776175 -263.153587) (xy 265.714963 -263.143555) (xy 265.656177 -263.123758)
			(xy 265.601367 -263.094715) (xy 265.576304 -263.076436) (xy 265.565304 -263.068497) (xy 265.540178 -263.058286)
			(xy 265.513248 -263.055062) (xy 265.486422 -263.059052) (xy 265.461597 -263.069974) (xy 265.44053 -263.087055)
			(xy 265.424713 -263.109086) (xy 265.419586 -263.121648) (xy 265.408953 -263.14853) (xy 265.380703 -263.198965)
			(xy 265.345166 -263.24456) (xy 265.303156 -263.28427) (xy 265.255634 -263.317187) (xy 265.20369 -263.342556)
			(xy 265.148513 -263.359796) (xy 265.091366 -263.368513) (xy 265.062462 -263.369044) (xy 265.035215 -263.368483)
			(xy 264.981277 -263.360723) (xy 264.928991 -263.345366) (xy 264.879424 -263.322725) (xy 264.833583 -263.29326)
			(xy 264.792401 -263.257572) (xy 264.756717 -263.216387) (xy 264.727257 -263.170543) (xy 264.704621 -263.120973)
			(xy 264.689269 -263.068686) (xy 264.681514 -263.014747) (xy 260.107925 -263.014747) (xy 260.095687 -263.055425)
			(xy 260.072015 -263.105922) (xy 260.041242 -263.152435) (xy 260.004025 -263.193972) (xy 259.961157 -263.229647)
			(xy 259.913551 -263.258701) (xy 259.862222 -263.280513) (xy 259.808265 -263.294619) (xy 259.752828 -263.300719)
			(xy 259.697094 -263.298682) (xy 259.642251 -263.288552) (xy 259.589467 -263.270545) (xy 259.539867 -263.245044)
			(xy 259.494509 -263.212593) (xy 259.45436 -263.173884) (xy 259.420274 -263.129741) (xy 259.392978 -263.081106)
			(xy 259.373055 -263.029015) (xy 259.360929 -262.974578) (xy 259.356858 -262.918956) (xy 258.132205 -262.918956)
			(xy 258.131817 -262.940238) (xy 258.123697 -262.995414) (xy 258.107629 -263.048821) (xy 258.083957 -263.099318)
			(xy 258.053184 -263.145831) (xy 258.015967 -263.187368) (xy 257.973099 -263.223043) (xy 257.925493 -263.252097)
			(xy 257.874164 -263.273909) (xy 257.820207 -263.288015) (xy 257.76477 -263.294115) (xy 257.709036 -263.292078)
			(xy 257.654193 -263.281948) (xy 257.601409 -263.263941) (xy 257.551809 -263.23844) (xy 257.506451 -263.205989)
			(xy 257.466302 -263.16728) (xy 257.432216 -263.123137) (xy 257.40492 -263.074502) (xy 257.384997 -263.022411)
			(xy 257.372871 -262.967974) (xy 257.3688 -262.912352) (xy 233.66857 -262.912352) (xy 233.66857 -263.37768)
			(xy 270.148048 -263.37768) (xy 270.152119 -263.322058) (xy 270.164245 -263.267621) (xy 270.184168 -263.21553)
			(xy 270.211464 -263.166895) (xy 270.24555 -263.122752) (xy 270.285699 -263.084043) (xy 270.331057 -263.051592)
			(xy 270.380657 -263.026091) (xy 270.433441 -263.008084) (xy 270.488284 -262.997954) (xy 270.544018 -262.995917)
			(xy 270.599455 -263.002017) (xy 270.653412 -263.016123) (xy 270.704741 -263.037935) (xy 270.752347 -263.066989)
			(xy 270.795215 -263.102664) (xy 270.832432 -263.144201) (xy 270.863205 -263.190714) (xy 270.886877 -263.241211)
			(xy 270.902945 -263.294618) (xy 270.911065 -263.349794) (xy 270.911574 -263.37768) (xy 270.911065 -263.405566)
			(xy 270.902945 -263.460742) (xy 270.886877 -263.514149) (xy 270.863205 -263.564646) (xy 270.832432 -263.611159)
			(xy 270.822238 -263.622536) (xy 273.729194 -263.622536) (xy 273.733265 -263.566914) (xy 273.745391 -263.512477)
			(xy 273.765314 -263.460386) (xy 273.79261 -263.411751) (xy 273.826696 -263.367608) (xy 273.866845 -263.328899)
			(xy 273.912203 -263.296448) (xy 273.961803 -263.270947) (xy 274.014587 -263.25294) (xy 274.06943 -263.24281)
			(xy 274.125164 -263.240773) (xy 274.180601 -263.246873) (xy 274.234558 -263.260979) (xy 274.285887 -263.282791)
			(xy 274.333493 -263.311845) (xy 274.376361 -263.34752) (xy 274.413578 -263.389057) (xy 274.444351 -263.43557)
			(xy 274.468023 -263.486067) (xy 274.484091 -263.539474) (xy 274.492211 -263.59465) (xy 274.49272 -263.622536)
			(xy 274.492211 -263.650422) (xy 274.484091 -263.705598) (xy 274.468023 -263.759005) (xy 274.444351 -263.809502)
			(xy 274.413578 -263.856015) (xy 274.376361 -263.897552) (xy 274.333493 -263.933227) (xy 274.285887 -263.962281)
			(xy 274.234558 -263.984093) (xy 274.180601 -263.998199) (xy 274.125164 -264.004299) (xy 274.06943 -264.002262)
			(xy 274.014587 -263.992132) (xy 273.961803 -263.974125) (xy 273.912203 -263.948624) (xy 273.866845 -263.916173)
			(xy 273.826696 -263.877464) (xy 273.79261 -263.833321) (xy 273.765314 -263.784686) (xy 273.745391 -263.732595)
			(xy 273.733265 -263.678158) (xy 273.729194 -263.622536) (xy 270.822238 -263.622536) (xy 270.795215 -263.652696)
			(xy 270.752347 -263.688371) (xy 270.704741 -263.717425) (xy 270.653412 -263.739237) (xy 270.599455 -263.753343)
			(xy 270.544018 -263.759443) (xy 270.488284 -263.757406) (xy 270.433441 -263.747276) (xy 270.380657 -263.729269)
			(xy 270.331057 -263.703768) (xy 270.285699 -263.671317) (xy 270.24555 -263.632608) (xy 270.211464 -263.588465)
			(xy 270.184168 -263.53983) (xy 270.164245 -263.487739) (xy 270.152119 -263.433302) (xy 270.148048 -263.37768)
			(xy 233.66857 -263.37768) (xy 233.66857 -264.250424) (xy 268.14983 -264.250424) (xy 268.153901 -264.194802)
			(xy 268.166027 -264.140365) (xy 268.18595 -264.088274) (xy 268.213246 -264.039639) (xy 268.247332 -263.995496)
			(xy 268.287481 -263.956787) (xy 268.332839 -263.924336) (xy 268.382439 -263.898835) (xy 268.435223 -263.880828)
			(xy 268.490066 -263.870698) (xy 268.5458 -263.868661) (xy 268.601237 -263.874761) (xy 268.655194 -263.888867)
			(xy 268.706523 -263.910679) (xy 268.754129 -263.939733) (xy 268.796997 -263.975408) (xy 268.834214 -264.016945)
			(xy 268.864987 -264.063458) (xy 268.888659 -264.113955) (xy 268.904727 -264.167362) (xy 268.912847 -264.222538)
			(xy 268.913356 -264.250424) (xy 268.912847 -264.27831) (xy 268.909064 -264.304018) (xy 270.618964 -264.304018)
			(xy 270.623035 -264.248396) (xy 270.635161 -264.193959) (xy 270.655084 -264.141868) (xy 270.68238 -264.093233)
			(xy 270.716466 -264.04909) (xy 270.756615 -264.010381) (xy 270.801973 -263.97793) (xy 270.851573 -263.952429)
			(xy 270.904357 -263.934422) (xy 270.9592 -263.924292) (xy 271.014934 -263.922255) (xy 271.070371 -263.928355)
			(xy 271.124328 -263.942461) (xy 271.175657 -263.964273) (xy 271.223263 -263.993327) (xy 271.266131 -264.029002)
			(xy 271.303348 -264.070539) (xy 271.334121 -264.117052) (xy 271.357793 -264.167549) (xy 271.373861 -264.220956)
			(xy 271.381981 -264.276132) (xy 271.38249 -264.304018) (xy 271.381981 -264.331904) (xy 271.373861 -264.38708)
			(xy 271.357793 -264.440487) (xy 271.334121 -264.490984) (xy 271.329262 -264.498328) (xy 273.06854 -264.498328)
			(xy 273.072611 -264.442706) (xy 273.084737 -264.388269) (xy 273.10466 -264.336178) (xy 273.131956 -264.287543)
			(xy 273.166042 -264.2434) (xy 273.206191 -264.204691) (xy 273.251549 -264.17224) (xy 273.301149 -264.146739)
			(xy 273.353933 -264.128732) (xy 273.408776 -264.118602) (xy 273.46451 -264.116565) (xy 273.519947 -264.122665)
			(xy 273.573904 -264.136771) (xy 273.625233 -264.158583) (xy 273.672839 -264.187637) (xy 273.715707 -264.223312)
			(xy 273.752924 -264.264849) (xy 273.783697 -264.311362) (xy 273.807369 -264.361859) (xy 273.823437 -264.415266)
			(xy 273.831557 -264.470442) (xy 273.832066 -264.498328) (xy 273.831557 -264.526214) (xy 273.823437 -264.58139)
			(xy 273.807369 -264.634797) (xy 273.783697 -264.685294) (xy 273.752924 -264.731807) (xy 273.715707 -264.773344)
			(xy 273.672839 -264.809019) (xy 273.625233 -264.838073) (xy 273.573904 -264.859885) (xy 273.519947 -264.873991)
			(xy 273.46451 -264.880091) (xy 273.408776 -264.878054) (xy 273.353933 -264.867924) (xy 273.301149 -264.849917)
			(xy 273.251549 -264.824416) (xy 273.206191 -264.791965) (xy 273.166042 -264.753256) (xy 273.131956 -264.709113)
			(xy 273.10466 -264.660478) (xy 273.084737 -264.608387) (xy 273.072611 -264.55395) (xy 273.06854 -264.498328)
			(xy 271.329262 -264.498328) (xy 271.303348 -264.537497) (xy 271.266131 -264.579034) (xy 271.223263 -264.614709)
			(xy 271.175657 -264.643763) (xy 271.124328 -264.665575) (xy 271.070371 -264.679681) (xy 271.014934 -264.685781)
			(xy 270.9592 -264.683744) (xy 270.904357 -264.673614) (xy 270.851573 -264.655607) (xy 270.801973 -264.630106)
			(xy 270.756615 -264.597655) (xy 270.716466 -264.558946) (xy 270.68238 -264.514803) (xy 270.655084 -264.466168)
			(xy 270.635161 -264.414077) (xy 270.623035 -264.35964) (xy 270.618964 -264.304018) (xy 268.909064 -264.304018)
			(xy 268.904727 -264.333486) (xy 268.888659 -264.386893) (xy 268.864987 -264.43739) (xy 268.834214 -264.483903)
			(xy 268.796997 -264.52544) (xy 268.754129 -264.561115) (xy 268.706523 -264.590169) (xy 268.655194 -264.611981)
			(xy 268.601237 -264.626087) (xy 268.5458 -264.632187) (xy 268.490066 -264.63015) (xy 268.435223 -264.62002)
			(xy 268.382439 -264.602013) (xy 268.332839 -264.576512) (xy 268.287481 -264.544061) (xy 268.247332 -264.505352)
			(xy 268.213246 -264.461209) (xy 268.18595 -264.412574) (xy 268.166027 -264.360483) (xy 268.153901 -264.306046)
			(xy 268.14983 -264.250424) (xy 233.66857 -264.250424) (xy 233.66857 -264.36066) (xy 233.669072 -264.370712)
			(xy 233.676788 -264.389279) (xy 233.683556 -264.396728) (xy 233.738674 -264.451846) (xy 233.761583 -264.475424)
			(xy 233.802555 -264.526839) (xy 233.837513 -264.582517) (xy 233.86602 -264.641758) (xy 233.887716 -264.703818)
			(xy 233.902329 -264.767917) (xy 233.909675 -264.833248) (xy 233.910124 -264.86612) (xy 233.910124 -265.067288)
			(xy 233.9097 -265.098952) (xy 233.902872 -265.161911) (xy 233.889296 -265.223767) (xy 233.869129 -265.283799)
			(xy 233.842607 -265.341306) (xy 233.810039 -265.395618) (xy 233.791252 -265.42111) (xy 233.785028 -265.430252)
			(xy 233.780312 -265.451836) (xy 233.785058 -265.473412) (xy 233.791252 -265.482578) (xy 233.801917 -265.497056)
			(xy 273.915122 -265.497056) (xy 273.919193 -265.441434) (xy 273.931319 -265.386997) (xy 273.951242 -265.334906)
			(xy 273.978538 -265.286271) (xy 274.012624 -265.242128) (xy 274.052773 -265.203419) (xy 274.098131 -265.170968)
			(xy 274.147731 -265.145467) (xy 274.200515 -265.12746) (xy 274.255358 -265.11733) (xy 274.311092 -265.115293)
			(xy 274.366529 -265.121393) (xy 274.420486 -265.135499) (xy 274.471815 -265.157311) (xy 274.519421 -265.186365)
			(xy 274.562289 -265.22204) (xy 274.599506 -265.263577) (xy 274.630279 -265.31009) (xy 274.653951 -265.360587)
			(xy 274.670019 -265.413994) (xy 274.678139 -265.46917) (xy 274.678648 -265.497056) (xy 274.678139 -265.524942)
			(xy 274.670019 -265.580118) (xy 274.653951 -265.633525) (xy 274.630279 -265.684022) (xy 274.599506 -265.730535)
			(xy 274.562289 -265.772072) (xy 274.519421 -265.807747) (xy 274.471815 -265.836801) (xy 274.420486 -265.858613)
			(xy 274.366529 -265.872719) (xy 274.311092 -265.878819) (xy 274.255358 -265.876782) (xy 274.200515 -265.866652)
			(xy 274.147731 -265.848645) (xy 274.098131 -265.823144) (xy 274.052773 -265.790693) (xy 274.012624 -265.751984)
			(xy 273.978538 -265.707841) (xy 273.951242 -265.659206) (xy 273.931319 -265.607115) (xy 273.919193 -265.552678)
			(xy 273.915122 -265.497056) (xy 233.801917 -265.497056) (xy 233.810034 -265.508074) (xy 233.842608 -265.562384)
			(xy 233.869136 -265.619889) (xy 233.889307 -265.67992) (xy 233.902887 -265.741776) (xy 233.909717 -265.804735)
			(xy 233.910124 -265.8364) (xy 233.910124 -266.012422) (xy 273.142454 -266.012422) (xy 273.146525 -265.9568)
			(xy 273.158651 -265.902363) (xy 273.178574 -265.850272) (xy 273.20587 -265.801637) (xy 273.239956 -265.757494)
			(xy 273.280105 -265.718785) (xy 273.325463 -265.686334) (xy 273.375063 -265.660833) (xy 273.427847 -265.642826)
			(xy 273.48269 -265.632696) (xy 273.538424 -265.630659) (xy 273.593861 -265.636759) (xy 273.647818 -265.650865)
			(xy 273.699147 -265.672677) (xy 273.746753 -265.701731) (xy 273.789621 -265.737406) (xy 273.826838 -265.778943)
			(xy 273.857611 -265.825456) (xy 273.881283 -265.875953) (xy 273.897351 -265.92936) (xy 273.905471 -265.984536)
			(xy 273.90598 -266.012422) (xy 273.905471 -266.040308) (xy 273.897351 -266.095484) (xy 273.881283 -266.148891)
			(xy 273.857611 -266.199388) (xy 273.826838 -266.245901) (xy 273.789621 -266.287438) (xy 273.746753 -266.323113)
			(xy 273.699147 -266.352167) (xy 273.647818 -266.373979) (xy 273.593861 -266.388085) (xy 273.538424 -266.394185)
			(xy 273.48269 -266.392148) (xy 273.427847 -266.382018) (xy 273.375063 -266.364011) (xy 273.325463 -266.33851)
			(xy 273.280105 -266.306059) (xy 273.239956 -266.26735) (xy 273.20587 -266.223207) (xy 273.178574 -266.174572)
			(xy 273.158651 -266.122481) (xy 273.146525 -266.068044) (xy 273.142454 -266.012422) (xy 233.910124 -266.012422)
			(xy 233.910124 -266.037568) (xy 233.909701 -266.069233) (xy 233.902876 -266.132193) (xy 233.889301 -266.19405)
			(xy 233.869136 -266.254083) (xy 233.842615 -266.311591) (xy 233.810048 -266.365904) (xy 233.791252 -266.39139)
			(xy 233.785024 -266.400532) (xy 233.7803 -266.422119) (xy 233.78504 -266.443703) (xy 233.791252 -266.452858)
			(xy 233.81003 -266.478355) (xy 233.842597 -266.532666) (xy 233.869117 -266.590172) (xy 233.88928 -266.650203)
			(xy 233.902851 -266.712058) (xy 233.909673 -266.775017) (xy 233.910124 -266.80668) (xy 233.910124 -267.007848)
			(xy 233.909697 -267.039511) (xy 233.902863 -267.102468) (xy 233.889282 -267.16432) (xy 233.86911 -267.224348)
			(xy 233.842583 -267.281851) (xy 233.810011 -267.336158) (xy 233.791252 -267.36167) (xy 233.78502 -267.370813)
			(xy 233.780288 -267.392403) (xy 233.785022 -267.413993) (xy 233.791252 -267.423138) (xy 233.810031 -267.448635)
			(xy 233.8426 -267.502945) (xy 233.869122 -267.560451) (xy 233.889287 -267.620482) (xy 233.90286 -267.682338)
			(xy 233.909684 -267.745296) (xy 233.910124 -267.77696) (xy 233.910124 -267.978128) (xy 233.909698 -268.009791)
			(xy 233.902866 -268.072749) (xy 233.889286 -268.134603) (xy 233.869116 -268.194632) (xy 233.842591 -268.252136)
			(xy 233.81002 -268.306445) (xy 233.791252 -268.33195) (xy 233.785015 -268.341093) (xy 233.780276 -268.362687)
			(xy 233.785004 -268.384284) (xy 233.791252 -268.393418) (xy 233.810032 -268.418915) (xy 233.842603 -268.473225)
			(xy 233.869127 -268.530731) (xy 233.889294 -268.590761) (xy 233.902869 -268.652617) (xy 233.909695 -268.715576)
			(xy 233.910124 -268.74724) (xy 233.910124 -268.948408) (xy 233.909696 -268.981282) (xy 233.902363 -269.046619)
			(xy 233.887758 -269.110723) (xy 233.866064 -269.172788) (xy 233.837553 -269.232032) (xy 233.802586 -269.28771)
			(xy 233.761602 -269.33912) (xy 233.738674 -269.362682) (xy 233.68635 -269.415006) (xy 233.679499 -269.422402)
			(xy 233.671759 -269.441001) (xy 233.671364 -269.451074) (xy 233.671364 -270.89989) (xy 257.098807 -270.89989)
			(xy 257.102813 -270.704835) (xy 257.114823 -270.510109) (xy 257.134818 -270.31604) (xy 257.162763 -270.122956)
			(xy 257.198612 -269.931181) (xy 257.242304 -269.741041) (xy 257.293765 -269.552854) (xy 257.352909 -269.366939)
			(xy 257.419636 -269.183608) (xy 257.493833 -269.003172) (xy 257.575375 -268.825934) (xy 257.664126 -268.652193)
			(xy 257.759934 -268.482242) (xy 257.862639 -268.316368) (xy 257.972067 -268.15485) (xy 258.088034 -267.997961)
			(xy 258.210345 -267.845966) (xy 258.338792 -267.69912) (xy 258.47316 -267.557671) (xy 258.613222 -267.421858)
			(xy 258.758741 -267.291909) (xy 258.909473 -267.168045) (xy 259.065163 -267.050473) (xy 259.225549 -266.939393)
			(xy 259.39036 -266.83499) (xy 259.559318 -266.737442) (xy 259.732139 -266.646913) (xy 259.908531 -266.563555)
			(xy 260.088196 -266.487509) (xy 260.270831 -266.418904) (xy 260.45613 -266.357854) (xy 260.643778 -266.304464)
			(xy 260.83346 -266.258822) (xy 261.024857 -266.221006) (xy 261.217644 -266.19108) (xy 261.411497 -266.169094)
			(xy 261.60609 -266.155085) (xy 261.801093 -266.149077) (xy 261.996179 -266.15108) (xy 262.191018 -266.161091)
			(xy 262.385282 -266.179092) (xy 262.578643 -266.205054) (xy 262.770776 -266.238932) (xy 262.961355 -266.280669)
			(xy 263.15006 -266.330196) (xy 263.336573 -266.387428) (xy 263.520579 -266.452269) (xy 263.701767 -266.52461)
			(xy 263.879833 -266.604328) (xy 264.054476 -266.69129) (xy 264.225402 -266.785349) (xy 264.286264 -266.822174)
			(xy 268.90218 -266.822174) (xy 268.902666 -266.794923) (xy 268.910422 -266.740975) (xy 268.925777 -266.68868)
			(xy 268.948419 -266.639103) (xy 268.977885 -266.593253) (xy 269.013576 -266.552062) (xy 269.054767 -266.516371)
			(xy 269.100617 -266.486905) (xy 269.150194 -266.464263) (xy 269.202489 -266.448908) (xy 269.256437 -266.441152)
			(xy 269.310939 -266.441152) (xy 269.364887 -266.448908) (xy 269.417182 -266.464263) (xy 269.466759 -266.486905)
			(xy 269.512609 -266.516371) (xy 269.5538 -266.552062) (xy 269.589491 -266.593253) (xy 269.618957 -266.639103)
			(xy 269.641599 -266.68868) (xy 269.656954 -266.740975) (xy 269.66471 -266.794923) (xy 269.665196 -266.822174)
			(xy 269.664723 -266.849884) (xy 269.65669 -266.90472) (xy 269.640803 -266.957815) (xy 269.638202 -266.963398)
			(xy 270.855946 -266.963398) (xy 270.860017 -266.907776) (xy 270.872143 -266.853339) (xy 270.892066 -266.801248)
			(xy 270.919362 -266.752613) (xy 270.953448 -266.70847) (xy 270.993597 -266.669761) (xy 271.038955 -266.63731)
			(xy 271.088555 -266.611809) (xy 271.141339 -266.593802) (xy 271.196182 -266.583672) (xy 271.251916 -266.581635)
			(xy 271.307353 -266.587735) (xy 271.36131 -266.601841) (xy 271.412639 -266.623653) (xy 271.460245 -266.652707)
			(xy 271.503113 -266.688382) (xy 271.54033 -266.729919) (xy 271.571103 -266.776432) (xy 271.594775 -266.826929)
			(xy 271.595026 -266.827762) (xy 271.740374 -266.827762) (xy 271.744445 -266.77214) (xy 271.756571 -266.717703)
			(xy 271.776494 -266.665612) (xy 271.80379 -266.616977) (xy 271.837876 -266.572834) (xy 271.878025 -266.534125)
			(xy 271.923383 -266.501674) (xy 271.972983 -266.476173) (xy 272.025767 -266.458166) (xy 272.08061 -266.448036)
			(xy 272.136344 -266.445999) (xy 272.191781 -266.452099) (xy 272.245738 -266.466205) (xy 272.297067 -266.488017)
			(xy 272.344673 -266.517071) (xy 272.387541 -266.552746) (xy 272.424758 -266.594283) (xy 272.455531 -266.640796)
			(xy 272.479203 -266.691293) (xy 272.495271 -266.7447) (xy 272.503391 -266.799876) (xy 272.5039 -266.827762)
			(xy 272.503391 -266.855648) (xy 272.495271 -266.910824) (xy 272.479203 -266.964231) (xy 272.455531 -267.014728)
			(xy 272.424758 -267.061241) (xy 272.387541 -267.102778) (xy 272.344673 -267.138453) (xy 272.297067 -267.167507)
			(xy 272.245738 -267.189319) (xy 272.191781 -267.203425) (xy 272.136344 -267.209525) (xy 272.08061 -267.207488)
			(xy 272.025767 -267.197358) (xy 271.972983 -267.179351) (xy 271.923383 -267.15385) (xy 271.878025 -267.121399)
			(xy 271.837876 -267.08269) (xy 271.80379 -267.038547) (xy 271.776494 -266.989912) (xy 271.756571 -266.937821)
			(xy 271.744445 -266.883384) (xy 271.740374 -266.827762) (xy 271.595026 -266.827762) (xy 271.610843 -266.880336)
			(xy 271.618963 -266.935512) (xy 271.619472 -266.963398) (xy 271.618963 -266.991284) (xy 271.610843 -267.04646)
			(xy 271.594775 -267.099867) (xy 271.571103 -267.150364) (xy 271.54033 -267.196877) (xy 271.503113 -267.238414)
			(xy 271.460245 -267.274089) (xy 271.412639 -267.303143) (xy 271.36131 -267.324955) (xy 271.307353 -267.339061)
			(xy 271.251916 -267.345161) (xy 271.196182 -267.343124) (xy 271.141339 -267.332994) (xy 271.088555 -267.314987)
			(xy 271.038955 -267.289486) (xy 270.993597 -267.257035) (xy 270.953448 -267.218326) (xy 270.919362 -267.174183)
			(xy 270.892066 -267.125548) (xy 270.872143 -267.073457) (xy 270.860017 -267.01902) (xy 270.855946 -266.963398)
			(xy 269.638202 -266.963398) (xy 269.617398 -267.008051) (xy 269.586966 -267.054369) (xy 269.56893 -267.075412)
			(xy 269.560331 -267.085734) (xy 269.548359 -267.109773) (xy 269.543065 -267.136103) (xy 269.544816 -267.162901)
			(xy 269.55349 -267.188318) (xy 269.568488 -267.210596) (xy 269.588773 -267.228196) (xy 269.60068 -267.234416)
			(xy 269.624563 -267.246491) (xy 269.669059 -267.276219) (xy 269.708964 -267.311875) (xy 269.743492 -267.352759)
			(xy 269.771965 -267.398068) (xy 269.793826 -267.446913) (xy 269.808643 -267.498334) (xy 269.816127 -267.551321)
			(xy 269.81658 -267.578078) (xy 269.816094 -267.605329) (xy 269.808338 -267.659277) (xy 269.792983 -267.711572)
			(xy 269.770341 -267.761149) (xy 269.740875 -267.806999) (xy 269.705184 -267.84819) (xy 269.663993 -267.883881)
			(xy 269.618143 -267.913347) (xy 269.568566 -267.935989) (xy 269.516271 -267.951344) (xy 269.462323 -267.9591)
			(xy 269.407821 -267.9591) (xy 269.353873 -267.951344) (xy 269.301578 -267.935989) (xy 269.252001 -267.913347)
			(xy 269.206151 -267.883881) (xy 269.16496 -267.84819) (xy 269.129269 -267.806999) (xy 269.099803 -267.761149)
			(xy 269.077161 -267.711572) (xy 269.061806 -267.659277) (xy 269.05405 -267.605329) (xy 269.053564 -267.578078)
			(xy 269.054078 -267.550369) (xy 269.062103 -267.495536) (xy 269.07798 -267.442442) (xy 269.101377 -267.392205)
			(xy 269.131798 -267.345885) (xy 269.14983 -267.32484) (xy 269.158498 -267.31457) (xy 269.170472 -267.290516)
			(xy 269.175762 -267.264173) (xy 269.174003 -267.237361) (xy 269.165315 -267.211935) (xy 269.150301 -267.189652)
			(xy 269.129997 -267.172053) (xy 269.11808 -267.165836) (xy 269.094169 -267.153815) (xy 269.049672 -267.124079)
			(xy 269.00977 -267.088414) (xy 268.975245 -267.047522) (xy 268.946775 -267.002205) (xy 268.924919 -266.953353)
			(xy 268.910107 -266.901926) (xy 268.90263 -266.848933) (xy 268.90218 -266.822174) (xy 264.286264 -266.822174)
			(xy 264.392321 -266.886345) (xy 264.554954 -266.99411) (xy 264.713025 -267.10846) (xy 264.866268 -267.229203)
			(xy 265.014425 -267.356137) (xy 265.157246 -267.489045) (xy 265.29449 -267.627705) (xy 265.425926 -267.771883)
			(xy 265.551331 -267.921336) (xy 265.670495 -268.07581) (xy 265.783216 -268.235047) (xy 265.889305 -268.398778)
			(xy 265.988583 -268.566725) (xy 266.080881 -268.738608) (xy 266.094491 -268.766658) (xy 271.815721 -268.766658)
			(xy 271.815721 -268.712146) (xy 271.823479 -268.658189) (xy 271.838837 -268.605885) (xy 271.861482 -268.556299)
			(xy 271.890954 -268.510441) (xy 271.926652 -268.469244) (xy 271.96785 -268.433547) (xy 272.01371 -268.404076)
			(xy 272.063296 -268.381432) (xy 272.1156 -268.366076) (xy 272.169558 -268.35832) (xy 272.196814 -268.357858)
			(xy 272.222265 -268.358291) (xy 272.272712 -268.365091) (xy 272.321805 -268.378542) (xy 272.345404 -268.388084)
			(xy 272.358518 -268.393175) (xy 272.386414 -268.396718) (xy 272.414218 -268.392512) (xy 272.439817 -268.380875)
			(xy 272.461267 -268.362692) (xy 272.476939 -268.339344) (xy 272.485642 -268.312605) (xy 272.486715 -268.284505)
			(xy 272.483834 -268.270736) (xy 272.478981 -268.24896) (xy 272.473764 -268.204651) (xy 272.47342 -268.182344)
			(xy 272.473808 -268.155088) (xy 272.48156 -268.101129) (xy 272.496912 -268.048823) (xy 272.519551 -267.999234)
			(xy 272.549018 -267.953372) (xy 272.584712 -267.91217) (xy 272.625906 -267.876468) (xy 272.671761 -267.846991)
			(xy 272.721345 -267.824341) (xy 272.773648 -267.808977) (xy 272.827605 -267.801214) (xy 272.882118 -267.801208)
			(xy 272.936076 -267.808961) (xy 272.988382 -267.824314) (xy 273.037971 -267.846954) (xy 273.083832 -267.876421)
			(xy 273.125033 -267.912116) (xy 273.160735 -267.95331) (xy 273.190211 -267.999166) (xy 273.212861 -268.04875)
			(xy 273.228224 -268.101053) (xy 273.235987 -268.15501) (xy 273.235991 -268.209523) (xy 273.228238 -268.263481)
			(xy 273.212885 -268.315787) (xy 273.190243 -268.365375) (xy 273.160775 -268.411237) (xy 273.125081 -268.452437)
			(xy 273.083886 -268.488139) (xy 273.038029 -268.517614) (xy 272.988445 -268.540263) (xy 272.936141 -268.555625)
			(xy 272.882184 -268.563387) (xy 272.854928 -268.563852) (xy 272.829477 -268.563405) (xy 272.779031 -268.55661)
			(xy 272.729937 -268.543165) (xy 272.706338 -268.533626) (xy 272.693217 -268.528571) (xy 272.665332 -268.525047)
			(xy 272.637544 -268.529263) (xy 272.611959 -268.540898) (xy 272.590519 -268.559071) (xy 272.574848 -268.582403)
			(xy 272.566135 -268.609124) (xy 272.565041 -268.637209) (xy 272.567908 -268.650974) (xy 272.572763 -268.672749)
			(xy 272.577979 -268.717059) (xy 272.578322 -268.739366) (xy 272.577881 -268.766622) (xy 272.570128 -268.82058)
			(xy 272.554775 -268.872885) (xy 272.532133 -268.922473) (xy 272.502665 -268.968334) (xy 272.46697 -269.009534)
			(xy 272.425775 -269.045234) (xy 272.379919 -269.074708) (xy 272.330334 -269.097356) (xy 272.278031 -269.112717)
			(xy 272.224074 -269.120478) (xy 272.169562 -269.12048) (xy 272.115604 -269.112725) (xy 272.0633 -269.097369)
			(xy 272.013713 -269.074726) (xy 271.967854 -269.045256) (xy 271.926655 -269.009559) (xy 271.890956 -268.968362)
			(xy 271.861484 -268.922505) (xy 271.838838 -268.872919) (xy 271.823479 -268.820615) (xy 271.815721 -268.766658)
			(xy 266.094491 -268.766658) (xy 266.166046 -268.914134) (xy 266.243932 -269.093009) (xy 266.314409 -269.274931)
			(xy 266.377357 -269.459593) (xy 266.432672 -269.646683) (xy 266.480258 -269.835887) (xy 266.520037 -270.026884)
			(xy 266.551941 -270.219354) (xy 266.575916 -270.412972) (xy 266.591922 -270.60741) (xy 266.599931 -270.802342)
			(xy 266.600432 -270.89989) (xy 266.599931 -270.997438) (xy 266.591922 -271.19237) (xy 266.575916 -271.386808)
			(xy 266.551941 -271.580426) (xy 266.520037 -271.772896) (xy 266.51269 -271.808173) (xy 272.60549 -271.808173)
			(xy 272.60549 -271.754875) (xy 272.613433 -271.702171) (xy 272.629143 -271.651241) (xy 272.652269 -271.60322)
			(xy 272.682293 -271.559183) (xy 272.718545 -271.520112) (xy 272.760216 -271.486881) (xy 272.806374 -271.460232)
			(xy 272.855988 -271.44076) (xy 272.90795 -271.4289) (xy 272.9611 -271.424917) (xy 273.01425 -271.4289)
			(xy 273.066212 -271.44076) (xy 273.115826 -271.460232) (xy 273.161984 -271.486881) (xy 273.203655 -271.520112)
			(xy 273.239907 -271.559183) (xy 273.269931 -271.60322) (xy 273.293057 -271.651241) (xy 273.308767 -271.702171)
			(xy 273.31671 -271.754875) (xy 273.317208 -271.781524) (xy 273.31671 -271.808173) (xy 273.308767 -271.860877)
			(xy 273.293057 -271.911807) (xy 273.269931 -271.959828) (xy 273.239907 -272.003865) (xy 273.203655 -272.042936)
			(xy 273.161984 -272.076167) (xy 273.115826 -272.102816) (xy 273.066212 -272.122288) (xy 273.01425 -272.134148)
			(xy 272.9611 -272.138132) (xy 272.90795 -272.134148) (xy 272.855988 -272.122288) (xy 272.806374 -272.102816)
			(xy 272.760216 -272.076167) (xy 272.718545 -272.042936) (xy 272.682293 -272.003865) (xy 272.652269 -271.959828)
			(xy 272.629143 -271.911807) (xy 272.613433 -271.860877) (xy 272.60549 -271.808173) (xy 266.51269 -271.808173)
			(xy 266.480258 -271.963893) (xy 266.433559 -272.14957) (xy 276.34363 -272.14957) (xy 276.34759 -272.100516)
			(xy 276.359367 -272.052732) (xy 276.378658 -272.007456) (xy 276.404961 -271.96586) (xy 276.437596 -271.929023)
			(xy 276.475717 -271.897898) (xy 276.518338 -271.873291) (xy 276.564354 -271.855839) (xy 276.612573 -271.845995)
			(xy 276.661748 -271.844014) (xy 276.710603 -271.849946) (xy 276.757874 -271.863638) (xy 276.802336 -271.884736)
			(xy 276.842839 -271.912692) (xy 276.878332 -271.946784) (xy 276.907897 -271.986128) (xy 276.930768 -272.029705)
			(xy 276.946352 -272.076386) (xy 276.954247 -272.124963) (xy 276.954742 -272.14957) (xy 278.243804 -272.14957)
			(xy 278.247764 -272.100516) (xy 278.259541 -272.052732) (xy 278.278832 -272.007456) (xy 278.305135 -271.96586)
			(xy 278.33777 -271.929023) (xy 278.375891 -271.897898) (xy 278.418512 -271.873291) (xy 278.464528 -271.855839)
			(xy 278.512747 -271.845995) (xy 278.561922 -271.844014) (xy 278.610777 -271.849946) (xy 278.658048 -271.863638)
			(xy 278.70251 -271.884736) (xy 278.743013 -271.912692) (xy 278.778506 -271.946784) (xy 278.808071 -271.986128)
			(xy 278.830942 -272.029705) (xy 278.846526 -272.076386) (xy 278.854421 -272.124963) (xy 278.854916 -272.14957)
			(xy 280.143724 -272.14957) (xy 280.147684 -272.100516) (xy 280.159461 -272.052732) (xy 280.178752 -272.007456)
			(xy 280.205055 -271.96586) (xy 280.23769 -271.929023) (xy 280.275811 -271.897898) (xy 280.318432 -271.873291)
			(xy 280.364448 -271.855839) (xy 280.412667 -271.845995) (xy 280.461842 -271.844014) (xy 280.510697 -271.849946)
			(xy 280.557968 -271.863638) (xy 280.60243 -271.884736) (xy 280.642933 -271.912692) (xy 280.678426 -271.946784)
			(xy 280.707991 -271.986128) (xy 280.730862 -272.029705) (xy 280.746446 -272.076386) (xy 280.754341 -272.124963)
			(xy 280.754836 -272.14957) (xy 282.043644 -272.14957) (xy 282.047604 -272.100516) (xy 282.059381 -272.052732)
			(xy 282.078672 -272.007456) (xy 282.104975 -271.96586) (xy 282.13761 -271.929023) (xy 282.175731 -271.897898)
			(xy 282.218352 -271.873291) (xy 282.264368 -271.855839) (xy 282.312587 -271.845995) (xy 282.361762 -271.844014)
			(xy 282.410617 -271.849946) (xy 282.457888 -271.863638) (xy 282.50235 -271.884736) (xy 282.542853 -271.912692)
			(xy 282.578346 -271.946784) (xy 282.607911 -271.986128) (xy 282.630782 -272.029705) (xy 282.646366 -272.076386)
			(xy 282.654261 -272.124963) (xy 282.654756 -272.14957) (xy 283.943818 -272.14957) (xy 283.947778 -272.100516)
			(xy 283.959555 -272.052732) (xy 283.978846 -272.007456) (xy 284.005149 -271.96586) (xy 284.037784 -271.929023)
			(xy 284.075905 -271.897898) (xy 284.118526 -271.873291) (xy 284.164542 -271.855839) (xy 284.212761 -271.845995)
			(xy 284.261936 -271.844014) (xy 284.310791 -271.849946) (xy 284.358062 -271.863638) (xy 284.402524 -271.884736)
			(xy 284.443027 -271.912692) (xy 284.47852 -271.946784) (xy 284.508085 -271.986128) (xy 284.530956 -272.029705)
			(xy 284.54654 -272.076386) (xy 284.554435 -272.124963) (xy 284.55493 -272.14957) (xy 285.843738 -272.14957)
			(xy 285.847698 -272.100516) (xy 285.859475 -272.052732) (xy 285.878766 -272.007456) (xy 285.905069 -271.96586)
			(xy 285.937704 -271.929023) (xy 285.975825 -271.897898) (xy 286.018446 -271.873291) (xy 286.064462 -271.855839)
			(xy 286.112681 -271.845995) (xy 286.161856 -271.844014) (xy 286.210711 -271.849946) (xy 286.257982 -271.863638)
			(xy 286.302444 -271.884736) (xy 286.342947 -271.912692) (xy 286.37844 -271.946784) (xy 286.408005 -271.986128)
			(xy 286.430876 -272.029705) (xy 286.44646 -272.076386) (xy 286.454355 -272.124963) (xy 286.45485 -272.14957)
			(xy 287.743658 -272.14957) (xy 287.747618 -272.100516) (xy 287.759395 -272.052732) (xy 287.778686 -272.007456)
			(xy 287.804989 -271.96586) (xy 287.837624 -271.929023) (xy 287.875745 -271.897898) (xy 287.918366 -271.873291)
			(xy 287.964382 -271.855839) (xy 288.012601 -271.845995) (xy 288.061776 -271.844014) (xy 288.110631 -271.849946)
			(xy 288.157902 -271.863638) (xy 288.202364 -271.884736) (xy 288.242867 -271.912692) (xy 288.27836 -271.946784)
			(xy 288.307925 -271.986128) (xy 288.330796 -272.029705) (xy 288.34638 -272.076386) (xy 288.354275 -272.124963)
			(xy 288.35477 -272.14957) (xy 288.354275 -272.174177) (xy 288.34638 -272.222754) (xy 288.330796 -272.269435)
			(xy 288.307925 -272.313012) (xy 288.27836 -272.352356) (xy 288.242867 -272.386448) (xy 288.202364 -272.414404)
			(xy 288.157902 -272.435502) (xy 288.110631 -272.449194) (xy 288.061776 -272.455126) (xy 288.012601 -272.453145)
			(xy 287.964382 -272.443301) (xy 287.918366 -272.425849) (xy 287.875745 -272.401242) (xy 287.837624 -272.370117)
			(xy 287.804989 -272.33328) (xy 287.778686 -272.291684) (xy 287.759395 -272.246408) (xy 287.747618 -272.198624)
			(xy 287.743658 -272.14957) (xy 286.45485 -272.14957) (xy 286.454355 -272.174177) (xy 286.44646 -272.222754)
			(xy 286.430876 -272.269435) (xy 286.408005 -272.313012) (xy 286.37844 -272.352356) (xy 286.342947 -272.386448)
			(xy 286.302444 -272.414404) (xy 286.257982 -272.435502) (xy 286.210711 -272.449194) (xy 286.161856 -272.455126)
			(xy 286.112681 -272.453145) (xy 286.064462 -272.443301) (xy 286.018446 -272.425849) (xy 285.975825 -272.401242)
			(xy 285.937704 -272.370117) (xy 285.905069 -272.33328) (xy 285.878766 -272.291684) (xy 285.859475 -272.246408)
			(xy 285.847698 -272.198624) (xy 285.843738 -272.14957) (xy 284.55493 -272.14957) (xy 284.554435 -272.174177)
			(xy 284.54654 -272.222754) (xy 284.530956 -272.269435) (xy 284.508085 -272.313012) (xy 284.47852 -272.352356)
			(xy 284.443027 -272.386448) (xy 284.402524 -272.414404) (xy 284.358062 -272.435502) (xy 284.310791 -272.449194)
			(xy 284.261936 -272.455126) (xy 284.212761 -272.453145) (xy 284.164542 -272.443301) (xy 284.118526 -272.425849)
			(xy 284.075905 -272.401242) (xy 284.037784 -272.370117) (xy 284.005149 -272.33328) (xy 283.978846 -272.291684)
			(xy 283.959555 -272.246408) (xy 283.947778 -272.198624) (xy 283.943818 -272.14957) (xy 282.654756 -272.14957)
			(xy 282.654261 -272.174177) (xy 282.646366 -272.222754) (xy 282.630782 -272.269435) (xy 282.607911 -272.313012)
			(xy 282.578346 -272.352356) (xy 282.542853 -272.386448) (xy 282.50235 -272.414404) (xy 282.457888 -272.435502)
			(xy 282.410617 -272.449194) (xy 282.361762 -272.455126) (xy 282.312587 -272.453145) (xy 282.264368 -272.443301)
			(xy 282.218352 -272.425849) (xy 282.175731 -272.401242) (xy 282.13761 -272.370117) (xy 282.104975 -272.33328)
			(xy 282.078672 -272.291684) (xy 282.059381 -272.246408) (xy 282.047604 -272.198624) (xy 282.043644 -272.14957)
			(xy 280.754836 -272.14957) (xy 280.754341 -272.174177) (xy 280.746446 -272.222754) (xy 280.730862 -272.269435)
			(xy 280.707991 -272.313012) (xy 280.678426 -272.352356) (xy 280.642933 -272.386448) (xy 280.60243 -272.414404)
			(xy 280.557968 -272.435502) (xy 280.510697 -272.449194) (xy 280.461842 -272.455126) (xy 280.412667 -272.453145)
			(xy 280.364448 -272.443301) (xy 280.318432 -272.425849) (xy 280.275811 -272.401242) (xy 280.23769 -272.370117)
			(xy 280.205055 -272.33328) (xy 280.178752 -272.291684) (xy 280.159461 -272.246408) (xy 280.147684 -272.198624)
			(xy 280.143724 -272.14957) (xy 278.854916 -272.14957) (xy 278.854421 -272.174177) (xy 278.846526 -272.222754)
			(xy 278.830942 -272.269435) (xy 278.808071 -272.313012) (xy 278.778506 -272.352356) (xy 278.743013 -272.386448)
			(xy 278.70251 -272.414404) (xy 278.658048 -272.435502) (xy 278.610777 -272.449194) (xy 278.561922 -272.455126)
			(xy 278.512747 -272.453145) (xy 278.464528 -272.443301) (xy 278.418512 -272.425849) (xy 278.375891 -272.401242)
			(xy 278.33777 -272.370117) (xy 278.305135 -272.33328) (xy 278.278832 -272.291684) (xy 278.259541 -272.246408)
			(xy 278.247764 -272.198624) (xy 278.243804 -272.14957) (xy 276.954742 -272.14957) (xy 276.954247 -272.174177)
			(xy 276.946352 -272.222754) (xy 276.930768 -272.269435) (xy 276.907897 -272.313012) (xy 276.878332 -272.352356)
			(xy 276.842839 -272.386448) (xy 276.802336 -272.414404) (xy 276.757874 -272.435502) (xy 276.710603 -272.449194)
			(xy 276.661748 -272.455126) (xy 276.612573 -272.453145) (xy 276.564354 -272.443301) (xy 276.518338 -272.425849)
			(xy 276.475717 -272.401242) (xy 276.437596 -272.370117) (xy 276.404961 -272.33328) (xy 276.378658 -272.291684)
			(xy 276.359367 -272.246408) (xy 276.34759 -272.198624) (xy 276.34363 -272.14957) (xy 266.433559 -272.14957)
			(xy 266.432672 -272.153097) (xy 266.377357 -272.340187) (xy 266.314409 -272.524849) (xy 266.275686 -272.624804)
			(xy 270.169144 -272.624804) (xy 270.173104 -272.57575) (xy 270.184881 -272.527966) (xy 270.204172 -272.48269)
			(xy 270.230475 -272.441094) (xy 270.26311 -272.404257) (xy 270.301231 -272.373132) (xy 270.343852 -272.348525)
			(xy 270.389868 -272.331073) (xy 270.438087 -272.321229) (xy 270.487262 -272.319248) (xy 270.536117 -272.32518)
			(xy 270.583388 -272.338872) (xy 270.62785 -272.35997) (xy 270.668353 -272.387926) (xy 270.703846 -272.422018)
			(xy 270.733411 -272.461362) (xy 270.756282 -272.504939) (xy 270.771866 -272.55162) (xy 270.779761 -272.600197)
			(xy 270.780256 -272.624804) (xy 271.119104 -272.624804) (xy 271.123064 -272.57575) (xy 271.134841 -272.527966)
			(xy 271.154132 -272.48269) (xy 271.180435 -272.441094) (xy 271.21307 -272.404257) (xy 271.251191 -272.373132)
			(xy 271.293812 -272.348525) (xy 271.339828 -272.331073) (xy 271.388047 -272.321229) (xy 271.437222 -272.319248)
			(xy 271.486077 -272.32518) (xy 271.533348 -272.338872) (xy 271.57781 -272.35997) (xy 271.618313 -272.387926)
			(xy 271.653806 -272.422018) (xy 271.683371 -272.461362) (xy 271.706242 -272.504939) (xy 271.721826 -272.55162)
			(xy 271.729721 -272.600197) (xy 271.730216 -272.624804) (xy 272.069064 -272.624804) (xy 272.073024 -272.57575)
			(xy 272.084801 -272.527966) (xy 272.104092 -272.48269) (xy 272.130395 -272.441094) (xy 272.16303 -272.404257)
			(xy 272.201151 -272.373132) (xy 272.243772 -272.348525) (xy 272.289788 -272.331073) (xy 272.338007 -272.321229)
			(xy 272.387182 -272.319248) (xy 272.436037 -272.32518) (xy 272.483308 -272.338872) (xy 272.52777 -272.35997)
			(xy 272.568273 -272.387926) (xy 272.603766 -272.422018) (xy 272.633331 -272.461362) (xy 272.656202 -272.504939)
			(xy 272.671786 -272.55162) (xy 272.679681 -272.600197) (xy 272.680176 -272.624804) (xy 273.019024 -272.624804)
			(xy 273.022984 -272.57575) (xy 273.034761 -272.527966) (xy 273.054052 -272.48269) (xy 273.080355 -272.441094)
			(xy 273.11299 -272.404257) (xy 273.151111 -272.373132) (xy 273.193732 -272.348525) (xy 273.239748 -272.331073)
			(xy 273.287967 -272.321229) (xy 273.337142 -272.319248) (xy 273.385997 -272.32518) (xy 273.433268 -272.338872)
			(xy 273.47773 -272.35997) (xy 273.518233 -272.387926) (xy 273.553726 -272.422018) (xy 273.583291 -272.461362)
			(xy 273.606162 -272.504939) (xy 273.621746 -272.55162) (xy 273.629641 -272.600197) (xy 273.630136 -272.624804)
			(xy 273.968984 -272.624804) (xy 273.972944 -272.57575) (xy 273.984721 -272.527966) (xy 274.004012 -272.48269)
			(xy 274.030315 -272.441094) (xy 274.06295 -272.404257) (xy 274.101071 -272.373132) (xy 274.143692 -272.348525)
			(xy 274.189708 -272.331073) (xy 274.237927 -272.321229) (xy 274.287102 -272.319248) (xy 274.335957 -272.32518)
			(xy 274.383228 -272.338872) (xy 274.42769 -272.35997) (xy 274.468193 -272.387926) (xy 274.503686 -272.422018)
			(xy 274.533251 -272.461362) (xy 274.556122 -272.504939) (xy 274.571706 -272.55162) (xy 274.579601 -272.600197)
			(xy 274.580096 -272.624804) (xy 274.918944 -272.624804) (xy 274.922904 -272.57575) (xy 274.934681 -272.527966)
			(xy 274.953972 -272.48269) (xy 274.980275 -272.441094) (xy 275.01291 -272.404257) (xy 275.051031 -272.373132)
			(xy 275.093652 -272.348525) (xy 275.139668 -272.331073) (xy 275.187887 -272.321229) (xy 275.237062 -272.319248)
			(xy 275.285917 -272.32518) (xy 275.333188 -272.338872) (xy 275.37765 -272.35997) (xy 275.418153 -272.387926)
			(xy 275.453646 -272.422018) (xy 275.483211 -272.461362) (xy 275.506082 -272.504939) (xy 275.521666 -272.55162)
			(xy 275.529561 -272.600197) (xy 275.530056 -272.624804) (xy 275.529561 -272.649411) (xy 275.521666 -272.697988)
			(xy 275.506082 -272.744669) (xy 275.483211 -272.788246) (xy 275.453646 -272.82759) (xy 275.418153 -272.861682)
			(xy 275.37765 -272.889638) (xy 275.333188 -272.910736) (xy 275.285917 -272.924428) (xy 275.237062 -272.93036)
			(xy 275.187887 -272.928379) (xy 275.139668 -272.918535) (xy 275.093652 -272.901083) (xy 275.051031 -272.876476)
			(xy 275.01291 -272.845351) (xy 274.980275 -272.808514) (xy 274.953972 -272.766918) (xy 274.934681 -272.721642)
			(xy 274.922904 -272.673858) (xy 274.918944 -272.624804) (xy 274.580096 -272.624804) (xy 274.579601 -272.649411)
			(xy 274.571706 -272.697988) (xy 274.556122 -272.744669) (xy 274.533251 -272.788246) (xy 274.503686 -272.82759)
			(xy 274.468193 -272.861682) (xy 274.42769 -272.889638) (xy 274.383228 -272.910736) (xy 274.335957 -272.924428)
			(xy 274.287102 -272.93036) (xy 274.237927 -272.928379) (xy 274.189708 -272.918535) (xy 274.143692 -272.901083)
			(xy 274.101071 -272.876476) (xy 274.06295 -272.845351) (xy 274.030315 -272.808514) (xy 274.004012 -272.766918)
			(xy 273.984721 -272.721642) (xy 273.972944 -272.673858) (xy 273.968984 -272.624804) (xy 273.630136 -272.624804)
			(xy 273.629641 -272.649411) (xy 273.621746 -272.697988) (xy 273.606162 -272.744669) (xy 273.583291 -272.788246)
			(xy 273.553726 -272.82759) (xy 273.518233 -272.861682) (xy 273.47773 -272.889638) (xy 273.433268 -272.910736)
			(xy 273.385997 -272.924428) (xy 273.337142 -272.93036) (xy 273.287967 -272.928379) (xy 273.239748 -272.918535)
			(xy 273.193732 -272.901083) (xy 273.151111 -272.876476) (xy 273.11299 -272.845351) (xy 273.080355 -272.808514)
			(xy 273.054052 -272.766918) (xy 273.034761 -272.721642) (xy 273.022984 -272.673858) (xy 273.019024 -272.624804)
			(xy 272.680176 -272.624804) (xy 272.679681 -272.649411) (xy 272.671786 -272.697988) (xy 272.656202 -272.744669)
			(xy 272.633331 -272.788246) (xy 272.603766 -272.82759) (xy 272.568273 -272.861682) (xy 272.52777 -272.889638)
			(xy 272.483308 -272.910736) (xy 272.436037 -272.924428) (xy 272.387182 -272.93036) (xy 272.338007 -272.928379)
			(xy 272.289788 -272.918535) (xy 272.243772 -272.901083) (xy 272.201151 -272.876476) (xy 272.16303 -272.845351)
			(xy 272.130395 -272.808514) (xy 272.104092 -272.766918) (xy 272.084801 -272.721642) (xy 272.073024 -272.673858)
			(xy 272.069064 -272.624804) (xy 271.730216 -272.624804) (xy 271.729721 -272.649411) (xy 271.721826 -272.697988)
			(xy 271.706242 -272.744669) (xy 271.683371 -272.788246) (xy 271.653806 -272.82759) (xy 271.618313 -272.861682)
			(xy 271.57781 -272.889638) (xy 271.533348 -272.910736) (xy 271.486077 -272.924428) (xy 271.437222 -272.93036)
			(xy 271.388047 -272.928379) (xy 271.339828 -272.918535) (xy 271.293812 -272.901083) (xy 271.251191 -272.876476)
			(xy 271.21307 -272.845351) (xy 271.180435 -272.808514) (xy 271.154132 -272.766918) (xy 271.134841 -272.721642)
			(xy 271.123064 -272.673858) (xy 271.119104 -272.624804) (xy 270.780256 -272.624804) (xy 270.779761 -272.649411)
			(xy 270.771866 -272.697988) (xy 270.756282 -272.744669) (xy 270.733411 -272.788246) (xy 270.703846 -272.82759)
			(xy 270.668353 -272.861682) (xy 270.62785 -272.889638) (xy 270.583388 -272.910736) (xy 270.536117 -272.924428)
			(xy 270.487262 -272.93036) (xy 270.438087 -272.928379) (xy 270.389868 -272.918535) (xy 270.343852 -272.901083)
			(xy 270.301231 -272.876476) (xy 270.26311 -272.845351) (xy 270.230475 -272.808514) (xy 270.204172 -272.766918)
			(xy 270.184881 -272.721642) (xy 270.173104 -272.673858) (xy 270.169144 -272.624804) (xy 266.275686 -272.624804)
			(xy 266.243932 -272.706771) (xy 266.166046 -272.885646) (xy 266.080881 -273.061172) (xy 266.046342 -273.125492)
			(xy 276.32304 -273.125492) (xy 276.32304 -273.074076) (xy 276.331083 -273.023294) (xy 276.346971 -272.974395)
			(xy 276.370314 -272.928583) (xy 276.400535 -272.886987) (xy 276.436891 -272.850631) (xy 276.478487 -272.82041)
			(xy 276.524299 -272.797067) (xy 276.573198 -272.781179) (xy 276.62398 -272.773136) (xy 276.675396 -272.773136)
			(xy 276.726178 -272.781179) (xy 276.775077 -272.797067) (xy 276.820889 -272.82041) (xy 276.862485 -272.850631)
			(xy 276.898841 -272.886987) (xy 276.929062 -272.928583) (xy 276.952405 -272.974395) (xy 276.968293 -273.023294)
			(xy 276.976336 -273.074076) (xy 276.97684 -273.099784) (xy 277.294098 -273.099784) (xy 277.298058 -273.05073)
			(xy 277.309835 -273.002946) (xy 277.329126 -272.95767) (xy 277.355429 -272.916074) (xy 277.388064 -272.879237)
			(xy 277.426185 -272.848112) (xy 277.468806 -272.823505) (xy 277.514822 -272.806053) (xy 277.563041 -272.796209)
			(xy 277.612216 -272.794228) (xy 277.661071 -272.80016) (xy 277.708342 -272.813852) (xy 277.752804 -272.83495)
			(xy 277.793307 -272.862906) (xy 277.8288 -272.896998) (xy 277.858365 -272.936342) (xy 277.881236 -272.979919)
			(xy 277.89682 -273.0266) (xy 277.904715 -273.075177) (xy 277.90521 -273.099784) (xy 277.904715 -273.124391)
			(xy 277.904536 -273.125492) (xy 278.223214 -273.125492) (xy 278.223214 -273.074076) (xy 278.231257 -273.023294)
			(xy 278.247145 -272.974395) (xy 278.270488 -272.928583) (xy 278.300709 -272.886987) (xy 278.337065 -272.850631)
			(xy 278.378661 -272.82041) (xy 278.424473 -272.797067) (xy 278.473372 -272.781179) (xy 278.524154 -272.773136)
			(xy 278.57557 -272.773136) (xy 278.626352 -272.781179) (xy 278.675251 -272.797067) (xy 278.721063 -272.82041)
			(xy 278.762659 -272.850631) (xy 278.799015 -272.886987) (xy 278.829236 -272.928583) (xy 278.852579 -272.974395)
			(xy 278.868467 -273.023294) (xy 278.87651 -273.074076) (xy 278.877014 -273.099784) (xy 279.194018 -273.099784)
			(xy 279.197978 -273.05073) (xy 279.209755 -273.002946) (xy 279.229046 -272.95767) (xy 279.255349 -272.916074)
			(xy 279.287984 -272.879237) (xy 279.326105 -272.848112) (xy 279.368726 -272.823505) (xy 279.414742 -272.806053)
			(xy 279.462961 -272.796209) (xy 279.512136 -272.794228) (xy 279.560991 -272.80016) (xy 279.608262 -272.813852)
			(xy 279.652724 -272.83495) (xy 279.693227 -272.862906) (xy 279.72872 -272.896998) (xy 279.758285 -272.936342)
			(xy 279.781156 -272.979919) (xy 279.79674 -273.0266) (xy 279.804635 -273.075177) (xy 279.80513 -273.099784)
			(xy 279.804635 -273.124391) (xy 279.804456 -273.125492) (xy 280.123134 -273.125492) (xy 280.123134 -273.074076)
			(xy 280.131177 -273.023294) (xy 280.147065 -272.974395) (xy 280.170408 -272.928583) (xy 280.200629 -272.886987)
			(xy 280.236985 -272.850631) (xy 280.278581 -272.82041) (xy 280.324393 -272.797067) (xy 280.373292 -272.781179)
			(xy 280.424074 -272.773136) (xy 280.47549 -272.773136) (xy 280.526272 -272.781179) (xy 280.575171 -272.797067)
			(xy 280.620983 -272.82041) (xy 280.662579 -272.850631) (xy 280.698935 -272.886987) (xy 280.729156 -272.928583)
			(xy 280.752499 -272.974395) (xy 280.768387 -273.023294) (xy 280.77643 -273.074076) (xy 280.776934 -273.099784)
			(xy 281.093938 -273.099784) (xy 281.097898 -273.05073) (xy 281.109675 -273.002946) (xy 281.128966 -272.95767)
			(xy 281.155269 -272.916074) (xy 281.187904 -272.879237) (xy 281.226025 -272.848112) (xy 281.268646 -272.823505)
			(xy 281.314662 -272.806053) (xy 281.362881 -272.796209) (xy 281.412056 -272.794228) (xy 281.460911 -272.80016)
			(xy 281.508182 -272.813852) (xy 281.552644 -272.83495) (xy 281.593147 -272.862906) (xy 281.62864 -272.896998)
			(xy 281.658205 -272.936342) (xy 281.681076 -272.979919) (xy 281.69666 -273.0266) (xy 281.704555 -273.075177)
			(xy 281.70505 -273.099784) (xy 281.704555 -273.124391) (xy 281.704376 -273.125492) (xy 282.023054 -273.125492)
			(xy 282.023054 -273.074076) (xy 282.031097 -273.023294) (xy 282.046985 -272.974395) (xy 282.070328 -272.928583)
			(xy 282.100549 -272.886987) (xy 282.136905 -272.850631) (xy 282.178501 -272.82041) (xy 282.224313 -272.797067)
			(xy 282.273212 -272.781179) (xy 282.323994 -272.773136) (xy 282.37541 -272.773136) (xy 282.426192 -272.781179)
			(xy 282.475091 -272.797067) (xy 282.520903 -272.82041) (xy 282.562499 -272.850631) (xy 282.598855 -272.886987)
			(xy 282.629076 -272.928583) (xy 282.652419 -272.974395) (xy 282.668307 -273.023294) (xy 282.67635 -273.074076)
			(xy 282.676854 -273.099784) (xy 282.994112 -273.099784) (xy 282.998072 -273.05073) (xy 283.009849 -273.002946)
			(xy 283.02914 -272.95767) (xy 283.055443 -272.916074) (xy 283.088078 -272.879237) (xy 283.126199 -272.848112)
			(xy 283.16882 -272.823505) (xy 283.214836 -272.806053) (xy 283.263055 -272.796209) (xy 283.31223 -272.794228)
			(xy 283.361085 -272.80016) (xy 283.408356 -272.813852) (xy 283.452818 -272.83495) (xy 283.493321 -272.862906)
			(xy 283.528814 -272.896998) (xy 283.558379 -272.936342) (xy 283.58125 -272.979919) (xy 283.596834 -273.0266)
			(xy 283.604729 -273.075177) (xy 283.605224 -273.099784) (xy 283.604729 -273.124391) (xy 283.60455 -273.125492)
			(xy 283.923228 -273.125492) (xy 283.923228 -273.074076) (xy 283.931271 -273.023294) (xy 283.947159 -272.974395)
			(xy 283.970502 -272.928583) (xy 284.000723 -272.886987) (xy 284.037079 -272.850631) (xy 284.078675 -272.82041)
			(xy 284.124487 -272.797067) (xy 284.173386 -272.781179) (xy 284.224168 -272.773136) (xy 284.275584 -272.773136)
			(xy 284.326366 -272.781179) (xy 284.375265 -272.797067) (xy 284.421077 -272.82041) (xy 284.462673 -272.850631)
			(xy 284.499029 -272.886987) (xy 284.52925 -272.928583) (xy 284.552593 -272.974395) (xy 284.568481 -273.023294)
			(xy 284.576524 -273.074076) (xy 284.577028 -273.099784) (xy 284.894032 -273.099784) (xy 284.897992 -273.05073)
			(xy 284.909769 -273.002946) (xy 284.92906 -272.95767) (xy 284.955363 -272.916074) (xy 284.987998 -272.879237)
			(xy 285.026119 -272.848112) (xy 285.06874 -272.823505) (xy 285.114756 -272.806053) (xy 285.162975 -272.796209)
			(xy 285.21215 -272.794228) (xy 285.261005 -272.80016) (xy 285.308276 -272.813852) (xy 285.352738 -272.83495)
			(xy 285.393241 -272.862906) (xy 285.428734 -272.896998) (xy 285.458299 -272.936342) (xy 285.48117 -272.979919)
			(xy 285.496754 -273.0266) (xy 285.504649 -273.075177) (xy 285.505144 -273.099784) (xy 285.504649 -273.124391)
			(xy 285.50447 -273.125492) (xy 285.823148 -273.125492) (xy 285.823148 -273.074076) (xy 285.831191 -273.023294)
			(xy 285.847079 -272.974395) (xy 285.870422 -272.928583) (xy 285.900643 -272.886987) (xy 285.936999 -272.850631)
			(xy 285.978595 -272.82041) (xy 286.024407 -272.797067) (xy 286.073306 -272.781179) (xy 286.124088 -272.773136)
			(xy 286.175504 -272.773136) (xy 286.226286 -272.781179) (xy 286.275185 -272.797067) (xy 286.320997 -272.82041)
			(xy 286.362593 -272.850631) (xy 286.398949 -272.886987) (xy 286.42917 -272.928583) (xy 286.452513 -272.974395)
			(xy 286.468401 -273.023294) (xy 286.476444 -273.074076) (xy 286.476948 -273.099784) (xy 286.793952 -273.099784)
			(xy 286.797912 -273.05073) (xy 286.809689 -273.002946) (xy 286.82898 -272.95767) (xy 286.855283 -272.916074)
			(xy 286.887918 -272.879237) (xy 286.926039 -272.848112) (xy 286.96866 -272.823505) (xy 287.014676 -272.806053)
			(xy 287.062895 -272.796209) (xy 287.11207 -272.794228) (xy 287.160925 -272.80016) (xy 287.208196 -272.813852)
			(xy 287.252658 -272.83495) (xy 287.293161 -272.862906) (xy 287.328654 -272.896998) (xy 287.358219 -272.936342)
			(xy 287.38109 -272.979919) (xy 287.396674 -273.0266) (xy 287.404569 -273.075177) (xy 287.405064 -273.099784)
			(xy 287.404569 -273.124391) (xy 287.40439 -273.125492) (xy 287.723068 -273.125492) (xy 287.723068 -273.074076)
			(xy 287.731111 -273.023294) (xy 287.746999 -272.974395) (xy 287.770342 -272.928583) (xy 287.800563 -272.886987)
			(xy 287.836919 -272.850631) (xy 287.878515 -272.82041) (xy 287.924327 -272.797067) (xy 287.973226 -272.781179)
			(xy 288.024008 -272.773136) (xy 288.075424 -272.773136) (xy 288.126206 -272.781179) (xy 288.175105 -272.797067)
			(xy 288.220917 -272.82041) (xy 288.262513 -272.850631) (xy 288.298869 -272.886987) (xy 288.32909 -272.928583)
			(xy 288.352433 -272.974395) (xy 288.368321 -273.023294) (xy 288.376364 -273.074076) (xy 288.376868 -273.099784)
			(xy 288.694126 -273.099784) (xy 288.698086 -273.05073) (xy 288.709863 -273.002946) (xy 288.729154 -272.95767)
			(xy 288.755457 -272.916074) (xy 288.788092 -272.879237) (xy 288.826213 -272.848112) (xy 288.868834 -272.823505)
			(xy 288.91485 -272.806053) (xy 288.963069 -272.796209) (xy 289.012244 -272.794228) (xy 289.061099 -272.80016)
			(xy 289.10837 -272.813852) (xy 289.152832 -272.83495) (xy 289.193335 -272.862906) (xy 289.228828 -272.896998)
			(xy 289.258393 -272.936342) (xy 289.281264 -272.979919) (xy 289.296848 -273.0266) (xy 289.304743 -273.075177)
			(xy 289.305238 -273.099784) (xy 289.304743 -273.124391) (xy 289.296848 -273.172968) (xy 289.281264 -273.219649)
			(xy 289.258393 -273.263226) (xy 289.228828 -273.30257) (xy 289.193335 -273.336662) (xy 289.152832 -273.364618)
			(xy 289.10837 -273.385716) (xy 289.061099 -273.399408) (xy 289.012244 -273.40534) (xy 288.963069 -273.403359)
			(xy 288.91485 -273.393515) (xy 288.868834 -273.376063) (xy 288.826213 -273.351456) (xy 288.788092 -273.320331)
			(xy 288.755457 -273.283494) (xy 288.729154 -273.241898) (xy 288.709863 -273.196622) (xy 288.698086 -273.148838)
			(xy 288.694126 -273.099784) (xy 288.376868 -273.099784) (xy 288.376364 -273.125492) (xy 288.368321 -273.176274)
			(xy 288.352433 -273.225173) (xy 288.32909 -273.270985) (xy 288.298869 -273.312581) (xy 288.262513 -273.348937)
			(xy 288.220917 -273.379158) (xy 288.175105 -273.402501) (xy 288.126206 -273.418389) (xy 288.075424 -273.426432)
			(xy 288.024008 -273.426432) (xy 287.973226 -273.418389) (xy 287.924327 -273.402501) (xy 287.878515 -273.379158)
			(xy 287.836919 -273.348937) (xy 287.800563 -273.312581) (xy 287.770342 -273.270985) (xy 287.746999 -273.225173)
			(xy 287.731111 -273.176274) (xy 287.723068 -273.125492) (xy 287.40439 -273.125492) (xy 287.396674 -273.172968)
			(xy 287.38109 -273.219649) (xy 287.358219 -273.263226) (xy 287.328654 -273.30257) (xy 287.293161 -273.336662)
			(xy 287.252658 -273.364618) (xy 287.208196 -273.385716) (xy 287.160925 -273.399408) (xy 287.11207 -273.40534)
			(xy 287.062895 -273.403359) (xy 287.014676 -273.393515) (xy 286.96866 -273.376063) (xy 286.926039 -273.351456)
			(xy 286.887918 -273.320331) (xy 286.855283 -273.283494) (xy 286.82898 -273.241898) (xy 286.809689 -273.196622)
			(xy 286.797912 -273.148838) (xy 286.793952 -273.099784) (xy 286.476948 -273.099784) (xy 286.476444 -273.125492)
			(xy 286.468401 -273.176274) (xy 286.452513 -273.225173) (xy 286.42917 -273.270985) (xy 286.398949 -273.312581)
			(xy 286.362593 -273.348937) (xy 286.320997 -273.379158) (xy 286.275185 -273.402501) (xy 286.226286 -273.418389)
			(xy 286.175504 -273.426432) (xy 286.124088 -273.426432) (xy 286.073306 -273.418389) (xy 286.024407 -273.402501)
			(xy 285.978595 -273.379158) (xy 285.936999 -273.348937) (xy 285.900643 -273.312581) (xy 285.870422 -273.270985)
			(xy 285.847079 -273.225173) (xy 285.831191 -273.176274) (xy 285.823148 -273.125492) (xy 285.50447 -273.125492)
			(xy 285.496754 -273.172968) (xy 285.48117 -273.219649) (xy 285.458299 -273.263226) (xy 285.428734 -273.30257)
			(xy 285.393241 -273.336662) (xy 285.352738 -273.364618) (xy 285.308276 -273.385716) (xy 285.261005 -273.399408)
			(xy 285.21215 -273.40534) (xy 285.162975 -273.403359) (xy 285.114756 -273.393515) (xy 285.06874 -273.376063)
			(xy 285.026119 -273.351456) (xy 284.987998 -273.320331) (xy 284.955363 -273.283494) (xy 284.92906 -273.241898)
			(xy 284.909769 -273.196622) (xy 284.897992 -273.148838) (xy 284.894032 -273.099784) (xy 284.577028 -273.099784)
			(xy 284.576524 -273.125492) (xy 284.568481 -273.176274) (xy 284.552593 -273.225173) (xy 284.52925 -273.270985)
			(xy 284.499029 -273.312581) (xy 284.462673 -273.348937) (xy 284.421077 -273.379158) (xy 284.375265 -273.402501)
			(xy 284.326366 -273.418389) (xy 284.275584 -273.426432) (xy 284.224168 -273.426432) (xy 284.173386 -273.418389)
			(xy 284.124487 -273.402501) (xy 284.078675 -273.379158) (xy 284.037079 -273.348937) (xy 284.000723 -273.312581)
			(xy 283.970502 -273.270985) (xy 283.947159 -273.225173) (xy 283.931271 -273.176274) (xy 283.923228 -273.125492)
			(xy 283.60455 -273.125492) (xy 283.596834 -273.172968) (xy 283.58125 -273.219649) (xy 283.558379 -273.263226)
			(xy 283.528814 -273.30257) (xy 283.493321 -273.336662) (xy 283.452818 -273.364618) (xy 283.408356 -273.385716)
			(xy 283.361085 -273.399408) (xy 283.31223 -273.40534) (xy 283.263055 -273.403359) (xy 283.214836 -273.393515)
			(xy 283.16882 -273.376063) (xy 283.126199 -273.351456) (xy 283.088078 -273.320331) (xy 283.055443 -273.283494)
			(xy 283.02914 -273.241898) (xy 283.009849 -273.196622) (xy 282.998072 -273.148838) (xy 282.994112 -273.099784)
			(xy 282.676854 -273.099784) (xy 282.67635 -273.125492) (xy 282.668307 -273.176274) (xy 282.652419 -273.225173)
			(xy 282.629076 -273.270985) (xy 282.598855 -273.312581) (xy 282.562499 -273.348937) (xy 282.520903 -273.379158)
			(xy 282.475091 -273.402501) (xy 282.426192 -273.418389) (xy 282.37541 -273.426432) (xy 282.323994 -273.426432)
			(xy 282.273212 -273.418389) (xy 282.224313 -273.402501) (xy 282.178501 -273.379158) (xy 282.136905 -273.348937)
			(xy 282.100549 -273.312581) (xy 282.070328 -273.270985) (xy 282.046985 -273.225173) (xy 282.031097 -273.176274)
			(xy 282.023054 -273.125492) (xy 281.704376 -273.125492) (xy 281.69666 -273.172968) (xy 281.681076 -273.219649)
			(xy 281.658205 -273.263226) (xy 281.62864 -273.30257) (xy 281.593147 -273.336662) (xy 281.552644 -273.364618)
			(xy 281.508182 -273.385716) (xy 281.460911 -273.399408) (xy 281.412056 -273.40534) (xy 281.362881 -273.403359)
			(xy 281.314662 -273.393515) (xy 281.268646 -273.376063) (xy 281.226025 -273.351456) (xy 281.187904 -273.320331)
			(xy 281.155269 -273.283494) (xy 281.128966 -273.241898) (xy 281.109675 -273.196622) (xy 281.097898 -273.148838)
			(xy 281.093938 -273.099784) (xy 280.776934 -273.099784) (xy 280.77643 -273.125492) (xy 280.768387 -273.176274)
			(xy 280.752499 -273.225173) (xy 280.729156 -273.270985) (xy 280.698935 -273.312581) (xy 280.662579 -273.348937)
			(xy 280.620983 -273.379158) (xy 280.575171 -273.402501) (xy 280.526272 -273.418389) (xy 280.47549 -273.426432)
			(xy 280.424074 -273.426432) (xy 280.373292 -273.418389) (xy 280.324393 -273.402501) (xy 280.278581 -273.379158)
			(xy 280.236985 -273.348937) (xy 280.200629 -273.312581) (xy 280.170408 -273.270985) (xy 280.147065 -273.225173)
			(xy 280.131177 -273.176274) (xy 280.123134 -273.125492) (xy 279.804456 -273.125492) (xy 279.79674 -273.172968)
			(xy 279.781156 -273.219649) (xy 279.758285 -273.263226) (xy 279.72872 -273.30257) (xy 279.693227 -273.336662)
			(xy 279.652724 -273.364618) (xy 279.608262 -273.385716) (xy 279.560991 -273.399408) (xy 279.512136 -273.40534)
			(xy 279.462961 -273.403359) (xy 279.414742 -273.393515) (xy 279.368726 -273.376063) (xy 279.326105 -273.351456)
			(xy 279.287984 -273.320331) (xy 279.255349 -273.283494) (xy 279.229046 -273.241898) (xy 279.209755 -273.196622)
			(xy 279.197978 -273.148838) (xy 279.194018 -273.099784) (xy 278.877014 -273.099784) (xy 278.87651 -273.125492)
			(xy 278.868467 -273.176274) (xy 278.852579 -273.225173) (xy 278.829236 -273.270985) (xy 278.799015 -273.312581)
			(xy 278.762659 -273.348937) (xy 278.721063 -273.379158) (xy 278.675251 -273.402501) (xy 278.626352 -273.418389)
			(xy 278.57557 -273.426432) (xy 278.524154 -273.426432) (xy 278.473372 -273.418389) (xy 278.424473 -273.402501)
			(xy 278.378661 -273.379158) (xy 278.337065 -273.348937) (xy 278.300709 -273.312581) (xy 278.270488 -273.270985)
			(xy 278.247145 -273.225173) (xy 278.231257 -273.176274) (xy 278.223214 -273.125492) (xy 277.904536 -273.125492)
			(xy 277.89682 -273.172968) (xy 277.881236 -273.219649) (xy 277.858365 -273.263226) (xy 277.8288 -273.30257)
			(xy 277.793307 -273.336662) (xy 277.752804 -273.364618) (xy 277.708342 -273.385716) (xy 277.661071 -273.399408)
			(xy 277.612216 -273.40534) (xy 277.563041 -273.403359) (xy 277.514822 -273.393515) (xy 277.468806 -273.376063)
			(xy 277.426185 -273.351456) (xy 277.388064 -273.320331) (xy 277.355429 -273.283494) (xy 277.329126 -273.241898)
			(xy 277.309835 -273.196622) (xy 277.298058 -273.148838) (xy 277.294098 -273.099784) (xy 276.97684 -273.099784)
			(xy 276.976336 -273.125492) (xy 276.968293 -273.176274) (xy 276.952405 -273.225173) (xy 276.929062 -273.270985)
			(xy 276.898841 -273.312581) (xy 276.862485 -273.348937) (xy 276.820889 -273.379158) (xy 276.775077 -273.402501)
			(xy 276.726178 -273.418389) (xy 276.675396 -273.426432) (xy 276.62398 -273.426432) (xy 276.573198 -273.418389)
			(xy 276.524299 -273.402501) (xy 276.478487 -273.379158) (xy 276.436891 -273.348937) (xy 276.400535 -273.312581)
			(xy 276.370314 -273.270985) (xy 276.346971 -273.225173) (xy 276.331083 -273.176274) (xy 276.32304 -273.125492)
			(xy 266.046342 -273.125492) (xy 265.988583 -273.233055) (xy 265.889305 -273.401002) (xy 265.783216 -273.564733)
			(xy 265.776115 -273.574764) (xy 269.21893 -273.574764) (xy 269.22289 -273.52571) (xy 269.234667 -273.477926)
			(xy 269.253958 -273.43265) (xy 269.280261 -273.391054) (xy 269.312896 -273.354217) (xy 269.351017 -273.323092)
			(xy 269.393638 -273.298485) (xy 269.439654 -273.281033) (xy 269.487873 -273.271189) (xy 269.537048 -273.269208)
			(xy 269.585903 -273.27514) (xy 269.633174 -273.288832) (xy 269.677636 -273.30993) (xy 269.718139 -273.337886)
			(xy 269.753632 -273.371978) (xy 269.783197 -273.411322) (xy 269.806068 -273.454899) (xy 269.821652 -273.50158)
			(xy 269.829547 -273.550157) (xy 269.830042 -273.574764) (xy 270.16889 -273.574764) (xy 270.17285 -273.52571)
			(xy 270.184627 -273.477926) (xy 270.203918 -273.43265) (xy 270.230221 -273.391054) (xy 270.262856 -273.354217)
			(xy 270.300977 -273.323092) (xy 270.343598 -273.298485) (xy 270.389614 -273.281033) (xy 270.437833 -273.271189)
			(xy 270.487008 -273.269208) (xy 270.535863 -273.27514) (xy 270.583134 -273.288832) (xy 270.627596 -273.30993)
			(xy 270.668099 -273.337886) (xy 270.703592 -273.371978) (xy 270.733157 -273.411322) (xy 270.756028 -273.454899)
			(xy 270.771612 -273.50158) (xy 270.779507 -273.550157) (xy 270.780002 -273.574764) (xy 271.119104 -273.574764)
			(xy 271.123064 -273.52571) (xy 271.134841 -273.477926) (xy 271.154132 -273.43265) (xy 271.180435 -273.391054)
			(xy 271.21307 -273.354217) (xy 271.251191 -273.323092) (xy 271.293812 -273.298485) (xy 271.339828 -273.281033)
			(xy 271.388047 -273.271189) (xy 271.437222 -273.269208) (xy 271.486077 -273.27514) (xy 271.533348 -273.288832)
			(xy 271.57781 -273.30993) (xy 271.618313 -273.337886) (xy 271.653806 -273.371978) (xy 271.683371 -273.411322)
			(xy 271.706242 -273.454899) (xy 271.721826 -273.50158) (xy 271.729721 -273.550157) (xy 271.730216 -273.574764)
			(xy 272.069064 -273.574764) (xy 272.073024 -273.52571) (xy 272.084801 -273.477926) (xy 272.104092 -273.43265)
			(xy 272.130395 -273.391054) (xy 272.16303 -273.354217) (xy 272.201151 -273.323092) (xy 272.243772 -273.298485)
			(xy 272.289788 -273.281033) (xy 272.338007 -273.271189) (xy 272.387182 -273.269208) (xy 272.436037 -273.27514)
			(xy 272.483308 -273.288832) (xy 272.52777 -273.30993) (xy 272.568273 -273.337886) (xy 272.603766 -273.371978)
			(xy 272.633331 -273.411322) (xy 272.656202 -273.454899) (xy 272.671786 -273.50158) (xy 272.679681 -273.550157)
			(xy 272.680176 -273.574764) (xy 273.019024 -273.574764) (xy 273.022984 -273.52571) (xy 273.034761 -273.477926)
			(xy 273.054052 -273.43265) (xy 273.080355 -273.391054) (xy 273.11299 -273.354217) (xy 273.151111 -273.323092)
			(xy 273.193732 -273.298485) (xy 273.239748 -273.281033) (xy 273.287967 -273.271189) (xy 273.337142 -273.269208)
			(xy 273.385997 -273.27514) (xy 273.433268 -273.288832) (xy 273.47773 -273.30993) (xy 273.518233 -273.337886)
			(xy 273.553726 -273.371978) (xy 273.583291 -273.411322) (xy 273.606162 -273.454899) (xy 273.621746 -273.50158)
			(xy 273.629641 -273.550157) (xy 273.630136 -273.574764) (xy 273.968984 -273.574764) (xy 273.972944 -273.52571)
			(xy 273.984721 -273.477926) (xy 274.004012 -273.43265) (xy 274.030315 -273.391054) (xy 274.06295 -273.354217)
			(xy 274.101071 -273.323092) (xy 274.143692 -273.298485) (xy 274.189708 -273.281033) (xy 274.237927 -273.271189)
			(xy 274.287102 -273.269208) (xy 274.335957 -273.27514) (xy 274.383228 -273.288832) (xy 274.42769 -273.30993)
			(xy 274.468193 -273.337886) (xy 274.503686 -273.371978) (xy 274.533251 -273.411322) (xy 274.556122 -273.454899)
			(xy 274.571706 -273.50158) (xy 274.579601 -273.550157) (xy 274.580096 -273.574764) (xy 274.918944 -273.574764)
			(xy 274.922904 -273.52571) (xy 274.934681 -273.477926) (xy 274.953972 -273.43265) (xy 274.980275 -273.391054)
			(xy 275.01291 -273.354217) (xy 275.051031 -273.323092) (xy 275.093652 -273.298485) (xy 275.139668 -273.281033)
			(xy 275.187887 -273.271189) (xy 275.237062 -273.269208) (xy 275.285917 -273.27514) (xy 275.333188 -273.288832)
			(xy 275.37765 -273.30993) (xy 275.418153 -273.337886) (xy 275.453646 -273.371978) (xy 275.483211 -273.411322)
			(xy 275.506082 -273.454899) (xy 275.521666 -273.50158) (xy 275.529561 -273.550157) (xy 275.530056 -273.574764)
			(xy 275.529561 -273.599371) (xy 275.521666 -273.647948) (xy 275.506082 -273.694629) (xy 275.483211 -273.738206)
			(xy 275.453646 -273.77755) (xy 275.418153 -273.811642) (xy 275.37765 -273.839598) (xy 275.333188 -273.860696)
			(xy 275.285917 -273.874388) (xy 275.237062 -273.88032) (xy 275.187887 -273.878339) (xy 275.139668 -273.868495)
			(xy 275.093652 -273.851043) (xy 275.051031 -273.826436) (xy 275.01291 -273.795311) (xy 274.980275 -273.758474)
			(xy 274.953972 -273.716878) (xy 274.934681 -273.671602) (xy 274.922904 -273.623818) (xy 274.918944 -273.574764)
			(xy 274.580096 -273.574764) (xy 274.579601 -273.599371) (xy 274.571706 -273.647948) (xy 274.556122 -273.694629)
			(xy 274.533251 -273.738206) (xy 274.503686 -273.77755) (xy 274.468193 -273.811642) (xy 274.42769 -273.839598)
			(xy 274.383228 -273.860696) (xy 274.335957 -273.874388) (xy 274.287102 -273.88032) (xy 274.237927 -273.878339)
			(xy 274.189708 -273.868495) (xy 274.143692 -273.851043) (xy 274.101071 -273.826436) (xy 274.06295 -273.795311)
			(xy 274.030315 -273.758474) (xy 274.004012 -273.716878) (xy 273.984721 -273.671602) (xy 273.972944 -273.623818)
			(xy 273.968984 -273.574764) (xy 273.630136 -273.574764) (xy 273.629641 -273.599371) (xy 273.621746 -273.647948)
			(xy 273.606162 -273.694629) (xy 273.583291 -273.738206) (xy 273.553726 -273.77755) (xy 273.518233 -273.811642)
			(xy 273.47773 -273.839598) (xy 273.433268 -273.860696) (xy 273.385997 -273.874388) (xy 273.337142 -273.88032)
			(xy 273.287967 -273.878339) (xy 273.239748 -273.868495) (xy 273.193732 -273.851043) (xy 273.151111 -273.826436)
			(xy 273.11299 -273.795311) (xy 273.080355 -273.758474) (xy 273.054052 -273.716878) (xy 273.034761 -273.671602)
			(xy 273.022984 -273.623818) (xy 273.019024 -273.574764) (xy 272.680176 -273.574764) (xy 272.679681 -273.599371)
			(xy 272.671786 -273.647948) (xy 272.656202 -273.694629) (xy 272.633331 -273.738206) (xy 272.603766 -273.77755)
			(xy 272.568273 -273.811642) (xy 272.52777 -273.839598) (xy 272.483308 -273.860696) (xy 272.436037 -273.874388)
			(xy 272.387182 -273.88032) (xy 272.338007 -273.878339) (xy 272.289788 -273.868495) (xy 272.243772 -273.851043)
			(xy 272.201151 -273.826436) (xy 272.16303 -273.795311) (xy 272.130395 -273.758474) (xy 272.104092 -273.716878)
			(xy 272.084801 -273.671602) (xy 272.073024 -273.623818) (xy 272.069064 -273.574764) (xy 271.730216 -273.574764)
			(xy 271.729721 -273.599371) (xy 271.721826 -273.647948) (xy 271.706242 -273.694629) (xy 271.683371 -273.738206)
			(xy 271.653806 -273.77755) (xy 271.618313 -273.811642) (xy 271.57781 -273.839598) (xy 271.533348 -273.860696)
			(xy 271.486077 -273.874388) (xy 271.437222 -273.88032) (xy 271.388047 -273.878339) (xy 271.339828 -273.868495)
			(xy 271.293812 -273.851043) (xy 271.251191 -273.826436) (xy 271.21307 -273.795311) (xy 271.180435 -273.758474)
			(xy 271.154132 -273.716878) (xy 271.134841 -273.671602) (xy 271.123064 -273.623818) (xy 271.119104 -273.574764)
			(xy 270.780002 -273.574764) (xy 270.779507 -273.599371) (xy 270.771612 -273.647948) (xy 270.756028 -273.694629)
			(xy 270.733157 -273.738206) (xy 270.703592 -273.77755) (xy 270.668099 -273.811642) (xy 270.627596 -273.839598)
			(xy 270.583134 -273.860696) (xy 270.535863 -273.874388) (xy 270.487008 -273.88032) (xy 270.437833 -273.878339)
			(xy 270.389614 -273.868495) (xy 270.343598 -273.851043) (xy 270.300977 -273.826436) (xy 270.262856 -273.795311)
			(xy 270.230221 -273.758474) (xy 270.203918 -273.716878) (xy 270.184627 -273.671602) (xy 270.17285 -273.623818)
			(xy 270.16889 -273.574764) (xy 269.830042 -273.574764) (xy 269.829547 -273.599371) (xy 269.821652 -273.647948)
			(xy 269.806068 -273.694629) (xy 269.783197 -273.738206) (xy 269.753632 -273.77755) (xy 269.718139 -273.811642)
			(xy 269.677636 -273.839598) (xy 269.633174 -273.860696) (xy 269.585903 -273.874388) (xy 269.537048 -273.88032)
			(xy 269.487873 -273.878339) (xy 269.439654 -273.868495) (xy 269.393638 -273.851043) (xy 269.351017 -273.826436)
			(xy 269.312896 -273.795311) (xy 269.280261 -273.758474) (xy 269.253958 -273.716878) (xy 269.234667 -273.671602)
			(xy 269.22289 -273.623818) (xy 269.21893 -273.574764) (xy 265.776115 -273.574764) (xy 265.670495 -273.72397)
			(xy 265.551331 -273.878444) (xy 265.425926 -274.027897) (xy 265.382574 -274.075452) (xy 276.32304 -274.075452)
			(xy 276.32304 -274.024036) (xy 276.331083 -273.973254) (xy 276.346971 -273.924355) (xy 276.370314 -273.878543)
			(xy 276.400535 -273.836947) (xy 276.436891 -273.800591) (xy 276.478487 -273.77037) (xy 276.524299 -273.747027)
			(xy 276.573198 -273.731139) (xy 276.62398 -273.723096) (xy 276.675396 -273.723096) (xy 276.726178 -273.731139)
			(xy 276.775077 -273.747027) (xy 276.820889 -273.77037) (xy 276.862485 -273.800591) (xy 276.898841 -273.836947)
			(xy 276.929062 -273.878543) (xy 276.952405 -273.924355) (xy 276.968293 -273.973254) (xy 276.976336 -274.024036)
			(xy 276.97684 -274.049744) (xy 277.294098 -274.049744) (xy 277.298058 -274.00069) (xy 277.309835 -273.952906)
			(xy 277.329126 -273.90763) (xy 277.355429 -273.866034) (xy 277.388064 -273.829197) (xy 277.426185 -273.798072)
			(xy 277.468806 -273.773465) (xy 277.514822 -273.756013) (xy 277.563041 -273.746169) (xy 277.612216 -273.744188)
			(xy 277.661071 -273.75012) (xy 277.708342 -273.763812) (xy 277.752804 -273.78491) (xy 277.793307 -273.812866)
			(xy 277.8288 -273.846958) (xy 277.858365 -273.886302) (xy 277.881236 -273.929879) (xy 277.89682 -273.97656)
			(xy 277.904715 -274.025137) (xy 277.90521 -274.049744) (xy 277.904715 -274.074351) (xy 277.904536 -274.075452)
			(xy 278.223214 -274.075452) (xy 278.223214 -274.024036) (xy 278.231257 -273.973254) (xy 278.247145 -273.924355)
			(xy 278.270488 -273.878543) (xy 278.300709 -273.836947) (xy 278.337065 -273.800591) (xy 278.378661 -273.77037)
			(xy 278.424473 -273.747027) (xy 278.473372 -273.731139) (xy 278.524154 -273.723096) (xy 278.57557 -273.723096)
			(xy 278.626352 -273.731139) (xy 278.675251 -273.747027) (xy 278.721063 -273.77037) (xy 278.762659 -273.800591)
			(xy 278.799015 -273.836947) (xy 278.829236 -273.878543) (xy 278.852579 -273.924355) (xy 278.868467 -273.973254)
			(xy 278.87651 -274.024036) (xy 278.877014 -274.049744) (xy 279.194018 -274.049744) (xy 279.197978 -274.00069)
			(xy 279.209755 -273.952906) (xy 279.229046 -273.90763) (xy 279.255349 -273.866034) (xy 279.287984 -273.829197)
			(xy 279.326105 -273.798072) (xy 279.368726 -273.773465) (xy 279.414742 -273.756013) (xy 279.462961 -273.746169)
			(xy 279.512136 -273.744188) (xy 279.560991 -273.75012) (xy 279.608262 -273.763812) (xy 279.652724 -273.78491)
			(xy 279.693227 -273.812866) (xy 279.72872 -273.846958) (xy 279.758285 -273.886302) (xy 279.781156 -273.929879)
			(xy 279.79674 -273.97656) (xy 279.804635 -274.025137) (xy 279.80513 -274.049744) (xy 279.804635 -274.074351)
			(xy 279.804456 -274.075452) (xy 280.123134 -274.075452) (xy 280.123134 -274.024036) (xy 280.131177 -273.973254)
			(xy 280.147065 -273.924355) (xy 280.170408 -273.878543) (xy 280.200629 -273.836947) (xy 280.236985 -273.800591)
			(xy 280.278581 -273.77037) (xy 280.324393 -273.747027) (xy 280.373292 -273.731139) (xy 280.424074 -273.723096)
			(xy 280.47549 -273.723096) (xy 280.526272 -273.731139) (xy 280.575171 -273.747027) (xy 280.620983 -273.77037)
			(xy 280.662579 -273.800591) (xy 280.698935 -273.836947) (xy 280.729156 -273.878543) (xy 280.752499 -273.924355)
			(xy 280.768387 -273.973254) (xy 280.77643 -274.024036) (xy 280.776934 -274.049744) (xy 281.093938 -274.049744)
			(xy 281.097898 -274.00069) (xy 281.109675 -273.952906) (xy 281.128966 -273.90763) (xy 281.155269 -273.866034)
			(xy 281.187904 -273.829197) (xy 281.226025 -273.798072) (xy 281.268646 -273.773465) (xy 281.314662 -273.756013)
			(xy 281.362881 -273.746169) (xy 281.412056 -273.744188) (xy 281.460911 -273.75012) (xy 281.508182 -273.763812)
			(xy 281.552644 -273.78491) (xy 281.593147 -273.812866) (xy 281.62864 -273.846958) (xy 281.658205 -273.886302)
			(xy 281.681076 -273.929879) (xy 281.69666 -273.97656) (xy 281.704555 -274.025137) (xy 281.70505 -274.049744)
			(xy 281.704555 -274.074351) (xy 281.704376 -274.075452) (xy 282.023054 -274.075452) (xy 282.023054 -274.024036)
			(xy 282.031097 -273.973254) (xy 282.046985 -273.924355) (xy 282.070328 -273.878543) (xy 282.100549 -273.836947)
			(xy 282.136905 -273.800591) (xy 282.178501 -273.77037) (xy 282.224313 -273.747027) (xy 282.273212 -273.731139)
			(xy 282.323994 -273.723096) (xy 282.37541 -273.723096) (xy 282.426192 -273.731139) (xy 282.475091 -273.747027)
			(xy 282.520903 -273.77037) (xy 282.562499 -273.800591) (xy 282.598855 -273.836947) (xy 282.629076 -273.878543)
			(xy 282.652419 -273.924355) (xy 282.668307 -273.973254) (xy 282.67635 -274.024036) (xy 282.676854 -274.049744)
			(xy 282.994112 -274.049744) (xy 282.998072 -274.00069) (xy 283.009849 -273.952906) (xy 283.02914 -273.90763)
			(xy 283.055443 -273.866034) (xy 283.088078 -273.829197) (xy 283.126199 -273.798072) (xy 283.16882 -273.773465)
			(xy 283.214836 -273.756013) (xy 283.263055 -273.746169) (xy 283.31223 -273.744188) (xy 283.361085 -273.75012)
			(xy 283.408356 -273.763812) (xy 283.452818 -273.78491) (xy 283.493321 -273.812866) (xy 283.528814 -273.846958)
			(xy 283.558379 -273.886302) (xy 283.58125 -273.929879) (xy 283.596834 -273.97656) (xy 283.604729 -274.025137)
			(xy 283.605224 -274.049744) (xy 283.604729 -274.074351) (xy 283.60455 -274.075452) (xy 283.923228 -274.075452)
			(xy 283.923228 -274.024036) (xy 283.931271 -273.973254) (xy 283.947159 -273.924355) (xy 283.970502 -273.878543)
			(xy 284.000723 -273.836947) (xy 284.037079 -273.800591) (xy 284.078675 -273.77037) (xy 284.124487 -273.747027)
			(xy 284.173386 -273.731139) (xy 284.224168 -273.723096) (xy 284.275584 -273.723096) (xy 284.326366 -273.731139)
			(xy 284.375265 -273.747027) (xy 284.421077 -273.77037) (xy 284.462673 -273.800591) (xy 284.499029 -273.836947)
			(xy 284.52925 -273.878543) (xy 284.552593 -273.924355) (xy 284.568481 -273.973254) (xy 284.576524 -274.024036)
			(xy 284.577028 -274.049744) (xy 284.894032 -274.049744) (xy 284.897992 -274.00069) (xy 284.909769 -273.952906)
			(xy 284.92906 -273.90763) (xy 284.955363 -273.866034) (xy 284.987998 -273.829197) (xy 285.026119 -273.798072)
			(xy 285.06874 -273.773465) (xy 285.114756 -273.756013) (xy 285.162975 -273.746169) (xy 285.21215 -273.744188)
			(xy 285.261005 -273.75012) (xy 285.308276 -273.763812) (xy 285.352738 -273.78491) (xy 285.393241 -273.812866)
			(xy 285.428734 -273.846958) (xy 285.458299 -273.886302) (xy 285.48117 -273.929879) (xy 285.496754 -273.97656)
			(xy 285.504649 -274.025137) (xy 285.505144 -274.049744) (xy 285.504649 -274.074351) (xy 285.50447 -274.075452)
			(xy 285.823148 -274.075452) (xy 285.823148 -274.024036) (xy 285.831191 -273.973254) (xy 285.847079 -273.924355)
			(xy 285.870422 -273.878543) (xy 285.900643 -273.836947) (xy 285.936999 -273.800591) (xy 285.978595 -273.77037)
			(xy 286.024407 -273.747027) (xy 286.073306 -273.731139) (xy 286.124088 -273.723096) (xy 286.175504 -273.723096)
			(xy 286.226286 -273.731139) (xy 286.275185 -273.747027) (xy 286.320997 -273.77037) (xy 286.362593 -273.800591)
			(xy 286.398949 -273.836947) (xy 286.42917 -273.878543) (xy 286.452513 -273.924355) (xy 286.468401 -273.973254)
			(xy 286.476444 -274.024036) (xy 286.476948 -274.049744) (xy 286.793952 -274.049744) (xy 286.797912 -274.00069)
			(xy 286.809689 -273.952906) (xy 286.82898 -273.90763) (xy 286.855283 -273.866034) (xy 286.887918 -273.829197)
			(xy 286.926039 -273.798072) (xy 286.96866 -273.773465) (xy 287.014676 -273.756013) (xy 287.062895 -273.746169)
			(xy 287.11207 -273.744188) (xy 287.160925 -273.75012) (xy 287.208196 -273.763812) (xy 287.252658 -273.78491)
			(xy 287.293161 -273.812866) (xy 287.328654 -273.846958) (xy 287.358219 -273.886302) (xy 287.38109 -273.929879)
			(xy 287.396674 -273.97656) (xy 287.404569 -274.025137) (xy 287.405064 -274.049744) (xy 287.404569 -274.074351)
			(xy 287.40439 -274.075452) (xy 287.723068 -274.075452) (xy 287.723068 -274.024036) (xy 287.731111 -273.973254)
			(xy 287.746999 -273.924355) (xy 287.770342 -273.878543) (xy 287.800563 -273.836947) (xy 287.836919 -273.800591)
			(xy 287.878515 -273.77037) (xy 287.924327 -273.747027) (xy 287.973226 -273.731139) (xy 288.024008 -273.723096)
			(xy 288.075424 -273.723096) (xy 288.126206 -273.731139) (xy 288.175105 -273.747027) (xy 288.220917 -273.77037)
			(xy 288.262513 -273.800591) (xy 288.298869 -273.836947) (xy 288.32909 -273.878543) (xy 288.352433 -273.924355)
			(xy 288.368321 -273.973254) (xy 288.376364 -274.024036) (xy 288.376868 -274.049744) (xy 288.694126 -274.049744)
			(xy 288.698086 -274.00069) (xy 288.709863 -273.952906) (xy 288.729154 -273.90763) (xy 288.755457 -273.866034)
			(xy 288.788092 -273.829197) (xy 288.826213 -273.798072) (xy 288.868834 -273.773465) (xy 288.91485 -273.756013)
			(xy 288.963069 -273.746169) (xy 289.012244 -273.744188) (xy 289.061099 -273.75012) (xy 289.10837 -273.763812)
			(xy 289.152832 -273.78491) (xy 289.193335 -273.812866) (xy 289.228828 -273.846958) (xy 289.258393 -273.886302)
			(xy 289.281264 -273.929879) (xy 289.296848 -273.97656) (xy 289.304743 -274.025137) (xy 289.305238 -274.049744)
			(xy 289.304743 -274.074351) (xy 289.296848 -274.122928) (xy 289.281264 -274.169609) (xy 289.258393 -274.213186)
			(xy 289.228828 -274.25253) (xy 289.193335 -274.286622) (xy 289.152832 -274.314578) (xy 289.10837 -274.335676)
			(xy 289.061099 -274.349368) (xy 289.012244 -274.3553) (xy 288.963069 -274.353319) (xy 288.91485 -274.343475)
			(xy 288.868834 -274.326023) (xy 288.826213 -274.301416) (xy 288.788092 -274.270291) (xy 288.755457 -274.233454)
			(xy 288.729154 -274.191858) (xy 288.709863 -274.146582) (xy 288.698086 -274.098798) (xy 288.694126 -274.049744)
			(xy 288.376868 -274.049744) (xy 288.376364 -274.075452) (xy 288.368321 -274.126234) (xy 288.352433 -274.175133)
			(xy 288.32909 -274.220945) (xy 288.298869 -274.262541) (xy 288.262513 -274.298897) (xy 288.220917 -274.329118)
			(xy 288.175105 -274.352461) (xy 288.126206 -274.368349) (xy 288.075424 -274.376392) (xy 288.024008 -274.376392)
			(xy 287.973226 -274.368349) (xy 287.924327 -274.352461) (xy 287.878515 -274.329118) (xy 287.836919 -274.298897)
			(xy 287.800563 -274.262541) (xy 287.770342 -274.220945) (xy 287.746999 -274.175133) (xy 287.731111 -274.126234)
			(xy 287.723068 -274.075452) (xy 287.40439 -274.075452) (xy 287.396674 -274.122928) (xy 287.38109 -274.169609)
			(xy 287.358219 -274.213186) (xy 287.328654 -274.25253) (xy 287.293161 -274.286622) (xy 287.252658 -274.314578)
			(xy 287.208196 -274.335676) (xy 287.160925 -274.349368) (xy 287.11207 -274.3553) (xy 287.062895 -274.353319)
			(xy 287.014676 -274.343475) (xy 286.96866 -274.326023) (xy 286.926039 -274.301416) (xy 286.887918 -274.270291)
			(xy 286.855283 -274.233454) (xy 286.82898 -274.191858) (xy 286.809689 -274.146582) (xy 286.797912 -274.098798)
			(xy 286.793952 -274.049744) (xy 286.476948 -274.049744) (xy 286.476444 -274.075452) (xy 286.468401 -274.126234)
			(xy 286.452513 -274.175133) (xy 286.42917 -274.220945) (xy 286.398949 -274.262541) (xy 286.362593 -274.298897)
			(xy 286.320997 -274.329118) (xy 286.275185 -274.352461) (xy 286.226286 -274.368349) (xy 286.175504 -274.376392)
			(xy 286.124088 -274.376392) (xy 286.073306 -274.368349) (xy 286.024407 -274.352461) (xy 285.978595 -274.329118)
			(xy 285.936999 -274.298897) (xy 285.900643 -274.262541) (xy 285.870422 -274.220945) (xy 285.847079 -274.175133)
			(xy 285.831191 -274.126234) (xy 285.823148 -274.075452) (xy 285.50447 -274.075452) (xy 285.496754 -274.122928)
			(xy 285.48117 -274.169609) (xy 285.458299 -274.213186) (xy 285.428734 -274.25253) (xy 285.393241 -274.286622)
			(xy 285.352738 -274.314578) (xy 285.308276 -274.335676) (xy 285.261005 -274.349368) (xy 285.21215 -274.3553)
			(xy 285.162975 -274.353319) (xy 285.114756 -274.343475) (xy 285.06874 -274.326023) (xy 285.026119 -274.301416)
			(xy 284.987998 -274.270291) (xy 284.955363 -274.233454) (xy 284.92906 -274.191858) (xy 284.909769 -274.146582)
			(xy 284.897992 -274.098798) (xy 284.894032 -274.049744) (xy 284.577028 -274.049744) (xy 284.576524 -274.075452)
			(xy 284.568481 -274.126234) (xy 284.552593 -274.175133) (xy 284.52925 -274.220945) (xy 284.499029 -274.262541)
			(xy 284.462673 -274.298897) (xy 284.421077 -274.329118) (xy 284.375265 -274.352461) (xy 284.326366 -274.368349)
			(xy 284.275584 -274.376392) (xy 284.224168 -274.376392) (xy 284.173386 -274.368349) (xy 284.124487 -274.352461)
			(xy 284.078675 -274.329118) (xy 284.037079 -274.298897) (xy 284.000723 -274.262541) (xy 283.970502 -274.220945)
			(xy 283.947159 -274.175133) (xy 283.931271 -274.126234) (xy 283.923228 -274.075452) (xy 283.60455 -274.075452)
			(xy 283.596834 -274.122928) (xy 283.58125 -274.169609) (xy 283.558379 -274.213186) (xy 283.528814 -274.25253)
			(xy 283.493321 -274.286622) (xy 283.452818 -274.314578) (xy 283.408356 -274.335676) (xy 283.361085 -274.349368)
			(xy 283.31223 -274.3553) (xy 283.263055 -274.353319) (xy 283.214836 -274.343475) (xy 283.16882 -274.326023)
			(xy 283.126199 -274.301416) (xy 283.088078 -274.270291) (xy 283.055443 -274.233454) (xy 283.02914 -274.191858)
			(xy 283.009849 -274.146582) (xy 282.998072 -274.098798) (xy 282.994112 -274.049744) (xy 282.676854 -274.049744)
			(xy 282.67635 -274.075452) (xy 282.668307 -274.126234) (xy 282.652419 -274.175133) (xy 282.629076 -274.220945)
			(xy 282.598855 -274.262541) (xy 282.562499 -274.298897) (xy 282.520903 -274.329118) (xy 282.475091 -274.352461)
			(xy 282.426192 -274.368349) (xy 282.37541 -274.376392) (xy 282.323994 -274.376392) (xy 282.273212 -274.368349)
			(xy 282.224313 -274.352461) (xy 282.178501 -274.329118) (xy 282.136905 -274.298897) (xy 282.100549 -274.262541)
			(xy 282.070328 -274.220945) (xy 282.046985 -274.175133) (xy 282.031097 -274.126234) (xy 282.023054 -274.075452)
			(xy 281.704376 -274.075452) (xy 281.69666 -274.122928) (xy 281.681076 -274.169609) (xy 281.658205 -274.213186)
			(xy 281.62864 -274.25253) (xy 281.593147 -274.286622) (xy 281.552644 -274.314578) (xy 281.508182 -274.335676)
			(xy 281.460911 -274.349368) (xy 281.412056 -274.3553) (xy 281.362881 -274.353319) (xy 281.314662 -274.343475)
			(xy 281.268646 -274.326023) (xy 281.226025 -274.301416) (xy 281.187904 -274.270291) (xy 281.155269 -274.233454)
			(xy 281.128966 -274.191858) (xy 281.109675 -274.146582) (xy 281.097898 -274.098798) (xy 281.093938 -274.049744)
			(xy 280.776934 -274.049744) (xy 280.77643 -274.075452) (xy 280.768387 -274.126234) (xy 280.752499 -274.175133)
			(xy 280.729156 -274.220945) (xy 280.698935 -274.262541) (xy 280.662579 -274.298897) (xy 280.620983 -274.329118)
			(xy 280.575171 -274.352461) (xy 280.526272 -274.368349) (xy 280.47549 -274.376392) (xy 280.424074 -274.376392)
			(xy 280.373292 -274.368349) (xy 280.324393 -274.352461) (xy 280.278581 -274.329118) (xy 280.236985 -274.298897)
			(xy 280.200629 -274.262541) (xy 280.170408 -274.220945) (xy 280.147065 -274.175133) (xy 280.131177 -274.126234)
			(xy 280.123134 -274.075452) (xy 279.804456 -274.075452) (xy 279.79674 -274.122928) (xy 279.781156 -274.169609)
			(xy 279.758285 -274.213186) (xy 279.72872 -274.25253) (xy 279.693227 -274.286622) (xy 279.652724 -274.314578)
			(xy 279.608262 -274.335676) (xy 279.560991 -274.349368) (xy 279.512136 -274.3553) (xy 279.462961 -274.353319)
			(xy 279.414742 -274.343475) (xy 279.368726 -274.326023) (xy 279.326105 -274.301416) (xy 279.287984 -274.270291)
			(xy 279.255349 -274.233454) (xy 279.229046 -274.191858) (xy 279.209755 -274.146582) (xy 279.197978 -274.098798)
			(xy 279.194018 -274.049744) (xy 278.877014 -274.049744) (xy 278.87651 -274.075452) (xy 278.868467 -274.126234)
			(xy 278.852579 -274.175133) (xy 278.829236 -274.220945) (xy 278.799015 -274.262541) (xy 278.762659 -274.298897)
			(xy 278.721063 -274.329118) (xy 278.675251 -274.352461) (xy 278.626352 -274.368349) (xy 278.57557 -274.376392)
			(xy 278.524154 -274.376392) (xy 278.473372 -274.368349) (xy 278.424473 -274.352461) (xy 278.378661 -274.329118)
			(xy 278.337065 -274.298897) (xy 278.300709 -274.262541) (xy 278.270488 -274.220945) (xy 278.247145 -274.175133)
			(xy 278.231257 -274.126234) (xy 278.223214 -274.075452) (xy 277.904536 -274.075452) (xy 277.89682 -274.122928)
			(xy 277.881236 -274.169609) (xy 277.858365 -274.213186) (xy 277.8288 -274.25253) (xy 277.793307 -274.286622)
			(xy 277.752804 -274.314578) (xy 277.708342 -274.335676) (xy 277.661071 -274.349368) (xy 277.612216 -274.3553)
			(xy 277.563041 -274.353319) (xy 277.514822 -274.343475) (xy 277.468806 -274.326023) (xy 277.426185 -274.301416)
			(xy 277.388064 -274.270291) (xy 277.355429 -274.233454) (xy 277.329126 -274.191858) (xy 277.309835 -274.146582)
			(xy 277.298058 -274.098798) (xy 277.294098 -274.049744) (xy 276.97684 -274.049744) (xy 276.976336 -274.075452)
			(xy 276.968293 -274.126234) (xy 276.952405 -274.175133) (xy 276.929062 -274.220945) (xy 276.898841 -274.262541)
			(xy 276.862485 -274.298897) (xy 276.820889 -274.329118) (xy 276.775077 -274.352461) (xy 276.726178 -274.368349)
			(xy 276.675396 -274.376392) (xy 276.62398 -274.376392) (xy 276.573198 -274.368349) (xy 276.524299 -274.352461)
			(xy 276.478487 -274.329118) (xy 276.436891 -274.298897) (xy 276.400535 -274.262541) (xy 276.370314 -274.220945)
			(xy 276.346971 -274.175133) (xy 276.331083 -274.126234) (xy 276.32304 -274.075452) (xy 265.382574 -274.075452)
			(xy 265.29449 -274.172075) (xy 265.157246 -274.310735) (xy 265.014425 -274.443643) (xy 264.919787 -274.524724)
			(xy 269.21893 -274.524724) (xy 269.22289 -274.47567) (xy 269.234667 -274.427886) (xy 269.253958 -274.38261)
			(xy 269.280261 -274.341014) (xy 269.312896 -274.304177) (xy 269.351017 -274.273052) (xy 269.393638 -274.248445)
			(xy 269.439654 -274.230993) (xy 269.487873 -274.221149) (xy 269.537048 -274.219168) (xy 269.585903 -274.2251)
			(xy 269.633174 -274.238792) (xy 269.677636 -274.25989) (xy 269.718139 -274.287846) (xy 269.753632 -274.321938)
			(xy 269.783197 -274.361282) (xy 269.806068 -274.404859) (xy 269.821652 -274.45154) (xy 269.829547 -274.500117)
			(xy 269.830042 -274.524724) (xy 269.830037 -274.524978) (xy 270.169144 -274.524978) (xy 270.173104 -274.475924)
			(xy 270.184881 -274.42814) (xy 270.204172 -274.382864) (xy 270.230475 -274.341268) (xy 270.26311 -274.304431)
			(xy 270.301231 -274.273306) (xy 270.343852 -274.248699) (xy 270.389868 -274.231247) (xy 270.438087 -274.221403)
			(xy 270.487262 -274.219422) (xy 270.536117 -274.225354) (xy 270.583388 -274.239046) (xy 270.62785 -274.260144)
			(xy 270.668353 -274.2881) (xy 270.703846 -274.322192) (xy 270.733411 -274.361536) (xy 270.756282 -274.405113)
			(xy 270.771866 -274.451794) (xy 270.779761 -274.500371) (xy 270.780256 -274.524978) (xy 271.119104 -274.524978)
			(xy 271.123064 -274.475924) (xy 271.134841 -274.42814) (xy 271.154132 -274.382864) (xy 271.180435 -274.341268)
			(xy 271.21307 -274.304431) (xy 271.251191 -274.273306) (xy 271.293812 -274.248699) (xy 271.339828 -274.231247)
			(xy 271.388047 -274.221403) (xy 271.437222 -274.219422) (xy 271.486077 -274.225354) (xy 271.533348 -274.239046)
			(xy 271.57781 -274.260144) (xy 271.618313 -274.2881) (xy 271.653806 -274.322192) (xy 271.683371 -274.361536)
			(xy 271.706242 -274.405113) (xy 271.721826 -274.451794) (xy 271.729721 -274.500371) (xy 271.730216 -274.524978)
			(xy 272.069064 -274.524978) (xy 272.073024 -274.475924) (xy 272.084801 -274.42814) (xy 272.104092 -274.382864)
			(xy 272.130395 -274.341268) (xy 272.16303 -274.304431) (xy 272.201151 -274.273306) (xy 272.243772 -274.248699)
			(xy 272.289788 -274.231247) (xy 272.338007 -274.221403) (xy 272.387182 -274.219422) (xy 272.436037 -274.225354)
			(xy 272.483308 -274.239046) (xy 272.52777 -274.260144) (xy 272.568273 -274.2881) (xy 272.603766 -274.322192)
			(xy 272.633331 -274.361536) (xy 272.656202 -274.405113) (xy 272.671786 -274.451794) (xy 272.679681 -274.500371)
			(xy 272.680176 -274.524978) (xy 273.019024 -274.524978) (xy 273.022984 -274.475924) (xy 273.034761 -274.42814)
			(xy 273.054052 -274.382864) (xy 273.080355 -274.341268) (xy 273.11299 -274.304431) (xy 273.151111 -274.273306)
			(xy 273.193732 -274.248699) (xy 273.239748 -274.231247) (xy 273.287967 -274.221403) (xy 273.337142 -274.219422)
			(xy 273.385997 -274.225354) (xy 273.433268 -274.239046) (xy 273.47773 -274.260144) (xy 273.518233 -274.2881)
			(xy 273.553726 -274.322192) (xy 273.583291 -274.361536) (xy 273.606162 -274.405113) (xy 273.621746 -274.451794)
			(xy 273.629641 -274.500371) (xy 273.630136 -274.524978) (xy 273.968984 -274.524978) (xy 273.972944 -274.475924)
			(xy 273.984721 -274.42814) (xy 274.004012 -274.382864) (xy 274.030315 -274.341268) (xy 274.06295 -274.304431)
			(xy 274.101071 -274.273306) (xy 274.143692 -274.248699) (xy 274.189708 -274.231247) (xy 274.237927 -274.221403)
			(xy 274.287102 -274.219422) (xy 274.335957 -274.225354) (xy 274.383228 -274.239046) (xy 274.42769 -274.260144)
			(xy 274.468193 -274.2881) (xy 274.503686 -274.322192) (xy 274.533251 -274.361536) (xy 274.556122 -274.405113)
			(xy 274.571706 -274.451794) (xy 274.579601 -274.500371) (xy 274.580096 -274.524978) (xy 274.918944 -274.524978)
			(xy 274.922904 -274.475924) (xy 274.934681 -274.42814) (xy 274.953972 -274.382864) (xy 274.980275 -274.341268)
			(xy 275.01291 -274.304431) (xy 275.051031 -274.273306) (xy 275.093652 -274.248699) (xy 275.139668 -274.231247)
			(xy 275.187887 -274.221403) (xy 275.237062 -274.219422) (xy 275.285917 -274.225354) (xy 275.333188 -274.239046)
			(xy 275.37765 -274.260144) (xy 275.418153 -274.2881) (xy 275.453646 -274.322192) (xy 275.483211 -274.361536)
			(xy 275.506082 -274.405113) (xy 275.521666 -274.451794) (xy 275.529561 -274.500371) (xy 275.530056 -274.524978)
			(xy 275.529561 -274.549585) (xy 275.521666 -274.598162) (xy 275.506082 -274.644843) (xy 275.483211 -274.68842)
			(xy 275.453646 -274.727764) (xy 275.418153 -274.761856) (xy 275.37765 -274.789812) (xy 275.333188 -274.81091)
			(xy 275.285917 -274.824602) (xy 275.237062 -274.830534) (xy 275.187887 -274.828553) (xy 275.139668 -274.818709)
			(xy 275.093652 -274.801257) (xy 275.051031 -274.77665) (xy 275.01291 -274.745525) (xy 274.980275 -274.708688)
			(xy 274.953972 -274.667092) (xy 274.934681 -274.621816) (xy 274.922904 -274.574032) (xy 274.918944 -274.524978)
			(xy 274.580096 -274.524978) (xy 274.579601 -274.549585) (xy 274.571706 -274.598162) (xy 274.556122 -274.644843)
			(xy 274.533251 -274.68842) (xy 274.503686 -274.727764) (xy 274.468193 -274.761856) (xy 274.42769 -274.789812)
			(xy 274.383228 -274.81091) (xy 274.335957 -274.824602) (xy 274.287102 -274.830534) (xy 274.237927 -274.828553)
			(xy 274.189708 -274.818709) (xy 274.143692 -274.801257) (xy 274.101071 -274.77665) (xy 274.06295 -274.745525)
			(xy 274.030315 -274.708688) (xy 274.004012 -274.667092) (xy 273.984721 -274.621816) (xy 273.972944 -274.574032)
			(xy 273.968984 -274.524978) (xy 273.630136 -274.524978) (xy 273.629641 -274.549585) (xy 273.621746 -274.598162)
			(xy 273.606162 -274.644843) (xy 273.583291 -274.68842) (xy 273.553726 -274.727764) (xy 273.518233 -274.761856)
			(xy 273.47773 -274.789812) (xy 273.433268 -274.81091) (xy 273.385997 -274.824602) (xy 273.337142 -274.830534)
			(xy 273.287967 -274.828553) (xy 273.239748 -274.818709) (xy 273.193732 -274.801257) (xy 273.151111 -274.77665)
			(xy 273.11299 -274.745525) (xy 273.080355 -274.708688) (xy 273.054052 -274.667092) (xy 273.034761 -274.621816)
			(xy 273.022984 -274.574032) (xy 273.019024 -274.524978) (xy 272.680176 -274.524978) (xy 272.679681 -274.549585)
			(xy 272.671786 -274.598162) (xy 272.656202 -274.644843) (xy 272.633331 -274.68842) (xy 272.603766 -274.727764)
			(xy 272.568273 -274.761856) (xy 272.52777 -274.789812) (xy 272.483308 -274.81091) (xy 272.436037 -274.824602)
			(xy 272.387182 -274.830534) (xy 272.338007 -274.828553) (xy 272.289788 -274.818709) (xy 272.243772 -274.801257)
			(xy 272.201151 -274.77665) (xy 272.16303 -274.745525) (xy 272.130395 -274.708688) (xy 272.104092 -274.667092)
			(xy 272.084801 -274.621816) (xy 272.073024 -274.574032) (xy 272.069064 -274.524978) (xy 271.730216 -274.524978)
			(xy 271.729721 -274.549585) (xy 271.721826 -274.598162) (xy 271.706242 -274.644843) (xy 271.683371 -274.68842)
			(xy 271.653806 -274.727764) (xy 271.618313 -274.761856) (xy 271.57781 -274.789812) (xy 271.533348 -274.81091)
			(xy 271.486077 -274.824602) (xy 271.437222 -274.830534) (xy 271.388047 -274.828553) (xy 271.339828 -274.818709)
			(xy 271.293812 -274.801257) (xy 271.251191 -274.77665) (xy 271.21307 -274.745525) (xy 271.180435 -274.708688)
			(xy 271.154132 -274.667092) (xy 271.134841 -274.621816) (xy 271.123064 -274.574032) (xy 271.119104 -274.524978)
			(xy 270.780256 -274.524978) (xy 270.779761 -274.549585) (xy 270.771866 -274.598162) (xy 270.756282 -274.644843)
			(xy 270.733411 -274.68842) (xy 270.703846 -274.727764) (xy 270.668353 -274.761856) (xy 270.62785 -274.789812)
			(xy 270.583388 -274.81091) (xy 270.536117 -274.824602) (xy 270.487262 -274.830534) (xy 270.438087 -274.828553)
			(xy 270.389868 -274.818709) (xy 270.343852 -274.801257) (xy 270.301231 -274.77665) (xy 270.26311 -274.745525)
			(xy 270.230475 -274.708688) (xy 270.204172 -274.667092) (xy 270.184881 -274.621816) (xy 270.173104 -274.574032)
			(xy 270.169144 -274.524978) (xy 269.830037 -274.524978) (xy 269.829547 -274.549331) (xy 269.821652 -274.597908)
			(xy 269.806068 -274.644589) (xy 269.783197 -274.688166) (xy 269.753632 -274.72751) (xy 269.718139 -274.761602)
			(xy 269.677636 -274.789558) (xy 269.633174 -274.810656) (xy 269.585903 -274.824348) (xy 269.537048 -274.83028)
			(xy 269.487873 -274.828299) (xy 269.439654 -274.818455) (xy 269.393638 -274.801003) (xy 269.351017 -274.776396)
			(xy 269.312896 -274.745271) (xy 269.280261 -274.708434) (xy 269.253958 -274.666838) (xy 269.234667 -274.621562)
			(xy 269.22289 -274.573778) (xy 269.21893 -274.524724) (xy 264.919787 -274.524724) (xy 264.866268 -274.570577)
			(xy 264.713025 -274.69132) (xy 264.554954 -274.80567) (xy 264.392321 -274.913435) (xy 264.249322 -274.999958)
			(xy 276.343884 -274.999958) (xy 276.347844 -274.950904) (xy 276.359621 -274.90312) (xy 276.378912 -274.857844)
			(xy 276.405215 -274.816248) (xy 276.43785 -274.779411) (xy 276.475971 -274.748286) (xy 276.518592 -274.723679)
			(xy 276.564608 -274.706227) (xy 276.612827 -274.696383) (xy 276.662002 -274.694402) (xy 276.710857 -274.700334)
			(xy 276.758128 -274.714026) (xy 276.80259 -274.735124) (xy 276.843093 -274.76308) (xy 276.878586 -274.797172)
			(xy 276.908151 -274.836516) (xy 276.931022 -274.880093) (xy 276.946606 -274.926774) (xy 276.954501 -274.975351)
			(xy 276.954996 -274.999958) (xy 276.954501 -275.024565) (xy 276.954322 -275.025666) (xy 277.273254 -275.025666)
			(xy 277.273254 -274.97425) (xy 277.281297 -274.923468) (xy 277.297185 -274.874569) (xy 277.320528 -274.828757)
			(xy 277.350749 -274.787161) (xy 277.387105 -274.750805) (xy 277.428701 -274.720584) (xy 277.474513 -274.697241)
			(xy 277.523412 -274.681353) (xy 277.574194 -274.67331) (xy 277.62561 -274.67331) (xy 277.676392 -274.681353)
			(xy 277.725291 -274.697241) (xy 277.771103 -274.720584) (xy 277.812699 -274.750805) (xy 277.849055 -274.787161)
			(xy 277.879276 -274.828757) (xy 277.902619 -274.874569) (xy 277.918507 -274.923468) (xy 277.92655 -274.97425)
			(xy 277.927054 -274.999958) (xy 278.244058 -274.999958) (xy 278.248018 -274.950904) (xy 278.259795 -274.90312)
			(xy 278.279086 -274.857844) (xy 278.305389 -274.816248) (xy 278.338024 -274.779411) (xy 278.376145 -274.748286)
			(xy 278.418766 -274.723679) (xy 278.464782 -274.706227) (xy 278.513001 -274.696383) (xy 278.562176 -274.694402)
			(xy 278.611031 -274.700334) (xy 278.658302 -274.714026) (xy 278.702764 -274.735124) (xy 278.743267 -274.76308)
			(xy 278.77876 -274.797172) (xy 278.808325 -274.836516) (xy 278.831196 -274.880093) (xy 278.84678 -274.926774)
			(xy 278.854675 -274.975351) (xy 278.85517 -274.999958) (xy 278.854675 -275.024565) (xy 278.854496 -275.025666)
			(xy 279.173174 -275.025666) (xy 279.173174 -274.97425) (xy 279.181217 -274.923468) (xy 279.197105 -274.874569)
			(xy 279.220448 -274.828757) (xy 279.250669 -274.787161) (xy 279.287025 -274.750805) (xy 279.328621 -274.720584)
			(xy 279.374433 -274.697241) (xy 279.423332 -274.681353) (xy 279.474114 -274.67331) (xy 279.52553 -274.67331)
			(xy 279.576312 -274.681353) (xy 279.625211 -274.697241) (xy 279.671023 -274.720584) (xy 279.712619 -274.750805)
			(xy 279.748975 -274.787161) (xy 279.779196 -274.828757) (xy 279.802539 -274.874569) (xy 279.818427 -274.923468)
			(xy 279.82647 -274.97425) (xy 279.826974 -274.999958) (xy 280.143978 -274.999958) (xy 280.147938 -274.950904)
			(xy 280.159715 -274.90312) (xy 280.179006 -274.857844) (xy 280.205309 -274.816248) (xy 280.237944 -274.779411)
			(xy 280.276065 -274.748286) (xy 280.318686 -274.723679) (xy 280.364702 -274.706227) (xy 280.412921 -274.696383)
			(xy 280.462096 -274.694402) (xy 280.510951 -274.700334) (xy 280.558222 -274.714026) (xy 280.602684 -274.735124)
			(xy 280.643187 -274.76308) (xy 280.67868 -274.797172) (xy 280.708245 -274.836516) (xy 280.731116 -274.880093)
			(xy 280.7467 -274.926774) (xy 280.754595 -274.975351) (xy 280.75509 -274.999958) (xy 280.754595 -275.024565)
			(xy 280.754416 -275.025666) (xy 281.073094 -275.025666) (xy 281.073094 -274.97425) (xy 281.081137 -274.923468)
			(xy 281.097025 -274.874569) (xy 281.120368 -274.828757) (xy 281.150589 -274.787161) (xy 281.186945 -274.750805)
			(xy 281.228541 -274.720584) (xy 281.274353 -274.697241) (xy 281.323252 -274.681353) (xy 281.374034 -274.67331)
			(xy 281.42545 -274.67331) (xy 281.476232 -274.681353) (xy 281.525131 -274.697241) (xy 281.570943 -274.720584)
			(xy 281.612539 -274.750805) (xy 281.648895 -274.787161) (xy 281.679116 -274.828757) (xy 281.702459 -274.874569)
			(xy 281.718347 -274.923468) (xy 281.72639 -274.97425) (xy 281.726894 -274.999958) (xy 282.043898 -274.999958)
			(xy 282.047858 -274.950904) (xy 282.059635 -274.90312) (xy 282.078926 -274.857844) (xy 282.105229 -274.816248)
			(xy 282.137864 -274.779411) (xy 282.175985 -274.748286) (xy 282.218606 -274.723679) (xy 282.264622 -274.706227)
			(xy 282.312841 -274.696383) (xy 282.362016 -274.694402) (xy 282.410871 -274.700334) (xy 282.458142 -274.714026)
			(xy 282.502604 -274.735124) (xy 282.543107 -274.76308) (xy 282.5786 -274.797172) (xy 282.608165 -274.836516)
			(xy 282.631036 -274.880093) (xy 282.64662 -274.926774) (xy 282.654515 -274.975351) (xy 282.65501 -274.999958)
			(xy 282.654515 -275.024565) (xy 282.654336 -275.025666) (xy 282.973268 -275.025666) (xy 282.973268 -274.97425)
			(xy 282.981311 -274.923468) (xy 282.997199 -274.874569) (xy 283.020542 -274.828757) (xy 283.050763 -274.787161)
			(xy 283.087119 -274.750805) (xy 283.128715 -274.720584) (xy 283.174527 -274.697241) (xy 283.223426 -274.681353)
			(xy 283.274208 -274.67331) (xy 283.325624 -274.67331) (xy 283.376406 -274.681353) (xy 283.425305 -274.697241)
			(xy 283.471117 -274.720584) (xy 283.512713 -274.750805) (xy 283.549069 -274.787161) (xy 283.57929 -274.828757)
			(xy 283.602633 -274.874569) (xy 283.618521 -274.923468) (xy 283.626564 -274.97425) (xy 283.627068 -274.999958)
			(xy 283.944072 -274.999958) (xy 283.948032 -274.950904) (xy 283.959809 -274.90312) (xy 283.9791 -274.857844)
			(xy 284.005403 -274.816248) (xy 284.038038 -274.779411) (xy 284.076159 -274.748286) (xy 284.11878 -274.723679)
			(xy 284.164796 -274.706227) (xy 284.213015 -274.696383) (xy 284.26219 -274.694402) (xy 284.311045 -274.700334)
			(xy 284.358316 -274.714026) (xy 284.402778 -274.735124) (xy 284.443281 -274.76308) (xy 284.478774 -274.797172)
			(xy 284.508339 -274.836516) (xy 284.53121 -274.880093) (xy 284.546794 -274.926774) (xy 284.554689 -274.975351)
			(xy 284.555184 -274.999958) (xy 284.554689 -275.024565) (xy 284.55451 -275.025666) (xy 284.873188 -275.025666)
			(xy 284.873188 -274.97425) (xy 284.881231 -274.923468) (xy 284.897119 -274.874569) (xy 284.920462 -274.828757)
			(xy 284.950683 -274.787161) (xy 284.987039 -274.750805) (xy 285.028635 -274.720584) (xy 285.074447 -274.697241)
			(xy 285.123346 -274.681353) (xy 285.174128 -274.67331) (xy 285.225544 -274.67331) (xy 285.276326 -274.681353)
			(xy 285.325225 -274.697241) (xy 285.371037 -274.720584) (xy 285.412633 -274.750805) (xy 285.448989 -274.787161)
			(xy 285.47921 -274.828757) (xy 285.502553 -274.874569) (xy 285.518441 -274.923468) (xy 285.526484 -274.97425)
			(xy 285.526988 -274.999958) (xy 285.843992 -274.999958) (xy 285.847952 -274.950904) (xy 285.859729 -274.90312)
			(xy 285.87902 -274.857844) (xy 285.905323 -274.816248) (xy 285.937958 -274.779411) (xy 285.976079 -274.748286)
			(xy 286.0187 -274.723679) (xy 286.064716 -274.706227) (xy 286.112935 -274.696383) (xy 286.16211 -274.694402)
			(xy 286.210965 -274.700334) (xy 286.258236 -274.714026) (xy 286.302698 -274.735124) (xy 286.343201 -274.76308)
			(xy 286.378694 -274.797172) (xy 286.408259 -274.836516) (xy 286.43113 -274.880093) (xy 286.446714 -274.926774)
			(xy 286.454609 -274.975351) (xy 286.455104 -274.999958) (xy 286.454609 -275.024565) (xy 286.45443 -275.025666)
			(xy 286.773108 -275.025666) (xy 286.773108 -274.97425) (xy 286.781151 -274.923468) (xy 286.797039 -274.874569)
			(xy 286.820382 -274.828757) (xy 286.850603 -274.787161) (xy 286.886959 -274.750805) (xy 286.928555 -274.720584)
			(xy 286.974367 -274.697241) (xy 287.023266 -274.681353) (xy 287.074048 -274.67331) (xy 287.125464 -274.67331)
			(xy 287.176246 -274.681353) (xy 287.225145 -274.697241) (xy 287.270957 -274.720584) (xy 287.312553 -274.750805)
			(xy 287.348909 -274.787161) (xy 287.37913 -274.828757) (xy 287.402473 -274.874569) (xy 287.418361 -274.923468)
			(xy 287.426404 -274.97425) (xy 287.426908 -274.999958) (xy 287.743912 -274.999958) (xy 287.747872 -274.950904)
			(xy 287.759649 -274.90312) (xy 287.77894 -274.857844) (xy 287.805243 -274.816248) (xy 287.837878 -274.779411)
			(xy 287.875999 -274.748286) (xy 287.91862 -274.723679) (xy 287.964636 -274.706227) (xy 288.012855 -274.696383)
			(xy 288.06203 -274.694402) (xy 288.110885 -274.700334) (xy 288.158156 -274.714026) (xy 288.202618 -274.735124)
			(xy 288.243121 -274.76308) (xy 288.278614 -274.797172) (xy 288.308179 -274.836516) (xy 288.33105 -274.880093)
			(xy 288.346634 -274.926774) (xy 288.354529 -274.975351) (xy 288.355024 -274.999958) (xy 288.354529 -275.024565)
			(xy 288.35435 -275.025666) (xy 288.673282 -275.025666) (xy 288.673282 -274.97425) (xy 288.681325 -274.923468)
			(xy 288.697213 -274.874569) (xy 288.720556 -274.828757) (xy 288.750777 -274.787161) (xy 288.787133 -274.750805)
			(xy 288.828729 -274.720584) (xy 288.874541 -274.697241) (xy 288.92344 -274.681353) (xy 288.974222 -274.67331)
			(xy 289.025638 -274.67331) (xy 289.07642 -274.681353) (xy 289.125319 -274.697241) (xy 289.171131 -274.720584)
			(xy 289.212727 -274.750805) (xy 289.249083 -274.787161) (xy 289.279304 -274.828757) (xy 289.302647 -274.874569)
			(xy 289.318535 -274.923468) (xy 289.326578 -274.97425) (xy 289.327082 -274.999958) (xy 289.326578 -275.025666)
			(xy 289.318535 -275.076448) (xy 289.302647 -275.125347) (xy 289.279304 -275.171159) (xy 289.249083 -275.212755)
			(xy 289.212727 -275.249111) (xy 289.171131 -275.279332) (xy 289.125319 -275.302675) (xy 289.07642 -275.318563)
			(xy 289.025638 -275.326606) (xy 288.974222 -275.326606) (xy 288.92344 -275.318563) (xy 288.874541 -275.302675)
			(xy 288.828729 -275.279332) (xy 288.787133 -275.249111) (xy 288.750777 -275.212755) (xy 288.720556 -275.171159)
			(xy 288.697213 -275.125347) (xy 288.681325 -275.076448) (xy 288.673282 -275.025666) (xy 288.35435 -275.025666)
			(xy 288.346634 -275.073142) (xy 288.33105 -275.119823) (xy 288.308179 -275.1634) (xy 288.278614 -275.202744)
			(xy 288.243121 -275.236836) (xy 288.202618 -275.264792) (xy 288.158156 -275.28589) (xy 288.110885 -275.299582)
			(xy 288.06203 -275.305514) (xy 288.012855 -275.303533) (xy 287.964636 -275.293689) (xy 287.91862 -275.276237)
			(xy 287.875999 -275.25163) (xy 287.837878 -275.220505) (xy 287.805243 -275.183668) (xy 287.77894 -275.142072)
			(xy 287.759649 -275.096796) (xy 287.747872 -275.049012) (xy 287.743912 -274.999958) (xy 287.426908 -274.999958)
			(xy 287.426404 -275.025666) (xy 287.418361 -275.076448) (xy 287.402473 -275.125347) (xy 287.37913 -275.171159)
			(xy 287.348909 -275.212755) (xy 287.312553 -275.249111) (xy 287.270957 -275.279332) (xy 287.225145 -275.302675)
			(xy 287.176246 -275.318563) (xy 287.125464 -275.326606) (xy 287.074048 -275.326606) (xy 287.023266 -275.318563)
			(xy 286.974367 -275.302675) (xy 286.928555 -275.279332) (xy 286.886959 -275.249111) (xy 286.850603 -275.212755)
			(xy 286.820382 -275.171159) (xy 286.797039 -275.125347) (xy 286.781151 -275.076448) (xy 286.773108 -275.025666)
			(xy 286.45443 -275.025666) (xy 286.446714 -275.073142) (xy 286.43113 -275.119823) (xy 286.408259 -275.1634)
			(xy 286.378694 -275.202744) (xy 286.343201 -275.236836) (xy 286.302698 -275.264792) (xy 286.258236 -275.28589)
			(xy 286.210965 -275.299582) (xy 286.16211 -275.305514) (xy 286.112935 -275.303533) (xy 286.064716 -275.293689)
			(xy 286.0187 -275.276237) (xy 285.976079 -275.25163) (xy 285.937958 -275.220505) (xy 285.905323 -275.183668)
			(xy 285.87902 -275.142072) (xy 285.859729 -275.096796) (xy 285.847952 -275.049012) (xy 285.843992 -274.999958)
			(xy 285.526988 -274.999958) (xy 285.526484 -275.025666) (xy 285.518441 -275.076448) (xy 285.502553 -275.125347)
			(xy 285.47921 -275.171159) (xy 285.448989 -275.212755) (xy 285.412633 -275.249111) (xy 285.371037 -275.279332)
			(xy 285.325225 -275.302675) (xy 285.276326 -275.318563) (xy 285.225544 -275.326606) (xy 285.174128 -275.326606)
			(xy 285.123346 -275.318563) (xy 285.074447 -275.302675) (xy 285.028635 -275.279332) (xy 284.987039 -275.249111)
			(xy 284.950683 -275.212755) (xy 284.920462 -275.171159) (xy 284.897119 -275.125347) (xy 284.881231 -275.076448)
			(xy 284.873188 -275.025666) (xy 284.55451 -275.025666) (xy 284.546794 -275.073142) (xy 284.53121 -275.119823)
			(xy 284.508339 -275.1634) (xy 284.478774 -275.202744) (xy 284.443281 -275.236836) (xy 284.402778 -275.264792)
			(xy 284.358316 -275.28589) (xy 284.311045 -275.299582) (xy 284.26219 -275.305514) (xy 284.213015 -275.303533)
			(xy 284.164796 -275.293689) (xy 284.11878 -275.276237) (xy 284.076159 -275.25163) (xy 284.038038 -275.220505)
			(xy 284.005403 -275.183668) (xy 283.9791 -275.142072) (xy 283.959809 -275.096796) (xy 283.948032 -275.049012)
			(xy 283.944072 -274.999958) (xy 283.627068 -274.999958) (xy 283.626564 -275.025666) (xy 283.618521 -275.076448)
			(xy 283.602633 -275.125347) (xy 283.57929 -275.171159) (xy 283.549069 -275.212755) (xy 283.512713 -275.249111)
			(xy 283.471117 -275.279332) (xy 283.425305 -275.302675) (xy 283.376406 -275.318563) (xy 283.325624 -275.326606)
			(xy 283.274208 -275.326606) (xy 283.223426 -275.318563) (xy 283.174527 -275.302675) (xy 283.128715 -275.279332)
			(xy 283.087119 -275.249111) (xy 283.050763 -275.212755) (xy 283.020542 -275.171159) (xy 282.997199 -275.125347)
			(xy 282.981311 -275.076448) (xy 282.973268 -275.025666) (xy 282.654336 -275.025666) (xy 282.64662 -275.073142)
			(xy 282.631036 -275.119823) (xy 282.608165 -275.1634) (xy 282.5786 -275.202744) (xy 282.543107 -275.236836)
			(xy 282.502604 -275.264792) (xy 282.458142 -275.28589) (xy 282.410871 -275.299582) (xy 282.362016 -275.305514)
			(xy 282.312841 -275.303533) (xy 282.264622 -275.293689) (xy 282.218606 -275.276237) (xy 282.175985 -275.25163)
			(xy 282.137864 -275.220505) (xy 282.105229 -275.183668) (xy 282.078926 -275.142072) (xy 282.059635 -275.096796)
			(xy 282.047858 -275.049012) (xy 282.043898 -274.999958) (xy 281.726894 -274.999958) (xy 281.72639 -275.025666)
			(xy 281.718347 -275.076448) (xy 281.702459 -275.125347) (xy 281.679116 -275.171159) (xy 281.648895 -275.212755)
			(xy 281.612539 -275.249111) (xy 281.570943 -275.279332) (xy 281.525131 -275.302675) (xy 281.476232 -275.318563)
			(xy 281.42545 -275.326606) (xy 281.374034 -275.326606) (xy 281.323252 -275.318563) (xy 281.274353 -275.302675)
			(xy 281.228541 -275.279332) (xy 281.186945 -275.249111) (xy 281.150589 -275.212755) (xy 281.120368 -275.171159)
			(xy 281.097025 -275.125347) (xy 281.081137 -275.076448) (xy 281.073094 -275.025666) (xy 280.754416 -275.025666)
			(xy 280.7467 -275.073142) (xy 280.731116 -275.119823) (xy 280.708245 -275.1634) (xy 280.67868 -275.202744)
			(xy 280.643187 -275.236836) (xy 280.602684 -275.264792) (xy 280.558222 -275.28589) (xy 280.510951 -275.299582)
			(xy 280.462096 -275.305514) (xy 280.412921 -275.303533) (xy 280.364702 -275.293689) (xy 280.318686 -275.276237)
			(xy 280.276065 -275.25163) (xy 280.237944 -275.220505) (xy 280.205309 -275.183668) (xy 280.179006 -275.142072)
			(xy 280.159715 -275.096796) (xy 280.147938 -275.049012) (xy 280.143978 -274.999958) (xy 279.826974 -274.999958)
			(xy 279.82647 -275.025666) (xy 279.818427 -275.076448) (xy 279.802539 -275.125347) (xy 279.779196 -275.171159)
			(xy 279.748975 -275.212755) (xy 279.712619 -275.249111) (xy 279.671023 -275.279332) (xy 279.625211 -275.302675)
			(xy 279.576312 -275.318563) (xy 279.52553 -275.326606) (xy 279.474114 -275.326606) (xy 279.423332 -275.318563)
			(xy 279.374433 -275.302675) (xy 279.328621 -275.279332) (xy 279.287025 -275.249111) (xy 279.250669 -275.212755)
			(xy 279.220448 -275.171159) (xy 279.197105 -275.125347) (xy 279.181217 -275.076448) (xy 279.173174 -275.025666)
			(xy 278.854496 -275.025666) (xy 278.84678 -275.073142) (xy 278.831196 -275.119823) (xy 278.808325 -275.1634)
			(xy 278.77876 -275.202744) (xy 278.743267 -275.236836) (xy 278.702764 -275.264792) (xy 278.658302 -275.28589)
			(xy 278.611031 -275.299582) (xy 278.562176 -275.305514) (xy 278.513001 -275.303533) (xy 278.464782 -275.293689)
			(xy 278.418766 -275.276237) (xy 278.376145 -275.25163) (xy 278.338024 -275.220505) (xy 278.305389 -275.183668)
			(xy 278.279086 -275.142072) (xy 278.259795 -275.096796) (xy 278.248018 -275.049012) (xy 278.244058 -274.999958)
			(xy 277.927054 -274.999958) (xy 277.92655 -275.025666) (xy 277.918507 -275.076448) (xy 277.902619 -275.125347)
			(xy 277.879276 -275.171159) (xy 277.849055 -275.212755) (xy 277.812699 -275.249111) (xy 277.771103 -275.279332)
			(xy 277.725291 -275.302675) (xy 277.676392 -275.318563) (xy 277.62561 -275.326606) (xy 277.574194 -275.326606)
			(xy 277.523412 -275.318563) (xy 277.474513 -275.302675) (xy 277.428701 -275.279332) (xy 277.387105 -275.249111)
			(xy 277.350749 -275.212755) (xy 277.320528 -275.171159) (xy 277.297185 -275.125347) (xy 277.281297 -275.076448)
			(xy 277.273254 -275.025666) (xy 276.954322 -275.025666) (xy 276.946606 -275.073142) (xy 276.931022 -275.119823)
			(xy 276.908151 -275.1634) (xy 276.878586 -275.202744) (xy 276.843093 -275.236836) (xy 276.80259 -275.264792)
			(xy 276.758128 -275.28589) (xy 276.710857 -275.299582) (xy 276.662002 -275.305514) (xy 276.612827 -275.303533)
			(xy 276.564608 -275.293689) (xy 276.518592 -275.276237) (xy 276.475971 -275.25163) (xy 276.43785 -275.220505)
			(xy 276.405215 -275.183668) (xy 276.378912 -275.142072) (xy 276.359621 -275.096796) (xy 276.347844 -275.049012)
			(xy 276.343884 -274.999958) (xy 264.249322 -274.999958) (xy 264.225402 -275.014431) (xy 264.054476 -275.10849)
			(xy 263.879833 -275.195452) (xy 263.701767 -275.27517) (xy 263.520579 -275.347511) (xy 263.336573 -275.412352)
			(xy 263.15006 -275.469584) (xy 263.12966 -275.474938) (xy 268.26897 -275.474938) (xy 268.27293 -275.425884)
			(xy 268.284707 -275.3781) (xy 268.303998 -275.332824) (xy 268.330301 -275.291228) (xy 268.362936 -275.254391)
			(xy 268.401057 -275.223266) (xy 268.443678 -275.198659) (xy 268.489694 -275.181207) (xy 268.537913 -275.171363)
			(xy 268.587088 -275.169382) (xy 268.635943 -275.175314) (xy 268.683214 -275.189006) (xy 268.727676 -275.210104)
			(xy 268.768179 -275.23806) (xy 268.803672 -275.272152) (xy 268.833237 -275.311496) (xy 268.856108 -275.355073)
			(xy 268.871692 -275.401754) (xy 268.879587 -275.450331) (xy 268.880082 -275.474938) (xy 269.21893 -275.474938)
			(xy 269.22289 -275.425884) (xy 269.234667 -275.3781) (xy 269.253958 -275.332824) (xy 269.280261 -275.291228)
			(xy 269.312896 -275.254391) (xy 269.351017 -275.223266) (xy 269.393638 -275.198659) (xy 269.439654 -275.181207)
			(xy 269.487873 -275.171363) (xy 269.537048 -275.169382) (xy 269.585903 -275.175314) (xy 269.633174 -275.189006)
			(xy 269.677636 -275.210104) (xy 269.718139 -275.23806) (xy 269.753632 -275.272152) (xy 269.783197 -275.311496)
			(xy 269.806068 -275.355073) (xy 269.821652 -275.401754) (xy 269.829547 -275.450331) (xy 269.830042 -275.474938)
			(xy 270.169144 -275.474938) (xy 270.173104 -275.425884) (xy 270.184881 -275.3781) (xy 270.204172 -275.332824)
			(xy 270.230475 -275.291228) (xy 270.26311 -275.254391) (xy 270.301231 -275.223266) (xy 270.343852 -275.198659)
			(xy 270.389868 -275.181207) (xy 270.438087 -275.171363) (xy 270.487262 -275.169382) (xy 270.536117 -275.175314)
			(xy 270.583388 -275.189006) (xy 270.62785 -275.210104) (xy 270.668353 -275.23806) (xy 270.703846 -275.272152)
			(xy 270.733411 -275.311496) (xy 270.756282 -275.355073) (xy 270.771866 -275.401754) (xy 270.779761 -275.450331)
			(xy 270.780256 -275.474938) (xy 271.119104 -275.474938) (xy 271.123064 -275.425884) (xy 271.134841 -275.3781)
			(xy 271.154132 -275.332824) (xy 271.180435 -275.291228) (xy 271.21307 -275.254391) (xy 271.251191 -275.223266)
			(xy 271.293812 -275.198659) (xy 271.339828 -275.181207) (xy 271.388047 -275.171363) (xy 271.437222 -275.169382)
			(xy 271.486077 -275.175314) (xy 271.533348 -275.189006) (xy 271.57781 -275.210104) (xy 271.618313 -275.23806)
			(xy 271.653806 -275.272152) (xy 271.683371 -275.311496) (xy 271.706242 -275.355073) (xy 271.721826 -275.401754)
			(xy 271.729721 -275.450331) (xy 271.730216 -275.474938) (xy 272.069064 -275.474938) (xy 272.073024 -275.425884)
			(xy 272.084801 -275.3781) (xy 272.104092 -275.332824) (xy 272.130395 -275.291228) (xy 272.16303 -275.254391)
			(xy 272.201151 -275.223266) (xy 272.243772 -275.198659) (xy 272.289788 -275.181207) (xy 272.338007 -275.171363)
			(xy 272.387182 -275.169382) (xy 272.436037 -275.175314) (xy 272.483308 -275.189006) (xy 272.52777 -275.210104)
			(xy 272.568273 -275.23806) (xy 272.603766 -275.272152) (xy 272.633331 -275.311496) (xy 272.656202 -275.355073)
			(xy 272.671786 -275.401754) (xy 272.679681 -275.450331) (xy 272.680176 -275.474938) (xy 273.019024 -275.474938)
			(xy 273.022984 -275.425884) (xy 273.034761 -275.3781) (xy 273.054052 -275.332824) (xy 273.080355 -275.291228)
			(xy 273.11299 -275.254391) (xy 273.151111 -275.223266) (xy 273.193732 -275.198659) (xy 273.239748 -275.181207)
			(xy 273.287967 -275.171363) (xy 273.337142 -275.169382) (xy 273.385997 -275.175314) (xy 273.433268 -275.189006)
			(xy 273.47773 -275.210104) (xy 273.518233 -275.23806) (xy 273.553726 -275.272152) (xy 273.583291 -275.311496)
			(xy 273.606162 -275.355073) (xy 273.621746 -275.401754) (xy 273.629641 -275.450331) (xy 273.630136 -275.474938)
			(xy 273.968984 -275.474938) (xy 273.972944 -275.425884) (xy 273.984721 -275.3781) (xy 274.004012 -275.332824)
			(xy 274.030315 -275.291228) (xy 274.06295 -275.254391) (xy 274.101071 -275.223266) (xy 274.143692 -275.198659)
			(xy 274.189708 -275.181207) (xy 274.237927 -275.171363) (xy 274.287102 -275.169382) (xy 274.335957 -275.175314)
			(xy 274.383228 -275.189006) (xy 274.42769 -275.210104) (xy 274.468193 -275.23806) (xy 274.503686 -275.272152)
			(xy 274.533251 -275.311496) (xy 274.556122 -275.355073) (xy 274.571706 -275.401754) (xy 274.579601 -275.450331)
			(xy 274.580096 -275.474938) (xy 274.918944 -275.474938) (xy 274.922904 -275.425884) (xy 274.934681 -275.3781)
			(xy 274.953972 -275.332824) (xy 274.980275 -275.291228) (xy 275.01291 -275.254391) (xy 275.051031 -275.223266)
			(xy 275.093652 -275.198659) (xy 275.139668 -275.181207) (xy 275.187887 -275.171363) (xy 275.237062 -275.169382)
			(xy 275.285917 -275.175314) (xy 275.333188 -275.189006) (xy 275.37765 -275.210104) (xy 275.418153 -275.23806)
			(xy 275.453646 -275.272152) (xy 275.483211 -275.311496) (xy 275.506082 -275.355073) (xy 275.521666 -275.401754)
			(xy 275.529561 -275.450331) (xy 275.530056 -275.474938) (xy 275.529561 -275.499545) (xy 275.521666 -275.548122)
			(xy 275.506082 -275.594803) (xy 275.483211 -275.63838) (xy 275.453646 -275.677724) (xy 275.418153 -275.711816)
			(xy 275.37765 -275.739772) (xy 275.333188 -275.76087) (xy 275.285917 -275.774562) (xy 275.237062 -275.780494)
			(xy 275.187887 -275.778513) (xy 275.139668 -275.768669) (xy 275.093652 -275.751217) (xy 275.051031 -275.72661)
			(xy 275.01291 -275.695485) (xy 274.980275 -275.658648) (xy 274.953972 -275.617052) (xy 274.934681 -275.571776)
			(xy 274.922904 -275.523992) (xy 274.918944 -275.474938) (xy 274.580096 -275.474938) (xy 274.579601 -275.499545)
			(xy 274.571706 -275.548122) (xy 274.556122 -275.594803) (xy 274.533251 -275.63838) (xy 274.503686 -275.677724)
			(xy 274.468193 -275.711816) (xy 274.42769 -275.739772) (xy 274.383228 -275.76087) (xy 274.335957 -275.774562)
			(xy 274.287102 -275.780494) (xy 274.237927 -275.778513) (xy 274.189708 -275.768669) (xy 274.143692 -275.751217)
			(xy 274.101071 -275.72661) (xy 274.06295 -275.695485) (xy 274.030315 -275.658648) (xy 274.004012 -275.617052)
			(xy 273.984721 -275.571776) (xy 273.972944 -275.523992) (xy 273.968984 -275.474938) (xy 273.630136 -275.474938)
			(xy 273.629641 -275.499545) (xy 273.621746 -275.548122) (xy 273.606162 -275.594803) (xy 273.583291 -275.63838)
			(xy 273.553726 -275.677724) (xy 273.518233 -275.711816) (xy 273.47773 -275.739772) (xy 273.433268 -275.76087)
			(xy 273.385997 -275.774562) (xy 273.337142 -275.780494) (xy 273.287967 -275.778513) (xy 273.239748 -275.768669)
			(xy 273.193732 -275.751217) (xy 273.151111 -275.72661) (xy 273.11299 -275.695485) (xy 273.080355 -275.658648)
			(xy 273.054052 -275.617052) (xy 273.034761 -275.571776) (xy 273.022984 -275.523992) (xy 273.019024 -275.474938)
			(xy 272.680176 -275.474938) (xy 272.679681 -275.499545) (xy 272.671786 -275.548122) (xy 272.656202 -275.594803)
			(xy 272.633331 -275.63838) (xy 272.603766 -275.677724) (xy 272.568273 -275.711816) (xy 272.52777 -275.739772)
			(xy 272.483308 -275.76087) (xy 272.436037 -275.774562) (xy 272.387182 -275.780494) (xy 272.338007 -275.778513)
			(xy 272.289788 -275.768669) (xy 272.243772 -275.751217) (xy 272.201151 -275.72661) (xy 272.16303 -275.695485)
			(xy 272.130395 -275.658648) (xy 272.104092 -275.617052) (xy 272.084801 -275.571776) (xy 272.073024 -275.523992)
			(xy 272.069064 -275.474938) (xy 271.730216 -275.474938) (xy 271.729721 -275.499545) (xy 271.721826 -275.548122)
			(xy 271.706242 -275.594803) (xy 271.683371 -275.63838) (xy 271.653806 -275.677724) (xy 271.618313 -275.711816)
			(xy 271.57781 -275.739772) (xy 271.533348 -275.76087) (xy 271.486077 -275.774562) (xy 271.437222 -275.780494)
			(xy 271.388047 -275.778513) (xy 271.339828 -275.768669) (xy 271.293812 -275.751217) (xy 271.251191 -275.72661)
			(xy 271.21307 -275.695485) (xy 271.180435 -275.658648) (xy 271.154132 -275.617052) (xy 271.134841 -275.571776)
			(xy 271.123064 -275.523992) (xy 271.119104 -275.474938) (xy 270.780256 -275.474938) (xy 270.779761 -275.499545)
			(xy 270.771866 -275.548122) (xy 270.756282 -275.594803) (xy 270.733411 -275.63838) (xy 270.703846 -275.677724)
			(xy 270.668353 -275.711816) (xy 270.62785 -275.739772) (xy 270.583388 -275.76087) (xy 270.536117 -275.774562)
			(xy 270.487262 -275.780494) (xy 270.438087 -275.778513) (xy 270.389868 -275.768669) (xy 270.343852 -275.751217)
			(xy 270.301231 -275.72661) (xy 270.26311 -275.695485) (xy 270.230475 -275.658648) (xy 270.204172 -275.617052)
			(xy 270.184881 -275.571776) (xy 270.173104 -275.523992) (xy 270.169144 -275.474938) (xy 269.830042 -275.474938)
			(xy 269.829547 -275.499545) (xy 269.821652 -275.548122) (xy 269.806068 -275.594803) (xy 269.783197 -275.63838)
			(xy 269.753632 -275.677724) (xy 269.718139 -275.711816) (xy 269.677636 -275.739772) (xy 269.633174 -275.76087)
			(xy 269.585903 -275.774562) (xy 269.537048 -275.780494) (xy 269.487873 -275.778513) (xy 269.439654 -275.768669)
			(xy 269.393638 -275.751217) (xy 269.351017 -275.72661) (xy 269.312896 -275.695485) (xy 269.280261 -275.658648)
			(xy 269.253958 -275.617052) (xy 269.234667 -275.571776) (xy 269.22289 -275.523992) (xy 269.21893 -275.474938)
			(xy 268.880082 -275.474938) (xy 268.879587 -275.499545) (xy 268.871692 -275.548122) (xy 268.856108 -275.594803)
			(xy 268.833237 -275.63838) (xy 268.803672 -275.677724) (xy 268.768179 -275.711816) (xy 268.727676 -275.739772)
			(xy 268.683214 -275.76087) (xy 268.635943 -275.774562) (xy 268.587088 -275.780494) (xy 268.537913 -275.778513)
			(xy 268.489694 -275.768669) (xy 268.443678 -275.751217) (xy 268.401057 -275.72661) (xy 268.362936 -275.695485)
			(xy 268.330301 -275.658648) (xy 268.303998 -275.617052) (xy 268.284707 -275.571776) (xy 268.27293 -275.523992)
			(xy 268.26897 -275.474938) (xy 263.12966 -275.474938) (xy 262.961355 -275.519111) (xy 262.770776 -275.560848)
			(xy 262.578643 -275.594726) (xy 262.385282 -275.620688) (xy 262.191018 -275.638689) (xy 261.996179 -275.6487)
			(xy 261.801093 -275.650703) (xy 261.60609 -275.644695) (xy 261.411497 -275.630686) (xy 261.217644 -275.6087)
			(xy 261.024857 -275.578774) (xy 260.83346 -275.540958) (xy 260.643778 -275.495316) (xy 260.45613 -275.441926)
			(xy 260.270831 -275.380876) (xy 260.088196 -275.312271) (xy 259.908531 -275.236225) (xy 259.732139 -275.152867)
			(xy 259.559318 -275.062338) (xy 259.39036 -274.96479) (xy 259.225549 -274.860387) (xy 259.065163 -274.749307)
			(xy 258.909473 -274.631735) (xy 258.758741 -274.507871) (xy 258.613222 -274.377922) (xy 258.47316 -274.242109)
			(xy 258.338792 -274.10066) (xy 258.210345 -273.953814) (xy 258.088034 -273.801819) (xy 257.972067 -273.64493)
			(xy 257.862639 -273.483412) (xy 257.759934 -273.317538) (xy 257.664126 -273.147587) (xy 257.575375 -272.973846)
			(xy 257.493833 -272.796608) (xy 257.419636 -272.616172) (xy 257.352909 -272.432841) (xy 257.293765 -272.246926)
			(xy 257.242304 -272.058739) (xy 257.198612 -271.868599) (xy 257.162763 -271.676824) (xy 257.134818 -271.48374)
			(xy 257.114823 -271.289671) (xy 257.102813 -271.094945) (xy 257.098807 -270.89989) (xy 233.671364 -270.89989)
			(xy 233.671364 -271.156938) (xy 233.671796 -271.167004) (xy 233.679527 -271.185592) (xy 233.68635 -271.193006)
			(xy 233.877866 -271.384522) (xy 233.878374 -271.38503) (xy 233.885755 -271.391611) (xy 233.904055 -271.399058)
			(xy 233.913934 -271.399508) (xy 248.0691 -271.399508) (xy 248.07917 -271.399931) (xy 248.097774 -271.407647)
			(xy 248.105168 -271.414494) (xy 248.590562 -271.899888) (xy 248.59349 -271.902776) (xy 248.600129 -271.907628)
			(xy 248.60377 -271.90954) (xy 248.617232 -271.916144) (xy 248.621042 -271.917414) (xy 248.626879 -271.919421)
			(xy 248.637421 -271.925836) (xy 248.64187 -271.930114) (xy 249.722132 -273.010376) (xy 249.728974 -273.017775)
			(xy 249.736691 -273.036374) (xy 249.737118 -273.046444) (xy 249.737118 -273.501358) (xy 249.737622 -273.511781)
			(xy 249.745885 -273.530921) (xy 249.75312 -273.538442) (xy 249.81535 -273.596608) (xy 249.835162 -273.60372)
			(xy 249.84583 -273.602958) (xy 249.872754 -273.601942) (xy 249.899831 -273.602419) (xy 249.95344 -273.610084)
			(xy 250.005427 -273.625251) (xy 250.054747 -273.647617) (xy 250.100409 -273.676731) (xy 250.141496 -273.712009)
			(xy 250.177183 -273.752742) (xy 250.206751 -273.798112) (xy 250.229607 -273.847206) (xy 250.245292 -273.899039)
			(xy 250.253491 -273.952569) (xy 250.254262 -273.97964) (xy 250.254262 -273.983704) (xy 250.253648 -274.014548)
			(xy 250.243696 -274.07543) (xy 250.23445 -274.104862) (xy 250.23064 -274.116292) (xy 250.232418 -274.128738)
			(xy 250.233005 -274.132754) (xy 250.23531 -274.140536) (xy 250.23699 -274.144232) (xy 250.268232 -274.207732)
			(xy 250.272959 -274.216342) (xy 250.287585 -274.229428) (xy 250.29668 -274.233132) (xy 250.323943 -274.243601)
			(xy 250.375176 -274.271625) (xy 250.421544 -274.307123) (xy 250.461966 -274.349269) (xy 250.495499 -274.397078)
			(xy 250.521361 -274.449436) (xy 250.538948 -274.505122) (xy 250.54785 -274.562836) (xy 250.548394 -274.592034)
			(xy 250.547905 -274.619283) (xy 250.540145 -274.673226) (xy 250.524787 -274.725516) (xy 250.502143 -274.775088)
			(xy 250.472676 -274.820933) (xy 250.436984 -274.862118) (xy 250.395795 -274.897805) (xy 250.349946 -274.927266)
			(xy 250.300371 -274.949903) (xy 250.24808 -274.965255) (xy 250.194135 -274.973009) (xy 250.166886 -274.973542)
			(xy 250.138397 -274.973014) (xy 250.082052 -274.964548) (xy 250.02759 -274.947805) (xy 249.976219 -274.923157)
			(xy 249.92908 -274.891151) (xy 249.907806 -274.872196) (xy 249.89663 -274.861782) (xy 249.866912 -274.856702)
			(xy 249.814588 -274.879562) (xy 249.767598 -274.900136) (xy 249.753628 -274.906232) (xy 249.737118 -274.931378)
			(xy 249.737118 -275.949918) (xy 276.343884 -275.949918) (xy 276.347844 -275.900864) (xy 276.359621 -275.85308)
			(xy 276.378912 -275.807804) (xy 276.405215 -275.766208) (xy 276.43785 -275.729371) (xy 276.475971 -275.698246)
			(xy 276.518592 -275.673639) (xy 276.564608 -275.656187) (xy 276.612827 -275.646343) (xy 276.662002 -275.644362)
			(xy 276.710857 -275.650294) (xy 276.758128 -275.663986) (xy 276.80259 -275.685084) (xy 276.843093 -275.71304)
			(xy 276.878586 -275.747132) (xy 276.908151 -275.786476) (xy 276.931022 -275.830053) (xy 276.946606 -275.876734)
			(xy 276.954501 -275.925311) (xy 276.954996 -275.949918) (xy 276.954501 -275.974525) (xy 276.954322 -275.975626)
			(xy 277.273254 -275.975626) (xy 277.273254 -275.92421) (xy 277.281297 -275.873428) (xy 277.297185 -275.824529)
			(xy 277.320528 -275.778717) (xy 277.350749 -275.737121) (xy 277.387105 -275.700765) (xy 277.428701 -275.670544)
			(xy 277.474513 -275.647201) (xy 277.523412 -275.631313) (xy 277.574194 -275.62327) (xy 277.62561 -275.62327)
			(xy 277.676392 -275.631313) (xy 277.725291 -275.647201) (xy 277.771103 -275.670544) (xy 277.812699 -275.700765)
			(xy 277.849055 -275.737121) (xy 277.879276 -275.778717) (xy 277.902619 -275.824529) (xy 277.918507 -275.873428)
			(xy 277.92655 -275.92421) (xy 277.927054 -275.949918) (xy 278.244058 -275.949918) (xy 278.248018 -275.900864)
			(xy 278.259795 -275.85308) (xy 278.279086 -275.807804) (xy 278.305389 -275.766208) (xy 278.338024 -275.729371)
			(xy 278.376145 -275.698246) (xy 278.418766 -275.673639) (xy 278.464782 -275.656187) (xy 278.513001 -275.646343)
			(xy 278.562176 -275.644362) (xy 278.611031 -275.650294) (xy 278.658302 -275.663986) (xy 278.702764 -275.685084)
			(xy 278.743267 -275.71304) (xy 278.77876 -275.747132) (xy 278.808325 -275.786476) (xy 278.831196 -275.830053)
			(xy 278.84678 -275.876734) (xy 278.854675 -275.925311) (xy 278.85517 -275.949918) (xy 278.854675 -275.974525)
			(xy 278.854496 -275.975626) (xy 279.173174 -275.975626) (xy 279.173174 -275.92421) (xy 279.181217 -275.873428)
			(xy 279.197105 -275.824529) (xy 279.220448 -275.778717) (xy 279.250669 -275.737121) (xy 279.287025 -275.700765)
			(xy 279.328621 -275.670544) (xy 279.374433 -275.647201) (xy 279.423332 -275.631313) (xy 279.474114 -275.62327)
			(xy 279.52553 -275.62327) (xy 279.576312 -275.631313) (xy 279.625211 -275.647201) (xy 279.671023 -275.670544)
			(xy 279.712619 -275.700765) (xy 279.748975 -275.737121) (xy 279.779196 -275.778717) (xy 279.802539 -275.824529)
			(xy 279.818427 -275.873428) (xy 279.82647 -275.92421) (xy 279.826974 -275.949918) (xy 280.143978 -275.949918)
			(xy 280.147938 -275.900864) (xy 280.159715 -275.85308) (xy 280.179006 -275.807804) (xy 280.205309 -275.766208)
			(xy 280.237944 -275.729371) (xy 280.276065 -275.698246) (xy 280.318686 -275.673639) (xy 280.364702 -275.656187)
			(xy 280.412921 -275.646343) (xy 280.462096 -275.644362) (xy 280.510951 -275.650294) (xy 280.558222 -275.663986)
			(xy 280.602684 -275.685084) (xy 280.643187 -275.71304) (xy 280.67868 -275.747132) (xy 280.708245 -275.786476)
			(xy 280.731116 -275.830053) (xy 280.7467 -275.876734) (xy 280.754595 -275.925311) (xy 280.75509 -275.949918)
			(xy 280.754595 -275.974525) (xy 280.754416 -275.975626) (xy 281.073094 -275.975626) (xy 281.073094 -275.92421)
			(xy 281.081137 -275.873428) (xy 281.097025 -275.824529) (xy 281.120368 -275.778717) (xy 281.150589 -275.737121)
			(xy 281.186945 -275.700765) (xy 281.228541 -275.670544) (xy 281.274353 -275.647201) (xy 281.323252 -275.631313)
			(xy 281.374034 -275.62327) (xy 281.42545 -275.62327) (xy 281.476232 -275.631313) (xy 281.525131 -275.647201)
			(xy 281.570943 -275.670544) (xy 281.612539 -275.700765) (xy 281.648895 -275.737121) (xy 281.679116 -275.778717)
			(xy 281.702459 -275.824529) (xy 281.718347 -275.873428) (xy 281.72639 -275.92421) (xy 281.726894 -275.949918)
			(xy 282.043898 -275.949918) (xy 282.047858 -275.900864) (xy 282.059635 -275.85308) (xy 282.078926 -275.807804)
			(xy 282.105229 -275.766208) (xy 282.137864 -275.729371) (xy 282.175985 -275.698246) (xy 282.218606 -275.673639)
			(xy 282.264622 -275.656187) (xy 282.312841 -275.646343) (xy 282.362016 -275.644362) (xy 282.410871 -275.650294)
			(xy 282.458142 -275.663986) (xy 282.502604 -275.685084) (xy 282.543107 -275.71304) (xy 282.5786 -275.747132)
			(xy 282.608165 -275.786476) (xy 282.631036 -275.830053) (xy 282.64662 -275.876734) (xy 282.654515 -275.925311)
			(xy 282.65501 -275.949918) (xy 282.654515 -275.974525) (xy 282.654336 -275.975626) (xy 282.973268 -275.975626)
			(xy 282.973268 -275.92421) (xy 282.981311 -275.873428) (xy 282.997199 -275.824529) (xy 283.020542 -275.778717)
			(xy 283.050763 -275.737121) (xy 283.087119 -275.700765) (xy 283.128715 -275.670544) (xy 283.174527 -275.647201)
			(xy 283.223426 -275.631313) (xy 283.274208 -275.62327) (xy 283.325624 -275.62327) (xy 283.376406 -275.631313)
			(xy 283.425305 -275.647201) (xy 283.471117 -275.670544) (xy 283.512713 -275.700765) (xy 283.549069 -275.737121)
			(xy 283.57929 -275.778717) (xy 283.602633 -275.824529) (xy 283.618521 -275.873428) (xy 283.626564 -275.92421)
			(xy 283.627068 -275.949918) (xy 283.944072 -275.949918) (xy 283.948032 -275.900864) (xy 283.959809 -275.85308)
			(xy 283.9791 -275.807804) (xy 284.005403 -275.766208) (xy 284.038038 -275.729371) (xy 284.076159 -275.698246)
			(xy 284.11878 -275.673639) (xy 284.164796 -275.656187) (xy 284.213015 -275.646343) (xy 284.26219 -275.644362)
			(xy 284.311045 -275.650294) (xy 284.358316 -275.663986) (xy 284.402778 -275.685084) (xy 284.443281 -275.71304)
			(xy 284.478774 -275.747132) (xy 284.508339 -275.786476) (xy 284.53121 -275.830053) (xy 284.546794 -275.876734)
			(xy 284.554689 -275.925311) (xy 284.555184 -275.949918) (xy 284.554689 -275.974525) (xy 284.55451 -275.975626)
			(xy 284.873188 -275.975626) (xy 284.873188 -275.92421) (xy 284.881231 -275.873428) (xy 284.897119 -275.824529)
			(xy 284.920462 -275.778717) (xy 284.950683 -275.737121) (xy 284.987039 -275.700765) (xy 285.028635 -275.670544)
			(xy 285.074447 -275.647201) (xy 285.123346 -275.631313) (xy 285.174128 -275.62327) (xy 285.225544 -275.62327)
			(xy 285.276326 -275.631313) (xy 285.325225 -275.647201) (xy 285.371037 -275.670544) (xy 285.412633 -275.700765)
			(xy 285.448989 -275.737121) (xy 285.47921 -275.778717) (xy 285.502553 -275.824529) (xy 285.518441 -275.873428)
			(xy 285.526484 -275.92421) (xy 285.526988 -275.949918) (xy 285.843992 -275.949918) (xy 285.847952 -275.900864)
			(xy 285.859729 -275.85308) (xy 285.87902 -275.807804) (xy 285.905323 -275.766208) (xy 285.937958 -275.729371)
			(xy 285.976079 -275.698246) (xy 286.0187 -275.673639) (xy 286.064716 -275.656187) (xy 286.112935 -275.646343)
			(xy 286.16211 -275.644362) (xy 286.210965 -275.650294) (xy 286.258236 -275.663986) (xy 286.302698 -275.685084)
			(xy 286.343201 -275.71304) (xy 286.378694 -275.747132) (xy 286.408259 -275.786476) (xy 286.43113 -275.830053)
			(xy 286.446714 -275.876734) (xy 286.454609 -275.925311) (xy 286.455104 -275.949918) (xy 286.454609 -275.974525)
			(xy 286.45443 -275.975626) (xy 286.773108 -275.975626) (xy 286.773108 -275.92421) (xy 286.781151 -275.873428)
			(xy 286.797039 -275.824529) (xy 286.820382 -275.778717) (xy 286.850603 -275.737121) (xy 286.886959 -275.700765)
			(xy 286.928555 -275.670544) (xy 286.974367 -275.647201) (xy 287.023266 -275.631313) (xy 287.074048 -275.62327)
			(xy 287.125464 -275.62327) (xy 287.176246 -275.631313) (xy 287.225145 -275.647201) (xy 287.270957 -275.670544)
			(xy 287.312553 -275.700765) (xy 287.348909 -275.737121) (xy 287.37913 -275.778717) (xy 287.402473 -275.824529)
			(xy 287.418361 -275.873428) (xy 287.426404 -275.92421) (xy 287.426908 -275.949918) (xy 287.743912 -275.949918)
			(xy 287.747872 -275.900864) (xy 287.759649 -275.85308) (xy 287.77894 -275.807804) (xy 287.805243 -275.766208)
			(xy 287.837878 -275.729371) (xy 287.875999 -275.698246) (xy 287.91862 -275.673639) (xy 287.964636 -275.656187)
			(xy 288.012855 -275.646343) (xy 288.06203 -275.644362) (xy 288.110885 -275.650294) (xy 288.158156 -275.663986)
			(xy 288.202618 -275.685084) (xy 288.243121 -275.71304) (xy 288.278614 -275.747132) (xy 288.308179 -275.786476)
			(xy 288.33105 -275.830053) (xy 288.346634 -275.876734) (xy 288.354529 -275.925311) (xy 288.355024 -275.949918)
			(xy 288.354529 -275.974525) (xy 288.35435 -275.975626) (xy 288.673282 -275.975626) (xy 288.673282 -275.92421)
			(xy 288.681325 -275.873428) (xy 288.697213 -275.824529) (xy 288.720556 -275.778717) (xy 288.750777 -275.737121)
			(xy 288.787133 -275.700765) (xy 288.828729 -275.670544) (xy 288.874541 -275.647201) (xy 288.92344 -275.631313)
			(xy 288.974222 -275.62327) (xy 289.025638 -275.62327) (xy 289.07642 -275.631313) (xy 289.125319 -275.647201)
			(xy 289.171131 -275.670544) (xy 289.212727 -275.700765) (xy 289.249083 -275.737121) (xy 289.279304 -275.778717)
			(xy 289.302647 -275.824529) (xy 289.318535 -275.873428) (xy 289.326578 -275.92421) (xy 289.327082 -275.949918)
			(xy 289.326578 -275.975626) (xy 289.318535 -276.026408) (xy 289.302647 -276.075307) (xy 289.279304 -276.121119)
			(xy 289.249083 -276.162715) (xy 289.212727 -276.199071) (xy 289.171131 -276.229292) (xy 289.125319 -276.252635)
			(xy 289.07642 -276.268523) (xy 289.025638 -276.276566) (xy 288.974222 -276.276566) (xy 288.92344 -276.268523)
			(xy 288.874541 -276.252635) (xy 288.828729 -276.229292) (xy 288.787133 -276.199071) (xy 288.750777 -276.162715)
			(xy 288.720556 -276.121119) (xy 288.697213 -276.075307) (xy 288.681325 -276.026408) (xy 288.673282 -275.975626)
			(xy 288.35435 -275.975626) (xy 288.346634 -276.023102) (xy 288.33105 -276.069783) (xy 288.308179 -276.11336)
			(xy 288.278614 -276.152704) (xy 288.243121 -276.186796) (xy 288.202618 -276.214752) (xy 288.158156 -276.23585)
			(xy 288.110885 -276.249542) (xy 288.06203 -276.255474) (xy 288.012855 -276.253493) (xy 287.964636 -276.243649)
			(xy 287.91862 -276.226197) (xy 287.875999 -276.20159) (xy 287.837878 -276.170465) (xy 287.805243 -276.133628)
			(xy 287.77894 -276.092032) (xy 287.759649 -276.046756) (xy 287.747872 -275.998972) (xy 287.743912 -275.949918)
			(xy 287.426908 -275.949918) (xy 287.426404 -275.975626) (xy 287.418361 -276.026408) (xy 287.402473 -276.075307)
			(xy 287.37913 -276.121119) (xy 287.348909 -276.162715) (xy 287.312553 -276.199071) (xy 287.270957 -276.229292)
			(xy 287.225145 -276.252635) (xy 287.176246 -276.268523) (xy 287.125464 -276.276566) (xy 287.074048 -276.276566)
			(xy 287.023266 -276.268523) (xy 286.974367 -276.252635) (xy 286.928555 -276.229292) (xy 286.886959 -276.199071)
			(xy 286.850603 -276.162715) (xy 286.820382 -276.121119) (xy 286.797039 -276.075307) (xy 286.781151 -276.026408)
			(xy 286.773108 -275.975626) (xy 286.45443 -275.975626) (xy 286.446714 -276.023102) (xy 286.43113 -276.069783)
			(xy 286.408259 -276.11336) (xy 286.378694 -276.152704) (xy 286.343201 -276.186796) (xy 286.302698 -276.214752)
			(xy 286.258236 -276.23585) (xy 286.210965 -276.249542) (xy 286.16211 -276.255474) (xy 286.112935 -276.253493)
			(xy 286.064716 -276.243649) (xy 286.0187 -276.226197) (xy 285.976079 -276.20159) (xy 285.937958 -276.170465)
			(xy 285.905323 -276.133628) (xy 285.87902 -276.092032) (xy 285.859729 -276.046756) (xy 285.847952 -275.998972)
			(xy 285.843992 -275.949918) (xy 285.526988 -275.949918) (xy 285.526484 -275.975626) (xy 285.518441 -276.026408)
			(xy 285.502553 -276.075307) (xy 285.47921 -276.121119) (xy 285.448989 -276.162715) (xy 285.412633 -276.199071)
			(xy 285.371037 -276.229292) (xy 285.325225 -276.252635) (xy 285.276326 -276.268523) (xy 285.225544 -276.276566)
			(xy 285.174128 -276.276566) (xy 285.123346 -276.268523) (xy 285.074447 -276.252635) (xy 285.028635 -276.229292)
			(xy 284.987039 -276.199071) (xy 284.950683 -276.162715) (xy 284.920462 -276.121119) (xy 284.897119 -276.075307)
			(xy 284.881231 -276.026408) (xy 284.873188 -275.975626) (xy 284.55451 -275.975626) (xy 284.546794 -276.023102)
			(xy 284.53121 -276.069783) (xy 284.508339 -276.11336) (xy 284.478774 -276.152704) (xy 284.443281 -276.186796)
			(xy 284.402778 -276.214752) (xy 284.358316 -276.23585) (xy 284.311045 -276.249542) (xy 284.26219 -276.255474)
			(xy 284.213015 -276.253493) (xy 284.164796 -276.243649) (xy 284.11878 -276.226197) (xy 284.076159 -276.20159)
			(xy 284.038038 -276.170465) (xy 284.005403 -276.133628) (xy 283.9791 -276.092032) (xy 283.959809 -276.046756)
			(xy 283.948032 -275.998972) (xy 283.944072 -275.949918) (xy 283.627068 -275.949918) (xy 283.626564 -275.975626)
			(xy 283.618521 -276.026408) (xy 283.602633 -276.075307) (xy 283.57929 -276.121119) (xy 283.549069 -276.162715)
			(xy 283.512713 -276.199071) (xy 283.471117 -276.229292) (xy 283.425305 -276.252635) (xy 283.376406 -276.268523)
			(xy 283.325624 -276.276566) (xy 283.274208 -276.276566) (xy 283.223426 -276.268523) (xy 283.174527 -276.252635)
			(xy 283.128715 -276.229292) (xy 283.087119 -276.199071) (xy 283.050763 -276.162715) (xy 283.020542 -276.121119)
			(xy 282.997199 -276.075307) (xy 282.981311 -276.026408) (xy 282.973268 -275.975626) (xy 282.654336 -275.975626)
			(xy 282.64662 -276.023102) (xy 282.631036 -276.069783) (xy 282.608165 -276.11336) (xy 282.5786 -276.152704)
			(xy 282.543107 -276.186796) (xy 282.502604 -276.214752) (xy 282.458142 -276.23585) (xy 282.410871 -276.249542)
			(xy 282.362016 -276.255474) (xy 282.312841 -276.253493) (xy 282.264622 -276.243649) (xy 282.218606 -276.226197)
			(xy 282.175985 -276.20159) (xy 282.137864 -276.170465) (xy 282.105229 -276.133628) (xy 282.078926 -276.092032)
			(xy 282.059635 -276.046756) (xy 282.047858 -275.998972) (xy 282.043898 -275.949918) (xy 281.726894 -275.949918)
			(xy 281.72639 -275.975626) (xy 281.718347 -276.026408) (xy 281.702459 -276.075307) (xy 281.679116 -276.121119)
			(xy 281.648895 -276.162715) (xy 281.612539 -276.199071) (xy 281.570943 -276.229292) (xy 281.525131 -276.252635)
			(xy 281.476232 -276.268523) (xy 281.42545 -276.276566) (xy 281.374034 -276.276566) (xy 281.323252 -276.268523)
			(xy 281.274353 -276.252635) (xy 281.228541 -276.229292) (xy 281.186945 -276.199071) (xy 281.150589 -276.162715)
			(xy 281.120368 -276.121119) (xy 281.097025 -276.075307) (xy 281.081137 -276.026408) (xy 281.073094 -275.975626)
			(xy 280.754416 -275.975626) (xy 280.7467 -276.023102) (xy 280.731116 -276.069783) (xy 280.708245 -276.11336)
			(xy 280.67868 -276.152704) (xy 280.643187 -276.186796) (xy 280.602684 -276.214752) (xy 280.558222 -276.23585)
			(xy 280.510951 -276.249542) (xy 280.462096 -276.255474) (xy 280.412921 -276.253493) (xy 280.364702 -276.243649)
			(xy 280.318686 -276.226197) (xy 280.276065 -276.20159) (xy 280.237944 -276.170465) (xy 280.205309 -276.133628)
			(xy 280.179006 -276.092032) (xy 280.159715 -276.046756) (xy 280.147938 -275.998972) (xy 280.143978 -275.949918)
			(xy 279.826974 -275.949918) (xy 279.82647 -275.975626) (xy 279.818427 -276.026408) (xy 279.802539 -276.075307)
			(xy 279.779196 -276.121119) (xy 279.748975 -276.162715) (xy 279.712619 -276.199071) (xy 279.671023 -276.229292)
			(xy 279.625211 -276.252635) (xy 279.576312 -276.268523) (xy 279.52553 -276.276566) (xy 279.474114 -276.276566)
			(xy 279.423332 -276.268523) (xy 279.374433 -276.252635) (xy 279.328621 -276.229292) (xy 279.287025 -276.199071)
			(xy 279.250669 -276.162715) (xy 279.220448 -276.121119) (xy 279.197105 -276.075307) (xy 279.181217 -276.026408)
			(xy 279.173174 -275.975626) (xy 278.854496 -275.975626) (xy 278.84678 -276.023102) (xy 278.831196 -276.069783)
			(xy 278.808325 -276.11336) (xy 278.77876 -276.152704) (xy 278.743267 -276.186796) (xy 278.702764 -276.214752)
			(xy 278.658302 -276.23585) (xy 278.611031 -276.249542) (xy 278.562176 -276.255474) (xy 278.513001 -276.253493)
			(xy 278.464782 -276.243649) (xy 278.418766 -276.226197) (xy 278.376145 -276.20159) (xy 278.338024 -276.170465)
			(xy 278.305389 -276.133628) (xy 278.279086 -276.092032) (xy 278.259795 -276.046756) (xy 278.248018 -275.998972)
			(xy 278.244058 -275.949918) (xy 277.927054 -275.949918) (xy 277.92655 -275.975626) (xy 277.918507 -276.026408)
			(xy 277.902619 -276.075307) (xy 277.879276 -276.121119) (xy 277.849055 -276.162715) (xy 277.812699 -276.199071)
			(xy 277.771103 -276.229292) (xy 277.725291 -276.252635) (xy 277.676392 -276.268523) (xy 277.62561 -276.276566)
			(xy 277.574194 -276.276566) (xy 277.523412 -276.268523) (xy 277.474513 -276.252635) (xy 277.428701 -276.229292)
			(xy 277.387105 -276.199071) (xy 277.350749 -276.162715) (xy 277.320528 -276.121119) (xy 277.297185 -276.075307)
			(xy 277.281297 -276.026408) (xy 277.273254 -275.975626) (xy 276.954322 -275.975626) (xy 276.946606 -276.023102)
			(xy 276.931022 -276.069783) (xy 276.908151 -276.11336) (xy 276.878586 -276.152704) (xy 276.843093 -276.186796)
			(xy 276.80259 -276.214752) (xy 276.758128 -276.23585) (xy 276.710857 -276.249542) (xy 276.662002 -276.255474)
			(xy 276.612827 -276.253493) (xy 276.564608 -276.243649) (xy 276.518592 -276.226197) (xy 276.475971 -276.20159)
			(xy 276.43785 -276.170465) (xy 276.405215 -276.133628) (xy 276.378912 -276.092032) (xy 276.359621 -276.046756)
			(xy 276.347844 -275.998972) (xy 276.343884 -275.949918) (xy 249.737118 -275.949918) (xy 249.737118 -276.424898)
			(xy 268.26897 -276.424898) (xy 268.27293 -276.375844) (xy 268.284707 -276.32806) (xy 268.303998 -276.282784)
			(xy 268.330301 -276.241188) (xy 268.362936 -276.204351) (xy 268.401057 -276.173226) (xy 268.443678 -276.148619)
			(xy 268.489694 -276.131167) (xy 268.537913 -276.121323) (xy 268.587088 -276.119342) (xy 268.635943 -276.125274)
			(xy 268.683214 -276.138966) (xy 268.727676 -276.160064) (xy 268.768179 -276.18802) (xy 268.803672 -276.222112)
			(xy 268.833237 -276.261456) (xy 268.856108 -276.305033) (xy 268.871692 -276.351714) (xy 268.879587 -276.400291)
			(xy 268.880082 -276.424898) (xy 269.21893 -276.424898) (xy 269.22289 -276.375844) (xy 269.234667 -276.32806)
			(xy 269.253958 -276.282784) (xy 269.280261 -276.241188) (xy 269.312896 -276.204351) (xy 269.351017 -276.173226)
			(xy 269.393638 -276.148619) (xy 269.439654 -276.131167) (xy 269.487873 -276.121323) (xy 269.537048 -276.119342)
			(xy 269.585903 -276.125274) (xy 269.633174 -276.138966) (xy 269.677636 -276.160064) (xy 269.718139 -276.18802)
			(xy 269.753632 -276.222112) (xy 269.783197 -276.261456) (xy 269.806068 -276.305033) (xy 269.821652 -276.351714)
			(xy 269.829547 -276.400291) (xy 269.830042 -276.424898) (xy 270.169144 -276.424898) (xy 270.173104 -276.375844)
			(xy 270.184881 -276.32806) (xy 270.204172 -276.282784) (xy 270.230475 -276.241188) (xy 270.26311 -276.204351)
			(xy 270.301231 -276.173226) (xy 270.343852 -276.148619) (xy 270.389868 -276.131167) (xy 270.438087 -276.121323)
			(xy 270.487262 -276.119342) (xy 270.536117 -276.125274) (xy 270.583388 -276.138966) (xy 270.62785 -276.160064)
			(xy 270.668353 -276.18802) (xy 270.703846 -276.222112) (xy 270.733411 -276.261456) (xy 270.756282 -276.305033)
			(xy 270.771866 -276.351714) (xy 270.779761 -276.400291) (xy 270.780256 -276.424898) (xy 271.119104 -276.424898)
			(xy 271.123064 -276.375844) (xy 271.134841 -276.32806) (xy 271.154132 -276.282784) (xy 271.180435 -276.241188)
			(xy 271.21307 -276.204351) (xy 271.251191 -276.173226) (xy 271.293812 -276.148619) (xy 271.339828 -276.131167)
			(xy 271.388047 -276.121323) (xy 271.437222 -276.119342) (xy 271.486077 -276.125274) (xy 271.533348 -276.138966)
			(xy 271.57781 -276.160064) (xy 271.618313 -276.18802) (xy 271.653806 -276.222112) (xy 271.683371 -276.261456)
			(xy 271.706242 -276.305033) (xy 271.721826 -276.351714) (xy 271.729721 -276.400291) (xy 271.730216 -276.424898)
			(xy 272.069064 -276.424898) (xy 272.073024 -276.375844) (xy 272.084801 -276.32806) (xy 272.104092 -276.282784)
			(xy 272.130395 -276.241188) (xy 272.16303 -276.204351) (xy 272.201151 -276.173226) (xy 272.243772 -276.148619)
			(xy 272.289788 -276.131167) (xy 272.338007 -276.121323) (xy 272.387182 -276.119342) (xy 272.436037 -276.125274)
			(xy 272.483308 -276.138966) (xy 272.52777 -276.160064) (xy 272.568273 -276.18802) (xy 272.603766 -276.222112)
			(xy 272.633331 -276.261456) (xy 272.656202 -276.305033) (xy 272.671786 -276.351714) (xy 272.679681 -276.400291)
			(xy 272.680176 -276.424898) (xy 273.019024 -276.424898) (xy 273.022984 -276.375844) (xy 273.034761 -276.32806)
			(xy 273.054052 -276.282784) (xy 273.080355 -276.241188) (xy 273.11299 -276.204351) (xy 273.151111 -276.173226)
			(xy 273.193732 -276.148619) (xy 273.239748 -276.131167) (xy 273.287967 -276.121323) (xy 273.337142 -276.119342)
			(xy 273.385997 -276.125274) (xy 273.433268 -276.138966) (xy 273.47773 -276.160064) (xy 273.518233 -276.18802)
			(xy 273.553726 -276.222112) (xy 273.583291 -276.261456) (xy 273.606162 -276.305033) (xy 273.621746 -276.351714)
			(xy 273.629641 -276.400291) (xy 273.630136 -276.424898) (xy 273.968984 -276.424898) (xy 273.972944 -276.375844)
			(xy 273.984721 -276.32806) (xy 274.004012 -276.282784) (xy 274.030315 -276.241188) (xy 274.06295 -276.204351)
			(xy 274.101071 -276.173226) (xy 274.143692 -276.148619) (xy 274.189708 -276.131167) (xy 274.237927 -276.121323)
			(xy 274.287102 -276.119342) (xy 274.335957 -276.125274) (xy 274.383228 -276.138966) (xy 274.42769 -276.160064)
			(xy 274.468193 -276.18802) (xy 274.503686 -276.222112) (xy 274.533251 -276.261456) (xy 274.556122 -276.305033)
			(xy 274.571706 -276.351714) (xy 274.579601 -276.400291) (xy 274.580096 -276.424898) (xy 274.918944 -276.424898)
			(xy 274.922904 -276.375844) (xy 274.934681 -276.32806) (xy 274.953972 -276.282784) (xy 274.980275 -276.241188)
			(xy 275.01291 -276.204351) (xy 275.051031 -276.173226) (xy 275.093652 -276.148619) (xy 275.139668 -276.131167)
			(xy 275.187887 -276.121323) (xy 275.237062 -276.119342) (xy 275.285917 -276.125274) (xy 275.333188 -276.138966)
			(xy 275.37765 -276.160064) (xy 275.418153 -276.18802) (xy 275.453646 -276.222112) (xy 275.483211 -276.261456)
			(xy 275.506082 -276.305033) (xy 275.521666 -276.351714) (xy 275.529561 -276.400291) (xy 275.530056 -276.424898)
			(xy 275.529561 -276.449505) (xy 275.521666 -276.498082) (xy 275.506082 -276.544763) (xy 275.483211 -276.58834)
			(xy 275.453646 -276.627684) (xy 275.418153 -276.661776) (xy 275.37765 -276.689732) (xy 275.333188 -276.71083)
			(xy 275.285917 -276.724522) (xy 275.237062 -276.730454) (xy 275.187887 -276.728473) (xy 275.139668 -276.718629)
			(xy 275.093652 -276.701177) (xy 275.051031 -276.67657) (xy 275.01291 -276.645445) (xy 274.980275 -276.608608)
			(xy 274.953972 -276.567012) (xy 274.934681 -276.521736) (xy 274.922904 -276.473952) (xy 274.918944 -276.424898)
			(xy 274.580096 -276.424898) (xy 274.579601 -276.449505) (xy 274.571706 -276.498082) (xy 274.556122 -276.544763)
			(xy 274.533251 -276.58834) (xy 274.503686 -276.627684) (xy 274.468193 -276.661776) (xy 274.42769 -276.689732)
			(xy 274.383228 -276.71083) (xy 274.335957 -276.724522) (xy 274.287102 -276.730454) (xy 274.237927 -276.728473)
			(xy 274.189708 -276.718629) (xy 274.143692 -276.701177) (xy 274.101071 -276.67657) (xy 274.06295 -276.645445)
			(xy 274.030315 -276.608608) (xy 274.004012 -276.567012) (xy 273.984721 -276.521736) (xy 273.972944 -276.473952)
			(xy 273.968984 -276.424898) (xy 273.630136 -276.424898) (xy 273.629641 -276.449505) (xy 273.621746 -276.498082)
			(xy 273.606162 -276.544763) (xy 273.583291 -276.58834) (xy 273.553726 -276.627684) (xy 273.518233 -276.661776)
			(xy 273.47773 -276.689732) (xy 273.433268 -276.71083) (xy 273.385997 -276.724522) (xy 273.337142 -276.730454)
			(xy 273.287967 -276.728473) (xy 273.239748 -276.718629) (xy 273.193732 -276.701177) (xy 273.151111 -276.67657)
			(xy 273.11299 -276.645445) (xy 273.080355 -276.608608) (xy 273.054052 -276.567012) (xy 273.034761 -276.521736)
			(xy 273.022984 -276.473952) (xy 273.019024 -276.424898) (xy 272.680176 -276.424898) (xy 272.679681 -276.449505)
			(xy 272.671786 -276.498082) (xy 272.656202 -276.544763) (xy 272.633331 -276.58834) (xy 272.603766 -276.627684)
			(xy 272.568273 -276.661776) (xy 272.52777 -276.689732) (xy 272.483308 -276.71083) (xy 272.436037 -276.724522)
			(xy 272.387182 -276.730454) (xy 272.338007 -276.728473) (xy 272.289788 -276.718629) (xy 272.243772 -276.701177)
			(xy 272.201151 -276.67657) (xy 272.16303 -276.645445) (xy 272.130395 -276.608608) (xy 272.104092 -276.567012)
			(xy 272.084801 -276.521736) (xy 272.073024 -276.473952) (xy 272.069064 -276.424898) (xy 271.730216 -276.424898)
			(xy 271.729721 -276.449505) (xy 271.721826 -276.498082) (xy 271.706242 -276.544763) (xy 271.683371 -276.58834)
			(xy 271.653806 -276.627684) (xy 271.618313 -276.661776) (xy 271.57781 -276.689732) (xy 271.533348 -276.71083)
			(xy 271.486077 -276.724522) (xy 271.437222 -276.730454) (xy 271.388047 -276.728473) (xy 271.339828 -276.718629)
			(xy 271.293812 -276.701177) (xy 271.251191 -276.67657) (xy 271.21307 -276.645445) (xy 271.180435 -276.608608)
			(xy 271.154132 -276.567012) (xy 271.134841 -276.521736) (xy 271.123064 -276.473952) (xy 271.119104 -276.424898)
			(xy 270.780256 -276.424898) (xy 270.779761 -276.449505) (xy 270.771866 -276.498082) (xy 270.756282 -276.544763)
			(xy 270.733411 -276.58834) (xy 270.703846 -276.627684) (xy 270.668353 -276.661776) (xy 270.62785 -276.689732)
			(xy 270.583388 -276.71083) (xy 270.536117 -276.724522) (xy 270.487262 -276.730454) (xy 270.438087 -276.728473)
			(xy 270.389868 -276.718629) (xy 270.343852 -276.701177) (xy 270.301231 -276.67657) (xy 270.26311 -276.645445)
			(xy 270.230475 -276.608608) (xy 270.204172 -276.567012) (xy 270.184881 -276.521736) (xy 270.173104 -276.473952)
			(xy 270.169144 -276.424898) (xy 269.830042 -276.424898) (xy 269.829547 -276.449505) (xy 269.821652 -276.498082)
			(xy 269.806068 -276.544763) (xy 269.783197 -276.58834) (xy 269.753632 -276.627684) (xy 269.718139 -276.661776)
			(xy 269.677636 -276.689732) (xy 269.633174 -276.71083) (xy 269.585903 -276.724522) (xy 269.537048 -276.730454)
			(xy 269.487873 -276.728473) (xy 269.439654 -276.718629) (xy 269.393638 -276.701177) (xy 269.351017 -276.67657)
			(xy 269.312896 -276.645445) (xy 269.280261 -276.608608) (xy 269.253958 -276.567012) (xy 269.234667 -276.521736)
			(xy 269.22289 -276.473952) (xy 269.21893 -276.424898) (xy 268.880082 -276.424898) (xy 268.879587 -276.449505)
			(xy 268.871692 -276.498082) (xy 268.856108 -276.544763) (xy 268.833237 -276.58834) (xy 268.803672 -276.627684)
			(xy 268.768179 -276.661776) (xy 268.727676 -276.689732) (xy 268.683214 -276.71083) (xy 268.635943 -276.724522)
			(xy 268.587088 -276.730454) (xy 268.537913 -276.728473) (xy 268.489694 -276.718629) (xy 268.443678 -276.701177)
			(xy 268.401057 -276.67657) (xy 268.362936 -276.645445) (xy 268.330301 -276.608608) (xy 268.303998 -276.567012)
			(xy 268.284707 -276.521736) (xy 268.27293 -276.473952) (xy 268.26897 -276.424898) (xy 249.737118 -276.424898)
			(xy 249.737118 -276.899878) (xy 276.343884 -276.899878) (xy 276.347844 -276.850824) (xy 276.359621 -276.80304)
			(xy 276.378912 -276.757764) (xy 276.405215 -276.716168) (xy 276.43785 -276.679331) (xy 276.475971 -276.648206)
			(xy 276.518592 -276.623599) (xy 276.564608 -276.606147) (xy 276.612827 -276.596303) (xy 276.662002 -276.594322)
			(xy 276.710857 -276.600254) (xy 276.758128 -276.613946) (xy 276.80259 -276.635044) (xy 276.843093 -276.663)
			(xy 276.878586 -276.697092) (xy 276.908151 -276.736436) (xy 276.931022 -276.780013) (xy 276.946606 -276.826694)
			(xy 276.954501 -276.875271) (xy 276.954996 -276.899878) (xy 277.294098 -276.899878) (xy 277.298058 -276.850824)
			(xy 277.309835 -276.80304) (xy 277.329126 -276.757764) (xy 277.355429 -276.716168) (xy 277.388064 -276.679331)
			(xy 277.426185 -276.648206) (xy 277.468806 -276.623599) (xy 277.514822 -276.606147) (xy 277.563041 -276.596303)
			(xy 277.612216 -276.594322) (xy 277.661071 -276.600254) (xy 277.708342 -276.613946) (xy 277.752804 -276.635044)
			(xy 277.793307 -276.663) (xy 277.8288 -276.697092) (xy 277.858365 -276.736436) (xy 277.881236 -276.780013)
			(xy 277.89682 -276.826694) (xy 277.904715 -276.875271) (xy 277.90521 -276.899878) (xy 278.244058 -276.899878)
			(xy 278.248018 -276.850824) (xy 278.259795 -276.80304) (xy 278.279086 -276.757764) (xy 278.305389 -276.716168)
			(xy 278.338024 -276.679331) (xy 278.376145 -276.648206) (xy 278.418766 -276.623599) (xy 278.464782 -276.606147)
			(xy 278.513001 -276.596303) (xy 278.562176 -276.594322) (xy 278.611031 -276.600254) (xy 278.658302 -276.613946)
			(xy 278.702764 -276.635044) (xy 278.743267 -276.663) (xy 278.77876 -276.697092) (xy 278.808325 -276.736436)
			(xy 278.831196 -276.780013) (xy 278.84678 -276.826694) (xy 278.854675 -276.875271) (xy 278.85517 -276.899878)
			(xy 279.194018 -276.899878) (xy 279.197978 -276.850824) (xy 279.209755 -276.80304) (xy 279.229046 -276.757764)
			(xy 279.255349 -276.716168) (xy 279.287984 -276.679331) (xy 279.326105 -276.648206) (xy 279.368726 -276.623599)
			(xy 279.414742 -276.606147) (xy 279.462961 -276.596303) (xy 279.512136 -276.594322) (xy 279.560991 -276.600254)
			(xy 279.608262 -276.613946) (xy 279.652724 -276.635044) (xy 279.693227 -276.663) (xy 279.72872 -276.697092)
			(xy 279.758285 -276.736436) (xy 279.781156 -276.780013) (xy 279.79674 -276.826694) (xy 279.804635 -276.875271)
			(xy 279.80513 -276.899878) (xy 280.143978 -276.899878) (xy 280.147938 -276.850824) (xy 280.159715 -276.80304)
			(xy 280.179006 -276.757764) (xy 280.205309 -276.716168) (xy 280.237944 -276.679331) (xy 280.276065 -276.648206)
			(xy 280.318686 -276.623599) (xy 280.364702 -276.606147) (xy 280.412921 -276.596303) (xy 280.462096 -276.594322)
			(xy 280.510951 -276.600254) (xy 280.558222 -276.613946) (xy 280.602684 -276.635044) (xy 280.643187 -276.663)
			(xy 280.67868 -276.697092) (xy 280.708245 -276.736436) (xy 280.731116 -276.780013) (xy 280.7467 -276.826694)
			(xy 280.754595 -276.875271) (xy 280.75509 -276.899878) (xy 281.093938 -276.899878) (xy 281.097898 -276.850824)
			(xy 281.109675 -276.80304) (xy 281.128966 -276.757764) (xy 281.155269 -276.716168) (xy 281.187904 -276.679331)
			(xy 281.226025 -276.648206) (xy 281.268646 -276.623599) (xy 281.314662 -276.606147) (xy 281.362881 -276.596303)
			(xy 281.412056 -276.594322) (xy 281.460911 -276.600254) (xy 281.508182 -276.613946) (xy 281.552644 -276.635044)
			(xy 281.593147 -276.663) (xy 281.62864 -276.697092) (xy 281.658205 -276.736436) (xy 281.681076 -276.780013)
			(xy 281.69666 -276.826694) (xy 281.704555 -276.875271) (xy 281.70505 -276.899878) (xy 282.043898 -276.899878)
			(xy 282.047858 -276.850824) (xy 282.059635 -276.80304) (xy 282.078926 -276.757764) (xy 282.105229 -276.716168)
			(xy 282.137864 -276.679331) (xy 282.175985 -276.648206) (xy 282.218606 -276.623599) (xy 282.264622 -276.606147)
			(xy 282.312841 -276.596303) (xy 282.362016 -276.594322) (xy 282.410871 -276.600254) (xy 282.458142 -276.613946)
			(xy 282.502604 -276.635044) (xy 282.543107 -276.663) (xy 282.5786 -276.697092) (xy 282.608165 -276.736436)
			(xy 282.631036 -276.780013) (xy 282.64662 -276.826694) (xy 282.654515 -276.875271) (xy 282.65501 -276.899878)
			(xy 282.994112 -276.899878) (xy 282.998072 -276.850824) (xy 283.009849 -276.80304) (xy 283.02914 -276.757764)
			(xy 283.055443 -276.716168) (xy 283.088078 -276.679331) (xy 283.126199 -276.648206) (xy 283.16882 -276.623599)
			(xy 283.214836 -276.606147) (xy 283.263055 -276.596303) (xy 283.31223 -276.594322) (xy 283.361085 -276.600254)
			(xy 283.408356 -276.613946) (xy 283.452818 -276.635044) (xy 283.493321 -276.663) (xy 283.528814 -276.697092)
			(xy 283.558379 -276.736436) (xy 283.58125 -276.780013) (xy 283.596834 -276.826694) (xy 283.604729 -276.875271)
			(xy 283.605224 -276.899878) (xy 283.944072 -276.899878) (xy 283.948032 -276.850824) (xy 283.959809 -276.80304)
			(xy 283.9791 -276.757764) (xy 284.005403 -276.716168) (xy 284.038038 -276.679331) (xy 284.076159 -276.648206)
			(xy 284.11878 -276.623599) (xy 284.164796 -276.606147) (xy 284.213015 -276.596303) (xy 284.26219 -276.594322)
			(xy 284.311045 -276.600254) (xy 284.358316 -276.613946) (xy 284.402778 -276.635044) (xy 284.443281 -276.663)
			(xy 284.478774 -276.697092) (xy 284.508339 -276.736436) (xy 284.53121 -276.780013) (xy 284.546794 -276.826694)
			(xy 284.554689 -276.875271) (xy 284.555184 -276.899878) (xy 284.894032 -276.899878) (xy 284.897992 -276.850824)
			(xy 284.909769 -276.80304) (xy 284.92906 -276.757764) (xy 284.955363 -276.716168) (xy 284.987998 -276.679331)
			(xy 285.026119 -276.648206) (xy 285.06874 -276.623599) (xy 285.114756 -276.606147) (xy 285.162975 -276.596303)
			(xy 285.21215 -276.594322) (xy 285.261005 -276.600254) (xy 285.308276 -276.613946) (xy 285.352738 -276.635044)
			(xy 285.393241 -276.663) (xy 285.428734 -276.697092) (xy 285.458299 -276.736436) (xy 285.48117 -276.780013)
			(xy 285.496754 -276.826694) (xy 285.504649 -276.875271) (xy 285.505144 -276.899878) (xy 285.843992 -276.899878)
			(xy 285.847952 -276.850824) (xy 285.859729 -276.80304) (xy 285.87902 -276.757764) (xy 285.905323 -276.716168)
			(xy 285.937958 -276.679331) (xy 285.976079 -276.648206) (xy 286.0187 -276.623599) (xy 286.064716 -276.606147)
			(xy 286.112935 -276.596303) (xy 286.16211 -276.594322) (xy 286.210965 -276.600254) (xy 286.258236 -276.613946)
			(xy 286.302698 -276.635044) (xy 286.343201 -276.663) (xy 286.378694 -276.697092) (xy 286.408259 -276.736436)
			(xy 286.43113 -276.780013) (xy 286.446714 -276.826694) (xy 286.454609 -276.875271) (xy 286.455104 -276.899878)
			(xy 286.793952 -276.899878) (xy 286.797912 -276.850824) (xy 286.809689 -276.80304) (xy 286.82898 -276.757764)
			(xy 286.855283 -276.716168) (xy 286.887918 -276.679331) (xy 286.926039 -276.648206) (xy 286.96866 -276.623599)
			(xy 287.014676 -276.606147) (xy 287.062895 -276.596303) (xy 287.11207 -276.594322) (xy 287.160925 -276.600254)
			(xy 287.208196 -276.613946) (xy 287.252658 -276.635044) (xy 287.293161 -276.663) (xy 287.328654 -276.697092)
			(xy 287.358219 -276.736436) (xy 287.38109 -276.780013) (xy 287.396674 -276.826694) (xy 287.404569 -276.875271)
			(xy 287.405064 -276.899878) (xy 287.743912 -276.899878) (xy 287.747872 -276.850824) (xy 287.759649 -276.80304)
			(xy 287.77894 -276.757764) (xy 287.805243 -276.716168) (xy 287.837878 -276.679331) (xy 287.875999 -276.648206)
			(xy 287.91862 -276.623599) (xy 287.964636 -276.606147) (xy 288.012855 -276.596303) (xy 288.06203 -276.594322)
			(xy 288.110885 -276.600254) (xy 288.158156 -276.613946) (xy 288.202618 -276.635044) (xy 288.243121 -276.663)
			(xy 288.278614 -276.697092) (xy 288.308179 -276.736436) (xy 288.33105 -276.780013) (xy 288.346634 -276.826694)
			(xy 288.354529 -276.875271) (xy 288.355024 -276.899878) (xy 288.694126 -276.899878) (xy 288.698086 -276.850824)
			(xy 288.709863 -276.80304) (xy 288.729154 -276.757764) (xy 288.755457 -276.716168) (xy 288.788092 -276.679331)
			(xy 288.826213 -276.648206) (xy 288.868834 -276.623599) (xy 288.91485 -276.606147) (xy 288.963069 -276.596303)
			(xy 289.012244 -276.594322) (xy 289.061099 -276.600254) (xy 289.10837 -276.613946) (xy 289.152832 -276.635044)
			(xy 289.193335 -276.663) (xy 289.228828 -276.697092) (xy 289.258393 -276.736436) (xy 289.281264 -276.780013)
			(xy 289.296848 -276.826694) (xy 289.304743 -276.875271) (xy 289.305238 -276.899878) (xy 289.304743 -276.924485)
			(xy 289.296848 -276.973062) (xy 289.281264 -277.019743) (xy 289.258393 -277.06332) (xy 289.228828 -277.102664)
			(xy 289.193335 -277.136756) (xy 289.152832 -277.164712) (xy 289.10837 -277.18581) (xy 289.061099 -277.199502)
			(xy 289.012244 -277.205434) (xy 288.963069 -277.203453) (xy 288.91485 -277.193609) (xy 288.868834 -277.176157)
			(xy 288.826213 -277.15155) (xy 288.788092 -277.120425) (xy 288.755457 -277.083588) (xy 288.729154 -277.041992)
			(xy 288.709863 -276.996716) (xy 288.698086 -276.948932) (xy 288.694126 -276.899878) (xy 288.355024 -276.899878)
			(xy 288.354529 -276.924485) (xy 288.346634 -276.973062) (xy 288.33105 -277.019743) (xy 288.308179 -277.06332)
			(xy 288.278614 -277.102664) (xy 288.243121 -277.136756) (xy 288.202618 -277.164712) (xy 288.158156 -277.18581)
			(xy 288.110885 -277.199502) (xy 288.06203 -277.205434) (xy 288.012855 -277.203453) (xy 287.964636 -277.193609)
			(xy 287.91862 -277.176157) (xy 287.875999 -277.15155) (xy 287.837878 -277.120425) (xy 287.805243 -277.083588)
			(xy 287.77894 -277.041992) (xy 287.759649 -276.996716) (xy 287.747872 -276.948932) (xy 287.743912 -276.899878)
			(xy 287.405064 -276.899878) (xy 287.404569 -276.924485) (xy 287.396674 -276.973062) (xy 287.38109 -277.019743)
			(xy 287.358219 -277.06332) (xy 287.328654 -277.102664) (xy 287.293161 -277.136756) (xy 287.252658 -277.164712)
			(xy 287.208196 -277.18581) (xy 287.160925 -277.199502) (xy 287.11207 -277.205434) (xy 287.062895 -277.203453)
			(xy 287.014676 -277.193609) (xy 286.96866 -277.176157) (xy 286.926039 -277.15155) (xy 286.887918 -277.120425)
			(xy 286.855283 -277.083588) (xy 286.82898 -277.041992) (xy 286.809689 -276.996716) (xy 286.797912 -276.948932)
			(xy 286.793952 -276.899878) (xy 286.455104 -276.899878) (xy 286.454609 -276.924485) (xy 286.446714 -276.973062)
			(xy 286.43113 -277.019743) (xy 286.408259 -277.06332) (xy 286.378694 -277.102664) (xy 286.343201 -277.136756)
			(xy 286.302698 -277.164712) (xy 286.258236 -277.18581) (xy 286.210965 -277.199502) (xy 286.16211 -277.205434)
			(xy 286.112935 -277.203453) (xy 286.064716 -277.193609) (xy 286.0187 -277.176157) (xy 285.976079 -277.15155)
			(xy 285.937958 -277.120425) (xy 285.905323 -277.083588) (xy 285.87902 -277.041992) (xy 285.859729 -276.996716)
			(xy 285.847952 -276.948932) (xy 285.843992 -276.899878) (xy 285.505144 -276.899878) (xy 285.504649 -276.924485)
			(xy 285.496754 -276.973062) (xy 285.48117 -277.019743) (xy 285.458299 -277.06332) (xy 285.428734 -277.102664)
			(xy 285.393241 -277.136756) (xy 285.352738 -277.164712) (xy 285.308276 -277.18581) (xy 285.261005 -277.199502)
			(xy 285.21215 -277.205434) (xy 285.162975 -277.203453) (xy 285.114756 -277.193609) (xy 285.06874 -277.176157)
			(xy 285.026119 -277.15155) (xy 284.987998 -277.120425) (xy 284.955363 -277.083588) (xy 284.92906 -277.041992)
			(xy 284.909769 -276.996716) (xy 284.897992 -276.948932) (xy 284.894032 -276.899878) (xy 284.555184 -276.899878)
			(xy 284.554689 -276.924485) (xy 284.546794 -276.973062) (xy 284.53121 -277.019743) (xy 284.508339 -277.06332)
			(xy 284.478774 -277.102664) (xy 284.443281 -277.136756) (xy 284.402778 -277.164712) (xy 284.358316 -277.18581)
			(xy 284.311045 -277.199502) (xy 284.26219 -277.205434) (xy 284.213015 -277.203453) (xy 284.164796 -277.193609)
			(xy 284.11878 -277.176157) (xy 284.076159 -277.15155) (xy 284.038038 -277.120425) (xy 284.005403 -277.083588)
			(xy 283.9791 -277.041992) (xy 283.959809 -276.996716) (xy 283.948032 -276.948932) (xy 283.944072 -276.899878)
			(xy 283.605224 -276.899878) (xy 283.604729 -276.924485) (xy 283.596834 -276.973062) (xy 283.58125 -277.019743)
			(xy 283.558379 -277.06332) (xy 283.528814 -277.102664) (xy 283.493321 -277.136756) (xy 283.452818 -277.164712)
			(xy 283.408356 -277.18581) (xy 283.361085 -277.199502) (xy 283.31223 -277.205434) (xy 283.263055 -277.203453)
			(xy 283.214836 -277.193609) (xy 283.16882 -277.176157) (xy 283.126199 -277.15155) (xy 283.088078 -277.120425)
			(xy 283.055443 -277.083588) (xy 283.02914 -277.041992) (xy 283.009849 -276.996716) (xy 282.998072 -276.948932)
			(xy 282.994112 -276.899878) (xy 282.65501 -276.899878) (xy 282.654515 -276.924485) (xy 282.64662 -276.973062)
			(xy 282.631036 -277.019743) (xy 282.608165 -277.06332) (xy 282.5786 -277.102664) (xy 282.543107 -277.136756)
			(xy 282.502604 -277.164712) (xy 282.458142 -277.18581) (xy 282.410871 -277.199502) (xy 282.362016 -277.205434)
			(xy 282.312841 -277.203453) (xy 282.264622 -277.193609) (xy 282.218606 -277.176157) (xy 282.175985 -277.15155)
			(xy 282.137864 -277.120425) (xy 282.105229 -277.083588) (xy 282.078926 -277.041992) (xy 282.059635 -276.996716)
			(xy 282.047858 -276.948932) (xy 282.043898 -276.899878) (xy 281.70505 -276.899878) (xy 281.704555 -276.924485)
			(xy 281.69666 -276.973062) (xy 281.681076 -277.019743) (xy 281.658205 -277.06332) (xy 281.62864 -277.102664)
			(xy 281.593147 -277.136756) (xy 281.552644 -277.164712) (xy 281.508182 -277.18581) (xy 281.460911 -277.199502)
			(xy 281.412056 -277.205434) (xy 281.362881 -277.203453) (xy 281.314662 -277.193609) (xy 281.268646 -277.176157)
			(xy 281.226025 -277.15155) (xy 281.187904 -277.120425) (xy 281.155269 -277.083588) (xy 281.128966 -277.041992)
			(xy 281.109675 -276.996716) (xy 281.097898 -276.948932) (xy 281.093938 -276.899878) (xy 280.75509 -276.899878)
			(xy 280.754595 -276.924485) (xy 280.7467 -276.973062) (xy 280.731116 -277.019743) (xy 280.708245 -277.06332)
			(xy 280.67868 -277.102664) (xy 280.643187 -277.136756) (xy 280.602684 -277.164712) (xy 280.558222 -277.18581)
			(xy 280.510951 -277.199502) (xy 280.462096 -277.205434) (xy 280.412921 -277.203453) (xy 280.364702 -277.193609)
			(xy 280.318686 -277.176157) (xy 280.276065 -277.15155) (xy 280.237944 -277.120425) (xy 280.205309 -277.083588)
			(xy 280.179006 -277.041992) (xy 280.159715 -276.996716) (xy 280.147938 -276.948932) (xy 280.143978 -276.899878)
			(xy 279.80513 -276.899878) (xy 279.804635 -276.924485) (xy 279.79674 -276.973062) (xy 279.781156 -277.019743)
			(xy 279.758285 -277.06332) (xy 279.72872 -277.102664) (xy 279.693227 -277.136756) (xy 279.652724 -277.164712)
			(xy 279.608262 -277.18581) (xy 279.560991 -277.199502) (xy 279.512136 -277.205434) (xy 279.462961 -277.203453)
			(xy 279.414742 -277.193609) (xy 279.368726 -277.176157) (xy 279.326105 -277.15155) (xy 279.287984 -277.120425)
			(xy 279.255349 -277.083588) (xy 279.229046 -277.041992) (xy 279.209755 -276.996716) (xy 279.197978 -276.948932)
			(xy 279.194018 -276.899878) (xy 278.85517 -276.899878) (xy 278.854675 -276.924485) (xy 278.84678 -276.973062)
			(xy 278.831196 -277.019743) (xy 278.808325 -277.06332) (xy 278.77876 -277.102664) (xy 278.743267 -277.136756)
			(xy 278.702764 -277.164712) (xy 278.658302 -277.18581) (xy 278.611031 -277.199502) (xy 278.562176 -277.205434)
			(xy 278.513001 -277.203453) (xy 278.464782 -277.193609) (xy 278.418766 -277.176157) (xy 278.376145 -277.15155)
			(xy 278.338024 -277.120425) (xy 278.305389 -277.083588) (xy 278.279086 -277.041992) (xy 278.259795 -276.996716)
			(xy 278.248018 -276.948932) (xy 278.244058 -276.899878) (xy 277.90521 -276.899878) (xy 277.904715 -276.924485)
			(xy 277.89682 -276.973062) (xy 277.881236 -277.019743) (xy 277.858365 -277.06332) (xy 277.8288 -277.102664)
			(xy 277.793307 -277.136756) (xy 277.752804 -277.164712) (xy 277.708342 -277.18581) (xy 277.661071 -277.199502)
			(xy 277.612216 -277.205434) (xy 277.563041 -277.203453) (xy 277.514822 -277.193609) (xy 277.468806 -277.176157)
			(xy 277.426185 -277.15155) (xy 277.388064 -277.120425) (xy 277.355429 -277.083588) (xy 277.329126 -277.041992)
			(xy 277.309835 -276.996716) (xy 277.298058 -276.948932) (xy 277.294098 -276.899878) (xy 276.954996 -276.899878)
			(xy 276.954501 -276.924485) (xy 276.946606 -276.973062) (xy 276.931022 -277.019743) (xy 276.908151 -277.06332)
			(xy 276.878586 -277.102664) (xy 276.843093 -277.136756) (xy 276.80259 -277.164712) (xy 276.758128 -277.18581)
			(xy 276.710857 -277.199502) (xy 276.662002 -277.205434) (xy 276.612827 -277.203453) (xy 276.564608 -277.193609)
			(xy 276.518592 -277.176157) (xy 276.475971 -277.15155) (xy 276.43785 -277.120425) (xy 276.405215 -277.083588)
			(xy 276.378912 -277.041992) (xy 276.359621 -276.996716) (xy 276.347844 -276.948932) (xy 276.343884 -276.899878)
			(xy 249.737118 -276.899878) (xy 249.737118 -277.374858) (xy 268.26897 -277.374858) (xy 268.27293 -277.325804)
			(xy 268.284707 -277.27802) (xy 268.303998 -277.232744) (xy 268.330301 -277.191148) (xy 268.362936 -277.154311)
			(xy 268.401057 -277.123186) (xy 268.443678 -277.098579) (xy 268.489694 -277.081127) (xy 268.537913 -277.071283)
			(xy 268.587088 -277.069302) (xy 268.635943 -277.075234) (xy 268.683214 -277.088926) (xy 268.727676 -277.110024)
			(xy 268.768179 -277.13798) (xy 268.803672 -277.172072) (xy 268.833237 -277.211416) (xy 268.856108 -277.254993)
			(xy 268.871692 -277.301674) (xy 268.879587 -277.350251) (xy 268.880082 -277.374858) (xy 269.21893 -277.374858)
			(xy 269.22289 -277.325804) (xy 269.234667 -277.27802) (xy 269.253958 -277.232744) (xy 269.280261 -277.191148)
			(xy 269.312896 -277.154311) (xy 269.351017 -277.123186) (xy 269.393638 -277.098579) (xy 269.439654 -277.081127)
			(xy 269.487873 -277.071283) (xy 269.537048 -277.069302) (xy 269.585903 -277.075234) (xy 269.633174 -277.088926)
			(xy 269.677636 -277.110024) (xy 269.718139 -277.13798) (xy 269.753632 -277.172072) (xy 269.783197 -277.211416)
			(xy 269.806068 -277.254993) (xy 269.821652 -277.301674) (xy 269.829547 -277.350251) (xy 269.830042 -277.374858)
			(xy 270.169144 -277.374858) (xy 270.173104 -277.325804) (xy 270.184881 -277.27802) (xy 270.204172 -277.232744)
			(xy 270.230475 -277.191148) (xy 270.26311 -277.154311) (xy 270.301231 -277.123186) (xy 270.343852 -277.098579)
			(xy 270.389868 -277.081127) (xy 270.438087 -277.071283) (xy 270.487262 -277.069302) (xy 270.536117 -277.075234)
			(xy 270.583388 -277.088926) (xy 270.62785 -277.110024) (xy 270.668353 -277.13798) (xy 270.703846 -277.172072)
			(xy 270.733411 -277.211416) (xy 270.756282 -277.254993) (xy 270.771866 -277.301674) (xy 270.779761 -277.350251)
			(xy 270.780256 -277.374858) (xy 271.119104 -277.374858) (xy 271.123064 -277.325804) (xy 271.134841 -277.27802)
			(xy 271.154132 -277.232744) (xy 271.180435 -277.191148) (xy 271.21307 -277.154311) (xy 271.251191 -277.123186)
			(xy 271.293812 -277.098579) (xy 271.339828 -277.081127) (xy 271.388047 -277.071283) (xy 271.437222 -277.069302)
			(xy 271.486077 -277.075234) (xy 271.533348 -277.088926) (xy 271.57781 -277.110024) (xy 271.618313 -277.13798)
			(xy 271.653806 -277.172072) (xy 271.683371 -277.211416) (xy 271.706242 -277.254993) (xy 271.721826 -277.301674)
			(xy 271.729721 -277.350251) (xy 271.730216 -277.374858) (xy 272.069064 -277.374858) (xy 272.073024 -277.325804)
			(xy 272.084801 -277.27802) (xy 272.104092 -277.232744) (xy 272.130395 -277.191148) (xy 272.16303 -277.154311)
			(xy 272.201151 -277.123186) (xy 272.243772 -277.098579) (xy 272.289788 -277.081127) (xy 272.338007 -277.071283)
			(xy 272.387182 -277.069302) (xy 272.436037 -277.075234) (xy 272.483308 -277.088926) (xy 272.52777 -277.110024)
			(xy 272.568273 -277.13798) (xy 272.603766 -277.172072) (xy 272.633331 -277.211416) (xy 272.656202 -277.254993)
			(xy 272.671786 -277.301674) (xy 272.679681 -277.350251) (xy 272.680176 -277.374858) (xy 273.019024 -277.374858)
			(xy 273.022984 -277.325804) (xy 273.034761 -277.27802) (xy 273.054052 -277.232744) (xy 273.080355 -277.191148)
			(xy 273.11299 -277.154311) (xy 273.151111 -277.123186) (xy 273.193732 -277.098579) (xy 273.239748 -277.081127)
			(xy 273.287967 -277.071283) (xy 273.337142 -277.069302) (xy 273.385997 -277.075234) (xy 273.433268 -277.088926)
			(xy 273.47773 -277.110024) (xy 273.518233 -277.13798) (xy 273.553726 -277.172072) (xy 273.583291 -277.211416)
			(xy 273.606162 -277.254993) (xy 273.621746 -277.301674) (xy 273.629641 -277.350251) (xy 273.630136 -277.374858)
			(xy 273.968984 -277.374858) (xy 273.972944 -277.325804) (xy 273.984721 -277.27802) (xy 274.004012 -277.232744)
			(xy 274.030315 -277.191148) (xy 274.06295 -277.154311) (xy 274.101071 -277.123186) (xy 274.143692 -277.098579)
			(xy 274.189708 -277.081127) (xy 274.237927 -277.071283) (xy 274.287102 -277.069302) (xy 274.335957 -277.075234)
			(xy 274.383228 -277.088926) (xy 274.42769 -277.110024) (xy 274.468193 -277.13798) (xy 274.503686 -277.172072)
			(xy 274.533251 -277.211416) (xy 274.556122 -277.254993) (xy 274.571706 -277.301674) (xy 274.579601 -277.350251)
			(xy 274.580096 -277.374858) (xy 274.918944 -277.374858) (xy 274.922904 -277.325804) (xy 274.934681 -277.27802)
			(xy 274.953972 -277.232744) (xy 274.980275 -277.191148) (xy 275.01291 -277.154311) (xy 275.051031 -277.123186)
			(xy 275.093652 -277.098579) (xy 275.139668 -277.081127) (xy 275.187887 -277.071283) (xy 275.237062 -277.069302)
			(xy 275.285917 -277.075234) (xy 275.333188 -277.088926) (xy 275.37765 -277.110024) (xy 275.418153 -277.13798)
			(xy 275.453646 -277.172072) (xy 275.483211 -277.211416) (xy 275.506082 -277.254993) (xy 275.521666 -277.301674)
			(xy 275.529561 -277.350251) (xy 275.530056 -277.374858) (xy 275.529561 -277.399465) (xy 275.521666 -277.448042)
			(xy 275.506082 -277.494723) (xy 275.483211 -277.5383) (xy 275.453646 -277.577644) (xy 275.418153 -277.611736)
			(xy 275.37765 -277.639692) (xy 275.333188 -277.66079) (xy 275.285917 -277.674482) (xy 275.237062 -277.680414)
			(xy 275.187887 -277.678433) (xy 275.139668 -277.668589) (xy 275.093652 -277.651137) (xy 275.051031 -277.62653)
			(xy 275.01291 -277.595405) (xy 274.980275 -277.558568) (xy 274.953972 -277.516972) (xy 274.934681 -277.471696)
			(xy 274.922904 -277.423912) (xy 274.918944 -277.374858) (xy 274.580096 -277.374858) (xy 274.579601 -277.399465)
			(xy 274.571706 -277.448042) (xy 274.556122 -277.494723) (xy 274.533251 -277.5383) (xy 274.503686 -277.577644)
			(xy 274.468193 -277.611736) (xy 274.42769 -277.639692) (xy 274.383228 -277.66079) (xy 274.335957 -277.674482)
			(xy 274.287102 -277.680414) (xy 274.237927 -277.678433) (xy 274.189708 -277.668589) (xy 274.143692 -277.651137)
			(xy 274.101071 -277.62653) (xy 274.06295 -277.595405) (xy 274.030315 -277.558568) (xy 274.004012 -277.516972)
			(xy 273.984721 -277.471696) (xy 273.972944 -277.423912) (xy 273.968984 -277.374858) (xy 273.630136 -277.374858)
			(xy 273.629641 -277.399465) (xy 273.621746 -277.448042) (xy 273.606162 -277.494723) (xy 273.583291 -277.5383)
			(xy 273.553726 -277.577644) (xy 273.518233 -277.611736) (xy 273.47773 -277.639692) (xy 273.433268 -277.66079)
			(xy 273.385997 -277.674482) (xy 273.337142 -277.680414) (xy 273.287967 -277.678433) (xy 273.239748 -277.668589)
			(xy 273.193732 -277.651137) (xy 273.151111 -277.62653) (xy 273.11299 -277.595405) (xy 273.080355 -277.558568)
			(xy 273.054052 -277.516972) (xy 273.034761 -277.471696) (xy 273.022984 -277.423912) (xy 273.019024 -277.374858)
			(xy 272.680176 -277.374858) (xy 272.679681 -277.399465) (xy 272.671786 -277.448042) (xy 272.656202 -277.494723)
			(xy 272.633331 -277.5383) (xy 272.603766 -277.577644) (xy 272.568273 -277.611736) (xy 272.52777 -277.639692)
			(xy 272.483308 -277.66079) (xy 272.436037 -277.674482) (xy 272.387182 -277.680414) (xy 272.338007 -277.678433)
			(xy 272.289788 -277.668589) (xy 272.243772 -277.651137) (xy 272.201151 -277.62653) (xy 272.16303 -277.595405)
			(xy 272.130395 -277.558568) (xy 272.104092 -277.516972) (xy 272.084801 -277.471696) (xy 272.073024 -277.423912)
			(xy 272.069064 -277.374858) (xy 271.730216 -277.374858) (xy 271.729721 -277.399465) (xy 271.721826 -277.448042)
			(xy 271.706242 -277.494723) (xy 271.683371 -277.5383) (xy 271.653806 -277.577644) (xy 271.618313 -277.611736)
			(xy 271.57781 -277.639692) (xy 271.533348 -277.66079) (xy 271.486077 -277.674482) (xy 271.437222 -277.680414)
			(xy 271.388047 -277.678433) (xy 271.339828 -277.668589) (xy 271.293812 -277.651137) (xy 271.251191 -277.62653)
			(xy 271.21307 -277.595405) (xy 271.180435 -277.558568) (xy 271.154132 -277.516972) (xy 271.134841 -277.471696)
			(xy 271.123064 -277.423912) (xy 271.119104 -277.374858) (xy 270.780256 -277.374858) (xy 270.779761 -277.399465)
			(xy 270.771866 -277.448042) (xy 270.756282 -277.494723) (xy 270.733411 -277.5383) (xy 270.703846 -277.577644)
			(xy 270.668353 -277.611736) (xy 270.62785 -277.639692) (xy 270.583388 -277.66079) (xy 270.536117 -277.674482)
			(xy 270.487262 -277.680414) (xy 270.438087 -277.678433) (xy 270.389868 -277.668589) (xy 270.343852 -277.651137)
			(xy 270.301231 -277.62653) (xy 270.26311 -277.595405) (xy 270.230475 -277.558568) (xy 270.204172 -277.516972)
			(xy 270.184881 -277.471696) (xy 270.173104 -277.423912) (xy 270.169144 -277.374858) (xy 269.830042 -277.374858)
			(xy 269.829547 -277.399465) (xy 269.821652 -277.448042) (xy 269.806068 -277.494723) (xy 269.783197 -277.5383)
			(xy 269.753632 -277.577644) (xy 269.718139 -277.611736) (xy 269.677636 -277.639692) (xy 269.633174 -277.66079)
			(xy 269.585903 -277.674482) (xy 269.537048 -277.680414) (xy 269.487873 -277.678433) (xy 269.439654 -277.668589)
			(xy 269.393638 -277.651137) (xy 269.351017 -277.62653) (xy 269.312896 -277.595405) (xy 269.280261 -277.558568)
			(xy 269.253958 -277.516972) (xy 269.234667 -277.471696) (xy 269.22289 -277.423912) (xy 269.21893 -277.374858)
			(xy 268.880082 -277.374858) (xy 268.879587 -277.399465) (xy 268.871692 -277.448042) (xy 268.856108 -277.494723)
			(xy 268.833237 -277.5383) (xy 268.803672 -277.577644) (xy 268.768179 -277.611736) (xy 268.727676 -277.639692)
			(xy 268.683214 -277.66079) (xy 268.635943 -277.674482) (xy 268.587088 -277.680414) (xy 268.537913 -277.678433)
			(xy 268.489694 -277.668589) (xy 268.443678 -277.651137) (xy 268.401057 -277.62653) (xy 268.362936 -277.595405)
			(xy 268.330301 -277.558568) (xy 268.303998 -277.516972) (xy 268.284707 -277.471696) (xy 268.27293 -277.423912)
			(xy 268.26897 -277.374858) (xy 249.737118 -277.374858) (xy 249.737118 -277.849838) (xy 276.343884 -277.849838)
			(xy 276.347844 -277.800784) (xy 276.359621 -277.753) (xy 276.378912 -277.707724) (xy 276.405215 -277.666128)
			(xy 276.43785 -277.629291) (xy 276.475971 -277.598166) (xy 276.518592 -277.573559) (xy 276.564608 -277.556107)
			(xy 276.612827 -277.546263) (xy 276.662002 -277.544282) (xy 276.710857 -277.550214) (xy 276.758128 -277.563906)
			(xy 276.80259 -277.585004) (xy 276.843093 -277.61296) (xy 276.878586 -277.647052) (xy 276.908151 -277.686396)
			(xy 276.931022 -277.729973) (xy 276.946606 -277.776654) (xy 276.954501 -277.825231) (xy 276.954996 -277.849838)
			(xy 277.294098 -277.849838) (xy 277.298058 -277.800784) (xy 277.309835 -277.753) (xy 277.329126 -277.707724)
			(xy 277.355429 -277.666128) (xy 277.388064 -277.629291) (xy 277.426185 -277.598166) (xy 277.468806 -277.573559)
			(xy 277.514822 -277.556107) (xy 277.563041 -277.546263) (xy 277.612216 -277.544282) (xy 277.661071 -277.550214)
			(xy 277.708342 -277.563906) (xy 277.752804 -277.585004) (xy 277.793307 -277.61296) (xy 277.8288 -277.647052)
			(xy 277.858365 -277.686396) (xy 277.881236 -277.729973) (xy 277.89682 -277.776654) (xy 277.904715 -277.825231)
			(xy 277.90521 -277.849838) (xy 278.244058 -277.849838) (xy 278.248018 -277.800784) (xy 278.259795 -277.753)
			(xy 278.279086 -277.707724) (xy 278.305389 -277.666128) (xy 278.338024 -277.629291) (xy 278.376145 -277.598166)
			(xy 278.418766 -277.573559) (xy 278.464782 -277.556107) (xy 278.513001 -277.546263) (xy 278.562176 -277.544282)
			(xy 278.611031 -277.550214) (xy 278.658302 -277.563906) (xy 278.702764 -277.585004) (xy 278.743267 -277.61296)
			(xy 278.77876 -277.647052) (xy 278.808325 -277.686396) (xy 278.831196 -277.729973) (xy 278.84678 -277.776654)
			(xy 278.854675 -277.825231) (xy 278.85517 -277.849838) (xy 279.194018 -277.849838) (xy 279.197978 -277.800784)
			(xy 279.209755 -277.753) (xy 279.229046 -277.707724) (xy 279.255349 -277.666128) (xy 279.287984 -277.629291)
			(xy 279.326105 -277.598166) (xy 279.368726 -277.573559) (xy 279.414742 -277.556107) (xy 279.462961 -277.546263)
			(xy 279.512136 -277.544282) (xy 279.560991 -277.550214) (xy 279.608262 -277.563906) (xy 279.652724 -277.585004)
			(xy 279.693227 -277.61296) (xy 279.72872 -277.647052) (xy 279.758285 -277.686396) (xy 279.781156 -277.729973)
			(xy 279.79674 -277.776654) (xy 279.804635 -277.825231) (xy 279.80513 -277.849838) (xy 280.143978 -277.849838)
			(xy 280.147938 -277.800784) (xy 280.159715 -277.753) (xy 280.179006 -277.707724) (xy 280.205309 -277.666128)
			(xy 280.237944 -277.629291) (xy 280.276065 -277.598166) (xy 280.318686 -277.573559) (xy 280.364702 -277.556107)
			(xy 280.412921 -277.546263) (xy 280.462096 -277.544282) (xy 280.510951 -277.550214) (xy 280.558222 -277.563906)
			(xy 280.602684 -277.585004) (xy 280.643187 -277.61296) (xy 280.67868 -277.647052) (xy 280.708245 -277.686396)
			(xy 280.731116 -277.729973) (xy 280.7467 -277.776654) (xy 280.754595 -277.825231) (xy 280.75509 -277.849838)
			(xy 281.093938 -277.849838) (xy 281.097898 -277.800784) (xy 281.109675 -277.753) (xy 281.128966 -277.707724)
			(xy 281.155269 -277.666128) (xy 281.187904 -277.629291) (xy 281.226025 -277.598166) (xy 281.268646 -277.573559)
			(xy 281.314662 -277.556107) (xy 281.362881 -277.546263) (xy 281.412056 -277.544282) (xy 281.460911 -277.550214)
			(xy 281.508182 -277.563906) (xy 281.552644 -277.585004) (xy 281.593147 -277.61296) (xy 281.62864 -277.647052)
			(xy 281.658205 -277.686396) (xy 281.681076 -277.729973) (xy 281.69666 -277.776654) (xy 281.704555 -277.825231)
			(xy 281.70505 -277.849838) (xy 282.043898 -277.849838) (xy 282.047858 -277.800784) (xy 282.059635 -277.753)
			(xy 282.078926 -277.707724) (xy 282.105229 -277.666128) (xy 282.137864 -277.629291) (xy 282.175985 -277.598166)
			(xy 282.218606 -277.573559) (xy 282.264622 -277.556107) (xy 282.312841 -277.546263) (xy 282.362016 -277.544282)
			(xy 282.410871 -277.550214) (xy 282.458142 -277.563906) (xy 282.502604 -277.585004) (xy 282.543107 -277.61296)
			(xy 282.5786 -277.647052) (xy 282.608165 -277.686396) (xy 282.631036 -277.729973) (xy 282.64662 -277.776654)
			(xy 282.654515 -277.825231) (xy 282.65501 -277.849838) (xy 282.994112 -277.849838) (xy 282.998072 -277.800784)
			(xy 283.009849 -277.753) (xy 283.02914 -277.707724) (xy 283.055443 -277.666128) (xy 283.088078 -277.629291)
			(xy 283.126199 -277.598166) (xy 283.16882 -277.573559) (xy 283.214836 -277.556107) (xy 283.263055 -277.546263)
			(xy 283.31223 -277.544282) (xy 283.361085 -277.550214) (xy 283.408356 -277.563906) (xy 283.452818 -277.585004)
			(xy 283.493321 -277.61296) (xy 283.528814 -277.647052) (xy 283.558379 -277.686396) (xy 283.58125 -277.729973)
			(xy 283.596834 -277.776654) (xy 283.604729 -277.825231) (xy 283.605224 -277.849838) (xy 283.944072 -277.849838)
			(xy 283.948032 -277.800784) (xy 283.959809 -277.753) (xy 283.9791 -277.707724) (xy 284.005403 -277.666128)
			(xy 284.038038 -277.629291) (xy 284.076159 -277.598166) (xy 284.11878 -277.573559) (xy 284.164796 -277.556107)
			(xy 284.213015 -277.546263) (xy 284.26219 -277.544282) (xy 284.311045 -277.550214) (xy 284.358316 -277.563906)
			(xy 284.402778 -277.585004) (xy 284.443281 -277.61296) (xy 284.478774 -277.647052) (xy 284.508339 -277.686396)
			(xy 284.53121 -277.729973) (xy 284.546794 -277.776654) (xy 284.554689 -277.825231) (xy 284.555184 -277.849838)
			(xy 284.894032 -277.849838) (xy 284.897992 -277.800784) (xy 284.909769 -277.753) (xy 284.92906 -277.707724)
			(xy 284.955363 -277.666128) (xy 284.987998 -277.629291) (xy 285.026119 -277.598166) (xy 285.06874 -277.573559)
			(xy 285.114756 -277.556107) (xy 285.162975 -277.546263) (xy 285.21215 -277.544282) (xy 285.261005 -277.550214)
			(xy 285.308276 -277.563906) (xy 285.352738 -277.585004) (xy 285.393241 -277.61296) (xy 285.428734 -277.647052)
			(xy 285.458299 -277.686396) (xy 285.48117 -277.729973) (xy 285.496754 -277.776654) (xy 285.504649 -277.825231)
			(xy 285.505144 -277.849838) (xy 285.843992 -277.849838) (xy 285.847952 -277.800784) (xy 285.859729 -277.753)
			(xy 285.87902 -277.707724) (xy 285.905323 -277.666128) (xy 285.937958 -277.629291) (xy 285.976079 -277.598166)
			(xy 286.0187 -277.573559) (xy 286.064716 -277.556107) (xy 286.112935 -277.546263) (xy 286.16211 -277.544282)
			(xy 286.210965 -277.550214) (xy 286.258236 -277.563906) (xy 286.302698 -277.585004) (xy 286.343201 -277.61296)
			(xy 286.378694 -277.647052) (xy 286.408259 -277.686396) (xy 286.43113 -277.729973) (xy 286.446714 -277.776654)
			(xy 286.454609 -277.825231) (xy 286.455104 -277.849838) (xy 286.793952 -277.849838) (xy 286.797912 -277.800784)
			(xy 286.809689 -277.753) (xy 286.82898 -277.707724) (xy 286.855283 -277.666128) (xy 286.887918 -277.629291)
			(xy 286.926039 -277.598166) (xy 286.96866 -277.573559) (xy 287.014676 -277.556107) (xy 287.062895 -277.546263)
			(xy 287.11207 -277.544282) (xy 287.160925 -277.550214) (xy 287.208196 -277.563906) (xy 287.252658 -277.585004)
			(xy 287.293161 -277.61296) (xy 287.328654 -277.647052) (xy 287.358219 -277.686396) (xy 287.38109 -277.729973)
			(xy 287.396674 -277.776654) (xy 287.404569 -277.825231) (xy 287.405064 -277.849838) (xy 287.743912 -277.849838)
			(xy 287.747872 -277.800784) (xy 287.759649 -277.753) (xy 287.77894 -277.707724) (xy 287.805243 -277.666128)
			(xy 287.837878 -277.629291) (xy 287.875999 -277.598166) (xy 287.91862 -277.573559) (xy 287.964636 -277.556107)
			(xy 288.012855 -277.546263) (xy 288.06203 -277.544282) (xy 288.110885 -277.550214) (xy 288.158156 -277.563906)
			(xy 288.202618 -277.585004) (xy 288.243121 -277.61296) (xy 288.278614 -277.647052) (xy 288.308179 -277.686396)
			(xy 288.33105 -277.729973) (xy 288.346634 -277.776654) (xy 288.354529 -277.825231) (xy 288.355024 -277.849838)
			(xy 288.694126 -277.849838) (xy 288.698086 -277.800784) (xy 288.709863 -277.753) (xy 288.729154 -277.707724)
			(xy 288.755457 -277.666128) (xy 288.788092 -277.629291) (xy 288.826213 -277.598166) (xy 288.868834 -277.573559)
			(xy 288.91485 -277.556107) (xy 288.963069 -277.546263) (xy 289.012244 -277.544282) (xy 289.061099 -277.550214)
			(xy 289.10837 -277.563906) (xy 289.152832 -277.585004) (xy 289.193335 -277.61296) (xy 289.228828 -277.647052)
			(xy 289.258393 -277.686396) (xy 289.281264 -277.729973) (xy 289.296848 -277.776654) (xy 289.304743 -277.825231)
			(xy 289.305238 -277.849838) (xy 289.304743 -277.874445) (xy 289.296848 -277.923022) (xy 289.281264 -277.969703)
			(xy 289.258393 -278.01328) (xy 289.228828 -278.052624) (xy 289.193335 -278.086716) (xy 289.152832 -278.114672)
			(xy 289.10837 -278.13577) (xy 289.061099 -278.149462) (xy 289.012244 -278.155394) (xy 288.963069 -278.153413)
			(xy 288.91485 -278.143569) (xy 288.868834 -278.126117) (xy 288.826213 -278.10151) (xy 288.788092 -278.070385)
			(xy 288.755457 -278.033548) (xy 288.729154 -277.991952) (xy 288.709863 -277.946676) (xy 288.698086 -277.898892)
			(xy 288.694126 -277.849838) (xy 288.355024 -277.849838) (xy 288.354529 -277.874445) (xy 288.346634 -277.923022)
			(xy 288.33105 -277.969703) (xy 288.308179 -278.01328) (xy 288.278614 -278.052624) (xy 288.243121 -278.086716)
			(xy 288.202618 -278.114672) (xy 288.158156 -278.13577) (xy 288.110885 -278.149462) (xy 288.06203 -278.155394)
			(xy 288.012855 -278.153413) (xy 287.964636 -278.143569) (xy 287.91862 -278.126117) (xy 287.875999 -278.10151)
			(xy 287.837878 -278.070385) (xy 287.805243 -278.033548) (xy 287.77894 -277.991952) (xy 287.759649 -277.946676)
			(xy 287.747872 -277.898892) (xy 287.743912 -277.849838) (xy 287.405064 -277.849838) (xy 287.404569 -277.874445)
			(xy 287.396674 -277.923022) (xy 287.38109 -277.969703) (xy 287.358219 -278.01328) (xy 287.328654 -278.052624)
			(xy 287.293161 -278.086716) (xy 287.252658 -278.114672) (xy 287.208196 -278.13577) (xy 287.160925 -278.149462)
			(xy 287.11207 -278.155394) (xy 287.062895 -278.153413) (xy 287.014676 -278.143569) (xy 286.96866 -278.126117)
			(xy 286.926039 -278.10151) (xy 286.887918 -278.070385) (xy 286.855283 -278.033548) (xy 286.82898 -277.991952)
			(xy 286.809689 -277.946676) (xy 286.797912 -277.898892) (xy 286.793952 -277.849838) (xy 286.455104 -277.849838)
			(xy 286.454609 -277.874445) (xy 286.446714 -277.923022) (xy 286.43113 -277.969703) (xy 286.408259 -278.01328)
			(xy 286.378694 -278.052624) (xy 286.343201 -278.086716) (xy 286.302698 -278.114672) (xy 286.258236 -278.13577)
			(xy 286.210965 -278.149462) (xy 286.16211 -278.155394) (xy 286.112935 -278.153413) (xy 286.064716 -278.143569)
			(xy 286.0187 -278.126117) (xy 285.976079 -278.10151) (xy 285.937958 -278.070385) (xy 285.905323 -278.033548)
			(xy 285.87902 -277.991952) (xy 285.859729 -277.946676) (xy 285.847952 -277.898892) (xy 285.843992 -277.849838)
			(xy 285.505144 -277.849838) (xy 285.504649 -277.874445) (xy 285.496754 -277.923022) (xy 285.48117 -277.969703)
			(xy 285.458299 -278.01328) (xy 285.428734 -278.052624) (xy 285.393241 -278.086716) (xy 285.352738 -278.114672)
			(xy 285.308276 -278.13577) (xy 285.261005 -278.149462) (xy 285.21215 -278.155394) (xy 285.162975 -278.153413)
			(xy 285.114756 -278.143569) (xy 285.06874 -278.126117) (xy 285.026119 -278.10151) (xy 284.987998 -278.070385)
			(xy 284.955363 -278.033548) (xy 284.92906 -277.991952) (xy 284.909769 -277.946676) (xy 284.897992 -277.898892)
			(xy 284.894032 -277.849838) (xy 284.555184 -277.849838) (xy 284.554689 -277.874445) (xy 284.546794 -277.923022)
			(xy 284.53121 -277.969703) (xy 284.508339 -278.01328) (xy 284.478774 -278.052624) (xy 284.443281 -278.086716)
			(xy 284.402778 -278.114672) (xy 284.358316 -278.13577) (xy 284.311045 -278.149462) (xy 284.26219 -278.155394)
			(xy 284.213015 -278.153413) (xy 284.164796 -278.143569) (xy 284.11878 -278.126117) (xy 284.076159 -278.10151)
			(xy 284.038038 -278.070385) (xy 284.005403 -278.033548) (xy 283.9791 -277.991952) (xy 283.959809 -277.946676)
			(xy 283.948032 -277.898892) (xy 283.944072 -277.849838) (xy 283.605224 -277.849838) (xy 283.604729 -277.874445)
			(xy 283.596834 -277.923022) (xy 283.58125 -277.969703) (xy 283.558379 -278.01328) (xy 283.528814 -278.052624)
			(xy 283.493321 -278.086716) (xy 283.452818 -278.114672) (xy 283.408356 -278.13577) (xy 283.361085 -278.149462)
			(xy 283.31223 -278.155394) (xy 283.263055 -278.153413) (xy 283.214836 -278.143569) (xy 283.16882 -278.126117)
			(xy 283.126199 -278.10151) (xy 283.088078 -278.070385) (xy 283.055443 -278.033548) (xy 283.02914 -277.991952)
			(xy 283.009849 -277.946676) (xy 282.998072 -277.898892) (xy 282.994112 -277.849838) (xy 282.65501 -277.849838)
			(xy 282.654515 -277.874445) (xy 282.64662 -277.923022) (xy 282.631036 -277.969703) (xy 282.608165 -278.01328)
			(xy 282.5786 -278.052624) (xy 282.543107 -278.086716) (xy 282.502604 -278.114672) (xy 282.458142 -278.13577)
			(xy 282.410871 -278.149462) (xy 282.362016 -278.155394) (xy 282.312841 -278.153413) (xy 282.264622 -278.143569)
			(xy 282.218606 -278.126117) (xy 282.175985 -278.10151) (xy 282.137864 -278.070385) (xy 282.105229 -278.033548)
			(xy 282.078926 -277.991952) (xy 282.059635 -277.946676) (xy 282.047858 -277.898892) (xy 282.043898 -277.849838)
			(xy 281.70505 -277.849838) (xy 281.704555 -277.874445) (xy 281.69666 -277.923022) (xy 281.681076 -277.969703)
			(xy 281.658205 -278.01328) (xy 281.62864 -278.052624) (xy 281.593147 -278.086716) (xy 281.552644 -278.114672)
			(xy 281.508182 -278.13577) (xy 281.460911 -278.149462) (xy 281.412056 -278.155394) (xy 281.362881 -278.153413)
			(xy 281.314662 -278.143569) (xy 281.268646 -278.126117) (xy 281.226025 -278.10151) (xy 281.187904 -278.070385)
			(xy 281.155269 -278.033548) (xy 281.128966 -277.991952) (xy 281.109675 -277.946676) (xy 281.097898 -277.898892)
			(xy 281.093938 -277.849838) (xy 280.75509 -277.849838) (xy 280.754595 -277.874445) (xy 280.7467 -277.923022)
			(xy 280.731116 -277.969703) (xy 280.708245 -278.01328) (xy 280.67868 -278.052624) (xy 280.643187 -278.086716)
			(xy 280.602684 -278.114672) (xy 280.558222 -278.13577) (xy 280.510951 -278.149462) (xy 280.462096 -278.155394)
			(xy 280.412921 -278.153413) (xy 280.364702 -278.143569) (xy 280.318686 -278.126117) (xy 280.276065 -278.10151)
			(xy 280.237944 -278.070385) (xy 280.205309 -278.033548) (xy 280.179006 -277.991952) (xy 280.159715 -277.946676)
			(xy 280.147938 -277.898892) (xy 280.143978 -277.849838) (xy 279.80513 -277.849838) (xy 279.804635 -277.874445)
			(xy 279.79674 -277.923022) (xy 279.781156 -277.969703) (xy 279.758285 -278.01328) (xy 279.72872 -278.052624)
			(xy 279.693227 -278.086716) (xy 279.652724 -278.114672) (xy 279.608262 -278.13577) (xy 279.560991 -278.149462)
			(xy 279.512136 -278.155394) (xy 279.462961 -278.153413) (xy 279.414742 -278.143569) (xy 279.368726 -278.126117)
			(xy 279.326105 -278.10151) (xy 279.287984 -278.070385) (xy 279.255349 -278.033548) (xy 279.229046 -277.991952)
			(xy 279.209755 -277.946676) (xy 279.197978 -277.898892) (xy 279.194018 -277.849838) (xy 278.85517 -277.849838)
			(xy 278.854675 -277.874445) (xy 278.84678 -277.923022) (xy 278.831196 -277.969703) (xy 278.808325 -278.01328)
			(xy 278.77876 -278.052624) (xy 278.743267 -278.086716) (xy 278.702764 -278.114672) (xy 278.658302 -278.13577)
			(xy 278.611031 -278.149462) (xy 278.562176 -278.155394) (xy 278.513001 -278.153413) (xy 278.464782 -278.143569)
			(xy 278.418766 -278.126117) (xy 278.376145 -278.10151) (xy 278.338024 -278.070385) (xy 278.305389 -278.033548)
			(xy 278.279086 -277.991952) (xy 278.259795 -277.946676) (xy 278.248018 -277.898892) (xy 278.244058 -277.849838)
			(xy 277.90521 -277.849838) (xy 277.904715 -277.874445) (xy 277.89682 -277.923022) (xy 277.881236 -277.969703)
			(xy 277.858365 -278.01328) (xy 277.8288 -278.052624) (xy 277.793307 -278.086716) (xy 277.752804 -278.114672)
			(xy 277.708342 -278.13577) (xy 277.661071 -278.149462) (xy 277.612216 -278.155394) (xy 277.563041 -278.153413)
			(xy 277.514822 -278.143569) (xy 277.468806 -278.126117) (xy 277.426185 -278.10151) (xy 277.388064 -278.070385)
			(xy 277.355429 -278.033548) (xy 277.329126 -277.991952) (xy 277.309835 -277.946676) (xy 277.298058 -277.898892)
			(xy 277.294098 -277.849838) (xy 276.954996 -277.849838) (xy 276.954501 -277.874445) (xy 276.946606 -277.923022)
			(xy 276.931022 -277.969703) (xy 276.908151 -278.01328) (xy 276.878586 -278.052624) (xy 276.843093 -278.086716)
			(xy 276.80259 -278.114672) (xy 276.758128 -278.13577) (xy 276.710857 -278.149462) (xy 276.662002 -278.155394)
			(xy 276.612827 -278.153413) (xy 276.564608 -278.143569) (xy 276.518592 -278.126117) (xy 276.475971 -278.10151)
			(xy 276.43785 -278.070385) (xy 276.405215 -278.033548) (xy 276.378912 -277.991952) (xy 276.359621 -277.946676)
			(xy 276.347844 -277.898892) (xy 276.343884 -277.849838) (xy 249.737118 -277.849838) (xy 249.737118 -278.324818)
			(xy 268.26897 -278.324818) (xy 268.27293 -278.275764) (xy 268.284707 -278.22798) (xy 268.303998 -278.182704)
			(xy 268.330301 -278.141108) (xy 268.362936 -278.104271) (xy 268.401057 -278.073146) (xy 268.443678 -278.048539)
			(xy 268.489694 -278.031087) (xy 268.537913 -278.021243) (xy 268.587088 -278.019262) (xy 268.635943 -278.025194)
			(xy 268.683214 -278.038886) (xy 268.727676 -278.059984) (xy 268.768179 -278.08794) (xy 268.803672 -278.122032)
			(xy 268.833237 -278.161376) (xy 268.856108 -278.204953) (xy 268.871692 -278.251634) (xy 268.879587 -278.300211)
			(xy 268.880082 -278.324818) (xy 269.21893 -278.324818) (xy 269.22289 -278.275764) (xy 269.234667 -278.22798)
			(xy 269.253958 -278.182704) (xy 269.280261 -278.141108) (xy 269.312896 -278.104271) (xy 269.351017 -278.073146)
			(xy 269.393638 -278.048539) (xy 269.439654 -278.031087) (xy 269.487873 -278.021243) (xy 269.537048 -278.019262)
			(xy 269.585903 -278.025194) (xy 269.633174 -278.038886) (xy 269.677636 -278.059984) (xy 269.718139 -278.08794)
			(xy 269.753632 -278.122032) (xy 269.783197 -278.161376) (xy 269.806068 -278.204953) (xy 269.821652 -278.251634)
			(xy 269.829547 -278.300211) (xy 269.830042 -278.324818) (xy 270.169144 -278.324818) (xy 270.173104 -278.275764)
			(xy 270.184881 -278.22798) (xy 270.204172 -278.182704) (xy 270.230475 -278.141108) (xy 270.26311 -278.104271)
			(xy 270.301231 -278.073146) (xy 270.343852 -278.048539) (xy 270.389868 -278.031087) (xy 270.438087 -278.021243)
			(xy 270.487262 -278.019262) (xy 270.536117 -278.025194) (xy 270.583388 -278.038886) (xy 270.62785 -278.059984)
			(xy 270.668353 -278.08794) (xy 270.703846 -278.122032) (xy 270.733411 -278.161376) (xy 270.756282 -278.204953)
			(xy 270.771866 -278.251634) (xy 270.779761 -278.300211) (xy 270.780256 -278.324818) (xy 271.119104 -278.324818)
			(xy 271.123064 -278.275764) (xy 271.134841 -278.22798) (xy 271.154132 -278.182704) (xy 271.180435 -278.141108)
			(xy 271.21307 -278.104271) (xy 271.251191 -278.073146) (xy 271.293812 -278.048539) (xy 271.339828 -278.031087)
			(xy 271.388047 -278.021243) (xy 271.437222 -278.019262) (xy 271.486077 -278.025194) (xy 271.533348 -278.038886)
			(xy 271.57781 -278.059984) (xy 271.618313 -278.08794) (xy 271.653806 -278.122032) (xy 271.683371 -278.161376)
			(xy 271.706242 -278.204953) (xy 271.721826 -278.251634) (xy 271.729721 -278.300211) (xy 271.730216 -278.324818)
			(xy 272.069064 -278.324818) (xy 272.073024 -278.275764) (xy 272.084801 -278.22798) (xy 272.104092 -278.182704)
			(xy 272.130395 -278.141108) (xy 272.16303 -278.104271) (xy 272.201151 -278.073146) (xy 272.243772 -278.048539)
			(xy 272.289788 -278.031087) (xy 272.338007 -278.021243) (xy 272.387182 -278.019262) (xy 272.436037 -278.025194)
			(xy 272.483308 -278.038886) (xy 272.52777 -278.059984) (xy 272.568273 -278.08794) (xy 272.603766 -278.122032)
			(xy 272.633331 -278.161376) (xy 272.656202 -278.204953) (xy 272.671786 -278.251634) (xy 272.679681 -278.300211)
			(xy 272.680176 -278.324818) (xy 273.019024 -278.324818) (xy 273.022984 -278.275764) (xy 273.034761 -278.22798)
			(xy 273.054052 -278.182704) (xy 273.080355 -278.141108) (xy 273.11299 -278.104271) (xy 273.151111 -278.073146)
			(xy 273.193732 -278.048539) (xy 273.239748 -278.031087) (xy 273.287967 -278.021243) (xy 273.337142 -278.019262)
			(xy 273.385997 -278.025194) (xy 273.433268 -278.038886) (xy 273.47773 -278.059984) (xy 273.518233 -278.08794)
			(xy 273.553726 -278.122032) (xy 273.583291 -278.161376) (xy 273.606162 -278.204953) (xy 273.621746 -278.251634)
			(xy 273.629641 -278.300211) (xy 273.630136 -278.324818) (xy 273.968984 -278.324818) (xy 273.972944 -278.275764)
			(xy 273.984721 -278.22798) (xy 274.004012 -278.182704) (xy 274.030315 -278.141108) (xy 274.06295 -278.104271)
			(xy 274.101071 -278.073146) (xy 274.143692 -278.048539) (xy 274.189708 -278.031087) (xy 274.237927 -278.021243)
			(xy 274.287102 -278.019262) (xy 274.335957 -278.025194) (xy 274.383228 -278.038886) (xy 274.42769 -278.059984)
			(xy 274.468193 -278.08794) (xy 274.503686 -278.122032) (xy 274.533251 -278.161376) (xy 274.556122 -278.204953)
			(xy 274.571706 -278.251634) (xy 274.579601 -278.300211) (xy 274.580096 -278.324818) (xy 274.918944 -278.324818)
			(xy 274.922904 -278.275764) (xy 274.934681 -278.22798) (xy 274.953972 -278.182704) (xy 274.980275 -278.141108)
			(xy 275.01291 -278.104271) (xy 275.051031 -278.073146) (xy 275.093652 -278.048539) (xy 275.139668 -278.031087)
			(xy 275.187887 -278.021243) (xy 275.237062 -278.019262) (xy 275.285917 -278.025194) (xy 275.333188 -278.038886)
			(xy 275.37765 -278.059984) (xy 275.418153 -278.08794) (xy 275.453646 -278.122032) (xy 275.483211 -278.161376)
			(xy 275.506082 -278.204953) (xy 275.521666 -278.251634) (xy 275.529561 -278.300211) (xy 275.530056 -278.324818)
			(xy 275.529561 -278.349425) (xy 275.521666 -278.398002) (xy 275.506082 -278.444683) (xy 275.483211 -278.48826)
			(xy 275.453646 -278.527604) (xy 275.418153 -278.561696) (xy 275.37765 -278.589652) (xy 275.333188 -278.61075)
			(xy 275.285917 -278.624442) (xy 275.237062 -278.630374) (xy 275.187887 -278.628393) (xy 275.139668 -278.618549)
			(xy 275.093652 -278.601097) (xy 275.051031 -278.57649) (xy 275.01291 -278.545365) (xy 274.980275 -278.508528)
			(xy 274.953972 -278.466932) (xy 274.934681 -278.421656) (xy 274.922904 -278.373872) (xy 274.918944 -278.324818)
			(xy 274.580096 -278.324818) (xy 274.579601 -278.349425) (xy 274.571706 -278.398002) (xy 274.556122 -278.444683)
			(xy 274.533251 -278.48826) (xy 274.503686 -278.527604) (xy 274.468193 -278.561696) (xy 274.42769 -278.589652)
			(xy 274.383228 -278.61075) (xy 274.335957 -278.624442) (xy 274.287102 -278.630374) (xy 274.237927 -278.628393)
			(xy 274.189708 -278.618549) (xy 274.143692 -278.601097) (xy 274.101071 -278.57649) (xy 274.06295 -278.545365)
			(xy 274.030315 -278.508528) (xy 274.004012 -278.466932) (xy 273.984721 -278.421656) (xy 273.972944 -278.373872)
			(xy 273.968984 -278.324818) (xy 273.630136 -278.324818) (xy 273.629641 -278.349425) (xy 273.621746 -278.398002)
			(xy 273.606162 -278.444683) (xy 273.583291 -278.48826) (xy 273.553726 -278.527604) (xy 273.518233 -278.561696)
			(xy 273.47773 -278.589652) (xy 273.433268 -278.61075) (xy 273.385997 -278.624442) (xy 273.337142 -278.630374)
			(xy 273.287967 -278.628393) (xy 273.239748 -278.618549) (xy 273.193732 -278.601097) (xy 273.151111 -278.57649)
			(xy 273.11299 -278.545365) (xy 273.080355 -278.508528) (xy 273.054052 -278.466932) (xy 273.034761 -278.421656)
			(xy 273.022984 -278.373872) (xy 273.019024 -278.324818) (xy 272.680176 -278.324818) (xy 272.679681 -278.349425)
			(xy 272.671786 -278.398002) (xy 272.656202 -278.444683) (xy 272.633331 -278.48826) (xy 272.603766 -278.527604)
			(xy 272.568273 -278.561696) (xy 272.52777 -278.589652) (xy 272.483308 -278.61075) (xy 272.436037 -278.624442)
			(xy 272.387182 -278.630374) (xy 272.338007 -278.628393) (xy 272.289788 -278.618549) (xy 272.243772 -278.601097)
			(xy 272.201151 -278.57649) (xy 272.16303 -278.545365) (xy 272.130395 -278.508528) (xy 272.104092 -278.466932)
			(xy 272.084801 -278.421656) (xy 272.073024 -278.373872) (xy 272.069064 -278.324818) (xy 271.730216 -278.324818)
			(xy 271.729721 -278.349425) (xy 271.721826 -278.398002) (xy 271.706242 -278.444683) (xy 271.683371 -278.48826)
			(xy 271.653806 -278.527604) (xy 271.618313 -278.561696) (xy 271.57781 -278.589652) (xy 271.533348 -278.61075)
			(xy 271.486077 -278.624442) (xy 271.437222 -278.630374) (xy 271.388047 -278.628393) (xy 271.339828 -278.618549)
			(xy 271.293812 -278.601097) (xy 271.251191 -278.57649) (xy 271.21307 -278.545365) (xy 271.180435 -278.508528)
			(xy 271.154132 -278.466932) (xy 271.134841 -278.421656) (xy 271.123064 -278.373872) (xy 271.119104 -278.324818)
			(xy 270.780256 -278.324818) (xy 270.779761 -278.349425) (xy 270.771866 -278.398002) (xy 270.756282 -278.444683)
			(xy 270.733411 -278.48826) (xy 270.703846 -278.527604) (xy 270.668353 -278.561696) (xy 270.62785 -278.589652)
			(xy 270.583388 -278.61075) (xy 270.536117 -278.624442) (xy 270.487262 -278.630374) (xy 270.438087 -278.628393)
			(xy 270.389868 -278.618549) (xy 270.343852 -278.601097) (xy 270.301231 -278.57649) (xy 270.26311 -278.545365)
			(xy 270.230475 -278.508528) (xy 270.204172 -278.466932) (xy 270.184881 -278.421656) (xy 270.173104 -278.373872)
			(xy 270.169144 -278.324818) (xy 269.830042 -278.324818) (xy 269.829547 -278.349425) (xy 269.821652 -278.398002)
			(xy 269.806068 -278.444683) (xy 269.783197 -278.48826) (xy 269.753632 -278.527604) (xy 269.718139 -278.561696)
			(xy 269.677636 -278.589652) (xy 269.633174 -278.61075) (xy 269.585903 -278.624442) (xy 269.537048 -278.630374)
			(xy 269.487873 -278.628393) (xy 269.439654 -278.618549) (xy 269.393638 -278.601097) (xy 269.351017 -278.57649)
			(xy 269.312896 -278.545365) (xy 269.280261 -278.508528) (xy 269.253958 -278.466932) (xy 269.234667 -278.421656)
			(xy 269.22289 -278.373872) (xy 269.21893 -278.324818) (xy 268.880082 -278.324818) (xy 268.879587 -278.349425)
			(xy 268.871692 -278.398002) (xy 268.856108 -278.444683) (xy 268.833237 -278.48826) (xy 268.803672 -278.527604)
			(xy 268.768179 -278.561696) (xy 268.727676 -278.589652) (xy 268.683214 -278.61075) (xy 268.635943 -278.624442)
			(xy 268.587088 -278.630374) (xy 268.537913 -278.628393) (xy 268.489694 -278.618549) (xy 268.443678 -278.601097)
			(xy 268.401057 -278.57649) (xy 268.362936 -278.545365) (xy 268.330301 -278.508528) (xy 268.303998 -278.466932)
			(xy 268.284707 -278.421656) (xy 268.27293 -278.373872) (xy 268.26897 -278.324818) (xy 249.737118 -278.324818)
			(xy 249.737118 -278.811482) (xy 250.954284 -278.811482) (xy 250.958355 -278.75586) (xy 250.970481 -278.701423)
			(xy 250.990404 -278.649332) (xy 251.0177 -278.600697) (xy 251.051786 -278.556554) (xy 251.091935 -278.517845)
			(xy 251.137293 -278.485394) (xy 251.186893 -278.459893) (xy 251.239677 -278.441886) (xy 251.29452 -278.431756)
			(xy 251.350254 -278.429719) (xy 251.405691 -278.435819) (xy 251.459648 -278.449925) (xy 251.510977 -278.471737)
			(xy 251.558583 -278.500791) (xy 251.601451 -278.536466) (xy 251.638668 -278.578003) (xy 251.669441 -278.624516)
			(xy 251.693113 -278.675013) (xy 251.709181 -278.72842) (xy 251.717301 -278.783596) (xy 251.71781 -278.811482)
			(xy 251.717301 -278.839368) (xy 251.709181 -278.894544) (xy 251.693113 -278.947951) (xy 251.669441 -278.998448)
			(xy 251.638668 -279.044961) (xy 251.601451 -279.086498) (xy 251.558583 -279.122173) (xy 251.510977 -279.151227)
			(xy 251.459648 -279.173039) (xy 251.405691 -279.187145) (xy 251.350254 -279.193245) (xy 251.29452 -279.191208)
			(xy 251.239677 -279.181078) (xy 251.186893 -279.163071) (xy 251.137293 -279.13757) (xy 251.091935 -279.105119)
			(xy 251.051786 -279.06641) (xy 251.0177 -279.022267) (xy 250.990404 -278.973632) (xy 250.970481 -278.921541)
			(xy 250.958355 -278.867104) (xy 250.954284 -278.811482) (xy 249.737118 -278.811482) (xy 249.737118 -279.931114)
			(xy 258.01142 -279.931114) (xy 258.015491 -279.875492) (xy 258.027617 -279.821055) (xy 258.04754 -279.768964)
			(xy 258.074836 -279.720329) (xy 258.108922 -279.676186) (xy 258.149071 -279.637477) (xy 258.194429 -279.605026)
			(xy 258.244029 -279.579525) (xy 258.296813 -279.561518) (xy 258.351656 -279.551388) (xy 258.40739 -279.549351)
			(xy 258.462827 -279.555451) (xy 258.516784 -279.569557) (xy 258.568113 -279.591369) (xy 258.615719 -279.620423)
			(xy 258.658587 -279.656098) (xy 258.695804 -279.697635) (xy 258.726577 -279.744148) (xy 258.750249 -279.794645)
			(xy 258.766317 -279.848052) (xy 258.774437 -279.903228) (xy 258.774946 -279.931114) (xy 259.486906 -279.931114)
			(xy 259.490977 -279.875492) (xy 259.503103 -279.821055) (xy 259.523026 -279.768964) (xy 259.550322 -279.720329)
			(xy 259.584408 -279.676186) (xy 259.624557 -279.637477) (xy 259.669915 -279.605026) (xy 259.719515 -279.579525)
			(xy 259.772299 -279.561518) (xy 259.827142 -279.551388) (xy 259.882876 -279.549351) (xy 259.938313 -279.555451)
			(xy 259.99227 -279.569557) (xy 260.043599 -279.591369) (xy 260.091205 -279.620423) (xy 260.134073 -279.656098)
			(xy 260.17129 -279.697635) (xy 260.202063 -279.744148) (xy 260.225735 -279.794645) (xy 260.241803 -279.848052)
			(xy 260.249923 -279.903228) (xy 260.250432 -279.931114) (xy 260.249923 -279.959) (xy 260.241803 -280.014176)
			(xy 260.228584 -280.058114) (xy 260.375906 -280.058114) (xy 260.379977 -280.002492) (xy 260.392103 -279.948055)
			(xy 260.412026 -279.895964) (xy 260.439322 -279.847329) (xy 260.473408 -279.803186) (xy 260.513557 -279.764477)
			(xy 260.558915 -279.732026) (xy 260.608515 -279.706525) (xy 260.661299 -279.688518) (xy 260.716142 -279.678388)
			(xy 260.771876 -279.676351) (xy 260.827313 -279.682451) (xy 260.88127 -279.696557) (xy 260.932599 -279.718369)
			(xy 260.980205 -279.747423) (xy 261.023073 -279.783098) (xy 261.06029 -279.824635) (xy 261.091063 -279.871148)
			(xy 261.114735 -279.921645) (xy 261.130803 -279.975052) (xy 261.138923 -280.030228) (xy 261.139432 -280.058114)
			(xy 261.138923 -280.086) (xy 261.130803 -280.141176) (xy 261.114735 -280.194583) (xy 261.091063 -280.24508)
			(xy 261.06029 -280.291593) (xy 261.023073 -280.33313) (xy 260.980205 -280.368805) (xy 260.932599 -280.397859)
			(xy 260.88127 -280.419671) (xy 260.827313 -280.433777) (xy 260.771876 -280.439877) (xy 260.716142 -280.43784)
			(xy 260.661299 -280.42771) (xy 260.608515 -280.409703) (xy 260.558915 -280.384202) (xy 260.513557 -280.351751)
			(xy 260.473408 -280.313042) (xy 260.439322 -280.268899) (xy 260.412026 -280.220264) (xy 260.392103 -280.168173)
			(xy 260.379977 -280.113736) (xy 260.375906 -280.058114) (xy 260.228584 -280.058114) (xy 260.225735 -280.067583)
			(xy 260.202063 -280.11808) (xy 260.17129 -280.164593) (xy 260.134073 -280.20613) (xy 260.091205 -280.241805)
			(xy 260.043599 -280.270859) (xy 259.99227 -280.292671) (xy 259.938313 -280.306777) (xy 259.882876 -280.312877)
			(xy 259.827142 -280.31084) (xy 259.772299 -280.30071) (xy 259.719515 -280.282703) (xy 259.669915 -280.257202)
			(xy 259.624557 -280.224751) (xy 259.584408 -280.186042) (xy 259.550322 -280.141899) (xy 259.523026 -280.093264)
			(xy 259.503103 -280.041173) (xy 259.490977 -279.986736) (xy 259.486906 -279.931114) (xy 258.774946 -279.931114)
			(xy 258.774437 -279.959) (xy 258.766317 -280.014176) (xy 258.750249 -280.067583) (xy 258.726577 -280.11808)
			(xy 258.695804 -280.164593) (xy 258.658587 -280.20613) (xy 258.615719 -280.241805) (xy 258.568113 -280.270859)
			(xy 258.516784 -280.292671) (xy 258.462827 -280.306777) (xy 258.40739 -280.312877) (xy 258.351656 -280.31084)
			(xy 258.296813 -280.30071) (xy 258.244029 -280.282703) (xy 258.194429 -280.257202) (xy 258.149071 -280.224751)
			(xy 258.108922 -280.186042) (xy 258.074836 -280.141899) (xy 258.04754 -280.093264) (xy 258.027617 -280.041173)
			(xy 258.015491 -279.986736) (xy 258.01142 -279.931114) (xy 249.737118 -279.931114) (xy 249.737118 -280.693114)
			(xy 263.537954 -280.693114) (xy 263.53852 -280.663733) (xy 263.547548 -280.605668) (xy 263.565376 -280.549675)
			(xy 263.591583 -280.49708) (xy 263.625547 -280.449128) (xy 263.666466 -280.406954) (xy 263.689592 -280.388822)
			(xy 263.69899 -280.381456) (xy 263.709404 -280.360882) (xy 263.710928 -280.256996) (xy 263.701022 -280.235914)
			(xy 263.691878 -280.228548) (xy 263.670018 -280.210356) (xy 263.63148 -280.168533) (xy 263.599575 -280.121455)
			(xy 263.57501 -280.070163) (xy 263.558329 -280.015793) (xy 263.549902 -279.95955) (xy 263.549384 -279.931114)
			(xy 263.549845 -279.902465) (xy 263.558404 -279.84581) (xy 263.575347 -279.791075) (xy 263.600292 -279.739492)
			(xy 263.632676 -279.692224) (xy 263.671771 -279.650336) (xy 263.716696 -279.614772) (xy 263.766437 -279.586332)
			(xy 263.79297 -279.575514) (xy 263.806178 -279.57018) (xy 263.82345 -279.548336) (xy 263.83742 -279.430988)
			(xy 263.82599 -279.405588) (xy 263.814306 -279.39746) (xy 263.793069 -279.38209) (xy 263.754616 -279.346457)
			(xy 263.7214 -279.305899) (xy 263.694043 -279.261178) (xy 263.673062 -279.213136) (xy 263.65885 -279.162675)
			(xy 263.651674 -279.110744) (xy 263.651238 -279.084532) (xy 263.651724 -279.057281) (xy 263.65948 -279.003333)
			(xy 263.674835 -278.951038) (xy 263.697477 -278.901461) (xy 263.726943 -278.855611) (xy 263.762634 -278.81442)
			(xy 263.803825 -278.778729) (xy 263.849675 -278.749263) (xy 263.899252 -278.726621) (xy 263.951547 -278.711266)
			(xy 264.005495 -278.70351) (xy 264.059997 -278.70351) (xy 264.113945 -278.711266) (xy 264.16624 -278.726621)
			(xy 264.215817 -278.749263) (xy 264.261667 -278.778729) (xy 264.285983 -278.799798) (xy 276.343884 -278.799798)
			(xy 276.347844 -278.750744) (xy 276.359621 -278.70296) (xy 276.378912 -278.657684) (xy 276.405215 -278.616088)
			(xy 276.43785 -278.579251) (xy 276.475971 -278.548126) (xy 276.518592 -278.523519) (xy 276.564608 -278.506067)
			(xy 276.612827 -278.496223) (xy 276.662002 -278.494242) (xy 276.710857 -278.500174) (xy 276.758128 -278.513866)
			(xy 276.80259 -278.534964) (xy 276.843093 -278.56292) (xy 276.878586 -278.597012) (xy 276.908151 -278.636356)
			(xy 276.931022 -278.679933) (xy 276.946606 -278.726614) (xy 276.954501 -278.775191) (xy 276.954996 -278.799798)
			(xy 277.294098 -278.799798) (xy 277.298058 -278.750744) (xy 277.309835 -278.70296) (xy 277.329126 -278.657684)
			(xy 277.355429 -278.616088) (xy 277.388064 -278.579251) (xy 277.426185 -278.548126) (xy 277.468806 -278.523519)
			(xy 277.514822 -278.506067) (xy 277.563041 -278.496223) (xy 277.612216 -278.494242) (xy 277.661071 -278.500174)
			(xy 277.708342 -278.513866) (xy 277.752804 -278.534964) (xy 277.793307 -278.56292) (xy 277.8288 -278.597012)
			(xy 277.858365 -278.636356) (xy 277.881236 -278.679933) (xy 277.89682 -278.726614) (xy 277.904715 -278.775191)
			(xy 277.90521 -278.799798) (xy 278.244058 -278.799798) (xy 278.248018 -278.750744) (xy 278.259795 -278.70296)
			(xy 278.279086 -278.657684) (xy 278.305389 -278.616088) (xy 278.338024 -278.579251) (xy 278.376145 -278.548126)
			(xy 278.418766 -278.523519) (xy 278.464782 -278.506067) (xy 278.513001 -278.496223) (xy 278.562176 -278.494242)
			(xy 278.611031 -278.500174) (xy 278.658302 -278.513866) (xy 278.702764 -278.534964) (xy 278.743267 -278.56292)
			(xy 278.77876 -278.597012) (xy 278.808325 -278.636356) (xy 278.831196 -278.679933) (xy 278.84678 -278.726614)
			(xy 278.854675 -278.775191) (xy 278.85517 -278.799798) (xy 279.194018 -278.799798) (xy 279.197978 -278.750744)
			(xy 279.209755 -278.70296) (xy 279.229046 -278.657684) (xy 279.255349 -278.616088) (xy 279.287984 -278.579251)
			(xy 279.326105 -278.548126) (xy 279.368726 -278.523519) (xy 279.414742 -278.506067) (xy 279.462961 -278.496223)
			(xy 279.512136 -278.494242) (xy 279.560991 -278.500174) (xy 279.608262 -278.513866) (xy 279.652724 -278.534964)
			(xy 279.693227 -278.56292) (xy 279.72872 -278.597012) (xy 279.758285 -278.636356) (xy 279.781156 -278.679933)
			(xy 279.79674 -278.726614) (xy 279.804635 -278.775191) (xy 279.80513 -278.799798) (xy 280.143978 -278.799798)
			(xy 280.147938 -278.750744) (xy 280.159715 -278.70296) (xy 280.179006 -278.657684) (xy 280.205309 -278.616088)
			(xy 280.237944 -278.579251) (xy 280.276065 -278.548126) (xy 280.318686 -278.523519) (xy 280.364702 -278.506067)
			(xy 280.412921 -278.496223) (xy 280.462096 -278.494242) (xy 280.510951 -278.500174) (xy 280.558222 -278.513866)
			(xy 280.602684 -278.534964) (xy 280.643187 -278.56292) (xy 280.67868 -278.597012) (xy 280.708245 -278.636356)
			(xy 280.731116 -278.679933) (xy 280.7467 -278.726614) (xy 280.754595 -278.775191) (xy 280.75509 -278.799798)
			(xy 281.093938 -278.799798) (xy 281.097898 -278.750744) (xy 281.109675 -278.70296) (xy 281.128966 -278.657684)
			(xy 281.155269 -278.616088) (xy 281.187904 -278.579251) (xy 281.226025 -278.548126) (xy 281.268646 -278.523519)
			(xy 281.314662 -278.506067) (xy 281.362881 -278.496223) (xy 281.412056 -278.494242) (xy 281.460911 -278.500174)
			(xy 281.508182 -278.513866) (xy 281.552644 -278.534964) (xy 281.593147 -278.56292) (xy 281.62864 -278.597012)
			(xy 281.658205 -278.636356) (xy 281.681076 -278.679933) (xy 281.69666 -278.726614) (xy 281.704555 -278.775191)
			(xy 281.70505 -278.799798) (xy 282.043898 -278.799798) (xy 282.047858 -278.750744) (xy 282.059635 -278.70296)
			(xy 282.078926 -278.657684) (xy 282.105229 -278.616088) (xy 282.137864 -278.579251) (xy 282.175985 -278.548126)
			(xy 282.218606 -278.523519) (xy 282.264622 -278.506067) (xy 282.312841 -278.496223) (xy 282.362016 -278.494242)
			(xy 282.410871 -278.500174) (xy 282.458142 -278.513866) (xy 282.502604 -278.534964) (xy 282.543107 -278.56292)
			(xy 282.5786 -278.597012) (xy 282.608165 -278.636356) (xy 282.631036 -278.679933) (xy 282.64662 -278.726614)
			(xy 282.654515 -278.775191) (xy 282.65501 -278.799798) (xy 282.994112 -278.799798) (xy 282.998072 -278.750744)
			(xy 283.009849 -278.70296) (xy 283.02914 -278.657684) (xy 283.055443 -278.616088) (xy 283.088078 -278.579251)
			(xy 283.126199 -278.548126) (xy 283.16882 -278.523519) (xy 283.214836 -278.506067) (xy 283.263055 -278.496223)
			(xy 283.31223 -278.494242) (xy 283.361085 -278.500174) (xy 283.408356 -278.513866) (xy 283.452818 -278.534964)
			(xy 283.493321 -278.56292) (xy 283.528814 -278.597012) (xy 283.558379 -278.636356) (xy 283.58125 -278.679933)
			(xy 283.596834 -278.726614) (xy 283.604729 -278.775191) (xy 283.605224 -278.799798) (xy 283.944072 -278.799798)
			(xy 283.948032 -278.750744) (xy 283.959809 -278.70296) (xy 283.9791 -278.657684) (xy 284.005403 -278.616088)
			(xy 284.038038 -278.579251) (xy 284.076159 -278.548126) (xy 284.11878 -278.523519) (xy 284.164796 -278.506067)
			(xy 284.213015 -278.496223) (xy 284.26219 -278.494242) (xy 284.311045 -278.500174) (xy 284.358316 -278.513866)
			(xy 284.402778 -278.534964) (xy 284.443281 -278.56292) (xy 284.478774 -278.597012) (xy 284.508339 -278.636356)
			(xy 284.53121 -278.679933) (xy 284.546794 -278.726614) (xy 284.554689 -278.775191) (xy 284.555184 -278.799798)
			(xy 284.894032 -278.799798) (xy 284.897992 -278.750744) (xy 284.909769 -278.70296) (xy 284.92906 -278.657684)
			(xy 284.955363 -278.616088) (xy 284.987998 -278.579251) (xy 285.026119 -278.548126) (xy 285.06874 -278.523519)
			(xy 285.114756 -278.506067) (xy 285.162975 -278.496223) (xy 285.21215 -278.494242) (xy 285.261005 -278.500174)
			(xy 285.308276 -278.513866) (xy 285.352738 -278.534964) (xy 285.393241 -278.56292) (xy 285.428734 -278.597012)
			(xy 285.458299 -278.636356) (xy 285.48117 -278.679933) (xy 285.496754 -278.726614) (xy 285.504649 -278.775191)
			(xy 285.505144 -278.799798) (xy 285.843992 -278.799798) (xy 285.847952 -278.750744) (xy 285.859729 -278.70296)
			(xy 285.87902 -278.657684) (xy 285.905323 -278.616088) (xy 285.937958 -278.579251) (xy 285.976079 -278.548126)
			(xy 286.0187 -278.523519) (xy 286.064716 -278.506067) (xy 286.112935 -278.496223) (xy 286.16211 -278.494242)
			(xy 286.210965 -278.500174) (xy 286.258236 -278.513866) (xy 286.302698 -278.534964) (xy 286.343201 -278.56292)
			(xy 286.378694 -278.597012) (xy 286.408259 -278.636356) (xy 286.43113 -278.679933) (xy 286.446714 -278.726614)
			(xy 286.454609 -278.775191) (xy 286.455104 -278.799798) (xy 286.793952 -278.799798) (xy 286.797912 -278.750744)
			(xy 286.809689 -278.70296) (xy 286.82898 -278.657684) (xy 286.855283 -278.616088) (xy 286.887918 -278.579251)
			(xy 286.926039 -278.548126) (xy 286.96866 -278.523519) (xy 287.014676 -278.506067) (xy 287.062895 -278.496223)
			(xy 287.11207 -278.494242) (xy 287.160925 -278.500174) (xy 287.208196 -278.513866) (xy 287.252658 -278.534964)
			(xy 287.293161 -278.56292) (xy 287.328654 -278.597012) (xy 287.358219 -278.636356) (xy 287.38109 -278.679933)
			(xy 287.396674 -278.726614) (xy 287.404569 -278.775191) (xy 287.405064 -278.799798) (xy 287.743912 -278.799798)
			(xy 287.747872 -278.750744) (xy 287.759649 -278.70296) (xy 287.77894 -278.657684) (xy 287.805243 -278.616088)
			(xy 287.837878 -278.579251) (xy 287.875999 -278.548126) (xy 287.91862 -278.523519) (xy 287.964636 -278.506067)
			(xy 288.012855 -278.496223) (xy 288.06203 -278.494242) (xy 288.110885 -278.500174) (xy 288.158156 -278.513866)
			(xy 288.202618 -278.534964) (xy 288.243121 -278.56292) (xy 288.278614 -278.597012) (xy 288.308179 -278.636356)
			(xy 288.33105 -278.679933) (xy 288.346634 -278.726614) (xy 288.354529 -278.775191) (xy 288.355024 -278.799798)
			(xy 288.694126 -278.799798) (xy 288.698086 -278.750744) (xy 288.709863 -278.70296) (xy 288.729154 -278.657684)
			(xy 288.755457 -278.616088) (xy 288.788092 -278.579251) (xy 288.826213 -278.548126) (xy 288.868834 -278.523519)
			(xy 288.91485 -278.506067) (xy 288.963069 -278.496223) (xy 289.012244 -278.494242) (xy 289.061099 -278.500174)
			(xy 289.10837 -278.513866) (xy 289.152832 -278.534964) (xy 289.193335 -278.56292) (xy 289.228828 -278.597012)
			(xy 289.258393 -278.636356) (xy 289.281264 -278.679933) (xy 289.296848 -278.726614) (xy 289.304743 -278.775191)
			(xy 289.305238 -278.799798) (xy 289.304743 -278.824405) (xy 289.296848 -278.872982) (xy 289.281264 -278.919663)
			(xy 289.258393 -278.96324) (xy 289.228828 -279.002584) (xy 289.193335 -279.036676) (xy 289.152832 -279.064632)
			(xy 289.10837 -279.08573) (xy 289.061099 -279.099422) (xy 289.012244 -279.105354) (xy 288.963069 -279.103373)
			(xy 288.91485 -279.093529) (xy 288.868834 -279.076077) (xy 288.826213 -279.05147) (xy 288.788092 -279.020345)
			(xy 288.755457 -278.983508) (xy 288.729154 -278.941912) (xy 288.709863 -278.896636) (xy 288.698086 -278.848852)
			(xy 288.694126 -278.799798) (xy 288.355024 -278.799798) (xy 288.354529 -278.824405) (xy 288.346634 -278.872982)
			(xy 288.33105 -278.919663) (xy 288.308179 -278.96324) (xy 288.278614 -279.002584) (xy 288.243121 -279.036676)
			(xy 288.202618 -279.064632) (xy 288.158156 -279.08573) (xy 288.110885 -279.099422) (xy 288.06203 -279.105354)
			(xy 288.012855 -279.103373) (xy 287.964636 -279.093529) (xy 287.91862 -279.076077) (xy 287.875999 -279.05147)
			(xy 287.837878 -279.020345) (xy 287.805243 -278.983508) (xy 287.77894 -278.941912) (xy 287.759649 -278.896636)
			(xy 287.747872 -278.848852) (xy 287.743912 -278.799798) (xy 287.405064 -278.799798) (xy 287.404569 -278.824405)
			(xy 287.396674 -278.872982) (xy 287.38109 -278.919663) (xy 287.358219 -278.96324) (xy 287.328654 -279.002584)
			(xy 287.293161 -279.036676) (xy 287.252658 -279.064632) (xy 287.208196 -279.08573) (xy 287.160925 -279.099422)
			(xy 287.11207 -279.105354) (xy 287.062895 -279.103373) (xy 287.014676 -279.093529) (xy 286.96866 -279.076077)
			(xy 286.926039 -279.05147) (xy 286.887918 -279.020345) (xy 286.855283 -278.983508) (xy 286.82898 -278.941912)
			(xy 286.809689 -278.896636) (xy 286.797912 -278.848852) (xy 286.793952 -278.799798) (xy 286.455104 -278.799798)
			(xy 286.454609 -278.824405) (xy 286.446714 -278.872982) (xy 286.43113 -278.919663) (xy 286.408259 -278.96324)
			(xy 286.378694 -279.002584) (xy 286.343201 -279.036676) (xy 286.302698 -279.064632) (xy 286.258236 -279.08573)
			(xy 286.210965 -279.099422) (xy 286.16211 -279.105354) (xy 286.112935 -279.103373) (xy 286.064716 -279.093529)
			(xy 286.0187 -279.076077) (xy 285.976079 -279.05147) (xy 285.937958 -279.020345) (xy 285.905323 -278.983508)
			(xy 285.87902 -278.941912) (xy 285.859729 -278.896636) (xy 285.847952 -278.848852) (xy 285.843992 -278.799798)
			(xy 285.505144 -278.799798) (xy 285.504649 -278.824405) (xy 285.496754 -278.872982) (xy 285.48117 -278.919663)
			(xy 285.458299 -278.96324) (xy 285.428734 -279.002584) (xy 285.393241 -279.036676) (xy 285.352738 -279.064632)
			(xy 285.308276 -279.08573) (xy 285.261005 -279.099422) (xy 285.21215 -279.105354) (xy 285.162975 -279.103373)
			(xy 285.114756 -279.093529) (xy 285.06874 -279.076077) (xy 285.026119 -279.05147) (xy 284.987998 -279.020345)
			(xy 284.955363 -278.983508) (xy 284.92906 -278.941912) (xy 284.909769 -278.896636) (xy 284.897992 -278.848852)
			(xy 284.894032 -278.799798) (xy 284.555184 -278.799798) (xy 284.554689 -278.824405) (xy 284.546794 -278.872982)
			(xy 284.53121 -278.919663) (xy 284.508339 -278.96324) (xy 284.478774 -279.002584) (xy 284.443281 -279.036676)
			(xy 284.402778 -279.064632) (xy 284.358316 -279.08573) (xy 284.311045 -279.099422) (xy 284.26219 -279.105354)
			(xy 284.213015 -279.103373) (xy 284.164796 -279.093529) (xy 284.11878 -279.076077) (xy 284.076159 -279.05147)
			(xy 284.038038 -279.020345) (xy 284.005403 -278.983508) (xy 283.9791 -278.941912) (xy 283.959809 -278.896636)
			(xy 283.948032 -278.848852) (xy 283.944072 -278.799798) (xy 283.605224 -278.799798) (xy 283.604729 -278.824405)
			(xy 283.596834 -278.872982) (xy 283.58125 -278.919663) (xy 283.558379 -278.96324) (xy 283.528814 -279.002584)
			(xy 283.493321 -279.036676) (xy 283.452818 -279.064632) (xy 283.408356 -279.08573) (xy 283.361085 -279.099422)
			(xy 283.31223 -279.105354) (xy 283.263055 -279.103373) (xy 283.214836 -279.093529) (xy 283.16882 -279.076077)
			(xy 283.126199 -279.05147) (xy 283.088078 -279.020345) (xy 283.055443 -278.983508) (xy 283.02914 -278.941912)
			(xy 283.009849 -278.896636) (xy 282.998072 -278.848852) (xy 282.994112 -278.799798) (xy 282.65501 -278.799798)
			(xy 282.654515 -278.824405) (xy 282.64662 -278.872982) (xy 282.631036 -278.919663) (xy 282.608165 -278.96324)
			(xy 282.5786 -279.002584) (xy 282.543107 -279.036676) (xy 282.502604 -279.064632) (xy 282.458142 -279.08573)
			(xy 282.410871 -279.099422) (xy 282.362016 -279.105354) (xy 282.312841 -279.103373) (xy 282.264622 -279.093529)
			(xy 282.218606 -279.076077) (xy 282.175985 -279.05147) (xy 282.137864 -279.020345) (xy 282.105229 -278.983508)
			(xy 282.078926 -278.941912) (xy 282.059635 -278.896636) (xy 282.047858 -278.848852) (xy 282.043898 -278.799798)
			(xy 281.70505 -278.799798) (xy 281.704555 -278.824405) (xy 281.69666 -278.872982) (xy 281.681076 -278.919663)
			(xy 281.658205 -278.96324) (xy 281.62864 -279.002584) (xy 281.593147 -279.036676) (xy 281.552644 -279.064632)
			(xy 281.508182 -279.08573) (xy 281.460911 -279.099422) (xy 281.412056 -279.105354) (xy 281.362881 -279.103373)
			(xy 281.314662 -279.093529) (xy 281.268646 -279.076077) (xy 281.226025 -279.05147) (xy 281.187904 -279.020345)
			(xy 281.155269 -278.983508) (xy 281.128966 -278.941912) (xy 281.109675 -278.896636) (xy 281.097898 -278.848852)
			(xy 281.093938 -278.799798) (xy 280.75509 -278.799798) (xy 280.754595 -278.824405) (xy 280.7467 -278.872982)
			(xy 280.731116 -278.919663) (xy 280.708245 -278.96324) (xy 280.67868 -279.002584) (xy 280.643187 -279.036676)
			(xy 280.602684 -279.064632) (xy 280.558222 -279.08573) (xy 280.510951 -279.099422) (xy 280.462096 -279.105354)
			(xy 280.412921 -279.103373) (xy 280.364702 -279.093529) (xy 280.318686 -279.076077) (xy 280.276065 -279.05147)
			(xy 280.237944 -279.020345) (xy 280.205309 -278.983508) (xy 280.179006 -278.941912) (xy 280.159715 -278.896636)
			(xy 280.147938 -278.848852) (xy 280.143978 -278.799798) (xy 279.80513 -278.799798) (xy 279.804635 -278.824405)
			(xy 279.79674 -278.872982) (xy 279.781156 -278.919663) (xy 279.758285 -278.96324) (xy 279.72872 -279.002584)
			(xy 279.693227 -279.036676) (xy 279.652724 -279.064632) (xy 279.608262 -279.08573) (xy 279.560991 -279.099422)
			(xy 279.512136 -279.105354) (xy 279.462961 -279.103373) (xy 279.414742 -279.093529) (xy 279.368726 -279.076077)
			(xy 279.326105 -279.05147) (xy 279.287984 -279.020345) (xy 279.255349 -278.983508) (xy 279.229046 -278.941912)
			(xy 279.209755 -278.896636) (xy 279.197978 -278.848852) (xy 279.194018 -278.799798) (xy 278.85517 -278.799798)
			(xy 278.854675 -278.824405) (xy 278.84678 -278.872982) (xy 278.831196 -278.919663) (xy 278.808325 -278.96324)
			(xy 278.77876 -279.002584) (xy 278.743267 -279.036676) (xy 278.702764 -279.064632) (xy 278.658302 -279.08573)
			(xy 278.611031 -279.099422) (xy 278.562176 -279.105354) (xy 278.513001 -279.103373) (xy 278.464782 -279.093529)
			(xy 278.418766 -279.076077) (xy 278.376145 -279.05147) (xy 278.338024 -279.020345) (xy 278.305389 -278.983508)
			(xy 278.279086 -278.941912) (xy 278.259795 -278.896636) (xy 278.248018 -278.848852) (xy 278.244058 -278.799798)
			(xy 277.90521 -278.799798) (xy 277.904715 -278.824405) (xy 277.89682 -278.872982) (xy 277.881236 -278.919663)
			(xy 277.858365 -278.96324) (xy 277.8288 -279.002584) (xy 277.793307 -279.036676) (xy 277.752804 -279.064632)
			(xy 277.708342 -279.08573) (xy 277.661071 -279.099422) (xy 277.612216 -279.105354) (xy 277.563041 -279.103373)
			(xy 277.514822 -279.093529) (xy 277.468806 -279.076077) (xy 277.426185 -279.05147) (xy 277.388064 -279.020345)
			(xy 277.355429 -278.983508) (xy 277.329126 -278.941912) (xy 277.309835 -278.896636) (xy 277.298058 -278.848852)
			(xy 277.294098 -278.799798) (xy 276.954996 -278.799798) (xy 276.954501 -278.824405) (xy 276.946606 -278.872982)
			(xy 276.931022 -278.919663) (xy 276.908151 -278.96324) (xy 276.878586 -279.002584) (xy 276.843093 -279.036676)
			(xy 276.80259 -279.064632) (xy 276.758128 -279.08573) (xy 276.710857 -279.099422) (xy 276.662002 -279.105354)
			(xy 276.612827 -279.103373) (xy 276.564608 -279.093529) (xy 276.518592 -279.076077) (xy 276.475971 -279.05147)
			(xy 276.43785 -279.020345) (xy 276.405215 -278.983508) (xy 276.378912 -278.941912) (xy 276.359621 -278.896636)
			(xy 276.347844 -278.848852) (xy 276.343884 -278.799798) (xy 264.285983 -278.799798) (xy 264.302858 -278.81442)
			(xy 264.338549 -278.855611) (xy 264.368015 -278.901461) (xy 264.390657 -278.951038) (xy 264.406012 -279.003333)
			(xy 264.413768 -279.057281) (xy 264.414254 -279.084532) (xy 264.413723 -279.113178) (xy 264.405172 -279.169829)
			(xy 264.388239 -279.224561) (xy 264.363963 -279.274778) (xy 268.26897 -279.274778) (xy 268.27293 -279.225724)
			(xy 268.284707 -279.17794) (xy 268.303998 -279.132664) (xy 268.330301 -279.091068) (xy 268.362936 -279.054231)
			(xy 268.401057 -279.023106) (xy 268.443678 -278.998499) (xy 268.489694 -278.981047) (xy 268.537913 -278.971203)
			(xy 268.587088 -278.969222) (xy 268.635943 -278.975154) (xy 268.683214 -278.988846) (xy 268.727676 -279.009944)
			(xy 268.768179 -279.0379) (xy 268.803672 -279.071992) (xy 268.833237 -279.111336) (xy 268.856108 -279.154913)
			(xy 268.871692 -279.201594) (xy 268.879587 -279.250171) (xy 268.880082 -279.274778) (xy 269.21893 -279.274778)
			(xy 269.22289 -279.225724) (xy 269.234667 -279.17794) (xy 269.253958 -279.132664) (xy 269.280261 -279.091068)
			(xy 269.312896 -279.054231) (xy 269.351017 -279.023106) (xy 269.393638 -278.998499) (xy 269.439654 -278.981047)
			(xy 269.487873 -278.971203) (xy 269.537048 -278.969222) (xy 269.585903 -278.975154) (xy 269.633174 -278.988846)
			(xy 269.677636 -279.009944) (xy 269.718139 -279.0379) (xy 269.753632 -279.071992) (xy 269.783197 -279.111336)
			(xy 269.806068 -279.154913) (xy 269.821652 -279.201594) (xy 269.829547 -279.250171) (xy 269.830042 -279.274778)
			(xy 270.169144 -279.274778) (xy 270.173104 -279.225724) (xy 270.184881 -279.17794) (xy 270.204172 -279.132664)
			(xy 270.230475 -279.091068) (xy 270.26311 -279.054231) (xy 270.301231 -279.023106) (xy 270.343852 -278.998499)
			(xy 270.389868 -278.981047) (xy 270.438087 -278.971203) (xy 270.487262 -278.969222) (xy 270.536117 -278.975154)
			(xy 270.583388 -278.988846) (xy 270.62785 -279.009944) (xy 270.668353 -279.0379) (xy 270.703846 -279.071992)
			(xy 270.733411 -279.111336) (xy 270.756282 -279.154913) (xy 270.771866 -279.201594) (xy 270.779761 -279.250171)
			(xy 270.780256 -279.274778) (xy 271.119104 -279.274778) (xy 271.123064 -279.225724) (xy 271.134841 -279.17794)
			(xy 271.154132 -279.132664) (xy 271.180435 -279.091068) (xy 271.21307 -279.054231) (xy 271.251191 -279.023106)
			(xy 271.293812 -278.998499) (xy 271.339828 -278.981047) (xy 271.388047 -278.971203) (xy 271.437222 -278.969222)
			(xy 271.486077 -278.975154) (xy 271.533348 -278.988846) (xy 271.57781 -279.009944) (xy 271.618313 -279.0379)
			(xy 271.653806 -279.071992) (xy 271.683371 -279.111336) (xy 271.706242 -279.154913) (xy 271.721826 -279.201594)
			(xy 271.729721 -279.250171) (xy 271.730216 -279.274778) (xy 272.069064 -279.274778) (xy 272.073024 -279.225724)
			(xy 272.084801 -279.17794) (xy 272.104092 -279.132664) (xy 272.130395 -279.091068) (xy 272.16303 -279.054231)
			(xy 272.201151 -279.023106) (xy 272.243772 -278.998499) (xy 272.289788 -278.981047) (xy 272.338007 -278.971203)
			(xy 272.387182 -278.969222) (xy 272.436037 -278.975154) (xy 272.483308 -278.988846) (xy 272.52777 -279.009944)
			(xy 272.568273 -279.0379) (xy 272.603766 -279.071992) (xy 272.633331 -279.111336) (xy 272.656202 -279.154913)
			(xy 272.671786 -279.201594) (xy 272.679681 -279.250171) (xy 272.680176 -279.274778) (xy 273.019024 -279.274778)
			(xy 273.022984 -279.225724) (xy 273.034761 -279.17794) (xy 273.054052 -279.132664) (xy 273.080355 -279.091068)
			(xy 273.11299 -279.054231) (xy 273.151111 -279.023106) (xy 273.193732 -278.998499) (xy 273.239748 -278.981047)
			(xy 273.287967 -278.971203) (xy 273.337142 -278.969222) (xy 273.385997 -278.975154) (xy 273.433268 -278.988846)
			(xy 273.47773 -279.009944) (xy 273.518233 -279.0379) (xy 273.553726 -279.071992) (xy 273.583291 -279.111336)
			(xy 273.606162 -279.154913) (xy 273.621746 -279.201594) (xy 273.629641 -279.250171) (xy 273.630136 -279.274778)
			(xy 273.968984 -279.274778) (xy 273.972944 -279.225724) (xy 273.984721 -279.17794) (xy 274.004012 -279.132664)
			(xy 274.030315 -279.091068) (xy 274.06295 -279.054231) (xy 274.101071 -279.023106) (xy 274.143692 -278.998499)
			(xy 274.189708 -278.981047) (xy 274.237927 -278.971203) (xy 274.287102 -278.969222) (xy 274.335957 -278.975154)
			(xy 274.383228 -278.988846) (xy 274.42769 -279.009944) (xy 274.468193 -279.0379) (xy 274.503686 -279.071992)
			(xy 274.533251 -279.111336) (xy 274.556122 -279.154913) (xy 274.571706 -279.201594) (xy 274.579601 -279.250171)
			(xy 274.580096 -279.274778) (xy 274.918944 -279.274778) (xy 274.922904 -279.225724) (xy 274.934681 -279.17794)
			(xy 274.953972 -279.132664) (xy 274.980275 -279.091068) (xy 275.01291 -279.054231) (xy 275.051031 -279.023106)
			(xy 275.093652 -278.998499) (xy 275.139668 -278.981047) (xy 275.187887 -278.971203) (xy 275.237062 -278.969222)
			(xy 275.285917 -278.975154) (xy 275.333188 -278.988846) (xy 275.37765 -279.009944) (xy 275.418153 -279.0379)
			(xy 275.453646 -279.071992) (xy 275.483211 -279.111336) (xy 275.506082 -279.154913) (xy 275.521666 -279.201594)
			(xy 275.529561 -279.250171) (xy 275.530056 -279.274778) (xy 275.529561 -279.299385) (xy 275.521666 -279.347962)
			(xy 275.506082 -279.394643) (xy 275.483211 -279.43822) (xy 275.453646 -279.477564) (xy 275.418153 -279.511656)
			(xy 275.37765 -279.539612) (xy 275.333188 -279.56071) (xy 275.285917 -279.574402) (xy 275.237062 -279.580334)
			(xy 275.187887 -279.578353) (xy 275.139668 -279.568509) (xy 275.093652 -279.551057) (xy 275.051031 -279.52645)
			(xy 275.01291 -279.495325) (xy 274.980275 -279.458488) (xy 274.953972 -279.416892) (xy 274.934681 -279.371616)
			(xy 274.922904 -279.323832) (xy 274.918944 -279.274778) (xy 274.580096 -279.274778) (xy 274.579601 -279.299385)
			(xy 274.571706 -279.347962) (xy 274.556122 -279.394643) (xy 274.533251 -279.43822) (xy 274.503686 -279.477564)
			(xy 274.468193 -279.511656) (xy 274.42769 -279.539612) (xy 274.383228 -279.56071) (xy 274.335957 -279.574402)
			(xy 274.287102 -279.580334) (xy 274.237927 -279.578353) (xy 274.189708 -279.568509) (xy 274.143692 -279.551057)
			(xy 274.101071 -279.52645) (xy 274.06295 -279.495325) (xy 274.030315 -279.458488) (xy 274.004012 -279.416892)
			(xy 273.984721 -279.371616) (xy 273.972944 -279.323832) (xy 273.968984 -279.274778) (xy 273.630136 -279.274778)
			(xy 273.629641 -279.299385) (xy 273.621746 -279.347962) (xy 273.606162 -279.394643) (xy 273.583291 -279.43822)
			(xy 273.553726 -279.477564) (xy 273.518233 -279.511656) (xy 273.47773 -279.539612) (xy 273.433268 -279.56071)
			(xy 273.385997 -279.574402) (xy 273.337142 -279.580334) (xy 273.287967 -279.578353) (xy 273.239748 -279.568509)
			(xy 273.193732 -279.551057) (xy 273.151111 -279.52645) (xy 273.11299 -279.495325) (xy 273.080355 -279.458488)
			(xy 273.054052 -279.416892) (xy 273.034761 -279.371616) (xy 273.022984 -279.323832) (xy 273.019024 -279.274778)
			(xy 272.680176 -279.274778) (xy 272.679681 -279.299385) (xy 272.671786 -279.347962) (xy 272.656202 -279.394643)
			(xy 272.633331 -279.43822) (xy 272.603766 -279.477564) (xy 272.568273 -279.511656) (xy 272.52777 -279.539612)
			(xy 272.483308 -279.56071) (xy 272.436037 -279.574402) (xy 272.387182 -279.580334) (xy 272.338007 -279.578353)
			(xy 272.289788 -279.568509) (xy 272.243772 -279.551057) (xy 272.201151 -279.52645) (xy 272.16303 -279.495325)
			(xy 272.130395 -279.458488) (xy 272.104092 -279.416892) (xy 272.084801 -279.371616) (xy 272.073024 -279.323832)
			(xy 272.069064 -279.274778) (xy 271.730216 -279.274778) (xy 271.729721 -279.299385) (xy 271.721826 -279.347962)
			(xy 271.706242 -279.394643) (xy 271.683371 -279.43822) (xy 271.653806 -279.477564) (xy 271.618313 -279.511656)
			(xy 271.57781 -279.539612) (xy 271.533348 -279.56071) (xy 271.486077 -279.574402) (xy 271.437222 -279.580334)
			(xy 271.388047 -279.578353) (xy 271.339828 -279.568509) (xy 271.293812 -279.551057) (xy 271.251191 -279.52645)
			(xy 271.21307 -279.495325) (xy 271.180435 -279.458488) (xy 271.154132 -279.416892) (xy 271.134841 -279.371616)
			(xy 271.123064 -279.323832) (xy 271.119104 -279.274778) (xy 270.780256 -279.274778) (xy 270.779761 -279.299385)
			(xy 270.771866 -279.347962) (xy 270.756282 -279.394643) (xy 270.733411 -279.43822) (xy 270.703846 -279.477564)
			(xy 270.668353 -279.511656) (xy 270.62785 -279.539612) (xy 270.583388 -279.56071) (xy 270.536117 -279.574402)
			(xy 270.487262 -279.580334) (xy 270.438087 -279.578353) (xy 270.389868 -279.568509) (xy 270.343852 -279.551057)
			(xy 270.301231 -279.52645) (xy 270.26311 -279.495325) (xy 270.230475 -279.458488) (xy 270.204172 -279.416892)
			(xy 270.184881 -279.371616) (xy 270.173104 -279.323832) (xy 270.169144 -279.274778) (xy 269.830042 -279.274778)
			(xy 269.829547 -279.299385) (xy 269.821652 -279.347962) (xy 269.806068 -279.394643) (xy 269.783197 -279.43822)
			(xy 269.753632 -279.477564) (xy 269.718139 -279.511656) (xy 269.677636 -279.539612) (xy 269.633174 -279.56071)
			(xy 269.585903 -279.574402) (xy 269.537048 -279.580334) (xy 269.487873 -279.578353) (xy 269.439654 -279.568509)
			(xy 269.393638 -279.551057) (xy 269.351017 -279.52645) (xy 269.312896 -279.495325) (xy 269.280261 -279.458488)
			(xy 269.253958 -279.416892) (xy 269.234667 -279.371616) (xy 269.22289 -279.323832) (xy 269.21893 -279.274778)
			(xy 268.880082 -279.274778) (xy 268.879587 -279.299385) (xy 268.871692 -279.347962) (xy 268.856108 -279.394643)
			(xy 268.833237 -279.43822) (xy 268.803672 -279.477564) (xy 268.768179 -279.511656) (xy 268.727676 -279.539612)
			(xy 268.683214 -279.56071) (xy 268.635943 -279.574402) (xy 268.587088 -279.580334) (xy 268.537913 -279.578353)
			(xy 268.489694 -279.568509) (xy 268.443678 -279.551057) (xy 268.401057 -279.52645) (xy 268.362936 -279.495325)
			(xy 268.330301 -279.458488) (xy 268.303998 -279.416892) (xy 268.284707 -279.371616) (xy 268.27293 -279.323832)
			(xy 268.26897 -279.274778) (xy 264.363963 -279.274778) (xy 264.363304 -279.276142) (xy 264.330929 -279.32341)
			(xy 264.291844 -279.3653) (xy 264.246929 -279.400867) (xy 264.197197 -279.429311) (xy 264.170668 -279.440132)
			(xy 264.15746 -279.445466) (xy 264.140188 -279.46731) (xy 264.126218 -279.584658) (xy 264.137648 -279.610058)
			(xy 264.149332 -279.618186) (xy 264.170577 -279.633546) (xy 264.209032 -279.669179) (xy 264.24225 -279.709737)
			(xy 264.266731 -279.749758) (xy 276.343884 -279.749758) (xy 276.347844 -279.700704) (xy 276.359621 -279.65292)
			(xy 276.378912 -279.607644) (xy 276.405215 -279.566048) (xy 276.43785 -279.529211) (xy 276.475971 -279.498086)
			(xy 276.518592 -279.473479) (xy 276.564608 -279.456027) (xy 276.612827 -279.446183) (xy 276.662002 -279.444202)
			(xy 276.710857 -279.450134) (xy 276.758128 -279.463826) (xy 276.80259 -279.484924) (xy 276.843093 -279.51288)
			(xy 276.878586 -279.546972) (xy 276.908151 -279.586316) (xy 276.931022 -279.629893) (xy 276.946606 -279.676574)
			(xy 276.954501 -279.725151) (xy 276.954991 -279.749504) (xy 277.294098 -279.749504) (xy 277.298058 -279.70045)
			(xy 277.309835 -279.652666) (xy 277.329126 -279.60739) (xy 277.355429 -279.565794) (xy 277.388064 -279.528957)
			(xy 277.426185 -279.497832) (xy 277.468806 -279.473225) (xy 277.514822 -279.455773) (xy 277.563041 -279.445929)
			(xy 277.612216 -279.443948) (xy 277.661071 -279.44988) (xy 277.708342 -279.463572) (xy 277.752804 -279.48467)
			(xy 277.793307 -279.512626) (xy 277.8288 -279.546718) (xy 277.858365 -279.586062) (xy 277.881236 -279.629639)
			(xy 277.89682 -279.67632) (xy 277.904715 -279.724897) (xy 277.90521 -279.749504) (xy 277.905205 -279.749758)
			(xy 278.244058 -279.749758) (xy 278.248018 -279.700704) (xy 278.259795 -279.65292) (xy 278.279086 -279.607644)
			(xy 278.305389 -279.566048) (xy 278.338024 -279.529211) (xy 278.376145 -279.498086) (xy 278.418766 -279.473479)
			(xy 278.464782 -279.456027) (xy 278.513001 -279.446183) (xy 278.562176 -279.444202) (xy 278.611031 -279.450134)
			(xy 278.658302 -279.463826) (xy 278.702764 -279.484924) (xy 278.743267 -279.51288) (xy 278.77876 -279.546972)
			(xy 278.808325 -279.586316) (xy 278.831196 -279.629893) (xy 278.84678 -279.676574) (xy 278.854675 -279.725151)
			(xy 278.855165 -279.749504) (xy 279.194018 -279.749504) (xy 279.197978 -279.70045) (xy 279.209755 -279.652666)
			(xy 279.229046 -279.60739) (xy 279.255349 -279.565794) (xy 279.287984 -279.528957) (xy 279.326105 -279.497832)
			(xy 279.368726 -279.473225) (xy 279.414742 -279.455773) (xy 279.462961 -279.445929) (xy 279.512136 -279.443948)
			(xy 279.560991 -279.44988) (xy 279.608262 -279.463572) (xy 279.652724 -279.48467) (xy 279.693227 -279.512626)
			(xy 279.72872 -279.546718) (xy 279.758285 -279.586062) (xy 279.781156 -279.629639) (xy 279.79674 -279.67632)
			(xy 279.804635 -279.724897) (xy 279.80513 -279.749504) (xy 279.805125 -279.749758) (xy 280.143978 -279.749758)
			(xy 280.147938 -279.700704) (xy 280.159715 -279.65292) (xy 280.179006 -279.607644) (xy 280.205309 -279.566048)
			(xy 280.237944 -279.529211) (xy 280.276065 -279.498086) (xy 280.318686 -279.473479) (xy 280.364702 -279.456027)
			(xy 280.412921 -279.446183) (xy 280.462096 -279.444202) (xy 280.510951 -279.450134) (xy 280.558222 -279.463826)
			(xy 280.602684 -279.484924) (xy 280.643187 -279.51288) (xy 280.67868 -279.546972) (xy 280.708245 -279.586316)
			(xy 280.731116 -279.629893) (xy 280.7467 -279.676574) (xy 280.754595 -279.725151) (xy 280.755085 -279.749504)
			(xy 281.093938 -279.749504) (xy 281.097898 -279.70045) (xy 281.109675 -279.652666) (xy 281.128966 -279.60739)
			(xy 281.155269 -279.565794) (xy 281.187904 -279.528957) (xy 281.226025 -279.497832) (xy 281.268646 -279.473225)
			(xy 281.314662 -279.455773) (xy 281.362881 -279.445929) (xy 281.412056 -279.443948) (xy 281.460911 -279.44988)
			(xy 281.508182 -279.463572) (xy 281.552644 -279.48467) (xy 281.593147 -279.512626) (xy 281.62864 -279.546718)
			(xy 281.658205 -279.586062) (xy 281.681076 -279.629639) (xy 281.69666 -279.67632) (xy 281.704555 -279.724897)
			(xy 281.70505 -279.749504) (xy 281.705045 -279.749758) (xy 282.043898 -279.749758) (xy 282.047858 -279.700704)
			(xy 282.059635 -279.65292) (xy 282.078926 -279.607644) (xy 282.105229 -279.566048) (xy 282.137864 -279.529211)
			(xy 282.175985 -279.498086) (xy 282.218606 -279.473479) (xy 282.264622 -279.456027) (xy 282.312841 -279.446183)
			(xy 282.362016 -279.444202) (xy 282.410871 -279.450134) (xy 282.458142 -279.463826) (xy 282.502604 -279.484924)
			(xy 282.543107 -279.51288) (xy 282.5786 -279.546972) (xy 282.608165 -279.586316) (xy 282.631036 -279.629893)
			(xy 282.64662 -279.676574) (xy 282.654515 -279.725151) (xy 282.655005 -279.749504) (xy 282.994112 -279.749504)
			(xy 282.998072 -279.70045) (xy 283.009849 -279.652666) (xy 283.02914 -279.60739) (xy 283.055443 -279.565794)
			(xy 283.088078 -279.528957) (xy 283.126199 -279.497832) (xy 283.16882 -279.473225) (xy 283.214836 -279.455773)
			(xy 283.263055 -279.445929) (xy 283.31223 -279.443948) (xy 283.361085 -279.44988) (xy 283.408356 -279.463572)
			(xy 283.452818 -279.48467) (xy 283.493321 -279.512626) (xy 283.528814 -279.546718) (xy 283.558379 -279.586062)
			(xy 283.58125 -279.629639) (xy 283.596834 -279.67632) (xy 283.604729 -279.724897) (xy 283.605224 -279.749504)
			(xy 283.605219 -279.749758) (xy 283.944072 -279.749758) (xy 283.948032 -279.700704) (xy 283.959809 -279.65292)
			(xy 283.9791 -279.607644) (xy 284.005403 -279.566048) (xy 284.038038 -279.529211) (xy 284.076159 -279.498086)
			(xy 284.11878 -279.473479) (xy 284.164796 -279.456027) (xy 284.213015 -279.446183) (xy 284.26219 -279.444202)
			(xy 284.311045 -279.450134) (xy 284.358316 -279.463826) (xy 284.402778 -279.484924) (xy 284.443281 -279.51288)
			(xy 284.478774 -279.546972) (xy 284.508339 -279.586316) (xy 284.53121 -279.629893) (xy 284.546794 -279.676574)
			(xy 284.554689 -279.725151) (xy 284.555179 -279.749504) (xy 284.894032 -279.749504) (xy 284.897992 -279.70045)
			(xy 284.909769 -279.652666) (xy 284.92906 -279.60739) (xy 284.955363 -279.565794) (xy 284.987998 -279.528957)
			(xy 285.026119 -279.497832) (xy 285.06874 -279.473225) (xy 285.114756 -279.455773) (xy 285.162975 -279.445929)
			(xy 285.21215 -279.443948) (xy 285.261005 -279.44988) (xy 285.308276 -279.463572) (xy 285.352738 -279.48467)
			(xy 285.393241 -279.512626) (xy 285.428734 -279.546718) (xy 285.458299 -279.586062) (xy 285.48117 -279.629639)
			(xy 285.496754 -279.67632) (xy 285.504649 -279.724897) (xy 285.505144 -279.749504) (xy 285.505139 -279.749758)
			(xy 285.843992 -279.749758) (xy 285.847952 -279.700704) (xy 285.859729 -279.65292) (xy 285.87902 -279.607644)
			(xy 285.905323 -279.566048) (xy 285.937958 -279.529211) (xy 285.976079 -279.498086) (xy 286.0187 -279.473479)
			(xy 286.064716 -279.456027) (xy 286.112935 -279.446183) (xy 286.16211 -279.444202) (xy 286.210965 -279.450134)
			(xy 286.258236 -279.463826) (xy 286.302698 -279.484924) (xy 286.343201 -279.51288) (xy 286.378694 -279.546972)
			(xy 286.408259 -279.586316) (xy 286.43113 -279.629893) (xy 286.446714 -279.676574) (xy 286.454609 -279.725151)
			(xy 286.455099 -279.749504) (xy 286.793952 -279.749504) (xy 286.797912 -279.70045) (xy 286.809689 -279.652666)
			(xy 286.82898 -279.60739) (xy 286.855283 -279.565794) (xy 286.887918 -279.528957) (xy 286.926039 -279.497832)
			(xy 286.96866 -279.473225) (xy 287.014676 -279.455773) (xy 287.062895 -279.445929) (xy 287.11207 -279.443948)
			(xy 287.160925 -279.44988) (xy 287.208196 -279.463572) (xy 287.252658 -279.48467) (xy 287.293161 -279.512626)
			(xy 287.328654 -279.546718) (xy 287.358219 -279.586062) (xy 287.38109 -279.629639) (xy 287.396674 -279.67632)
			(xy 287.404569 -279.724897) (xy 287.405064 -279.749504) (xy 287.405059 -279.749758) (xy 287.743912 -279.749758)
			(xy 287.747872 -279.700704) (xy 287.759649 -279.65292) (xy 287.77894 -279.607644) (xy 287.805243 -279.566048)
			(xy 287.837878 -279.529211) (xy 287.875999 -279.498086) (xy 287.91862 -279.473479) (xy 287.964636 -279.456027)
			(xy 288.012855 -279.446183) (xy 288.06203 -279.444202) (xy 288.110885 -279.450134) (xy 288.158156 -279.463826)
			(xy 288.202618 -279.484924) (xy 288.243121 -279.51288) (xy 288.278614 -279.546972) (xy 288.308179 -279.586316)
			(xy 288.33105 -279.629893) (xy 288.346634 -279.676574) (xy 288.354529 -279.725151) (xy 288.355019 -279.749504)
			(xy 288.693872 -279.749504) (xy 288.697832 -279.70045) (xy 288.709609 -279.652666) (xy 288.7289 -279.60739)
			(xy 288.755203 -279.565794) (xy 288.787838 -279.528957) (xy 288.825959 -279.497832) (xy 288.86858 -279.473225)
			(xy 288.914596 -279.455773) (xy 288.962815 -279.445929) (xy 289.01199 -279.443948) (xy 289.060845 -279.44988)
			(xy 289.108116 -279.463572) (xy 289.152578 -279.48467) (xy 289.193081 -279.512626) (xy 289.228574 -279.546718)
			(xy 289.258139 -279.586062) (xy 289.28101 -279.629639) (xy 289.296594 -279.67632) (xy 289.304489 -279.724897)
			(xy 289.304984 -279.749504) (xy 289.304489 -279.774111) (xy 289.296594 -279.822688) (xy 289.28101 -279.869369)
			(xy 289.258139 -279.912946) (xy 289.228574 -279.95229) (xy 289.193081 -279.986382) (xy 289.152578 -280.014338)
			(xy 289.108116 -280.035436) (xy 289.060845 -280.049128) (xy 289.01199 -280.05506) (xy 288.962815 -280.053079)
			(xy 288.914596 -280.043235) (xy 288.86858 -280.025783) (xy 288.825959 -280.001176) (xy 288.787838 -279.970051)
			(xy 288.755203 -279.933214) (xy 288.7289 -279.891618) (xy 288.709609 -279.846342) (xy 288.697832 -279.798558)
			(xy 288.693872 -279.749504) (xy 288.355019 -279.749504) (xy 288.355024 -279.749758) (xy 288.354529 -279.774365)
			(xy 288.346634 -279.822942) (xy 288.33105 -279.869623) (xy 288.308179 -279.9132) (xy 288.278614 -279.952544)
			(xy 288.243121 -279.986636) (xy 288.202618 -280.014592) (xy 288.158156 -280.03569) (xy 288.110885 -280.049382)
			(xy 288.06203 -280.055314) (xy 288.012855 -280.053333) (xy 287.964636 -280.043489) (xy 287.91862 -280.026037)
			(xy 287.875999 -280.00143) (xy 287.837878 -279.970305) (xy 287.805243 -279.933468) (xy 287.77894 -279.891872)
			(xy 287.759649 -279.846596) (xy 287.747872 -279.798812) (xy 287.743912 -279.749758) (xy 287.405059 -279.749758)
			(xy 287.404569 -279.774111) (xy 287.396674 -279.822688) (xy 287.38109 -279.869369) (xy 287.358219 -279.912946)
			(xy 287.328654 -279.95229) (xy 287.293161 -279.986382) (xy 287.252658 -280.014338) (xy 287.208196 -280.035436)
			(xy 287.160925 -280.049128) (xy 287.11207 -280.05506) (xy 287.062895 -280.053079) (xy 287.014676 -280.043235)
			(xy 286.96866 -280.025783) (xy 286.926039 -280.001176) (xy 286.887918 -279.970051) (xy 286.855283 -279.933214)
			(xy 286.82898 -279.891618) (xy 286.809689 -279.846342) (xy 286.797912 -279.798558) (xy 286.793952 -279.749504)
			(xy 286.455099 -279.749504) (xy 286.455104 -279.749758) (xy 286.454609 -279.774365) (xy 286.446714 -279.822942)
			(xy 286.43113 -279.869623) (xy 286.408259 -279.9132) (xy 286.378694 -279.952544) (xy 286.343201 -279.986636)
			(xy 286.302698 -280.014592) (xy 286.258236 -280.03569) (xy 286.210965 -280.049382) (xy 286.16211 -280.055314)
			(xy 286.112935 -280.053333) (xy 286.064716 -280.043489) (xy 286.0187 -280.026037) (xy 285.976079 -280.00143)
			(xy 285.937958 -279.970305) (xy 285.905323 -279.933468) (xy 285.87902 -279.891872) (xy 285.859729 -279.846596)
			(xy 285.847952 -279.798812) (xy 285.843992 -279.749758) (xy 285.505139 -279.749758) (xy 285.504649 -279.774111)
			(xy 285.496754 -279.822688) (xy 285.48117 -279.869369) (xy 285.458299 -279.912946) (xy 285.428734 -279.95229)
			(xy 285.393241 -279.986382) (xy 285.352738 -280.014338) (xy 285.308276 -280.035436) (xy 285.261005 -280.049128)
			(xy 285.21215 -280.05506) (xy 285.162975 -280.053079) (xy 285.114756 -280.043235) (xy 285.06874 -280.025783)
			(xy 285.026119 -280.001176) (xy 284.987998 -279.970051) (xy 284.955363 -279.933214) (xy 284.92906 -279.891618)
			(xy 284.909769 -279.846342) (xy 284.897992 -279.798558) (xy 284.894032 -279.749504) (xy 284.555179 -279.749504)
			(xy 284.555184 -279.749758) (xy 284.554689 -279.774365) (xy 284.546794 -279.822942) (xy 284.53121 -279.869623)
			(xy 284.508339 -279.9132) (xy 284.478774 -279.952544) (xy 284.443281 -279.986636) (xy 284.402778 -280.014592)
			(xy 284.358316 -280.03569) (xy 284.311045 -280.049382) (xy 284.26219 -280.055314) (xy 284.213015 -280.053333)
			(xy 284.164796 -280.043489) (xy 284.11878 -280.026037) (xy 284.076159 -280.00143) (xy 284.038038 -279.970305)
			(xy 284.005403 -279.933468) (xy 283.9791 -279.891872) (xy 283.959809 -279.846596) (xy 283.948032 -279.798812)
			(xy 283.944072 -279.749758) (xy 283.605219 -279.749758) (xy 283.604729 -279.774111) (xy 283.596834 -279.822688)
			(xy 283.58125 -279.869369) (xy 283.558379 -279.912946) (xy 283.528814 -279.95229) (xy 283.493321 -279.986382)
			(xy 283.452818 -280.014338) (xy 283.408356 -280.035436) (xy 283.361085 -280.049128) (xy 283.31223 -280.05506)
			(xy 283.263055 -280.053079) (xy 283.214836 -280.043235) (xy 283.16882 -280.025783) (xy 283.126199 -280.001176)
			(xy 283.088078 -279.970051) (xy 283.055443 -279.933214) (xy 283.02914 -279.891618) (xy 283.009849 -279.846342)
			(xy 282.998072 -279.798558) (xy 282.994112 -279.749504) (xy 282.655005 -279.749504) (xy 282.65501 -279.749758)
			(xy 282.654515 -279.774365) (xy 282.64662 -279.822942) (xy 282.631036 -279.869623) (xy 282.608165 -279.9132)
			(xy 282.5786 -279.952544) (xy 282.543107 -279.986636) (xy 282.502604 -280.014592) (xy 282.458142 -280.03569)
			(xy 282.410871 -280.049382) (xy 282.362016 -280.055314) (xy 282.312841 -280.053333) (xy 282.264622 -280.043489)
			(xy 282.218606 -280.026037) (xy 282.175985 -280.00143) (xy 282.137864 -279.970305) (xy 282.105229 -279.933468)
			(xy 282.078926 -279.891872) (xy 282.059635 -279.846596) (xy 282.047858 -279.798812) (xy 282.043898 -279.749758)
			(xy 281.705045 -279.749758) (xy 281.704555 -279.774111) (xy 281.69666 -279.822688) (xy 281.681076 -279.869369)
			(xy 281.658205 -279.912946) (xy 281.62864 -279.95229) (xy 281.593147 -279.986382) (xy 281.552644 -280.014338)
			(xy 281.508182 -280.035436) (xy 281.460911 -280.049128) (xy 281.412056 -280.05506) (xy 281.362881 -280.053079)
			(xy 281.314662 -280.043235) (xy 281.268646 -280.025783) (xy 281.226025 -280.001176) (xy 281.187904 -279.970051)
			(xy 281.155269 -279.933214) (xy 281.128966 -279.891618) (xy 281.109675 -279.846342) (xy 281.097898 -279.798558)
			(xy 281.093938 -279.749504) (xy 280.755085 -279.749504) (xy 280.75509 -279.749758) (xy 280.754595 -279.774365)
			(xy 280.7467 -279.822942) (xy 280.731116 -279.869623) (xy 280.708245 -279.9132) (xy 280.67868 -279.952544)
			(xy 280.643187 -279.986636) (xy 280.602684 -280.014592) (xy 280.558222 -280.03569) (xy 280.510951 -280.049382)
			(xy 280.462096 -280.055314) (xy 280.412921 -280.053333) (xy 280.364702 -280.043489) (xy 280.318686 -280.026037)
			(xy 280.276065 -280.00143) (xy 280.237944 -279.970305) (xy 280.205309 -279.933468) (xy 280.179006 -279.891872)
			(xy 280.159715 -279.846596) (xy 280.147938 -279.798812) (xy 280.143978 -279.749758) (xy 279.805125 -279.749758)
			(xy 279.804635 -279.774111) (xy 279.79674 -279.822688) (xy 279.781156 -279.869369) (xy 279.758285 -279.912946)
			(xy 279.72872 -279.95229) (xy 279.693227 -279.986382) (xy 279.652724 -280.014338) (xy 279.608262 -280.035436)
			(xy 279.560991 -280.049128) (xy 279.512136 -280.05506) (xy 279.462961 -280.053079) (xy 279.414742 -280.043235)
			(xy 279.368726 -280.025783) (xy 279.326105 -280.001176) (xy 279.287984 -279.970051) (xy 279.255349 -279.933214)
			(xy 279.229046 -279.891618) (xy 279.209755 -279.846342) (xy 279.197978 -279.798558) (xy 279.194018 -279.749504)
			(xy 278.855165 -279.749504) (xy 278.85517 -279.749758) (xy 278.854675 -279.774365) (xy 278.84678 -279.822942)
			(xy 278.831196 -279.869623) (xy 278.808325 -279.9132) (xy 278.77876 -279.952544) (xy 278.743267 -279.986636)
			(xy 278.702764 -280.014592) (xy 278.658302 -280.03569) (xy 278.611031 -280.049382) (xy 278.562176 -280.055314)
			(xy 278.513001 -280.053333) (xy 278.464782 -280.043489) (xy 278.418766 -280.026037) (xy 278.376145 -280.00143)
			(xy 278.338024 -279.970305) (xy 278.305389 -279.933468) (xy 278.279086 -279.891872) (xy 278.259795 -279.846596)
			(xy 278.248018 -279.798812) (xy 278.244058 -279.749758) (xy 277.905205 -279.749758) (xy 277.904715 -279.774111)
			(xy 277.89682 -279.822688) (xy 277.881236 -279.869369) (xy 277.858365 -279.912946) (xy 277.8288 -279.95229)
			(xy 277.793307 -279.986382) (xy 277.752804 -280.014338) (xy 277.708342 -280.035436) (xy 277.661071 -280.049128)
			(xy 277.612216 -280.05506) (xy 277.563041 -280.053079) (xy 277.514822 -280.043235) (xy 277.468806 -280.025783)
			(xy 277.426185 -280.001176) (xy 277.388064 -279.970051) (xy 277.355429 -279.933214) (xy 277.329126 -279.891618)
			(xy 277.309835 -279.846342) (xy 277.298058 -279.798558) (xy 277.294098 -279.749504) (xy 276.954991 -279.749504)
			(xy 276.954996 -279.749758) (xy 276.954501 -279.774365) (xy 276.946606 -279.822942) (xy 276.931022 -279.869623)
			(xy 276.908151 -279.9132) (xy 276.878586 -279.952544) (xy 276.843093 -279.986636) (xy 276.80259 -280.014592)
			(xy 276.758128 -280.03569) (xy 276.710857 -280.049382) (xy 276.662002 -280.055314) (xy 276.612827 -280.053333)
			(xy 276.564608 -280.043489) (xy 276.518592 -280.026037) (xy 276.475971 -280.00143) (xy 276.43785 -279.970305)
			(xy 276.405215 -279.933468) (xy 276.378912 -279.891872) (xy 276.359621 -279.846596) (xy 276.347844 -279.798812)
			(xy 276.343884 -279.749758) (xy 264.266731 -279.749758) (xy 264.269607 -279.75446) (xy 264.290587 -279.802505)
			(xy 264.304796 -279.852968) (xy 264.311967 -279.904901) (xy 264.3124 -279.931114) (xy 264.311872 -279.960497)
			(xy 264.302839 -280.018564) (xy 264.285005 -280.074559) (xy 264.258791 -280.127154) (xy 264.224818 -280.175105)
			(xy 264.183891 -280.217276) (xy 264.174371 -280.224738) (xy 268.26897 -280.224738) (xy 268.27293 -280.175684)
			(xy 268.284707 -280.1279) (xy 268.303998 -280.082624) (xy 268.330301 -280.041028) (xy 268.362936 -280.004191)
			(xy 268.401057 -279.973066) (xy 268.443678 -279.948459) (xy 268.489694 -279.931007) (xy 268.537913 -279.921163)
			(xy 268.587088 -279.919182) (xy 268.635943 -279.925114) (xy 268.683214 -279.938806) (xy 268.727676 -279.959904)
			(xy 268.768179 -279.98786) (xy 268.803672 -280.021952) (xy 268.833237 -280.061296) (xy 268.856108 -280.104873)
			(xy 268.871692 -280.151554) (xy 268.879587 -280.200131) (xy 268.880082 -280.224738) (xy 269.21893 -280.224738)
			(xy 269.22289 -280.175684) (xy 269.234667 -280.1279) (xy 269.253958 -280.082624) (xy 269.280261 -280.041028)
			(xy 269.312896 -280.004191) (xy 269.351017 -279.973066) (xy 269.393638 -279.948459) (xy 269.439654 -279.931007)
			(xy 269.487873 -279.921163) (xy 269.537048 -279.919182) (xy 269.585903 -279.925114) (xy 269.633174 -279.938806)
			(xy 269.677636 -279.959904) (xy 269.718139 -279.98786) (xy 269.753632 -280.021952) (xy 269.783197 -280.061296)
			(xy 269.806068 -280.104873) (xy 269.821652 -280.151554) (xy 269.829547 -280.200131) (xy 269.830042 -280.224738)
			(xy 270.169144 -280.224738) (xy 270.173104 -280.175684) (xy 270.184881 -280.1279) (xy 270.204172 -280.082624)
			(xy 270.230475 -280.041028) (xy 270.26311 -280.004191) (xy 270.301231 -279.973066) (xy 270.343852 -279.948459)
			(xy 270.389868 -279.931007) (xy 270.438087 -279.921163) (xy 270.487262 -279.919182) (xy 270.536117 -279.925114)
			(xy 270.583388 -279.938806) (xy 270.62785 -279.959904) (xy 270.668353 -279.98786) (xy 270.703846 -280.021952)
			(xy 270.733411 -280.061296) (xy 270.756282 -280.104873) (xy 270.771866 -280.151554) (xy 270.779761 -280.200131)
			(xy 270.780256 -280.224738) (xy 271.119104 -280.224738) (xy 271.123064 -280.175684) (xy 271.134841 -280.1279)
			(xy 271.154132 -280.082624) (xy 271.180435 -280.041028) (xy 271.21307 -280.004191) (xy 271.251191 -279.973066)
			(xy 271.293812 -279.948459) (xy 271.339828 -279.931007) (xy 271.388047 -279.921163) (xy 271.437222 -279.919182)
			(xy 271.486077 -279.925114) (xy 271.533348 -279.938806) (xy 271.57781 -279.959904) (xy 271.618313 -279.98786)
			(xy 271.653806 -280.021952) (xy 271.683371 -280.061296) (xy 271.706242 -280.104873) (xy 271.721826 -280.151554)
			(xy 271.729721 -280.200131) (xy 271.730216 -280.224738) (xy 272.069064 -280.224738) (xy 272.073024 -280.175684)
			(xy 272.084801 -280.1279) (xy 272.104092 -280.082624) (xy 272.130395 -280.041028) (xy 272.16303 -280.004191)
			(xy 272.201151 -279.973066) (xy 272.243772 -279.948459) (xy 272.289788 -279.931007) (xy 272.338007 -279.921163)
			(xy 272.387182 -279.919182) (xy 272.436037 -279.925114) (xy 272.483308 -279.938806) (xy 272.52777 -279.959904)
			(xy 272.568273 -279.98786) (xy 272.603766 -280.021952) (xy 272.633331 -280.061296) (xy 272.656202 -280.104873)
			(xy 272.671786 -280.151554) (xy 272.679681 -280.200131) (xy 272.680176 -280.224738) (xy 273.019024 -280.224738)
			(xy 273.022984 -280.175684) (xy 273.034761 -280.1279) (xy 273.054052 -280.082624) (xy 273.080355 -280.041028)
			(xy 273.11299 -280.004191) (xy 273.151111 -279.973066) (xy 273.193732 -279.948459) (xy 273.239748 -279.931007)
			(xy 273.287967 -279.921163) (xy 273.337142 -279.919182) (xy 273.385997 -279.925114) (xy 273.433268 -279.938806)
			(xy 273.47773 -279.959904) (xy 273.518233 -279.98786) (xy 273.553726 -280.021952) (xy 273.583291 -280.061296)
			(xy 273.606162 -280.104873) (xy 273.621746 -280.151554) (xy 273.629641 -280.200131) (xy 273.630136 -280.224738)
			(xy 273.968984 -280.224738) (xy 273.972944 -280.175684) (xy 273.984721 -280.1279) (xy 274.004012 -280.082624)
			(xy 274.030315 -280.041028) (xy 274.06295 -280.004191) (xy 274.101071 -279.973066) (xy 274.143692 -279.948459)
			(xy 274.189708 -279.931007) (xy 274.237927 -279.921163) (xy 274.287102 -279.919182) (xy 274.335957 -279.925114)
			(xy 274.383228 -279.938806) (xy 274.42769 -279.959904) (xy 274.468193 -279.98786) (xy 274.503686 -280.021952)
			(xy 274.533251 -280.061296) (xy 274.556122 -280.104873) (xy 274.571706 -280.151554) (xy 274.579601 -280.200131)
			(xy 274.580096 -280.224738) (xy 274.918944 -280.224738) (xy 274.922904 -280.175684) (xy 274.934681 -280.1279)
			(xy 274.953972 -280.082624) (xy 274.980275 -280.041028) (xy 275.01291 -280.004191) (xy 275.051031 -279.973066)
			(xy 275.093652 -279.948459) (xy 275.139668 -279.931007) (xy 275.187887 -279.921163) (xy 275.237062 -279.919182)
			(xy 275.285917 -279.925114) (xy 275.333188 -279.938806) (xy 275.37765 -279.959904) (xy 275.418153 -279.98786)
			(xy 275.453646 -280.021952) (xy 275.483211 -280.061296) (xy 275.506082 -280.104873) (xy 275.521666 -280.151554)
			(xy 275.529561 -280.200131) (xy 275.530056 -280.224738) (xy 275.529561 -280.249345) (xy 275.521666 -280.297922)
			(xy 275.506082 -280.344603) (xy 275.483211 -280.38818) (xy 275.453646 -280.427524) (xy 275.418153 -280.461616)
			(xy 275.37765 -280.489572) (xy 275.333188 -280.51067) (xy 275.285917 -280.524362) (xy 275.237062 -280.530294)
			(xy 275.187887 -280.528313) (xy 275.139668 -280.518469) (xy 275.093652 -280.501017) (xy 275.051031 -280.47641)
			(xy 275.01291 -280.445285) (xy 274.980275 -280.408448) (xy 274.953972 -280.366852) (xy 274.934681 -280.321576)
			(xy 274.922904 -280.273792) (xy 274.918944 -280.224738) (xy 274.580096 -280.224738) (xy 274.579601 -280.249345)
			(xy 274.571706 -280.297922) (xy 274.556122 -280.344603) (xy 274.533251 -280.38818) (xy 274.503686 -280.427524)
			(xy 274.468193 -280.461616) (xy 274.42769 -280.489572) (xy 274.383228 -280.51067) (xy 274.335957 -280.524362)
			(xy 274.287102 -280.530294) (xy 274.237927 -280.528313) (xy 274.189708 -280.518469) (xy 274.143692 -280.501017)
			(xy 274.101071 -280.47641) (xy 274.06295 -280.445285) (xy 274.030315 -280.408448) (xy 274.004012 -280.366852)
			(xy 273.984721 -280.321576) (xy 273.972944 -280.273792) (xy 273.968984 -280.224738) (xy 273.630136 -280.224738)
			(xy 273.629641 -280.249345) (xy 273.621746 -280.297922) (xy 273.606162 -280.344603) (xy 273.583291 -280.38818)
			(xy 273.553726 -280.427524) (xy 273.518233 -280.461616) (xy 273.47773 -280.489572) (xy 273.433268 -280.51067)
			(xy 273.385997 -280.524362) (xy 273.337142 -280.530294) (xy 273.287967 -280.528313) (xy 273.239748 -280.518469)
			(xy 273.193732 -280.501017) (xy 273.151111 -280.47641) (xy 273.11299 -280.445285) (xy 273.080355 -280.408448)
			(xy 273.054052 -280.366852) (xy 273.034761 -280.321576) (xy 273.022984 -280.273792) (xy 273.019024 -280.224738)
			(xy 272.680176 -280.224738) (xy 272.679681 -280.249345) (xy 272.671786 -280.297922) (xy 272.656202 -280.344603)
			(xy 272.633331 -280.38818) (xy 272.603766 -280.427524) (xy 272.568273 -280.461616) (xy 272.52777 -280.489572)
			(xy 272.483308 -280.51067) (xy 272.436037 -280.524362) (xy 272.387182 -280.530294) (xy 272.338007 -280.528313)
			(xy 272.289788 -280.518469) (xy 272.243772 -280.501017) (xy 272.201151 -280.47641) (xy 272.16303 -280.445285)
			(xy 272.130395 -280.408448) (xy 272.104092 -280.366852) (xy 272.084801 -280.321576) (xy 272.073024 -280.273792)
			(xy 272.069064 -280.224738) (xy 271.730216 -280.224738) (xy 271.729721 -280.249345) (xy 271.721826 -280.297922)
			(xy 271.706242 -280.344603) (xy 271.683371 -280.38818) (xy 271.653806 -280.427524) (xy 271.618313 -280.461616)
			(xy 271.57781 -280.489572) (xy 271.533348 -280.51067) (xy 271.486077 -280.524362) (xy 271.437222 -280.530294)
			(xy 271.388047 -280.528313) (xy 271.339828 -280.518469) (xy 271.293812 -280.501017) (xy 271.251191 -280.47641)
			(xy 271.21307 -280.445285) (xy 271.180435 -280.408448) (xy 271.154132 -280.366852) (xy 271.134841 -280.321576)
			(xy 271.123064 -280.273792) (xy 271.119104 -280.224738) (xy 270.780256 -280.224738) (xy 270.779761 -280.249345)
			(xy 270.771866 -280.297922) (xy 270.756282 -280.344603) (xy 270.733411 -280.38818) (xy 270.703846 -280.427524)
			(xy 270.668353 -280.461616) (xy 270.62785 -280.489572) (xy 270.583388 -280.51067) (xy 270.536117 -280.524362)
			(xy 270.487262 -280.530294) (xy 270.438087 -280.528313) (xy 270.389868 -280.518469) (xy 270.343852 -280.501017)
			(xy 270.301231 -280.47641) (xy 270.26311 -280.445285) (xy 270.230475 -280.408448) (xy 270.204172 -280.366852)
			(xy 270.184881 -280.321576) (xy 270.173104 -280.273792) (xy 270.169144 -280.224738) (xy 269.830042 -280.224738)
			(xy 269.829547 -280.249345) (xy 269.821652 -280.297922) (xy 269.806068 -280.344603) (xy 269.783197 -280.38818)
			(xy 269.753632 -280.427524) (xy 269.718139 -280.461616) (xy 269.677636 -280.489572) (xy 269.633174 -280.51067)
			(xy 269.585903 -280.524362) (xy 269.537048 -280.530294) (xy 269.487873 -280.528313) (xy 269.439654 -280.518469)
			(xy 269.393638 -280.501017) (xy 269.351017 -280.47641) (xy 269.312896 -280.445285) (xy 269.280261 -280.408448)
			(xy 269.253958 -280.366852) (xy 269.234667 -280.321576) (xy 269.22289 -280.273792) (xy 269.21893 -280.224738)
			(xy 268.880082 -280.224738) (xy 268.879587 -280.249345) (xy 268.871692 -280.297922) (xy 268.856108 -280.344603)
			(xy 268.833237 -280.38818) (xy 268.803672 -280.427524) (xy 268.768179 -280.461616) (xy 268.727676 -280.489572)
			(xy 268.683214 -280.51067) (xy 268.635943 -280.524362) (xy 268.587088 -280.530294) (xy 268.537913 -280.528313)
			(xy 268.489694 -280.518469) (xy 268.443678 -280.501017) (xy 268.401057 -280.47641) (xy 268.362936 -280.445285)
			(xy 268.330301 -280.408448) (xy 268.303998 -280.366852) (xy 268.284707 -280.321576) (xy 268.27293 -280.273792)
			(xy 268.26897 -280.224738) (xy 264.174371 -280.224738) (xy 264.160762 -280.235406) (xy 264.151364 -280.242772)
			(xy 264.14095 -280.263346) (xy 264.139426 -280.367232) (xy 264.149332 -280.388314) (xy 264.158476 -280.39568)
			(xy 264.180292 -280.413923) (xy 264.218835 -280.455733) (xy 264.250747 -280.502801) (xy 264.275319 -280.554084)
			(xy 264.292009 -280.608445) (xy 264.300447 -280.664681) (xy 264.30097 -280.693114) (xy 264.934444 -280.693114)
			(xy 264.938515 -280.637492) (xy 264.950641 -280.583055) (xy 264.970564 -280.530964) (xy 264.99786 -280.482329)
			(xy 265.031946 -280.438186) (xy 265.072095 -280.399477) (xy 265.117453 -280.367026) (xy 265.167053 -280.341525)
			(xy 265.219837 -280.323518) (xy 265.27468 -280.313388) (xy 265.330414 -280.311351) (xy 265.385851 -280.317451)
			(xy 265.439808 -280.331557) (xy 265.491137 -280.353369) (xy 265.538743 -280.382423) (xy 265.581611 -280.418098)
			(xy 265.618828 -280.459635) (xy 265.649601 -280.506148) (xy 265.673273 -280.556645) (xy 265.689341 -280.610052)
			(xy 265.697461 -280.665228) (xy 265.69797 -280.693114) (xy 265.820904 -280.693114) (xy 265.824975 -280.637492)
			(xy 265.837101 -280.583055) (xy 265.857024 -280.530964) (xy 265.88432 -280.482329) (xy 265.918406 -280.438186)
			(xy 265.958555 -280.399477) (xy 266.003913 -280.367026) (xy 266.053513 -280.341525) (xy 266.106297 -280.323518)
			(xy 266.16114 -280.313388) (xy 266.216874 -280.311351) (xy 266.272311 -280.317451) (xy 266.326268 -280.331557)
			(xy 266.377597 -280.353369) (xy 266.425203 -280.382423) (xy 266.468071 -280.418098) (xy 266.505288 -280.459635)
			(xy 266.536061 -280.506148) (xy 266.559733 -280.556645) (xy 266.575801 -280.610052) (xy 266.583921 -280.665228)
			(xy 266.58443 -280.693114) (xy 266.583921 -280.721) (xy 266.575801 -280.776176) (xy 266.559733 -280.829583)
			(xy 266.536061 -280.88008) (xy 266.505288 -280.926593) (xy 266.468071 -280.96813) (xy 266.425203 -281.003805)
			(xy 266.377597 -281.032859) (xy 266.326268 -281.054671) (xy 266.272311 -281.068777) (xy 266.216874 -281.074877)
			(xy 266.16114 -281.07284) (xy 266.106297 -281.06271) (xy 266.053513 -281.044703) (xy 266.003913 -281.019202)
			(xy 265.958555 -280.986751) (xy 265.918406 -280.948042) (xy 265.88432 -280.903899) (xy 265.857024 -280.855264)
			(xy 265.837101 -280.803173) (xy 265.824975 -280.748736) (xy 265.820904 -280.693114) (xy 265.69797 -280.693114)
			(xy 265.697461 -280.721) (xy 265.689341 -280.776176) (xy 265.673273 -280.829583) (xy 265.649601 -280.88008)
			(xy 265.618828 -280.926593) (xy 265.581611 -280.96813) (xy 265.538743 -281.003805) (xy 265.491137 -281.032859)
			(xy 265.439808 -281.054671) (xy 265.385851 -281.068777) (xy 265.330414 -281.074877) (xy 265.27468 -281.07284)
			(xy 265.219837 -281.06271) (xy 265.167053 -281.044703) (xy 265.117453 -281.019202) (xy 265.072095 -280.986751)
			(xy 265.031946 -280.948042) (xy 264.99786 -280.903899) (xy 264.970564 -280.855264) (xy 264.950641 -280.803173)
			(xy 264.938515 -280.748736) (xy 264.934444 -280.693114) (xy 264.30097 -280.693114) (xy 264.300484 -280.720365)
			(xy 264.292728 -280.774313) (xy 264.277373 -280.826608) (xy 264.254731 -280.876185) (xy 264.225265 -280.922035)
			(xy 264.189574 -280.963226) (xy 264.148383 -280.998917) (xy 264.102533 -281.028383) (xy 264.052956 -281.051025)
			(xy 264.000661 -281.06638) (xy 263.946713 -281.074136) (xy 263.892211 -281.074136) (xy 263.838263 -281.06638)
			(xy 263.785968 -281.051025) (xy 263.736391 -281.028383) (xy 263.690541 -280.998917) (xy 263.64935 -280.963226)
			(xy 263.613659 -280.922035) (xy 263.584193 -280.876185) (xy 263.561551 -280.826608) (xy 263.546196 -280.774313)
			(xy 263.53844 -280.720365) (xy 263.537954 -280.693114) (xy 249.737118 -280.693114) (xy 249.737118 -281.55011)
			(xy 250.225812 -281.55011) (xy 250.229883 -281.494488) (xy 250.242009 -281.440051) (xy 250.261932 -281.38796)
			(xy 250.289228 -281.339325) (xy 250.323314 -281.295182) (xy 250.363463 -281.256473) (xy 250.408821 -281.224022)
			(xy 250.458421 -281.198521) (xy 250.511205 -281.180514) (xy 250.566048 -281.170384) (xy 250.621782 -281.168347)
			(xy 250.677219 -281.174447) (xy 250.679151 -281.174952) (xy 268.26897 -281.174952) (xy 268.27293 -281.125898)
			(xy 268.284707 -281.078114) (xy 268.303998 -281.032838) (xy 268.330301 -280.991242) (xy 268.362936 -280.954405)
			(xy 268.401057 -280.92328) (xy 268.443678 -280.898673) (xy 268.489694 -280.881221) (xy 268.537913 -280.871377)
			(xy 268.587088 -280.869396) (xy 268.635943 -280.875328) (xy 268.683214 -280.88902) (xy 268.727676 -280.910118)
			(xy 268.768179 -280.938074) (xy 268.803672 -280.972166) (xy 268.833237 -281.01151) (xy 268.856108 -281.055087)
			(xy 268.871692 -281.101768) (xy 268.879587 -281.150345) (xy 268.880082 -281.174952) (xy 269.21893 -281.174952)
			(xy 269.22289 -281.125898) (xy 269.234667 -281.078114) (xy 269.253958 -281.032838) (xy 269.280261 -280.991242)
			(xy 269.312896 -280.954405) (xy 269.351017 -280.92328) (xy 269.393638 -280.898673) (xy 269.439654 -280.881221)
			(xy 269.487873 -280.871377) (xy 269.537048 -280.869396) (xy 269.585903 -280.875328) (xy 269.633174 -280.88902)
			(xy 269.677636 -280.910118) (xy 269.718139 -280.938074) (xy 269.753632 -280.972166) (xy 269.783197 -281.01151)
			(xy 269.806068 -281.055087) (xy 269.821652 -281.101768) (xy 269.829547 -281.150345) (xy 269.830042 -281.174952)
			(xy 270.169144 -281.174952) (xy 270.173104 -281.125898) (xy 270.184881 -281.078114) (xy 270.204172 -281.032838)
			(xy 270.230475 -280.991242) (xy 270.26311 -280.954405) (xy 270.301231 -280.92328) (xy 270.343852 -280.898673)
			(xy 270.389868 -280.881221) (xy 270.438087 -280.871377) (xy 270.487262 -280.869396) (xy 270.536117 -280.875328)
			(xy 270.583388 -280.88902) (xy 270.62785 -280.910118) (xy 270.668353 -280.938074) (xy 270.703846 -280.972166)
			(xy 270.733411 -281.01151) (xy 270.756282 -281.055087) (xy 270.771866 -281.101768) (xy 270.779761 -281.150345)
			(xy 270.780256 -281.174952) (xy 271.119104 -281.174952) (xy 271.123064 -281.125898) (xy 271.134841 -281.078114)
			(xy 271.154132 -281.032838) (xy 271.180435 -280.991242) (xy 271.21307 -280.954405) (xy 271.251191 -280.92328)
			(xy 271.293812 -280.898673) (xy 271.339828 -280.881221) (xy 271.388047 -280.871377) (xy 271.437222 -280.869396)
			(xy 271.486077 -280.875328) (xy 271.533348 -280.88902) (xy 271.57781 -280.910118) (xy 271.618313 -280.938074)
			(xy 271.653806 -280.972166) (xy 271.683371 -281.01151) (xy 271.706242 -281.055087) (xy 271.721826 -281.101768)
			(xy 271.729721 -281.150345) (xy 271.730216 -281.174952) (xy 272.069064 -281.174952) (xy 272.073024 -281.125898)
			(xy 272.084801 -281.078114) (xy 272.104092 -281.032838) (xy 272.130395 -280.991242) (xy 272.16303 -280.954405)
			(xy 272.201151 -280.92328) (xy 272.243772 -280.898673) (xy 272.289788 -280.881221) (xy 272.338007 -280.871377)
			(xy 272.387182 -280.869396) (xy 272.436037 -280.875328) (xy 272.483308 -280.88902) (xy 272.52777 -280.910118)
			(xy 272.568273 -280.938074) (xy 272.603766 -280.972166) (xy 272.633331 -281.01151) (xy 272.656202 -281.055087)
			(xy 272.671786 -281.101768) (xy 272.679681 -281.150345) (xy 272.680176 -281.174952) (xy 273.019024 -281.174952)
			(xy 273.022984 -281.125898) (xy 273.034761 -281.078114) (xy 273.054052 -281.032838) (xy 273.080355 -280.991242)
			(xy 273.11299 -280.954405) (xy 273.151111 -280.92328) (xy 273.193732 -280.898673) (xy 273.239748 -280.881221)
			(xy 273.287967 -280.871377) (xy 273.337142 -280.869396) (xy 273.385997 -280.875328) (xy 273.433268 -280.88902)
			(xy 273.47773 -280.910118) (xy 273.518233 -280.938074) (xy 273.553726 -280.972166) (xy 273.583291 -281.01151)
			(xy 273.606162 -281.055087) (xy 273.621746 -281.101768) (xy 273.629641 -281.150345) (xy 273.630136 -281.174952)
			(xy 273.968984 -281.174952) (xy 273.972944 -281.125898) (xy 273.984721 -281.078114) (xy 274.004012 -281.032838)
			(xy 274.030315 -280.991242) (xy 274.06295 -280.954405) (xy 274.101071 -280.92328) (xy 274.143692 -280.898673)
			(xy 274.189708 -280.881221) (xy 274.237927 -280.871377) (xy 274.287102 -280.869396) (xy 274.335957 -280.875328)
			(xy 274.383228 -280.88902) (xy 274.42769 -280.910118) (xy 274.468193 -280.938074) (xy 274.503686 -280.972166)
			(xy 274.533251 -281.01151) (xy 274.556122 -281.055087) (xy 274.571706 -281.101768) (xy 274.579601 -281.150345)
			(xy 274.580096 -281.174952) (xy 274.918944 -281.174952) (xy 274.922904 -281.125898) (xy 274.934681 -281.078114)
			(xy 274.953972 -281.032838) (xy 274.980275 -280.991242) (xy 275.01291 -280.954405) (xy 275.051031 -280.92328)
			(xy 275.093652 -280.898673) (xy 275.139668 -280.881221) (xy 275.187887 -280.871377) (xy 275.237062 -280.869396)
			(xy 275.285917 -280.875328) (xy 275.333188 -280.88902) (xy 275.37765 -280.910118) (xy 275.418153 -280.938074)
			(xy 275.453646 -280.972166) (xy 275.483211 -281.01151) (xy 275.506082 -281.055087) (xy 275.521666 -281.101768)
			(xy 275.529561 -281.150345) (xy 275.530056 -281.174952) (xy 275.530055 -281.175) (xy 275.868792 -281.175)
			(xy 275.872964 -281.124648) (xy 275.885367 -281.07567) (xy 275.905663 -281.029402) (xy 275.933298 -280.987105)
			(xy 275.967517 -280.949933) (xy 276.007388 -280.918901) (xy 276.051824 -280.894855) (xy 276.099611 -280.878451)
			(xy 276.149446 -280.870136) (xy 276.174708 -280.869644) (xy 276.188891 -280.869819) (xy 276.217131 -280.872492)
			(xy 276.231096 -280.874978) (xy 276.243542 -280.877264) (xy 276.267418 -280.869898) (xy 276.344634 -280.792682)
			(xy 276.352 -280.768552) (xy 276.349714 -280.75636) (xy 276.347226 -280.742332) (xy 276.344556 -280.713964)
			(xy 276.34438 -280.699718) (xy 276.344859 -280.674895) (xy 276.352888 -280.625903) (xy 276.368737 -280.578855)
			(xy 276.391989 -280.534992) (xy 276.422032 -280.495468) (xy 276.458073 -280.461325) (xy 276.499163 -280.433463)
			(xy 276.544219 -280.412616) (xy 276.592055 -280.399332) (xy 276.64141 -280.393963) (xy 276.690983 -280.39665)
			(xy 276.739468 -280.407321) (xy 276.785588 -280.425696) (xy 276.828127 -280.45129) (xy 276.865966 -280.48343)
			(xy 276.898106 -280.521268) (xy 276.923701 -280.563807) (xy 276.942077 -280.609927) (xy 276.952749 -280.658412)
			(xy 276.954989 -280.699718) (xy 277.294098 -280.699718) (xy 277.298058 -280.650664) (xy 277.309835 -280.60288)
			(xy 277.329126 -280.557604) (xy 277.355429 -280.516008) (xy 277.388064 -280.479171) (xy 277.426185 -280.448046)
			(xy 277.468806 -280.423439) (xy 277.514822 -280.405987) (xy 277.563041 -280.396143) (xy 277.612216 -280.394162)
			(xy 277.661071 -280.400094) (xy 277.708342 -280.413786) (xy 277.752804 -280.434884) (xy 277.793307 -280.46284)
			(xy 277.8288 -280.496932) (xy 277.858365 -280.536276) (xy 277.881236 -280.579853) (xy 277.89682 -280.626534)
			(xy 277.904715 -280.675111) (xy 277.90521 -280.699718) (xy 278.244058 -280.699718) (xy 278.248018 -280.650664)
			(xy 278.259795 -280.60288) (xy 278.279086 -280.557604) (xy 278.305389 -280.516008) (xy 278.338024 -280.479171)
			(xy 278.376145 -280.448046) (xy 278.418766 -280.423439) (xy 278.464782 -280.405987) (xy 278.513001 -280.396143)
			(xy 278.562176 -280.394162) (xy 278.611031 -280.400094) (xy 278.658302 -280.413786) (xy 278.702764 -280.434884)
			(xy 278.743267 -280.46284) (xy 278.77876 -280.496932) (xy 278.808325 -280.536276) (xy 278.831196 -280.579853)
			(xy 278.84678 -280.626534) (xy 278.854675 -280.675111) (xy 278.85517 -280.699718) (xy 279.194018 -280.699718)
			(xy 279.197978 -280.650664) (xy 279.209755 -280.60288) (xy 279.229046 -280.557604) (xy 279.255349 -280.516008)
			(xy 279.287984 -280.479171) (xy 279.326105 -280.448046) (xy 279.368726 -280.423439) (xy 279.414742 -280.405987)
			(xy 279.462961 -280.396143) (xy 279.512136 -280.394162) (xy 279.560991 -280.400094) (xy 279.608262 -280.413786)
			(xy 279.652724 -280.434884) (xy 279.693227 -280.46284) (xy 279.72872 -280.496932) (xy 279.758285 -280.536276)
			(xy 279.781156 -280.579853) (xy 279.79674 -280.626534) (xy 279.804635 -280.675111) (xy 279.80513 -280.699718)
			(xy 280.143978 -280.699718) (xy 280.147938 -280.650664) (xy 280.159715 -280.60288) (xy 280.179006 -280.557604)
			(xy 280.205309 -280.516008) (xy 280.237944 -280.479171) (xy 280.276065 -280.448046) (xy 280.318686 -280.423439)
			(xy 280.364702 -280.405987) (xy 280.412921 -280.396143) (xy 280.462096 -280.394162) (xy 280.510951 -280.400094)
			(xy 280.558222 -280.413786) (xy 280.602684 -280.434884) (xy 280.643187 -280.46284) (xy 280.67868 -280.496932)
			(xy 280.708245 -280.536276) (xy 280.731116 -280.579853) (xy 280.7467 -280.626534) (xy 280.754595 -280.675111)
			(xy 280.75509 -280.699718) (xy 281.093938 -280.699718) (xy 281.097898 -280.650664) (xy 281.109675 -280.60288)
			(xy 281.128966 -280.557604) (xy 281.155269 -280.516008) (xy 281.187904 -280.479171) (xy 281.226025 -280.448046)
			(xy 281.268646 -280.423439) (xy 281.314662 -280.405987) (xy 281.362881 -280.396143) (xy 281.412056 -280.394162)
			(xy 281.460911 -280.400094) (xy 281.508182 -280.413786) (xy 281.552644 -280.434884) (xy 281.593147 -280.46284)
			(xy 281.62864 -280.496932) (xy 281.658205 -280.536276) (xy 281.681076 -280.579853) (xy 281.69666 -280.626534)
			(xy 281.704555 -280.675111) (xy 281.70505 -280.699718) (xy 282.043898 -280.699718) (xy 282.047858 -280.650664)
			(xy 282.059635 -280.60288) (xy 282.078926 -280.557604) (xy 282.105229 -280.516008) (xy 282.137864 -280.479171)
			(xy 282.175985 -280.448046) (xy 282.218606 -280.423439) (xy 282.264622 -280.405987) (xy 282.312841 -280.396143)
			(xy 282.362016 -280.394162) (xy 282.410871 -280.400094) (xy 282.458142 -280.413786) (xy 282.502604 -280.434884)
			(xy 282.543107 -280.46284) (xy 282.5786 -280.496932) (xy 282.608165 -280.536276) (xy 282.631036 -280.579853)
			(xy 282.64662 -280.626534) (xy 282.654515 -280.675111) (xy 282.65501 -280.699718) (xy 282.994112 -280.699718)
			(xy 282.998072 -280.650664) (xy 283.009849 -280.60288) (xy 283.02914 -280.557604) (xy 283.055443 -280.516008)
			(xy 283.088078 -280.479171) (xy 283.126199 -280.448046) (xy 283.16882 -280.423439) (xy 283.214836 -280.405987)
			(xy 283.263055 -280.396143) (xy 283.31223 -280.394162) (xy 283.361085 -280.400094) (xy 283.408356 -280.413786)
			(xy 283.452818 -280.434884) (xy 283.493321 -280.46284) (xy 283.528814 -280.496932) (xy 283.558379 -280.536276)
			(xy 283.58125 -280.579853) (xy 283.596834 -280.626534) (xy 283.604729 -280.675111) (xy 283.605224 -280.699718)
			(xy 283.944072 -280.699718) (xy 283.948032 -280.650664) (xy 283.959809 -280.60288) (xy 283.9791 -280.557604)
			(xy 284.005403 -280.516008) (xy 284.038038 -280.479171) (xy 284.076159 -280.448046) (xy 284.11878 -280.423439)
			(xy 284.164796 -280.405987) (xy 284.213015 -280.396143) (xy 284.26219 -280.394162) (xy 284.311045 -280.400094)
			(xy 284.358316 -280.413786) (xy 284.402778 -280.434884) (xy 284.443281 -280.46284) (xy 284.478774 -280.496932)
			(xy 284.508339 -280.536276) (xy 284.53121 -280.579853) (xy 284.546794 -280.626534) (xy 284.554689 -280.675111)
			(xy 284.555184 -280.699718) (xy 284.894032 -280.699718) (xy 284.897992 -280.650664) (xy 284.909769 -280.60288)
			(xy 284.92906 -280.557604) (xy 284.955363 -280.516008) (xy 284.987998 -280.479171) (xy 285.026119 -280.448046)
			(xy 285.06874 -280.423439) (xy 285.114756 -280.405987) (xy 285.162975 -280.396143) (xy 285.21215 -280.394162)
			(xy 285.261005 -280.400094) (xy 285.308276 -280.413786) (xy 285.352738 -280.434884) (xy 285.393241 -280.46284)
			(xy 285.428734 -280.496932) (xy 285.458299 -280.536276) (xy 285.48117 -280.579853) (xy 285.496754 -280.626534)
			(xy 285.504649 -280.675111) (xy 285.505144 -280.699718) (xy 285.843992 -280.699718) (xy 285.847952 -280.650664)
			(xy 285.859729 -280.60288) (xy 285.87902 -280.557604) (xy 285.905323 -280.516008) (xy 285.937958 -280.479171)
			(xy 285.976079 -280.448046) (xy 286.0187 -280.423439) (xy 286.064716 -280.405987) (xy 286.112935 -280.396143)
			(xy 286.16211 -280.394162) (xy 286.210965 -280.400094) (xy 286.258236 -280.413786) (xy 286.302698 -280.434884)
			(xy 286.343201 -280.46284) (xy 286.378694 -280.496932) (xy 286.408259 -280.536276) (xy 286.43113 -280.579853)
			(xy 286.446714 -280.626534) (xy 286.454609 -280.675111) (xy 286.455104 -280.699718) (xy 286.793952 -280.699718)
			(xy 286.797912 -280.650664) (xy 286.809689 -280.60288) (xy 286.82898 -280.557604) (xy 286.855283 -280.516008)
			(xy 286.887918 -280.479171) (xy 286.926039 -280.448046) (xy 286.96866 -280.423439) (xy 287.014676 -280.405987)
			(xy 287.062895 -280.396143) (xy 287.11207 -280.394162) (xy 287.160925 -280.400094) (xy 287.208196 -280.413786)
			(xy 287.252658 -280.434884) (xy 287.293161 -280.46284) (xy 287.328654 -280.496932) (xy 287.358219 -280.536276)
			(xy 287.38109 -280.579853) (xy 287.396674 -280.626534) (xy 287.404569 -280.675111) (xy 287.405064 -280.699718)
			(xy 287.743912 -280.699718) (xy 287.747872 -280.650664) (xy 287.759649 -280.60288) (xy 287.77894 -280.557604)
			(xy 287.805243 -280.516008) (xy 287.837878 -280.479171) (xy 287.875999 -280.448046) (xy 287.91862 -280.423439)
			(xy 287.964636 -280.405987) (xy 288.012855 -280.396143) (xy 288.06203 -280.394162) (xy 288.110885 -280.400094)
			(xy 288.158156 -280.413786) (xy 288.202618 -280.434884) (xy 288.243121 -280.46284) (xy 288.278614 -280.496932)
			(xy 288.308179 -280.536276) (xy 288.33105 -280.579853) (xy 288.346634 -280.626534) (xy 288.354529 -280.675111)
			(xy 288.355024 -280.699718) (xy 288.693872 -280.699718) (xy 288.697832 -280.650664) (xy 288.709609 -280.60288)
			(xy 288.7289 -280.557604) (xy 288.755203 -280.516008) (xy 288.787838 -280.479171) (xy 288.825959 -280.448046)
			(xy 288.86858 -280.423439) (xy 288.914596 -280.405987) (xy 288.962815 -280.396143) (xy 289.01199 -280.394162)
			(xy 289.060845 -280.400094) (xy 289.108116 -280.413786) (xy 289.152578 -280.434884) (xy 289.193081 -280.46284)
			(xy 289.228574 -280.496932) (xy 289.258139 -280.536276) (xy 289.28101 -280.579853) (xy 289.296594 -280.626534)
			(xy 289.304489 -280.675111) (xy 289.304984 -280.699718) (xy 289.304489 -280.724325) (xy 289.296594 -280.772902)
			(xy 289.28101 -280.819583) (xy 289.258139 -280.86316) (xy 289.228574 -280.902504) (xy 289.193081 -280.936596)
			(xy 289.152578 -280.964552) (xy 289.108116 -280.98565) (xy 289.060845 -280.999342) (xy 289.01199 -281.005274)
			(xy 288.962815 -281.003293) (xy 288.914596 -280.993449) (xy 288.86858 -280.975997) (xy 288.825959 -280.95139)
			(xy 288.787838 -280.920265) (xy 288.755203 -280.883428) (xy 288.7289 -280.841832) (xy 288.709609 -280.796556)
			(xy 288.697832 -280.748772) (xy 288.693872 -280.699718) (xy 288.355024 -280.699718) (xy 288.354529 -280.724325)
			(xy 288.346634 -280.772902) (xy 288.33105 -280.819583) (xy 288.308179 -280.86316) (xy 288.278614 -280.902504)
			(xy 288.243121 -280.936596) (xy 288.202618 -280.964552) (xy 288.158156 -280.98565) (xy 288.110885 -280.999342)
			(xy 288.06203 -281.005274) (xy 288.012855 -281.003293) (xy 287.964636 -280.993449) (xy 287.91862 -280.975997)
			(xy 287.875999 -280.95139) (xy 287.837878 -280.920265) (xy 287.805243 -280.883428) (xy 287.77894 -280.841832)
			(xy 287.759649 -280.796556) (xy 287.747872 -280.748772) (xy 287.743912 -280.699718) (xy 287.405064 -280.699718)
			(xy 287.404569 -280.724325) (xy 287.396674 -280.772902) (xy 287.38109 -280.819583) (xy 287.358219 -280.86316)
			(xy 287.328654 -280.902504) (xy 287.293161 -280.936596) (xy 287.252658 -280.964552) (xy 287.208196 -280.98565)
			(xy 287.160925 -280.999342) (xy 287.11207 -281.005274) (xy 287.062895 -281.003293) (xy 287.014676 -280.993449)
			(xy 286.96866 -280.975997) (xy 286.926039 -280.95139) (xy 286.887918 -280.920265) (xy 286.855283 -280.883428)
			(xy 286.82898 -280.841832) (xy 286.809689 -280.796556) (xy 286.797912 -280.748772) (xy 286.793952 -280.699718)
			(xy 286.455104 -280.699718) (xy 286.454609 -280.724325) (xy 286.446714 -280.772902) (xy 286.43113 -280.819583)
			(xy 286.408259 -280.86316) (xy 286.378694 -280.902504) (xy 286.343201 -280.936596) (xy 286.302698 -280.964552)
			(xy 286.258236 -280.98565) (xy 286.210965 -280.999342) (xy 286.16211 -281.005274) (xy 286.112935 -281.003293)
			(xy 286.064716 -280.993449) (xy 286.0187 -280.975997) (xy 285.976079 -280.95139) (xy 285.937958 -280.920265)
			(xy 285.905323 -280.883428) (xy 285.87902 -280.841832) (xy 285.859729 -280.796556) (xy 285.847952 -280.748772)
			(xy 285.843992 -280.699718) (xy 285.505144 -280.699718) (xy 285.504649 -280.724325) (xy 285.496754 -280.772902)
			(xy 285.48117 -280.819583) (xy 285.458299 -280.86316) (xy 285.428734 -280.902504) (xy 285.393241 -280.936596)
			(xy 285.352738 -280.964552) (xy 285.308276 -280.98565) (xy 285.261005 -280.999342) (xy 285.21215 -281.005274)
			(xy 285.162975 -281.003293) (xy 285.114756 -280.993449) (xy 285.06874 -280.975997) (xy 285.026119 -280.95139)
			(xy 284.987998 -280.920265) (xy 284.955363 -280.883428) (xy 284.92906 -280.841832) (xy 284.909769 -280.796556)
			(xy 284.897992 -280.748772) (xy 284.894032 -280.699718) (xy 284.555184 -280.699718) (xy 284.554689 -280.724325)
			(xy 284.546794 -280.772902) (xy 284.53121 -280.819583) (xy 284.508339 -280.86316) (xy 284.478774 -280.902504)
			(xy 284.443281 -280.936596) (xy 284.402778 -280.964552) (xy 284.358316 -280.98565) (xy 284.311045 -280.999342)
			(xy 284.26219 -281.005274) (xy 284.213015 -281.003293) (xy 284.164796 -280.993449) (xy 284.11878 -280.975997)
			(xy 284.076159 -280.95139) (xy 284.038038 -280.920265) (xy 284.005403 -280.883428) (xy 283.9791 -280.841832)
			(xy 283.959809 -280.796556) (xy 283.948032 -280.748772) (xy 283.944072 -280.699718) (xy 283.605224 -280.699718)
			(xy 283.604729 -280.724325) (xy 283.596834 -280.772902) (xy 283.58125 -280.819583) (xy 283.558379 -280.86316)
			(xy 283.528814 -280.902504) (xy 283.493321 -280.936596) (xy 283.452818 -280.964552) (xy 283.408356 -280.98565)
			(xy 283.361085 -280.999342) (xy 283.31223 -281.005274) (xy 283.263055 -281.003293) (xy 283.214836 -280.993449)
			(xy 283.16882 -280.975997) (xy 283.126199 -280.95139) (xy 283.088078 -280.920265) (xy 283.055443 -280.883428)
			(xy 283.02914 -280.841832) (xy 283.009849 -280.796556) (xy 282.998072 -280.748772) (xy 282.994112 -280.699718)
			(xy 282.65501 -280.699718) (xy 282.654515 -280.724325) (xy 282.64662 -280.772902) (xy 282.631036 -280.819583)
			(xy 282.608165 -280.86316) (xy 282.5786 -280.902504) (xy 282.543107 -280.936596) (xy 282.502604 -280.964552)
			(xy 282.458142 -280.98565) (xy 282.410871 -280.999342) (xy 282.362016 -281.005274) (xy 282.312841 -281.003293)
			(xy 282.264622 -280.993449) (xy 282.218606 -280.975997) (xy 282.175985 -280.95139) (xy 282.137864 -280.920265)
			(xy 282.105229 -280.883428) (xy 282.078926 -280.841832) (xy 282.059635 -280.796556) (xy 282.047858 -280.748772)
			(xy 282.043898 -280.699718) (xy 281.70505 -280.699718) (xy 281.704555 -280.724325) (xy 281.69666 -280.772902)
			(xy 281.681076 -280.819583) (xy 281.658205 -280.86316) (xy 281.62864 -280.902504) (xy 281.593147 -280.936596)
			(xy 281.552644 -280.964552) (xy 281.508182 -280.98565) (xy 281.460911 -280.999342) (xy 281.412056 -281.005274)
			(xy 281.362881 -281.003293) (xy 281.314662 -280.993449) (xy 281.268646 -280.975997) (xy 281.226025 -280.95139)
			(xy 281.187904 -280.920265) (xy 281.155269 -280.883428) (xy 281.128966 -280.841832) (xy 281.109675 -280.796556)
			(xy 281.097898 -280.748772) (xy 281.093938 -280.699718) (xy 280.75509 -280.699718) (xy 280.754595 -280.724325)
			(xy 280.7467 -280.772902) (xy 280.731116 -280.819583) (xy 280.708245 -280.86316) (xy 280.67868 -280.902504)
			(xy 280.643187 -280.936596) (xy 280.602684 -280.964552) (xy 280.558222 -280.98565) (xy 280.510951 -280.999342)
			(xy 280.462096 -281.005274) (xy 280.412921 -281.003293) (xy 280.364702 -280.993449) (xy 280.318686 -280.975997)
			(xy 280.276065 -280.95139) (xy 280.237944 -280.920265) (xy 280.205309 -280.883428) (xy 280.179006 -280.841832)
			(xy 280.159715 -280.796556) (xy 280.147938 -280.748772) (xy 280.143978 -280.699718) (xy 279.80513 -280.699718)
			(xy 279.804635 -280.724325) (xy 279.79674 -280.772902) (xy 279.781156 -280.819583) (xy 279.758285 -280.86316)
			(xy 279.72872 -280.902504) (xy 279.693227 -280.936596) (xy 279.652724 -280.964552) (xy 279.608262 -280.98565)
			(xy 279.560991 -280.999342) (xy 279.512136 -281.005274) (xy 279.462961 -281.003293) (xy 279.414742 -280.993449)
			(xy 279.368726 -280.975997) (xy 279.326105 -280.95139) (xy 279.287984 -280.920265) (xy 279.255349 -280.883428)
			(xy 279.229046 -280.841832) (xy 279.209755 -280.796556) (xy 279.197978 -280.748772) (xy 279.194018 -280.699718)
			(xy 278.85517 -280.699718) (xy 278.854675 -280.724325) (xy 278.84678 -280.772902) (xy 278.831196 -280.819583)
			(xy 278.808325 -280.86316) (xy 278.77876 -280.902504) (xy 278.743267 -280.936596) (xy 278.702764 -280.964552)
			(xy 278.658302 -280.98565) (xy 278.611031 -280.999342) (xy 278.562176 -281.005274) (xy 278.513001 -281.003293)
			(xy 278.464782 -280.993449) (xy 278.418766 -280.975997) (xy 278.376145 -280.95139) (xy 278.338024 -280.920265)
			(xy 278.305389 -280.883428) (xy 278.279086 -280.841832) (xy 278.259795 -280.796556) (xy 278.248018 -280.748772)
			(xy 278.244058 -280.699718) (xy 277.90521 -280.699718) (xy 277.904715 -280.724325) (xy 277.89682 -280.772902)
			(xy 277.881236 -280.819583) (xy 277.858365 -280.86316) (xy 277.8288 -280.902504) (xy 277.793307 -280.936596)
			(xy 277.752804 -280.964552) (xy 277.708342 -280.98565) (xy 277.661071 -280.999342) (xy 277.612216 -281.005274)
			(xy 277.563041 -281.003293) (xy 277.514822 -280.993449) (xy 277.468806 -280.975997) (xy 277.426185 -280.95139)
			(xy 277.388064 -280.920265) (xy 277.355429 -280.883428) (xy 277.329126 -280.841832) (xy 277.309835 -280.796556)
			(xy 277.298058 -280.748772) (xy 277.294098 -280.699718) (xy 276.954989 -280.699718) (xy 276.955437 -280.707984)
			(xy 276.950069 -280.757339) (xy 276.936787 -280.805175) (xy 276.91594 -280.850232) (xy 276.888079 -280.891322)
			(xy 276.853937 -280.927364) (xy 276.814413 -280.957407) (xy 276.77055 -280.980661) (xy 276.723503 -280.996511)
			(xy 276.674511 -281.004541) (xy 276.649688 -281.005026) (xy 276.635505 -281.004851) (xy 276.607265 -281.002178)
			(xy 276.5933 -280.999692) (xy 276.580854 -280.997406) (xy 276.556978 -281.004772) (xy 276.479762 -281.081988)
			(xy 276.472396 -281.106118) (xy 276.474682 -281.11831) (xy 276.477166 -281.132339) (xy 276.479838 -281.160706)
			(xy 276.480016 -281.174952) (xy 276.479833 -281.189135) (xy 276.477165 -281.217375) (xy 276.474682 -281.23134)
			(xy 276.472396 -281.243786) (xy 276.479762 -281.267408) (xy 276.557232 -281.344878) (xy 276.580854 -281.352244)
			(xy 276.5933 -281.349958) (xy 276.607267 -281.347486) (xy 276.635506 -281.344811) (xy 276.649688 -281.344624)
			(xy 276.673682 -281.345049) (xy 276.721081 -281.352555) (xy 276.766721 -281.367384) (xy 276.809479 -281.389171)
			(xy 276.848302 -281.417379) (xy 276.882234 -281.451313) (xy 276.91044 -281.490138) (xy 276.932223 -281.532898)
			(xy 276.947049 -281.578539) (xy 276.954552 -281.625938) (xy 276.954996 -281.649932) (xy 276.954824 -281.664115)
			(xy 276.952149 -281.692355) (xy 276.949662 -281.70632) (xy 276.947376 -281.718766) (xy 276.954742 -281.742642)
			(xy 277.031958 -281.819858) (xy 277.056088 -281.827224) (xy 277.06828 -281.824938) (xy 277.08231 -281.822458)
			(xy 277.110676 -281.819783) (xy 277.124922 -281.819604) (xy 277.139105 -281.819777) (xy 277.167345 -281.822452)
			(xy 277.18131 -281.824938) (xy 277.193756 -281.827224) (xy 277.217378 -281.819858) (xy 277.294848 -281.742388)
			(xy 277.302214 -281.718766) (xy 277.299928 -281.70632) (xy 277.297445 -281.692355) (xy 277.294777 -281.664115)
			(xy 277.294594 -281.649932) (xy 277.295116 -281.624677) (xy 277.303429 -281.574855) (xy 277.31983 -281.527081)
			(xy 277.343871 -281.482658) (xy 277.374895 -281.442798) (xy 277.412057 -281.408588) (xy 277.454343 -281.380962)
			(xy 277.500599 -281.360672) (xy 277.549564 -281.348272) (xy 277.599902 -281.344101) (xy 277.65024 -281.348272)
			(xy 277.699205 -281.360672) (xy 277.745461 -281.380962) (xy 277.787747 -281.408588) (xy 277.824909 -281.442798)
			(xy 277.855933 -281.482658) (xy 277.879974 -281.527081) (xy 277.896375 -281.574855) (xy 277.904688 -281.624677)
			(xy 277.90521 -281.649932) (xy 277.905038 -281.664115) (xy 277.902363 -281.692355) (xy 277.899876 -281.70632)
			(xy 277.89759 -281.718766) (xy 277.904956 -281.742388) (xy 277.982426 -281.819858) (xy 278.006048 -281.827224)
			(xy 278.018494 -281.824938) (xy 278.032461 -281.822467) (xy 278.0607 -281.819791) (xy 278.074882 -281.819604)
			(xy 278.089065 -281.819783) (xy 278.117305 -281.822453) (xy 278.13127 -281.824938) (xy 278.143716 -281.827224)
			(xy 278.167338 -281.819858) (xy 278.244808 -281.742388) (xy 278.252174 -281.718766) (xy 278.249888 -281.70632)
			(xy 278.247404 -281.692355) (xy 278.244737 -281.664115) (xy 278.244554 -281.649932) (xy 278.245043 -281.625107)
			(xy 278.253071 -281.576111) (xy 278.26892 -281.52906) (xy 278.292173 -281.485192) (xy 278.322216 -281.445664)
			(xy 278.358259 -281.411518) (xy 278.399352 -281.383653) (xy 278.444411 -281.362804) (xy 278.49225 -281.349519)
			(xy 278.541608 -281.344149) (xy 278.591185 -281.346836) (xy 278.639674 -281.357508) (xy 278.685797 -281.375885)
			(xy 278.728339 -281.401482) (xy 278.76618 -281.433624) (xy 278.798322 -281.471466) (xy 278.823918 -281.514009)
			(xy 278.842293 -281.560132) (xy 278.852965 -281.608621) (xy 278.855202 -281.649932) (xy 279.194018 -281.649932)
			(xy 279.197978 -281.600878) (xy 279.209755 -281.553094) (xy 279.229046 -281.507818) (xy 279.255349 -281.466222)
			(xy 279.287984 -281.429385) (xy 279.326105 -281.39826) (xy 279.368726 -281.373653) (xy 279.414742 -281.356201)
			(xy 279.462961 -281.346357) (xy 279.512136 -281.344376) (xy 279.560991 -281.350308) (xy 279.608262 -281.364)
			(xy 279.652724 -281.385098) (xy 279.693227 -281.413054) (xy 279.72872 -281.447146) (xy 279.758285 -281.48649)
			(xy 279.781156 -281.530067) (xy 279.79674 -281.576748) (xy 279.804635 -281.625325) (xy 279.80513 -281.649932)
			(xy 280.143978 -281.649932) (xy 280.147938 -281.600878) (xy 280.159715 -281.553094) (xy 280.179006 -281.507818)
			(xy 280.205309 -281.466222) (xy 280.237944 -281.429385) (xy 280.276065 -281.39826) (xy 280.318686 -281.373653)
			(xy 280.364702 -281.356201) (xy 280.412921 -281.346357) (xy 280.462096 -281.344376) (xy 280.510951 -281.350308)
			(xy 280.558222 -281.364) (xy 280.602684 -281.385098) (xy 280.643187 -281.413054) (xy 280.67868 -281.447146)
			(xy 280.708245 -281.48649) (xy 280.731116 -281.530067) (xy 280.7467 -281.576748) (xy 280.754595 -281.625325)
			(xy 280.75509 -281.649932) (xy 281.093938 -281.649932) (xy 281.097898 -281.600878) (xy 281.109675 -281.553094)
			(xy 281.128966 -281.507818) (xy 281.155269 -281.466222) (xy 281.187904 -281.429385) (xy 281.226025 -281.39826)
			(xy 281.268646 -281.373653) (xy 281.314662 -281.356201) (xy 281.362881 -281.346357) (xy 281.412056 -281.344376)
			(xy 281.460911 -281.350308) (xy 281.508182 -281.364) (xy 281.552644 -281.385098) (xy 281.593147 -281.413054)
			(xy 281.62864 -281.447146) (xy 281.658205 -281.48649) (xy 281.681076 -281.530067) (xy 281.69666 -281.576748)
			(xy 281.704555 -281.625325) (xy 281.70505 -281.649932) (xy 282.043898 -281.649932) (xy 282.047858 -281.600878)
			(xy 282.059635 -281.553094) (xy 282.078926 -281.507818) (xy 282.105229 -281.466222) (xy 282.137864 -281.429385)
			(xy 282.175985 -281.39826) (xy 282.218606 -281.373653) (xy 282.264622 -281.356201) (xy 282.312841 -281.346357)
			(xy 282.362016 -281.344376) (xy 282.410871 -281.350308) (xy 282.458142 -281.364) (xy 282.502604 -281.385098)
			(xy 282.543107 -281.413054) (xy 282.5786 -281.447146) (xy 282.608165 -281.48649) (xy 282.631036 -281.530067)
			(xy 282.64662 -281.576748) (xy 282.654515 -281.625325) (xy 282.65501 -281.649932) (xy 282.994112 -281.649932)
			(xy 282.998072 -281.600878) (xy 283.009849 -281.553094) (xy 283.02914 -281.507818) (xy 283.055443 -281.466222)
			(xy 283.088078 -281.429385) (xy 283.126199 -281.39826) (xy 283.16882 -281.373653) (xy 283.214836 -281.356201)
			(xy 283.263055 -281.346357) (xy 283.31223 -281.344376) (xy 283.361085 -281.350308) (xy 283.408356 -281.364)
			(xy 283.452818 -281.385098) (xy 283.493321 -281.413054) (xy 283.528814 -281.447146) (xy 283.558379 -281.48649)
			(xy 283.58125 -281.530067) (xy 283.596834 -281.576748) (xy 283.604729 -281.625325) (xy 283.605224 -281.649932)
			(xy 283.944072 -281.649932) (xy 283.948032 -281.600878) (xy 283.959809 -281.553094) (xy 283.9791 -281.507818)
			(xy 284.005403 -281.466222) (xy 284.038038 -281.429385) (xy 284.076159 -281.39826) (xy 284.11878 -281.373653)
			(xy 284.164796 -281.356201) (xy 284.213015 -281.346357) (xy 284.26219 -281.344376) (xy 284.311045 -281.350308)
			(xy 284.358316 -281.364) (xy 284.402778 -281.385098) (xy 284.443281 -281.413054) (xy 284.478774 -281.447146)
			(xy 284.508339 -281.48649) (xy 284.53121 -281.530067) (xy 284.546794 -281.576748) (xy 284.554689 -281.625325)
			(xy 284.555184 -281.649932) (xy 284.894032 -281.649932) (xy 284.897992 -281.600878) (xy 284.909769 -281.553094)
			(xy 284.92906 -281.507818) (xy 284.955363 -281.466222) (xy 284.987998 -281.429385) (xy 285.026119 -281.39826)
			(xy 285.06874 -281.373653) (xy 285.114756 -281.356201) (xy 285.162975 -281.346357) (xy 285.21215 -281.344376)
			(xy 285.261005 -281.350308) (xy 285.308276 -281.364) (xy 285.352738 -281.385098) (xy 285.393241 -281.413054)
			(xy 285.428734 -281.447146) (xy 285.458299 -281.48649) (xy 285.48117 -281.530067) (xy 285.496754 -281.576748)
			(xy 285.504649 -281.625325) (xy 285.505144 -281.649932) (xy 285.843992 -281.649932) (xy 285.847952 -281.600878)
			(xy 285.859729 -281.553094) (xy 285.87902 -281.507818) (xy 285.905323 -281.466222) (xy 285.937958 -281.429385)
			(xy 285.976079 -281.39826) (xy 286.0187 -281.373653) (xy 286.064716 -281.356201) (xy 286.112935 -281.346357)
			(xy 286.16211 -281.344376) (xy 286.210965 -281.350308) (xy 286.258236 -281.364) (xy 286.302698 -281.385098)
			(xy 286.343201 -281.413054) (xy 286.378694 -281.447146) (xy 286.408259 -281.48649) (xy 286.43113 -281.530067)
			(xy 286.446714 -281.576748) (xy 286.454609 -281.625325) (xy 286.455104 -281.649932) (xy 286.793952 -281.649932)
			(xy 286.797912 -281.600878) (xy 286.809689 -281.553094) (xy 286.82898 -281.507818) (xy 286.855283 -281.466222)
			(xy 286.887918 -281.429385) (xy 286.926039 -281.39826) (xy 286.96866 -281.373653) (xy 287.014676 -281.356201)
			(xy 287.062895 -281.346357) (xy 287.11207 -281.344376) (xy 287.160925 -281.350308) (xy 287.208196 -281.364)
			(xy 287.252658 -281.385098) (xy 287.293161 -281.413054) (xy 287.328654 -281.447146) (xy 287.358219 -281.48649)
			(xy 287.38109 -281.530067) (xy 287.396674 -281.576748) (xy 287.404569 -281.625325) (xy 287.405064 -281.649932)
			(xy 287.743912 -281.649932) (xy 287.747872 -281.600878) (xy 287.759649 -281.553094) (xy 287.77894 -281.507818)
			(xy 287.805243 -281.466222) (xy 287.837878 -281.429385) (xy 287.875999 -281.39826) (xy 287.91862 -281.373653)
			(xy 287.964636 -281.356201) (xy 288.012855 -281.346357) (xy 288.06203 -281.344376) (xy 288.110885 -281.350308)
			(xy 288.158156 -281.364) (xy 288.202618 -281.385098) (xy 288.243121 -281.413054) (xy 288.278614 -281.447146)
			(xy 288.308179 -281.48649) (xy 288.33105 -281.530067) (xy 288.346634 -281.576748) (xy 288.354529 -281.625325)
			(xy 288.355024 -281.649932) (xy 288.694126 -281.649932) (xy 288.698086 -281.600878) (xy 288.709863 -281.553094)
			(xy 288.729154 -281.507818) (xy 288.755457 -281.466222) (xy 288.788092 -281.429385) (xy 288.826213 -281.39826)
			(xy 288.868834 -281.373653) (xy 288.91485 -281.356201) (xy 288.963069 -281.346357) (xy 289.012244 -281.344376)
			(xy 289.061099 -281.350308) (xy 289.10837 -281.364) (xy 289.152832 -281.385098) (xy 289.193335 -281.413054)
			(xy 289.228828 -281.447146) (xy 289.258393 -281.48649) (xy 289.281264 -281.530067) (xy 289.296848 -281.576748)
			(xy 289.304743 -281.625325) (xy 289.305238 -281.649932) (xy 289.304743 -281.674539) (xy 289.296848 -281.723116)
			(xy 289.281264 -281.769797) (xy 289.258393 -281.813374) (xy 289.228828 -281.852718) (xy 289.193335 -281.88681)
			(xy 289.152832 -281.914766) (xy 289.10837 -281.935864) (xy 289.061099 -281.949556) (xy 289.012244 -281.955488)
			(xy 288.963069 -281.953507) (xy 288.91485 -281.943663) (xy 288.868834 -281.926211) (xy 288.826213 -281.901604)
			(xy 288.788092 -281.870479) (xy 288.755457 -281.833642) (xy 288.729154 -281.792046) (xy 288.709863 -281.74677)
			(xy 288.698086 -281.698986) (xy 288.694126 -281.649932) (xy 288.355024 -281.649932) (xy 288.354529 -281.674539)
			(xy 288.346634 -281.723116) (xy 288.33105 -281.769797) (xy 288.308179 -281.813374) (xy 288.278614 -281.852718)
			(xy 288.243121 -281.88681) (xy 288.202618 -281.914766) (xy 288.158156 -281.935864) (xy 288.110885 -281.949556)
			(xy 288.06203 -281.955488) (xy 288.012855 -281.953507) (xy 287.964636 -281.943663) (xy 287.91862 -281.926211)
			(xy 287.875999 -281.901604) (xy 287.837878 -281.870479) (xy 287.805243 -281.833642) (xy 287.77894 -281.792046)
			(xy 287.759649 -281.74677) (xy 287.747872 -281.698986) (xy 287.743912 -281.649932) (xy 287.405064 -281.649932)
			(xy 287.404569 -281.674539) (xy 287.396674 -281.723116) (xy 287.38109 -281.769797) (xy 287.358219 -281.813374)
			(xy 287.328654 -281.852718) (xy 287.293161 -281.88681) (xy 287.252658 -281.914766) (xy 287.208196 -281.935864)
			(xy 287.160925 -281.949556) (xy 287.11207 -281.955488) (xy 287.062895 -281.953507) (xy 287.014676 -281.943663)
			(xy 286.96866 -281.926211) (xy 286.926039 -281.901604) (xy 286.887918 -281.870479) (xy 286.855283 -281.833642)
			(xy 286.82898 -281.792046) (xy 286.809689 -281.74677) (xy 286.797912 -281.698986) (xy 286.793952 -281.649932)
			(xy 286.455104 -281.649932) (xy 286.454609 -281.674539) (xy 286.446714 -281.723116) (xy 286.43113 -281.769797)
			(xy 286.408259 -281.813374) (xy 286.378694 -281.852718) (xy 286.343201 -281.88681) (xy 286.302698 -281.914766)
			(xy 286.258236 -281.935864) (xy 286.210965 -281.949556) (xy 286.16211 -281.955488) (xy 286.112935 -281.953507)
			(xy 286.064716 -281.943663) (xy 286.0187 -281.926211) (xy 285.976079 -281.901604) (xy 285.937958 -281.870479)
			(xy 285.905323 -281.833642) (xy 285.87902 -281.792046) (xy 285.859729 -281.74677) (xy 285.847952 -281.698986)
			(xy 285.843992 -281.649932) (xy 285.505144 -281.649932) (xy 285.504649 -281.674539) (xy 285.496754 -281.723116)
			(xy 285.48117 -281.769797) (xy 285.458299 -281.813374) (xy 285.428734 -281.852718) (xy 285.393241 -281.88681)
			(xy 285.352738 -281.914766) (xy 285.308276 -281.935864) (xy 285.261005 -281.949556) (xy 285.21215 -281.955488)
			(xy 285.162975 -281.953507) (xy 285.114756 -281.943663) (xy 285.06874 -281.926211) (xy 285.026119 -281.901604)
			(xy 284.987998 -281.870479) (xy 284.955363 -281.833642) (xy 284.92906 -281.792046) (xy 284.909769 -281.74677)
			(xy 284.897992 -281.698986) (xy 284.894032 -281.649932) (xy 284.555184 -281.649932) (xy 284.554689 -281.674539)
			(xy 284.546794 -281.723116) (xy 284.53121 -281.769797) (xy 284.508339 -281.813374) (xy 284.478774 -281.852718)
			(xy 284.443281 -281.88681) (xy 284.402778 -281.914766) (xy 284.358316 -281.935864) (xy 284.311045 -281.949556)
			(xy 284.26219 -281.955488) (xy 284.213015 -281.953507) (xy 284.164796 -281.943663) (xy 284.11878 -281.926211)
			(xy 284.076159 -281.901604) (xy 284.038038 -281.870479) (xy 284.005403 -281.833642) (xy 283.9791 -281.792046)
			(xy 283.959809 -281.74677) (xy 283.948032 -281.698986) (xy 283.944072 -281.649932) (xy 283.605224 -281.649932)
			(xy 283.604729 -281.674539) (xy 283.596834 -281.723116) (xy 283.58125 -281.769797) (xy 283.558379 -281.813374)
			(xy 283.528814 -281.852718) (xy 283.493321 -281.88681) (xy 283.452818 -281.914766) (xy 283.408356 -281.935864)
			(xy 283.361085 -281.949556) (xy 283.31223 -281.955488) (xy 283.263055 -281.953507) (xy 283.214836 -281.943663)
			(xy 283.16882 -281.926211) (xy 283.126199 -281.901604) (xy 283.088078 -281.870479) (xy 283.055443 -281.833642)
			(xy 283.02914 -281.792046) (xy 283.009849 -281.74677) (xy 282.998072 -281.698986) (xy 282.994112 -281.649932)
			(xy 282.65501 -281.649932) (xy 282.654515 -281.674539) (xy 282.64662 -281.723116) (xy 282.631036 -281.769797)
			(xy 282.608165 -281.813374) (xy 282.5786 -281.852718) (xy 282.543107 -281.88681) (xy 282.502604 -281.914766)
			(xy 282.458142 -281.935864) (xy 282.410871 -281.949556) (xy 282.362016 -281.955488) (xy 282.312841 -281.953507)
			(xy 282.264622 -281.943663) (xy 282.218606 -281.926211) (xy 282.175985 -281.901604) (xy 282.137864 -281.870479)
			(xy 282.105229 -281.833642) (xy 282.078926 -281.792046) (xy 282.059635 -281.74677) (xy 282.047858 -281.698986)
			(xy 282.043898 -281.649932) (xy 281.70505 -281.649932) (xy 281.704555 -281.674539) (xy 281.69666 -281.723116)
			(xy 281.681076 -281.769797) (xy 281.658205 -281.813374) (xy 281.62864 -281.852718) (xy 281.593147 -281.88681)
			(xy 281.552644 -281.914766) (xy 281.508182 -281.935864) (xy 281.460911 -281.949556) (xy 281.412056 -281.955488)
			(xy 281.362881 -281.953507) (xy 281.314662 -281.943663) (xy 281.268646 -281.926211) (xy 281.226025 -281.901604)
			(xy 281.187904 -281.870479) (xy 281.155269 -281.833642) (xy 281.128966 -281.792046) (xy 281.109675 -281.74677)
			(xy 281.097898 -281.698986) (xy 281.093938 -281.649932) (xy 280.75509 -281.649932) (xy 280.754595 -281.674539)
			(xy 280.7467 -281.723116) (xy 280.731116 -281.769797) (xy 280.708245 -281.813374) (xy 280.67868 -281.852718)
			(xy 280.643187 -281.88681) (xy 280.602684 -281.914766) (xy 280.558222 -281.935864) (xy 280.510951 -281.949556)
			(xy 280.462096 -281.955488) (xy 280.412921 -281.953507) (xy 280.364702 -281.943663) (xy 280.318686 -281.926211)
			(xy 280.276065 -281.901604) (xy 280.237944 -281.870479) (xy 280.205309 -281.833642) (xy 280.179006 -281.792046)
			(xy 280.159715 -281.74677) (xy 280.147938 -281.698986) (xy 280.143978 -281.649932) (xy 279.80513 -281.649932)
			(xy 279.804635 -281.674539) (xy 279.79674 -281.723116) (xy 279.781156 -281.769797) (xy 279.758285 -281.813374)
			(xy 279.72872 -281.852718) (xy 279.693227 -281.88681) (xy 279.652724 -281.914766) (xy 279.608262 -281.935864)
			(xy 279.560991 -281.949556) (xy 279.512136 -281.955488) (xy 279.462961 -281.953507) (xy 279.414742 -281.943663)
			(xy 279.368726 -281.926211) (xy 279.326105 -281.901604) (xy 279.287984 -281.870479) (xy 279.255349 -281.833642)
			(xy 279.229046 -281.792046) (xy 279.209755 -281.74677) (xy 279.197978 -281.698986) (xy 279.194018 -281.649932)
			(xy 278.855202 -281.649932) (xy 278.85565 -281.658198) (xy 278.85028 -281.707556) (xy 278.836994 -281.755394)
			(xy 278.816144 -281.800453) (xy 278.788278 -281.841546) (xy 278.754131 -281.877588) (xy 278.714603 -281.907631)
			(xy 278.670735 -281.930882) (xy 278.623683 -281.94673) (xy 278.574687 -281.954757) (xy 278.549862 -281.95524)
			(xy 278.535679 -281.955068) (xy 278.507439 -281.952393) (xy 278.493474 -281.949906) (xy 278.481028 -281.94762)
			(xy 278.457406 -281.954986) (xy 278.379936 -282.032456) (xy 278.37257 -282.056078) (xy 278.374856 -282.068524)
			(xy 278.377331 -282.08249) (xy 278.380004 -282.11073) (xy 278.38019 -282.124912) (xy 278.379668 -282.150167)
			(xy 278.371355 -282.199989) (xy 278.354954 -282.247763) (xy 278.330913 -282.292186) (xy 278.299889 -282.332046)
			(xy 278.262727 -282.366256) (xy 278.220441 -282.393882) (xy 278.174185 -282.414172) (xy 278.12522 -282.426572)
			(xy 278.074882 -282.430743) (xy 278.024544 -282.426572) (xy 277.975579 -282.414172) (xy 277.929323 -282.393882)
			(xy 277.887037 -282.366256) (xy 277.849875 -282.332046) (xy 277.818851 -282.292186) (xy 277.79481 -282.247763)
			(xy 277.778409 -282.199989) (xy 277.770096 -282.150167) (xy 277.769574 -282.124912) (xy 277.769753 -282.110729)
			(xy 277.772423 -282.082489) (xy 277.774908 -282.068524) (xy 277.777194 -282.056078) (xy 277.769828 -282.032456)
			(xy 277.692358 -281.954986) (xy 277.668736 -281.94762) (xy 277.65629 -281.949906) (xy 277.642324 -281.95238)
			(xy 277.614084 -281.955053) (xy 277.599902 -281.95524) (xy 277.585719 -281.955063) (xy 277.557479 -281.952391)
			(xy 277.543514 -281.949906) (xy 277.531068 -281.94762) (xy 277.507446 -281.954986) (xy 277.429976 -282.032456)
			(xy 277.42261 -282.056078) (xy 277.424896 -282.068524) (xy 277.427372 -282.08249) (xy 277.430044 -282.110729)
			(xy 277.43023 -282.124912) (xy 277.429708 -282.150167) (xy 277.421395 -282.199989) (xy 277.404994 -282.247763)
			(xy 277.380953 -282.292186) (xy 277.349929 -282.332046) (xy 277.312767 -282.366256) (xy 277.270481 -282.393882)
			(xy 277.224225 -282.414172) (xy 277.17526 -282.426572) (xy 277.124922 -282.430743) (xy 277.074584 -282.426572)
			(xy 277.025619 -282.414172) (xy 276.979363 -282.393882) (xy 276.937077 -282.366256) (xy 276.899915 -282.332046)
			(xy 276.868891 -282.292186) (xy 276.84485 -282.247763) (xy 276.828449 -282.199989) (xy 276.820136 -282.150167)
			(xy 276.819614 -282.124912) (xy 276.819792 -282.110729) (xy 276.822463 -282.082489) (xy 276.824948 -282.068524)
			(xy 276.827234 -282.056078) (xy 276.819868 -282.032202) (xy 276.742652 -281.954986) (xy 276.718522 -281.94762)
			(xy 276.70633 -281.949906) (xy 276.692302 -281.952398) (xy 276.663934 -281.955065) (xy 276.649688 -281.95524)
			(xy 276.635505 -281.955064) (xy 276.607265 -281.952392) (xy 276.5933 -281.949906) (xy 276.580854 -281.94762)
			(xy 276.557232 -281.954986) (xy 276.479762 -282.032456) (xy 276.472396 -282.056078) (xy 276.474682 -282.068524)
			(xy 276.477158 -282.08249) (xy 276.47983 -282.11073) (xy 276.480016 -282.124912) (xy 276.479509 -282.149732)
			(xy 276.471476 -282.198717) (xy 276.455625 -282.245758) (xy 276.432371 -282.289614) (xy 276.402329 -282.329131)
			(xy 276.36629 -282.363266) (xy 276.325203 -282.391122) (xy 276.28015 -282.411964) (xy 276.23232 -282.425242)
			(xy 276.182971 -282.430607) (xy 276.133404 -282.427918) (xy 276.084925 -282.417245) (xy 276.038812 -282.39887)
			(xy 275.996279 -282.373277) (xy 275.958446 -282.34114) (xy 275.926311 -282.303305) (xy 275.900721 -282.26077)
			(xy 275.882349 -282.214656) (xy 275.871679 -282.166176) (xy 275.868993 -282.116609) (xy 275.874362 -282.067261)
			(xy 275.887643 -282.019431) (xy 275.908488 -281.97438) (xy 275.936346 -281.933295) (xy 275.970484 -281.897257)
			(xy 276.010003 -281.867218) (xy 276.053861 -281.843967) (xy 276.100902 -281.828119) (xy 276.149888 -281.820089)
			(xy 276.174708 -281.819604) (xy 276.188891 -281.819779) (xy 276.217131 -281.822452) (xy 276.231096 -281.824938)
			(xy 276.243542 -281.827224) (xy 276.267164 -281.819858) (xy 276.344634 -281.742388) (xy 276.352 -281.718766)
			(xy 276.349714 -281.70632) (xy 276.347231 -281.692355) (xy 276.344563 -281.664115) (xy 276.34438 -281.649932)
			(xy 276.344561 -281.635749) (xy 276.34723 -281.607509) (xy 276.349714 -281.593544) (xy 276.352 -281.581098)
			(xy 276.344634 -281.557476) (xy 276.267164 -281.480006) (xy 276.243542 -281.47264) (xy 276.231096 -281.474926)
			(xy 276.21713 -281.477399) (xy 276.18889 -281.480073) (xy 276.174708 -281.48026) (xy 276.149446 -281.479864)
			(xy 276.099611 -281.471549) (xy 276.051824 -281.455145) (xy 276.007388 -281.431099) (xy 275.967517 -281.400067)
			(xy 275.933298 -281.362895) (xy 275.905663 -281.320598) (xy 275.885367 -281.27433) (xy 275.872964 -281.225352)
			(xy 275.868792 -281.175) (xy 275.530055 -281.175) (xy 275.529561 -281.199559) (xy 275.521666 -281.248136)
			(xy 275.506082 -281.294817) (xy 275.483211 -281.338394) (xy 275.453646 -281.377738) (xy 275.418153 -281.41183)
			(xy 275.37765 -281.439786) (xy 275.333188 -281.460884) (xy 275.285917 -281.474576) (xy 275.237062 -281.480508)
			(xy 275.187887 -281.478527) (xy 275.139668 -281.468683) (xy 275.093652 -281.451231) (xy 275.051031 -281.426624)
			(xy 275.01291 -281.395499) (xy 274.980275 -281.358662) (xy 274.953972 -281.317066) (xy 274.934681 -281.27179)
			(xy 274.922904 -281.224006) (xy 274.918944 -281.174952) (xy 274.580096 -281.174952) (xy 274.579601 -281.199559)
			(xy 274.571706 -281.248136) (xy 274.556122 -281.294817) (xy 274.533251 -281.338394) (xy 274.503686 -281.377738)
			(xy 274.468193 -281.41183) (xy 274.42769 -281.439786) (xy 274.383228 -281.460884) (xy 274.335957 -281.474576)
			(xy 274.287102 -281.480508) (xy 274.237927 -281.478527) (xy 274.189708 -281.468683) (xy 274.143692 -281.451231)
			(xy 274.101071 -281.426624) (xy 274.06295 -281.395499) (xy 274.030315 -281.358662) (xy 274.004012 -281.317066)
			(xy 273.984721 -281.27179) (xy 273.972944 -281.224006) (xy 273.968984 -281.174952) (xy 273.630136 -281.174952)
			(xy 273.629641 -281.199559) (xy 273.621746 -281.248136) (xy 273.606162 -281.294817) (xy 273.583291 -281.338394)
			(xy 273.553726 -281.377738) (xy 273.518233 -281.41183) (xy 273.47773 -281.439786) (xy 273.433268 -281.460884)
			(xy 273.385997 -281.474576) (xy 273.337142 -281.480508) (xy 273.287967 -281.478527) (xy 273.239748 -281.468683)
			(xy 273.193732 -281.451231) (xy 273.151111 -281.426624) (xy 273.11299 -281.395499) (xy 273.080355 -281.358662)
			(xy 273.054052 -281.317066) (xy 273.034761 -281.27179) (xy 273.022984 -281.224006) (xy 273.019024 -281.174952)
			(xy 272.680176 -281.174952) (xy 272.679681 -281.199559) (xy 272.671786 -281.248136) (xy 272.656202 -281.294817)
			(xy 272.633331 -281.338394) (xy 272.603766 -281.377738) (xy 272.568273 -281.41183) (xy 272.52777 -281.439786)
			(xy 272.483308 -281.460884) (xy 272.436037 -281.474576) (xy 272.387182 -281.480508) (xy 272.338007 -281.478527)
			(xy 272.289788 -281.468683) (xy 272.243772 -281.451231) (xy 272.201151 -281.426624) (xy 272.16303 -281.395499)
			(xy 272.130395 -281.358662) (xy 272.104092 -281.317066) (xy 272.084801 -281.27179) (xy 272.073024 -281.224006)
			(xy 272.069064 -281.174952) (xy 271.730216 -281.174952) (xy 271.729721 -281.199559) (xy 271.721826 -281.248136)
			(xy 271.706242 -281.294817) (xy 271.683371 -281.338394) (xy 271.653806 -281.377738) (xy 271.618313 -281.41183)
			(xy 271.57781 -281.439786) (xy 271.533348 -281.460884) (xy 271.486077 -281.474576) (xy 271.437222 -281.480508)
			(xy 271.388047 -281.478527) (xy 271.339828 -281.468683) (xy 271.293812 -281.451231) (xy 271.251191 -281.426624)
			(xy 271.21307 -281.395499) (xy 271.180435 -281.358662) (xy 271.154132 -281.317066) (xy 271.134841 -281.27179)
			(xy 271.123064 -281.224006) (xy 271.119104 -281.174952) (xy 270.780256 -281.174952) (xy 270.779761 -281.199559)
			(xy 270.771866 -281.248136) (xy 270.756282 -281.294817) (xy 270.733411 -281.338394) (xy 270.703846 -281.377738)
			(xy 270.668353 -281.41183) (xy 270.62785 -281.439786) (xy 270.583388 -281.460884) (xy 270.536117 -281.474576)
			(xy 270.487262 -281.480508) (xy 270.438087 -281.478527) (xy 270.389868 -281.468683) (xy 270.343852 -281.451231)
			(xy 270.301231 -281.426624) (xy 270.26311 -281.395499) (xy 270.230475 -281.358662) (xy 270.204172 -281.317066)
			(xy 270.184881 -281.27179) (xy 270.173104 -281.224006) (xy 270.169144 -281.174952) (xy 269.830042 -281.174952)
			(xy 269.829547 -281.199559) (xy 269.821652 -281.248136) (xy 269.806068 -281.294817) (xy 269.783197 -281.338394)
			(xy 269.753632 -281.377738) (xy 269.718139 -281.41183) (xy 269.677636 -281.439786) (xy 269.633174 -281.460884)
			(xy 269.585903 -281.474576) (xy 269.537048 -281.480508) (xy 269.487873 -281.478527) (xy 269.439654 -281.468683)
			(xy 269.393638 -281.451231) (xy 269.351017 -281.426624) (xy 269.312896 -281.395499) (xy 269.280261 -281.358662)
			(xy 269.253958 -281.317066) (xy 269.234667 -281.27179) (xy 269.22289 -281.224006) (xy 269.21893 -281.174952)
			(xy 268.880082 -281.174952) (xy 268.879587 -281.199559) (xy 268.871692 -281.248136) (xy 268.856108 -281.294817)
			(xy 268.833237 -281.338394) (xy 268.803672 -281.377738) (xy 268.768179 -281.41183) (xy 268.727676 -281.439786)
			(xy 268.683214 -281.460884) (xy 268.635943 -281.474576) (xy 268.587088 -281.480508) (xy 268.537913 -281.478527)
			(xy 268.489694 -281.468683) (xy 268.443678 -281.451231) (xy 268.401057 -281.426624) (xy 268.362936 -281.395499)
			(xy 268.330301 -281.358662) (xy 268.303998 -281.317066) (xy 268.284707 -281.27179) (xy 268.27293 -281.224006)
			(xy 268.26897 -281.174952) (xy 250.679151 -281.174952) (xy 250.731176 -281.188553) (xy 250.782505 -281.210365)
			(xy 250.830111 -281.239419) (xy 250.872979 -281.275094) (xy 250.910196 -281.316631) (xy 250.940969 -281.363144)
			(xy 250.964641 -281.413641) (xy 250.980709 -281.467048) (xy 250.988829 -281.522224) (xy 250.989338 -281.55011)
			(xy 250.988829 -281.577996) (xy 250.980709 -281.633172) (xy 250.964641 -281.686579) (xy 250.940969 -281.737076)
			(xy 250.910196 -281.783589) (xy 250.872979 -281.825126) (xy 250.868016 -281.829256) (xy 258.01142 -281.829256)
			(xy 258.015491 -281.773634) (xy 258.027617 -281.719197) (xy 258.04754 -281.667106) (xy 258.074836 -281.618471)
			(xy 258.108922 -281.574328) (xy 258.149071 -281.535619) (xy 258.194429 -281.503168) (xy 258.244029 -281.477667)
			(xy 258.296813 -281.45966) (xy 258.351656 -281.44953) (xy 258.40739 -281.447493) (xy 258.462827 -281.453593)
			(xy 258.516784 -281.467699) (xy 258.568113 -281.489511) (xy 258.615719 -281.518565) (xy 258.658587 -281.55424)
			(xy 258.695804 -281.595777) (xy 258.726577 -281.64229) (xy 258.750249 -281.692787) (xy 258.766317 -281.746194)
			(xy 258.774437 -281.80137) (xy 258.774946 -281.829256) (xy 259.496558 -281.829256) (xy 259.500629 -281.773634)
			(xy 259.512755 -281.719197) (xy 259.532678 -281.667106) (xy 259.559974 -281.618471) (xy 259.59406 -281.574328)
			(xy 259.634209 -281.535619) (xy 259.679567 -281.503168) (xy 259.729167 -281.477667) (xy 259.781951 -281.45966)
			(xy 259.836794 -281.44953) (xy 259.892528 -281.447493) (xy 259.947965 -281.453593) (xy 260.001922 -281.467699)
			(xy 260.053251 -281.489511) (xy 260.100857 -281.518565) (xy 260.143725 -281.55424) (xy 260.180942 -281.595777)
			(xy 260.211715 -281.64229) (xy 260.235387 -281.692787) (xy 260.251455 -281.746194) (xy 260.259575 -281.80137)
			(xy 260.260084 -281.829256) (xy 260.259575 -281.857142) (xy 260.251455 -281.912318) (xy 260.235387 -281.965725)
			(xy 260.211715 -282.016222) (xy 260.180942 -282.062735) (xy 260.143725 -282.104272) (xy 260.118923 -282.124912)
			(xy 268.26897 -282.124912) (xy 268.27293 -282.075858) (xy 268.284707 -282.028074) (xy 268.303998 -281.982798)
			(xy 268.330301 -281.941202) (xy 268.362936 -281.904365) (xy 268.401057 -281.87324) (xy 268.443678 -281.848633)
			(xy 268.489694 -281.831181) (xy 268.537913 -281.821337) (xy 268.587088 -281.819356) (xy 268.635943 -281.825288)
			(xy 268.683214 -281.83898) (xy 268.727676 -281.860078) (xy 268.768179 -281.888034) (xy 268.803672 -281.922126)
			(xy 268.833237 -281.96147) (xy 268.856108 -282.005047) (xy 268.871692 -282.051728) (xy 268.879587 -282.100305)
			(xy 268.880082 -282.124912) (xy 269.21893 -282.124912) (xy 269.22289 -282.075858) (xy 269.234667 -282.028074)
			(xy 269.253958 -281.982798) (xy 269.280261 -281.941202) (xy 269.312896 -281.904365) (xy 269.351017 -281.87324)
			(xy 269.393638 -281.848633) (xy 269.439654 -281.831181) (xy 269.487873 -281.821337) (xy 269.537048 -281.819356)
			(xy 269.585903 -281.825288) (xy 269.633174 -281.83898) (xy 269.677636 -281.860078) (xy 269.718139 -281.888034)
			(xy 269.753632 -281.922126) (xy 269.783197 -281.96147) (xy 269.806068 -282.005047) (xy 269.821652 -282.051728)
			(xy 269.829547 -282.100305) (xy 269.830042 -282.124912) (xy 270.169144 -282.124912) (xy 270.173104 -282.075858)
			(xy 270.184881 -282.028074) (xy 270.204172 -281.982798) (xy 270.230475 -281.941202) (xy 270.26311 -281.904365)
			(xy 270.301231 -281.87324) (xy 270.343852 -281.848633) (xy 270.389868 -281.831181) (xy 270.438087 -281.821337)
			(xy 270.487262 -281.819356) (xy 270.536117 -281.825288) (xy 270.583388 -281.83898) (xy 270.62785 -281.860078)
			(xy 270.668353 -281.888034) (xy 270.703846 -281.922126) (xy 270.733411 -281.96147) (xy 270.756282 -282.005047)
			(xy 270.771866 -282.051728) (xy 270.779761 -282.100305) (xy 270.780256 -282.124912) (xy 271.119104 -282.124912)
			(xy 271.123064 -282.075858) (xy 271.134841 -282.028074) (xy 271.154132 -281.982798) (xy 271.180435 -281.941202)
			(xy 271.21307 -281.904365) (xy 271.251191 -281.87324) (xy 271.293812 -281.848633) (xy 271.339828 -281.831181)
			(xy 271.388047 -281.821337) (xy 271.437222 -281.819356) (xy 271.486077 -281.825288) (xy 271.533348 -281.83898)
			(xy 271.57781 -281.860078) (xy 271.618313 -281.888034) (xy 271.653806 -281.922126) (xy 271.683371 -281.96147)
			(xy 271.706242 -282.005047) (xy 271.721826 -282.051728) (xy 271.729721 -282.100305) (xy 271.730216 -282.124912)
			(xy 272.069064 -282.124912) (xy 272.073024 -282.075858) (xy 272.084801 -282.028074) (xy 272.104092 -281.982798)
			(xy 272.130395 -281.941202) (xy 272.16303 -281.904365) (xy 272.201151 -281.87324) (xy 272.243772 -281.848633)
			(xy 272.289788 -281.831181) (xy 272.338007 -281.821337) (xy 272.387182 -281.819356) (xy 272.436037 -281.825288)
			(xy 272.483308 -281.83898) (xy 272.52777 -281.860078) (xy 272.568273 -281.888034) (xy 272.603766 -281.922126)
			(xy 272.633331 -281.96147) (xy 272.656202 -282.005047) (xy 272.671786 -282.051728) (xy 272.679681 -282.100305)
			(xy 272.680176 -282.124912) (xy 273.019024 -282.124912) (xy 273.022984 -282.075858) (xy 273.034761 -282.028074)
			(xy 273.054052 -281.982798) (xy 273.080355 -281.941202) (xy 273.11299 -281.904365) (xy 273.151111 -281.87324)
			(xy 273.193732 -281.848633) (xy 273.239748 -281.831181) (xy 273.287967 -281.821337) (xy 273.337142 -281.819356)
			(xy 273.385997 -281.825288) (xy 273.433268 -281.83898) (xy 273.47773 -281.860078) (xy 273.518233 -281.888034)
			(xy 273.553726 -281.922126) (xy 273.583291 -281.96147) (xy 273.606162 -282.005047) (xy 273.621746 -282.051728)
			(xy 273.629641 -282.100305) (xy 273.630136 -282.124912) (xy 273.968984 -282.124912) (xy 273.972944 -282.075858)
			(xy 273.984721 -282.028074) (xy 274.004012 -281.982798) (xy 274.030315 -281.941202) (xy 274.06295 -281.904365)
			(xy 274.101071 -281.87324) (xy 274.143692 -281.848633) (xy 274.189708 -281.831181) (xy 274.237927 -281.821337)
			(xy 274.287102 -281.819356) (xy 274.335957 -281.825288) (xy 274.383228 -281.83898) (xy 274.42769 -281.860078)
			(xy 274.468193 -281.888034) (xy 274.503686 -281.922126) (xy 274.533251 -281.96147) (xy 274.556122 -282.005047)
			(xy 274.571706 -282.051728) (xy 274.579601 -282.100305) (xy 274.580096 -282.124912) (xy 274.918944 -282.124912)
			(xy 274.922904 -282.075858) (xy 274.934681 -282.028074) (xy 274.953972 -281.982798) (xy 274.980275 -281.941202)
			(xy 275.01291 -281.904365) (xy 275.051031 -281.87324) (xy 275.093652 -281.848633) (xy 275.139668 -281.831181)
			(xy 275.187887 -281.821337) (xy 275.237062 -281.819356) (xy 275.285917 -281.825288) (xy 275.333188 -281.83898)
			(xy 275.37765 -281.860078) (xy 275.418153 -281.888034) (xy 275.453646 -281.922126) (xy 275.483211 -281.96147)
			(xy 275.506082 -282.005047) (xy 275.521666 -282.051728) (xy 275.529561 -282.100305) (xy 275.530056 -282.124912)
			(xy 275.529561 -282.149519) (xy 275.521666 -282.198096) (xy 275.506082 -282.244777) (xy 275.483211 -282.288354)
			(xy 275.453646 -282.327698) (xy 275.418153 -282.36179) (xy 275.37765 -282.389746) (xy 275.333188 -282.410844)
			(xy 275.285917 -282.424536) (xy 275.237062 -282.430468) (xy 275.187887 -282.428487) (xy 275.139668 -282.418643)
			(xy 275.093652 -282.401191) (xy 275.051031 -282.376584) (xy 275.01291 -282.345459) (xy 274.980275 -282.308622)
			(xy 274.953972 -282.267026) (xy 274.934681 -282.22175) (xy 274.922904 -282.173966) (xy 274.918944 -282.124912)
			(xy 274.580096 -282.124912) (xy 274.579601 -282.149519) (xy 274.571706 -282.198096) (xy 274.556122 -282.244777)
			(xy 274.533251 -282.288354) (xy 274.503686 -282.327698) (xy 274.468193 -282.36179) (xy 274.42769 -282.389746)
			(xy 274.383228 -282.410844) (xy 274.335957 -282.424536) (xy 274.287102 -282.430468) (xy 274.237927 -282.428487)
			(xy 274.189708 -282.418643) (xy 274.143692 -282.401191) (xy 274.101071 -282.376584) (xy 274.06295 -282.345459)
			(xy 274.030315 -282.308622) (xy 274.004012 -282.267026) (xy 273.984721 -282.22175) (xy 273.972944 -282.173966)
			(xy 273.968984 -282.124912) (xy 273.630136 -282.124912) (xy 273.629641 -282.149519) (xy 273.621746 -282.198096)
			(xy 273.606162 -282.244777) (xy 273.583291 -282.288354) (xy 273.553726 -282.327698) (xy 273.518233 -282.36179)
			(xy 273.47773 -282.389746) (xy 273.433268 -282.410844) (xy 273.385997 -282.424536) (xy 273.337142 -282.430468)
			(xy 273.287967 -282.428487) (xy 273.239748 -282.418643) (xy 273.193732 -282.401191) (xy 273.151111 -282.376584)
			(xy 273.11299 -282.345459) (xy 273.080355 -282.308622) (xy 273.054052 -282.267026) (xy 273.034761 -282.22175)
			(xy 273.022984 -282.173966) (xy 273.019024 -282.124912) (xy 272.680176 -282.124912) (xy 272.679681 -282.149519)
			(xy 272.671786 -282.198096) (xy 272.656202 -282.244777) (xy 272.633331 -282.288354) (xy 272.603766 -282.327698)
			(xy 272.568273 -282.36179) (xy 272.52777 -282.389746) (xy 272.483308 -282.410844) (xy 272.436037 -282.424536)
			(xy 272.387182 -282.430468) (xy 272.338007 -282.428487) (xy 272.289788 -282.418643) (xy 272.243772 -282.401191)
			(xy 272.201151 -282.376584) (xy 272.16303 -282.345459) (xy 272.130395 -282.308622) (xy 272.104092 -282.267026)
			(xy 272.084801 -282.22175) (xy 272.073024 -282.173966) (xy 272.069064 -282.124912) (xy 271.730216 -282.124912)
			(xy 271.729721 -282.149519) (xy 271.721826 -282.198096) (xy 271.706242 -282.244777) (xy 271.683371 -282.288354)
			(xy 271.653806 -282.327698) (xy 271.618313 -282.36179) (xy 271.57781 -282.389746) (xy 271.533348 -282.410844)
			(xy 271.486077 -282.424536) (xy 271.437222 -282.430468) (xy 271.388047 -282.428487) (xy 271.339828 -282.418643)
			(xy 271.293812 -282.401191) (xy 271.251191 -282.376584) (xy 271.21307 -282.345459) (xy 271.180435 -282.308622)
			(xy 271.154132 -282.267026) (xy 271.134841 -282.22175) (xy 271.123064 -282.173966) (xy 271.119104 -282.124912)
			(xy 270.780256 -282.124912) (xy 270.779761 -282.149519) (xy 270.771866 -282.198096) (xy 270.756282 -282.244777)
			(xy 270.733411 -282.288354) (xy 270.703846 -282.327698) (xy 270.668353 -282.36179) (xy 270.62785 -282.389746)
			(xy 270.583388 -282.410844) (xy 270.536117 -282.424536) (xy 270.487262 -282.430468) (xy 270.438087 -282.428487)
			(xy 270.389868 -282.418643) (xy 270.343852 -282.401191) (xy 270.301231 -282.376584) (xy 270.26311 -282.345459)
			(xy 270.230475 -282.308622) (xy 270.204172 -282.267026) (xy 270.184881 -282.22175) (xy 270.173104 -282.173966)
			(xy 270.169144 -282.124912) (xy 269.830042 -282.124912) (xy 269.829547 -282.149519) (xy 269.821652 -282.198096)
			(xy 269.806068 -282.244777) (xy 269.783197 -282.288354) (xy 269.753632 -282.327698) (xy 269.718139 -282.36179)
			(xy 269.677636 -282.389746) (xy 269.633174 -282.410844) (xy 269.585903 -282.424536) (xy 269.537048 -282.430468)
			(xy 269.487873 -282.428487) (xy 269.439654 -282.418643) (xy 269.393638 -282.401191) (xy 269.351017 -282.376584)
			(xy 269.312896 -282.345459) (xy 269.280261 -282.308622) (xy 269.253958 -282.267026) (xy 269.234667 -282.22175)
			(xy 269.22289 -282.173966) (xy 269.21893 -282.124912) (xy 268.880082 -282.124912) (xy 268.879587 -282.149519)
			(xy 268.871692 -282.198096) (xy 268.856108 -282.244777) (xy 268.833237 -282.288354) (xy 268.803672 -282.327698)
			(xy 268.768179 -282.36179) (xy 268.727676 -282.389746) (xy 268.683214 -282.410844) (xy 268.635943 -282.424536)
			(xy 268.587088 -282.430468) (xy 268.537913 -282.428487) (xy 268.489694 -282.418643) (xy 268.443678 -282.401191)
			(xy 268.401057 -282.376584) (xy 268.362936 -282.345459) (xy 268.330301 -282.308622) (xy 268.303998 -282.267026)
			(xy 268.284707 -282.22175) (xy 268.27293 -282.173966) (xy 268.26897 -282.124912) (xy 260.118923 -282.124912)
			(xy 260.100857 -282.139947) (xy 260.053251 -282.169001) (xy 260.001922 -282.190813) (xy 259.947965 -282.204919)
			(xy 259.892528 -282.211019) (xy 259.836794 -282.208982) (xy 259.781951 -282.198852) (xy 259.729167 -282.180845)
			(xy 259.679567 -282.155344) (xy 259.634209 -282.122893) (xy 259.59406 -282.084184) (xy 259.559974 -282.040041)
			(xy 259.532678 -281.991406) (xy 259.512755 -281.939315) (xy 259.500629 -281.884878) (xy 259.496558 -281.829256)
			(xy 258.774946 -281.829256) (xy 258.774437 -281.857142) (xy 258.766317 -281.912318) (xy 258.750249 -281.965725)
			(xy 258.726577 -282.016222) (xy 258.695804 -282.062735) (xy 258.658587 -282.104272) (xy 258.615719 -282.139947)
			(xy 258.568113 -282.169001) (xy 258.516784 -282.190813) (xy 258.462827 -282.204919) (xy 258.40739 -282.211019)
			(xy 258.351656 -282.208982) (xy 258.296813 -282.198852) (xy 258.244029 -282.180845) (xy 258.194429 -282.155344)
			(xy 258.149071 -282.122893) (xy 258.108922 -282.084184) (xy 258.074836 -282.040041) (xy 258.04754 -281.991406)
			(xy 258.027617 -281.939315) (xy 258.015491 -281.884878) (xy 258.01142 -281.829256) (xy 250.868016 -281.829256)
			(xy 250.830111 -281.860801) (xy 250.782505 -281.889855) (xy 250.731176 -281.911667) (xy 250.677219 -281.925773)
			(xy 250.621782 -281.931873) (xy 250.566048 -281.929836) (xy 250.511205 -281.919706) (xy 250.458421 -281.901699)
			(xy 250.408821 -281.876198) (xy 250.363463 -281.843747) (xy 250.323314 -281.805038) (xy 250.289228 -281.760895)
			(xy 250.261932 -281.71226) (xy 250.242009 -281.660169) (xy 250.229883 -281.605732) (xy 250.225812 -281.55011)
			(xy 249.737118 -281.55011) (xy 249.737118 -283.131514) (xy 258.01142 -283.131514) (xy 258.015491 -283.075892)
			(xy 258.027617 -283.021455) (xy 258.04754 -282.969364) (xy 258.074836 -282.920729) (xy 258.108922 -282.876586)
			(xy 258.149071 -282.837877) (xy 258.194429 -282.805426) (xy 258.244029 -282.779925) (xy 258.296813 -282.761918)
			(xy 258.351656 -282.751788) (xy 258.40739 -282.749751) (xy 258.462827 -282.755851) (xy 258.516784 -282.769957)
			(xy 258.568113 -282.791769) (xy 258.615719 -282.820823) (xy 258.658587 -282.856498) (xy 258.695804 -282.898035)
			(xy 258.726577 -282.944548) (xy 258.750249 -282.995045) (xy 258.766317 -283.048452) (xy 258.774437 -283.103628)
			(xy 258.774946 -283.131514) (xy 259.486906 -283.131514) (xy 259.490977 -283.075892) (xy 259.503103 -283.021455)
			(xy 259.523026 -282.969364) (xy 259.550322 -282.920729) (xy 259.584408 -282.876586) (xy 259.624557 -282.837877)
			(xy 259.669915 -282.805426) (xy 259.719515 -282.779925) (xy 259.772299 -282.761918) (xy 259.827142 -282.751788)
			(xy 259.882876 -282.749751) (xy 259.938313 -282.755851) (xy 259.99227 -282.769957) (xy 260.043599 -282.791769)
			(xy 260.091205 -282.820823) (xy 260.134073 -282.856498) (xy 260.17129 -282.898035) (xy 260.202063 -282.944548)
			(xy 260.225735 -282.995045) (xy 260.241803 -283.048452) (xy 260.249923 -283.103628) (xy 260.250432 -283.131514)
			(xy 260.375906 -283.131514) (xy 260.379977 -283.075892) (xy 260.392103 -283.021455) (xy 260.412026 -282.969364)
			(xy 260.439322 -282.920729) (xy 260.473408 -282.876586) (xy 260.513557 -282.837877) (xy 260.558915 -282.805426)
			(xy 260.608515 -282.779925) (xy 260.661299 -282.761918) (xy 260.716142 -282.751788) (xy 260.771876 -282.749751)
			(xy 260.827313 -282.755851) (xy 260.88127 -282.769957) (xy 260.932599 -282.791769) (xy 260.980205 -282.820823)
			(xy 261.023073 -282.856498) (xy 261.06029 -282.898035) (xy 261.091063 -282.944548) (xy 261.114735 -282.995045)
			(xy 261.130803 -283.048452) (xy 261.138923 -283.103628) (xy 261.139432 -283.131514) (xy 261.138923 -283.1594)
			(xy 261.130803 -283.214576) (xy 261.114735 -283.267983) (xy 261.091063 -283.31848) (xy 261.06029 -283.364993)
			(xy 261.023073 -283.40653) (xy 260.980205 -283.442205) (xy 260.932599 -283.471259) (xy 260.88127 -283.493071)
			(xy 260.827313 -283.507177) (xy 260.771876 -283.513277) (xy 260.716142 -283.51124) (xy 260.661299 -283.50111)
			(xy 260.608515 -283.483103) (xy 260.558915 -283.457602) (xy 260.513557 -283.425151) (xy 260.473408 -283.386442)
			(xy 260.439322 -283.342299) (xy 260.412026 -283.293664) (xy 260.392103 -283.241573) (xy 260.379977 -283.187136)
			(xy 260.375906 -283.131514) (xy 260.250432 -283.131514) (xy 260.249923 -283.1594) (xy 260.241803 -283.214576)
			(xy 260.225735 -283.267983) (xy 260.202063 -283.31848) (xy 260.17129 -283.364993) (xy 260.134073 -283.40653)
			(xy 260.091205 -283.442205) (xy 260.043599 -283.471259) (xy 259.99227 -283.493071) (xy 259.938313 -283.507177)
			(xy 259.882876 -283.513277) (xy 259.827142 -283.51124) (xy 259.772299 -283.50111) (xy 259.719515 -283.483103)
			(xy 259.669915 -283.457602) (xy 259.624557 -283.425151) (xy 259.584408 -283.386442) (xy 259.550322 -283.342299)
			(xy 259.523026 -283.293664) (xy 259.503103 -283.241573) (xy 259.490977 -283.187136) (xy 259.486906 -283.131514)
			(xy 258.774946 -283.131514) (xy 258.774437 -283.1594) (xy 258.766317 -283.214576) (xy 258.750249 -283.267983)
			(xy 258.726577 -283.31848) (xy 258.695804 -283.364993) (xy 258.658587 -283.40653) (xy 258.615719 -283.442205)
			(xy 258.568113 -283.471259) (xy 258.516784 -283.493071) (xy 258.462827 -283.507177) (xy 258.40739 -283.513277)
			(xy 258.351656 -283.51124) (xy 258.296813 -283.50111) (xy 258.244029 -283.483103) (xy 258.194429 -283.457602)
			(xy 258.149071 -283.425151) (xy 258.108922 -283.386442) (xy 258.074836 -283.342299) (xy 258.04754 -283.293664)
			(xy 258.027617 -283.241573) (xy 258.015491 -283.187136) (xy 258.01142 -283.131514) (xy 249.737118 -283.131514)
			(xy 249.737118 -283.893514) (xy 263.537954 -283.893514) (xy 263.53852 -283.864133) (xy 263.547548 -283.806068)
			(xy 263.565376 -283.750075) (xy 263.591583 -283.69748) (xy 263.625547 -283.649528) (xy 263.666466 -283.607354)
			(xy 263.689592 -283.589222) (xy 263.69899 -283.581856) (xy 263.709404 -283.561282) (xy 263.710928 -283.457396)
			(xy 263.701022 -283.436314) (xy 263.691878 -283.428948) (xy 263.670018 -283.410756) (xy 263.63148 -283.368933)
			(xy 263.599575 -283.321855) (xy 263.57501 -283.270563) (xy 263.558329 -283.216193) (xy 263.549902 -283.15995)
			(xy 263.549384 -283.131514) (xy 263.54987 -283.104263) (xy 263.557626 -283.050315) (xy 263.572981 -282.99802)
			(xy 263.595623 -282.948443) (xy 263.625089 -282.902593) (xy 263.66078 -282.861402) (xy 263.701971 -282.825711)
			(xy 263.747821 -282.796245) (xy 263.797398 -282.773603) (xy 263.849693 -282.758248) (xy 263.903641 -282.750492)
			(xy 263.958143 -282.750492) (xy 264.012091 -282.758248) (xy 264.064386 -282.773603) (xy 264.113963 -282.796245)
			(xy 264.159813 -282.825711) (xy 264.201004 -282.861402) (xy 264.236695 -282.902593) (xy 264.266161 -282.948443)
			(xy 264.288803 -282.99802) (xy 264.304158 -283.050315) (xy 264.307689 -283.074872) (xy 268.26897 -283.074872)
			(xy 268.27293 -283.025818) (xy 268.284707 -282.978034) (xy 268.303998 -282.932758) (xy 268.330301 -282.891162)
			(xy 268.362936 -282.854325) (xy 268.401057 -282.8232) (xy 268.443678 -282.798593) (xy 268.489694 -282.781141)
			(xy 268.537913 -282.771297) (xy 268.587088 -282.769316) (xy 268.635943 -282.775248) (xy 268.683214 -282.78894)
			(xy 268.727676 -282.810038) (xy 268.768179 -282.837994) (xy 268.803672 -282.872086) (xy 268.833237 -282.91143)
			(xy 268.856108 -282.955007) (xy 268.871692 -283.001688) (xy 268.879587 -283.050265) (xy 268.880082 -283.074872)
			(xy 269.21893 -283.074872) (xy 269.22289 -283.025818) (xy 269.234667 -282.978034) (xy 269.253958 -282.932758)
			(xy 269.280261 -282.891162) (xy 269.312896 -282.854325) (xy 269.351017 -282.8232) (xy 269.393638 -282.798593)
			(xy 269.439654 -282.781141) (xy 269.487873 -282.771297) (xy 269.537048 -282.769316) (xy 269.585903 -282.775248)
			(xy 269.633174 -282.78894) (xy 269.677636 -282.810038) (xy 269.718139 -282.837994) (xy 269.753632 -282.872086)
			(xy 269.783197 -282.91143) (xy 269.806068 -282.955007) (xy 269.821652 -283.001688) (xy 269.829547 -283.050265)
			(xy 269.830042 -283.074872) (xy 270.169144 -283.074872) (xy 270.173104 -283.025818) (xy 270.184881 -282.978034)
			(xy 270.204172 -282.932758) (xy 270.230475 -282.891162) (xy 270.26311 -282.854325) (xy 270.301231 -282.8232)
			(xy 270.343852 -282.798593) (xy 270.389868 -282.781141) (xy 270.438087 -282.771297) (xy 270.487262 -282.769316)
			(xy 270.536117 -282.775248) (xy 270.583388 -282.78894) (xy 270.62785 -282.810038) (xy 270.668353 -282.837994)
			(xy 270.703846 -282.872086) (xy 270.733411 -282.91143) (xy 270.756282 -282.955007) (xy 270.771866 -283.001688)
			(xy 270.779761 -283.050265) (xy 270.780256 -283.074872) (xy 271.119104 -283.074872) (xy 271.123064 -283.025818)
			(xy 271.134841 -282.978034) (xy 271.154132 -282.932758) (xy 271.180435 -282.891162) (xy 271.21307 -282.854325)
			(xy 271.251191 -282.8232) (xy 271.293812 -282.798593) (xy 271.339828 -282.781141) (xy 271.388047 -282.771297)
			(xy 271.437222 -282.769316) (xy 271.486077 -282.775248) (xy 271.533348 -282.78894) (xy 271.57781 -282.810038)
			(xy 271.618313 -282.837994) (xy 271.653806 -282.872086) (xy 271.683371 -282.91143) (xy 271.706242 -282.955007)
			(xy 271.721826 -283.001688) (xy 271.729721 -283.050265) (xy 271.730216 -283.074872) (xy 272.069064 -283.074872)
			(xy 272.073024 -283.025818) (xy 272.084801 -282.978034) (xy 272.104092 -282.932758) (xy 272.130395 -282.891162)
			(xy 272.16303 -282.854325) (xy 272.201151 -282.8232) (xy 272.243772 -282.798593) (xy 272.289788 -282.781141)
			(xy 272.338007 -282.771297) (xy 272.387182 -282.769316) (xy 272.436037 -282.775248) (xy 272.483308 -282.78894)
			(xy 272.52777 -282.810038) (xy 272.568273 -282.837994) (xy 272.603766 -282.872086) (xy 272.633331 -282.91143)
			(xy 272.656202 -282.955007) (xy 272.671786 -283.001688) (xy 272.679681 -283.050265) (xy 272.680176 -283.074872)
			(xy 273.019024 -283.074872) (xy 273.022984 -283.025818) (xy 273.034761 -282.978034) (xy 273.054052 -282.932758)
			(xy 273.080355 -282.891162) (xy 273.11299 -282.854325) (xy 273.151111 -282.8232) (xy 273.193732 -282.798593)
			(xy 273.239748 -282.781141) (xy 273.287967 -282.771297) (xy 273.337142 -282.769316) (xy 273.385997 -282.775248)
			(xy 273.433268 -282.78894) (xy 273.47773 -282.810038) (xy 273.518233 -282.837994) (xy 273.553726 -282.872086)
			(xy 273.583291 -282.91143) (xy 273.606162 -282.955007) (xy 273.621746 -283.001688) (xy 273.629641 -283.050265)
			(xy 273.630136 -283.074872) (xy 273.968984 -283.074872) (xy 273.972944 -283.025818) (xy 273.984721 -282.978034)
			(xy 274.004012 -282.932758) (xy 274.030315 -282.891162) (xy 274.06295 -282.854325) (xy 274.101071 -282.8232)
			(xy 274.143692 -282.798593) (xy 274.189708 -282.781141) (xy 274.237927 -282.771297) (xy 274.287102 -282.769316)
			(xy 274.335957 -282.775248) (xy 274.383228 -282.78894) (xy 274.42769 -282.810038) (xy 274.468193 -282.837994)
			(xy 274.503686 -282.872086) (xy 274.533251 -282.91143) (xy 274.556122 -282.955007) (xy 274.571706 -283.001688)
			(xy 274.579601 -283.050265) (xy 274.580096 -283.074872) (xy 274.918944 -283.074872) (xy 274.922904 -283.025818)
			(xy 274.934681 -282.978034) (xy 274.953972 -282.932758) (xy 274.980275 -282.891162) (xy 275.01291 -282.854325)
			(xy 275.051031 -282.8232) (xy 275.093652 -282.798593) (xy 275.139668 -282.781141) (xy 275.187887 -282.771297)
			(xy 275.237062 -282.769316) (xy 275.285917 -282.775248) (xy 275.333188 -282.78894) (xy 275.37765 -282.810038)
			(xy 275.418153 -282.837994) (xy 275.453646 -282.872086) (xy 275.483211 -282.91143) (xy 275.506082 -282.955007)
			(xy 275.521666 -283.001688) (xy 275.529561 -283.050265) (xy 275.530056 -283.074872) (xy 275.868904 -283.074872)
			(xy 275.872864 -283.025818) (xy 275.884641 -282.978034) (xy 275.903932 -282.932758) (xy 275.930235 -282.891162)
			(xy 275.96287 -282.854325) (xy 276.000991 -282.8232) (xy 276.043612 -282.798593) (xy 276.089628 -282.781141)
			(xy 276.137847 -282.771297) (xy 276.187022 -282.769316) (xy 276.235877 -282.775248) (xy 276.283148 -282.78894)
			(xy 276.32761 -282.810038) (xy 276.368113 -282.837994) (xy 276.403606 -282.872086) (xy 276.433171 -282.91143)
			(xy 276.456042 -282.955007) (xy 276.471626 -283.001688) (xy 276.479521 -283.050265) (xy 276.480016 -283.074872)
			(xy 276.819118 -283.074872) (xy 276.823078 -283.025818) (xy 276.834855 -282.978034) (xy 276.854146 -282.932758)
			(xy 276.880449 -282.891162) (xy 276.913084 -282.854325) (xy 276.951205 -282.8232) (xy 276.993826 -282.798593)
			(xy 277.039842 -282.781141) (xy 277.088061 -282.771297) (xy 277.137236 -282.769316) (xy 277.186091 -282.775248)
			(xy 277.233362 -282.78894) (xy 277.277824 -282.810038) (xy 277.318327 -282.837994) (xy 277.35382 -282.872086)
			(xy 277.383385 -282.91143) (xy 277.406256 -282.955007) (xy 277.42184 -283.001688) (xy 277.429735 -283.050265)
			(xy 277.43023 -283.074872) (xy 277.769078 -283.074872) (xy 277.773038 -283.025818) (xy 277.784815 -282.978034)
			(xy 277.804106 -282.932758) (xy 277.830409 -282.891162) (xy 277.863044 -282.854325) (xy 277.901165 -282.8232)
			(xy 277.943786 -282.798593) (xy 277.989802 -282.781141) (xy 278.038021 -282.771297) (xy 278.087196 -282.769316)
			(xy 278.136051 -282.775248) (xy 278.183322 -282.78894) (xy 278.227784 -282.810038) (xy 278.268287 -282.837994)
			(xy 278.30378 -282.872086) (xy 278.333345 -282.91143) (xy 278.356216 -282.955007) (xy 278.3718 -283.001688)
			(xy 278.379695 -283.050265) (xy 278.38019 -283.074872) (xy 278.719038 -283.074872) (xy 278.722998 -283.025818)
			(xy 278.734775 -282.978034) (xy 278.754066 -282.932758) (xy 278.780369 -282.891162) (xy 278.813004 -282.854325)
			(xy 278.851125 -282.8232) (xy 278.893746 -282.798593) (xy 278.939762 -282.781141) (xy 278.987981 -282.771297)
			(xy 279.037156 -282.769316) (xy 279.086011 -282.775248) (xy 279.133282 -282.78894) (xy 279.177744 -282.810038)
			(xy 279.218247 -282.837994) (xy 279.25374 -282.872086) (xy 279.283305 -282.91143) (xy 279.306176 -282.955007)
			(xy 279.32176 -283.001688) (xy 279.329655 -283.050265) (xy 279.33015 -283.074872) (xy 279.668998 -283.074872)
			(xy 279.672958 -283.025818) (xy 279.684735 -282.978034) (xy 279.704026 -282.932758) (xy 279.730329 -282.891162)
			(xy 279.762964 -282.854325) (xy 279.801085 -282.8232) (xy 279.843706 -282.798593) (xy 279.889722 -282.781141)
			(xy 279.937941 -282.771297) (xy 279.987116 -282.769316) (xy 280.035971 -282.775248) (xy 280.083242 -282.78894)
			(xy 280.127704 -282.810038) (xy 280.168207 -282.837994) (xy 280.2037 -282.872086) (xy 280.233265 -282.91143)
			(xy 280.256136 -282.955007) (xy 280.27172 -283.001688) (xy 280.279615 -283.050265) (xy 280.28011 -283.074872)
			(xy 280.618958 -283.074872) (xy 280.622918 -283.025818) (xy 280.634695 -282.978034) (xy 280.653986 -282.932758)
			(xy 280.680289 -282.891162) (xy 280.712924 -282.854325) (xy 280.751045 -282.8232) (xy 280.793666 -282.798593)
			(xy 280.839682 -282.781141) (xy 280.887901 -282.771297) (xy 280.937076 -282.769316) (xy 280.985931 -282.775248)
			(xy 281.033202 -282.78894) (xy 281.077664 -282.810038) (xy 281.118167 -282.837994) (xy 281.15366 -282.872086)
			(xy 281.183225 -282.91143) (xy 281.206096 -282.955007) (xy 281.22168 -283.001688) (xy 281.229575 -283.050265)
			(xy 281.23007 -283.074872) (xy 281.568918 -283.074872) (xy 281.572878 -283.025818) (xy 281.584655 -282.978034)
			(xy 281.603946 -282.932758) (xy 281.630249 -282.891162) (xy 281.662884 -282.854325) (xy 281.701005 -282.8232)
			(xy 281.743626 -282.798593) (xy 281.789642 -282.781141) (xy 281.837861 -282.771297) (xy 281.887036 -282.769316)
			(xy 281.935891 -282.775248) (xy 281.983162 -282.78894) (xy 282.027624 -282.810038) (xy 282.068127 -282.837994)
			(xy 282.10362 -282.872086) (xy 282.133185 -282.91143) (xy 282.156056 -282.955007) (xy 282.17164 -283.001688)
			(xy 282.179535 -283.050265) (xy 282.18003 -283.074872) (xy 282.519132 -283.074872) (xy 282.523092 -283.025818)
			(xy 282.534869 -282.978034) (xy 282.55416 -282.932758) (xy 282.580463 -282.891162) (xy 282.613098 -282.854325)
			(xy 282.651219 -282.8232) (xy 282.69384 -282.798593) (xy 282.739856 -282.781141) (xy 282.788075 -282.771297)
			(xy 282.83725 -282.769316) (xy 282.886105 -282.775248) (xy 282.933376 -282.78894) (xy 282.977838 -282.810038)
			(xy 283.018341 -282.837994) (xy 283.053834 -282.872086) (xy 283.083399 -282.91143) (xy 283.10627 -282.955007)
			(xy 283.121854 -283.001688) (xy 283.129749 -283.050265) (xy 283.130244 -283.074872) (xy 283.469092 -283.074872)
			(xy 283.473052 -283.025818) (xy 283.484829 -282.978034) (xy 283.50412 -282.932758) (xy 283.530423 -282.891162)
			(xy 283.563058 -282.854325) (xy 283.601179 -282.8232) (xy 283.6438 -282.798593) (xy 283.689816 -282.781141)
			(xy 283.738035 -282.771297) (xy 283.78721 -282.769316) (xy 283.836065 -282.775248) (xy 283.883336 -282.78894)
			(xy 283.927798 -282.810038) (xy 283.968301 -282.837994) (xy 284.003794 -282.872086) (xy 284.033359 -282.91143)
			(xy 284.05623 -282.955007) (xy 284.071814 -283.001688) (xy 284.079709 -283.050265) (xy 284.080204 -283.074872)
			(xy 284.419052 -283.074872) (xy 284.423012 -283.025818) (xy 284.434789 -282.978034) (xy 284.45408 -282.932758)
			(xy 284.480383 -282.891162) (xy 284.513018 -282.854325) (xy 284.551139 -282.8232) (xy 284.59376 -282.798593)
			(xy 284.639776 -282.781141) (xy 284.687995 -282.771297) (xy 284.73717 -282.769316) (xy 284.786025 -282.775248)
			(xy 284.833296 -282.78894) (xy 284.877758 -282.810038) (xy 284.918261 -282.837994) (xy 284.953754 -282.872086)
			(xy 284.983319 -282.91143) (xy 285.00619 -282.955007) (xy 285.021774 -283.001688) (xy 285.029669 -283.050265)
			(xy 285.030164 -283.074872) (xy 285.369012 -283.074872) (xy 285.372972 -283.025818) (xy 285.384749 -282.978034)
			(xy 285.40404 -282.932758) (xy 285.430343 -282.891162) (xy 285.462978 -282.854325) (xy 285.501099 -282.8232)
			(xy 285.54372 -282.798593) (xy 285.589736 -282.781141) (xy 285.637955 -282.771297) (xy 285.68713 -282.769316)
			(xy 285.735985 -282.775248) (xy 285.783256 -282.78894) (xy 285.827718 -282.810038) (xy 285.868221 -282.837994)
			(xy 285.903714 -282.872086) (xy 285.933279 -282.91143) (xy 285.95615 -282.955007) (xy 285.971734 -283.001688)
			(xy 285.979629 -283.050265) (xy 285.979958 -283.066643) (xy 286.319052 -283.066643) (xy 286.324416 -283.017287)
			(xy 286.337694 -282.969449) (xy 286.358536 -282.92439) (xy 286.386394 -282.883296) (xy 286.420533 -282.84725)
			(xy 286.460053 -282.817202) (xy 286.503915 -282.793944) (xy 286.550961 -282.778088) (xy 286.599953 -282.770052)
			(xy 286.624776 -282.769564) (xy 286.638959 -282.769744) (xy 286.667199 -282.772414) (xy 286.681164 -282.774898)
			(xy 286.69361 -282.777184) (xy 286.717232 -282.769818) (xy 286.794702 -282.692348) (xy 286.802068 -282.668726)
			(xy 286.799782 -282.65628) (xy 286.797307 -282.642314) (xy 286.794634 -282.614074) (xy 286.794448 -282.599892)
			(xy 286.79497 -282.574637) (xy 286.803283 -282.524815) (xy 286.819684 -282.477041) (xy 286.843725 -282.432618)
			(xy 286.874749 -282.392758) (xy 286.911911 -282.358548) (xy 286.954197 -282.330922) (xy 287.000453 -282.310632)
			(xy 287.049418 -282.298232) (xy 287.099756 -282.294061) (xy 287.150094 -282.298232) (xy 287.199059 -282.310632)
			(xy 287.245315 -282.330922) (xy 287.287601 -282.358548) (xy 287.324763 -282.392758) (xy 287.355787 -282.432618)
			(xy 287.379828 -282.477041) (xy 287.396229 -282.524815) (xy 287.404542 -282.574637) (xy 287.405064 -282.599892)
			(xy 287.404887 -282.614075) (xy 287.402215 -282.642315) (xy 287.39973 -282.65628) (xy 287.397444 -282.668726)
			(xy 287.40481 -282.692348) (xy 287.48228 -282.769818) (xy 287.505902 -282.777184) (xy 287.518348 -282.774898)
			(xy 287.532313 -282.772419) (xy 287.560553 -282.769749) (xy 287.574736 -282.769564) (xy 287.599554 -282.770117)
			(xy 287.648535 -282.778153) (xy 287.69557 -282.794007) (xy 287.739421 -282.817262) (xy 287.778932 -282.847304)
			(xy 287.813062 -282.883343) (xy 287.840913 -282.924429) (xy 287.861749 -282.96948) (xy 287.875023 -283.017307)
			(xy 287.880384 -283.066653) (xy 287.879937 -283.074872) (xy 288.219146 -283.074872) (xy 288.223106 -283.025818)
			(xy 288.234883 -282.978034) (xy 288.254174 -282.932758) (xy 288.280477 -282.891162) (xy 288.313112 -282.854325)
			(xy 288.351233 -282.8232) (xy 288.393854 -282.798593) (xy 288.43987 -282.781141) (xy 288.488089 -282.771297)
			(xy 288.537264 -282.769316) (xy 288.586119 -282.775248) (xy 288.63339 -282.78894) (xy 288.677852 -282.810038)
			(xy 288.718355 -282.837994) (xy 288.753848 -282.872086) (xy 288.783413 -282.91143) (xy 288.806284 -282.955007)
			(xy 288.821868 -283.001688) (xy 288.829763 -283.050265) (xy 288.830258 -283.074872) (xy 289.169106 -283.074872)
			(xy 289.173066 -283.025818) (xy 289.184843 -282.978034) (xy 289.204134 -282.932758) (xy 289.230437 -282.891162)
			(xy 289.263072 -282.854325) (xy 289.301193 -282.8232) (xy 289.343814 -282.798593) (xy 289.38983 -282.781141)
			(xy 289.438049 -282.771297) (xy 289.487224 -282.769316) (xy 289.536079 -282.775248) (xy 289.58335 -282.78894)
			(xy 289.627812 -282.810038) (xy 289.668315 -282.837994) (xy 289.703808 -282.872086) (xy 289.733373 -282.91143)
			(xy 289.756244 -282.955007) (xy 289.771828 -283.001688) (xy 289.779723 -283.050265) (xy 289.780218 -283.074872)
			(xy 290.119066 -283.074872) (xy 290.123026 -283.025818) (xy 290.134803 -282.978034) (xy 290.154094 -282.932758)
			(xy 290.180397 -282.891162) (xy 290.213032 -282.854325) (xy 290.251153 -282.8232) (xy 290.293774 -282.798593)
			(xy 290.33979 -282.781141) (xy 290.388009 -282.771297) (xy 290.437184 -282.769316) (xy 290.486039 -282.775248)
			(xy 290.53331 -282.78894) (xy 290.577772 -282.810038) (xy 290.618275 -282.837994) (xy 290.653768 -282.872086)
			(xy 290.683333 -282.91143) (xy 290.706204 -282.955007) (xy 290.721788 -283.001688) (xy 290.729683 -283.050265)
			(xy 290.730178 -283.074872) (xy 292.018986 -283.074872) (xy 292.022946 -283.025818) (xy 292.034723 -282.978034)
			(xy 292.054014 -282.932758) (xy 292.080317 -282.891162) (xy 292.112952 -282.854325) (xy 292.151073 -282.8232)
			(xy 292.193694 -282.798593) (xy 292.23971 -282.781141) (xy 292.287929 -282.771297) (xy 292.337104 -282.769316)
			(xy 292.385959 -282.775248) (xy 292.43323 -282.78894) (xy 292.477692 -282.810038) (xy 292.518195 -282.837994)
			(xy 292.553688 -282.872086) (xy 292.583253 -282.91143) (xy 292.606124 -282.955007) (xy 292.621708 -283.001688)
			(xy 292.629603 -283.050265) (xy 292.630098 -283.074872) (xy 292.968946 -283.074872) (xy 292.972906 -283.025818)
			(xy 292.984683 -282.978034) (xy 293.003974 -282.932758) (xy 293.030277 -282.891162) (xy 293.062912 -282.854325)
			(xy 293.101033 -282.8232) (xy 293.143654 -282.798593) (xy 293.18967 -282.781141) (xy 293.237889 -282.771297)
			(xy 293.287064 -282.769316) (xy 293.335919 -282.775248) (xy 293.38319 -282.78894) (xy 293.427652 -282.810038)
			(xy 293.468155 -282.837994) (xy 293.503648 -282.872086) (xy 293.533213 -282.91143) (xy 293.556084 -282.955007)
			(xy 293.571668 -283.001688) (xy 293.579563 -283.050265) (xy 293.580058 -283.074872) (xy 293.918906 -283.074872)
			(xy 293.922866 -283.025818) (xy 293.934643 -282.978034) (xy 293.953934 -282.932758) (xy 293.980237 -282.891162)
			(xy 294.012872 -282.854325) (xy 294.050993 -282.8232) (xy 294.093614 -282.798593) (xy 294.13963 -282.781141)
			(xy 294.187849 -282.771297) (xy 294.237024 -282.769316) (xy 294.285879 -282.775248) (xy 294.33315 -282.78894)
			(xy 294.377612 -282.810038) (xy 294.418115 -282.837994) (xy 294.453608 -282.872086) (xy 294.483173 -282.91143)
			(xy 294.506044 -282.955007) (xy 294.521628 -283.001688) (xy 294.529523 -283.050265) (xy 294.530018 -283.074872)
			(xy 294.86912 -283.074872) (xy 294.87308 -283.025818) (xy 294.884857 -282.978034) (xy 294.904148 -282.932758)
			(xy 294.930451 -282.891162) (xy 294.963086 -282.854325) (xy 295.001207 -282.8232) (xy 295.043828 -282.798593)
			(xy 295.089844 -282.781141) (xy 295.138063 -282.771297) (xy 295.187238 -282.769316) (xy 295.236093 -282.775248)
			(xy 295.283364 -282.78894) (xy 295.327826 -282.810038) (xy 295.368329 -282.837994) (xy 295.403822 -282.872086)
			(xy 295.433387 -282.91143) (xy 295.456258 -282.955007) (xy 295.471842 -283.001688) (xy 295.479737 -283.050265)
			(xy 295.480232 -283.074872) (xy 295.479737 -283.099479) (xy 295.471842 -283.148056) (xy 295.456258 -283.194737)
			(xy 295.433387 -283.238314) (xy 295.403822 -283.277658) (xy 295.368329 -283.31175) (xy 295.327826 -283.339706)
			(xy 295.283364 -283.360804) (xy 295.236093 -283.374496) (xy 295.187238 -283.380428) (xy 295.138063 -283.378447)
			(xy 295.089844 -283.368603) (xy 295.043828 -283.351151) (xy 295.001207 -283.326544) (xy 294.963086 -283.295419)
			(xy 294.930451 -283.258582) (xy 294.904148 -283.216986) (xy 294.884857 -283.17171) (xy 294.87308 -283.123926)
			(xy 294.86912 -283.074872) (xy 294.530018 -283.074872) (xy 294.529523 -283.099479) (xy 294.521628 -283.148056)
			(xy 294.506044 -283.194737) (xy 294.483173 -283.238314) (xy 294.453608 -283.277658) (xy 294.418115 -283.31175)
			(xy 294.377612 -283.339706) (xy 294.33315 -283.360804) (xy 294.285879 -283.374496) (xy 294.237024 -283.380428)
			(xy 294.187849 -283.378447) (xy 294.13963 -283.368603) (xy 294.093614 -283.351151) (xy 294.050993 -283.326544)
			(xy 294.012872 -283.295419) (xy 293.980237 -283.258582) (xy 293.953934 -283.216986) (xy 293.934643 -283.17171)
			(xy 293.922866 -283.123926) (xy 293.918906 -283.074872) (xy 293.580058 -283.074872) (xy 293.579563 -283.099479)
			(xy 293.571668 -283.148056) (xy 293.556084 -283.194737) (xy 293.533213 -283.238314) (xy 293.503648 -283.277658)
			(xy 293.468155 -283.31175) (xy 293.427652 -283.339706) (xy 293.38319 -283.360804) (xy 293.335919 -283.374496)
			(xy 293.287064 -283.380428) (xy 293.237889 -283.378447) (xy 293.18967 -283.368603) (xy 293.143654 -283.351151)
			(xy 293.101033 -283.326544) (xy 293.062912 -283.295419) (xy 293.030277 -283.258582) (xy 293.003974 -283.216986)
			(xy 292.984683 -283.17171) (xy 292.972906 -283.123926) (xy 292.968946 -283.074872) (xy 292.630098 -283.074872)
			(xy 292.629603 -283.099479) (xy 292.621708 -283.148056) (xy 292.606124 -283.194737) (xy 292.583253 -283.238314)
			(xy 292.553688 -283.277658) (xy 292.518195 -283.31175) (xy 292.477692 -283.339706) (xy 292.43323 -283.360804)
			(xy 292.385959 -283.374496) (xy 292.337104 -283.380428) (xy 292.287929 -283.378447) (xy 292.23971 -283.368603)
			(xy 292.193694 -283.351151) (xy 292.151073 -283.326544) (xy 292.112952 -283.295419) (xy 292.080317 -283.258582)
			(xy 292.054014 -283.216986) (xy 292.034723 -283.17171) (xy 292.022946 -283.123926) (xy 292.018986 -283.074872)
			(xy 290.730178 -283.074872) (xy 290.729683 -283.099479) (xy 290.721788 -283.148056) (xy 290.706204 -283.194737)
			(xy 290.683333 -283.238314) (xy 290.653768 -283.277658) (xy 290.618275 -283.31175) (xy 290.577772 -283.339706)
			(xy 290.53331 -283.360804) (xy 290.486039 -283.374496) (xy 290.437184 -283.380428) (xy 290.388009 -283.378447)
			(xy 290.33979 -283.368603) (xy 290.293774 -283.351151) (xy 290.251153 -283.326544) (xy 290.213032 -283.295419)
			(xy 290.180397 -283.258582) (xy 290.154094 -283.216986) (xy 290.134803 -283.17171) (xy 290.123026 -283.123926)
			(xy 290.119066 -283.074872) (xy 289.780218 -283.074872) (xy 289.779723 -283.099479) (xy 289.771828 -283.148056)
			(xy 289.756244 -283.194737) (xy 289.733373 -283.238314) (xy 289.703808 -283.277658) (xy 289.668315 -283.31175)
			(xy 289.627812 -283.339706) (xy 289.58335 -283.360804) (xy 289.536079 -283.374496) (xy 289.487224 -283.380428)
			(xy 289.438049 -283.378447) (xy 289.38983 -283.368603) (xy 289.343814 -283.351151) (xy 289.301193 -283.326544)
			(xy 289.263072 -283.295419) (xy 289.230437 -283.258582) (xy 289.204134 -283.216986) (xy 289.184843 -283.17171)
			(xy 289.173066 -283.123926) (xy 289.169106 -283.074872) (xy 288.830258 -283.074872) (xy 288.829763 -283.099479)
			(xy 288.821868 -283.148056) (xy 288.806284 -283.194737) (xy 288.783413 -283.238314) (xy 288.753848 -283.277658)
			(xy 288.718355 -283.31175) (xy 288.677852 -283.339706) (xy 288.63339 -283.360804) (xy 288.586119 -283.374496)
			(xy 288.537264 -283.380428) (xy 288.488089 -283.378447) (xy 288.43987 -283.368603) (xy 288.393854 -283.351151)
			(xy 288.351233 -283.326544) (xy 288.313112 -283.295419) (xy 288.280477 -283.258582) (xy 288.254174 -283.216986)
			(xy 288.234883 -283.17171) (xy 288.223106 -283.123926) (xy 288.219146 -283.074872) (xy 287.879937 -283.074872)
			(xy 287.877691 -283.116215) (xy 287.867016 -283.164689) (xy 287.848639 -283.210798) (xy 287.823044 -283.253325)
			(xy 287.790907 -283.291152) (xy 287.753073 -283.323282) (xy 287.71054 -283.348867) (xy 287.664428 -283.367235)
			(xy 287.615952 -283.3779) (xy 287.566389 -283.380582) (xy 287.517045 -283.375211) (xy 287.469219 -283.361927)
			(xy 287.424173 -283.341081) (xy 287.383093 -283.313222) (xy 287.347061 -283.279084) (xy 287.317027 -283.239567)
			(xy 287.293781 -283.195711) (xy 287.277937 -283.148672) (xy 287.269911 -283.09969) (xy 287.269428 -283.074872)
			(xy 287.2696 -283.060689) (xy 287.272275 -283.032449) (xy 287.274762 -283.018484) (xy 287.277048 -283.006038)
			(xy 287.269682 -282.982416) (xy 287.192212 -282.904946) (xy 287.16859 -282.89758) (xy 287.156144 -282.899866)
			(xy 287.142179 -282.902346) (xy 287.113939 -282.905015) (xy 287.099756 -282.9052) (xy 287.085573 -282.905016)
			(xy 287.057333 -282.902349) (xy 287.043368 -282.899866) (xy 287.030922 -282.89758) (xy 287.0073 -282.904946)
			(xy 286.92983 -282.982416) (xy 286.922464 -283.006038) (xy 286.92475 -283.018484) (xy 286.927234 -283.032449)
			(xy 286.929901 -283.060689) (xy 286.930084 -283.074872) (xy 286.929652 -283.099695) (xy 286.921625 -283.148688)
			(xy 286.905777 -283.195737) (xy 286.882526 -283.239603) (xy 286.852485 -283.279128) (xy 286.816445 -283.313273)
			(xy 286.775356 -283.341138) (xy 286.7303 -283.361988) (xy 286.682464 -283.375274) (xy 286.633109 -283.380646)
			(xy 286.583535 -283.377963) (xy 286.535049 -283.367294) (xy 286.488927 -283.348922) (xy 286.446385 -283.323331)
			(xy 286.408543 -283.291193) (xy 286.3764 -283.253358) (xy 286.350801 -283.21082) (xy 286.332421 -283.164701)
			(xy 286.321744 -283.116216) (xy 286.319052 -283.066643) (xy 285.979958 -283.066643) (xy 285.980124 -283.074872)
			(xy 285.979629 -283.099479) (xy 285.971734 -283.148056) (xy 285.95615 -283.194737) (xy 285.933279 -283.238314)
			(xy 285.903714 -283.277658) (xy 285.868221 -283.31175) (xy 285.827718 -283.339706) (xy 285.783256 -283.360804)
			(xy 285.735985 -283.374496) (xy 285.68713 -283.380428) (xy 285.637955 -283.378447) (xy 285.589736 -283.368603)
			(xy 285.54372 -283.351151) (xy 285.501099 -283.326544) (xy 285.462978 -283.295419) (xy 285.430343 -283.258582)
			(xy 285.40404 -283.216986) (xy 285.384749 -283.17171) (xy 285.372972 -283.123926) (xy 285.369012 -283.074872)
			(xy 285.030164 -283.074872) (xy 285.029669 -283.099479) (xy 285.021774 -283.148056) (xy 285.00619 -283.194737)
			(xy 284.983319 -283.238314) (xy 284.953754 -283.277658) (xy 284.918261 -283.31175) (xy 284.877758 -283.339706)
			(xy 284.833296 -283.360804) (xy 284.786025 -283.374496) (xy 284.73717 -283.380428) (xy 284.687995 -283.378447)
			(xy 284.639776 -283.368603) (xy 284.59376 -283.351151) (xy 284.551139 -283.326544) (xy 284.513018 -283.295419)
			(xy 284.480383 -283.258582) (xy 284.45408 -283.216986) (xy 284.434789 -283.17171) (xy 284.423012 -283.123926)
			(xy 284.419052 -283.074872) (xy 284.080204 -283.074872) (xy 284.079709 -283.099479) (xy 284.071814 -283.148056)
			(xy 284.05623 -283.194737) (xy 284.033359 -283.238314) (xy 284.003794 -283.277658) (xy 283.968301 -283.31175)
			(xy 283.927798 -283.339706) (xy 283.883336 -283.360804) (xy 283.836065 -283.374496) (xy 283.78721 -283.380428)
			(xy 283.738035 -283.378447) (xy 283.689816 -283.368603) (xy 283.6438 -283.351151) (xy 283.601179 -283.326544)
			(xy 283.563058 -283.295419) (xy 283.530423 -283.258582) (xy 283.50412 -283.216986) (xy 283.484829 -283.17171)
			(xy 283.473052 -283.123926) (xy 283.469092 -283.074872) (xy 283.130244 -283.074872) (xy 283.129749 -283.099479)
			(xy 283.121854 -283.148056) (xy 283.10627 -283.194737) (xy 283.083399 -283.238314) (xy 283.053834 -283.277658)
			(xy 283.018341 -283.31175) (xy 282.977838 -283.339706) (xy 282.933376 -283.360804) (xy 282.886105 -283.374496)
			(xy 282.83725 -283.380428) (xy 282.788075 -283.378447) (xy 282.739856 -283.368603) (xy 282.69384 -283.351151)
			(xy 282.651219 -283.326544) (xy 282.613098 -283.295419) (xy 282.580463 -283.258582) (xy 282.55416 -283.216986)
			(xy 282.534869 -283.17171) (xy 282.523092 -283.123926) (xy 282.519132 -283.074872) (xy 282.18003 -283.074872)
			(xy 282.179535 -283.099479) (xy 282.17164 -283.148056) (xy 282.156056 -283.194737) (xy 282.133185 -283.238314)
			(xy 282.10362 -283.277658) (xy 282.068127 -283.31175) (xy 282.027624 -283.339706) (xy 281.983162 -283.360804)
			(xy 281.935891 -283.374496) (xy 281.887036 -283.380428) (xy 281.837861 -283.378447) (xy 281.789642 -283.368603)
			(xy 281.743626 -283.351151) (xy 281.701005 -283.326544) (xy 281.662884 -283.295419) (xy 281.630249 -283.258582)
			(xy 281.603946 -283.216986) (xy 281.584655 -283.17171) (xy 281.572878 -283.123926) (xy 281.568918 -283.074872)
			(xy 281.23007 -283.074872) (xy 281.229575 -283.099479) (xy 281.22168 -283.148056) (xy 281.206096 -283.194737)
			(xy 281.183225 -283.238314) (xy 281.15366 -283.277658) (xy 281.118167 -283.31175) (xy 281.077664 -283.339706)
			(xy 281.033202 -283.360804) (xy 280.985931 -283.374496) (xy 280.937076 -283.380428) (xy 280.887901 -283.378447)
			(xy 280.839682 -283.368603) (xy 280.793666 -283.351151) (xy 280.751045 -283.326544) (xy 280.712924 -283.295419)
			(xy 280.680289 -283.258582) (xy 280.653986 -283.216986) (xy 280.634695 -283.17171) (xy 280.622918 -283.123926)
			(xy 280.618958 -283.074872) (xy 280.28011 -283.074872) (xy 280.279615 -283.099479) (xy 280.27172 -283.148056)
			(xy 280.256136 -283.194737) (xy 280.233265 -283.238314) (xy 280.2037 -283.277658) (xy 280.168207 -283.31175)
			(xy 280.127704 -283.339706) (xy 280.083242 -283.360804) (xy 280.035971 -283.374496) (xy 279.987116 -283.380428)
			(xy 279.937941 -283.378447) (xy 279.889722 -283.368603) (xy 279.843706 -283.351151) (xy 279.801085 -283.326544)
			(xy 279.762964 -283.295419) (xy 279.730329 -283.258582) (xy 279.704026 -283.216986) (xy 279.684735 -283.17171)
			(xy 279.672958 -283.123926) (xy 279.668998 -283.074872) (xy 279.33015 -283.074872) (xy 279.329655 -283.099479)
			(xy 279.32176 -283.148056) (xy 279.306176 -283.194737) (xy 279.283305 -283.238314) (xy 279.25374 -283.277658)
			(xy 279.218247 -283.31175) (xy 279.177744 -283.339706) (xy 279.133282 -283.360804) (xy 279.086011 -283.374496)
			(xy 279.037156 -283.380428) (xy 278.987981 -283.378447) (xy 278.939762 -283.368603) (xy 278.893746 -283.351151)
			(xy 278.851125 -283.326544) (xy 278.813004 -283.295419) (xy 278.780369 -283.258582) (xy 278.754066 -283.216986)
			(xy 278.734775 -283.17171) (xy 278.722998 -283.123926) (xy 278.719038 -283.074872) (xy 278.38019 -283.074872)
			(xy 278.379695 -283.099479) (xy 278.3718 -283.148056) (xy 278.356216 -283.194737) (xy 278.333345 -283.238314)
			(xy 278.30378 -283.277658) (xy 278.268287 -283.31175) (xy 278.227784 -283.339706) (xy 278.183322 -283.360804)
			(xy 278.136051 -283.374496) (xy 278.087196 -283.380428) (xy 278.038021 -283.378447) (xy 277.989802 -283.368603)
			(xy 277.943786 -283.351151) (xy 277.901165 -283.326544) (xy 277.863044 -283.295419) (xy 277.830409 -283.258582)
			(xy 277.804106 -283.216986) (xy 277.784815 -283.17171) (xy 277.773038 -283.123926) (xy 277.769078 -283.074872)
			(xy 277.43023 -283.074872) (xy 277.429735 -283.099479) (xy 277.42184 -283.148056) (xy 277.406256 -283.194737)
			(xy 277.383385 -283.238314) (xy 277.35382 -283.277658) (xy 277.318327 -283.31175) (xy 277.277824 -283.339706)
			(xy 277.233362 -283.360804) (xy 277.186091 -283.374496) (xy 277.137236 -283.380428) (xy 277.088061 -283.378447)
			(xy 277.039842 -283.368603) (xy 276.993826 -283.351151) (xy 276.951205 -283.326544) (xy 276.913084 -283.295419)
			(xy 276.880449 -283.258582) (xy 276.854146 -283.216986) (xy 276.834855 -283.17171) (xy 276.823078 -283.123926)
			(xy 276.819118 -283.074872) (xy 276.480016 -283.074872) (xy 276.479521 -283.099479) (xy 276.471626 -283.148056)
			(xy 276.456042 -283.194737) (xy 276.433171 -283.238314) (xy 276.403606 -283.277658) (xy 276.368113 -283.31175)
			(xy 276.32761 -283.339706) (xy 276.283148 -283.360804) (xy 276.235877 -283.374496) (xy 276.187022 -283.380428)
			(xy 276.137847 -283.378447) (xy 276.089628 -283.368603) (xy 276.043612 -283.351151) (xy 276.000991 -283.326544)
			(xy 275.96287 -283.295419) (xy 275.930235 -283.258582) (xy 275.903932 -283.216986) (xy 275.884641 -283.17171)
			(xy 275.872864 -283.123926) (xy 275.868904 -283.074872) (xy 275.530056 -283.074872) (xy 275.529561 -283.099479)
			(xy 275.521666 -283.148056) (xy 275.506082 -283.194737) (xy 275.483211 -283.238314) (xy 275.453646 -283.277658)
			(xy 275.418153 -283.31175) (xy 275.37765 -283.339706) (xy 275.333188 -283.360804) (xy 275.285917 -283.374496)
			(xy 275.237062 -283.380428) (xy 275.187887 -283.378447) (xy 275.139668 -283.368603) (xy 275.093652 -283.351151)
			(xy 275.051031 -283.326544) (xy 275.01291 -283.295419) (xy 274.980275 -283.258582) (xy 274.953972 -283.216986)
			(xy 274.934681 -283.17171) (xy 274.922904 -283.123926) (xy 274.918944 -283.074872) (xy 274.580096 -283.074872)
			(xy 274.579601 -283.099479) (xy 274.571706 -283.148056) (xy 274.556122 -283.194737) (xy 274.533251 -283.238314)
			(xy 274.503686 -283.277658) (xy 274.468193 -283.31175) (xy 274.42769 -283.339706) (xy 274.383228 -283.360804)
			(xy 274.335957 -283.374496) (xy 274.287102 -283.380428) (xy 274.237927 -283.378447) (xy 274.189708 -283.368603)
			(xy 274.143692 -283.351151) (xy 274.101071 -283.326544) (xy 274.06295 -283.295419) (xy 274.030315 -283.258582)
			(xy 274.004012 -283.216986) (xy 273.984721 -283.17171) (xy 273.972944 -283.123926) (xy 273.968984 -283.074872)
			(xy 273.630136 -283.074872) (xy 273.629641 -283.099479) (xy 273.621746 -283.148056) (xy 273.606162 -283.194737)
			(xy 273.583291 -283.238314) (xy 273.553726 -283.277658) (xy 273.518233 -283.31175) (xy 273.47773 -283.339706)
			(xy 273.433268 -283.360804) (xy 273.385997 -283.374496) (xy 273.337142 -283.380428) (xy 273.287967 -283.378447)
			(xy 273.239748 -283.368603) (xy 273.193732 -283.351151) (xy 273.151111 -283.326544) (xy 273.11299 -283.295419)
			(xy 273.080355 -283.258582) (xy 273.054052 -283.216986) (xy 273.034761 -283.17171) (xy 273.022984 -283.123926)
			(xy 273.019024 -283.074872) (xy 272.680176 -283.074872) (xy 272.679681 -283.099479) (xy 272.671786 -283.148056)
			(xy 272.656202 -283.194737) (xy 272.633331 -283.238314) (xy 272.603766 -283.277658) (xy 272.568273 -283.31175)
			(xy 272.52777 -283.339706) (xy 272.483308 -283.360804) (xy 272.436037 -283.374496) (xy 272.387182 -283.380428)
			(xy 272.338007 -283.378447) (xy 272.289788 -283.368603) (xy 272.243772 -283.351151) (xy 272.201151 -283.326544)
			(xy 272.16303 -283.295419) (xy 272.130395 -283.258582) (xy 272.104092 -283.216986) (xy 272.084801 -283.17171)
			(xy 272.073024 -283.123926) (xy 272.069064 -283.074872) (xy 271.730216 -283.074872) (xy 271.729721 -283.099479)
			(xy 271.721826 -283.148056) (xy 271.706242 -283.194737) (xy 271.683371 -283.238314) (xy 271.653806 -283.277658)
			(xy 271.618313 -283.31175) (xy 271.57781 -283.339706) (xy 271.533348 -283.360804) (xy 271.486077 -283.374496)
			(xy 271.437222 -283.380428) (xy 271.388047 -283.378447) (xy 271.339828 -283.368603) (xy 271.293812 -283.351151)
			(xy 271.251191 -283.326544) (xy 271.21307 -283.295419) (xy 271.180435 -283.258582) (xy 271.154132 -283.216986)
			(xy 271.134841 -283.17171) (xy 271.123064 -283.123926) (xy 271.119104 -283.074872) (xy 270.780256 -283.074872)
			(xy 270.779761 -283.099479) (xy 270.771866 -283.148056) (xy 270.756282 -283.194737) (xy 270.733411 -283.238314)
			(xy 270.703846 -283.277658) (xy 270.668353 -283.31175) (xy 270.62785 -283.339706) (xy 270.583388 -283.360804)
			(xy 270.536117 -283.374496) (xy 270.487262 -283.380428) (xy 270.438087 -283.378447) (xy 270.389868 -283.368603)
			(xy 270.343852 -283.351151) (xy 270.301231 -283.326544) (xy 270.26311 -283.295419) (xy 270.230475 -283.258582)
			(xy 270.204172 -283.216986) (xy 270.184881 -283.17171) (xy 270.173104 -283.123926) (xy 270.169144 -283.074872)
			(xy 269.830042 -283.074872) (xy 269.829547 -283.099479) (xy 269.821652 -283.148056) (xy 269.806068 -283.194737)
			(xy 269.783197 -283.238314) (xy 269.753632 -283.277658) (xy 269.718139 -283.31175) (xy 269.677636 -283.339706)
			(xy 269.633174 -283.360804) (xy 269.585903 -283.374496) (xy 269.537048 -283.380428) (xy 269.487873 -283.378447)
			(xy 269.439654 -283.368603) (xy 269.393638 -283.351151) (xy 269.351017 -283.326544) (xy 269.312896 -283.295419)
			(xy 269.280261 -283.258582) (xy 269.253958 -283.216986) (xy 269.234667 -283.17171) (xy 269.22289 -283.123926)
			(xy 269.21893 -283.074872) (xy 268.880082 -283.074872) (xy 268.879587 -283.099479) (xy 268.871692 -283.148056)
			(xy 268.856108 -283.194737) (xy 268.833237 -283.238314) (xy 268.803672 -283.277658) (xy 268.768179 -283.31175)
			(xy 268.727676 -283.339706) (xy 268.683214 -283.360804) (xy 268.635943 -283.374496) (xy 268.587088 -283.380428)
			(xy 268.537913 -283.378447) (xy 268.489694 -283.368603) (xy 268.443678 -283.351151) (xy 268.401057 -283.326544)
			(xy 268.362936 -283.295419) (xy 268.330301 -283.258582) (xy 268.303998 -283.216986) (xy 268.284707 -283.17171)
			(xy 268.27293 -283.123926) (xy 268.26897 -283.074872) (xy 264.307689 -283.074872) (xy 264.311914 -283.104263)
			(xy 264.3124 -283.131514) (xy 264.311872 -283.160897) (xy 264.302839 -283.218964) (xy 264.285005 -283.274959)
			(xy 264.258791 -283.327554) (xy 264.224818 -283.375505) (xy 264.183891 -283.417676) (xy 264.160762 -283.435806)
			(xy 264.151364 -283.443172) (xy 264.14095 -283.463746) (xy 264.139426 -283.567632) (xy 264.149332 -283.588714)
			(xy 264.158476 -283.59608) (xy 264.180292 -283.614323) (xy 264.218835 -283.656133) (xy 264.250747 -283.703201)
			(xy 264.275319 -283.754484) (xy 264.292009 -283.808845) (xy 264.300447 -283.865081) (xy 264.30097 -283.893514)
			(xy 264.934444 -283.893514) (xy 264.938515 -283.837892) (xy 264.950641 -283.783455) (xy 264.970564 -283.731364)
			(xy 264.99786 -283.682729) (xy 265.031946 -283.638586) (xy 265.072095 -283.599877) (xy 265.117453 -283.567426)
			(xy 265.167053 -283.541925) (xy 265.219837 -283.523918) (xy 265.27468 -283.513788) (xy 265.330414 -283.511751)
			(xy 265.385851 -283.517851) (xy 265.439808 -283.531957) (xy 265.491137 -283.553769) (xy 265.538743 -283.582823)
			(xy 265.581611 -283.618498) (xy 265.618828 -283.660035) (xy 265.649601 -283.706548) (xy 265.673273 -283.757045)
			(xy 265.689341 -283.810452) (xy 265.697461 -283.865628) (xy 265.69797 -283.893514) (xy 265.820904 -283.893514)
			(xy 265.824975 -283.837892) (xy 265.837101 -283.783455) (xy 265.857024 -283.731364) (xy 265.88432 -283.682729)
			(xy 265.918406 -283.638586) (xy 265.958555 -283.599877) (xy 266.003913 -283.567426) (xy 266.053513 -283.541925)
			(xy 266.106297 -283.523918) (xy 266.16114 -283.513788) (xy 266.216874 -283.511751) (xy 266.272311 -283.517851)
			(xy 266.326268 -283.531957) (xy 266.377597 -283.553769) (xy 266.425203 -283.582823) (xy 266.468071 -283.618498)
			(xy 266.505288 -283.660035) (xy 266.536061 -283.706548) (xy 266.559733 -283.757045) (xy 266.575801 -283.810452)
			(xy 266.583921 -283.865628) (xy 266.58443 -283.893514) (xy 266.583921 -283.9214) (xy 266.575801 -283.976576)
			(xy 266.561283 -284.024832) (xy 268.26897 -284.024832) (xy 268.27293 -283.975778) (xy 268.284707 -283.927994)
			(xy 268.303998 -283.882718) (xy 268.330301 -283.841122) (xy 268.362936 -283.804285) (xy 268.401057 -283.77316)
			(xy 268.443678 -283.748553) (xy 268.489694 -283.731101) (xy 268.537913 -283.721257) (xy 268.587088 -283.719276)
			(xy 268.635943 -283.725208) (xy 268.683214 -283.7389) (xy 268.727676 -283.759998) (xy 268.768179 -283.787954)
			(xy 268.803672 -283.822046) (xy 268.833237 -283.86139) (xy 268.856108 -283.904967) (xy 268.871692 -283.951648)
			(xy 268.879587 -284.000225) (xy 268.880082 -284.024832) (xy 269.21893 -284.024832) (xy 269.22289 -283.975778)
			(xy 269.234667 -283.927994) (xy 269.253958 -283.882718) (xy 269.280261 -283.841122) (xy 269.312896 -283.804285)
			(xy 269.351017 -283.77316) (xy 269.393638 -283.748553) (xy 269.439654 -283.731101) (xy 269.487873 -283.721257)
			(xy 269.537048 -283.719276) (xy 269.585903 -283.725208) (xy 269.633174 -283.7389) (xy 269.677636 -283.759998)
			(xy 269.718139 -283.787954) (xy 269.753632 -283.822046) (xy 269.783197 -283.86139) (xy 269.806068 -283.904967)
			(xy 269.821652 -283.951648) (xy 269.829547 -284.000225) (xy 269.830042 -284.024832) (xy 270.169144 -284.024832)
			(xy 270.173104 -283.975778) (xy 270.184881 -283.927994) (xy 270.204172 -283.882718) (xy 270.230475 -283.841122)
			(xy 270.26311 -283.804285) (xy 270.301231 -283.77316) (xy 270.343852 -283.748553) (xy 270.389868 -283.731101)
			(xy 270.438087 -283.721257) (xy 270.487262 -283.719276) (xy 270.536117 -283.725208) (xy 270.583388 -283.7389)
			(xy 270.62785 -283.759998) (xy 270.668353 -283.787954) (xy 270.703846 -283.822046) (xy 270.733411 -283.86139)
			(xy 270.756282 -283.904967) (xy 270.771866 -283.951648) (xy 270.779761 -284.000225) (xy 270.780256 -284.024832)
			(xy 271.119104 -284.024832) (xy 271.123064 -283.975778) (xy 271.134841 -283.927994) (xy 271.154132 -283.882718)
			(xy 271.180435 -283.841122) (xy 271.21307 -283.804285) (xy 271.251191 -283.77316) (xy 271.293812 -283.748553)
			(xy 271.339828 -283.731101) (xy 271.388047 -283.721257) (xy 271.437222 -283.719276) (xy 271.486077 -283.725208)
			(xy 271.533348 -283.7389) (xy 271.57781 -283.759998) (xy 271.618313 -283.787954) (xy 271.653806 -283.822046)
			(xy 271.683371 -283.86139) (xy 271.706242 -283.904967) (xy 271.721826 -283.951648) (xy 271.729721 -284.000225)
			(xy 271.730216 -284.024832) (xy 272.069064 -284.024832) (xy 272.073024 -283.975778) (xy 272.084801 -283.927994)
			(xy 272.104092 -283.882718) (xy 272.130395 -283.841122) (xy 272.16303 -283.804285) (xy 272.201151 -283.77316)
			(xy 272.243772 -283.748553) (xy 272.289788 -283.731101) (xy 272.338007 -283.721257) (xy 272.387182 -283.719276)
			(xy 272.436037 -283.725208) (xy 272.483308 -283.7389) (xy 272.52777 -283.759998) (xy 272.568273 -283.787954)
			(xy 272.603766 -283.822046) (xy 272.633331 -283.86139) (xy 272.656202 -283.904967) (xy 272.671786 -283.951648)
			(xy 272.679681 -284.000225) (xy 272.680176 -284.024832) (xy 273.019024 -284.024832) (xy 273.022984 -283.975778)
			(xy 273.034761 -283.927994) (xy 273.054052 -283.882718) (xy 273.080355 -283.841122) (xy 273.11299 -283.804285)
			(xy 273.151111 -283.77316) (xy 273.193732 -283.748553) (xy 273.239748 -283.731101) (xy 273.287967 -283.721257)
			(xy 273.337142 -283.719276) (xy 273.385997 -283.725208) (xy 273.433268 -283.7389) (xy 273.47773 -283.759998)
			(xy 273.518233 -283.787954) (xy 273.553726 -283.822046) (xy 273.583291 -283.86139) (xy 273.606162 -283.904967)
			(xy 273.621746 -283.951648) (xy 273.629641 -284.000225) (xy 273.630136 -284.024832) (xy 273.968984 -284.024832)
			(xy 273.972944 -283.975778) (xy 273.984721 -283.927994) (xy 274.004012 -283.882718) (xy 274.030315 -283.841122)
			(xy 274.06295 -283.804285) (xy 274.101071 -283.77316) (xy 274.143692 -283.748553) (xy 274.189708 -283.731101)
			(xy 274.237927 -283.721257) (xy 274.287102 -283.719276) (xy 274.335957 -283.725208) (xy 274.383228 -283.7389)
			(xy 274.42769 -283.759998) (xy 274.468193 -283.787954) (xy 274.503686 -283.822046) (xy 274.533251 -283.86139)
			(xy 274.556122 -283.904967) (xy 274.571706 -283.951648) (xy 274.579601 -284.000225) (xy 274.580096 -284.024832)
			(xy 274.918944 -284.024832) (xy 274.922904 -283.975778) (xy 274.934681 -283.927994) (xy 274.953972 -283.882718)
			(xy 274.980275 -283.841122) (xy 275.01291 -283.804285) (xy 275.051031 -283.77316) (xy 275.093652 -283.748553)
			(xy 275.139668 -283.731101) (xy 275.187887 -283.721257) (xy 275.237062 -283.719276) (xy 275.285917 -283.725208)
			(xy 275.333188 -283.7389) (xy 275.37765 -283.759998) (xy 275.418153 -283.787954) (xy 275.453646 -283.822046)
			(xy 275.483211 -283.86139) (xy 275.506082 -283.904967) (xy 275.521666 -283.951648) (xy 275.529561 -284.000225)
			(xy 275.530056 -284.024832) (xy 275.868904 -284.024832) (xy 275.872864 -283.975778) (xy 275.884641 -283.927994)
			(xy 275.903932 -283.882718) (xy 275.930235 -283.841122) (xy 275.96287 -283.804285) (xy 276.000991 -283.77316)
			(xy 276.043612 -283.748553) (xy 276.089628 -283.731101) (xy 276.137847 -283.721257) (xy 276.187022 -283.719276)
			(xy 276.235877 -283.725208) (xy 276.283148 -283.7389) (xy 276.32761 -283.759998) (xy 276.368113 -283.787954)
			(xy 276.403606 -283.822046) (xy 276.433171 -283.86139) (xy 276.456042 -283.904967) (xy 276.471626 -283.951648)
			(xy 276.479521 -284.000225) (xy 276.480016 -284.024832) (xy 276.819118 -284.024832) (xy 276.823078 -283.975778)
			(xy 276.834855 -283.927994) (xy 276.854146 -283.882718) (xy 276.880449 -283.841122) (xy 276.913084 -283.804285)
			(xy 276.951205 -283.77316) (xy 276.993826 -283.748553) (xy 277.039842 -283.731101) (xy 277.088061 -283.721257)
			(xy 277.137236 -283.719276) (xy 277.186091 -283.725208) (xy 277.233362 -283.7389) (xy 277.277824 -283.759998)
			(xy 277.318327 -283.787954) (xy 277.35382 -283.822046) (xy 277.383385 -283.86139) (xy 277.406256 -283.904967)
			(xy 277.42184 -283.951648) (xy 277.429735 -284.000225) (xy 277.43023 -284.024832) (xy 277.769078 -284.024832)
			(xy 277.773038 -283.975778) (xy 277.784815 -283.927994) (xy 277.804106 -283.882718) (xy 277.830409 -283.841122)
			(xy 277.863044 -283.804285) (xy 277.901165 -283.77316) (xy 277.943786 -283.748553) (xy 277.989802 -283.731101)
			(xy 278.038021 -283.721257) (xy 278.087196 -283.719276) (xy 278.136051 -283.725208) (xy 278.183322 -283.7389)
			(xy 278.227784 -283.759998) (xy 278.268287 -283.787954) (xy 278.30378 -283.822046) (xy 278.333345 -283.86139)
			(xy 278.356216 -283.904967) (xy 278.3718 -283.951648) (xy 278.379695 -284.000225) (xy 278.38019 -284.024832)
			(xy 278.719038 -284.024832) (xy 278.722998 -283.975778) (xy 278.734775 -283.927994) (xy 278.754066 -283.882718)
			(xy 278.780369 -283.841122) (xy 278.813004 -283.804285) (xy 278.851125 -283.77316) (xy 278.893746 -283.748553)
			(xy 278.939762 -283.731101) (xy 278.987981 -283.721257) (xy 279.037156 -283.719276) (xy 279.086011 -283.725208)
			(xy 279.133282 -283.7389) (xy 279.177744 -283.759998) (xy 279.218247 -283.787954) (xy 279.25374 -283.822046)
			(xy 279.283305 -283.86139) (xy 279.306176 -283.904967) (xy 279.32176 -283.951648) (xy 279.329655 -284.000225)
			(xy 279.33015 -284.024832) (xy 279.668998 -284.024832) (xy 279.672958 -283.975778) (xy 279.684735 -283.927994)
			(xy 279.704026 -283.882718) (xy 279.730329 -283.841122) (xy 279.762964 -283.804285) (xy 279.801085 -283.77316)
			(xy 279.843706 -283.748553) (xy 279.889722 -283.731101) (xy 279.937941 -283.721257) (xy 279.987116 -283.719276)
			(xy 280.035971 -283.725208) (xy 280.083242 -283.7389) (xy 280.127704 -283.759998) (xy 280.168207 -283.787954)
			(xy 280.2037 -283.822046) (xy 280.233265 -283.86139) (xy 280.256136 -283.904967) (xy 280.27172 -283.951648)
			(xy 280.279615 -284.000225) (xy 280.28011 -284.024832) (xy 280.618958 -284.024832) (xy 280.622918 -283.975778)
			(xy 280.634695 -283.927994) (xy 280.653986 -283.882718) (xy 280.680289 -283.841122) (xy 280.712924 -283.804285)
			(xy 280.751045 -283.77316) (xy 280.793666 -283.748553) (xy 280.839682 -283.731101) (xy 280.887901 -283.721257)
			(xy 280.937076 -283.719276) (xy 280.985931 -283.725208) (xy 281.033202 -283.7389) (xy 281.077664 -283.759998)
			(xy 281.118167 -283.787954) (xy 281.15366 -283.822046) (xy 281.183225 -283.86139) (xy 281.206096 -283.904967)
			(xy 281.22168 -283.951648) (xy 281.229575 -284.000225) (xy 281.23007 -284.024832) (xy 281.568918 -284.024832)
			(xy 281.572878 -283.975778) (xy 281.584655 -283.927994) (xy 281.603946 -283.882718) (xy 281.630249 -283.841122)
			(xy 281.662884 -283.804285) (xy 281.701005 -283.77316) (xy 281.743626 -283.748553) (xy 281.789642 -283.731101)
			(xy 281.837861 -283.721257) (xy 281.887036 -283.719276) (xy 281.935891 -283.725208) (xy 281.983162 -283.7389)
			(xy 282.027624 -283.759998) (xy 282.068127 -283.787954) (xy 282.10362 -283.822046) (xy 282.133185 -283.86139)
			(xy 282.156056 -283.904967) (xy 282.17164 -283.951648) (xy 282.179535 -284.000225) (xy 282.18003 -284.024832)
			(xy 282.519132 -284.024832) (xy 282.523092 -283.975778) (xy 282.534869 -283.927994) (xy 282.55416 -283.882718)
			(xy 282.580463 -283.841122) (xy 282.613098 -283.804285) (xy 282.651219 -283.77316) (xy 282.69384 -283.748553)
			(xy 282.739856 -283.731101) (xy 282.788075 -283.721257) (xy 282.83725 -283.719276) (xy 282.886105 -283.725208)
			(xy 282.933376 -283.7389) (xy 282.977838 -283.759998) (xy 283.018341 -283.787954) (xy 283.053834 -283.822046)
			(xy 283.083399 -283.86139) (xy 283.10627 -283.904967) (xy 283.121854 -283.951648) (xy 283.129749 -284.000225)
			(xy 283.130244 -284.024832) (xy 283.469092 -284.024832) (xy 283.473052 -283.975778) (xy 283.484829 -283.927994)
			(xy 283.50412 -283.882718) (xy 283.530423 -283.841122) (xy 283.563058 -283.804285) (xy 283.601179 -283.77316)
			(xy 283.6438 -283.748553) (xy 283.689816 -283.731101) (xy 283.738035 -283.721257) (xy 283.78721 -283.719276)
			(xy 283.836065 -283.725208) (xy 283.883336 -283.7389) (xy 283.927798 -283.759998) (xy 283.968301 -283.787954)
			(xy 284.003794 -283.822046) (xy 284.033359 -283.86139) (xy 284.05623 -283.904967) (xy 284.071814 -283.951648)
			(xy 284.079709 -284.000225) (xy 284.080204 -284.024832) (xy 284.419052 -284.024832) (xy 284.423012 -283.975778)
			(xy 284.434789 -283.927994) (xy 284.45408 -283.882718) (xy 284.480383 -283.841122) (xy 284.513018 -283.804285)
			(xy 284.551139 -283.77316) (xy 284.59376 -283.748553) (xy 284.639776 -283.731101) (xy 284.687995 -283.721257)
			(xy 284.73717 -283.719276) (xy 284.786025 -283.725208) (xy 284.833296 -283.7389) (xy 284.877758 -283.759998)
			(xy 284.918261 -283.787954) (xy 284.953754 -283.822046) (xy 284.983319 -283.86139) (xy 285.00619 -283.904967)
			(xy 285.021774 -283.951648) (xy 285.029669 -284.000225) (xy 285.030164 -284.024832) (xy 285.369012 -284.024832)
			(xy 285.372972 -283.975778) (xy 285.384749 -283.927994) (xy 285.40404 -283.882718) (xy 285.430343 -283.841122)
			(xy 285.462978 -283.804285) (xy 285.501099 -283.77316) (xy 285.54372 -283.748553) (xy 285.589736 -283.731101)
			(xy 285.637955 -283.721257) (xy 285.68713 -283.719276) (xy 285.735985 -283.725208) (xy 285.783256 -283.7389)
			(xy 285.827718 -283.759998) (xy 285.868221 -283.787954) (xy 285.903714 -283.822046) (xy 285.933279 -283.86139)
			(xy 285.95615 -283.904967) (xy 285.971734 -283.951648) (xy 285.979629 -284.000225) (xy 285.980124 -284.024832)
			(xy 286.318972 -284.024832) (xy 286.322932 -283.975778) (xy 286.334709 -283.927994) (xy 286.354 -283.882718)
			(xy 286.380303 -283.841122) (xy 286.412938 -283.804285) (xy 286.451059 -283.77316) (xy 286.49368 -283.748553)
			(xy 286.539696 -283.731101) (xy 286.587915 -283.721257) (xy 286.63709 -283.719276) (xy 286.685945 -283.725208)
			(xy 286.733216 -283.7389) (xy 286.777678 -283.759998) (xy 286.818181 -283.787954) (xy 286.853674 -283.822046)
			(xy 286.883239 -283.86139) (xy 286.90611 -283.904967) (xy 286.921694 -283.951648) (xy 286.929589 -284.000225)
			(xy 286.930084 -284.024832) (xy 287.268932 -284.024832) (xy 287.272892 -283.975778) (xy 287.284669 -283.927994)
			(xy 287.30396 -283.882718) (xy 287.330263 -283.841122) (xy 287.362898 -283.804285) (xy 287.401019 -283.77316)
			(xy 287.44364 -283.748553) (xy 287.489656 -283.731101) (xy 287.537875 -283.721257) (xy 287.58705 -283.719276)
			(xy 287.635905 -283.725208) (xy 287.683176 -283.7389) (xy 287.727638 -283.759998) (xy 287.768141 -283.787954)
			(xy 287.803634 -283.822046) (xy 287.833199 -283.86139) (xy 287.85607 -283.904967) (xy 287.871654 -283.951648)
			(xy 287.879549 -284.000225) (xy 287.880044 -284.024832) (xy 288.218892 -284.024832) (xy 288.222852 -283.975778)
			(xy 288.234629 -283.927994) (xy 288.25392 -283.882718) (xy 288.280223 -283.841122) (xy 288.312858 -283.804285)
			(xy 288.350979 -283.77316) (xy 288.3936 -283.748553) (xy 288.439616 -283.731101) (xy 288.487835 -283.721257)
			(xy 288.53701 -283.719276) (xy 288.585865 -283.725208) (xy 288.633136 -283.7389) (xy 288.677598 -283.759998)
			(xy 288.718101 -283.787954) (xy 288.753594 -283.822046) (xy 288.783159 -283.86139) (xy 288.80603 -283.904967)
			(xy 288.821614 -283.951648) (xy 288.829509 -284.000225) (xy 288.830004 -284.024832) (xy 289.169106 -284.024832)
			(xy 289.173066 -283.975778) (xy 289.184843 -283.927994) (xy 289.204134 -283.882718) (xy 289.230437 -283.841122)
			(xy 289.263072 -283.804285) (xy 289.301193 -283.77316) (xy 289.343814 -283.748553) (xy 289.38983 -283.731101)
			(xy 289.438049 -283.721257) (xy 289.487224 -283.719276) (xy 289.536079 -283.725208) (xy 289.58335 -283.7389)
			(xy 289.627812 -283.759998) (xy 289.668315 -283.787954) (xy 289.703808 -283.822046) (xy 289.733373 -283.86139)
			(xy 289.756244 -283.904967) (xy 289.771828 -283.951648) (xy 289.779723 -284.000225) (xy 289.780218 -284.024832)
			(xy 290.119066 -284.024832) (xy 290.123026 -283.975778) (xy 290.134803 -283.927994) (xy 290.154094 -283.882718)
			(xy 290.180397 -283.841122) (xy 290.213032 -283.804285) (xy 290.251153 -283.77316) (xy 290.293774 -283.748553)
			(xy 290.33979 -283.731101) (xy 290.388009 -283.721257) (xy 290.437184 -283.719276) (xy 290.486039 -283.725208)
			(xy 290.53331 -283.7389) (xy 290.577772 -283.759998) (xy 290.618275 -283.787954) (xy 290.653768 -283.822046)
			(xy 290.683333 -283.86139) (xy 290.706204 -283.904967) (xy 290.721788 -283.951648) (xy 290.729683 -284.000225)
			(xy 290.730178 -284.024832) (xy 292.018986 -284.024832) (xy 292.022946 -283.975778) (xy 292.034723 -283.927994)
			(xy 292.054014 -283.882718) (xy 292.080317 -283.841122) (xy 292.112952 -283.804285) (xy 292.151073 -283.77316)
			(xy 292.193694 -283.748553) (xy 292.23971 -283.731101) (xy 292.287929 -283.721257) (xy 292.337104 -283.719276)
			(xy 292.385959 -283.725208) (xy 292.43323 -283.7389) (xy 292.477692 -283.759998) (xy 292.518195 -283.787954)
			(xy 292.553688 -283.822046) (xy 292.583253 -283.86139) (xy 292.606124 -283.904967) (xy 292.621708 -283.951648)
			(xy 292.629603 -284.000225) (xy 292.630098 -284.024832) (xy 292.968946 -284.024832) (xy 292.972906 -283.975778)
			(xy 292.984683 -283.927994) (xy 293.003974 -283.882718) (xy 293.030277 -283.841122) (xy 293.062912 -283.804285)
			(xy 293.101033 -283.77316) (xy 293.143654 -283.748553) (xy 293.18967 -283.731101) (xy 293.237889 -283.721257)
			(xy 293.287064 -283.719276) (xy 293.335919 -283.725208) (xy 293.38319 -283.7389) (xy 293.427652 -283.759998)
			(xy 293.468155 -283.787954) (xy 293.503648 -283.822046) (xy 293.533213 -283.86139) (xy 293.556084 -283.904967)
			(xy 293.571668 -283.951648) (xy 293.579563 -284.000225) (xy 293.580058 -284.024832) (xy 293.918906 -284.024832)
			(xy 293.922866 -283.975778) (xy 293.934643 -283.927994) (xy 293.953934 -283.882718) (xy 293.980237 -283.841122)
			(xy 294.012872 -283.804285) (xy 294.050993 -283.77316) (xy 294.093614 -283.748553) (xy 294.13963 -283.731101)
			(xy 294.187849 -283.721257) (xy 294.237024 -283.719276) (xy 294.285879 -283.725208) (xy 294.33315 -283.7389)
			(xy 294.377612 -283.759998) (xy 294.418115 -283.787954) (xy 294.453608 -283.822046) (xy 294.483173 -283.86139)
			(xy 294.506044 -283.904967) (xy 294.521628 -283.951648) (xy 294.529523 -284.000225) (xy 294.530018 -284.024832)
			(xy 294.86912 -284.024832) (xy 294.87308 -283.975778) (xy 294.884857 -283.927994) (xy 294.904148 -283.882718)
			(xy 294.930451 -283.841122) (xy 294.963086 -283.804285) (xy 295.001207 -283.77316) (xy 295.043828 -283.748553)
			(xy 295.089844 -283.731101) (xy 295.138063 -283.721257) (xy 295.187238 -283.719276) (xy 295.236093 -283.725208)
			(xy 295.283364 -283.7389) (xy 295.327826 -283.759998) (xy 295.368329 -283.787954) (xy 295.403822 -283.822046)
			(xy 295.433387 -283.86139) (xy 295.456258 -283.904967) (xy 295.471842 -283.951648) (xy 295.479737 -284.000225)
			(xy 295.480232 -284.024832) (xy 295.81908 -284.024832) (xy 295.82304 -283.975778) (xy 295.834817 -283.927994)
			(xy 295.854108 -283.882718) (xy 295.880411 -283.841122) (xy 295.913046 -283.804285) (xy 295.951167 -283.77316)
			(xy 295.993788 -283.748553) (xy 296.039804 -283.731101) (xy 296.088023 -283.721257) (xy 296.137198 -283.719276)
			(xy 296.186053 -283.725208) (xy 296.233324 -283.7389) (xy 296.277786 -283.759998) (xy 296.318289 -283.787954)
			(xy 296.353782 -283.822046) (xy 296.383347 -283.86139) (xy 296.406218 -283.904967) (xy 296.421802 -283.951648)
			(xy 296.429697 -284.000225) (xy 296.430192 -284.024832) (xy 296.76904 -284.024832) (xy 296.773 -283.975778)
			(xy 296.784777 -283.927994) (xy 296.804068 -283.882718) (xy 296.830371 -283.841122) (xy 296.863006 -283.804285)
			(xy 296.901127 -283.77316) (xy 296.943748 -283.748553) (xy 296.989764 -283.731101) (xy 297.037983 -283.721257)
			(xy 297.087158 -283.719276) (xy 297.136013 -283.725208) (xy 297.183284 -283.7389) (xy 297.227746 -283.759998)
			(xy 297.268249 -283.787954) (xy 297.303742 -283.822046) (xy 297.333307 -283.86139) (xy 297.356178 -283.904967)
			(xy 297.371762 -283.951648) (xy 297.379657 -284.000225) (xy 297.380152 -284.024832) (xy 297.719 -284.024832)
			(xy 297.72296 -283.975778) (xy 297.734737 -283.927994) (xy 297.754028 -283.882718) (xy 297.780331 -283.841122)
			(xy 297.812966 -283.804285) (xy 297.851087 -283.77316) (xy 297.893708 -283.748553) (xy 297.939724 -283.731101)
			(xy 297.987943 -283.721257) (xy 298.037118 -283.719276) (xy 298.085973 -283.725208) (xy 298.133244 -283.7389)
			(xy 298.177706 -283.759998) (xy 298.218209 -283.787954) (xy 298.253702 -283.822046) (xy 298.283267 -283.86139)
			(xy 298.306138 -283.904967) (xy 298.321722 -283.951648) (xy 298.329617 -284.000225) (xy 298.330112 -284.024832)
			(xy 298.66896 -284.024832) (xy 298.67292 -283.975778) (xy 298.684697 -283.927994) (xy 298.703988 -283.882718)
			(xy 298.730291 -283.841122) (xy 298.762926 -283.804285) (xy 298.801047 -283.77316) (xy 298.843668 -283.748553)
			(xy 298.889684 -283.731101) (xy 298.937903 -283.721257) (xy 298.987078 -283.719276) (xy 299.035933 -283.725208)
			(xy 299.083204 -283.7389) (xy 299.127666 -283.759998) (xy 299.168169 -283.787954) (xy 299.203662 -283.822046)
			(xy 299.233227 -283.86139) (xy 299.256098 -283.904967) (xy 299.271682 -283.951648) (xy 299.279577 -284.000225)
			(xy 299.280072 -284.024832) (xy 300.56888 -284.024832) (xy 300.57284 -283.975778) (xy 300.584617 -283.927994)
			(xy 300.603908 -283.882718) (xy 300.630211 -283.841122) (xy 300.662846 -283.804285) (xy 300.700967 -283.77316)
			(xy 300.743588 -283.748553) (xy 300.789604 -283.731101) (xy 300.837823 -283.721257) (xy 300.886998 -283.719276)
			(xy 300.935853 -283.725208) (xy 300.983124 -283.7389) (xy 301.027586 -283.759998) (xy 301.068089 -283.787954)
			(xy 301.103582 -283.822046) (xy 301.133147 -283.86139) (xy 301.156018 -283.904967) (xy 301.171602 -283.951648)
			(xy 301.179497 -284.000225) (xy 301.179992 -284.024832) (xy 301.519094 -284.024832) (xy 301.523054 -283.975778)
			(xy 301.534831 -283.927994) (xy 301.554122 -283.882718) (xy 301.580425 -283.841122) (xy 301.61306 -283.804285)
			(xy 301.651181 -283.77316) (xy 301.693802 -283.748553) (xy 301.739818 -283.731101) (xy 301.788037 -283.721257)
			(xy 301.837212 -283.719276) (xy 301.886067 -283.725208) (xy 301.933338 -283.7389) (xy 301.9778 -283.759998)
			(xy 302.018303 -283.787954) (xy 302.053796 -283.822046) (xy 302.083361 -283.86139) (xy 302.106232 -283.904967)
			(xy 302.121816 -283.951648) (xy 302.129711 -284.000225) (xy 302.130206 -284.024832) (xy 302.469054 -284.024832)
			(xy 302.473014 -283.975778) (xy 302.484791 -283.927994) (xy 302.504082 -283.882718) (xy 302.530385 -283.841122)
			(xy 302.56302 -283.804285) (xy 302.601141 -283.77316) (xy 302.643762 -283.748553) (xy 302.689778 -283.731101)
			(xy 302.737997 -283.721257) (xy 302.787172 -283.719276) (xy 302.836027 -283.725208) (xy 302.883298 -283.7389)
			(xy 302.92776 -283.759998) (xy 302.968263 -283.787954) (xy 303.003756 -283.822046) (xy 303.033321 -283.86139)
			(xy 303.056192 -283.904967) (xy 303.071776 -283.951648) (xy 303.079671 -284.000225) (xy 303.080166 -284.024832)
			(xy 303.419014 -284.024832) (xy 303.422974 -283.975778) (xy 303.434751 -283.927994) (xy 303.454042 -283.882718)
			(xy 303.480345 -283.841122) (xy 303.51298 -283.804285) (xy 303.551101 -283.77316) (xy 303.593722 -283.748553)
			(xy 303.639738 -283.731101) (xy 303.687957 -283.721257) (xy 303.737132 -283.719276) (xy 303.785987 -283.725208)
			(xy 303.833258 -283.7389) (xy 303.87772 -283.759998) (xy 303.918223 -283.787954) (xy 303.953716 -283.822046)
			(xy 303.983281 -283.86139) (xy 304.006152 -283.904967) (xy 304.021736 -283.951648) (xy 304.029631 -284.000225)
			(xy 304.030126 -284.024832) (xy 304.368974 -284.024832) (xy 304.372934 -283.975778) (xy 304.384711 -283.927994)
			(xy 304.404002 -283.882718) (xy 304.430305 -283.841122) (xy 304.46294 -283.804285) (xy 304.501061 -283.77316)
			(xy 304.543682 -283.748553) (xy 304.589698 -283.731101) (xy 304.637917 -283.721257) (xy 304.687092 -283.719276)
			(xy 304.735947 -283.725208) (xy 304.783218 -283.7389) (xy 304.82768 -283.759998) (xy 304.868183 -283.787954)
			(xy 304.903676 -283.822046) (xy 304.933241 -283.86139) (xy 304.956112 -283.904967) (xy 304.971696 -283.951648)
			(xy 304.979591 -284.000225) (xy 304.980086 -284.024832) (xy 304.979591 -284.049439) (xy 304.971696 -284.098016)
			(xy 304.956112 -284.144697) (xy 304.933241 -284.188274) (xy 304.903676 -284.227618) (xy 304.868183 -284.26171)
			(xy 304.82768 -284.289666) (xy 304.783218 -284.310764) (xy 304.735947 -284.324456) (xy 304.687092 -284.330388)
			(xy 304.637917 -284.328407) (xy 304.589698 -284.318563) (xy 304.543682 -284.301111) (xy 304.501061 -284.276504)
			(xy 304.46294 -284.245379) (xy 304.430305 -284.208542) (xy 304.404002 -284.166946) (xy 304.384711 -284.12167)
			(xy 304.372934 -284.073886) (xy 304.368974 -284.024832) (xy 304.030126 -284.024832) (xy 304.029631 -284.049439)
			(xy 304.021736 -284.098016) (xy 304.006152 -284.144697) (xy 303.983281 -284.188274) (xy 303.953716 -284.227618)
			(xy 303.918223 -284.26171) (xy 303.87772 -284.289666) (xy 303.833258 -284.310764) (xy 303.785987 -284.324456)
			(xy 303.737132 -284.330388) (xy 303.687957 -284.328407) (xy 303.639738 -284.318563) (xy 303.593722 -284.301111)
			(xy 303.551101 -284.276504) (xy 303.51298 -284.245379) (xy 303.480345 -284.208542) (xy 303.454042 -284.166946)
			(xy 303.434751 -284.12167) (xy 303.422974 -284.073886) (xy 303.419014 -284.024832) (xy 303.080166 -284.024832)
			(xy 303.079671 -284.049439) (xy 303.071776 -284.098016) (xy 303.056192 -284.144697) (xy 303.033321 -284.188274)
			(xy 303.003756 -284.227618) (xy 302.968263 -284.26171) (xy 302.92776 -284.289666) (xy 302.883298 -284.310764)
			(xy 302.836027 -284.324456) (xy 302.787172 -284.330388) (xy 302.737997 -284.328407) (xy 302.689778 -284.318563)
			(xy 302.643762 -284.301111) (xy 302.601141 -284.276504) (xy 302.56302 -284.245379) (xy 302.530385 -284.208542)
			(xy 302.504082 -284.166946) (xy 302.484791 -284.12167) (xy 302.473014 -284.073886) (xy 302.469054 -284.024832)
			(xy 302.130206 -284.024832) (xy 302.129711 -284.049439) (xy 302.121816 -284.098016) (xy 302.106232 -284.144697)
			(xy 302.083361 -284.188274) (xy 302.053796 -284.227618) (xy 302.018303 -284.26171) (xy 301.9778 -284.289666)
			(xy 301.933338 -284.310764) (xy 301.886067 -284.324456) (xy 301.837212 -284.330388) (xy 301.788037 -284.328407)
			(xy 301.739818 -284.318563) (xy 301.693802 -284.301111) (xy 301.651181 -284.276504) (xy 301.61306 -284.245379)
			(xy 301.580425 -284.208542) (xy 301.554122 -284.166946) (xy 301.534831 -284.12167) (xy 301.523054 -284.073886)
			(xy 301.519094 -284.024832) (xy 301.179992 -284.024832) (xy 301.179497 -284.049439) (xy 301.171602 -284.098016)
			(xy 301.156018 -284.144697) (xy 301.133147 -284.188274) (xy 301.103582 -284.227618) (xy 301.068089 -284.26171)
			(xy 301.027586 -284.289666) (xy 300.983124 -284.310764) (xy 300.935853 -284.324456) (xy 300.886998 -284.330388)
			(xy 300.837823 -284.328407) (xy 300.789604 -284.318563) (xy 300.743588 -284.301111) (xy 300.700967 -284.276504)
			(xy 300.662846 -284.245379) (xy 300.630211 -284.208542) (xy 300.603908 -284.166946) (xy 300.584617 -284.12167)
			(xy 300.57284 -284.073886) (xy 300.56888 -284.024832) (xy 299.280072 -284.024832) (xy 299.279577 -284.049439)
			(xy 299.271682 -284.098016) (xy 299.256098 -284.144697) (xy 299.233227 -284.188274) (xy 299.203662 -284.227618)
			(xy 299.168169 -284.26171) (xy 299.127666 -284.289666) (xy 299.083204 -284.310764) (xy 299.035933 -284.324456)
			(xy 298.987078 -284.330388) (xy 298.937903 -284.328407) (xy 298.889684 -284.318563) (xy 298.843668 -284.301111)
			(xy 298.801047 -284.276504) (xy 298.762926 -284.245379) (xy 298.730291 -284.208542) (xy 298.703988 -284.166946)
			(xy 298.684697 -284.12167) (xy 298.67292 -284.073886) (xy 298.66896 -284.024832) (xy 298.330112 -284.024832)
			(xy 298.329617 -284.049439) (xy 298.321722 -284.098016) (xy 298.306138 -284.144697) (xy 298.283267 -284.188274)
			(xy 298.253702 -284.227618) (xy 298.218209 -284.26171) (xy 298.177706 -284.289666) (xy 298.133244 -284.310764)
			(xy 298.085973 -284.324456) (xy 298.037118 -284.330388) (xy 297.987943 -284.328407) (xy 297.939724 -284.318563)
			(xy 297.893708 -284.301111) (xy 297.851087 -284.276504) (xy 297.812966 -284.245379) (xy 297.780331 -284.208542)
			(xy 297.754028 -284.166946) (xy 297.734737 -284.12167) (xy 297.72296 -284.073886) (xy 297.719 -284.024832)
			(xy 297.380152 -284.024832) (xy 297.379657 -284.049439) (xy 297.371762 -284.098016) (xy 297.356178 -284.144697)
			(xy 297.333307 -284.188274) (xy 297.303742 -284.227618) (xy 297.268249 -284.26171) (xy 297.227746 -284.289666)
			(xy 297.183284 -284.310764) (xy 297.136013 -284.324456) (xy 297.087158 -284.330388) (xy 297.037983 -284.328407)
			(xy 296.989764 -284.318563) (xy 296.943748 -284.301111) (xy 296.901127 -284.276504) (xy 296.863006 -284.245379)
			(xy 296.830371 -284.208542) (xy 296.804068 -284.166946) (xy 296.784777 -284.12167) (xy 296.773 -284.073886)
			(xy 296.76904 -284.024832) (xy 296.430192 -284.024832) (xy 296.429697 -284.049439) (xy 296.421802 -284.098016)
			(xy 296.406218 -284.144697) (xy 296.383347 -284.188274) (xy 296.353782 -284.227618) (xy 296.318289 -284.26171)
			(xy 296.277786 -284.289666) (xy 296.233324 -284.310764) (xy 296.186053 -284.324456) (xy 296.137198 -284.330388)
			(xy 296.088023 -284.328407) (xy 296.039804 -284.318563) (xy 295.993788 -284.301111) (xy 295.951167 -284.276504)
			(xy 295.913046 -284.245379) (xy 295.880411 -284.208542) (xy 295.854108 -284.166946) (xy 295.834817 -284.12167)
			(xy 295.82304 -284.073886) (xy 295.81908 -284.024832) (xy 295.480232 -284.024832) (xy 295.479737 -284.049439)
			(xy 295.471842 -284.098016) (xy 295.456258 -284.144697) (xy 295.433387 -284.188274) (xy 295.403822 -284.227618)
			(xy 295.368329 -284.26171) (xy 295.327826 -284.289666) (xy 295.283364 -284.310764) (xy 295.236093 -284.324456)
			(xy 295.187238 -284.330388) (xy 295.138063 -284.328407) (xy 295.089844 -284.318563) (xy 295.043828 -284.301111)
			(xy 295.001207 -284.276504) (xy 294.963086 -284.245379) (xy 294.930451 -284.208542) (xy 294.904148 -284.166946)
			(xy 294.884857 -284.12167) (xy 294.87308 -284.073886) (xy 294.86912 -284.024832) (xy 294.530018 -284.024832)
			(xy 294.529523 -284.049439) (xy 294.521628 -284.098016) (xy 294.506044 -284.144697) (xy 294.483173 -284.188274)
			(xy 294.453608 -284.227618) (xy 294.418115 -284.26171) (xy 294.377612 -284.289666) (xy 294.33315 -284.310764)
			(xy 294.285879 -284.324456) (xy 294.237024 -284.330388) (xy 294.187849 -284.328407) (xy 294.13963 -284.318563)
			(xy 294.093614 -284.301111) (xy 294.050993 -284.276504) (xy 294.012872 -284.245379) (xy 293.980237 -284.208542)
			(xy 293.953934 -284.166946) (xy 293.934643 -284.12167) (xy 293.922866 -284.073886) (xy 293.918906 -284.024832)
			(xy 293.580058 -284.024832) (xy 293.579563 -284.049439) (xy 293.571668 -284.098016) (xy 293.556084 -284.144697)
			(xy 293.533213 -284.188274) (xy 293.503648 -284.227618) (xy 293.468155 -284.26171) (xy 293.427652 -284.289666)
			(xy 293.38319 -284.310764) (xy 293.335919 -284.324456) (xy 293.287064 -284.330388) (xy 293.237889 -284.328407)
			(xy 293.18967 -284.318563) (xy 293.143654 -284.301111) (xy 293.101033 -284.276504) (xy 293.062912 -284.245379)
			(xy 293.030277 -284.208542) (xy 293.003974 -284.166946) (xy 292.984683 -284.12167) (xy 292.972906 -284.073886)
			(xy 292.968946 -284.024832) (xy 292.630098 -284.024832) (xy 292.629603 -284.049439) (xy 292.621708 -284.098016)
			(xy 292.606124 -284.144697) (xy 292.583253 -284.188274) (xy 292.553688 -284.227618) (xy 292.518195 -284.26171)
			(xy 292.477692 -284.289666) (xy 292.43323 -284.310764) (xy 292.385959 -284.324456) (xy 292.337104 -284.330388)
			(xy 292.287929 -284.328407) (xy 292.23971 -284.318563) (xy 292.193694 -284.301111) (xy 292.151073 -284.276504)
			(xy 292.112952 -284.245379) (xy 292.080317 -284.208542) (xy 292.054014 -284.166946) (xy 292.034723 -284.12167)
			(xy 292.022946 -284.073886) (xy 292.018986 -284.024832) (xy 290.730178 -284.024832) (xy 290.729683 -284.049439)
			(xy 290.721788 -284.098016) (xy 290.706204 -284.144697) (xy 290.683333 -284.188274) (xy 290.653768 -284.227618)
			(xy 290.618275 -284.26171) (xy 290.577772 -284.289666) (xy 290.53331 -284.310764) (xy 290.486039 -284.324456)
			(xy 290.437184 -284.330388) (xy 290.388009 -284.328407) (xy 290.33979 -284.318563) (xy 290.293774 -284.301111)
			(xy 290.251153 -284.276504) (xy 290.213032 -284.245379) (xy 290.180397 -284.208542) (xy 290.154094 -284.166946)
			(xy 290.134803 -284.12167) (xy 290.123026 -284.073886) (xy 290.119066 -284.024832) (xy 289.780218 -284.024832)
			(xy 289.779723 -284.049439) (xy 289.771828 -284.098016) (xy 289.756244 -284.144697) (xy 289.733373 -284.188274)
			(xy 289.703808 -284.227618) (xy 289.668315 -284.26171) (xy 289.627812 -284.289666) (xy 289.58335 -284.310764)
			(xy 289.536079 -284.324456) (xy 289.487224 -284.330388) (xy 289.438049 -284.328407) (xy 289.38983 -284.318563)
			(xy 289.343814 -284.301111) (xy 289.301193 -284.276504) (xy 289.263072 -284.245379) (xy 289.230437 -284.208542)
			(xy 289.204134 -284.166946) (xy 289.184843 -284.12167) (xy 289.173066 -284.073886) (xy 289.169106 -284.024832)
			(xy 288.830004 -284.024832) (xy 288.829509 -284.049439) (xy 288.821614 -284.098016) (xy 288.80603 -284.144697)
			(xy 288.783159 -284.188274) (xy 288.753594 -284.227618) (xy 288.718101 -284.26171) (xy 288.677598 -284.289666)
			(xy 288.633136 -284.310764) (xy 288.585865 -284.324456) (xy 288.53701 -284.330388) (xy 288.487835 -284.328407)
			(xy 288.439616 -284.318563) (xy 288.3936 -284.301111) (xy 288.350979 -284.276504) (xy 288.312858 -284.245379)
			(xy 288.280223 -284.208542) (xy 288.25392 -284.166946) (xy 288.234629 -284.12167) (xy 288.222852 -284.073886)
			(xy 288.218892 -284.024832) (xy 287.880044 -284.024832) (xy 287.879549 -284.049439) (xy 287.871654 -284.098016)
			(xy 287.85607 -284.144697) (xy 287.833199 -284.188274) (xy 287.803634 -284.227618) (xy 287.768141 -284.26171)
			(xy 287.727638 -284.289666) (xy 287.683176 -284.310764) (xy 287.635905 -284.324456) (xy 287.58705 -284.330388)
			(xy 287.537875 -284.328407) (xy 287.489656 -284.318563) (xy 287.44364 -284.301111) (xy 287.401019 -284.276504)
			(xy 287.362898 -284.245379) (xy 287.330263 -284.208542) (xy 287.30396 -284.166946) (xy 287.284669 -284.12167)
			(xy 287.272892 -284.073886) (xy 287.268932 -284.024832) (xy 286.930084 -284.024832) (xy 286.929589 -284.049439)
			(xy 286.921694 -284.098016) (xy 286.90611 -284.144697) (xy 286.883239 -284.188274) (xy 286.853674 -284.227618)
			(xy 286.818181 -284.26171) (xy 286.777678 -284.289666) (xy 286.733216 -284.310764) (xy 286.685945 -284.324456)
			(xy 286.63709 -284.330388) (xy 286.587915 -284.328407) (xy 286.539696 -284.318563) (xy 286.49368 -284.301111)
			(xy 286.451059 -284.276504) (xy 286.412938 -284.245379) (xy 286.380303 -284.208542) (xy 286.354 -284.166946)
			(xy 286.334709 -284.12167) (xy 286.322932 -284.073886) (xy 286.318972 -284.024832) (xy 285.980124 -284.024832)
			(xy 285.979629 -284.049439) (xy 285.971734 -284.098016) (xy 285.95615 -284.144697) (xy 285.933279 -284.188274)
			(xy 285.903714 -284.227618) (xy 285.868221 -284.26171) (xy 285.827718 -284.289666) (xy 285.783256 -284.310764)
			(xy 285.735985 -284.324456) (xy 285.68713 -284.330388) (xy 285.637955 -284.328407) (xy 285.589736 -284.318563)
			(xy 285.54372 -284.301111) (xy 285.501099 -284.276504) (xy 285.462978 -284.245379) (xy 285.430343 -284.208542)
			(xy 285.40404 -284.166946) (xy 285.384749 -284.12167) (xy 285.372972 -284.073886) (xy 285.369012 -284.024832)
			(xy 285.030164 -284.024832) (xy 285.029669 -284.049439) (xy 285.021774 -284.098016) (xy 285.00619 -284.144697)
			(xy 284.983319 -284.188274) (xy 284.953754 -284.227618) (xy 284.918261 -284.26171) (xy 284.877758 -284.289666)
			(xy 284.833296 -284.310764) (xy 284.786025 -284.324456) (xy 284.73717 -284.330388) (xy 284.687995 -284.328407)
			(xy 284.639776 -284.318563) (xy 284.59376 -284.301111) (xy 284.551139 -284.276504) (xy 284.513018 -284.245379)
			(xy 284.480383 -284.208542) (xy 284.45408 -284.166946) (xy 284.434789 -284.12167) (xy 284.423012 -284.073886)
			(xy 284.419052 -284.024832) (xy 284.080204 -284.024832) (xy 284.079709 -284.049439) (xy 284.071814 -284.098016)
			(xy 284.05623 -284.144697) (xy 284.033359 -284.188274) (xy 284.003794 -284.227618) (xy 283.968301 -284.26171)
			(xy 283.927798 -284.289666) (xy 283.883336 -284.310764) (xy 283.836065 -284.324456) (xy 283.78721 -284.330388)
			(xy 283.738035 -284.328407) (xy 283.689816 -284.318563) (xy 283.6438 -284.301111) (xy 283.601179 -284.276504)
			(xy 283.563058 -284.245379) (xy 283.530423 -284.208542) (xy 283.50412 -284.166946) (xy 283.484829 -284.12167)
			(xy 283.473052 -284.073886) (xy 283.469092 -284.024832) (xy 283.130244 -284.024832) (xy 283.129749 -284.049439)
			(xy 283.121854 -284.098016) (xy 283.10627 -284.144697) (xy 283.083399 -284.188274) (xy 283.053834 -284.227618)
			(xy 283.018341 -284.26171) (xy 282.977838 -284.289666) (xy 282.933376 -284.310764) (xy 282.886105 -284.324456)
			(xy 282.83725 -284.330388) (xy 282.788075 -284.328407) (xy 282.739856 -284.318563) (xy 282.69384 -284.301111)
			(xy 282.651219 -284.276504) (xy 282.613098 -284.245379) (xy 282.580463 -284.208542) (xy 282.55416 -284.166946)
			(xy 282.534869 -284.12167) (xy 282.523092 -284.073886) (xy 282.519132 -284.024832) (xy 282.18003 -284.024832)
			(xy 282.179535 -284.049439) (xy 282.17164 -284.098016) (xy 282.156056 -284.144697) (xy 282.133185 -284.188274)
			(xy 282.10362 -284.227618) (xy 282.068127 -284.26171) (xy 282.027624 -284.289666) (xy 281.983162 -284.310764)
			(xy 281.935891 -284.324456) (xy 281.887036 -284.330388) (xy 281.837861 -284.328407) (xy 281.789642 -284.318563)
			(xy 281.743626 -284.301111) (xy 281.701005 -284.276504) (xy 281.662884 -284.245379) (xy 281.630249 -284.208542)
			(xy 281.603946 -284.166946) (xy 281.584655 -284.12167) (xy 281.572878 -284.073886) (xy 281.568918 -284.024832)
			(xy 281.23007 -284.024832) (xy 281.229575 -284.049439) (xy 281.22168 -284.098016) (xy 281.206096 -284.144697)
			(xy 281.183225 -284.188274) (xy 281.15366 -284.227618) (xy 281.118167 -284.26171) (xy 281.077664 -284.289666)
			(xy 281.033202 -284.310764) (xy 280.985931 -284.324456) (xy 280.937076 -284.330388) (xy 280.887901 -284.328407)
			(xy 280.839682 -284.318563) (xy 280.793666 -284.301111) (xy 280.751045 -284.276504) (xy 280.712924 -284.245379)
			(xy 280.680289 -284.208542) (xy 280.653986 -284.166946) (xy 280.634695 -284.12167) (xy 280.622918 -284.073886)
			(xy 280.618958 -284.024832) (xy 280.28011 -284.024832) (xy 280.279615 -284.049439) (xy 280.27172 -284.098016)
			(xy 280.256136 -284.144697) (xy 280.233265 -284.188274) (xy 280.2037 -284.227618) (xy 280.168207 -284.26171)
			(xy 280.127704 -284.289666) (xy 280.083242 -284.310764) (xy 280.035971 -284.324456) (xy 279.987116 -284.330388)
			(xy 279.937941 -284.328407) (xy 279.889722 -284.318563) (xy 279.843706 -284.301111) (xy 279.801085 -284.276504)
			(xy 279.762964 -284.245379) (xy 279.730329 -284.208542) (xy 279.704026 -284.166946) (xy 279.684735 -284.12167)
			(xy 279.672958 -284.073886) (xy 279.668998 -284.024832) (xy 279.33015 -284.024832) (xy 279.329655 -284.049439)
			(xy 279.32176 -284.098016) (xy 279.306176 -284.144697) (xy 279.283305 -284.188274) (xy 279.25374 -284.227618)
			(xy 279.218247 -284.26171) (xy 279.177744 -284.289666) (xy 279.133282 -284.310764) (xy 279.086011 -284.324456)
			(xy 279.037156 -284.330388) (xy 278.987981 -284.328407) (xy 278.939762 -284.318563) (xy 278.893746 -284.301111)
			(xy 278.851125 -284.276504) (xy 278.813004 -284.245379) (xy 278.780369 -284.208542) (xy 278.754066 -284.166946)
			(xy 278.734775 -284.12167) (xy 278.722998 -284.073886) (xy 278.719038 -284.024832) (xy 278.38019 -284.024832)
			(xy 278.379695 -284.049439) (xy 278.3718 -284.098016) (xy 278.356216 -284.144697) (xy 278.333345 -284.188274)
			(xy 278.30378 -284.227618) (xy 278.268287 -284.26171) (xy 278.227784 -284.289666) (xy 278.183322 -284.310764)
			(xy 278.136051 -284.324456) (xy 278.087196 -284.330388) (xy 278.038021 -284.328407) (xy 277.989802 -284.318563)
			(xy 277.943786 -284.301111) (xy 277.901165 -284.276504) (xy 277.863044 -284.245379) (xy 277.830409 -284.208542)
			(xy 277.804106 -284.166946) (xy 277.784815 -284.12167) (xy 277.773038 -284.073886) (xy 277.769078 -284.024832)
			(xy 277.43023 -284.024832) (xy 277.429735 -284.049439) (xy 277.42184 -284.098016) (xy 277.406256 -284.144697)
			(xy 277.383385 -284.188274) (xy 277.35382 -284.227618) (xy 277.318327 -284.26171) (xy 277.277824 -284.289666)
			(xy 277.233362 -284.310764) (xy 277.186091 -284.324456) (xy 277.137236 -284.330388) (xy 277.088061 -284.328407)
			(xy 277.039842 -284.318563) (xy 276.993826 -284.301111) (xy 276.951205 -284.276504) (xy 276.913084 -284.245379)
			(xy 276.880449 -284.208542) (xy 276.854146 -284.166946) (xy 276.834855 -284.12167) (xy 276.823078 -284.073886)
			(xy 276.819118 -284.024832) (xy 276.480016 -284.024832) (xy 276.479521 -284.049439) (xy 276.471626 -284.098016)
			(xy 276.456042 -284.144697) (xy 276.433171 -284.188274) (xy 276.403606 -284.227618) (xy 276.368113 -284.26171)
			(xy 276.32761 -284.289666) (xy 276.283148 -284.310764) (xy 276.235877 -284.324456) (xy 276.187022 -284.330388)
			(xy 276.137847 -284.328407) (xy 276.089628 -284.318563) (xy 276.043612 -284.301111) (xy 276.000991 -284.276504)
			(xy 275.96287 -284.245379) (xy 275.930235 -284.208542) (xy 275.903932 -284.166946) (xy 275.884641 -284.12167)
			(xy 275.872864 -284.073886) (xy 275.868904 -284.024832) (xy 275.530056 -284.024832) (xy 275.529561 -284.049439)
			(xy 275.521666 -284.098016) (xy 275.506082 -284.144697) (xy 275.483211 -284.188274) (xy 275.453646 -284.227618)
			(xy 275.418153 -284.26171) (xy 275.37765 -284.289666) (xy 275.333188 -284.310764) (xy 275.285917 -284.324456)
			(xy 275.237062 -284.330388) (xy 275.187887 -284.328407) (xy 275.139668 -284.318563) (xy 275.093652 -284.301111)
			(xy 275.051031 -284.276504) (xy 275.01291 -284.245379) (xy 274.980275 -284.208542) (xy 274.953972 -284.166946)
			(xy 274.934681 -284.12167) (xy 274.922904 -284.073886) (xy 274.918944 -284.024832) (xy 274.580096 -284.024832)
			(xy 274.579601 -284.049439) (xy 274.571706 -284.098016) (xy 274.556122 -284.144697) (xy 274.533251 -284.188274)
			(xy 274.503686 -284.227618) (xy 274.468193 -284.26171) (xy 274.42769 -284.289666) (xy 274.383228 -284.310764)
			(xy 274.335957 -284.324456) (xy 274.287102 -284.330388) (xy 274.237927 -284.328407) (xy 274.189708 -284.318563)
			(xy 274.143692 -284.301111) (xy 274.101071 -284.276504) (xy 274.06295 -284.245379) (xy 274.030315 -284.208542)
			(xy 274.004012 -284.166946) (xy 273.984721 -284.12167) (xy 273.972944 -284.073886) (xy 273.968984 -284.024832)
			(xy 273.630136 -284.024832) (xy 273.629641 -284.049439) (xy 273.621746 -284.098016) (xy 273.606162 -284.144697)
			(xy 273.583291 -284.188274) (xy 273.553726 -284.227618) (xy 273.518233 -284.26171) (xy 273.47773 -284.289666)
			(xy 273.433268 -284.310764) (xy 273.385997 -284.324456) (xy 273.337142 -284.330388) (xy 273.287967 -284.328407)
			(xy 273.239748 -284.318563) (xy 273.193732 -284.301111) (xy 273.151111 -284.276504) (xy 273.11299 -284.245379)
			(xy 273.080355 -284.208542) (xy 273.054052 -284.166946) (xy 273.034761 -284.12167) (xy 273.022984 -284.073886)
			(xy 273.019024 -284.024832) (xy 272.680176 -284.024832) (xy 272.679681 -284.049439) (xy 272.671786 -284.098016)
			(xy 272.656202 -284.144697) (xy 272.633331 -284.188274) (xy 272.603766 -284.227618) (xy 272.568273 -284.26171)
			(xy 272.52777 -284.289666) (xy 272.483308 -284.310764) (xy 272.436037 -284.324456) (xy 272.387182 -284.330388)
			(xy 272.338007 -284.328407) (xy 272.289788 -284.318563) (xy 272.243772 -284.301111) (xy 272.201151 -284.276504)
			(xy 272.16303 -284.245379) (xy 272.130395 -284.208542) (xy 272.104092 -284.166946) (xy 272.084801 -284.12167)
			(xy 272.073024 -284.073886) (xy 272.069064 -284.024832) (xy 271.730216 -284.024832) (xy 271.729721 -284.049439)
			(xy 271.721826 -284.098016) (xy 271.706242 -284.144697) (xy 271.683371 -284.188274) (xy 271.653806 -284.227618)
			(xy 271.618313 -284.26171) (xy 271.57781 -284.289666) (xy 271.533348 -284.310764) (xy 271.486077 -284.324456)
			(xy 271.437222 -284.330388) (xy 271.388047 -284.328407) (xy 271.339828 -284.318563) (xy 271.293812 -284.301111)
			(xy 271.251191 -284.276504) (xy 271.21307 -284.245379) (xy 271.180435 -284.208542) (xy 271.154132 -284.166946)
			(xy 271.134841 -284.12167) (xy 271.123064 -284.073886) (xy 271.119104 -284.024832) (xy 270.780256 -284.024832)
			(xy 270.779761 -284.049439) (xy 270.771866 -284.098016) (xy 270.756282 -284.144697) (xy 270.733411 -284.188274)
			(xy 270.703846 -284.227618) (xy 270.668353 -284.26171) (xy 270.62785 -284.289666) (xy 270.583388 -284.310764)
			(xy 270.536117 -284.324456) (xy 270.487262 -284.330388) (xy 270.438087 -284.328407) (xy 270.389868 -284.318563)
			(xy 270.343852 -284.301111) (xy 270.301231 -284.276504) (xy 270.26311 -284.245379) (xy 270.230475 -284.208542)
			(xy 270.204172 -284.166946) (xy 270.184881 -284.12167) (xy 270.173104 -284.073886) (xy 270.169144 -284.024832)
			(xy 269.830042 -284.024832) (xy 269.829547 -284.049439) (xy 269.821652 -284.098016) (xy 269.806068 -284.144697)
			(xy 269.783197 -284.188274) (xy 269.753632 -284.227618) (xy 269.718139 -284.26171) (xy 269.677636 -284.289666)
			(xy 269.633174 -284.310764) (xy 269.585903 -284.324456) (xy 269.537048 -284.330388) (xy 269.487873 -284.328407)
			(xy 269.439654 -284.318563) (xy 269.393638 -284.301111) (xy 269.351017 -284.276504) (xy 269.312896 -284.245379)
			(xy 269.280261 -284.208542) (xy 269.253958 -284.166946) (xy 269.234667 -284.12167) (xy 269.22289 -284.073886)
			(xy 269.21893 -284.024832) (xy 268.880082 -284.024832) (xy 268.879587 -284.049439) (xy 268.871692 -284.098016)
			(xy 268.856108 -284.144697) (xy 268.833237 -284.188274) (xy 268.803672 -284.227618) (xy 268.768179 -284.26171)
			(xy 268.727676 -284.289666) (xy 268.683214 -284.310764) (xy 268.635943 -284.324456) (xy 268.587088 -284.330388)
			(xy 268.537913 -284.328407) (xy 268.489694 -284.318563) (xy 268.443678 -284.301111) (xy 268.401057 -284.276504)
			(xy 268.362936 -284.245379) (xy 268.330301 -284.208542) (xy 268.303998 -284.166946) (xy 268.284707 -284.12167)
			(xy 268.27293 -284.073886) (xy 268.26897 -284.024832) (xy 266.561283 -284.024832) (xy 266.559733 -284.029983)
			(xy 266.536061 -284.08048) (xy 266.505288 -284.126993) (xy 266.468071 -284.16853) (xy 266.425203 -284.204205)
			(xy 266.377597 -284.233259) (xy 266.326268 -284.255071) (xy 266.272311 -284.269177) (xy 266.216874 -284.275277)
			(xy 266.16114 -284.27324) (xy 266.106297 -284.26311) (xy 266.053513 -284.245103) (xy 266.003913 -284.219602)
			(xy 265.958555 -284.187151) (xy 265.918406 -284.148442) (xy 265.88432 -284.104299) (xy 265.857024 -284.055664)
			(xy 265.837101 -284.003573) (xy 265.824975 -283.949136) (xy 265.820904 -283.893514) (xy 265.69797 -283.893514)
			(xy 265.697461 -283.9214) (xy 265.689341 -283.976576) (xy 265.673273 -284.029983) (xy 265.649601 -284.08048)
			(xy 265.618828 -284.126993) (xy 265.581611 -284.16853) (xy 265.538743 -284.204205) (xy 265.491137 -284.233259)
			(xy 265.439808 -284.255071) (xy 265.385851 -284.269177) (xy 265.330414 -284.275277) (xy 265.27468 -284.27324)
			(xy 265.219837 -284.26311) (xy 265.167053 -284.245103) (xy 265.117453 -284.219602) (xy 265.072095 -284.187151)
			(xy 265.031946 -284.148442) (xy 264.99786 -284.104299) (xy 264.970564 -284.055664) (xy 264.950641 -284.003573)
			(xy 264.938515 -283.949136) (xy 264.934444 -283.893514) (xy 264.30097 -283.893514) (xy 264.300484 -283.920765)
			(xy 264.292728 -283.974713) (xy 264.277373 -284.027008) (xy 264.254731 -284.076585) (xy 264.225265 -284.122435)
			(xy 264.189574 -284.163626) (xy 264.148383 -284.199317) (xy 264.102533 -284.228783) (xy 264.052956 -284.251425)
			(xy 264.000661 -284.26678) (xy 263.946713 -284.274536) (xy 263.892211 -284.274536) (xy 263.838263 -284.26678)
			(xy 263.785968 -284.251425) (xy 263.736391 -284.228783) (xy 263.690541 -284.199317) (xy 263.64935 -284.163626)
			(xy 263.613659 -284.122435) (xy 263.584193 -284.076585) (xy 263.561551 -284.027008) (xy 263.546196 -283.974713)
			(xy 263.53844 -283.920765) (xy 263.537954 -283.893514) (xy 249.737118 -283.893514) (xy 249.737118 -285.029656)
			(xy 258.01142 -285.029656) (xy 258.015491 -284.974034) (xy 258.027617 -284.919597) (xy 258.04754 -284.867506)
			(xy 258.074836 -284.818871) (xy 258.108922 -284.774728) (xy 258.149071 -284.736019) (xy 258.194429 -284.703568)
			(xy 258.244029 -284.678067) (xy 258.296813 -284.66006) (xy 258.351656 -284.64993) (xy 258.40739 -284.647893)
			(xy 258.462827 -284.653993) (xy 258.516784 -284.668099) (xy 258.568113 -284.689911) (xy 258.615719 -284.718965)
			(xy 258.658587 -284.75464) (xy 258.695804 -284.796177) (xy 258.726577 -284.84269) (xy 258.750249 -284.893187)
			(xy 258.766317 -284.946594) (xy 258.774437 -285.00177) (xy 258.774946 -285.029656) (xy 259.496558 -285.029656)
			(xy 259.500629 -284.974034) (xy 259.512755 -284.919597) (xy 259.532678 -284.867506) (xy 259.559974 -284.818871)
			(xy 259.59406 -284.774728) (xy 259.634209 -284.736019) (xy 259.679567 -284.703568) (xy 259.729167 -284.678067)
			(xy 259.781951 -284.66006) (xy 259.836794 -284.64993) (xy 259.892528 -284.647893) (xy 259.947965 -284.653993)
			(xy 260.001922 -284.668099) (xy 260.053251 -284.689911) (xy 260.100857 -284.718965) (xy 260.143725 -284.75464)
			(xy 260.180942 -284.796177) (xy 260.211715 -284.84269) (xy 260.235387 -284.893187) (xy 260.251455 -284.946594)
			(xy 260.255605 -284.974792) (xy 268.26897 -284.974792) (xy 268.27293 -284.925738) (xy 268.284707 -284.877954)
			(xy 268.303998 -284.832678) (xy 268.330301 -284.791082) (xy 268.362936 -284.754245) (xy 268.401057 -284.72312)
			(xy 268.443678 -284.698513) (xy 268.489694 -284.681061) (xy 268.537913 -284.671217) (xy 268.587088 -284.669236)
			(xy 268.635943 -284.675168) (xy 268.683214 -284.68886) (xy 268.727676 -284.709958) (xy 268.768179 -284.737914)
			(xy 268.803672 -284.772006) (xy 268.833237 -284.81135) (xy 268.856108 -284.854927) (xy 268.871692 -284.901608)
			(xy 268.879587 -284.950185) (xy 268.880082 -284.974792) (xy 269.21893 -284.974792) (xy 269.22289 -284.925738)
			(xy 269.234667 -284.877954) (xy 269.253958 -284.832678) (xy 269.280261 -284.791082) (xy 269.312896 -284.754245)
			(xy 269.351017 -284.72312) (xy 269.393638 -284.698513) (xy 269.439654 -284.681061) (xy 269.487873 -284.671217)
			(xy 269.537048 -284.669236) (xy 269.585903 -284.675168) (xy 269.633174 -284.68886) (xy 269.677636 -284.709958)
			(xy 269.718139 -284.737914) (xy 269.753632 -284.772006) (xy 269.783197 -284.81135) (xy 269.806068 -284.854927)
			(xy 269.821652 -284.901608) (xy 269.829547 -284.950185) (xy 269.830042 -284.974792) (xy 270.169144 -284.974792)
			(xy 270.173104 -284.925738) (xy 270.184881 -284.877954) (xy 270.204172 -284.832678) (xy 270.230475 -284.791082)
			(xy 270.26311 -284.754245) (xy 270.301231 -284.72312) (xy 270.343852 -284.698513) (xy 270.389868 -284.681061)
			(xy 270.438087 -284.671217) (xy 270.487262 -284.669236) (xy 270.536117 -284.675168) (xy 270.583388 -284.68886)
			(xy 270.62785 -284.709958) (xy 270.668353 -284.737914) (xy 270.703846 -284.772006) (xy 270.733411 -284.81135)
			(xy 270.756282 -284.854927) (xy 270.771866 -284.901608) (xy 270.779761 -284.950185) (xy 270.780256 -284.974792)
			(xy 271.119104 -284.974792) (xy 271.123064 -284.925738) (xy 271.134841 -284.877954) (xy 271.154132 -284.832678)
			(xy 271.180435 -284.791082) (xy 271.21307 -284.754245) (xy 271.251191 -284.72312) (xy 271.293812 -284.698513)
			(xy 271.339828 -284.681061) (xy 271.388047 -284.671217) (xy 271.437222 -284.669236) (xy 271.486077 -284.675168)
			(xy 271.533348 -284.68886) (xy 271.57781 -284.709958) (xy 271.618313 -284.737914) (xy 271.653806 -284.772006)
			(xy 271.683371 -284.81135) (xy 271.706242 -284.854927) (xy 271.721826 -284.901608) (xy 271.729721 -284.950185)
			(xy 271.730216 -284.974792) (xy 272.069064 -284.974792) (xy 272.073024 -284.925738) (xy 272.084801 -284.877954)
			(xy 272.104092 -284.832678) (xy 272.130395 -284.791082) (xy 272.16303 -284.754245) (xy 272.201151 -284.72312)
			(xy 272.243772 -284.698513) (xy 272.289788 -284.681061) (xy 272.338007 -284.671217) (xy 272.387182 -284.669236)
			(xy 272.436037 -284.675168) (xy 272.483308 -284.68886) (xy 272.52777 -284.709958) (xy 272.568273 -284.737914)
			(xy 272.603766 -284.772006) (xy 272.633331 -284.81135) (xy 272.656202 -284.854927) (xy 272.671786 -284.901608)
			(xy 272.679681 -284.950185) (xy 272.680176 -284.974792) (xy 273.019024 -284.974792) (xy 273.022984 -284.925738)
			(xy 273.034761 -284.877954) (xy 273.054052 -284.832678) (xy 273.080355 -284.791082) (xy 273.11299 -284.754245)
			(xy 273.151111 -284.72312) (xy 273.193732 -284.698513) (xy 273.239748 -284.681061) (xy 273.287967 -284.671217)
			(xy 273.337142 -284.669236) (xy 273.385997 -284.675168) (xy 273.433268 -284.68886) (xy 273.47773 -284.709958)
			(xy 273.518233 -284.737914) (xy 273.553726 -284.772006) (xy 273.583291 -284.81135) (xy 273.606162 -284.854927)
			(xy 273.621746 -284.901608) (xy 273.629641 -284.950185) (xy 273.630136 -284.974792) (xy 274.918944 -284.974792)
			(xy 274.922904 -284.925738) (xy 274.934681 -284.877954) (xy 274.953972 -284.832678) (xy 274.980275 -284.791082)
			(xy 275.01291 -284.754245) (xy 275.051031 -284.72312) (xy 275.093652 -284.698513) (xy 275.139668 -284.681061)
			(xy 275.187887 -284.671217) (xy 275.237062 -284.669236) (xy 275.285917 -284.675168) (xy 275.333188 -284.68886)
			(xy 275.37765 -284.709958) (xy 275.418153 -284.737914) (xy 275.453646 -284.772006) (xy 275.483211 -284.81135)
			(xy 275.506082 -284.854927) (xy 275.521666 -284.901608) (xy 275.529561 -284.950185) (xy 275.530056 -284.974792)
			(xy 276.819118 -284.974792) (xy 276.823078 -284.925738) (xy 276.834855 -284.877954) (xy 276.854146 -284.832678)
			(xy 276.880449 -284.791082) (xy 276.913084 -284.754245) (xy 276.951205 -284.72312) (xy 276.993826 -284.698513)
			(xy 277.039842 -284.681061) (xy 277.088061 -284.671217) (xy 277.137236 -284.669236) (xy 277.186091 -284.675168)
			(xy 277.233362 -284.68886) (xy 277.277824 -284.709958) (xy 277.318327 -284.737914) (xy 277.35382 -284.772006)
			(xy 277.383385 -284.81135) (xy 277.406256 -284.854927) (xy 277.42184 -284.901608) (xy 277.429735 -284.950185)
			(xy 277.43023 -284.974792) (xy 277.769078 -284.974792) (xy 277.773038 -284.925738) (xy 277.784815 -284.877954)
			(xy 277.804106 -284.832678) (xy 277.830409 -284.791082) (xy 277.863044 -284.754245) (xy 277.901165 -284.72312)
			(xy 277.943786 -284.698513) (xy 277.989802 -284.681061) (xy 278.038021 -284.671217) (xy 278.087196 -284.669236)
			(xy 278.136051 -284.675168) (xy 278.183322 -284.68886) (xy 278.227784 -284.709958) (xy 278.268287 -284.737914)
			(xy 278.30378 -284.772006) (xy 278.333345 -284.81135) (xy 278.356216 -284.854927) (xy 278.3718 -284.901608)
			(xy 278.379695 -284.950185) (xy 278.38019 -284.974792) (xy 278.719038 -284.974792) (xy 278.722998 -284.925738)
			(xy 278.734775 -284.877954) (xy 278.754066 -284.832678) (xy 278.780369 -284.791082) (xy 278.813004 -284.754245)
			(xy 278.851125 -284.72312) (xy 278.893746 -284.698513) (xy 278.939762 -284.681061) (xy 278.987981 -284.671217)
			(xy 279.037156 -284.669236) (xy 279.086011 -284.675168) (xy 279.133282 -284.68886) (xy 279.177744 -284.709958)
			(xy 279.218247 -284.737914) (xy 279.25374 -284.772006) (xy 279.283305 -284.81135) (xy 279.306176 -284.854927)
			(xy 279.32176 -284.901608) (xy 279.329655 -284.950185) (xy 279.33015 -284.974792) (xy 279.668998 -284.974792)
			(xy 279.672958 -284.925738) (xy 279.684735 -284.877954) (xy 279.704026 -284.832678) (xy 279.730329 -284.791082)
			(xy 279.762964 -284.754245) (xy 279.801085 -284.72312) (xy 279.843706 -284.698513) (xy 279.889722 -284.681061)
			(xy 279.937941 -284.671217) (xy 279.987116 -284.669236) (xy 280.035971 -284.675168) (xy 280.083242 -284.68886)
			(xy 280.127704 -284.709958) (xy 280.168207 -284.737914) (xy 280.2037 -284.772006) (xy 280.233265 -284.81135)
			(xy 280.256136 -284.854927) (xy 280.27172 -284.901608) (xy 280.279615 -284.950185) (xy 280.28011 -284.974792)
			(xy 280.618958 -284.974792) (xy 280.622918 -284.925738) (xy 280.634695 -284.877954) (xy 280.653986 -284.832678)
			(xy 280.680289 -284.791082) (xy 280.712924 -284.754245) (xy 280.751045 -284.72312) (xy 280.793666 -284.698513)
			(xy 280.839682 -284.681061) (xy 280.887901 -284.671217) (xy 280.937076 -284.669236) (xy 280.985931 -284.675168)
			(xy 281.033202 -284.68886) (xy 281.077664 -284.709958) (xy 281.118167 -284.737914) (xy 281.15366 -284.772006)
			(xy 281.183225 -284.81135) (xy 281.206096 -284.854927) (xy 281.22168 -284.901608) (xy 281.229575 -284.950185)
			(xy 281.23007 -284.974792) (xy 281.568918 -284.974792) (xy 281.572878 -284.925738) (xy 281.584655 -284.877954)
			(xy 281.603946 -284.832678) (xy 281.630249 -284.791082) (xy 281.662884 -284.754245) (xy 281.701005 -284.72312)
			(xy 281.743626 -284.698513) (xy 281.789642 -284.681061) (xy 281.837861 -284.671217) (xy 281.887036 -284.669236)
			(xy 281.935891 -284.675168) (xy 281.983162 -284.68886) (xy 282.027624 -284.709958) (xy 282.068127 -284.737914)
			(xy 282.10362 -284.772006) (xy 282.133185 -284.81135) (xy 282.156056 -284.854927) (xy 282.17164 -284.901608)
			(xy 282.179535 -284.950185) (xy 282.18003 -284.974792) (xy 282.519132 -284.974792) (xy 282.523092 -284.925738)
			(xy 282.534869 -284.877954) (xy 282.55416 -284.832678) (xy 282.580463 -284.791082) (xy 282.613098 -284.754245)
			(xy 282.651219 -284.72312) (xy 282.69384 -284.698513) (xy 282.739856 -284.681061) (xy 282.788075 -284.671217)
			(xy 282.83725 -284.669236) (xy 282.886105 -284.675168) (xy 282.933376 -284.68886) (xy 282.977838 -284.709958)
			(xy 283.018341 -284.737914) (xy 283.053834 -284.772006) (xy 283.083399 -284.81135) (xy 283.10627 -284.854927)
			(xy 283.121854 -284.901608) (xy 283.129749 -284.950185) (xy 283.130244 -284.974792) (xy 283.469092 -284.974792)
			(xy 283.473052 -284.925738) (xy 283.484829 -284.877954) (xy 283.50412 -284.832678) (xy 283.530423 -284.791082)
			(xy 283.563058 -284.754245) (xy 283.601179 -284.72312) (xy 283.6438 -284.698513) (xy 283.689816 -284.681061)
			(xy 283.738035 -284.671217) (xy 283.78721 -284.669236) (xy 283.836065 -284.675168) (xy 283.883336 -284.68886)
			(xy 283.927798 -284.709958) (xy 283.968301 -284.737914) (xy 284.003794 -284.772006) (xy 284.033359 -284.81135)
			(xy 284.05623 -284.854927) (xy 284.071814 -284.901608) (xy 284.079709 -284.950185) (xy 284.080204 -284.974792)
			(xy 284.419052 -284.974792) (xy 284.423012 -284.925738) (xy 284.434789 -284.877954) (xy 284.45408 -284.832678)
			(xy 284.480383 -284.791082) (xy 284.513018 -284.754245) (xy 284.551139 -284.72312) (xy 284.59376 -284.698513)
			(xy 284.639776 -284.681061) (xy 284.687995 -284.671217) (xy 284.73717 -284.669236) (xy 284.786025 -284.675168)
			(xy 284.833296 -284.68886) (xy 284.877758 -284.709958) (xy 284.918261 -284.737914) (xy 284.953754 -284.772006)
			(xy 284.983319 -284.81135) (xy 285.00619 -284.854927) (xy 285.021774 -284.901608) (xy 285.029669 -284.950185)
			(xy 285.030164 -284.974792) (xy 285.369012 -284.974792) (xy 285.372972 -284.925738) (xy 285.384749 -284.877954)
			(xy 285.40404 -284.832678) (xy 285.430343 -284.791082) (xy 285.462978 -284.754245) (xy 285.501099 -284.72312)
			(xy 285.54372 -284.698513) (xy 285.589736 -284.681061) (xy 285.637955 -284.671217) (xy 285.68713 -284.669236)
			(xy 285.735985 -284.675168) (xy 285.783256 -284.68886) (xy 285.827718 -284.709958) (xy 285.868221 -284.737914)
			(xy 285.903714 -284.772006) (xy 285.933279 -284.81135) (xy 285.95615 -284.854927) (xy 285.971734 -284.901608)
			(xy 285.979629 -284.950185) (xy 285.980124 -284.974792) (xy 286.318972 -284.974792) (xy 286.322932 -284.925738)
			(xy 286.334709 -284.877954) (xy 286.354 -284.832678) (xy 286.380303 -284.791082) (xy 286.412938 -284.754245)
			(xy 286.451059 -284.72312) (xy 286.49368 -284.698513) (xy 286.539696 -284.681061) (xy 286.587915 -284.671217)
			(xy 286.63709 -284.669236) (xy 286.685945 -284.675168) (xy 286.733216 -284.68886) (xy 286.777678 -284.709958)
			(xy 286.818181 -284.737914) (xy 286.853674 -284.772006) (xy 286.883239 -284.81135) (xy 286.90611 -284.854927)
			(xy 286.921694 -284.901608) (xy 286.929589 -284.950185) (xy 286.930084 -284.974792) (xy 287.268932 -284.974792)
			(xy 287.272892 -284.925738) (xy 287.284669 -284.877954) (xy 287.30396 -284.832678) (xy 287.330263 -284.791082)
			(xy 287.362898 -284.754245) (xy 287.401019 -284.72312) (xy 287.44364 -284.698513) (xy 287.489656 -284.681061)
			(xy 287.537875 -284.671217) (xy 287.58705 -284.669236) (xy 287.635905 -284.675168) (xy 287.683176 -284.68886)
			(xy 287.727638 -284.709958) (xy 287.768141 -284.737914) (xy 287.803634 -284.772006) (xy 287.833199 -284.81135)
			(xy 287.85607 -284.854927) (xy 287.871654 -284.901608) (xy 287.879549 -284.950185) (xy 287.880044 -284.974792)
			(xy 288.218892 -284.974792) (xy 288.222852 -284.925738) (xy 288.234629 -284.877954) (xy 288.25392 -284.832678)
			(xy 288.280223 -284.791082) (xy 288.312858 -284.754245) (xy 288.350979 -284.72312) (xy 288.3936 -284.698513)
			(xy 288.439616 -284.681061) (xy 288.487835 -284.671217) (xy 288.53701 -284.669236) (xy 288.585865 -284.675168)
			(xy 288.633136 -284.68886) (xy 288.677598 -284.709958) (xy 288.718101 -284.737914) (xy 288.753594 -284.772006)
			(xy 288.783159 -284.81135) (xy 288.80603 -284.854927) (xy 288.821614 -284.901608) (xy 288.829509 -284.950185)
			(xy 288.830004 -284.974792) (xy 289.169106 -284.974792) (xy 289.173066 -284.925738) (xy 289.184843 -284.877954)
			(xy 289.204134 -284.832678) (xy 289.230437 -284.791082) (xy 289.263072 -284.754245) (xy 289.301193 -284.72312)
			(xy 289.343814 -284.698513) (xy 289.38983 -284.681061) (xy 289.438049 -284.671217) (xy 289.487224 -284.669236)
			(xy 289.536079 -284.675168) (xy 289.58335 -284.68886) (xy 289.627812 -284.709958) (xy 289.668315 -284.737914)
			(xy 289.703808 -284.772006) (xy 289.733373 -284.81135) (xy 289.756244 -284.854927) (xy 289.771828 -284.901608)
			(xy 289.779723 -284.950185) (xy 289.780218 -284.974792) (xy 290.119066 -284.974792) (xy 290.123026 -284.925738)
			(xy 290.134803 -284.877954) (xy 290.154094 -284.832678) (xy 290.180397 -284.791082) (xy 290.213032 -284.754245)
			(xy 290.251153 -284.72312) (xy 290.293774 -284.698513) (xy 290.33979 -284.681061) (xy 290.388009 -284.671217)
			(xy 290.437184 -284.669236) (xy 290.486039 -284.675168) (xy 290.53331 -284.68886) (xy 290.577772 -284.709958)
			(xy 290.618275 -284.737914) (xy 290.653768 -284.772006) (xy 290.683333 -284.81135) (xy 290.706204 -284.854927)
			(xy 290.721788 -284.901608) (xy 290.729683 -284.950185) (xy 290.730178 -284.974792) (xy 292.018986 -284.974792)
			(xy 292.022946 -284.925738) (xy 292.034723 -284.877954) (xy 292.054014 -284.832678) (xy 292.080317 -284.791082)
			(xy 292.112952 -284.754245) (xy 292.151073 -284.72312) (xy 292.193694 -284.698513) (xy 292.23971 -284.681061)
			(xy 292.287929 -284.671217) (xy 292.337104 -284.669236) (xy 292.385959 -284.675168) (xy 292.43323 -284.68886)
			(xy 292.477692 -284.709958) (xy 292.518195 -284.737914) (xy 292.553688 -284.772006) (xy 292.583253 -284.81135)
			(xy 292.606124 -284.854927) (xy 292.621708 -284.901608) (xy 292.629603 -284.950185) (xy 292.630098 -284.974792)
			(xy 292.968946 -284.974792) (xy 292.972906 -284.925738) (xy 292.984683 -284.877954) (xy 293.003974 -284.832678)
			(xy 293.030277 -284.791082) (xy 293.062912 -284.754245) (xy 293.101033 -284.72312) (xy 293.143654 -284.698513)
			(xy 293.18967 -284.681061) (xy 293.237889 -284.671217) (xy 293.287064 -284.669236) (xy 293.335919 -284.675168)
			(xy 293.38319 -284.68886) (xy 293.427652 -284.709958) (xy 293.468155 -284.737914) (xy 293.503648 -284.772006)
			(xy 293.533213 -284.81135) (xy 293.556084 -284.854927) (xy 293.571668 -284.901608) (xy 293.579563 -284.950185)
			(xy 293.580058 -284.974792) (xy 293.918906 -284.974792) (xy 293.922866 -284.925738) (xy 293.934643 -284.877954)
			(xy 293.953934 -284.832678) (xy 293.980237 -284.791082) (xy 294.012872 -284.754245) (xy 294.050993 -284.72312)
			(xy 294.093614 -284.698513) (xy 294.13963 -284.681061) (xy 294.187849 -284.671217) (xy 294.237024 -284.669236)
			(xy 294.285879 -284.675168) (xy 294.33315 -284.68886) (xy 294.377612 -284.709958) (xy 294.418115 -284.737914)
			(xy 294.453608 -284.772006) (xy 294.483173 -284.81135) (xy 294.506044 -284.854927) (xy 294.521628 -284.901608)
			(xy 294.529523 -284.950185) (xy 294.530018 -284.974792) (xy 294.86912 -284.974792) (xy 294.87308 -284.925738)
			(xy 294.884857 -284.877954) (xy 294.904148 -284.832678) (xy 294.930451 -284.791082) (xy 294.963086 -284.754245)
			(xy 295.001207 -284.72312) (xy 295.043828 -284.698513) (xy 295.089844 -284.681061) (xy 295.138063 -284.671217)
			(xy 295.187238 -284.669236) (xy 295.236093 -284.675168) (xy 295.283364 -284.68886) (xy 295.327826 -284.709958)
			(xy 295.368329 -284.737914) (xy 295.403822 -284.772006) (xy 295.433387 -284.81135) (xy 295.456258 -284.854927)
			(xy 295.471842 -284.901608) (xy 295.479737 -284.950185) (xy 295.480232 -284.974792) (xy 295.81908 -284.974792)
			(xy 295.82304 -284.925738) (xy 295.834817 -284.877954) (xy 295.854108 -284.832678) (xy 295.880411 -284.791082)
			(xy 295.913046 -284.754245) (xy 295.951167 -284.72312) (xy 295.993788 -284.698513) (xy 296.039804 -284.681061)
			(xy 296.088023 -284.671217) (xy 296.137198 -284.669236) (xy 296.186053 -284.675168) (xy 296.233324 -284.68886)
			(xy 296.277786 -284.709958) (xy 296.318289 -284.737914) (xy 296.353782 -284.772006) (xy 296.383347 -284.81135)
			(xy 296.406218 -284.854927) (xy 296.421802 -284.901608) (xy 296.429697 -284.950185) (xy 296.430192 -284.974792)
			(xy 296.76904 -284.974792) (xy 296.773 -284.925738) (xy 296.784777 -284.877954) (xy 296.804068 -284.832678)
			(xy 296.830371 -284.791082) (xy 296.863006 -284.754245) (xy 296.901127 -284.72312) (xy 296.943748 -284.698513)
			(xy 296.989764 -284.681061) (xy 297.037983 -284.671217) (xy 297.087158 -284.669236) (xy 297.136013 -284.675168)
			(xy 297.183284 -284.68886) (xy 297.227746 -284.709958) (xy 297.268249 -284.737914) (xy 297.303742 -284.772006)
			(xy 297.333307 -284.81135) (xy 297.356178 -284.854927) (xy 297.371762 -284.901608) (xy 297.379657 -284.950185)
			(xy 297.380152 -284.974792) (xy 297.719 -284.974792) (xy 297.72296 -284.925738) (xy 297.734737 -284.877954)
			(xy 297.754028 -284.832678) (xy 297.780331 -284.791082) (xy 297.812966 -284.754245) (xy 297.851087 -284.72312)
			(xy 297.893708 -284.698513) (xy 297.939724 -284.681061) (xy 297.987943 -284.671217) (xy 298.037118 -284.669236)
			(xy 298.085973 -284.675168) (xy 298.133244 -284.68886) (xy 298.177706 -284.709958) (xy 298.218209 -284.737914)
			(xy 298.253702 -284.772006) (xy 298.283267 -284.81135) (xy 298.306138 -284.854927) (xy 298.321722 -284.901608)
			(xy 298.329617 -284.950185) (xy 298.330112 -284.974792) (xy 298.66896 -284.974792) (xy 298.67292 -284.925738)
			(xy 298.684697 -284.877954) (xy 298.703988 -284.832678) (xy 298.730291 -284.791082) (xy 298.762926 -284.754245)
			(xy 298.801047 -284.72312) (xy 298.843668 -284.698513) (xy 298.889684 -284.681061) (xy 298.937903 -284.671217)
			(xy 298.987078 -284.669236) (xy 299.035933 -284.675168) (xy 299.083204 -284.68886) (xy 299.127666 -284.709958)
			(xy 299.168169 -284.737914) (xy 299.203662 -284.772006) (xy 299.233227 -284.81135) (xy 299.256098 -284.854927)
			(xy 299.271682 -284.901608) (xy 299.279577 -284.950185) (xy 299.280072 -284.974792) (xy 299.61892 -284.974792)
			(xy 299.62288 -284.925738) (xy 299.634657 -284.877954) (xy 299.653948 -284.832678) (xy 299.680251 -284.791082)
			(xy 299.712886 -284.754245) (xy 299.751007 -284.72312) (xy 299.793628 -284.698513) (xy 299.839644 -284.681061)
			(xy 299.887863 -284.671217) (xy 299.937038 -284.669236) (xy 299.985893 -284.675168) (xy 300.033164 -284.68886)
			(xy 300.077626 -284.709958) (xy 300.118129 -284.737914) (xy 300.153622 -284.772006) (xy 300.183187 -284.81135)
			(xy 300.206058 -284.854927) (xy 300.221642 -284.901608) (xy 300.229537 -284.950185) (xy 300.230032 -284.974792)
			(xy 300.56888 -284.974792) (xy 300.57284 -284.925738) (xy 300.584617 -284.877954) (xy 300.603908 -284.832678)
			(xy 300.630211 -284.791082) (xy 300.662846 -284.754245) (xy 300.700967 -284.72312) (xy 300.743588 -284.698513)
			(xy 300.789604 -284.681061) (xy 300.837823 -284.671217) (xy 300.886998 -284.669236) (xy 300.935853 -284.675168)
			(xy 300.983124 -284.68886) (xy 301.027586 -284.709958) (xy 301.068089 -284.737914) (xy 301.103582 -284.772006)
			(xy 301.133147 -284.81135) (xy 301.156018 -284.854927) (xy 301.171602 -284.901608) (xy 301.179497 -284.950185)
			(xy 301.179992 -284.974792) (xy 301.519094 -284.974792) (xy 301.523054 -284.925738) (xy 301.534831 -284.877954)
			(xy 301.554122 -284.832678) (xy 301.580425 -284.791082) (xy 301.61306 -284.754245) (xy 301.651181 -284.72312)
			(xy 301.693802 -284.698513) (xy 301.739818 -284.681061) (xy 301.788037 -284.671217) (xy 301.837212 -284.669236)
			(xy 301.886067 -284.675168) (xy 301.933338 -284.68886) (xy 301.9778 -284.709958) (xy 302.018303 -284.737914)
			(xy 302.053796 -284.772006) (xy 302.083361 -284.81135) (xy 302.106232 -284.854927) (xy 302.121816 -284.901608)
			(xy 302.129711 -284.950185) (xy 302.130206 -284.974792) (xy 302.469054 -284.974792) (xy 302.473014 -284.925738)
			(xy 302.484791 -284.877954) (xy 302.504082 -284.832678) (xy 302.530385 -284.791082) (xy 302.56302 -284.754245)
			(xy 302.601141 -284.72312) (xy 302.643762 -284.698513) (xy 302.689778 -284.681061) (xy 302.737997 -284.671217)
			(xy 302.787172 -284.669236) (xy 302.836027 -284.675168) (xy 302.883298 -284.68886) (xy 302.92776 -284.709958)
			(xy 302.968263 -284.737914) (xy 303.003756 -284.772006) (xy 303.033321 -284.81135) (xy 303.056192 -284.854927)
			(xy 303.071776 -284.901608) (xy 303.079671 -284.950185) (xy 303.080166 -284.974792) (xy 303.079671 -284.999399)
			(xy 303.071776 -285.047976) (xy 303.056192 -285.094657) (xy 303.033321 -285.138234) (xy 303.003756 -285.177578)
			(xy 302.968263 -285.21167) (xy 302.92776 -285.239626) (xy 302.883298 -285.260724) (xy 302.836027 -285.274416)
			(xy 302.787172 -285.280348) (xy 302.737997 -285.278367) (xy 302.689778 -285.268523) (xy 302.643762 -285.251071)
			(xy 302.601141 -285.226464) (xy 302.56302 -285.195339) (xy 302.530385 -285.158502) (xy 302.504082 -285.116906)
			(xy 302.484791 -285.07163) (xy 302.473014 -285.023846) (xy 302.469054 -284.974792) (xy 302.130206 -284.974792)
			(xy 302.129711 -284.999399) (xy 302.121816 -285.047976) (xy 302.106232 -285.094657) (xy 302.083361 -285.138234)
			(xy 302.053796 -285.177578) (xy 302.018303 -285.21167) (xy 301.9778 -285.239626) (xy 301.933338 -285.260724)
			(xy 301.886067 -285.274416) (xy 301.837212 -285.280348) (xy 301.788037 -285.278367) (xy 301.739818 -285.268523)
			(xy 301.693802 -285.251071) (xy 301.651181 -285.226464) (xy 301.61306 -285.195339) (xy 301.580425 -285.158502)
			(xy 301.554122 -285.116906) (xy 301.534831 -285.07163) (xy 301.523054 -285.023846) (xy 301.519094 -284.974792)
			(xy 301.179992 -284.974792) (xy 301.179497 -284.999399) (xy 301.171602 -285.047976) (xy 301.156018 -285.094657)
			(xy 301.133147 -285.138234) (xy 301.103582 -285.177578) (xy 301.068089 -285.21167) (xy 301.027586 -285.239626)
			(xy 300.983124 -285.260724) (xy 300.935853 -285.274416) (xy 300.886998 -285.280348) (xy 300.837823 -285.278367)
			(xy 300.789604 -285.268523) (xy 300.743588 -285.251071) (xy 300.700967 -285.226464) (xy 300.662846 -285.195339)
			(xy 300.630211 -285.158502) (xy 300.603908 -285.116906) (xy 300.584617 -285.07163) (xy 300.57284 -285.023846)
			(xy 300.56888 -284.974792) (xy 300.230032 -284.974792) (xy 300.229537 -284.999399) (xy 300.221642 -285.047976)
			(xy 300.206058 -285.094657) (xy 300.183187 -285.138234) (xy 300.153622 -285.177578) (xy 300.118129 -285.21167)
			(xy 300.077626 -285.239626) (xy 300.033164 -285.260724) (xy 299.985893 -285.274416) (xy 299.937038 -285.280348)
			(xy 299.887863 -285.278367) (xy 299.839644 -285.268523) (xy 299.793628 -285.251071) (xy 299.751007 -285.226464)
			(xy 299.712886 -285.195339) (xy 299.680251 -285.158502) (xy 299.653948 -285.116906) (xy 299.634657 -285.07163)
			(xy 299.62288 -285.023846) (xy 299.61892 -284.974792) (xy 299.280072 -284.974792) (xy 299.279577 -284.999399)
			(xy 299.271682 -285.047976) (xy 299.256098 -285.094657) (xy 299.233227 -285.138234) (xy 299.203662 -285.177578)
			(xy 299.168169 -285.21167) (xy 299.127666 -285.239626) (xy 299.083204 -285.260724) (xy 299.035933 -285.274416)
			(xy 298.987078 -285.280348) (xy 298.937903 -285.278367) (xy 298.889684 -285.268523) (xy 298.843668 -285.251071)
			(xy 298.801047 -285.226464) (xy 298.762926 -285.195339) (xy 298.730291 -285.158502) (xy 298.703988 -285.116906)
			(xy 298.684697 -285.07163) (xy 298.67292 -285.023846) (xy 298.66896 -284.974792) (xy 298.330112 -284.974792)
			(xy 298.329617 -284.999399) (xy 298.321722 -285.047976) (xy 298.306138 -285.094657) (xy 298.283267 -285.138234)
			(xy 298.253702 -285.177578) (xy 298.218209 -285.21167) (xy 298.177706 -285.239626) (xy 298.133244 -285.260724)
			(xy 298.085973 -285.274416) (xy 298.037118 -285.280348) (xy 297.987943 -285.278367) (xy 297.939724 -285.268523)
			(xy 297.893708 -285.251071) (xy 297.851087 -285.226464) (xy 297.812966 -285.195339) (xy 297.780331 -285.158502)
			(xy 297.754028 -285.116906) (xy 297.734737 -285.07163) (xy 297.72296 -285.023846) (xy 297.719 -284.974792)
			(xy 297.380152 -284.974792) (xy 297.379657 -284.999399) (xy 297.371762 -285.047976) (xy 297.356178 -285.094657)
			(xy 297.333307 -285.138234) (xy 297.303742 -285.177578) (xy 297.268249 -285.21167) (xy 297.227746 -285.239626)
			(xy 297.183284 -285.260724) (xy 297.136013 -285.274416) (xy 297.087158 -285.280348) (xy 297.037983 -285.278367)
			(xy 296.989764 -285.268523) (xy 296.943748 -285.251071) (xy 296.901127 -285.226464) (xy 296.863006 -285.195339)
			(xy 296.830371 -285.158502) (xy 296.804068 -285.116906) (xy 296.784777 -285.07163) (xy 296.773 -285.023846)
			(xy 296.76904 -284.974792) (xy 296.430192 -284.974792) (xy 296.429697 -284.999399) (xy 296.421802 -285.047976)
			(xy 296.406218 -285.094657) (xy 296.383347 -285.138234) (xy 296.353782 -285.177578) (xy 296.318289 -285.21167)
			(xy 296.277786 -285.239626) (xy 296.233324 -285.260724) (xy 296.186053 -285.274416) (xy 296.137198 -285.280348)
			(xy 296.088023 -285.278367) (xy 296.039804 -285.268523) (xy 295.993788 -285.251071) (xy 295.951167 -285.226464)
			(xy 295.913046 -285.195339) (xy 295.880411 -285.158502) (xy 295.854108 -285.116906) (xy 295.834817 -285.07163)
			(xy 295.82304 -285.023846) (xy 295.81908 -284.974792) (xy 295.480232 -284.974792) (xy 295.479737 -284.999399)
			(xy 295.471842 -285.047976) (xy 295.456258 -285.094657) (xy 295.433387 -285.138234) (xy 295.403822 -285.177578)
			(xy 295.368329 -285.21167) (xy 295.327826 -285.239626) (xy 295.283364 -285.260724) (xy 295.236093 -285.274416)
			(xy 295.187238 -285.280348) (xy 295.138063 -285.278367) (xy 295.089844 -285.268523) (xy 295.043828 -285.251071)
			(xy 295.001207 -285.226464) (xy 294.963086 -285.195339) (xy 294.930451 -285.158502) (xy 294.904148 -285.116906)
			(xy 294.884857 -285.07163) (xy 294.87308 -285.023846) (xy 294.86912 -284.974792) (xy 294.530018 -284.974792)
			(xy 294.529523 -284.999399) (xy 294.521628 -285.047976) (xy 294.506044 -285.094657) (xy 294.483173 -285.138234)
			(xy 294.453608 -285.177578) (xy 294.418115 -285.21167) (xy 294.377612 -285.239626) (xy 294.33315 -285.260724)
			(xy 294.285879 -285.274416) (xy 294.237024 -285.280348) (xy 294.187849 -285.278367) (xy 294.13963 -285.268523)
			(xy 294.093614 -285.251071) (xy 294.050993 -285.226464) (xy 294.012872 -285.195339) (xy 293.980237 -285.158502)
			(xy 293.953934 -285.116906) (xy 293.934643 -285.07163) (xy 293.922866 -285.023846) (xy 293.918906 -284.974792)
			(xy 293.580058 -284.974792) (xy 293.579563 -284.999399) (xy 293.571668 -285.047976) (xy 293.556084 -285.094657)
			(xy 293.533213 -285.138234) (xy 293.503648 -285.177578) (xy 293.468155 -285.21167) (xy 293.427652 -285.239626)
			(xy 293.38319 -285.260724) (xy 293.335919 -285.274416) (xy 293.287064 -285.280348) (xy 293.237889 -285.278367)
			(xy 293.18967 -285.268523) (xy 293.143654 -285.251071) (xy 293.101033 -285.226464) (xy 293.062912 -285.195339)
			(xy 293.030277 -285.158502) (xy 293.003974 -285.116906) (xy 292.984683 -285.07163) (xy 292.972906 -285.023846)
			(xy 292.968946 -284.974792) (xy 292.630098 -284.974792) (xy 292.629603 -284.999399) (xy 292.621708 -285.047976)
			(xy 292.606124 -285.094657) (xy 292.583253 -285.138234) (xy 292.553688 -285.177578) (xy 292.518195 -285.21167)
			(xy 292.477692 -285.239626) (xy 292.43323 -285.260724) (xy 292.385959 -285.274416) (xy 292.337104 -285.280348)
			(xy 292.287929 -285.278367) (xy 292.23971 -285.268523) (xy 292.193694 -285.251071) (xy 292.151073 -285.226464)
			(xy 292.112952 -285.195339) (xy 292.080317 -285.158502) (xy 292.054014 -285.116906) (xy 292.034723 -285.07163)
			(xy 292.022946 -285.023846) (xy 292.018986 -284.974792) (xy 290.730178 -284.974792) (xy 290.729683 -284.999399)
			(xy 290.721788 -285.047976) (xy 290.706204 -285.094657) (xy 290.683333 -285.138234) (xy 290.653768 -285.177578)
			(xy 290.618275 -285.21167) (xy 290.577772 -285.239626) (xy 290.53331 -285.260724) (xy 290.486039 -285.274416)
			(xy 290.437184 -285.280348) (xy 290.388009 -285.278367) (xy 290.33979 -285.268523) (xy 290.293774 -285.251071)
			(xy 290.251153 -285.226464) (xy 290.213032 -285.195339) (xy 290.180397 -285.158502) (xy 290.154094 -285.116906)
			(xy 290.134803 -285.07163) (xy 290.123026 -285.023846) (xy 290.119066 -284.974792) (xy 289.780218 -284.974792)
			(xy 289.779723 -284.999399) (xy 289.771828 -285.047976) (xy 289.756244 -285.094657) (xy 289.733373 -285.138234)
			(xy 289.703808 -285.177578) (xy 289.668315 -285.21167) (xy 289.627812 -285.239626) (xy 289.58335 -285.260724)
			(xy 289.536079 -285.274416) (xy 289.487224 -285.280348) (xy 289.438049 -285.278367) (xy 289.38983 -285.268523)
			(xy 289.343814 -285.251071) (xy 289.301193 -285.226464) (xy 289.263072 -285.195339) (xy 289.230437 -285.158502)
			(xy 289.204134 -285.116906) (xy 289.184843 -285.07163) (xy 289.173066 -285.023846) (xy 289.169106 -284.974792)
			(xy 288.830004 -284.974792) (xy 288.829509 -284.999399) (xy 288.821614 -285.047976) (xy 288.80603 -285.094657)
			(xy 288.783159 -285.138234) (xy 288.753594 -285.177578) (xy 288.718101 -285.21167) (xy 288.677598 -285.239626)
			(xy 288.633136 -285.260724) (xy 288.585865 -285.274416) (xy 288.53701 -285.280348) (xy 288.487835 -285.278367)
			(xy 288.439616 -285.268523) (xy 288.3936 -285.251071) (xy 288.350979 -285.226464) (xy 288.312858 -285.195339)
			(xy 288.280223 -285.158502) (xy 288.25392 -285.116906) (xy 288.234629 -285.07163) (xy 288.222852 -285.023846)
			(xy 288.218892 -284.974792) (xy 287.880044 -284.974792) (xy 287.879549 -284.999399) (xy 287.871654 -285.047976)
			(xy 287.85607 -285.094657) (xy 287.833199 -285.138234) (xy 287.803634 -285.177578) (xy 287.768141 -285.21167)
			(xy 287.727638 -285.239626) (xy 287.683176 -285.260724) (xy 287.635905 -285.274416) (xy 287.58705 -285.280348)
			(xy 287.537875 -285.278367) (xy 287.489656 -285.268523) (xy 287.44364 -285.251071) (xy 287.401019 -285.226464)
			(xy 287.362898 -285.195339) (xy 287.330263 -285.158502) (xy 287.30396 -285.116906) (xy 287.284669 -285.07163)
			(xy 287.272892 -285.023846) (xy 287.268932 -284.974792) (xy 286.930084 -284.974792) (xy 286.929589 -284.999399)
			(xy 286.921694 -285.047976) (xy 286.90611 -285.094657) (xy 286.883239 -285.138234) (xy 286.853674 -285.177578)
			(xy 286.818181 -285.21167) (xy 286.777678 -285.239626) (xy 286.733216 -285.260724) (xy 286.685945 -285.274416)
			(xy 286.63709 -285.280348) (xy 286.587915 -285.278367) (xy 286.539696 -285.268523) (xy 286.49368 -285.251071)
			(xy 286.451059 -285.226464) (xy 286.412938 -285.195339) (xy 286.380303 -285.158502) (xy 286.354 -285.116906)
			(xy 286.334709 -285.07163) (xy 286.322932 -285.023846) (xy 286.318972 -284.974792) (xy 285.980124 -284.974792)
			(xy 285.979629 -284.999399) (xy 285.971734 -285.047976) (xy 285.95615 -285.094657) (xy 285.933279 -285.138234)
			(xy 285.903714 -285.177578) (xy 285.868221 -285.21167) (xy 285.827718 -285.239626) (xy 285.783256 -285.260724)
			(xy 285.735985 -285.274416) (xy 285.68713 -285.280348) (xy 285.637955 -285.278367) (xy 285.589736 -285.268523)
			(xy 285.54372 -285.251071) (xy 285.501099 -285.226464) (xy 285.462978 -285.195339) (xy 285.430343 -285.158502)
			(xy 285.40404 -285.116906) (xy 285.384749 -285.07163) (xy 285.372972 -285.023846) (xy 285.369012 -284.974792)
			(xy 285.030164 -284.974792) (xy 285.029669 -284.999399) (xy 285.021774 -285.047976) (xy 285.00619 -285.094657)
			(xy 284.983319 -285.138234) (xy 284.953754 -285.177578) (xy 284.918261 -285.21167) (xy 284.877758 -285.239626)
			(xy 284.833296 -285.260724) (xy 284.786025 -285.274416) (xy 284.73717 -285.280348) (xy 284.687995 -285.278367)
			(xy 284.639776 -285.268523) (xy 284.59376 -285.251071) (xy 284.551139 -285.226464) (xy 284.513018 -285.195339)
			(xy 284.480383 -285.158502) (xy 284.45408 -285.116906) (xy 284.434789 -285.07163) (xy 284.423012 -285.023846)
			(xy 284.419052 -284.974792) (xy 284.080204 -284.974792) (xy 284.079709 -284.999399) (xy 284.071814 -285.047976)
			(xy 284.05623 -285.094657) (xy 284.033359 -285.138234) (xy 284.003794 -285.177578) (xy 283.968301 -285.21167)
			(xy 283.927798 -285.239626) (xy 283.883336 -285.260724) (xy 283.836065 -285.274416) (xy 283.78721 -285.280348)
			(xy 283.738035 -285.278367) (xy 283.689816 -285.268523) (xy 283.6438 -285.251071) (xy 283.601179 -285.226464)
			(xy 283.563058 -285.195339) (xy 283.530423 -285.158502) (xy 283.50412 -285.116906) (xy 283.484829 -285.07163)
			(xy 283.473052 -285.023846) (xy 283.469092 -284.974792) (xy 283.130244 -284.974792) (xy 283.129749 -284.999399)
			(xy 283.121854 -285.047976) (xy 283.10627 -285.094657) (xy 283.083399 -285.138234) (xy 283.053834 -285.177578)
			(xy 283.018341 -285.21167) (xy 282.977838 -285.239626) (xy 282.933376 -285.260724) (xy 282.886105 -285.274416)
			(xy 282.83725 -285.280348) (xy 282.788075 -285.278367) (xy 282.739856 -285.268523) (xy 282.69384 -285.251071)
			(xy 282.651219 -285.226464) (xy 282.613098 -285.195339) (xy 282.580463 -285.158502) (xy 282.55416 -285.116906)
			(xy 282.534869 -285.07163) (xy 282.523092 -285.023846) (xy 282.519132 -284.974792) (xy 282.18003 -284.974792)
			(xy 282.179535 -284.999399) (xy 282.17164 -285.047976) (xy 282.156056 -285.094657) (xy 282.133185 -285.138234)
			(xy 282.10362 -285.177578) (xy 282.068127 -285.21167) (xy 282.027624 -285.239626) (xy 281.983162 -285.260724)
			(xy 281.935891 -285.274416) (xy 281.887036 -285.280348) (xy 281.837861 -285.278367) (xy 281.789642 -285.268523)
			(xy 281.743626 -285.251071) (xy 281.701005 -285.226464) (xy 281.662884 -285.195339) (xy 281.630249 -285.158502)
			(xy 281.603946 -285.116906) (xy 281.584655 -285.07163) (xy 281.572878 -285.023846) (xy 281.568918 -284.974792)
			(xy 281.23007 -284.974792) (xy 281.229575 -284.999399) (xy 281.22168 -285.047976) (xy 281.206096 -285.094657)
			(xy 281.183225 -285.138234) (xy 281.15366 -285.177578) (xy 281.118167 -285.21167) (xy 281.077664 -285.239626)
			(xy 281.033202 -285.260724) (xy 280.985931 -285.274416) (xy 280.937076 -285.280348) (xy 280.887901 -285.278367)
			(xy 280.839682 -285.268523) (xy 280.793666 -285.251071) (xy 280.751045 -285.226464) (xy 280.712924 -285.195339)
			(xy 280.680289 -285.158502) (xy 280.653986 -285.116906) (xy 280.634695 -285.07163) (xy 280.622918 -285.023846)
			(xy 280.618958 -284.974792) (xy 280.28011 -284.974792) (xy 280.279615 -284.999399) (xy 280.27172 -285.047976)
			(xy 280.256136 -285.094657) (xy 280.233265 -285.138234) (xy 280.2037 -285.177578) (xy 280.168207 -285.21167)
			(xy 280.127704 -285.239626) (xy 280.083242 -285.260724) (xy 280.035971 -285.274416) (xy 279.987116 -285.280348)
			(xy 279.937941 -285.278367) (xy 279.889722 -285.268523) (xy 279.843706 -285.251071) (xy 279.801085 -285.226464)
			(xy 279.762964 -285.195339) (xy 279.730329 -285.158502) (xy 279.704026 -285.116906) (xy 279.684735 -285.07163)
			(xy 279.672958 -285.023846) (xy 279.668998 -284.974792) (xy 279.33015 -284.974792) (xy 279.329655 -284.999399)
			(xy 279.32176 -285.047976) (xy 279.306176 -285.094657) (xy 279.283305 -285.138234) (xy 279.25374 -285.177578)
			(xy 279.218247 -285.21167) (xy 279.177744 -285.239626) (xy 279.133282 -285.260724) (xy 279.086011 -285.274416)
			(xy 279.037156 -285.280348) (xy 278.987981 -285.278367) (xy 278.939762 -285.268523) (xy 278.893746 -285.251071)
			(xy 278.851125 -285.226464) (xy 278.813004 -285.195339) (xy 278.780369 -285.158502) (xy 278.754066 -285.116906)
			(xy 278.734775 -285.07163) (xy 278.722998 -285.023846) (xy 278.719038 -284.974792) (xy 278.38019 -284.974792)
			(xy 278.379695 -284.999399) (xy 278.3718 -285.047976) (xy 278.356216 -285.094657) (xy 278.333345 -285.138234)
			(xy 278.30378 -285.177578) (xy 278.268287 -285.21167) (xy 278.227784 -285.239626) (xy 278.183322 -285.260724)
			(xy 278.136051 -285.274416) (xy 278.087196 -285.280348) (xy 278.038021 -285.278367) (xy 277.989802 -285.268523)
			(xy 277.943786 -285.251071) (xy 277.901165 -285.226464) (xy 277.863044 -285.195339) (xy 277.830409 -285.158502)
			(xy 277.804106 -285.116906) (xy 277.784815 -285.07163) (xy 277.773038 -285.023846) (xy 277.769078 -284.974792)
			(xy 277.43023 -284.974792) (xy 277.429735 -284.999399) (xy 277.42184 -285.047976) (xy 277.406256 -285.094657)
			(xy 277.383385 -285.138234) (xy 277.35382 -285.177578) (xy 277.318327 -285.21167) (xy 277.277824 -285.239626)
			(xy 277.233362 -285.260724) (xy 277.186091 -285.274416) (xy 277.137236 -285.280348) (xy 277.088061 -285.278367)
			(xy 277.039842 -285.268523) (xy 276.993826 -285.251071) (xy 276.951205 -285.226464) (xy 276.913084 -285.195339)
			(xy 276.880449 -285.158502) (xy 276.854146 -285.116906) (xy 276.834855 -285.07163) (xy 276.823078 -285.023846)
			(xy 276.819118 -284.974792) (xy 275.530056 -284.974792) (xy 275.529561 -284.999399) (xy 275.521666 -285.047976)
			(xy 275.506082 -285.094657) (xy 275.483211 -285.138234) (xy 275.453646 -285.177578) (xy 275.418153 -285.21167)
			(xy 275.37765 -285.239626) (xy 275.333188 -285.260724) (xy 275.285917 -285.274416) (xy 275.237062 -285.280348)
			(xy 275.187887 -285.278367) (xy 275.139668 -285.268523) (xy 275.093652 -285.251071) (xy 275.051031 -285.226464)
			(xy 275.01291 -285.195339) (xy 274.980275 -285.158502) (xy 274.953972 -285.116906) (xy 274.934681 -285.07163)
			(xy 274.922904 -285.023846) (xy 274.918944 -284.974792) (xy 273.630136 -284.974792) (xy 273.629641 -284.999399)
			(xy 273.621746 -285.047976) (xy 273.606162 -285.094657) (xy 273.583291 -285.138234) (xy 273.553726 -285.177578)
			(xy 273.518233 -285.21167) (xy 273.47773 -285.239626) (xy 273.433268 -285.260724) (xy 273.385997 -285.274416)
			(xy 273.337142 -285.280348) (xy 273.287967 -285.278367) (xy 273.239748 -285.268523) (xy 273.193732 -285.251071)
			(xy 273.151111 -285.226464) (xy 273.11299 -285.195339) (xy 273.080355 -285.158502) (xy 273.054052 -285.116906)
			(xy 273.034761 -285.07163) (xy 273.022984 -285.023846) (xy 273.019024 -284.974792) (xy 272.680176 -284.974792)
			(xy 272.679681 -284.999399) (xy 272.671786 -285.047976) (xy 272.656202 -285.094657) (xy 272.633331 -285.138234)
			(xy 272.603766 -285.177578) (xy 272.568273 -285.21167) (xy 272.52777 -285.239626) (xy 272.483308 -285.260724)
			(xy 272.436037 -285.274416) (xy 272.387182 -285.280348) (xy 272.338007 -285.278367) (xy 272.289788 -285.268523)
			(xy 272.243772 -285.251071) (xy 272.201151 -285.226464) (xy 272.16303 -285.195339) (xy 272.130395 -285.158502)
			(xy 272.104092 -285.116906) (xy 272.084801 -285.07163) (xy 272.073024 -285.023846) (xy 272.069064 -284.974792)
			(xy 271.730216 -284.974792) (xy 271.729721 -284.999399) (xy 271.721826 -285.047976) (xy 271.706242 -285.094657)
			(xy 271.683371 -285.138234) (xy 271.653806 -285.177578) (xy 271.618313 -285.21167) (xy 271.57781 -285.239626)
			(xy 271.533348 -285.260724) (xy 271.486077 -285.274416) (xy 271.437222 -285.280348) (xy 271.388047 -285.278367)
			(xy 271.339828 -285.268523) (xy 271.293812 -285.251071) (xy 271.251191 -285.226464) (xy 271.21307 -285.195339)
			(xy 271.180435 -285.158502) (xy 271.154132 -285.116906) (xy 271.134841 -285.07163) (xy 271.123064 -285.023846)
			(xy 271.119104 -284.974792) (xy 270.780256 -284.974792) (xy 270.779761 -284.999399) (xy 270.771866 -285.047976)
			(xy 270.756282 -285.094657) (xy 270.733411 -285.138234) (xy 270.703846 -285.177578) (xy 270.668353 -285.21167)
			(xy 270.62785 -285.239626) (xy 270.583388 -285.260724) (xy 270.536117 -285.274416) (xy 270.487262 -285.280348)
			(xy 270.438087 -285.278367) (xy 270.389868 -285.268523) (xy 270.343852 -285.251071) (xy 270.301231 -285.226464)
			(xy 270.26311 -285.195339) (xy 270.230475 -285.158502) (xy 270.204172 -285.116906) (xy 270.184881 -285.07163)
			(xy 270.173104 -285.023846) (xy 270.169144 -284.974792) (xy 269.830042 -284.974792) (xy 269.829547 -284.999399)
			(xy 269.821652 -285.047976) (xy 269.806068 -285.094657) (xy 269.783197 -285.138234) (xy 269.753632 -285.177578)
			(xy 269.718139 -285.21167) (xy 269.677636 -285.239626) (xy 269.633174 -285.260724) (xy 269.585903 -285.274416)
			(xy 269.537048 -285.280348) (xy 269.487873 -285.278367) (xy 269.439654 -285.268523) (xy 269.393638 -285.251071)
			(xy 269.351017 -285.226464) (xy 269.312896 -285.195339) (xy 269.280261 -285.158502) (xy 269.253958 -285.116906)
			(xy 269.234667 -285.07163) (xy 269.22289 -285.023846) (xy 269.21893 -284.974792) (xy 268.880082 -284.974792)
			(xy 268.879587 -284.999399) (xy 268.871692 -285.047976) (xy 268.856108 -285.094657) (xy 268.833237 -285.138234)
			(xy 268.803672 -285.177578) (xy 268.768179 -285.21167) (xy 268.727676 -285.239626) (xy 268.683214 -285.260724)
			(xy 268.635943 -285.274416) (xy 268.587088 -285.280348) (xy 268.537913 -285.278367) (xy 268.489694 -285.268523)
			(xy 268.443678 -285.251071) (xy 268.401057 -285.226464) (xy 268.362936 -285.195339) (xy 268.330301 -285.158502)
			(xy 268.303998 -285.116906) (xy 268.284707 -285.07163) (xy 268.27293 -285.023846) (xy 268.26897 -284.974792)
			(xy 260.255605 -284.974792) (xy 260.259575 -285.00177) (xy 260.260084 -285.029656) (xy 260.259575 -285.057542)
			(xy 260.251455 -285.112718) (xy 260.235387 -285.166125) (xy 260.211715 -285.216622) (xy 260.180942 -285.263135)
			(xy 260.143725 -285.304672) (xy 260.100857 -285.340347) (xy 260.053251 -285.369401) (xy 260.001922 -285.391213)
			(xy 259.947965 -285.405319) (xy 259.892528 -285.411419) (xy 259.836794 -285.409382) (xy 259.781951 -285.399252)
			(xy 259.729167 -285.381245) (xy 259.679567 -285.355744) (xy 259.634209 -285.323293) (xy 259.59406 -285.284584)
			(xy 259.559974 -285.240441) (xy 259.532678 -285.191806) (xy 259.512755 -285.139715) (xy 259.500629 -285.085278)
			(xy 259.496558 -285.029656) (xy 258.774946 -285.029656) (xy 258.774437 -285.057542) (xy 258.766317 -285.112718)
			(xy 258.750249 -285.166125) (xy 258.726577 -285.216622) (xy 258.695804 -285.263135) (xy 258.658587 -285.304672)
			(xy 258.615719 -285.340347) (xy 258.568113 -285.369401) (xy 258.516784 -285.391213) (xy 258.462827 -285.405319)
			(xy 258.40739 -285.411419) (xy 258.351656 -285.409382) (xy 258.296813 -285.399252) (xy 258.244029 -285.381245)
			(xy 258.194429 -285.355744) (xy 258.149071 -285.323293) (xy 258.108922 -285.284584) (xy 258.074836 -285.240441)
			(xy 258.04754 -285.191806) (xy 258.027617 -285.139715) (xy 258.015491 -285.085278) (xy 258.01142 -285.029656)
			(xy 249.737118 -285.029656) (xy 249.737118 -285.924752) (xy 268.26897 -285.924752) (xy 268.27293 -285.875698)
			(xy 268.284707 -285.827914) (xy 268.303998 -285.782638) (xy 268.330301 -285.741042) (xy 268.362936 -285.704205)
			(xy 268.401057 -285.67308) (xy 268.443678 -285.648473) (xy 268.489694 -285.631021) (xy 268.537913 -285.621177)
			(xy 268.587088 -285.619196) (xy 268.635943 -285.625128) (xy 268.683214 -285.63882) (xy 268.727676 -285.659918)
			(xy 268.768179 -285.687874) (xy 268.803672 -285.721966) (xy 268.833237 -285.76131) (xy 268.856108 -285.804887)
			(xy 268.871692 -285.851568) (xy 268.879587 -285.900145) (xy 268.880082 -285.924752) (xy 269.21893 -285.924752)
			(xy 269.22289 -285.875698) (xy 269.234667 -285.827914) (xy 269.253958 -285.782638) (xy 269.280261 -285.741042)
			(xy 269.312896 -285.704205) (xy 269.351017 -285.67308) (xy 269.393638 -285.648473) (xy 269.439654 -285.631021)
			(xy 269.487873 -285.621177) (xy 269.537048 -285.619196) (xy 269.585903 -285.625128) (xy 269.633174 -285.63882)
			(xy 269.677636 -285.659918) (xy 269.718139 -285.687874) (xy 269.753632 -285.721966) (xy 269.783197 -285.76131)
			(xy 269.806068 -285.804887) (xy 269.821652 -285.851568) (xy 269.829547 -285.900145) (xy 269.830042 -285.924752)
			(xy 270.169144 -285.924752) (xy 270.173104 -285.875698) (xy 270.184881 -285.827914) (xy 270.204172 -285.782638)
			(xy 270.230475 -285.741042) (xy 270.26311 -285.704205) (xy 270.301231 -285.67308) (xy 270.343852 -285.648473)
			(xy 270.389868 -285.631021) (xy 270.438087 -285.621177) (xy 270.487262 -285.619196) (xy 270.536117 -285.625128)
			(xy 270.583388 -285.63882) (xy 270.62785 -285.659918) (xy 270.668353 -285.687874) (xy 270.703846 -285.721966)
			(xy 270.733411 -285.76131) (xy 270.756282 -285.804887) (xy 270.771866 -285.851568) (xy 270.779761 -285.900145)
			(xy 270.780256 -285.924752) (xy 271.119104 -285.924752) (xy 271.123064 -285.875698) (xy 271.134841 -285.827914)
			(xy 271.154132 -285.782638) (xy 271.180435 -285.741042) (xy 271.21307 -285.704205) (xy 271.251191 -285.67308)
			(xy 271.293812 -285.648473) (xy 271.339828 -285.631021) (xy 271.388047 -285.621177) (xy 271.437222 -285.619196)
			(xy 271.486077 -285.625128) (xy 271.533348 -285.63882) (xy 271.57781 -285.659918) (xy 271.618313 -285.687874)
			(xy 271.653806 -285.721966) (xy 271.683371 -285.76131) (xy 271.706242 -285.804887) (xy 271.721826 -285.851568)
			(xy 271.729721 -285.900145) (xy 271.730216 -285.924752) (xy 272.069064 -285.924752) (xy 272.073024 -285.875698)
			(xy 272.084801 -285.827914) (xy 272.104092 -285.782638) (xy 272.130395 -285.741042) (xy 272.16303 -285.704205)
			(xy 272.201151 -285.67308) (xy 272.243772 -285.648473) (xy 272.289788 -285.631021) (xy 272.338007 -285.621177)
			(xy 272.387182 -285.619196) (xy 272.436037 -285.625128) (xy 272.483308 -285.63882) (xy 272.52777 -285.659918)
			(xy 272.568273 -285.687874) (xy 272.603766 -285.721966) (xy 272.633331 -285.76131) (xy 272.656202 -285.804887)
			(xy 272.671786 -285.851568) (xy 272.679681 -285.900145) (xy 272.680176 -285.924752) (xy 273.019024 -285.924752)
			(xy 273.022984 -285.875698) (xy 273.034761 -285.827914) (xy 273.054052 -285.782638) (xy 273.080355 -285.741042)
			(xy 273.11299 -285.704205) (xy 273.151111 -285.67308) (xy 273.193732 -285.648473) (xy 273.239748 -285.631021)
			(xy 273.287967 -285.621177) (xy 273.337142 -285.619196) (xy 273.385997 -285.625128) (xy 273.433268 -285.63882)
			(xy 273.47773 -285.659918) (xy 273.518233 -285.687874) (xy 273.553726 -285.721966) (xy 273.583291 -285.76131)
			(xy 273.606162 -285.804887) (xy 273.621746 -285.851568) (xy 273.629641 -285.900145) (xy 273.630136 -285.924752)
			(xy 276.819118 -285.924752) (xy 276.823078 -285.875698) (xy 276.834855 -285.827914) (xy 276.854146 -285.782638)
			(xy 276.880449 -285.741042) (xy 276.913084 -285.704205) (xy 276.951205 -285.67308) (xy 276.993826 -285.648473)
			(xy 277.039842 -285.631021) (xy 277.088061 -285.621177) (xy 277.137236 -285.619196) (xy 277.186091 -285.625128)
			(xy 277.233362 -285.63882) (xy 277.277824 -285.659918) (xy 277.318327 -285.687874) (xy 277.35382 -285.721966)
			(xy 277.383385 -285.76131) (xy 277.406256 -285.804887) (xy 277.42184 -285.851568) (xy 277.429735 -285.900145)
			(xy 277.43023 -285.924752) (xy 277.769078 -285.924752) (xy 277.773038 -285.875698) (xy 277.784815 -285.827914)
			(xy 277.804106 -285.782638) (xy 277.830409 -285.741042) (xy 277.863044 -285.704205) (xy 277.901165 -285.67308)
			(xy 277.943786 -285.648473) (xy 277.989802 -285.631021) (xy 278.038021 -285.621177) (xy 278.087196 -285.619196)
			(xy 278.136051 -285.625128) (xy 278.183322 -285.63882) (xy 278.227784 -285.659918) (xy 278.268287 -285.687874)
			(xy 278.30378 -285.721966) (xy 278.333345 -285.76131) (xy 278.356216 -285.804887) (xy 278.3718 -285.851568)
			(xy 278.379695 -285.900145) (xy 278.38019 -285.924752) (xy 278.719038 -285.924752) (xy 278.722998 -285.875698)
			(xy 278.734775 -285.827914) (xy 278.754066 -285.782638) (xy 278.780369 -285.741042) (xy 278.813004 -285.704205)
			(xy 278.851125 -285.67308) (xy 278.893746 -285.648473) (xy 278.939762 -285.631021) (xy 278.987981 -285.621177)
			(xy 279.037156 -285.619196) (xy 279.086011 -285.625128) (xy 279.133282 -285.63882) (xy 279.177744 -285.659918)
			(xy 279.218247 -285.687874) (xy 279.25374 -285.721966) (xy 279.283305 -285.76131) (xy 279.306176 -285.804887)
			(xy 279.32176 -285.851568) (xy 279.329655 -285.900145) (xy 279.33015 -285.924752) (xy 279.668998 -285.924752)
			(xy 279.672958 -285.875698) (xy 279.684735 -285.827914) (xy 279.704026 -285.782638) (xy 279.730329 -285.741042)
			(xy 279.762964 -285.704205) (xy 279.801085 -285.67308) (xy 279.843706 -285.648473) (xy 279.889722 -285.631021)
			(xy 279.937941 -285.621177) (xy 279.987116 -285.619196) (xy 280.035971 -285.625128) (xy 280.083242 -285.63882)
			(xy 280.127704 -285.659918) (xy 280.168207 -285.687874) (xy 280.2037 -285.721966) (xy 280.233265 -285.76131)
			(xy 280.256136 -285.804887) (xy 280.27172 -285.851568) (xy 280.279615 -285.900145) (xy 280.28011 -285.924752)
			(xy 280.618958 -285.924752) (xy 280.622918 -285.875698) (xy 280.634695 -285.827914) (xy 280.653986 -285.782638)
			(xy 280.680289 -285.741042) (xy 280.712924 -285.704205) (xy 280.751045 -285.67308) (xy 280.793666 -285.648473)
			(xy 280.839682 -285.631021) (xy 280.887901 -285.621177) (xy 280.937076 -285.619196) (xy 280.985931 -285.625128)
			(xy 281.033202 -285.63882) (xy 281.077664 -285.659918) (xy 281.118167 -285.687874) (xy 281.15366 -285.721966)
			(xy 281.183225 -285.76131) (xy 281.206096 -285.804887) (xy 281.22168 -285.851568) (xy 281.229575 -285.900145)
			(xy 281.23007 -285.924752) (xy 281.568918 -285.924752) (xy 281.572878 -285.875698) (xy 281.584655 -285.827914)
			(xy 281.603946 -285.782638) (xy 281.630249 -285.741042) (xy 281.662884 -285.704205) (xy 281.701005 -285.67308)
			(xy 281.743626 -285.648473) (xy 281.789642 -285.631021) (xy 281.837861 -285.621177) (xy 281.887036 -285.619196)
			(xy 281.935891 -285.625128) (xy 281.983162 -285.63882) (xy 282.027624 -285.659918) (xy 282.068127 -285.687874)
			(xy 282.10362 -285.721966) (xy 282.133185 -285.76131) (xy 282.156056 -285.804887) (xy 282.17164 -285.851568)
			(xy 282.179535 -285.900145) (xy 282.18003 -285.924752) (xy 282.519132 -285.924752) (xy 282.523092 -285.875698)
			(xy 282.534869 -285.827914) (xy 282.55416 -285.782638) (xy 282.580463 -285.741042) (xy 282.613098 -285.704205)
			(xy 282.651219 -285.67308) (xy 282.69384 -285.648473) (xy 282.739856 -285.631021) (xy 282.788075 -285.621177)
			(xy 282.83725 -285.619196) (xy 282.886105 -285.625128) (xy 282.933376 -285.63882) (xy 282.977838 -285.659918)
			(xy 283.018341 -285.687874) (xy 283.053834 -285.721966) (xy 283.083399 -285.76131) (xy 283.10627 -285.804887)
			(xy 283.121854 -285.851568) (xy 283.129749 -285.900145) (xy 283.130244 -285.924752) (xy 283.469092 -285.924752)
			(xy 283.473052 -285.875698) (xy 283.484829 -285.827914) (xy 283.50412 -285.782638) (xy 283.530423 -285.741042)
			(xy 283.563058 -285.704205) (xy 283.601179 -285.67308) (xy 283.6438 -285.648473) (xy 283.689816 -285.631021)
			(xy 283.738035 -285.621177) (xy 283.78721 -285.619196) (xy 283.836065 -285.625128) (xy 283.883336 -285.63882)
			(xy 283.927798 -285.659918) (xy 283.968301 -285.687874) (xy 284.003794 -285.721966) (xy 284.033359 -285.76131)
			(xy 284.05623 -285.804887) (xy 284.071814 -285.851568) (xy 284.079709 -285.900145) (xy 284.080204 -285.924752)
			(xy 284.419052 -285.924752) (xy 284.423012 -285.875698) (xy 284.434789 -285.827914) (xy 284.45408 -285.782638)
			(xy 284.480383 -285.741042) (xy 284.513018 -285.704205) (xy 284.551139 -285.67308) (xy 284.59376 -285.648473)
			(xy 284.639776 -285.631021) (xy 284.687995 -285.621177) (xy 284.73717 -285.619196) (xy 284.786025 -285.625128)
			(xy 284.833296 -285.63882) (xy 284.877758 -285.659918) (xy 284.918261 -285.687874) (xy 284.953754 -285.721966)
			(xy 284.983319 -285.76131) (xy 285.00619 -285.804887) (xy 285.021774 -285.851568) (xy 285.029669 -285.900145)
			(xy 285.030164 -285.924752) (xy 285.369012 -285.924752) (xy 285.372972 -285.875698) (xy 285.384749 -285.827914)
			(xy 285.40404 -285.782638) (xy 285.430343 -285.741042) (xy 285.462978 -285.704205) (xy 285.501099 -285.67308)
			(xy 285.54372 -285.648473) (xy 285.589736 -285.631021) (xy 285.637955 -285.621177) (xy 285.68713 -285.619196)
			(xy 285.735985 -285.625128) (xy 285.783256 -285.63882) (xy 285.827718 -285.659918) (xy 285.868221 -285.687874)
			(xy 285.903714 -285.721966) (xy 285.933279 -285.76131) (xy 285.95615 -285.804887) (xy 285.971734 -285.851568)
			(xy 285.979629 -285.900145) (xy 285.980124 -285.924752) (xy 286.318972 -285.924752) (xy 286.322932 -285.875698)
			(xy 286.334709 -285.827914) (xy 286.354 -285.782638) (xy 286.380303 -285.741042) (xy 286.412938 -285.704205)
			(xy 286.451059 -285.67308) (xy 286.49368 -285.648473) (xy 286.539696 -285.631021) (xy 286.587915 -285.621177)
			(xy 286.63709 -285.619196) (xy 286.685945 -285.625128) (xy 286.733216 -285.63882) (xy 286.777678 -285.659918)
			(xy 286.818181 -285.687874) (xy 286.853674 -285.721966) (xy 286.883239 -285.76131) (xy 286.90611 -285.804887)
			(xy 286.921694 -285.851568) (xy 286.929589 -285.900145) (xy 286.930084 -285.924752) (xy 287.268932 -285.924752)
			(xy 287.272892 -285.875698) (xy 287.284669 -285.827914) (xy 287.30396 -285.782638) (xy 287.330263 -285.741042)
			(xy 287.362898 -285.704205) (xy 287.401019 -285.67308) (xy 287.44364 -285.648473) (xy 287.489656 -285.631021)
			(xy 287.537875 -285.621177) (xy 287.58705 -285.619196) (xy 287.635905 -285.625128) (xy 287.683176 -285.63882)
			(xy 287.727638 -285.659918) (xy 287.768141 -285.687874) (xy 287.803634 -285.721966) (xy 287.833199 -285.76131)
			(xy 287.85607 -285.804887) (xy 287.871654 -285.851568) (xy 287.879549 -285.900145) (xy 287.880044 -285.924752)
			(xy 288.218892 -285.924752) (xy 288.222852 -285.875698) (xy 288.234629 -285.827914) (xy 288.25392 -285.782638)
			(xy 288.280223 -285.741042) (xy 288.312858 -285.704205) (xy 288.350979 -285.67308) (xy 288.3936 -285.648473)
			(xy 288.439616 -285.631021) (xy 288.487835 -285.621177) (xy 288.53701 -285.619196) (xy 288.585865 -285.625128)
			(xy 288.633136 -285.63882) (xy 288.677598 -285.659918) (xy 288.718101 -285.687874) (xy 288.753594 -285.721966)
			(xy 288.783159 -285.76131) (xy 288.80603 -285.804887) (xy 288.821614 -285.851568) (xy 288.829509 -285.900145)
			(xy 288.830004 -285.924752) (xy 289.169106 -285.924752) (xy 289.173066 -285.875698) (xy 289.184843 -285.827914)
			(xy 289.204134 -285.782638) (xy 289.230437 -285.741042) (xy 289.263072 -285.704205) (xy 289.301193 -285.67308)
			(xy 289.343814 -285.648473) (xy 289.38983 -285.631021) (xy 289.438049 -285.621177) (xy 289.487224 -285.619196)
			(xy 289.536079 -285.625128) (xy 289.58335 -285.63882) (xy 289.627812 -285.659918) (xy 289.668315 -285.687874)
			(xy 289.703808 -285.721966) (xy 289.733373 -285.76131) (xy 289.756244 -285.804887) (xy 289.771828 -285.851568)
			(xy 289.779723 -285.900145) (xy 289.780218 -285.924752) (xy 290.119066 -285.924752) (xy 290.123026 -285.875698)
			(xy 290.134803 -285.827914) (xy 290.154094 -285.782638) (xy 290.180397 -285.741042) (xy 290.213032 -285.704205)
			(xy 290.251153 -285.67308) (xy 290.293774 -285.648473) (xy 290.33979 -285.631021) (xy 290.388009 -285.621177)
			(xy 290.437184 -285.619196) (xy 290.486039 -285.625128) (xy 290.53331 -285.63882) (xy 290.577772 -285.659918)
			(xy 290.618275 -285.687874) (xy 290.653768 -285.721966) (xy 290.683333 -285.76131) (xy 290.706204 -285.804887)
			(xy 290.721788 -285.851568) (xy 290.729683 -285.900145) (xy 290.730178 -285.924752) (xy 292.018986 -285.924752)
			(xy 292.022946 -285.875698) (xy 292.034723 -285.827914) (xy 292.054014 -285.782638) (xy 292.080317 -285.741042)
			(xy 292.112952 -285.704205) (xy 292.151073 -285.67308) (xy 292.193694 -285.648473) (xy 292.23971 -285.631021)
			(xy 292.287929 -285.621177) (xy 292.337104 -285.619196) (xy 292.385959 -285.625128) (xy 292.43323 -285.63882)
			(xy 292.477692 -285.659918) (xy 292.518195 -285.687874) (xy 292.553688 -285.721966) (xy 292.583253 -285.76131)
			(xy 292.606124 -285.804887) (xy 292.621708 -285.851568) (xy 292.629603 -285.900145) (xy 292.630098 -285.924752)
			(xy 292.968946 -285.924752) (xy 292.972906 -285.875698) (xy 292.984683 -285.827914) (xy 293.003974 -285.782638)
			(xy 293.030277 -285.741042) (xy 293.062912 -285.704205) (xy 293.101033 -285.67308) (xy 293.143654 -285.648473)
			(xy 293.18967 -285.631021) (xy 293.237889 -285.621177) (xy 293.287064 -285.619196) (xy 293.335919 -285.625128)
			(xy 293.38319 -285.63882) (xy 293.427652 -285.659918) (xy 293.468155 -285.687874) (xy 293.503648 -285.721966)
			(xy 293.533213 -285.76131) (xy 293.556084 -285.804887) (xy 293.571668 -285.851568) (xy 293.579563 -285.900145)
			(xy 293.580058 -285.924752) (xy 293.918906 -285.924752) (xy 293.922866 -285.875698) (xy 293.934643 -285.827914)
			(xy 293.953934 -285.782638) (xy 293.980237 -285.741042) (xy 294.012872 -285.704205) (xy 294.050993 -285.67308)
			(xy 294.093614 -285.648473) (xy 294.13963 -285.631021) (xy 294.187849 -285.621177) (xy 294.237024 -285.619196)
			(xy 294.285879 -285.625128) (xy 294.33315 -285.63882) (xy 294.377612 -285.659918) (xy 294.418115 -285.687874)
			(xy 294.453608 -285.721966) (xy 294.483173 -285.76131) (xy 294.506044 -285.804887) (xy 294.521628 -285.851568)
			(xy 294.529523 -285.900145) (xy 294.530018 -285.924752) (xy 294.86912 -285.924752) (xy 294.87308 -285.875698)
			(xy 294.884857 -285.827914) (xy 294.904148 -285.782638) (xy 294.930451 -285.741042) (xy 294.963086 -285.704205)
			(xy 295.001207 -285.67308) (xy 295.043828 -285.648473) (xy 295.089844 -285.631021) (xy 295.138063 -285.621177)
			(xy 295.187238 -285.619196) (xy 295.236093 -285.625128) (xy 295.283364 -285.63882) (xy 295.327826 -285.659918)
			(xy 295.368329 -285.687874) (xy 295.403822 -285.721966) (xy 295.433387 -285.76131) (xy 295.456258 -285.804887)
			(xy 295.471842 -285.851568) (xy 295.479737 -285.900145) (xy 295.480232 -285.924752) (xy 295.81908 -285.924752)
			(xy 295.82304 -285.875698) (xy 295.834817 -285.827914) (xy 295.854108 -285.782638) (xy 295.880411 -285.741042)
			(xy 295.913046 -285.704205) (xy 295.951167 -285.67308) (xy 295.993788 -285.648473) (xy 296.039804 -285.631021)
			(xy 296.088023 -285.621177) (xy 296.137198 -285.619196) (xy 296.186053 -285.625128) (xy 296.233324 -285.63882)
			(xy 296.277786 -285.659918) (xy 296.318289 -285.687874) (xy 296.353782 -285.721966) (xy 296.383347 -285.76131)
			(xy 296.406218 -285.804887) (xy 296.421802 -285.851568) (xy 296.429697 -285.900145) (xy 296.430192 -285.924752)
			(xy 296.76904 -285.924752) (xy 296.773 -285.875698) (xy 296.784777 -285.827914) (xy 296.804068 -285.782638)
			(xy 296.830371 -285.741042) (xy 296.863006 -285.704205) (xy 296.901127 -285.67308) (xy 296.943748 -285.648473)
			(xy 296.989764 -285.631021) (xy 297.037983 -285.621177) (xy 297.087158 -285.619196) (xy 297.136013 -285.625128)
			(xy 297.183284 -285.63882) (xy 297.227746 -285.659918) (xy 297.268249 -285.687874) (xy 297.303742 -285.721966)
			(xy 297.333307 -285.76131) (xy 297.356178 -285.804887) (xy 297.371762 -285.851568) (xy 297.379657 -285.900145)
			(xy 297.380152 -285.924752) (xy 297.719 -285.924752) (xy 297.72296 -285.875698) (xy 297.734737 -285.827914)
			(xy 297.754028 -285.782638) (xy 297.780331 -285.741042) (xy 297.812966 -285.704205) (xy 297.851087 -285.67308)
			(xy 297.893708 -285.648473) (xy 297.939724 -285.631021) (xy 297.987943 -285.621177) (xy 298.037118 -285.619196)
			(xy 298.085973 -285.625128) (xy 298.133244 -285.63882) (xy 298.177706 -285.659918) (xy 298.218209 -285.687874)
			(xy 298.253702 -285.721966) (xy 298.283267 -285.76131) (xy 298.306138 -285.804887) (xy 298.321722 -285.851568)
			(xy 298.329617 -285.900145) (xy 298.330112 -285.924752) (xy 298.66896 -285.924752) (xy 298.67292 -285.875698)
			(xy 298.684697 -285.827914) (xy 298.703988 -285.782638) (xy 298.730291 -285.741042) (xy 298.762926 -285.704205)
			(xy 298.801047 -285.67308) (xy 298.843668 -285.648473) (xy 298.889684 -285.631021) (xy 298.937903 -285.621177)
			(xy 298.987078 -285.619196) (xy 299.035933 -285.625128) (xy 299.083204 -285.63882) (xy 299.127666 -285.659918)
			(xy 299.168169 -285.687874) (xy 299.203662 -285.721966) (xy 299.233227 -285.76131) (xy 299.256098 -285.804887)
			(xy 299.271682 -285.851568) (xy 299.279577 -285.900145) (xy 299.280072 -285.924752) (xy 299.61892 -285.924752)
			(xy 299.62288 -285.875698) (xy 299.634657 -285.827914) (xy 299.653948 -285.782638) (xy 299.680251 -285.741042)
			(xy 299.712886 -285.704205) (xy 299.751007 -285.67308) (xy 299.793628 -285.648473) (xy 299.839644 -285.631021)
			(xy 299.887863 -285.621177) (xy 299.937038 -285.619196) (xy 299.985893 -285.625128) (xy 300.033164 -285.63882)
			(xy 300.077626 -285.659918) (xy 300.118129 -285.687874) (xy 300.153622 -285.721966) (xy 300.183187 -285.76131)
			(xy 300.206058 -285.804887) (xy 300.221642 -285.851568) (xy 300.229537 -285.900145) (xy 300.230032 -285.924752)
			(xy 300.56888 -285.924752) (xy 300.57284 -285.875698) (xy 300.584617 -285.827914) (xy 300.603908 -285.782638)
			(xy 300.630211 -285.741042) (xy 300.662846 -285.704205) (xy 300.700967 -285.67308) (xy 300.743588 -285.648473)
			(xy 300.789604 -285.631021) (xy 300.837823 -285.621177) (xy 300.886998 -285.619196) (xy 300.935853 -285.625128)
			(xy 300.983124 -285.63882) (xy 301.027586 -285.659918) (xy 301.068089 -285.687874) (xy 301.103582 -285.721966)
			(xy 301.133147 -285.76131) (xy 301.156018 -285.804887) (xy 301.171602 -285.851568) (xy 301.179497 -285.900145)
			(xy 301.179992 -285.924752) (xy 301.519094 -285.924752) (xy 301.523054 -285.875698) (xy 301.534831 -285.827914)
			(xy 301.554122 -285.782638) (xy 301.580425 -285.741042) (xy 301.61306 -285.704205) (xy 301.651181 -285.67308)
			(xy 301.693802 -285.648473) (xy 301.739818 -285.631021) (xy 301.788037 -285.621177) (xy 301.837212 -285.619196)
			(xy 301.886067 -285.625128) (xy 301.933338 -285.63882) (xy 301.9778 -285.659918) (xy 302.018303 -285.687874)
			(xy 302.053796 -285.721966) (xy 302.083361 -285.76131) (xy 302.106232 -285.804887) (xy 302.121816 -285.851568)
			(xy 302.129711 -285.900145) (xy 302.130206 -285.924752) (xy 302.469054 -285.924752) (xy 302.473014 -285.875698)
			(xy 302.484791 -285.827914) (xy 302.504082 -285.782638) (xy 302.530385 -285.741042) (xy 302.56302 -285.704205)
			(xy 302.601141 -285.67308) (xy 302.643762 -285.648473) (xy 302.689778 -285.631021) (xy 302.737997 -285.621177)
			(xy 302.787172 -285.619196) (xy 302.836027 -285.625128) (xy 302.883298 -285.63882) (xy 302.92776 -285.659918)
			(xy 302.968263 -285.687874) (xy 303.003756 -285.721966) (xy 303.033321 -285.76131) (xy 303.056192 -285.804887)
			(xy 303.071776 -285.851568) (xy 303.079671 -285.900145) (xy 303.080166 -285.924752) (xy 303.079671 -285.949359)
			(xy 303.071776 -285.997936) (xy 303.056192 -286.044617) (xy 303.033321 -286.088194) (xy 303.003756 -286.127538)
			(xy 302.968263 -286.16163) (xy 302.92776 -286.189586) (xy 302.883298 -286.210684) (xy 302.836027 -286.224376)
			(xy 302.787172 -286.230308) (xy 302.737997 -286.228327) (xy 302.689778 -286.218483) (xy 302.643762 -286.201031)
			(xy 302.601141 -286.176424) (xy 302.56302 -286.145299) (xy 302.530385 -286.108462) (xy 302.504082 -286.066866)
			(xy 302.484791 -286.02159) (xy 302.473014 -285.973806) (xy 302.469054 -285.924752) (xy 302.130206 -285.924752)
			(xy 302.129711 -285.949359) (xy 302.121816 -285.997936) (xy 302.106232 -286.044617) (xy 302.083361 -286.088194)
			(xy 302.053796 -286.127538) (xy 302.018303 -286.16163) (xy 301.9778 -286.189586) (xy 301.933338 -286.210684)
			(xy 301.886067 -286.224376) (xy 301.837212 -286.230308) (xy 301.788037 -286.228327) (xy 301.739818 -286.218483)
			(xy 301.693802 -286.201031) (xy 301.651181 -286.176424) (xy 301.61306 -286.145299) (xy 301.580425 -286.108462)
			(xy 301.554122 -286.066866) (xy 301.534831 -286.02159) (xy 301.523054 -285.973806) (xy 301.519094 -285.924752)
			(xy 301.179992 -285.924752) (xy 301.179497 -285.949359) (xy 301.171602 -285.997936) (xy 301.156018 -286.044617)
			(xy 301.133147 -286.088194) (xy 301.103582 -286.127538) (xy 301.068089 -286.16163) (xy 301.027586 -286.189586)
			(xy 300.983124 -286.210684) (xy 300.935853 -286.224376) (xy 300.886998 -286.230308) (xy 300.837823 -286.228327)
			(xy 300.789604 -286.218483) (xy 300.743588 -286.201031) (xy 300.700967 -286.176424) (xy 300.662846 -286.145299)
			(xy 300.630211 -286.108462) (xy 300.603908 -286.066866) (xy 300.584617 -286.02159) (xy 300.57284 -285.973806)
			(xy 300.56888 -285.924752) (xy 300.230032 -285.924752) (xy 300.229537 -285.949359) (xy 300.221642 -285.997936)
			(xy 300.206058 -286.044617) (xy 300.183187 -286.088194) (xy 300.153622 -286.127538) (xy 300.118129 -286.16163)
			(xy 300.077626 -286.189586) (xy 300.033164 -286.210684) (xy 299.985893 -286.224376) (xy 299.937038 -286.230308)
			(xy 299.887863 -286.228327) (xy 299.839644 -286.218483) (xy 299.793628 -286.201031) (xy 299.751007 -286.176424)
			(xy 299.712886 -286.145299) (xy 299.680251 -286.108462) (xy 299.653948 -286.066866) (xy 299.634657 -286.02159)
			(xy 299.62288 -285.973806) (xy 299.61892 -285.924752) (xy 299.280072 -285.924752) (xy 299.279577 -285.949359)
			(xy 299.271682 -285.997936) (xy 299.256098 -286.044617) (xy 299.233227 -286.088194) (xy 299.203662 -286.127538)
			(xy 299.168169 -286.16163) (xy 299.127666 -286.189586) (xy 299.083204 -286.210684) (xy 299.035933 -286.224376)
			(xy 298.987078 -286.230308) (xy 298.937903 -286.228327) (xy 298.889684 -286.218483) (xy 298.843668 -286.201031)
			(xy 298.801047 -286.176424) (xy 298.762926 -286.145299) (xy 298.730291 -286.108462) (xy 298.703988 -286.066866)
			(xy 298.684697 -286.02159) (xy 298.67292 -285.973806) (xy 298.66896 -285.924752) (xy 298.330112 -285.924752)
			(xy 298.329617 -285.949359) (xy 298.321722 -285.997936) (xy 298.306138 -286.044617) (xy 298.283267 -286.088194)
			(xy 298.253702 -286.127538) (xy 298.218209 -286.16163) (xy 298.177706 -286.189586) (xy 298.133244 -286.210684)
			(xy 298.085973 -286.224376) (xy 298.037118 -286.230308) (xy 297.987943 -286.228327) (xy 297.939724 -286.218483)
			(xy 297.893708 -286.201031) (xy 297.851087 -286.176424) (xy 297.812966 -286.145299) (xy 297.780331 -286.108462)
			(xy 297.754028 -286.066866) (xy 297.734737 -286.02159) (xy 297.72296 -285.973806) (xy 297.719 -285.924752)
			(xy 297.380152 -285.924752) (xy 297.379657 -285.949359) (xy 297.371762 -285.997936) (xy 297.356178 -286.044617)
			(xy 297.333307 -286.088194) (xy 297.303742 -286.127538) (xy 297.268249 -286.16163) (xy 297.227746 -286.189586)
			(xy 297.183284 -286.210684) (xy 297.136013 -286.224376) (xy 297.087158 -286.230308) (xy 297.037983 -286.228327)
			(xy 296.989764 -286.218483) (xy 296.943748 -286.201031) (xy 296.901127 -286.176424) (xy 296.863006 -286.145299)
			(xy 296.830371 -286.108462) (xy 296.804068 -286.066866) (xy 296.784777 -286.02159) (xy 296.773 -285.973806)
			(xy 296.76904 -285.924752) (xy 296.430192 -285.924752) (xy 296.429697 -285.949359) (xy 296.421802 -285.997936)
			(xy 296.406218 -286.044617) (xy 296.383347 -286.088194) (xy 296.353782 -286.127538) (xy 296.318289 -286.16163)
			(xy 296.277786 -286.189586) (xy 296.233324 -286.210684) (xy 296.186053 -286.224376) (xy 296.137198 -286.230308)
			(xy 296.088023 -286.228327) (xy 296.039804 -286.218483) (xy 295.993788 -286.201031) (xy 295.951167 -286.176424)
			(xy 295.913046 -286.145299) (xy 295.880411 -286.108462) (xy 295.854108 -286.066866) (xy 295.834817 -286.02159)
			(xy 295.82304 -285.973806) (xy 295.81908 -285.924752) (xy 295.480232 -285.924752) (xy 295.479737 -285.949359)
			(xy 295.471842 -285.997936) (xy 295.456258 -286.044617) (xy 295.433387 -286.088194) (xy 295.403822 -286.127538)
			(xy 295.368329 -286.16163) (xy 295.327826 -286.189586) (xy 295.283364 -286.210684) (xy 295.236093 -286.224376)
			(xy 295.187238 -286.230308) (xy 295.138063 -286.228327) (xy 295.089844 -286.218483) (xy 295.043828 -286.201031)
			(xy 295.001207 -286.176424) (xy 294.963086 -286.145299) (xy 294.930451 -286.108462) (xy 294.904148 -286.066866)
			(xy 294.884857 -286.02159) (xy 294.87308 -285.973806) (xy 294.86912 -285.924752) (xy 294.530018 -285.924752)
			(xy 294.529523 -285.949359) (xy 294.521628 -285.997936) (xy 294.506044 -286.044617) (xy 294.483173 -286.088194)
			(xy 294.453608 -286.127538) (xy 294.418115 -286.16163) (xy 294.377612 -286.189586) (xy 294.33315 -286.210684)
			(xy 294.285879 -286.224376) (xy 294.237024 -286.230308) (xy 294.187849 -286.228327) (xy 294.13963 -286.218483)
			(xy 294.093614 -286.201031) (xy 294.050993 -286.176424) (xy 294.012872 -286.145299) (xy 293.980237 -286.108462)
			(xy 293.953934 -286.066866) (xy 293.934643 -286.02159) (xy 293.922866 -285.973806) (xy 293.918906 -285.924752)
			(xy 293.580058 -285.924752) (xy 293.579563 -285.949359) (xy 293.571668 -285.997936) (xy 293.556084 -286.044617)
			(xy 293.533213 -286.088194) (xy 293.503648 -286.127538) (xy 293.468155 -286.16163) (xy 293.427652 -286.189586)
			(xy 293.38319 -286.210684) (xy 293.335919 -286.224376) (xy 293.287064 -286.230308) (xy 293.237889 -286.228327)
			(xy 293.18967 -286.218483) (xy 293.143654 -286.201031) (xy 293.101033 -286.176424) (xy 293.062912 -286.145299)
			(xy 293.030277 -286.108462) (xy 293.003974 -286.066866) (xy 292.984683 -286.02159) (xy 292.972906 -285.973806)
			(xy 292.968946 -285.924752) (xy 292.630098 -285.924752) (xy 292.629603 -285.949359) (xy 292.621708 -285.997936)
			(xy 292.606124 -286.044617) (xy 292.583253 -286.088194) (xy 292.553688 -286.127538) (xy 292.518195 -286.16163)
			(xy 292.477692 -286.189586) (xy 292.43323 -286.210684) (xy 292.385959 -286.224376) (xy 292.337104 -286.230308)
			(xy 292.287929 -286.228327) (xy 292.23971 -286.218483) (xy 292.193694 -286.201031) (xy 292.151073 -286.176424)
			(xy 292.112952 -286.145299) (xy 292.080317 -286.108462) (xy 292.054014 -286.066866) (xy 292.034723 -286.02159)
			(xy 292.022946 -285.973806) (xy 292.018986 -285.924752) (xy 290.730178 -285.924752) (xy 290.729683 -285.949359)
			(xy 290.721788 -285.997936) (xy 290.706204 -286.044617) (xy 290.683333 -286.088194) (xy 290.653768 -286.127538)
			(xy 290.618275 -286.16163) (xy 290.577772 -286.189586) (xy 290.53331 -286.210684) (xy 290.486039 -286.224376)
			(xy 290.437184 -286.230308) (xy 290.388009 -286.228327) (xy 290.33979 -286.218483) (xy 290.293774 -286.201031)
			(xy 290.251153 -286.176424) (xy 290.213032 -286.145299) (xy 290.180397 -286.108462) (xy 290.154094 -286.066866)
			(xy 290.134803 -286.02159) (xy 290.123026 -285.973806) (xy 290.119066 -285.924752) (xy 289.780218 -285.924752)
			(xy 289.779723 -285.949359) (xy 289.771828 -285.997936) (xy 289.756244 -286.044617) (xy 289.733373 -286.088194)
			(xy 289.703808 -286.127538) (xy 289.668315 -286.16163) (xy 289.627812 -286.189586) (xy 289.58335 -286.210684)
			(xy 289.536079 -286.224376) (xy 289.487224 -286.230308) (xy 289.438049 -286.228327) (xy 289.38983 -286.218483)
			(xy 289.343814 -286.201031) (xy 289.301193 -286.176424) (xy 289.263072 -286.145299) (xy 289.230437 -286.108462)
			(xy 289.204134 -286.066866) (xy 289.184843 -286.02159) (xy 289.173066 -285.973806) (xy 289.169106 -285.924752)
			(xy 288.830004 -285.924752) (xy 288.829509 -285.949359) (xy 288.821614 -285.997936) (xy 288.80603 -286.044617)
			(xy 288.783159 -286.088194) (xy 288.753594 -286.127538) (xy 288.718101 -286.16163) (xy 288.677598 -286.189586)
			(xy 288.633136 -286.210684) (xy 288.585865 -286.224376) (xy 288.53701 -286.230308) (xy 288.487835 -286.228327)
			(xy 288.439616 -286.218483) (xy 288.3936 -286.201031) (xy 288.350979 -286.176424) (xy 288.312858 -286.145299)
			(xy 288.280223 -286.108462) (xy 288.25392 -286.066866) (xy 288.234629 -286.02159) (xy 288.222852 -285.973806)
			(xy 288.218892 -285.924752) (xy 287.880044 -285.924752) (xy 287.879549 -285.949359) (xy 287.871654 -285.997936)
			(xy 287.85607 -286.044617) (xy 287.833199 -286.088194) (xy 287.803634 -286.127538) (xy 287.768141 -286.16163)
			(xy 287.727638 -286.189586) (xy 287.683176 -286.210684) (xy 287.635905 -286.224376) (xy 287.58705 -286.230308)
			(xy 287.537875 -286.228327) (xy 287.489656 -286.218483) (xy 287.44364 -286.201031) (xy 287.401019 -286.176424)
			(xy 287.362898 -286.145299) (xy 287.330263 -286.108462) (xy 287.30396 -286.066866) (xy 287.284669 -286.02159)
			(xy 287.272892 -285.973806) (xy 287.268932 -285.924752) (xy 286.930084 -285.924752) (xy 286.929589 -285.949359)
			(xy 286.921694 -285.997936) (xy 286.90611 -286.044617) (xy 286.883239 -286.088194) (xy 286.853674 -286.127538)
			(xy 286.818181 -286.16163) (xy 286.777678 -286.189586) (xy 286.733216 -286.210684) (xy 286.685945 -286.224376)
			(xy 286.63709 -286.230308) (xy 286.587915 -286.228327) (xy 286.539696 -286.218483) (xy 286.49368 -286.201031)
			(xy 286.451059 -286.176424) (xy 286.412938 -286.145299) (xy 286.380303 -286.108462) (xy 286.354 -286.066866)
			(xy 286.334709 -286.02159) (xy 286.322932 -285.973806) (xy 286.318972 -285.924752) (xy 285.980124 -285.924752)
			(xy 285.979629 -285.949359) (xy 285.971734 -285.997936) (xy 285.95615 -286.044617) (xy 285.933279 -286.088194)
			(xy 285.903714 -286.127538) (xy 285.868221 -286.16163) (xy 285.827718 -286.189586) (xy 285.783256 -286.210684)
			(xy 285.735985 -286.224376) (xy 285.68713 -286.230308) (xy 285.637955 -286.228327) (xy 285.589736 -286.218483)
			(xy 285.54372 -286.201031) (xy 285.501099 -286.176424) (xy 285.462978 -286.145299) (xy 285.430343 -286.108462)
			(xy 285.40404 -286.066866) (xy 285.384749 -286.02159) (xy 285.372972 -285.973806) (xy 285.369012 -285.924752)
			(xy 285.030164 -285.924752) (xy 285.029669 -285.949359) (xy 285.021774 -285.997936) (xy 285.00619 -286.044617)
			(xy 284.983319 -286.088194) (xy 284.953754 -286.127538) (xy 284.918261 -286.16163) (xy 284.877758 -286.189586)
			(xy 284.833296 -286.210684) (xy 284.786025 -286.224376) (xy 284.73717 -286.230308) (xy 284.687995 -286.228327)
			(xy 284.639776 -286.218483) (xy 284.59376 -286.201031) (xy 284.551139 -286.176424) (xy 284.513018 -286.145299)
			(xy 284.480383 -286.108462) (xy 284.45408 -286.066866) (xy 284.434789 -286.02159) (xy 284.423012 -285.973806)
			(xy 284.419052 -285.924752) (xy 284.080204 -285.924752) (xy 284.079709 -285.949359) (xy 284.071814 -285.997936)
			(xy 284.05623 -286.044617) (xy 284.033359 -286.088194) (xy 284.003794 -286.127538) (xy 283.968301 -286.16163)
			(xy 283.927798 -286.189586) (xy 283.883336 -286.210684) (xy 283.836065 -286.224376) (xy 283.78721 -286.230308)
			(xy 283.738035 -286.228327) (xy 283.689816 -286.218483) (xy 283.6438 -286.201031) (xy 283.601179 -286.176424)
			(xy 283.563058 -286.145299) (xy 283.530423 -286.108462) (xy 283.50412 -286.066866) (xy 283.484829 -286.02159)
			(xy 283.473052 -285.973806) (xy 283.469092 -285.924752) (xy 283.130244 -285.924752) (xy 283.129749 -285.949359)
			(xy 283.121854 -285.997936) (xy 283.10627 -286.044617) (xy 283.083399 -286.088194) (xy 283.053834 -286.127538)
			(xy 283.018341 -286.16163) (xy 282.977838 -286.189586) (xy 282.933376 -286.210684) (xy 282.886105 -286.224376)
			(xy 282.83725 -286.230308) (xy 282.788075 -286.228327) (xy 282.739856 -286.218483) (xy 282.69384 -286.201031)
			(xy 282.651219 -286.176424) (xy 282.613098 -286.145299) (xy 282.580463 -286.108462) (xy 282.55416 -286.066866)
			(xy 282.534869 -286.02159) (xy 282.523092 -285.973806) (xy 282.519132 -285.924752) (xy 282.18003 -285.924752)
			(xy 282.179535 -285.949359) (xy 282.17164 -285.997936) (xy 282.156056 -286.044617) (xy 282.133185 -286.088194)
			(xy 282.10362 -286.127538) (xy 282.068127 -286.16163) (xy 282.027624 -286.189586) (xy 281.983162 -286.210684)
			(xy 281.935891 -286.224376) (xy 281.887036 -286.230308) (xy 281.837861 -286.228327) (xy 281.789642 -286.218483)
			(xy 281.743626 -286.201031) (xy 281.701005 -286.176424) (xy 281.662884 -286.145299) (xy 281.630249 -286.108462)
			(xy 281.603946 -286.066866) (xy 281.584655 -286.02159) (xy 281.572878 -285.973806) (xy 281.568918 -285.924752)
			(xy 281.23007 -285.924752) (xy 281.229575 -285.949359) (xy 281.22168 -285.997936) (xy 281.206096 -286.044617)
			(xy 281.183225 -286.088194) (xy 281.15366 -286.127538) (xy 281.118167 -286.16163) (xy 281.077664 -286.189586)
			(xy 281.033202 -286.210684) (xy 280.985931 -286.224376) (xy 280.937076 -286.230308) (xy 280.887901 -286.228327)
			(xy 280.839682 -286.218483) (xy 280.793666 -286.201031) (xy 280.751045 -286.176424) (xy 280.712924 -286.145299)
			(xy 280.680289 -286.108462) (xy 280.653986 -286.066866) (xy 280.634695 -286.02159) (xy 280.622918 -285.973806)
			(xy 280.618958 -285.924752) (xy 280.28011 -285.924752) (xy 280.279615 -285.949359) (xy 280.27172 -285.997936)
			(xy 280.256136 -286.044617) (xy 280.233265 -286.088194) (xy 280.2037 -286.127538) (xy 280.168207 -286.16163)
			(xy 280.127704 -286.189586) (xy 280.083242 -286.210684) (xy 280.035971 -286.224376) (xy 279.987116 -286.230308)
			(xy 279.937941 -286.228327) (xy 279.889722 -286.218483) (xy 279.843706 -286.201031) (xy 279.801085 -286.176424)
			(xy 279.762964 -286.145299) (xy 279.730329 -286.108462) (xy 279.704026 -286.066866) (xy 279.684735 -286.02159)
			(xy 279.672958 -285.973806) (xy 279.668998 -285.924752) (xy 279.33015 -285.924752) (xy 279.329655 -285.949359)
			(xy 279.32176 -285.997936) (xy 279.306176 -286.044617) (xy 279.283305 -286.088194) (xy 279.25374 -286.127538)
			(xy 279.218247 -286.16163) (xy 279.177744 -286.189586) (xy 279.133282 -286.210684) (xy 279.086011 -286.224376)
			(xy 279.037156 -286.230308) (xy 278.987981 -286.228327) (xy 278.939762 -286.218483) (xy 278.893746 -286.201031)
			(xy 278.851125 -286.176424) (xy 278.813004 -286.145299) (xy 278.780369 -286.108462) (xy 278.754066 -286.066866)
			(xy 278.734775 -286.02159) (xy 278.722998 -285.973806) (xy 278.719038 -285.924752) (xy 278.38019 -285.924752)
			(xy 278.379695 -285.949359) (xy 278.3718 -285.997936) (xy 278.356216 -286.044617) (xy 278.333345 -286.088194)
			(xy 278.30378 -286.127538) (xy 278.268287 -286.16163) (xy 278.227784 -286.189586) (xy 278.183322 -286.210684)
			(xy 278.136051 -286.224376) (xy 278.087196 -286.230308) (xy 278.038021 -286.228327) (xy 277.989802 -286.218483)
			(xy 277.943786 -286.201031) (xy 277.901165 -286.176424) (xy 277.863044 -286.145299) (xy 277.830409 -286.108462)
			(xy 277.804106 -286.066866) (xy 277.784815 -286.02159) (xy 277.773038 -285.973806) (xy 277.769078 -285.924752)
			(xy 277.43023 -285.924752) (xy 277.429735 -285.949359) (xy 277.42184 -285.997936) (xy 277.406256 -286.044617)
			(xy 277.383385 -286.088194) (xy 277.35382 -286.127538) (xy 277.318327 -286.16163) (xy 277.277824 -286.189586)
			(xy 277.233362 -286.210684) (xy 277.186091 -286.224376) (xy 277.137236 -286.230308) (xy 277.088061 -286.228327)
			(xy 277.039842 -286.218483) (xy 276.993826 -286.201031) (xy 276.951205 -286.176424) (xy 276.913084 -286.145299)
			(xy 276.880449 -286.108462) (xy 276.854146 -286.066866) (xy 276.834855 -286.02159) (xy 276.823078 -285.973806)
			(xy 276.819118 -285.924752) (xy 273.630136 -285.924752) (xy 273.629641 -285.949359) (xy 273.621746 -285.997936)
			(xy 273.606162 -286.044617) (xy 273.583291 -286.088194) (xy 273.553726 -286.127538) (xy 273.518233 -286.16163)
			(xy 273.47773 -286.189586) (xy 273.433268 -286.210684) (xy 273.385997 -286.224376) (xy 273.337142 -286.230308)
			(xy 273.287967 -286.228327) (xy 273.239748 -286.218483) (xy 273.193732 -286.201031) (xy 273.151111 -286.176424)
			(xy 273.11299 -286.145299) (xy 273.080355 -286.108462) (xy 273.054052 -286.066866) (xy 273.034761 -286.02159)
			(xy 273.022984 -285.973806) (xy 273.019024 -285.924752) (xy 272.680176 -285.924752) (xy 272.679681 -285.949359)
			(xy 272.671786 -285.997936) (xy 272.656202 -286.044617) (xy 272.633331 -286.088194) (xy 272.603766 -286.127538)
			(xy 272.568273 -286.16163) (xy 272.52777 -286.189586) (xy 272.483308 -286.210684) (xy 272.436037 -286.224376)
			(xy 272.387182 -286.230308) (xy 272.338007 -286.228327) (xy 272.289788 -286.218483) (xy 272.243772 -286.201031)
			(xy 272.201151 -286.176424) (xy 272.16303 -286.145299) (xy 272.130395 -286.108462) (xy 272.104092 -286.066866)
			(xy 272.084801 -286.02159) (xy 272.073024 -285.973806) (xy 272.069064 -285.924752) (xy 271.730216 -285.924752)
			(xy 271.729721 -285.949359) (xy 271.721826 -285.997936) (xy 271.706242 -286.044617) (xy 271.683371 -286.088194)
			(xy 271.653806 -286.127538) (xy 271.618313 -286.16163) (xy 271.57781 -286.189586) (xy 271.533348 -286.210684)
			(xy 271.486077 -286.224376) (xy 271.437222 -286.230308) (xy 271.388047 -286.228327) (xy 271.339828 -286.218483)
			(xy 271.293812 -286.201031) (xy 271.251191 -286.176424) (xy 271.21307 -286.145299) (xy 271.180435 -286.108462)
			(xy 271.154132 -286.066866) (xy 271.134841 -286.02159) (xy 271.123064 -285.973806) (xy 271.119104 -285.924752)
			(xy 270.780256 -285.924752) (xy 270.779761 -285.949359) (xy 270.771866 -285.997936) (xy 270.756282 -286.044617)
			(xy 270.733411 -286.088194) (xy 270.703846 -286.127538) (xy 270.668353 -286.16163) (xy 270.62785 -286.189586)
			(xy 270.583388 -286.210684) (xy 270.536117 -286.224376) (xy 270.487262 -286.230308) (xy 270.438087 -286.228327)
			(xy 270.389868 -286.218483) (xy 270.343852 -286.201031) (xy 270.301231 -286.176424) (xy 270.26311 -286.145299)
			(xy 270.230475 -286.108462) (xy 270.204172 -286.066866) (xy 270.184881 -286.02159) (xy 270.173104 -285.973806)
			(xy 270.169144 -285.924752) (xy 269.830042 -285.924752) (xy 269.829547 -285.949359) (xy 269.821652 -285.997936)
			(xy 269.806068 -286.044617) (xy 269.783197 -286.088194) (xy 269.753632 -286.127538) (xy 269.718139 -286.16163)
			(xy 269.677636 -286.189586) (xy 269.633174 -286.210684) (xy 269.585903 -286.224376) (xy 269.537048 -286.230308)
			(xy 269.487873 -286.228327) (xy 269.439654 -286.218483) (xy 269.393638 -286.201031) (xy 269.351017 -286.176424)
			(xy 269.312896 -286.145299) (xy 269.280261 -286.108462) (xy 269.253958 -286.066866) (xy 269.234667 -286.02159)
			(xy 269.22289 -285.973806) (xy 269.21893 -285.924752) (xy 268.880082 -285.924752) (xy 268.879587 -285.949359)
			(xy 268.871692 -285.997936) (xy 268.856108 -286.044617) (xy 268.833237 -286.088194) (xy 268.803672 -286.127538)
			(xy 268.768179 -286.16163) (xy 268.727676 -286.189586) (xy 268.683214 -286.210684) (xy 268.635943 -286.224376)
			(xy 268.587088 -286.230308) (xy 268.537913 -286.228327) (xy 268.489694 -286.218483) (xy 268.443678 -286.201031)
			(xy 268.401057 -286.176424) (xy 268.362936 -286.145299) (xy 268.330301 -286.108462) (xy 268.303998 -286.066866)
			(xy 268.284707 -286.02159) (xy 268.27293 -285.973806) (xy 268.26897 -285.924752) (xy 249.737118 -285.924752)
			(xy 249.737118 -286.331914) (xy 258.01142 -286.331914) (xy 258.015491 -286.276292) (xy 258.027617 -286.221855)
			(xy 258.04754 -286.169764) (xy 258.074836 -286.121129) (xy 258.108922 -286.076986) (xy 258.149071 -286.038277)
			(xy 258.194429 -286.005826) (xy 258.244029 -285.980325) (xy 258.296813 -285.962318) (xy 258.351656 -285.952188)
			(xy 258.40739 -285.950151) (xy 258.462827 -285.956251) (xy 258.516784 -285.970357) (xy 258.568113 -285.992169)
			(xy 258.615719 -286.021223) (xy 258.658587 -286.056898) (xy 258.695804 -286.098435) (xy 258.726577 -286.144948)
			(xy 258.750249 -286.195445) (xy 258.766317 -286.248852) (xy 258.774437 -286.304028) (xy 258.774946 -286.331914)
			(xy 259.486906 -286.331914) (xy 259.490977 -286.276292) (xy 259.503103 -286.221855) (xy 259.523026 -286.169764)
			(xy 259.550322 -286.121129) (xy 259.584408 -286.076986) (xy 259.624557 -286.038277) (xy 259.669915 -286.005826)
			(xy 259.719515 -285.980325) (xy 259.772299 -285.962318) (xy 259.827142 -285.952188) (xy 259.882876 -285.950151)
			(xy 259.938313 -285.956251) (xy 259.99227 -285.970357) (xy 260.043599 -285.992169) (xy 260.091205 -286.021223)
			(xy 260.134073 -286.056898) (xy 260.17129 -286.098435) (xy 260.202063 -286.144948) (xy 260.225735 -286.195445)
			(xy 260.241803 -286.248852) (xy 260.249923 -286.304028) (xy 260.250432 -286.331914) (xy 260.375906 -286.331914)
			(xy 260.379977 -286.276292) (xy 260.392103 -286.221855) (xy 260.412026 -286.169764) (xy 260.439322 -286.121129)
			(xy 260.473408 -286.076986) (xy 260.513557 -286.038277) (xy 260.558915 -286.005826) (xy 260.608515 -285.980325)
			(xy 260.661299 -285.962318) (xy 260.716142 -285.952188) (xy 260.771876 -285.950151) (xy 260.827313 -285.956251)
			(xy 260.88127 -285.970357) (xy 260.932599 -285.992169) (xy 260.980205 -286.021223) (xy 261.023073 -286.056898)
			(xy 261.06029 -286.098435) (xy 261.091063 -286.144948) (xy 261.114735 -286.195445) (xy 261.130803 -286.248852)
			(xy 261.138923 -286.304028) (xy 261.139432 -286.331914) (xy 261.138923 -286.3598) (xy 261.130803 -286.414976)
			(xy 261.114735 -286.468383) (xy 261.091063 -286.51888) (xy 261.06029 -286.565393) (xy 261.023073 -286.60693)
			(xy 260.980205 -286.642605) (xy 260.932599 -286.671659) (xy 260.88127 -286.693471) (xy 260.827313 -286.707577)
			(xy 260.771876 -286.713677) (xy 260.716142 -286.71164) (xy 260.661299 -286.70151) (xy 260.608515 -286.683503)
			(xy 260.558915 -286.658002) (xy 260.513557 -286.625551) (xy 260.473408 -286.586842) (xy 260.439322 -286.542699)
			(xy 260.412026 -286.494064) (xy 260.392103 -286.441973) (xy 260.379977 -286.387536) (xy 260.375906 -286.331914)
			(xy 260.250432 -286.331914) (xy 260.249923 -286.3598) (xy 260.241803 -286.414976) (xy 260.225735 -286.468383)
			(xy 260.202063 -286.51888) (xy 260.17129 -286.565393) (xy 260.134073 -286.60693) (xy 260.091205 -286.642605)
			(xy 260.043599 -286.671659) (xy 259.99227 -286.693471) (xy 259.938313 -286.707577) (xy 259.882876 -286.713677)
			(xy 259.827142 -286.71164) (xy 259.772299 -286.70151) (xy 259.719515 -286.683503) (xy 259.669915 -286.658002)
			(xy 259.624557 -286.625551) (xy 259.584408 -286.586842) (xy 259.550322 -286.542699) (xy 259.523026 -286.494064)
			(xy 259.503103 -286.441973) (xy 259.490977 -286.387536) (xy 259.486906 -286.331914) (xy 258.774946 -286.331914)
			(xy 258.774437 -286.3598) (xy 258.766317 -286.414976) (xy 258.750249 -286.468383) (xy 258.726577 -286.51888)
			(xy 258.695804 -286.565393) (xy 258.658587 -286.60693) (xy 258.615719 -286.642605) (xy 258.568113 -286.671659)
			(xy 258.516784 -286.693471) (xy 258.462827 -286.707577) (xy 258.40739 -286.713677) (xy 258.351656 -286.71164)
			(xy 258.296813 -286.70151) (xy 258.244029 -286.683503) (xy 258.194429 -286.658002) (xy 258.149071 -286.625551)
			(xy 258.108922 -286.586842) (xy 258.074836 -286.542699) (xy 258.04754 -286.494064) (xy 258.027617 -286.441973)
			(xy 258.015491 -286.387536) (xy 258.01142 -286.331914) (xy 249.737118 -286.331914) (xy 249.737118 -287.093914)
			(xy 263.537954 -287.093914) (xy 263.53852 -287.064533) (xy 263.547548 -287.006468) (xy 263.565376 -286.950475)
			(xy 263.591583 -286.89788) (xy 263.625547 -286.849928) (xy 263.666466 -286.807754) (xy 263.689592 -286.789622)
			(xy 263.69899 -286.782256) (xy 263.709404 -286.761682) (xy 263.710928 -286.657796) (xy 263.701022 -286.636714)
			(xy 263.691878 -286.629348) (xy 263.670018 -286.611156) (xy 263.63148 -286.569333) (xy 263.599575 -286.522255)
			(xy 263.57501 -286.470963) (xy 263.558329 -286.416593) (xy 263.549902 -286.36035) (xy 263.549384 -286.331914)
			(xy 263.54987 -286.304663) (xy 263.557626 -286.250715) (xy 263.572981 -286.19842) (xy 263.595623 -286.148843)
			(xy 263.625089 -286.102993) (xy 263.66078 -286.061802) (xy 263.701971 -286.026111) (xy 263.747821 -285.996645)
			(xy 263.797398 -285.974003) (xy 263.849693 -285.958648) (xy 263.903641 -285.950892) (xy 263.958143 -285.950892)
			(xy 264.012091 -285.958648) (xy 264.064386 -285.974003) (xy 264.113963 -285.996645) (xy 264.159813 -286.026111)
			(xy 264.201004 -286.061802) (xy 264.236695 -286.102993) (xy 264.266161 -286.148843) (xy 264.288803 -286.19842)
			(xy 264.304158 -286.250715) (xy 264.311914 -286.304663) (xy 264.3124 -286.331914) (xy 264.311872 -286.361297)
			(xy 264.302839 -286.419364) (xy 264.285005 -286.475359) (xy 264.258791 -286.527954) (xy 264.224818 -286.575905)
			(xy 264.183891 -286.618076) (xy 264.160762 -286.636206) (xy 264.151364 -286.643572) (xy 264.14095 -286.664146)
			(xy 264.139426 -286.768032) (xy 264.149332 -286.789114) (xy 264.158476 -286.79648) (xy 264.180292 -286.814723)
			(xy 264.218835 -286.856533) (xy 264.250747 -286.903601) (xy 264.275319 -286.954884) (xy 264.292009 -287.009245)
			(xy 264.300447 -287.065481) (xy 264.30097 -287.093914) (xy 264.934444 -287.093914) (xy 264.938515 -287.038292)
			(xy 264.950641 -286.983855) (xy 264.970564 -286.931764) (xy 264.99786 -286.883129) (xy 265.031946 -286.838986)
			(xy 265.072095 -286.800277) (xy 265.117453 -286.767826) (xy 265.167053 -286.742325) (xy 265.219837 -286.724318)
			(xy 265.27468 -286.714188) (xy 265.330414 -286.712151) (xy 265.385851 -286.718251) (xy 265.439808 -286.732357)
			(xy 265.491137 -286.754169) (xy 265.538743 -286.783223) (xy 265.581611 -286.818898) (xy 265.618828 -286.860435)
			(xy 265.649601 -286.906948) (xy 265.673273 -286.957445) (xy 265.689341 -287.010852) (xy 265.697461 -287.066028)
			(xy 265.69797 -287.093914) (xy 265.820904 -287.093914) (xy 265.824975 -287.038292) (xy 265.837101 -286.983855)
			(xy 265.857024 -286.931764) (xy 265.88432 -286.883129) (xy 265.918406 -286.838986) (xy 265.958555 -286.800277)
			(xy 266.003913 -286.767826) (xy 266.053513 -286.742325) (xy 266.106297 -286.724318) (xy 266.16114 -286.714188)
			(xy 266.216874 -286.712151) (xy 266.272311 -286.718251) (xy 266.326268 -286.732357) (xy 266.377597 -286.754169)
			(xy 266.425203 -286.783223) (xy 266.468071 -286.818898) (xy 266.505288 -286.860435) (xy 266.514902 -286.874966)
			(xy 268.26897 -286.874966) (xy 268.27293 -286.825912) (xy 268.284707 -286.778128) (xy 268.303998 -286.732852)
			(xy 268.330301 -286.691256) (xy 268.362936 -286.654419) (xy 268.401057 -286.623294) (xy 268.443678 -286.598687)
			(xy 268.489694 -286.581235) (xy 268.537913 -286.571391) (xy 268.587088 -286.56941) (xy 268.635943 -286.575342)
			(xy 268.683214 -286.589034) (xy 268.727676 -286.610132) (xy 268.768179 -286.638088) (xy 268.803672 -286.67218)
			(xy 268.833237 -286.711524) (xy 268.856108 -286.755101) (xy 268.871692 -286.801782) (xy 268.879587 -286.850359)
			(xy 268.880082 -286.874966) (xy 269.21893 -286.874966) (xy 269.22289 -286.825912) (xy 269.234667 -286.778128)
			(xy 269.253958 -286.732852) (xy 269.280261 -286.691256) (xy 269.312896 -286.654419) (xy 269.351017 -286.623294)
			(xy 269.393638 -286.598687) (xy 269.439654 -286.581235) (xy 269.487873 -286.571391) (xy 269.537048 -286.56941)
			(xy 269.585903 -286.575342) (xy 269.633174 -286.589034) (xy 269.677636 -286.610132) (xy 269.718139 -286.638088)
			(xy 269.753632 -286.67218) (xy 269.783197 -286.711524) (xy 269.806068 -286.755101) (xy 269.821652 -286.801782)
			(xy 269.829547 -286.850359) (xy 269.830042 -286.874966) (xy 270.169144 -286.874966) (xy 270.173104 -286.825912)
			(xy 270.184881 -286.778128) (xy 270.204172 -286.732852) (xy 270.230475 -286.691256) (xy 270.26311 -286.654419)
			(xy 270.301231 -286.623294) (xy 270.343852 -286.598687) (xy 270.389868 -286.581235) (xy 270.438087 -286.571391)
			(xy 270.487262 -286.56941) (xy 270.536117 -286.575342) (xy 270.583388 -286.589034) (xy 270.62785 -286.610132)
			(xy 270.668353 -286.638088) (xy 270.703846 -286.67218) (xy 270.733411 -286.711524) (xy 270.756282 -286.755101)
			(xy 270.771866 -286.801782) (xy 270.779761 -286.850359) (xy 270.780256 -286.874966) (xy 271.119104 -286.874966)
			(xy 271.123064 -286.825912) (xy 271.134841 -286.778128) (xy 271.154132 -286.732852) (xy 271.180435 -286.691256)
			(xy 271.21307 -286.654419) (xy 271.251191 -286.623294) (xy 271.293812 -286.598687) (xy 271.339828 -286.581235)
			(xy 271.388047 -286.571391) (xy 271.437222 -286.56941) (xy 271.486077 -286.575342) (xy 271.533348 -286.589034)
			(xy 271.57781 -286.610132) (xy 271.618313 -286.638088) (xy 271.653806 -286.67218) (xy 271.683371 -286.711524)
			(xy 271.706242 -286.755101) (xy 271.721826 -286.801782) (xy 271.729721 -286.850359) (xy 271.730216 -286.874966)
			(xy 272.069064 -286.874966) (xy 272.073024 -286.825912) (xy 272.084801 -286.778128) (xy 272.104092 -286.732852)
			(xy 272.130395 -286.691256) (xy 272.16303 -286.654419) (xy 272.201151 -286.623294) (xy 272.243772 -286.598687)
			(xy 272.289788 -286.581235) (xy 272.338007 -286.571391) (xy 272.387182 -286.56941) (xy 272.436037 -286.575342)
			(xy 272.483308 -286.589034) (xy 272.52777 -286.610132) (xy 272.568273 -286.638088) (xy 272.603766 -286.67218)
			(xy 272.633331 -286.711524) (xy 272.656202 -286.755101) (xy 272.671786 -286.801782) (xy 272.679681 -286.850359)
			(xy 272.680176 -286.874966) (xy 273.019024 -286.874966) (xy 273.022984 -286.825912) (xy 273.034761 -286.778128)
			(xy 273.054052 -286.732852) (xy 273.080355 -286.691256) (xy 273.11299 -286.654419) (xy 273.151111 -286.623294)
			(xy 273.193732 -286.598687) (xy 273.239748 -286.581235) (xy 273.287967 -286.571391) (xy 273.337142 -286.56941)
			(xy 273.385997 -286.575342) (xy 273.433268 -286.589034) (xy 273.47773 -286.610132) (xy 273.518233 -286.638088)
			(xy 273.553726 -286.67218) (xy 273.583291 -286.711524) (xy 273.606162 -286.755101) (xy 273.621746 -286.801782)
			(xy 273.629641 -286.850359) (xy 273.630136 -286.874966) (xy 273.968984 -286.874966) (xy 273.972944 -286.825912)
			(xy 273.984721 -286.778128) (xy 274.004012 -286.732852) (xy 274.030315 -286.691256) (xy 274.06295 -286.654419)
			(xy 274.101071 -286.623294) (xy 274.143692 -286.598687) (xy 274.189708 -286.581235) (xy 274.237927 -286.571391)
			(xy 274.287102 -286.56941) (xy 274.335957 -286.575342) (xy 274.383228 -286.589034) (xy 274.42769 -286.610132)
			(xy 274.468193 -286.638088) (xy 274.503686 -286.67218) (xy 274.533251 -286.711524) (xy 274.556122 -286.755101)
			(xy 274.571706 -286.801782) (xy 274.579601 -286.850359) (xy 274.580091 -286.874712) (xy 274.918944 -286.874712)
			(xy 274.922904 -286.825658) (xy 274.934681 -286.777874) (xy 274.953972 -286.732598) (xy 274.980275 -286.691002)
			(xy 275.01291 -286.654165) (xy 275.051031 -286.62304) (xy 275.093652 -286.598433) (xy 275.139668 -286.580981)
			(xy 275.187887 -286.571137) (xy 275.237062 -286.569156) (xy 275.285917 -286.575088) (xy 275.333188 -286.58878)
			(xy 275.37765 -286.609878) (xy 275.418153 -286.637834) (xy 275.453646 -286.671926) (xy 275.483211 -286.71127)
			(xy 275.506082 -286.754847) (xy 275.521666 -286.801528) (xy 275.529561 -286.850105) (xy 275.530056 -286.874712)
			(xy 275.868904 -286.874712) (xy 275.872864 -286.825658) (xy 275.884641 -286.777874) (xy 275.903932 -286.732598)
			(xy 275.930235 -286.691002) (xy 275.96287 -286.654165) (xy 276.000991 -286.62304) (xy 276.043612 -286.598433)
			(xy 276.089628 -286.580981) (xy 276.137847 -286.571137) (xy 276.187022 -286.569156) (xy 276.235877 -286.575088)
			(xy 276.283148 -286.58878) (xy 276.32761 -286.609878) (xy 276.368113 -286.637834) (xy 276.403606 -286.671926)
			(xy 276.433171 -286.71127) (xy 276.456042 -286.754847) (xy 276.471626 -286.801528) (xy 276.479521 -286.850105)
			(xy 276.480016 -286.874712) (xy 276.480011 -286.874966) (xy 276.819118 -286.874966) (xy 276.823078 -286.825912)
			(xy 276.834855 -286.778128) (xy 276.854146 -286.732852) (xy 276.880449 -286.691256) (xy 276.913084 -286.654419)
			(xy 276.951205 -286.623294) (xy 276.993826 -286.598687) (xy 277.039842 -286.581235) (xy 277.088061 -286.571391)
			(xy 277.137236 -286.56941) (xy 277.186091 -286.575342) (xy 277.233362 -286.589034) (xy 277.277824 -286.610132)
			(xy 277.318327 -286.638088) (xy 277.35382 -286.67218) (xy 277.383385 -286.711524) (xy 277.406256 -286.755101)
			(xy 277.42184 -286.801782) (xy 277.429735 -286.850359) (xy 277.43023 -286.874966) (xy 277.769078 -286.874966)
			(xy 277.773038 -286.825912) (xy 277.784815 -286.778128) (xy 277.804106 -286.732852) (xy 277.830409 -286.691256)
			(xy 277.863044 -286.654419) (xy 277.901165 -286.623294) (xy 277.943786 -286.598687) (xy 277.989802 -286.581235)
			(xy 278.038021 -286.571391) (xy 278.087196 -286.56941) (xy 278.136051 -286.575342) (xy 278.183322 -286.589034)
			(xy 278.227784 -286.610132) (xy 278.268287 -286.638088) (xy 278.30378 -286.67218) (xy 278.333345 -286.711524)
			(xy 278.356216 -286.755101) (xy 278.3718 -286.801782) (xy 278.379695 -286.850359) (xy 278.38019 -286.874966)
			(xy 278.719038 -286.874966) (xy 278.722998 -286.825912) (xy 278.734775 -286.778128) (xy 278.754066 -286.732852)
			(xy 278.780369 -286.691256) (xy 278.813004 -286.654419) (xy 278.851125 -286.623294) (xy 278.893746 -286.598687)
			(xy 278.939762 -286.581235) (xy 278.987981 -286.571391) (xy 279.037156 -286.56941) (xy 279.086011 -286.575342)
			(xy 279.133282 -286.589034) (xy 279.177744 -286.610132) (xy 279.218247 -286.638088) (xy 279.25374 -286.67218)
			(xy 279.283305 -286.711524) (xy 279.306176 -286.755101) (xy 279.32176 -286.801782) (xy 279.329655 -286.850359)
			(xy 279.33015 -286.874966) (xy 279.668998 -286.874966) (xy 279.672958 -286.825912) (xy 279.684735 -286.778128)
			(xy 279.704026 -286.732852) (xy 279.730329 -286.691256) (xy 279.762964 -286.654419) (xy 279.801085 -286.623294)
			(xy 279.843706 -286.598687) (xy 279.889722 -286.581235) (xy 279.937941 -286.571391) (xy 279.987116 -286.56941)
			(xy 280.035971 -286.575342) (xy 280.083242 -286.589034) (xy 280.127704 -286.610132) (xy 280.168207 -286.638088)
			(xy 280.2037 -286.67218) (xy 280.233265 -286.711524) (xy 280.256136 -286.755101) (xy 280.27172 -286.801782)
			(xy 280.279615 -286.850359) (xy 280.28011 -286.874966) (xy 280.618958 -286.874966) (xy 280.622918 -286.825912)
			(xy 280.634695 -286.778128) (xy 280.653986 -286.732852) (xy 280.680289 -286.691256) (xy 280.712924 -286.654419)
			(xy 280.751045 -286.623294) (xy 280.793666 -286.598687) (xy 280.839682 -286.581235) (xy 280.887901 -286.571391)
			(xy 280.937076 -286.56941) (xy 280.985931 -286.575342) (xy 281.033202 -286.589034) (xy 281.077664 -286.610132)
			(xy 281.118167 -286.638088) (xy 281.15366 -286.67218) (xy 281.183225 -286.711524) (xy 281.206096 -286.755101)
			(xy 281.22168 -286.801782) (xy 281.229575 -286.850359) (xy 281.23007 -286.874966) (xy 281.568918 -286.874966)
			(xy 281.572878 -286.825912) (xy 281.584655 -286.778128) (xy 281.603946 -286.732852) (xy 281.630249 -286.691256)
			(xy 281.662884 -286.654419) (xy 281.701005 -286.623294) (xy 281.743626 -286.598687) (xy 281.789642 -286.581235)
			(xy 281.837861 -286.571391) (xy 281.887036 -286.56941) (xy 281.935891 -286.575342) (xy 281.983162 -286.589034)
			(xy 282.027624 -286.610132) (xy 282.068127 -286.638088) (xy 282.10362 -286.67218) (xy 282.133185 -286.711524)
			(xy 282.156056 -286.755101) (xy 282.17164 -286.801782) (xy 282.179535 -286.850359) (xy 282.18003 -286.874966)
			(xy 300.56888 -286.874966) (xy 300.57284 -286.825912) (xy 300.584617 -286.778128) (xy 300.603908 -286.732852)
			(xy 300.630211 -286.691256) (xy 300.662846 -286.654419) (xy 300.700967 -286.623294) (xy 300.743588 -286.598687)
			(xy 300.789604 -286.581235) (xy 300.837823 -286.571391) (xy 300.886998 -286.56941) (xy 300.935853 -286.575342)
			(xy 300.983124 -286.589034) (xy 301.027586 -286.610132) (xy 301.068089 -286.638088) (xy 301.103582 -286.67218)
			(xy 301.133147 -286.711524) (xy 301.156018 -286.755101) (xy 301.171602 -286.801782) (xy 301.179497 -286.850359)
			(xy 301.179992 -286.874966) (xy 301.519094 -286.874966) (xy 301.523054 -286.825912) (xy 301.534831 -286.778128)
			(xy 301.554122 -286.732852) (xy 301.580425 -286.691256) (xy 301.61306 -286.654419) (xy 301.651181 -286.623294)
			(xy 301.693802 -286.598687) (xy 301.739818 -286.581235) (xy 301.788037 -286.571391) (xy 301.837212 -286.56941)
			(xy 301.886067 -286.575342) (xy 301.933338 -286.589034) (xy 301.9778 -286.610132) (xy 302.018303 -286.638088)
			(xy 302.053796 -286.67218) (xy 302.083361 -286.711524) (xy 302.106232 -286.755101) (xy 302.121816 -286.801782)
			(xy 302.129711 -286.850359) (xy 302.130206 -286.874966) (xy 302.469054 -286.874966) (xy 302.473014 -286.825912)
			(xy 302.484791 -286.778128) (xy 302.504082 -286.732852) (xy 302.530385 -286.691256) (xy 302.56302 -286.654419)
			(xy 302.601141 -286.623294) (xy 302.643762 -286.598687) (xy 302.689778 -286.581235) (xy 302.737997 -286.571391)
			(xy 302.787172 -286.56941) (xy 302.836027 -286.575342) (xy 302.883298 -286.589034) (xy 302.92776 -286.610132)
			(xy 302.968263 -286.638088) (xy 303.003756 -286.67218) (xy 303.033321 -286.711524) (xy 303.056192 -286.755101)
			(xy 303.071776 -286.801782) (xy 303.079671 -286.850359) (xy 303.080166 -286.874966) (xy 303.079671 -286.899573)
			(xy 303.071776 -286.94815) (xy 303.056192 -286.994831) (xy 303.033321 -287.038408) (xy 303.003756 -287.077752)
			(xy 302.968263 -287.111844) (xy 302.92776 -287.1398) (xy 302.883298 -287.160898) (xy 302.836027 -287.17459)
			(xy 302.787172 -287.180522) (xy 302.737997 -287.178541) (xy 302.689778 -287.168697) (xy 302.643762 -287.151245)
			(xy 302.601141 -287.126638) (xy 302.56302 -287.095513) (xy 302.530385 -287.058676) (xy 302.504082 -287.01708)
			(xy 302.484791 -286.971804) (xy 302.473014 -286.92402) (xy 302.469054 -286.874966) (xy 302.130206 -286.874966)
			(xy 302.129711 -286.899573) (xy 302.121816 -286.94815) (xy 302.106232 -286.994831) (xy 302.083361 -287.038408)
			(xy 302.053796 -287.077752) (xy 302.018303 -287.111844) (xy 301.9778 -287.1398) (xy 301.933338 -287.160898)
			(xy 301.886067 -287.17459) (xy 301.837212 -287.180522) (xy 301.788037 -287.178541) (xy 301.739818 -287.168697)
			(xy 301.693802 -287.151245) (xy 301.651181 -287.126638) (xy 301.61306 -287.095513) (xy 301.580425 -287.058676)
			(xy 301.554122 -287.01708) (xy 301.534831 -286.971804) (xy 301.523054 -286.92402) (xy 301.519094 -286.874966)
			(xy 301.179992 -286.874966) (xy 301.179497 -286.899573) (xy 301.171602 -286.94815) (xy 301.156018 -286.994831)
			(xy 301.133147 -287.038408) (xy 301.103582 -287.077752) (xy 301.068089 -287.111844) (xy 301.027586 -287.1398)
			(xy 300.983124 -287.160898) (xy 300.935853 -287.17459) (xy 300.886998 -287.180522) (xy 300.837823 -287.178541)
			(xy 300.789604 -287.168697) (xy 300.743588 -287.151245) (xy 300.700967 -287.126638) (xy 300.662846 -287.095513)
			(xy 300.630211 -287.058676) (xy 300.603908 -287.01708) (xy 300.584617 -286.971804) (xy 300.57284 -286.92402)
			(xy 300.56888 -286.874966) (xy 282.18003 -286.874966) (xy 282.179535 -286.899573) (xy 282.17164 -286.94815)
			(xy 282.156056 -286.994831) (xy 282.133185 -287.038408) (xy 282.10362 -287.077752) (xy 282.068127 -287.111844)
			(xy 282.027624 -287.1398) (xy 281.983162 -287.160898) (xy 281.935891 -287.17459) (xy 281.887036 -287.180522)
			(xy 281.837861 -287.178541) (xy 281.789642 -287.168697) (xy 281.743626 -287.151245) (xy 281.701005 -287.126638)
			(xy 281.662884 -287.095513) (xy 281.630249 -287.058676) (xy 281.603946 -287.01708) (xy 281.584655 -286.971804)
			(xy 281.572878 -286.92402) (xy 281.568918 -286.874966) (xy 281.23007 -286.874966) (xy 281.229575 -286.899573)
			(xy 281.22168 -286.94815) (xy 281.206096 -286.994831) (xy 281.183225 -287.038408) (xy 281.15366 -287.077752)
			(xy 281.118167 -287.111844) (xy 281.077664 -287.1398) (xy 281.033202 -287.160898) (xy 280.985931 -287.17459)
			(xy 280.937076 -287.180522) (xy 280.887901 -287.178541) (xy 280.839682 -287.168697) (xy 280.793666 -287.151245)
			(xy 280.751045 -287.126638) (xy 280.712924 -287.095513) (xy 280.680289 -287.058676) (xy 280.653986 -287.01708)
			(xy 280.634695 -286.971804) (xy 280.622918 -286.92402) (xy 280.618958 -286.874966) (xy 280.28011 -286.874966)
			(xy 280.279615 -286.899573) (xy 280.27172 -286.94815) (xy 280.256136 -286.994831) (xy 280.233265 -287.038408)
			(xy 280.2037 -287.077752) (xy 280.168207 -287.111844) (xy 280.127704 -287.1398) (xy 280.083242 -287.160898)
			(xy 280.035971 -287.17459) (xy 279.987116 -287.180522) (xy 279.937941 -287.178541) (xy 279.889722 -287.168697)
			(xy 279.843706 -287.151245) (xy 279.801085 -287.126638) (xy 279.762964 -287.095513) (xy 279.730329 -287.058676)
			(xy 279.704026 -287.01708) (xy 279.684735 -286.971804) (xy 279.672958 -286.92402) (xy 279.668998 -286.874966)
			(xy 279.33015 -286.874966) (xy 279.329655 -286.899573) (xy 279.32176 -286.94815) (xy 279.306176 -286.994831)
			(xy 279.283305 -287.038408) (xy 279.25374 -287.077752) (xy 279.218247 -287.111844) (xy 279.177744 -287.1398)
			(xy 279.133282 -287.160898) (xy 279.086011 -287.17459) (xy 279.037156 -287.180522) (xy 278.987981 -287.178541)
			(xy 278.939762 -287.168697) (xy 278.893746 -287.151245) (xy 278.851125 -287.126638) (xy 278.813004 -287.095513)
			(xy 278.780369 -287.058676) (xy 278.754066 -287.01708) (xy 278.734775 -286.971804) (xy 278.722998 -286.92402)
			(xy 278.719038 -286.874966) (xy 278.38019 -286.874966) (xy 278.379695 -286.899573) (xy 278.3718 -286.94815)
			(xy 278.356216 -286.994831) (xy 278.333345 -287.038408) (xy 278.30378 -287.077752) (xy 278.268287 -287.111844)
			(xy 278.227784 -287.1398) (xy 278.183322 -287.160898) (xy 278.136051 -287.17459) (xy 278.087196 -287.180522)
			(xy 278.038021 -287.178541) (xy 277.989802 -287.168697) (xy 277.943786 -287.151245) (xy 277.901165 -287.126638)
			(xy 277.863044 -287.095513) (xy 277.830409 -287.058676) (xy 277.804106 -287.01708) (xy 277.784815 -286.971804)
			(xy 277.773038 -286.92402) (xy 277.769078 -286.874966) (xy 277.43023 -286.874966) (xy 277.429735 -286.899573)
			(xy 277.42184 -286.94815) (xy 277.406256 -286.994831) (xy 277.383385 -287.038408) (xy 277.35382 -287.077752)
			(xy 277.318327 -287.111844) (xy 277.277824 -287.1398) (xy 277.233362 -287.160898) (xy 277.186091 -287.17459)
			(xy 277.137236 -287.180522) (xy 277.088061 -287.178541) (xy 277.039842 -287.168697) (xy 276.993826 -287.151245)
			(xy 276.951205 -287.126638) (xy 276.913084 -287.095513) (xy 276.880449 -287.058676) (xy 276.854146 -287.01708)
			(xy 276.834855 -286.971804) (xy 276.823078 -286.92402) (xy 276.819118 -286.874966) (xy 276.480011 -286.874966)
			(xy 276.479521 -286.899319) (xy 276.471626 -286.947896) (xy 276.456042 -286.994577) (xy 276.433171 -287.038154)
			(xy 276.403606 -287.077498) (xy 276.368113 -287.11159) (xy 276.32761 -287.139546) (xy 276.283148 -287.160644)
			(xy 276.235877 -287.174336) (xy 276.187022 -287.180268) (xy 276.137847 -287.178287) (xy 276.089628 -287.168443)
			(xy 276.043612 -287.150991) (xy 276.000991 -287.126384) (xy 275.96287 -287.095259) (xy 275.930235 -287.058422)
			(xy 275.903932 -287.016826) (xy 275.884641 -286.97155) (xy 275.872864 -286.923766) (xy 275.868904 -286.874712)
			(xy 275.530056 -286.874712) (xy 275.529561 -286.899319) (xy 275.521666 -286.947896) (xy 275.506082 -286.994577)
			(xy 275.483211 -287.038154) (xy 275.453646 -287.077498) (xy 275.418153 -287.11159) (xy 275.37765 -287.139546)
			(xy 275.333188 -287.160644) (xy 275.285917 -287.174336) (xy 275.237062 -287.180268) (xy 275.187887 -287.178287)
			(xy 275.139668 -287.168443) (xy 275.093652 -287.150991) (xy 275.051031 -287.126384) (xy 275.01291 -287.095259)
			(xy 274.980275 -287.058422) (xy 274.953972 -287.016826) (xy 274.934681 -286.97155) (xy 274.922904 -286.923766)
			(xy 274.918944 -286.874712) (xy 274.580091 -286.874712) (xy 274.580096 -286.874966) (xy 274.579601 -286.899573)
			(xy 274.571706 -286.94815) (xy 274.556122 -286.994831) (xy 274.533251 -287.038408) (xy 274.503686 -287.077752)
			(xy 274.468193 -287.111844) (xy 274.42769 -287.1398) (xy 274.383228 -287.160898) (xy 274.335957 -287.17459)
			(xy 274.287102 -287.180522) (xy 274.237927 -287.178541) (xy 274.189708 -287.168697) (xy 274.143692 -287.151245)
			(xy 274.101071 -287.126638) (xy 274.06295 -287.095513) (xy 274.030315 -287.058676) (xy 274.004012 -287.01708)
			(xy 273.984721 -286.971804) (xy 273.972944 -286.92402) (xy 273.968984 -286.874966) (xy 273.630136 -286.874966)
			(xy 273.629641 -286.899573) (xy 273.621746 -286.94815) (xy 273.606162 -286.994831) (xy 273.583291 -287.038408)
			(xy 273.553726 -287.077752) (xy 273.518233 -287.111844) (xy 273.47773 -287.1398) (xy 273.433268 -287.160898)
			(xy 273.385997 -287.17459) (xy 273.337142 -287.180522) (xy 273.287967 -287.178541) (xy 273.239748 -287.168697)
			(xy 273.193732 -287.151245) (xy 273.151111 -287.126638) (xy 273.11299 -287.095513) (xy 273.080355 -287.058676)
			(xy 273.054052 -287.01708) (xy 273.034761 -286.971804) (xy 273.022984 -286.92402) (xy 273.019024 -286.874966)
			(xy 272.680176 -286.874966) (xy 272.679681 -286.899573) (xy 272.671786 -286.94815) (xy 272.656202 -286.994831)
			(xy 272.633331 -287.038408) (xy 272.603766 -287.077752) (xy 272.568273 -287.111844) (xy 272.52777 -287.1398)
			(xy 272.483308 -287.160898) (xy 272.436037 -287.17459) (xy 272.387182 -287.180522) (xy 272.338007 -287.178541)
			(xy 272.289788 -287.168697) (xy 272.243772 -287.151245) (xy 272.201151 -287.126638) (xy 272.16303 -287.095513)
			(xy 272.130395 -287.058676) (xy 272.104092 -287.01708) (xy 272.084801 -286.971804) (xy 272.073024 -286.92402)
			(xy 272.069064 -286.874966) (xy 271.730216 -286.874966) (xy 271.729721 -286.899573) (xy 271.721826 -286.94815)
			(xy 271.706242 -286.994831) (xy 271.683371 -287.038408) (xy 271.653806 -287.077752) (xy 271.618313 -287.111844)
			(xy 271.57781 -287.1398) (xy 271.533348 -287.160898) (xy 271.486077 -287.17459) (xy 271.437222 -287.180522)
			(xy 271.388047 -287.178541) (xy 271.339828 -287.168697) (xy 271.293812 -287.151245) (xy 271.251191 -287.126638)
			(xy 271.21307 -287.095513) (xy 271.180435 -287.058676) (xy 271.154132 -287.01708) (xy 271.134841 -286.971804)
			(xy 271.123064 -286.92402) (xy 271.119104 -286.874966) (xy 270.780256 -286.874966) (xy 270.779761 -286.899573)
			(xy 270.771866 -286.94815) (xy 270.756282 -286.994831) (xy 270.733411 -287.038408) (xy 270.703846 -287.077752)
			(xy 270.668353 -287.111844) (xy 270.62785 -287.1398) (xy 270.583388 -287.160898) (xy 270.536117 -287.17459)
			(xy 270.487262 -287.180522) (xy 270.438087 -287.178541) (xy 270.389868 -287.168697) (xy 270.343852 -287.151245)
			(xy 270.301231 -287.126638) (xy 270.26311 -287.095513) (xy 270.230475 -287.058676) (xy 270.204172 -287.01708)
			(xy 270.184881 -286.971804) (xy 270.173104 -286.92402) (xy 270.169144 -286.874966) (xy 269.830042 -286.874966)
			(xy 269.829547 -286.899573) (xy 269.821652 -286.94815) (xy 269.806068 -286.994831) (xy 269.783197 -287.038408)
			(xy 269.753632 -287.077752) (xy 269.718139 -287.111844) (xy 269.677636 -287.1398) (xy 269.633174 -287.160898)
			(xy 269.585903 -287.17459) (xy 269.537048 -287.180522) (xy 269.487873 -287.178541) (xy 269.439654 -287.168697)
			(xy 269.393638 -287.151245) (xy 269.351017 -287.126638) (xy 269.312896 -287.095513) (xy 269.280261 -287.058676)
			(xy 269.253958 -287.01708) (xy 269.234667 -286.971804) (xy 269.22289 -286.92402) (xy 269.21893 -286.874966)
			(xy 268.880082 -286.874966) (xy 268.879587 -286.899573) (xy 268.871692 -286.94815) (xy 268.856108 -286.994831)
			(xy 268.833237 -287.038408) (xy 268.803672 -287.077752) (xy 268.768179 -287.111844) (xy 268.727676 -287.1398)
			(xy 268.683214 -287.160898) (xy 268.635943 -287.17459) (xy 268.587088 -287.180522) (xy 268.537913 -287.178541)
			(xy 268.489694 -287.168697) (xy 268.443678 -287.151245) (xy 268.401057 -287.126638) (xy 268.362936 -287.095513)
			(xy 268.330301 -287.058676) (xy 268.303998 -287.01708) (xy 268.284707 -286.971804) (xy 268.27293 -286.92402)
			(xy 268.26897 -286.874966) (xy 266.514902 -286.874966) (xy 266.536061 -286.906948) (xy 266.559733 -286.957445)
			(xy 266.575801 -287.010852) (xy 266.583921 -287.066028) (xy 266.58443 -287.093914) (xy 266.583921 -287.1218)
			(xy 266.575801 -287.176976) (xy 266.559733 -287.230383) (xy 266.536061 -287.28088) (xy 266.505288 -287.327393)
			(xy 266.468071 -287.36893) (xy 266.425203 -287.404605) (xy 266.377597 -287.433659) (xy 266.326268 -287.455471)
			(xy 266.272311 -287.469577) (xy 266.216874 -287.475677) (xy 266.16114 -287.47364) (xy 266.106297 -287.46351)
			(xy 266.053513 -287.445503) (xy 266.003913 -287.420002) (xy 265.958555 -287.387551) (xy 265.918406 -287.348842)
			(xy 265.88432 -287.304699) (xy 265.857024 -287.256064) (xy 265.837101 -287.203973) (xy 265.824975 -287.149536)
			(xy 265.820904 -287.093914) (xy 265.69797 -287.093914) (xy 265.697461 -287.1218) (xy 265.689341 -287.176976)
			(xy 265.673273 -287.230383) (xy 265.649601 -287.28088) (xy 265.618828 -287.327393) (xy 265.581611 -287.36893)
			(xy 265.538743 -287.404605) (xy 265.491137 -287.433659) (xy 265.439808 -287.455471) (xy 265.385851 -287.469577)
			(xy 265.330414 -287.475677) (xy 265.27468 -287.47364) (xy 265.219837 -287.46351) (xy 265.167053 -287.445503)
			(xy 265.117453 -287.420002) (xy 265.072095 -287.387551) (xy 265.031946 -287.348842) (xy 264.99786 -287.304699)
			(xy 264.970564 -287.256064) (xy 264.950641 -287.203973) (xy 264.938515 -287.149536) (xy 264.934444 -287.093914)
			(xy 264.30097 -287.093914) (xy 264.300484 -287.121165) (xy 264.292728 -287.175113) (xy 264.277373 -287.227408)
			(xy 264.254731 -287.276985) (xy 264.225265 -287.322835) (xy 264.189574 -287.364026) (xy 264.148383 -287.399717)
			(xy 264.102533 -287.429183) (xy 264.052956 -287.451825) (xy 264.000661 -287.46718) (xy 263.946713 -287.474936)
			(xy 263.892211 -287.474936) (xy 263.838263 -287.46718) (xy 263.785968 -287.451825) (xy 263.736391 -287.429183)
			(xy 263.690541 -287.399717) (xy 263.64935 -287.364026) (xy 263.613659 -287.322835) (xy 263.584193 -287.276985)
			(xy 263.561551 -287.227408) (xy 263.546196 -287.175113) (xy 263.53844 -287.121165) (xy 263.537954 -287.093914)
			(xy 249.737118 -287.093914) (xy 249.737118 -287.824926) (xy 268.26897 -287.824926) (xy 268.27293 -287.775872)
			(xy 268.284707 -287.728088) (xy 268.303998 -287.682812) (xy 268.330301 -287.641216) (xy 268.362936 -287.604379)
			(xy 268.401057 -287.573254) (xy 268.443678 -287.548647) (xy 268.489694 -287.531195) (xy 268.537913 -287.521351)
			(xy 268.587088 -287.51937) (xy 268.635943 -287.525302) (xy 268.683214 -287.538994) (xy 268.727676 -287.560092)
			(xy 268.768179 -287.588048) (xy 268.803672 -287.62214) (xy 268.833237 -287.661484) (xy 268.856108 -287.705061)
			(xy 268.871692 -287.751742) (xy 268.879587 -287.800319) (xy 268.880082 -287.824926) (xy 269.21893 -287.824926)
			(xy 269.22289 -287.775872) (xy 269.234667 -287.728088) (xy 269.253958 -287.682812) (xy 269.280261 -287.641216)
			(xy 269.312896 -287.604379) (xy 269.351017 -287.573254) (xy 269.393638 -287.548647) (xy 269.439654 -287.531195)
			(xy 269.487873 -287.521351) (xy 269.537048 -287.51937) (xy 269.585903 -287.525302) (xy 269.633174 -287.538994)
			(xy 269.677636 -287.560092) (xy 269.718139 -287.588048) (xy 269.753632 -287.62214) (xy 269.783197 -287.661484)
			(xy 269.806068 -287.705061) (xy 269.821652 -287.751742) (xy 269.829547 -287.800319) (xy 269.830042 -287.824926)
			(xy 270.169144 -287.824926) (xy 270.173104 -287.775872) (xy 270.184881 -287.728088) (xy 270.204172 -287.682812)
			(xy 270.230475 -287.641216) (xy 270.26311 -287.604379) (xy 270.301231 -287.573254) (xy 270.343852 -287.548647)
			(xy 270.389868 -287.531195) (xy 270.438087 -287.521351) (xy 270.487262 -287.51937) (xy 270.536117 -287.525302)
			(xy 270.583388 -287.538994) (xy 270.62785 -287.560092) (xy 270.668353 -287.588048) (xy 270.703846 -287.62214)
			(xy 270.733411 -287.661484) (xy 270.756282 -287.705061) (xy 270.771866 -287.751742) (xy 270.779761 -287.800319)
			(xy 270.780256 -287.824926) (xy 273.019024 -287.824926) (xy 273.022984 -287.775872) (xy 273.034761 -287.728088)
			(xy 273.054052 -287.682812) (xy 273.080355 -287.641216) (xy 273.11299 -287.604379) (xy 273.151111 -287.573254)
			(xy 273.193732 -287.548647) (xy 273.239748 -287.531195) (xy 273.287967 -287.521351) (xy 273.337142 -287.51937)
			(xy 273.385997 -287.525302) (xy 273.433268 -287.538994) (xy 273.47773 -287.560092) (xy 273.518233 -287.588048)
			(xy 273.553726 -287.62214) (xy 273.583291 -287.661484) (xy 273.606162 -287.705061) (xy 273.621746 -287.751742)
			(xy 273.629641 -287.800319) (xy 273.630136 -287.824926) (xy 276.819118 -287.824926) (xy 276.823078 -287.775872)
			(xy 276.834855 -287.728088) (xy 276.854146 -287.682812) (xy 276.880449 -287.641216) (xy 276.913084 -287.604379)
			(xy 276.951205 -287.573254) (xy 276.993826 -287.548647) (xy 277.039842 -287.531195) (xy 277.088061 -287.521351)
			(xy 277.137236 -287.51937) (xy 277.186091 -287.525302) (xy 277.233362 -287.538994) (xy 277.277824 -287.560092)
			(xy 277.318327 -287.588048) (xy 277.35382 -287.62214) (xy 277.383385 -287.661484) (xy 277.406256 -287.705061)
			(xy 277.42184 -287.751742) (xy 277.429735 -287.800319) (xy 277.43023 -287.824926) (xy 277.769078 -287.824926)
			(xy 277.773038 -287.775872) (xy 277.784815 -287.728088) (xy 277.804106 -287.682812) (xy 277.830409 -287.641216)
			(xy 277.863044 -287.604379) (xy 277.901165 -287.573254) (xy 277.943786 -287.548647) (xy 277.989802 -287.531195)
			(xy 278.038021 -287.521351) (xy 278.087196 -287.51937) (xy 278.136051 -287.525302) (xy 278.183322 -287.538994)
			(xy 278.227784 -287.560092) (xy 278.268287 -287.588048) (xy 278.30378 -287.62214) (xy 278.333345 -287.661484)
			(xy 278.356216 -287.705061) (xy 278.3718 -287.751742) (xy 278.379695 -287.800319) (xy 278.38019 -287.824926)
			(xy 278.719038 -287.824926) (xy 278.722998 -287.775872) (xy 278.734775 -287.728088) (xy 278.754066 -287.682812)
			(xy 278.780369 -287.641216) (xy 278.813004 -287.604379) (xy 278.851125 -287.573254) (xy 278.893746 -287.548647)
			(xy 278.939762 -287.531195) (xy 278.987981 -287.521351) (xy 279.037156 -287.51937) (xy 279.086011 -287.525302)
			(xy 279.133282 -287.538994) (xy 279.177744 -287.560092) (xy 279.218247 -287.588048) (xy 279.25374 -287.62214)
			(xy 279.283305 -287.661484) (xy 279.306176 -287.705061) (xy 279.32176 -287.751742) (xy 279.329655 -287.800319)
			(xy 279.33015 -287.824926) (xy 279.668998 -287.824926) (xy 279.672958 -287.775872) (xy 279.684735 -287.728088)
			(xy 279.704026 -287.682812) (xy 279.730329 -287.641216) (xy 279.762964 -287.604379) (xy 279.801085 -287.573254)
			(xy 279.843706 -287.548647) (xy 279.889722 -287.531195) (xy 279.937941 -287.521351) (xy 279.987116 -287.51937)
			(xy 280.035971 -287.525302) (xy 280.083242 -287.538994) (xy 280.127704 -287.560092) (xy 280.168207 -287.588048)
			(xy 280.2037 -287.62214) (xy 280.233265 -287.661484) (xy 280.256136 -287.705061) (xy 280.27172 -287.751742)
			(xy 280.279615 -287.800319) (xy 280.28011 -287.824926) (xy 280.618958 -287.824926) (xy 280.622918 -287.775872)
			(xy 280.634695 -287.728088) (xy 280.653986 -287.682812) (xy 280.680289 -287.641216) (xy 280.712924 -287.604379)
			(xy 280.751045 -287.573254) (xy 280.793666 -287.548647) (xy 280.839682 -287.531195) (xy 280.887901 -287.521351)
			(xy 280.937076 -287.51937) (xy 280.985931 -287.525302) (xy 281.033202 -287.538994) (xy 281.077664 -287.560092)
			(xy 281.118167 -287.588048) (xy 281.15366 -287.62214) (xy 281.183225 -287.661484) (xy 281.206096 -287.705061)
			(xy 281.22168 -287.751742) (xy 281.229575 -287.800319) (xy 281.23007 -287.824926) (xy 281.568918 -287.824926)
			(xy 281.572878 -287.775872) (xy 281.584655 -287.728088) (xy 281.603946 -287.682812) (xy 281.630249 -287.641216)
			(xy 281.662884 -287.604379) (xy 281.701005 -287.573254) (xy 281.743626 -287.548647) (xy 281.789642 -287.531195)
			(xy 281.837861 -287.521351) (xy 281.887036 -287.51937) (xy 281.935891 -287.525302) (xy 281.983162 -287.538994)
			(xy 282.027624 -287.560092) (xy 282.068127 -287.588048) (xy 282.10362 -287.62214) (xy 282.133185 -287.661484)
			(xy 282.156056 -287.705061) (xy 282.17164 -287.751742) (xy 282.179535 -287.800319) (xy 282.18003 -287.824926)
			(xy 282.519132 -287.824926) (xy 282.523092 -287.775872) (xy 282.534869 -287.728088) (xy 282.55416 -287.682812)
			(xy 282.580463 -287.641216) (xy 282.613098 -287.604379) (xy 282.651219 -287.573254) (xy 282.69384 -287.548647)
			(xy 282.739856 -287.531195) (xy 282.788075 -287.521351) (xy 282.83725 -287.51937) (xy 282.886105 -287.525302)
			(xy 282.933376 -287.538994) (xy 282.977838 -287.560092) (xy 283.018341 -287.588048) (xy 283.053834 -287.62214)
			(xy 283.083399 -287.661484) (xy 283.10627 -287.705061) (xy 283.121854 -287.751742) (xy 283.129749 -287.800319)
			(xy 283.130244 -287.824926) (xy 283.469092 -287.824926) (xy 283.473052 -287.775872) (xy 283.484829 -287.728088)
			(xy 283.50412 -287.682812) (xy 283.530423 -287.641216) (xy 283.563058 -287.604379) (xy 283.601179 -287.573254)
			(xy 283.6438 -287.548647) (xy 283.689816 -287.531195) (xy 283.738035 -287.521351) (xy 283.78721 -287.51937)
			(xy 283.836065 -287.525302) (xy 283.883336 -287.538994) (xy 283.927798 -287.560092) (xy 283.968301 -287.588048)
			(xy 284.003794 -287.62214) (xy 284.033359 -287.661484) (xy 284.05623 -287.705061) (xy 284.071814 -287.751742)
			(xy 284.079709 -287.800319) (xy 284.080204 -287.824926) (xy 284.419052 -287.824926) (xy 284.423012 -287.775872)
			(xy 284.434789 -287.728088) (xy 284.45408 -287.682812) (xy 284.480383 -287.641216) (xy 284.513018 -287.604379)
			(xy 284.551139 -287.573254) (xy 284.59376 -287.548647) (xy 284.639776 -287.531195) (xy 284.687995 -287.521351)
			(xy 284.73717 -287.51937) (xy 284.786025 -287.525302) (xy 284.833296 -287.538994) (xy 284.877758 -287.560092)
			(xy 284.918261 -287.588048) (xy 284.953754 -287.62214) (xy 284.983319 -287.661484) (xy 285.00619 -287.705061)
			(xy 285.021774 -287.751742) (xy 285.029669 -287.800319) (xy 285.030164 -287.824926) (xy 285.369012 -287.824926)
			(xy 285.372972 -287.775872) (xy 285.384749 -287.728088) (xy 285.40404 -287.682812) (xy 285.430343 -287.641216)
			(xy 285.462978 -287.604379) (xy 285.501099 -287.573254) (xy 285.54372 -287.548647) (xy 285.589736 -287.531195)
			(xy 285.637955 -287.521351) (xy 285.68713 -287.51937) (xy 285.735985 -287.525302) (xy 285.783256 -287.538994)
			(xy 285.827718 -287.560092) (xy 285.868221 -287.588048) (xy 285.903714 -287.62214) (xy 285.933279 -287.661484)
			(xy 285.95615 -287.705061) (xy 285.971734 -287.751742) (xy 285.979629 -287.800319) (xy 285.980124 -287.824926)
			(xy 286.318972 -287.824926) (xy 286.322932 -287.775872) (xy 286.334709 -287.728088) (xy 286.354 -287.682812)
			(xy 286.380303 -287.641216) (xy 286.412938 -287.604379) (xy 286.451059 -287.573254) (xy 286.49368 -287.548647)
			(xy 286.539696 -287.531195) (xy 286.587915 -287.521351) (xy 286.63709 -287.51937) (xy 286.685945 -287.525302)
			(xy 286.733216 -287.538994) (xy 286.777678 -287.560092) (xy 286.818181 -287.588048) (xy 286.853674 -287.62214)
			(xy 286.883239 -287.661484) (xy 286.90611 -287.705061) (xy 286.921694 -287.751742) (xy 286.929589 -287.800319)
			(xy 286.930084 -287.824926) (xy 287.268932 -287.824926) (xy 287.272892 -287.775872) (xy 287.284669 -287.728088)
			(xy 287.30396 -287.682812) (xy 287.330263 -287.641216) (xy 287.362898 -287.604379) (xy 287.401019 -287.573254)
			(xy 287.44364 -287.548647) (xy 287.489656 -287.531195) (xy 287.537875 -287.521351) (xy 287.58705 -287.51937)
			(xy 287.635905 -287.525302) (xy 287.683176 -287.538994) (xy 287.727638 -287.560092) (xy 287.768141 -287.588048)
			(xy 287.803634 -287.62214) (xy 287.833199 -287.661484) (xy 287.85607 -287.705061) (xy 287.871654 -287.751742)
			(xy 287.879549 -287.800319) (xy 287.880044 -287.824926) (xy 288.218892 -287.824926) (xy 288.222852 -287.775872)
			(xy 288.234629 -287.728088) (xy 288.25392 -287.682812) (xy 288.280223 -287.641216) (xy 288.312858 -287.604379)
			(xy 288.350979 -287.573254) (xy 288.3936 -287.548647) (xy 288.439616 -287.531195) (xy 288.487835 -287.521351)
			(xy 288.53701 -287.51937) (xy 288.585865 -287.525302) (xy 288.633136 -287.538994) (xy 288.677598 -287.560092)
			(xy 288.718101 -287.588048) (xy 288.753594 -287.62214) (xy 288.783159 -287.661484) (xy 288.80603 -287.705061)
			(xy 288.821614 -287.751742) (xy 288.829509 -287.800319) (xy 288.830004 -287.824926) (xy 289.169106 -287.824926)
			(xy 289.173066 -287.775872) (xy 289.184843 -287.728088) (xy 289.204134 -287.682812) (xy 289.230437 -287.641216)
			(xy 289.263072 -287.604379) (xy 289.301193 -287.573254) (xy 289.343814 -287.548647) (xy 289.38983 -287.531195)
			(xy 289.438049 -287.521351) (xy 289.487224 -287.51937) (xy 289.536079 -287.525302) (xy 289.58335 -287.538994)
			(xy 289.627812 -287.560092) (xy 289.668315 -287.588048) (xy 289.703808 -287.62214) (xy 289.733373 -287.661484)
			(xy 289.753566 -287.699958) (xy 290.143958 -287.699958) (xy 290.147918 -287.650904) (xy 290.159695 -287.60312)
			(xy 290.178986 -287.557844) (xy 290.205289 -287.516248) (xy 290.237924 -287.479411) (xy 290.276045 -287.448286)
			(xy 290.318666 -287.423679) (xy 290.364682 -287.406227) (xy 290.412901 -287.396383) (xy 290.462076 -287.394402)
			(xy 290.510931 -287.400334) (xy 290.558202 -287.414026) (xy 290.602664 -287.435124) (xy 290.643167 -287.46308)
			(xy 290.67866 -287.497172) (xy 290.708225 -287.536516) (xy 290.731096 -287.580093) (xy 290.74668 -287.626774)
			(xy 290.754575 -287.675351) (xy 290.75507 -287.699958) (xy 290.754575 -287.724565) (xy 290.74668 -287.773142)
			(xy 290.731096 -287.819823) (xy 290.708225 -287.8634) (xy 290.68083 -287.899856) (xy 292.018986 -287.899856)
			(xy 292.022946 -287.850802) (xy 292.034723 -287.803018) (xy 292.054014 -287.757742) (xy 292.080317 -287.716146)
			(xy 292.112952 -287.679309) (xy 292.151073 -287.648184) (xy 292.193694 -287.623577) (xy 292.23971 -287.606125)
			(xy 292.287929 -287.596281) (xy 292.337104 -287.5943) (xy 292.385959 -287.600232) (xy 292.43323 -287.613924)
			(xy 292.477692 -287.635022) (xy 292.518195 -287.662978) (xy 292.553688 -287.69707) (xy 292.583253 -287.736414)
			(xy 292.606124 -287.779991) (xy 292.621125 -287.824926) (xy 292.968946 -287.824926) (xy 292.972906 -287.775872)
			(xy 292.984683 -287.728088) (xy 293.003974 -287.682812) (xy 293.030277 -287.641216) (xy 293.062912 -287.604379)
			(xy 293.101033 -287.573254) (xy 293.143654 -287.548647) (xy 293.18967 -287.531195) (xy 293.237889 -287.521351)
			(xy 293.287064 -287.51937) (xy 293.335919 -287.525302) (xy 293.38319 -287.538994) (xy 293.427652 -287.560092)
			(xy 293.468155 -287.588048) (xy 293.503648 -287.62214) (xy 293.533213 -287.661484) (xy 293.556084 -287.705061)
			(xy 293.571668 -287.751742) (xy 293.579563 -287.800319) (xy 293.580058 -287.824926) (xy 293.918906 -287.824926)
			(xy 293.922866 -287.775872) (xy 293.934643 -287.728088) (xy 293.953934 -287.682812) (xy 293.980237 -287.641216)
			(xy 294.012872 -287.604379) (xy 294.050993 -287.573254) (xy 294.093614 -287.548647) (xy 294.13963 -287.531195)
			(xy 294.187849 -287.521351) (xy 294.237024 -287.51937) (xy 294.285879 -287.525302) (xy 294.33315 -287.538994)
			(xy 294.377612 -287.560092) (xy 294.418115 -287.588048) (xy 294.453608 -287.62214) (xy 294.483173 -287.661484)
			(xy 294.506044 -287.705061) (xy 294.521628 -287.751742) (xy 294.529523 -287.800319) (xy 294.530018 -287.824926)
			(xy 294.86912 -287.824926) (xy 294.87308 -287.775872) (xy 294.884857 -287.728088) (xy 294.904148 -287.682812)
			(xy 294.930451 -287.641216) (xy 294.963086 -287.604379) (xy 295.001207 -287.573254) (xy 295.043828 -287.548647)
			(xy 295.089844 -287.531195) (xy 295.138063 -287.521351) (xy 295.187238 -287.51937) (xy 295.236093 -287.525302)
			(xy 295.283364 -287.538994) (xy 295.327826 -287.560092) (xy 295.368329 -287.588048) (xy 295.403822 -287.62214)
			(xy 295.433387 -287.661484) (xy 295.456258 -287.705061) (xy 295.471842 -287.751742) (xy 295.479737 -287.800319)
			(xy 295.480232 -287.824926) (xy 295.81908 -287.824926) (xy 295.82304 -287.775872) (xy 295.834817 -287.728088)
			(xy 295.854108 -287.682812) (xy 295.880411 -287.641216) (xy 295.913046 -287.604379) (xy 295.951167 -287.573254)
			(xy 295.993788 -287.548647) (xy 296.039804 -287.531195) (xy 296.088023 -287.521351) (xy 296.137198 -287.51937)
			(xy 296.186053 -287.525302) (xy 296.233324 -287.538994) (xy 296.277786 -287.560092) (xy 296.318289 -287.588048)
			(xy 296.353782 -287.62214) (xy 296.383347 -287.661484) (xy 296.406218 -287.705061) (xy 296.421802 -287.751742)
			(xy 296.429697 -287.800319) (xy 296.430192 -287.824926) (xy 296.76904 -287.824926) (xy 296.773 -287.775872)
			(xy 296.784777 -287.728088) (xy 296.804068 -287.682812) (xy 296.830371 -287.641216) (xy 296.863006 -287.604379)
			(xy 296.901127 -287.573254) (xy 296.943748 -287.548647) (xy 296.989764 -287.531195) (xy 297.037983 -287.521351)
			(xy 297.087158 -287.51937) (xy 297.136013 -287.525302) (xy 297.183284 -287.538994) (xy 297.227746 -287.560092)
			(xy 297.268249 -287.588048) (xy 297.303742 -287.62214) (xy 297.333307 -287.661484) (xy 297.356178 -287.705061)
			(xy 297.371762 -287.751742) (xy 297.379657 -287.800319) (xy 297.380152 -287.824926) (xy 297.719 -287.824926)
			(xy 297.72296 -287.775872) (xy 297.734737 -287.728088) (xy 297.754028 -287.682812) (xy 297.780331 -287.641216)
			(xy 297.812966 -287.604379) (xy 297.851087 -287.573254) (xy 297.893708 -287.548647) (xy 297.939724 -287.531195)
			(xy 297.987943 -287.521351) (xy 298.037118 -287.51937) (xy 298.085973 -287.525302) (xy 298.133244 -287.538994)
			(xy 298.177706 -287.560092) (xy 298.218209 -287.588048) (xy 298.253702 -287.62214) (xy 298.283267 -287.661484)
			(xy 298.306138 -287.705061) (xy 298.321722 -287.751742) (xy 298.329617 -287.800319) (xy 298.330112 -287.824926)
			(xy 298.66896 -287.824926) (xy 298.67292 -287.775872) (xy 298.684697 -287.728088) (xy 298.703988 -287.682812)
			(xy 298.730291 -287.641216) (xy 298.762926 -287.604379) (xy 298.801047 -287.573254) (xy 298.843668 -287.548647)
			(xy 298.889684 -287.531195) (xy 298.937903 -287.521351) (xy 298.987078 -287.51937) (xy 299.035933 -287.525302)
			(xy 299.083204 -287.538994) (xy 299.127666 -287.560092) (xy 299.168169 -287.588048) (xy 299.203662 -287.62214)
			(xy 299.233227 -287.661484) (xy 299.256098 -287.705061) (xy 299.271682 -287.751742) (xy 299.279577 -287.800319)
			(xy 299.280072 -287.824926) (xy 299.61892 -287.824926) (xy 299.62288 -287.775872) (xy 299.634657 -287.728088)
			(xy 299.653948 -287.682812) (xy 299.680251 -287.641216) (xy 299.712886 -287.604379) (xy 299.751007 -287.573254)
			(xy 299.793628 -287.548647) (xy 299.839644 -287.531195) (xy 299.887863 -287.521351) (xy 299.937038 -287.51937)
			(xy 299.985893 -287.525302) (xy 300.033164 -287.538994) (xy 300.077626 -287.560092) (xy 300.118129 -287.588048)
			(xy 300.153622 -287.62214) (xy 300.183187 -287.661484) (xy 300.206058 -287.705061) (xy 300.221642 -287.751742)
			(xy 300.229537 -287.800319) (xy 300.230032 -287.824926) (xy 300.56888 -287.824926) (xy 300.57284 -287.775872)
			(xy 300.584617 -287.728088) (xy 300.603908 -287.682812) (xy 300.630211 -287.641216) (xy 300.662846 -287.604379)
			(xy 300.700967 -287.573254) (xy 300.743588 -287.548647) (xy 300.789604 -287.531195) (xy 300.837823 -287.521351)
			(xy 300.886998 -287.51937) (xy 300.935853 -287.525302) (xy 300.983124 -287.538994) (xy 301.027586 -287.560092)
			(xy 301.068089 -287.588048) (xy 301.103582 -287.62214) (xy 301.133147 -287.661484) (xy 301.156018 -287.705061)
			(xy 301.171602 -287.751742) (xy 301.179497 -287.800319) (xy 301.179992 -287.824926) (xy 302.469054 -287.824926)
			(xy 302.473014 -287.775872) (xy 302.484791 -287.728088) (xy 302.504082 -287.682812) (xy 302.530385 -287.641216)
			(xy 302.56302 -287.604379) (xy 302.601141 -287.573254) (xy 302.643762 -287.548647) (xy 302.689778 -287.531195)
			(xy 302.737997 -287.521351) (xy 302.787172 -287.51937) (xy 302.836027 -287.525302) (xy 302.883298 -287.538994)
			(xy 302.92776 -287.560092) (xy 302.968263 -287.588048) (xy 303.003756 -287.62214) (xy 303.033321 -287.661484)
			(xy 303.056192 -287.705061) (xy 303.071776 -287.751742) (xy 303.079671 -287.800319) (xy 303.080166 -287.824926)
			(xy 303.079671 -287.849533) (xy 303.071776 -287.89811) (xy 303.056192 -287.944791) (xy 303.033321 -287.988368)
			(xy 303.003756 -288.027712) (xy 302.968263 -288.061804) (xy 302.92776 -288.08976) (xy 302.883298 -288.110858)
			(xy 302.836027 -288.12455) (xy 302.787172 -288.130482) (xy 302.737997 -288.128501) (xy 302.689778 -288.118657)
			(xy 302.643762 -288.101205) (xy 302.601141 -288.076598) (xy 302.56302 -288.045473) (xy 302.530385 -288.008636)
			(xy 302.504082 -287.96704) (xy 302.484791 -287.921764) (xy 302.473014 -287.87398) (xy 302.469054 -287.824926)
			(xy 301.179992 -287.824926) (xy 301.179497 -287.849533) (xy 301.171602 -287.89811) (xy 301.156018 -287.944791)
			(xy 301.133147 -287.988368) (xy 301.103582 -288.027712) (xy 301.068089 -288.061804) (xy 301.027586 -288.08976)
			(xy 300.983124 -288.110858) (xy 300.935853 -288.12455) (xy 300.886998 -288.130482) (xy 300.837823 -288.128501)
			(xy 300.789604 -288.118657) (xy 300.743588 -288.101205) (xy 300.700967 -288.076598) (xy 300.662846 -288.045473)
			(xy 300.630211 -288.008636) (xy 300.603908 -287.96704) (xy 300.584617 -287.921764) (xy 300.57284 -287.87398)
			(xy 300.56888 -287.824926) (xy 300.230032 -287.824926) (xy 300.229537 -287.849533) (xy 300.221642 -287.89811)
			(xy 300.206058 -287.944791) (xy 300.183187 -287.988368) (xy 300.153622 -288.027712) (xy 300.118129 -288.061804)
			(xy 300.077626 -288.08976) (xy 300.033164 -288.110858) (xy 299.985893 -288.12455) (xy 299.937038 -288.130482)
			(xy 299.887863 -288.128501) (xy 299.839644 -288.118657) (xy 299.793628 -288.101205) (xy 299.751007 -288.076598)
			(xy 299.712886 -288.045473) (xy 299.680251 -288.008636) (xy 299.653948 -287.96704) (xy 299.634657 -287.921764)
			(xy 299.62288 -287.87398) (xy 299.61892 -287.824926) (xy 299.280072 -287.824926) (xy 299.279577 -287.849533)
			(xy 299.271682 -287.89811) (xy 299.256098 -287.944791) (xy 299.233227 -287.988368) (xy 299.203662 -288.027712)
			(xy 299.168169 -288.061804) (xy 299.127666 -288.08976) (xy 299.083204 -288.110858) (xy 299.035933 -288.12455)
			(xy 298.987078 -288.130482) (xy 298.937903 -288.128501) (xy 298.889684 -288.118657) (xy 298.843668 -288.101205)
			(xy 298.801047 -288.076598) (xy 298.762926 -288.045473) (xy 298.730291 -288.008636) (xy 298.703988 -287.96704)
			(xy 298.684697 -287.921764) (xy 298.67292 -287.87398) (xy 298.66896 -287.824926) (xy 298.330112 -287.824926)
			(xy 298.329617 -287.849533) (xy 298.321722 -287.89811) (xy 298.306138 -287.944791) (xy 298.283267 -287.988368)
			(xy 298.253702 -288.027712) (xy 298.218209 -288.061804) (xy 298.177706 -288.08976) (xy 298.133244 -288.110858)
			(xy 298.085973 -288.12455) (xy 298.037118 -288.130482) (xy 297.987943 -288.128501) (xy 297.939724 -288.118657)
			(xy 297.893708 -288.101205) (xy 297.851087 -288.076598) (xy 297.812966 -288.045473) (xy 297.780331 -288.008636)
			(xy 297.754028 -287.96704) (xy 297.734737 -287.921764) (xy 297.72296 -287.87398) (xy 297.719 -287.824926)
			(xy 297.380152 -287.824926) (xy 297.379657 -287.849533) (xy 297.371762 -287.89811) (xy 297.356178 -287.944791)
			(xy 297.333307 -287.988368) (xy 297.303742 -288.027712) (xy 297.268249 -288.061804) (xy 297.227746 -288.08976)
			(xy 297.183284 -288.110858) (xy 297.136013 -288.12455) (xy 297.087158 -288.130482) (xy 297.037983 -288.128501)
			(xy 296.989764 -288.118657) (xy 296.943748 -288.101205) (xy 296.901127 -288.076598) (xy 296.863006 -288.045473)
			(xy 296.830371 -288.008636) (xy 296.804068 -287.96704) (xy 296.784777 -287.921764) (xy 296.773 -287.87398)
			(xy 296.76904 -287.824926) (xy 296.430192 -287.824926) (xy 296.429697 -287.849533) (xy 296.421802 -287.89811)
			(xy 296.406218 -287.944791) (xy 296.383347 -287.988368) (xy 296.353782 -288.027712) (xy 296.318289 -288.061804)
			(xy 296.277786 -288.08976) (xy 296.233324 -288.110858) (xy 296.186053 -288.12455) (xy 296.137198 -288.130482)
			(xy 296.088023 -288.128501) (xy 296.039804 -288.118657) (xy 295.993788 -288.101205) (xy 295.951167 -288.076598)
			(xy 295.913046 -288.045473) (xy 295.880411 -288.008636) (xy 295.854108 -287.96704) (xy 295.834817 -287.921764)
			(xy 295.82304 -287.87398) (xy 295.81908 -287.824926) (xy 295.480232 -287.824926) (xy 295.479737 -287.849533)
			(xy 295.471842 -287.89811) (xy 295.456258 -287.944791) (xy 295.433387 -287.988368) (xy 295.403822 -288.027712)
			(xy 295.368329 -288.061804) (xy 295.327826 -288.08976) (xy 295.283364 -288.110858) (xy 295.236093 -288.12455)
			(xy 295.187238 -288.130482) (xy 295.138063 -288.128501) (xy 295.089844 -288.118657) (xy 295.043828 -288.101205)
			(xy 295.001207 -288.076598) (xy 294.963086 -288.045473) (xy 294.930451 -288.008636) (xy 294.904148 -287.96704)
			(xy 294.884857 -287.921764) (xy 294.87308 -287.87398) (xy 294.86912 -287.824926) (xy 294.530018 -287.824926)
			(xy 294.529523 -287.849533) (xy 294.521628 -287.89811) (xy 294.506044 -287.944791) (xy 294.483173 -287.988368)
			(xy 294.453608 -288.027712) (xy 294.418115 -288.061804) (xy 294.377612 -288.08976) (xy 294.33315 -288.110858)
			(xy 294.285879 -288.12455) (xy 294.237024 -288.130482) (xy 294.187849 -288.128501) (xy 294.13963 -288.118657)
			(xy 294.093614 -288.101205) (xy 294.050993 -288.076598) (xy 294.012872 -288.045473) (xy 293.980237 -288.008636)
			(xy 293.953934 -287.96704) (xy 293.934643 -287.921764) (xy 293.922866 -287.87398) (xy 293.918906 -287.824926)
			(xy 293.580058 -287.824926) (xy 293.579563 -287.849533) (xy 293.571668 -287.89811) (xy 293.556084 -287.944791)
			(xy 293.533213 -287.988368) (xy 293.503648 -288.027712) (xy 293.468155 -288.061804) (xy 293.427652 -288.08976)
			(xy 293.38319 -288.110858) (xy 293.335919 -288.12455) (xy 293.287064 -288.130482) (xy 293.237889 -288.128501)
			(xy 293.18967 -288.118657) (xy 293.143654 -288.101205) (xy 293.101033 -288.076598) (xy 293.062912 -288.045473)
			(xy 293.030277 -288.008636) (xy 293.003974 -287.96704) (xy 292.984683 -287.921764) (xy 292.972906 -287.87398)
			(xy 292.968946 -287.824926) (xy 292.621125 -287.824926) (xy 292.621708 -287.826672) (xy 292.629603 -287.875249)
			(xy 292.630098 -287.899856) (xy 292.629603 -287.924463) (xy 292.621708 -287.97304) (xy 292.606124 -288.019721)
			(xy 292.583253 -288.063298) (xy 292.553688 -288.102642) (xy 292.518195 -288.136734) (xy 292.477692 -288.16469)
			(xy 292.43323 -288.185788) (xy 292.385959 -288.19948) (xy 292.337104 -288.205412) (xy 292.287929 -288.203431)
			(xy 292.23971 -288.193587) (xy 292.193694 -288.176135) (xy 292.151073 -288.151528) (xy 292.112952 -288.120403)
			(xy 292.080317 -288.083566) (xy 292.054014 -288.04197) (xy 292.034723 -287.996694) (xy 292.022946 -287.94891)
			(xy 292.018986 -287.899856) (xy 290.68083 -287.899856) (xy 290.67866 -287.902744) (xy 290.643167 -287.936836)
			(xy 290.602664 -287.964792) (xy 290.558202 -287.98589) (xy 290.510931 -287.999582) (xy 290.462076 -288.005514)
			(xy 290.412901 -288.003533) (xy 290.364682 -287.993689) (xy 290.318666 -287.976237) (xy 290.276045 -287.95163)
			(xy 290.237924 -287.920505) (xy 290.205289 -287.883668) (xy 290.178986 -287.842072) (xy 290.159695 -287.796796)
			(xy 290.147918 -287.749012) (xy 290.143958 -287.699958) (xy 289.753566 -287.699958) (xy 289.756244 -287.705061)
			(xy 289.771828 -287.751742) (xy 289.779723 -287.800319) (xy 289.780218 -287.824926) (xy 289.779723 -287.849533)
			(xy 289.771828 -287.89811) (xy 289.756244 -287.944791) (xy 289.733373 -287.988368) (xy 289.703808 -288.027712)
			(xy 289.668315 -288.061804) (xy 289.627812 -288.08976) (xy 289.58335 -288.110858) (xy 289.536079 -288.12455)
			(xy 289.487224 -288.130482) (xy 289.438049 -288.128501) (xy 289.38983 -288.118657) (xy 289.343814 -288.101205)
			(xy 289.301193 -288.076598) (xy 289.263072 -288.045473) (xy 289.230437 -288.008636) (xy 289.204134 -287.96704)
			(xy 289.184843 -287.921764) (xy 289.173066 -287.87398) (xy 289.169106 -287.824926) (xy 288.830004 -287.824926)
			(xy 288.829509 -287.849533) (xy 288.821614 -287.89811) (xy 288.80603 -287.944791) (xy 288.783159 -287.988368)
			(xy 288.753594 -288.027712) (xy 288.718101 -288.061804) (xy 288.677598 -288.08976) (xy 288.633136 -288.110858)
			(xy 288.585865 -288.12455) (xy 288.53701 -288.130482) (xy 288.487835 -288.128501) (xy 288.439616 -288.118657)
			(xy 288.3936 -288.101205) (xy 288.350979 -288.076598) (xy 288.312858 -288.045473) (xy 288.280223 -288.008636)
			(xy 288.25392 -287.96704) (xy 288.234629 -287.921764) (xy 288.222852 -287.87398) (xy 288.218892 -287.824926)
			(xy 287.880044 -287.824926) (xy 287.879549 -287.849533) (xy 287.871654 -287.89811) (xy 287.85607 -287.944791)
			(xy 287.833199 -287.988368) (xy 287.803634 -288.027712) (xy 287.768141 -288.061804) (xy 287.727638 -288.08976)
			(xy 287.683176 -288.110858) (xy 287.635905 -288.12455) (xy 287.58705 -288.130482) (xy 287.537875 -288.128501)
			(xy 287.489656 -288.118657) (xy 287.44364 -288.101205) (xy 287.401019 -288.076598) (xy 287.362898 -288.045473)
			(xy 287.330263 -288.008636) (xy 287.30396 -287.96704) (xy 287.284669 -287.921764) (xy 287.272892 -287.87398)
			(xy 287.268932 -287.824926) (xy 286.930084 -287.824926) (xy 286.929589 -287.849533) (xy 286.921694 -287.89811)
			(xy 286.90611 -287.944791) (xy 286.883239 -287.988368) (xy 286.853674 -288.027712) (xy 286.818181 -288.061804)
			(xy 286.777678 -288.08976) (xy 286.733216 -288.110858) (xy 286.685945 -288.12455) (xy 286.63709 -288.130482)
			(xy 286.587915 -288.128501) (xy 286.539696 -288.118657) (xy 286.49368 -288.101205) (xy 286.451059 -288.076598)
			(xy 286.412938 -288.045473) (xy 286.380303 -288.008636) (xy 286.354 -287.96704) (xy 286.334709 -287.921764)
			(xy 286.322932 -287.87398) (xy 286.318972 -287.824926) (xy 285.980124 -287.824926) (xy 285.979629 -287.849533)
			(xy 285.971734 -287.89811) (xy 285.95615 -287.944791) (xy 285.933279 -287.988368) (xy 285.903714 -288.027712)
			(xy 285.868221 -288.061804) (xy 285.827718 -288.08976) (xy 285.783256 -288.110858) (xy 285.735985 -288.12455)
			(xy 285.68713 -288.130482) (xy 285.637955 -288.128501) (xy 285.589736 -288.118657) (xy 285.54372 -288.101205)
			(xy 285.501099 -288.076598) (xy 285.462978 -288.045473) (xy 285.430343 -288.008636) (xy 285.40404 -287.96704)
			(xy 285.384749 -287.921764) (xy 285.372972 -287.87398) (xy 285.369012 -287.824926) (xy 285.030164 -287.824926)
			(xy 285.029669 -287.849533) (xy 285.021774 -287.89811) (xy 285.00619 -287.944791) (xy 284.983319 -287.988368)
			(xy 284.953754 -288.027712) (xy 284.918261 -288.061804) (xy 284.877758 -288.08976) (xy 284.833296 -288.110858)
			(xy 284.786025 -288.12455) (xy 284.73717 -288.130482) (xy 284.687995 -288.128501) (xy 284.639776 -288.118657)
			(xy 284.59376 -288.101205) (xy 284.551139 -288.076598) (xy 284.513018 -288.045473) (xy 284.480383 -288.008636)
			(xy 284.45408 -287.96704) (xy 284.434789 -287.921764) (xy 284.423012 -287.87398) (xy 284.419052 -287.824926)
			(xy 284.080204 -287.824926) (xy 284.079709 -287.849533) (xy 284.071814 -287.89811) (xy 284.05623 -287.944791)
			(xy 284.033359 -287.988368) (xy 284.003794 -288.027712) (xy 283.968301 -288.061804) (xy 283.927798 -288.08976)
			(xy 283.883336 -288.110858) (xy 283.836065 -288.12455) (xy 283.78721 -288.130482) (xy 283.738035 -288.128501)
			(xy 283.689816 -288.118657) (xy 283.6438 -288.101205) (xy 283.601179 -288.076598) (xy 283.563058 -288.045473)
			(xy 283.530423 -288.008636) (xy 283.50412 -287.96704) (xy 283.484829 -287.921764) (xy 283.473052 -287.87398)
			(xy 283.469092 -287.824926) (xy 283.130244 -287.824926) (xy 283.129749 -287.849533) (xy 283.121854 -287.89811)
			(xy 283.10627 -287.944791) (xy 283.083399 -287.988368) (xy 283.053834 -288.027712) (xy 283.018341 -288.061804)
			(xy 282.977838 -288.08976) (xy 282.933376 -288.110858) (xy 282.886105 -288.12455) (xy 282.83725 -288.130482)
			(xy 282.788075 -288.128501) (xy 282.739856 -288.118657) (xy 282.69384 -288.101205) (xy 282.651219 -288.076598)
			(xy 282.613098 -288.045473) (xy 282.580463 -288.008636) (xy 282.55416 -287.96704) (xy 282.534869 -287.921764)
			(xy 282.523092 -287.87398) (xy 282.519132 -287.824926) (xy 282.18003 -287.824926) (xy 282.179535 -287.849533)
			(xy 282.17164 -287.89811) (xy 282.156056 -287.944791) (xy 282.133185 -287.988368) (xy 282.10362 -288.027712)
			(xy 282.068127 -288.061804) (xy 282.027624 -288.08976) (xy 281.983162 -288.110858) (xy 281.935891 -288.12455)
			(xy 281.887036 -288.130482) (xy 281.837861 -288.128501) (xy 281.789642 -288.118657) (xy 281.743626 -288.101205)
			(xy 281.701005 -288.076598) (xy 281.662884 -288.045473) (xy 281.630249 -288.008636) (xy 281.603946 -287.96704)
			(xy 281.584655 -287.921764) (xy 281.572878 -287.87398) (xy 281.568918 -287.824926) (xy 281.23007 -287.824926)
			(xy 281.229575 -287.849533) (xy 281.22168 -287.89811) (xy 281.206096 -287.944791) (xy 281.183225 -287.988368)
			(xy 281.15366 -288.027712) (xy 281.118167 -288.061804) (xy 281.077664 -288.08976) (xy 281.033202 -288.110858)
			(xy 280.985931 -288.12455) (xy 280.937076 -288.130482) (xy 280.887901 -288.128501) (xy 280.839682 -288.118657)
			(xy 280.793666 -288.101205) (xy 280.751045 -288.076598) (xy 280.712924 -288.045473) (xy 280.680289 -288.008636)
			(xy 280.653986 -287.96704) (xy 280.634695 -287.921764) (xy 280.622918 -287.87398) (xy 280.618958 -287.824926)
			(xy 280.28011 -287.824926) (xy 280.279615 -287.849533) (xy 280.27172 -287.89811) (xy 280.256136 -287.944791)
			(xy 280.233265 -287.988368) (xy 280.2037 -288.027712) (xy 280.168207 -288.061804) (xy 280.127704 -288.08976)
			(xy 280.083242 -288.110858) (xy 280.035971 -288.12455) (xy 279.987116 -288.130482) (xy 279.937941 -288.128501)
			(xy 279.889722 -288.118657) (xy 279.843706 -288.101205) (xy 279.801085 -288.076598) (xy 279.762964 -288.045473)
			(xy 279.730329 -288.008636) (xy 279.704026 -287.96704) (xy 279.684735 -287.921764) (xy 279.672958 -287.87398)
			(xy 279.668998 -287.824926) (xy 279.33015 -287.824926) (xy 279.329655 -287.849533) (xy 279.32176 -287.89811)
			(xy 279.306176 -287.944791) (xy 279.283305 -287.988368) (xy 279.25374 -288.027712) (xy 279.218247 -288.061804)
			(xy 279.177744 -288.08976) (xy 279.133282 -288.110858) (xy 279.086011 -288.12455) (xy 279.037156 -288.130482)
			(xy 278.987981 -288.128501) (xy 278.939762 -288.118657) (xy 278.893746 -288.101205) (xy 278.851125 -288.076598)
			(xy 278.813004 -288.045473) (xy 278.780369 -288.008636) (xy 278.754066 -287.96704) (xy 278.734775 -287.921764)
			(xy 278.722998 -287.87398) (xy 278.719038 -287.824926) (xy 278.38019 -287.824926) (xy 278.379695 -287.849533)
			(xy 278.3718 -287.89811) (xy 278.356216 -287.944791) (xy 278.333345 -287.988368) (xy 278.30378 -288.027712)
			(xy 278.268287 -288.061804) (xy 278.227784 -288.08976) (xy 278.183322 -288.110858) (xy 278.136051 -288.12455)
			(xy 278.087196 -288.130482) (xy 278.038021 -288.128501) (xy 277.989802 -288.118657) (xy 277.943786 -288.101205)
			(xy 277.901165 -288.076598) (xy 277.863044 -288.045473) (xy 277.830409 -288.008636) (xy 277.804106 -287.96704)
			(xy 277.784815 -287.921764) (xy 277.773038 -287.87398) (xy 277.769078 -287.824926) (xy 277.43023 -287.824926)
			(xy 277.429735 -287.849533) (xy 277.42184 -287.89811) (xy 277.406256 -287.944791) (xy 277.383385 -287.988368)
			(xy 277.35382 -288.027712) (xy 277.318327 -288.061804) (xy 277.277824 -288.08976) (xy 277.233362 -288.110858)
			(xy 277.186091 -288.12455) (xy 277.137236 -288.130482) (xy 277.088061 -288.128501) (xy 277.039842 -288.118657)
			(xy 276.993826 -288.101205) (xy 276.951205 -288.076598) (xy 276.913084 -288.045473) (xy 276.880449 -288.008636)
			(xy 276.854146 -287.96704) (xy 276.834855 -287.921764) (xy 276.823078 -287.87398) (xy 276.819118 -287.824926)
			(xy 273.630136 -287.824926) (xy 273.629641 -287.849533) (xy 273.621746 -287.89811) (xy 273.606162 -287.944791)
			(xy 273.583291 -287.988368) (xy 273.553726 -288.027712) (xy 273.518233 -288.061804) (xy 273.47773 -288.08976)
			(xy 273.433268 -288.110858) (xy 273.385997 -288.12455) (xy 273.337142 -288.130482) (xy 273.287967 -288.128501)
			(xy 273.239748 -288.118657) (xy 273.193732 -288.101205) (xy 273.151111 -288.076598) (xy 273.11299 -288.045473)
			(xy 273.080355 -288.008636) (xy 273.054052 -287.96704) (xy 273.034761 -287.921764) (xy 273.022984 -287.87398)
			(xy 273.019024 -287.824926) (xy 270.780256 -287.824926) (xy 270.779761 -287.849533) (xy 270.771866 -287.89811)
			(xy 270.756282 -287.944791) (xy 270.733411 -287.988368) (xy 270.703846 -288.027712) (xy 270.668353 -288.061804)
			(xy 270.62785 -288.08976) (xy 270.583388 -288.110858) (xy 270.536117 -288.12455) (xy 270.487262 -288.130482)
			(xy 270.438087 -288.128501) (xy 270.389868 -288.118657) (xy 270.343852 -288.101205) (xy 270.301231 -288.076598)
			(xy 270.26311 -288.045473) (xy 270.230475 -288.008636) (xy 270.204172 -287.96704) (xy 270.184881 -287.921764)
			(xy 270.173104 -287.87398) (xy 270.169144 -287.824926) (xy 269.830042 -287.824926) (xy 269.829547 -287.849533)
			(xy 269.821652 -287.89811) (xy 269.806068 -287.944791) (xy 269.783197 -287.988368) (xy 269.753632 -288.027712)
			(xy 269.718139 -288.061804) (xy 269.677636 -288.08976) (xy 269.633174 -288.110858) (xy 269.585903 -288.12455)
			(xy 269.537048 -288.130482) (xy 269.487873 -288.128501) (xy 269.439654 -288.118657) (xy 269.393638 -288.101205)
			(xy 269.351017 -288.076598) (xy 269.312896 -288.045473) (xy 269.280261 -288.008636) (xy 269.253958 -287.96704)
			(xy 269.234667 -287.921764) (xy 269.22289 -287.87398) (xy 269.21893 -287.824926) (xy 268.880082 -287.824926)
			(xy 268.879587 -287.849533) (xy 268.871692 -287.89811) (xy 268.856108 -287.944791) (xy 268.833237 -287.988368)
			(xy 268.803672 -288.027712) (xy 268.768179 -288.061804) (xy 268.727676 -288.08976) (xy 268.683214 -288.110858)
			(xy 268.635943 -288.12455) (xy 268.587088 -288.130482) (xy 268.537913 -288.128501) (xy 268.489694 -288.118657)
			(xy 268.443678 -288.101205) (xy 268.401057 -288.076598) (xy 268.362936 -288.045473) (xy 268.330301 -288.008636)
			(xy 268.303998 -287.96704) (xy 268.284707 -287.921764) (xy 268.27293 -287.87398) (xy 268.26897 -287.824926)
			(xy 249.737118 -287.824926) (xy 249.737118 -288.230056) (xy 258.01142 -288.230056) (xy 258.015491 -288.174434)
			(xy 258.027617 -288.119997) (xy 258.04754 -288.067906) (xy 258.074836 -288.019271) (xy 258.108922 -287.975128)
			(xy 258.149071 -287.936419) (xy 258.194429 -287.903968) (xy 258.244029 -287.878467) (xy 258.296813 -287.86046)
			(xy 258.351656 -287.85033) (xy 258.40739 -287.848293) (xy 258.462827 -287.854393) (xy 258.516784 -287.868499)
			(xy 258.568113 -287.890311) (xy 258.615719 -287.919365) (xy 258.658587 -287.95504) (xy 258.695804 -287.996577)
			(xy 258.726577 -288.04309) (xy 258.750249 -288.093587) (xy 258.766317 -288.146994) (xy 258.774437 -288.20217)
			(xy 258.774946 -288.230056) (xy 259.496558 -288.230056) (xy 259.500629 -288.174434) (xy 259.512755 -288.119997)
			(xy 259.532678 -288.067906) (xy 259.559974 -288.019271) (xy 259.59406 -287.975128) (xy 259.634209 -287.936419)
			(xy 259.679567 -287.903968) (xy 259.729167 -287.878467) (xy 259.781951 -287.86046) (xy 259.836794 -287.85033)
			(xy 259.892528 -287.848293) (xy 259.947965 -287.854393) (xy 260.001922 -287.868499) (xy 260.053251 -287.890311)
			(xy 260.100857 -287.919365) (xy 260.143725 -287.95504) (xy 260.180942 -287.996577) (xy 260.211715 -288.04309)
			(xy 260.235387 -288.093587) (xy 260.251455 -288.146994) (xy 260.259575 -288.20217) (xy 260.260084 -288.230056)
			(xy 260.259575 -288.257942) (xy 260.251455 -288.313118) (xy 260.235387 -288.366525) (xy 260.211715 -288.417022)
			(xy 260.180942 -288.463535) (xy 260.143725 -288.505072) (xy 260.100857 -288.540747) (xy 260.053251 -288.569801)
			(xy 260.001922 -288.591613) (xy 259.947965 -288.605719) (xy 259.892528 -288.611819) (xy 259.836794 -288.609782)
			(xy 259.781951 -288.599652) (xy 259.729167 -288.581645) (xy 259.679567 -288.556144) (xy 259.634209 -288.523693)
			(xy 259.59406 -288.484984) (xy 259.559974 -288.440841) (xy 259.532678 -288.392206) (xy 259.512755 -288.340115)
			(xy 259.500629 -288.285678) (xy 259.496558 -288.230056) (xy 258.774946 -288.230056) (xy 258.774437 -288.257942)
			(xy 258.766317 -288.313118) (xy 258.750249 -288.366525) (xy 258.726577 -288.417022) (xy 258.695804 -288.463535)
			(xy 258.658587 -288.505072) (xy 258.615719 -288.540747) (xy 258.568113 -288.569801) (xy 258.516784 -288.591613)
			(xy 258.462827 -288.605719) (xy 258.40739 -288.611819) (xy 258.351656 -288.609782) (xy 258.296813 -288.599652)
			(xy 258.244029 -288.581645) (xy 258.194429 -288.556144) (xy 258.149071 -288.523693) (xy 258.108922 -288.484984)
			(xy 258.074836 -288.440841) (xy 258.04754 -288.392206) (xy 258.027617 -288.340115) (xy 258.015491 -288.285678)
			(xy 258.01142 -288.230056) (xy 249.737118 -288.230056) (xy 249.737118 -288.774886) (xy 268.26897 -288.774886)
			(xy 268.27293 -288.725832) (xy 268.284707 -288.678048) (xy 268.303998 -288.632772) (xy 268.330301 -288.591176)
			(xy 268.362936 -288.554339) (xy 268.401057 -288.523214) (xy 268.443678 -288.498607) (xy 268.489694 -288.481155)
			(xy 268.537913 -288.471311) (xy 268.587088 -288.46933) (xy 268.635943 -288.475262) (xy 268.683214 -288.488954)
			(xy 268.727676 -288.510052) (xy 268.768179 -288.538008) (xy 268.803672 -288.5721) (xy 268.833237 -288.611444)
			(xy 268.856108 -288.655021) (xy 268.871692 -288.701702) (xy 268.879587 -288.750279) (xy 268.880082 -288.774886)
			(xy 269.21893 -288.774886) (xy 269.22289 -288.725832) (xy 269.234667 -288.678048) (xy 269.253958 -288.632772)
			(xy 269.280261 -288.591176) (xy 269.312896 -288.554339) (xy 269.351017 -288.523214) (xy 269.393638 -288.498607)
			(xy 269.439654 -288.481155) (xy 269.487873 -288.471311) (xy 269.537048 -288.46933) (xy 269.585903 -288.475262)
			(xy 269.633174 -288.488954) (xy 269.677636 -288.510052) (xy 269.718139 -288.538008) (xy 269.753632 -288.5721)
			(xy 269.783197 -288.611444) (xy 269.806068 -288.655021) (xy 269.821652 -288.701702) (xy 269.829547 -288.750279)
			(xy 269.830042 -288.774886) (xy 270.169144 -288.774886) (xy 270.173104 -288.725832) (xy 270.184881 -288.678048)
			(xy 270.204172 -288.632772) (xy 270.230475 -288.591176) (xy 270.26311 -288.554339) (xy 270.301231 -288.523214)
			(xy 270.343852 -288.498607) (xy 270.389868 -288.481155) (xy 270.438087 -288.471311) (xy 270.487262 -288.46933)
			(xy 270.536117 -288.475262) (xy 270.583388 -288.488954) (xy 270.62785 -288.510052) (xy 270.668353 -288.538008)
			(xy 270.703846 -288.5721) (xy 270.733411 -288.611444) (xy 270.756282 -288.655021) (xy 270.771866 -288.701702)
			(xy 270.779761 -288.750279) (xy 270.780256 -288.774886) (xy 274.918944 -288.774886) (xy 274.922904 -288.725832)
			(xy 274.934681 -288.678048) (xy 274.953972 -288.632772) (xy 274.980275 -288.591176) (xy 275.01291 -288.554339)
			(xy 275.051031 -288.523214) (xy 275.093652 -288.498607) (xy 275.139668 -288.481155) (xy 275.187887 -288.471311)
			(xy 275.237062 -288.46933) (xy 275.285917 -288.475262) (xy 275.333188 -288.488954) (xy 275.37765 -288.510052)
			(xy 275.418153 -288.538008) (xy 275.453646 -288.5721) (xy 275.483211 -288.611444) (xy 275.506082 -288.655021)
			(xy 275.521666 -288.701702) (xy 275.529561 -288.750279) (xy 275.530056 -288.774886) (xy 275.868904 -288.774886)
			(xy 275.872864 -288.725832) (xy 275.884641 -288.678048) (xy 275.903932 -288.632772) (xy 275.930235 -288.591176)
			(xy 275.96287 -288.554339) (xy 276.000991 -288.523214) (xy 276.043612 -288.498607) (xy 276.089628 -288.481155)
			(xy 276.137847 -288.471311) (xy 276.187022 -288.46933) (xy 276.235877 -288.475262) (xy 276.283148 -288.488954)
			(xy 276.32761 -288.510052) (xy 276.368113 -288.538008) (xy 276.403606 -288.5721) (xy 276.433171 -288.611444)
			(xy 276.456042 -288.655021) (xy 276.471626 -288.701702) (xy 276.479521 -288.750279) (xy 276.480016 -288.774886)
			(xy 276.819118 -288.774886) (xy 276.823078 -288.725832) (xy 276.834855 -288.678048) (xy 276.854146 -288.632772)
			(xy 276.880449 -288.591176) (xy 276.913084 -288.554339) (xy 276.951205 -288.523214) (xy 276.993826 -288.498607)
			(xy 277.039842 -288.481155) (xy 277.088061 -288.471311) (xy 277.137236 -288.46933) (xy 277.186091 -288.475262)
			(xy 277.233362 -288.488954) (xy 277.277824 -288.510052) (xy 277.318327 -288.538008) (xy 277.35382 -288.5721)
			(xy 277.383385 -288.611444) (xy 277.406256 -288.655021) (xy 277.42184 -288.701702) (xy 277.429735 -288.750279)
			(xy 277.43023 -288.774886) (xy 277.769078 -288.774886) (xy 277.773038 -288.725832) (xy 277.784815 -288.678048)
			(xy 277.804106 -288.632772) (xy 277.830409 -288.591176) (xy 277.863044 -288.554339) (xy 277.901165 -288.523214)
			(xy 277.943786 -288.498607) (xy 277.989802 -288.481155) (xy 278.038021 -288.471311) (xy 278.087196 -288.46933)
			(xy 278.136051 -288.475262) (xy 278.183322 -288.488954) (xy 278.227784 -288.510052) (xy 278.268287 -288.538008)
			(xy 278.30378 -288.5721) (xy 278.333345 -288.611444) (xy 278.356216 -288.655021) (xy 278.3718 -288.701702)
			(xy 278.379695 -288.750279) (xy 278.38019 -288.774886) (xy 278.719038 -288.774886) (xy 278.722998 -288.725832)
			(xy 278.734775 -288.678048) (xy 278.754066 -288.632772) (xy 278.780369 -288.591176) (xy 278.813004 -288.554339)
			(xy 278.851125 -288.523214) (xy 278.893746 -288.498607) (xy 278.939762 -288.481155) (xy 278.987981 -288.471311)
			(xy 279.037156 -288.46933) (xy 279.086011 -288.475262) (xy 279.133282 -288.488954) (xy 279.177744 -288.510052)
			(xy 279.218247 -288.538008) (xy 279.25374 -288.5721) (xy 279.283305 -288.611444) (xy 279.306176 -288.655021)
			(xy 279.32176 -288.701702) (xy 279.329655 -288.750279) (xy 279.33015 -288.774886) (xy 279.668998 -288.774886)
			(xy 279.672958 -288.725832) (xy 279.684735 -288.678048) (xy 279.704026 -288.632772) (xy 279.730329 -288.591176)
			(xy 279.762964 -288.554339) (xy 279.801085 -288.523214) (xy 279.843706 -288.498607) (xy 279.889722 -288.481155)
			(xy 279.937941 -288.471311) (xy 279.987116 -288.46933) (xy 280.035971 -288.475262) (xy 280.083242 -288.488954)
			(xy 280.127704 -288.510052) (xy 280.168207 -288.538008) (xy 280.2037 -288.5721) (xy 280.233265 -288.611444)
			(xy 280.256136 -288.655021) (xy 280.27172 -288.701702) (xy 280.279615 -288.750279) (xy 280.28011 -288.774886)
			(xy 280.618958 -288.774886) (xy 280.622918 -288.725832) (xy 280.634695 -288.678048) (xy 280.653986 -288.632772)
			(xy 280.680289 -288.591176) (xy 280.712924 -288.554339) (xy 280.751045 -288.523214) (xy 280.793666 -288.498607)
			(xy 280.839682 -288.481155) (xy 280.887901 -288.471311) (xy 280.937076 -288.46933) (xy 280.985931 -288.475262)
			(xy 281.033202 -288.488954) (xy 281.077664 -288.510052) (xy 281.118167 -288.538008) (xy 281.15366 -288.5721)
			(xy 281.183225 -288.611444) (xy 281.206096 -288.655021) (xy 281.22168 -288.701702) (xy 281.229575 -288.750279)
			(xy 281.23007 -288.774886) (xy 281.568918 -288.774886) (xy 281.572878 -288.725832) (xy 281.584655 -288.678048)
			(xy 281.603946 -288.632772) (xy 281.630249 -288.591176) (xy 281.662884 -288.554339) (xy 281.701005 -288.523214)
			(xy 281.743626 -288.498607) (xy 281.789642 -288.481155) (xy 281.837861 -288.471311) (xy 281.887036 -288.46933)
			(xy 281.935891 -288.475262) (xy 281.983162 -288.488954) (xy 282.027624 -288.510052) (xy 282.068127 -288.538008)
			(xy 282.10362 -288.5721) (xy 282.133185 -288.611444) (xy 282.156056 -288.655021) (xy 282.17164 -288.701702)
			(xy 282.179535 -288.750279) (xy 282.18003 -288.774886) (xy 282.519132 -288.774886) (xy 282.523092 -288.725832)
			(xy 282.534869 -288.678048) (xy 282.55416 -288.632772) (xy 282.580463 -288.591176) (xy 282.613098 -288.554339)
			(xy 282.651219 -288.523214) (xy 282.69384 -288.498607) (xy 282.739856 -288.481155) (xy 282.788075 -288.471311)
			(xy 282.83725 -288.46933) (xy 282.886105 -288.475262) (xy 282.933376 -288.488954) (xy 282.977838 -288.510052)
			(xy 283.018341 -288.538008) (xy 283.053834 -288.5721) (xy 283.083399 -288.611444) (xy 283.10627 -288.655021)
			(xy 283.121854 -288.701702) (xy 283.129749 -288.750279) (xy 283.130244 -288.774886) (xy 283.469092 -288.774886)
			(xy 283.473052 -288.725832) (xy 283.484829 -288.678048) (xy 283.50412 -288.632772) (xy 283.530423 -288.591176)
			(xy 283.563058 -288.554339) (xy 283.601179 -288.523214) (xy 283.6438 -288.498607) (xy 283.689816 -288.481155)
			(xy 283.738035 -288.471311) (xy 283.78721 -288.46933) (xy 283.836065 -288.475262) (xy 283.883336 -288.488954)
			(xy 283.927798 -288.510052) (xy 283.968301 -288.538008) (xy 284.003794 -288.5721) (xy 284.033359 -288.611444)
			(xy 284.05623 -288.655021) (xy 284.071814 -288.701702) (xy 284.079709 -288.750279) (xy 284.080204 -288.774886)
			(xy 284.419052 -288.774886) (xy 284.423012 -288.725832) (xy 284.434789 -288.678048) (xy 284.45408 -288.632772)
			(xy 284.480383 -288.591176) (xy 284.513018 -288.554339) (xy 284.551139 -288.523214) (xy 284.59376 -288.498607)
			(xy 284.639776 -288.481155) (xy 284.687995 -288.471311) (xy 284.73717 -288.46933) (xy 284.786025 -288.475262)
			(xy 284.833296 -288.488954) (xy 284.877758 -288.510052) (xy 284.918261 -288.538008) (xy 284.953754 -288.5721)
			(xy 284.983319 -288.611444) (xy 285.00619 -288.655021) (xy 285.021774 -288.701702) (xy 285.029669 -288.750279)
			(xy 285.030164 -288.774886) (xy 285.369012 -288.774886) (xy 285.372972 -288.725832) (xy 285.384749 -288.678048)
			(xy 285.40404 -288.632772) (xy 285.430343 -288.591176) (xy 285.462978 -288.554339) (xy 285.501099 -288.523214)
			(xy 285.54372 -288.498607) (xy 285.589736 -288.481155) (xy 285.637955 -288.471311) (xy 285.68713 -288.46933)
			(xy 285.735985 -288.475262) (xy 285.783256 -288.488954) (xy 285.827718 -288.510052) (xy 285.868221 -288.538008)
			(xy 285.903714 -288.5721) (xy 285.933279 -288.611444) (xy 285.95615 -288.655021) (xy 285.971734 -288.701702)
			(xy 285.979629 -288.750279) (xy 285.980124 -288.774886) (xy 286.318972 -288.774886) (xy 286.322932 -288.725832)
			(xy 286.334709 -288.678048) (xy 286.354 -288.632772) (xy 286.380303 -288.591176) (xy 286.412938 -288.554339)
			(xy 286.451059 -288.523214) (xy 286.49368 -288.498607) (xy 286.539696 -288.481155) (xy 286.587915 -288.471311)
			(xy 286.63709 -288.46933) (xy 286.685945 -288.475262) (xy 286.733216 -288.488954) (xy 286.777678 -288.510052)
			(xy 286.818181 -288.538008) (xy 286.853674 -288.5721) (xy 286.883239 -288.611444) (xy 286.90611 -288.655021)
			(xy 286.921694 -288.701702) (xy 286.929589 -288.750279) (xy 286.930084 -288.774886) (xy 287.268932 -288.774886)
			(xy 287.272892 -288.725832) (xy 287.284669 -288.678048) (xy 287.30396 -288.632772) (xy 287.330263 -288.591176)
			(xy 287.362898 -288.554339) (xy 287.401019 -288.523214) (xy 287.44364 -288.498607) (xy 287.489656 -288.481155)
			(xy 287.537875 -288.471311) (xy 287.58705 -288.46933) (xy 287.635905 -288.475262) (xy 287.683176 -288.488954)
			(xy 287.727638 -288.510052) (xy 287.768141 -288.538008) (xy 287.803634 -288.5721) (xy 287.833199 -288.611444)
			(xy 287.85607 -288.655021) (xy 287.871654 -288.701702) (xy 287.879549 -288.750279) (xy 287.880044 -288.774886)
			(xy 288.218892 -288.774886) (xy 288.222852 -288.725832) (xy 288.234629 -288.678048) (xy 288.25392 -288.632772)
			(xy 288.280223 -288.591176) (xy 288.312858 -288.554339) (xy 288.350979 -288.523214) (xy 288.3936 -288.498607)
			(xy 288.439616 -288.481155) (xy 288.487835 -288.471311) (xy 288.53701 -288.46933) (xy 288.585865 -288.475262)
			(xy 288.633136 -288.488954) (xy 288.677598 -288.510052) (xy 288.718101 -288.538008) (xy 288.753594 -288.5721)
			(xy 288.783159 -288.611444) (xy 288.80603 -288.655021) (xy 288.821614 -288.701702) (xy 288.829509 -288.750279)
			(xy 288.830004 -288.774886) (xy 289.169106 -288.774886) (xy 289.173066 -288.725832) (xy 289.184843 -288.678048)
			(xy 289.204134 -288.632772) (xy 289.230437 -288.591176) (xy 289.263072 -288.554339) (xy 289.301193 -288.523214)
			(xy 289.343814 -288.498607) (xy 289.38983 -288.481155) (xy 289.438049 -288.471311) (xy 289.487224 -288.46933)
			(xy 289.536079 -288.475262) (xy 289.58335 -288.488954) (xy 289.627812 -288.510052) (xy 289.668315 -288.538008)
			(xy 289.703808 -288.5721) (xy 289.733373 -288.611444) (xy 289.756244 -288.655021) (xy 289.771828 -288.701702)
			(xy 289.779723 -288.750279) (xy 289.780218 -288.774886) (xy 290.119066 -288.774886) (xy 290.123026 -288.725832)
			(xy 290.134803 -288.678048) (xy 290.154094 -288.632772) (xy 290.180397 -288.591176) (xy 290.213032 -288.554339)
			(xy 290.251153 -288.523214) (xy 290.293774 -288.498607) (xy 290.33979 -288.481155) (xy 290.388009 -288.471311)
			(xy 290.437184 -288.46933) (xy 290.486039 -288.475262) (xy 290.53331 -288.488954) (xy 290.577772 -288.510052)
			(xy 290.618275 -288.538008) (xy 290.653768 -288.5721) (xy 290.683333 -288.611444) (xy 290.706204 -288.655021)
			(xy 290.721788 -288.701702) (xy 290.729683 -288.750279) (xy 290.730178 -288.774886) (xy 292.018986 -288.774886)
			(xy 292.022946 -288.725832) (xy 292.034723 -288.678048) (xy 292.054014 -288.632772) (xy 292.080317 -288.591176)
			(xy 292.112952 -288.554339) (xy 292.151073 -288.523214) (xy 292.193694 -288.498607) (xy 292.23971 -288.481155)
			(xy 292.287929 -288.471311) (xy 292.337104 -288.46933) (xy 292.385959 -288.475262) (xy 292.43323 -288.488954)
			(xy 292.477692 -288.510052) (xy 292.518195 -288.538008) (xy 292.553688 -288.5721) (xy 292.583253 -288.611444)
			(xy 292.606124 -288.655021) (xy 292.621708 -288.701702) (xy 292.629603 -288.750279) (xy 292.630098 -288.774886)
			(xy 292.968946 -288.774886) (xy 292.972906 -288.725832) (xy 292.984683 -288.678048) (xy 293.003974 -288.632772)
			(xy 293.030277 -288.591176) (xy 293.062912 -288.554339) (xy 293.101033 -288.523214) (xy 293.143654 -288.498607)
			(xy 293.18967 -288.481155) (xy 293.237889 -288.471311) (xy 293.287064 -288.46933) (xy 293.335919 -288.475262)
			(xy 293.38319 -288.488954) (xy 293.427652 -288.510052) (xy 293.468155 -288.538008) (xy 293.503648 -288.5721)
			(xy 293.533213 -288.611444) (xy 293.556084 -288.655021) (xy 293.571668 -288.701702) (xy 293.579563 -288.750279)
			(xy 293.580058 -288.774886) (xy 293.918906 -288.774886) (xy 293.922866 -288.725832) (xy 293.934643 -288.678048)
			(xy 293.953934 -288.632772) (xy 293.980237 -288.591176) (xy 294.012872 -288.554339) (xy 294.050993 -288.523214)
			(xy 294.093614 -288.498607) (xy 294.13963 -288.481155) (xy 294.187849 -288.471311) (xy 294.237024 -288.46933)
			(xy 294.285879 -288.475262) (xy 294.33315 -288.488954) (xy 294.377612 -288.510052) (xy 294.418115 -288.538008)
			(xy 294.453608 -288.5721) (xy 294.483173 -288.611444) (xy 294.506044 -288.655021) (xy 294.521628 -288.701702)
			(xy 294.529523 -288.750279) (xy 294.530018 -288.774886) (xy 294.86912 -288.774886) (xy 294.87308 -288.725832)
			(xy 294.884857 -288.678048) (xy 294.904148 -288.632772) (xy 294.930451 -288.591176) (xy 294.963086 -288.554339)
			(xy 295.001207 -288.523214) (xy 295.043828 -288.498607) (xy 295.089844 -288.481155) (xy 295.138063 -288.471311)
			(xy 295.187238 -288.46933) (xy 295.236093 -288.475262) (xy 295.283364 -288.488954) (xy 295.327826 -288.510052)
			(xy 295.368329 -288.538008) (xy 295.403822 -288.5721) (xy 295.433387 -288.611444) (xy 295.456258 -288.655021)
			(xy 295.471842 -288.701702) (xy 295.479737 -288.750279) (xy 295.480232 -288.774886) (xy 295.81908 -288.774886)
			(xy 295.82304 -288.725832) (xy 295.834817 -288.678048) (xy 295.854108 -288.632772) (xy 295.880411 -288.591176)
			(xy 295.913046 -288.554339) (xy 295.951167 -288.523214) (xy 295.993788 -288.498607) (xy 296.039804 -288.481155)
			(xy 296.088023 -288.471311) (xy 296.137198 -288.46933) (xy 296.186053 -288.475262) (xy 296.233324 -288.488954)
			(xy 296.277786 -288.510052) (xy 296.318289 -288.538008) (xy 296.353782 -288.5721) (xy 296.383347 -288.611444)
			(xy 296.406218 -288.655021) (xy 296.421802 -288.701702) (xy 296.429697 -288.750279) (xy 296.430192 -288.774886)
			(xy 296.76904 -288.774886) (xy 296.773 -288.725832) (xy 296.784777 -288.678048) (xy 296.804068 -288.632772)
			(xy 296.830371 -288.591176) (xy 296.863006 -288.554339) (xy 296.901127 -288.523214) (xy 296.943748 -288.498607)
			(xy 296.989764 -288.481155) (xy 297.037983 -288.471311) (xy 297.087158 -288.46933) (xy 297.136013 -288.475262)
			(xy 297.183284 -288.488954) (xy 297.227746 -288.510052) (xy 297.268249 -288.538008) (xy 297.303742 -288.5721)
			(xy 297.333307 -288.611444) (xy 297.356178 -288.655021) (xy 297.371762 -288.701702) (xy 297.379657 -288.750279)
			(xy 297.380152 -288.774886) (xy 297.719 -288.774886) (xy 297.72296 -288.725832) (xy 297.734737 -288.678048)
			(xy 297.754028 -288.632772) (xy 297.780331 -288.591176) (xy 297.812966 -288.554339) (xy 297.851087 -288.523214)
			(xy 297.893708 -288.498607) (xy 297.939724 -288.481155) (xy 297.987943 -288.471311) (xy 298.037118 -288.46933)
			(xy 298.085973 -288.475262) (xy 298.133244 -288.488954) (xy 298.177706 -288.510052) (xy 298.218209 -288.538008)
			(xy 298.253702 -288.5721) (xy 298.283267 -288.611444) (xy 298.306138 -288.655021) (xy 298.321722 -288.701702)
			(xy 298.329617 -288.750279) (xy 298.330112 -288.774886) (xy 298.66896 -288.774886) (xy 298.67292 -288.725832)
			(xy 298.684697 -288.678048) (xy 298.703988 -288.632772) (xy 298.730291 -288.591176) (xy 298.762926 -288.554339)
			(xy 298.801047 -288.523214) (xy 298.843668 -288.498607) (xy 298.889684 -288.481155) (xy 298.937903 -288.471311)
			(xy 298.987078 -288.46933) (xy 299.035933 -288.475262) (xy 299.083204 -288.488954) (xy 299.127666 -288.510052)
			(xy 299.168169 -288.538008) (xy 299.203662 -288.5721) (xy 299.233227 -288.611444) (xy 299.256098 -288.655021)
			(xy 299.271682 -288.701702) (xy 299.279577 -288.750279) (xy 299.280072 -288.774886) (xy 299.61892 -288.774886)
			(xy 299.62288 -288.725832) (xy 299.634657 -288.678048) (xy 299.653948 -288.632772) (xy 299.680251 -288.591176)
			(xy 299.712886 -288.554339) (xy 299.751007 -288.523214) (xy 299.793628 -288.498607) (xy 299.839644 -288.481155)
			(xy 299.887863 -288.471311) (xy 299.937038 -288.46933) (xy 299.985893 -288.475262) (xy 300.033164 -288.488954)
			(xy 300.077626 -288.510052) (xy 300.118129 -288.538008) (xy 300.153622 -288.5721) (xy 300.183187 -288.611444)
			(xy 300.206058 -288.655021) (xy 300.221642 -288.701702) (xy 300.229537 -288.750279) (xy 300.230032 -288.774886)
			(xy 300.56888 -288.774886) (xy 300.57284 -288.725832) (xy 300.584617 -288.678048) (xy 300.603908 -288.632772)
			(xy 300.630211 -288.591176) (xy 300.662846 -288.554339) (xy 300.700967 -288.523214) (xy 300.743588 -288.498607)
			(xy 300.789604 -288.481155) (xy 300.837823 -288.471311) (xy 300.886998 -288.46933) (xy 300.935853 -288.475262)
			(xy 300.983124 -288.488954) (xy 301.027586 -288.510052) (xy 301.068089 -288.538008) (xy 301.103582 -288.5721)
			(xy 301.133147 -288.611444) (xy 301.156018 -288.655021) (xy 301.171602 -288.701702) (xy 301.179497 -288.750279)
			(xy 301.179992 -288.774886) (xy 301.519094 -288.774886) (xy 301.523054 -288.725832) (xy 301.534831 -288.678048)
			(xy 301.554122 -288.632772) (xy 301.580425 -288.591176) (xy 301.61306 -288.554339) (xy 301.651181 -288.523214)
			(xy 301.693802 -288.498607) (xy 301.739818 -288.481155) (xy 301.788037 -288.471311) (xy 301.837212 -288.46933)
			(xy 301.886067 -288.475262) (xy 301.933338 -288.488954) (xy 301.9778 -288.510052) (xy 302.018303 -288.538008)
			(xy 302.053796 -288.5721) (xy 302.083361 -288.611444) (xy 302.106232 -288.655021) (xy 302.121816 -288.701702)
			(xy 302.129711 -288.750279) (xy 302.130206 -288.774886) (xy 302.469054 -288.774886) (xy 302.473014 -288.725832)
			(xy 302.484791 -288.678048) (xy 302.504082 -288.632772) (xy 302.530385 -288.591176) (xy 302.56302 -288.554339)
			(xy 302.601141 -288.523214) (xy 302.643762 -288.498607) (xy 302.689778 -288.481155) (xy 302.737997 -288.471311)
			(xy 302.787172 -288.46933) (xy 302.836027 -288.475262) (xy 302.883298 -288.488954) (xy 302.92776 -288.510052)
			(xy 302.968263 -288.538008) (xy 303.003756 -288.5721) (xy 303.033321 -288.611444) (xy 303.056192 -288.655021)
			(xy 303.071776 -288.701702) (xy 303.079671 -288.750279) (xy 303.080166 -288.774886) (xy 303.419014 -288.774886)
			(xy 303.422974 -288.725832) (xy 303.434751 -288.678048) (xy 303.454042 -288.632772) (xy 303.480345 -288.591176)
			(xy 303.51298 -288.554339) (xy 303.551101 -288.523214) (xy 303.593722 -288.498607) (xy 303.639738 -288.481155)
			(xy 303.687957 -288.471311) (xy 303.737132 -288.46933) (xy 303.785987 -288.475262) (xy 303.833258 -288.488954)
			(xy 303.87772 -288.510052) (xy 303.918223 -288.538008) (xy 303.953716 -288.5721) (xy 303.983281 -288.611444)
			(xy 304.006152 -288.655021) (xy 304.021736 -288.701702) (xy 304.029631 -288.750279) (xy 304.030126 -288.774886)
			(xy 304.368974 -288.774886) (xy 304.372934 -288.725832) (xy 304.384711 -288.678048) (xy 304.404002 -288.632772)
			(xy 304.430305 -288.591176) (xy 304.46294 -288.554339) (xy 304.501061 -288.523214) (xy 304.543682 -288.498607)
			(xy 304.589698 -288.481155) (xy 304.637917 -288.471311) (xy 304.687092 -288.46933) (xy 304.735947 -288.475262)
			(xy 304.783218 -288.488954) (xy 304.82768 -288.510052) (xy 304.868183 -288.538008) (xy 304.903676 -288.5721)
			(xy 304.933241 -288.611444) (xy 304.956112 -288.655021) (xy 304.971696 -288.701702) (xy 304.979591 -288.750279)
			(xy 304.980086 -288.774886) (xy 304.979591 -288.799493) (xy 304.971696 -288.84807) (xy 304.956112 -288.894751)
			(xy 304.933241 -288.938328) (xy 304.903676 -288.977672) (xy 304.868183 -289.011764) (xy 304.82768 -289.03972)
			(xy 304.783218 -289.060818) (xy 304.735947 -289.07451) (xy 304.687092 -289.080442) (xy 304.637917 -289.078461)
			(xy 304.589698 -289.068617) (xy 304.543682 -289.051165) (xy 304.501061 -289.026558) (xy 304.46294 -288.995433)
			(xy 304.430305 -288.958596) (xy 304.404002 -288.917) (xy 304.384711 -288.871724) (xy 304.372934 -288.82394)
			(xy 304.368974 -288.774886) (xy 304.030126 -288.774886) (xy 304.029631 -288.799493) (xy 304.021736 -288.84807)
			(xy 304.006152 -288.894751) (xy 303.983281 -288.938328) (xy 303.953716 -288.977672) (xy 303.918223 -289.011764)
			(xy 303.87772 -289.03972) (xy 303.833258 -289.060818) (xy 303.785987 -289.07451) (xy 303.737132 -289.080442)
			(xy 303.687957 -289.078461) (xy 303.639738 -289.068617) (xy 303.593722 -289.051165) (xy 303.551101 -289.026558)
			(xy 303.51298 -288.995433) (xy 303.480345 -288.958596) (xy 303.454042 -288.917) (xy 303.434751 -288.871724)
			(xy 303.422974 -288.82394) (xy 303.419014 -288.774886) (xy 303.080166 -288.774886) (xy 303.079671 -288.799493)
			(xy 303.071776 -288.84807) (xy 303.056192 -288.894751) (xy 303.033321 -288.938328) (xy 303.003756 -288.977672)
			(xy 302.968263 -289.011764) (xy 302.92776 -289.03972) (xy 302.883298 -289.060818) (xy 302.836027 -289.07451)
			(xy 302.787172 -289.080442) (xy 302.737997 -289.078461) (xy 302.689778 -289.068617) (xy 302.643762 -289.051165)
			(xy 302.601141 -289.026558) (xy 302.56302 -288.995433) (xy 302.530385 -288.958596) (xy 302.504082 -288.917)
			(xy 302.484791 -288.871724) (xy 302.473014 -288.82394) (xy 302.469054 -288.774886) (xy 302.130206 -288.774886)
			(xy 302.129711 -288.799493) (xy 302.121816 -288.84807) (xy 302.106232 -288.894751) (xy 302.083361 -288.938328)
			(xy 302.053796 -288.977672) (xy 302.018303 -289.011764) (xy 301.9778 -289.03972) (xy 301.933338 -289.060818)
			(xy 301.886067 -289.07451) (xy 301.837212 -289.080442) (xy 301.788037 -289.078461) (xy 301.739818 -289.068617)
			(xy 301.693802 -289.051165) (xy 301.651181 -289.026558) (xy 301.61306 -288.995433) (xy 301.580425 -288.958596)
			(xy 301.554122 -288.917) (xy 301.534831 -288.871724) (xy 301.523054 -288.82394) (xy 301.519094 -288.774886)
			(xy 301.179992 -288.774886) (xy 301.179497 -288.799493) (xy 301.171602 -288.84807) (xy 301.156018 -288.894751)
			(xy 301.133147 -288.938328) (xy 301.103582 -288.977672) (xy 301.068089 -289.011764) (xy 301.027586 -289.03972)
			(xy 300.983124 -289.060818) (xy 300.935853 -289.07451) (xy 300.886998 -289.080442) (xy 300.837823 -289.078461)
			(xy 300.789604 -289.068617) (xy 300.743588 -289.051165) (xy 300.700967 -289.026558) (xy 300.662846 -288.995433)
			(xy 300.630211 -288.958596) (xy 300.603908 -288.917) (xy 300.584617 -288.871724) (xy 300.57284 -288.82394)
			(xy 300.56888 -288.774886) (xy 300.230032 -288.774886) (xy 300.229537 -288.799493) (xy 300.221642 -288.84807)
			(xy 300.206058 -288.894751) (xy 300.183187 -288.938328) (xy 300.153622 -288.977672) (xy 300.118129 -289.011764)
			(xy 300.077626 -289.03972) (xy 300.033164 -289.060818) (xy 299.985893 -289.07451) (xy 299.937038 -289.080442)
			(xy 299.887863 -289.078461) (xy 299.839644 -289.068617) (xy 299.793628 -289.051165) (xy 299.751007 -289.026558)
			(xy 299.712886 -288.995433) (xy 299.680251 -288.958596) (xy 299.653948 -288.917) (xy 299.634657 -288.871724)
			(xy 299.62288 -288.82394) (xy 299.61892 -288.774886) (xy 299.280072 -288.774886) (xy 299.279577 -288.799493)
			(xy 299.271682 -288.84807) (xy 299.256098 -288.894751) (xy 299.233227 -288.938328) (xy 299.203662 -288.977672)
			(xy 299.168169 -289.011764) (xy 299.127666 -289.03972) (xy 299.083204 -289.060818) (xy 299.035933 -289.07451)
			(xy 298.987078 -289.080442) (xy 298.937903 -289.078461) (xy 298.889684 -289.068617) (xy 298.843668 -289.051165)
			(xy 298.801047 -289.026558) (xy 298.762926 -288.995433) (xy 298.730291 -288.958596) (xy 298.703988 -288.917)
			(xy 298.684697 -288.871724) (xy 298.67292 -288.82394) (xy 298.66896 -288.774886) (xy 298.330112 -288.774886)
			(xy 298.329617 -288.799493) (xy 298.321722 -288.84807) (xy 298.306138 -288.894751) (xy 298.283267 -288.938328)
			(xy 298.253702 -288.977672) (xy 298.218209 -289.011764) (xy 298.177706 -289.03972) (xy 298.133244 -289.060818)
			(xy 298.085973 -289.07451) (xy 298.037118 -289.080442) (xy 297.987943 -289.078461) (xy 297.939724 -289.068617)
			(xy 297.893708 -289.051165) (xy 297.851087 -289.026558) (xy 297.812966 -288.995433) (xy 297.780331 -288.958596)
			(xy 297.754028 -288.917) (xy 297.734737 -288.871724) (xy 297.72296 -288.82394) (xy 297.719 -288.774886)
			(xy 297.380152 -288.774886) (xy 297.379657 -288.799493) (xy 297.371762 -288.84807) (xy 297.356178 -288.894751)
			(xy 297.333307 -288.938328) (xy 297.303742 -288.977672) (xy 297.268249 -289.011764) (xy 297.227746 -289.03972)
			(xy 297.183284 -289.060818) (xy 297.136013 -289.07451) (xy 297.087158 -289.080442) (xy 297.037983 -289.078461)
			(xy 296.989764 -289.068617) (xy 296.943748 -289.051165) (xy 296.901127 -289.026558) (xy 296.863006 -288.995433)
			(xy 296.830371 -288.958596) (xy 296.804068 -288.917) (xy 296.784777 -288.871724) (xy 296.773 -288.82394)
			(xy 296.76904 -288.774886) (xy 296.430192 -288.774886) (xy 296.429697 -288.799493) (xy 296.421802 -288.84807)
			(xy 296.406218 -288.894751) (xy 296.383347 -288.938328) (xy 296.353782 -288.977672) (xy 296.318289 -289.011764)
			(xy 296.277786 -289.03972) (xy 296.233324 -289.060818) (xy 296.186053 -289.07451) (xy 296.137198 -289.080442)
			(xy 296.088023 -289.078461) (xy 296.039804 -289.068617) (xy 295.993788 -289.051165) (xy 295.951167 -289.026558)
			(xy 295.913046 -288.995433) (xy 295.880411 -288.958596) (xy 295.854108 -288.917) (xy 295.834817 -288.871724)
			(xy 295.82304 -288.82394) (xy 295.81908 -288.774886) (xy 295.480232 -288.774886) (xy 295.479737 -288.799493)
			(xy 295.471842 -288.84807) (xy 295.456258 -288.894751) (xy 295.433387 -288.938328) (xy 295.403822 -288.977672)
			(xy 295.368329 -289.011764) (xy 295.327826 -289.03972) (xy 295.283364 -289.060818) (xy 295.236093 -289.07451)
			(xy 295.187238 -289.080442) (xy 295.138063 -289.078461) (xy 295.089844 -289.068617) (xy 295.043828 -289.051165)
			(xy 295.001207 -289.026558) (xy 294.963086 -288.995433) (xy 294.930451 -288.958596) (xy 294.904148 -288.917)
			(xy 294.884857 -288.871724) (xy 294.87308 -288.82394) (xy 294.86912 -288.774886) (xy 294.530018 -288.774886)
			(xy 294.529523 -288.799493) (xy 294.521628 -288.84807) (xy 294.506044 -288.894751) (xy 294.483173 -288.938328)
			(xy 294.453608 -288.977672) (xy 294.418115 -289.011764) (xy 294.377612 -289.03972) (xy 294.33315 -289.060818)
			(xy 294.285879 -289.07451) (xy 294.237024 -289.080442) (xy 294.187849 -289.078461) (xy 294.13963 -289.068617)
			(xy 294.093614 -289.051165) (xy 294.050993 -289.026558) (xy 294.012872 -288.995433) (xy 293.980237 -288.958596)
			(xy 293.953934 -288.917) (xy 293.934643 -288.871724) (xy 293.922866 -288.82394) (xy 293.918906 -288.774886)
			(xy 293.580058 -288.774886) (xy 293.579563 -288.799493) (xy 293.571668 -288.84807) (xy 293.556084 -288.894751)
			(xy 293.533213 -288.938328) (xy 293.503648 -288.977672) (xy 293.468155 -289.011764) (xy 293.427652 -289.03972)
			(xy 293.38319 -289.060818) (xy 293.335919 -289.07451) (xy 293.287064 -289.080442) (xy 293.237889 -289.078461)
			(xy 293.18967 -289.068617) (xy 293.143654 -289.051165) (xy 293.101033 -289.026558) (xy 293.062912 -288.995433)
			(xy 293.030277 -288.958596) (xy 293.003974 -288.917) (xy 292.984683 -288.871724) (xy 292.972906 -288.82394)
			(xy 292.968946 -288.774886) (xy 292.630098 -288.774886) (xy 292.629603 -288.799493) (xy 292.621708 -288.84807)
			(xy 292.606124 -288.894751) (xy 292.583253 -288.938328) (xy 292.553688 -288.977672) (xy 292.518195 -289.011764)
			(xy 292.477692 -289.03972) (xy 292.43323 -289.060818) (xy 292.385959 -289.07451) (xy 292.337104 -289.080442)
			(xy 292.287929 -289.078461) (xy 292.23971 -289.068617) (xy 292.193694 -289.051165) (xy 292.151073 -289.026558)
			(xy 292.112952 -288.995433) (xy 292.080317 -288.958596) (xy 292.054014 -288.917) (xy 292.034723 -288.871724)
			(xy 292.022946 -288.82394) (xy 292.018986 -288.774886) (xy 290.730178 -288.774886) (xy 290.729683 -288.799493)
			(xy 290.721788 -288.84807) (xy 290.706204 -288.894751) (xy 290.683333 -288.938328) (xy 290.653768 -288.977672)
			(xy 290.618275 -289.011764) (xy 290.577772 -289.03972) (xy 290.53331 -289.060818) (xy 290.486039 -289.07451)
			(xy 290.437184 -289.080442) (xy 290.388009 -289.078461) (xy 290.33979 -289.068617) (xy 290.293774 -289.051165)
			(xy 290.251153 -289.026558) (xy 290.213032 -288.995433) (xy 290.180397 -288.958596) (xy 290.154094 -288.917)
			(xy 290.134803 -288.871724) (xy 290.123026 -288.82394) (xy 290.119066 -288.774886) (xy 289.780218 -288.774886)
			(xy 289.779723 -288.799493) (xy 289.771828 -288.84807) (xy 289.756244 -288.894751) (xy 289.733373 -288.938328)
			(xy 289.703808 -288.977672) (xy 289.668315 -289.011764) (xy 289.627812 -289.03972) (xy 289.58335 -289.060818)
			(xy 289.536079 -289.07451) (xy 289.487224 -289.080442) (xy 289.438049 -289.078461) (xy 289.38983 -289.068617)
			(xy 289.343814 -289.051165) (xy 289.301193 -289.026558) (xy 289.263072 -288.995433) (xy 289.230437 -288.958596)
			(xy 289.204134 -288.917) (xy 289.184843 -288.871724) (xy 289.173066 -288.82394) (xy 289.169106 -288.774886)
			(xy 288.830004 -288.774886) (xy 288.829509 -288.799493) (xy 288.821614 -288.84807) (xy 288.80603 -288.894751)
			(xy 288.783159 -288.938328) (xy 288.753594 -288.977672) (xy 288.718101 -289.011764) (xy 288.677598 -289.03972)
			(xy 288.633136 -289.060818) (xy 288.585865 -289.07451) (xy 288.53701 -289.080442) (xy 288.487835 -289.078461)
			(xy 288.439616 -289.068617) (xy 288.3936 -289.051165) (xy 288.350979 -289.026558) (xy 288.312858 -288.995433)
			(xy 288.280223 -288.958596) (xy 288.25392 -288.917) (xy 288.234629 -288.871724) (xy 288.222852 -288.82394)
			(xy 288.218892 -288.774886) (xy 287.880044 -288.774886) (xy 287.879549 -288.799493) (xy 287.871654 -288.84807)
			(xy 287.85607 -288.894751) (xy 287.833199 -288.938328) (xy 287.803634 -288.977672) (xy 287.768141 -289.011764)
			(xy 287.727638 -289.03972) (xy 287.683176 -289.060818) (xy 287.635905 -289.07451) (xy 287.58705 -289.080442)
			(xy 287.537875 -289.078461) (xy 287.489656 -289.068617) (xy 287.44364 -289.051165) (xy 287.401019 -289.026558)
			(xy 287.362898 -288.995433) (xy 287.330263 -288.958596) (xy 287.30396 -288.917) (xy 287.284669 -288.871724)
			(xy 287.272892 -288.82394) (xy 287.268932 -288.774886) (xy 286.930084 -288.774886) (xy 286.929589 -288.799493)
			(xy 286.921694 -288.84807) (xy 286.90611 -288.894751) (xy 286.883239 -288.938328) (xy 286.853674 -288.977672)
			(xy 286.818181 -289.011764) (xy 286.777678 -289.03972) (xy 286.733216 -289.060818) (xy 286.685945 -289.07451)
			(xy 286.63709 -289.080442) (xy 286.587915 -289.078461) (xy 286.539696 -289.068617) (xy 286.49368 -289.051165)
			(xy 286.451059 -289.026558) (xy 286.412938 -288.995433) (xy 286.380303 -288.958596) (xy 286.354 -288.917)
			(xy 286.334709 -288.871724) (xy 286.322932 -288.82394) (xy 286.318972 -288.774886) (xy 285.980124 -288.774886)
			(xy 285.979629 -288.799493) (xy 285.971734 -288.84807) (xy 285.95615 -288.894751) (xy 285.933279 -288.938328)
			(xy 285.903714 -288.977672) (xy 285.868221 -289.011764) (xy 285.827718 -289.03972) (xy 285.783256 -289.060818)
			(xy 285.735985 -289.07451) (xy 285.68713 -289.080442) (xy 285.637955 -289.078461) (xy 285.589736 -289.068617)
			(xy 285.54372 -289.051165) (xy 285.501099 -289.026558) (xy 285.462978 -288.995433) (xy 285.430343 -288.958596)
			(xy 285.40404 -288.917) (xy 285.384749 -288.871724) (xy 285.372972 -288.82394) (xy 285.369012 -288.774886)
			(xy 285.030164 -288.774886) (xy 285.029669 -288.799493) (xy 285.021774 -288.84807) (xy 285.00619 -288.894751)
			(xy 284.983319 -288.938328) (xy 284.953754 -288.977672) (xy 284.918261 -289.011764) (xy 284.877758 -289.03972)
			(xy 284.833296 -289.060818) (xy 284.786025 -289.07451) (xy 284.73717 -289.080442) (xy 284.687995 -289.078461)
			(xy 284.639776 -289.068617) (xy 284.59376 -289.051165) (xy 284.551139 -289.026558) (xy 284.513018 -288.995433)
			(xy 284.480383 -288.958596) (xy 284.45408 -288.917) (xy 284.434789 -288.871724) (xy 284.423012 -288.82394)
			(xy 284.419052 -288.774886) (xy 284.080204 -288.774886) (xy 284.079709 -288.799493) (xy 284.071814 -288.84807)
			(xy 284.05623 -288.894751) (xy 284.033359 -288.938328) (xy 284.003794 -288.977672) (xy 283.968301 -289.011764)
			(xy 283.927798 -289.03972) (xy 283.883336 -289.060818) (xy 283.836065 -289.07451) (xy 283.78721 -289.080442)
			(xy 283.738035 -289.078461) (xy 283.689816 -289.068617) (xy 283.6438 -289.051165) (xy 283.601179 -289.026558)
			(xy 283.563058 -288.995433) (xy 283.530423 -288.958596) (xy 283.50412 -288.917) (xy 283.484829 -288.871724)
			(xy 283.473052 -288.82394) (xy 283.469092 -288.774886) (xy 283.130244 -288.774886) (xy 283.129749 -288.799493)
			(xy 283.121854 -288.84807) (xy 283.10627 -288.894751) (xy 283.083399 -288.938328) (xy 283.053834 -288.977672)
			(xy 283.018341 -289.011764) (xy 282.977838 -289.03972) (xy 282.933376 -289.060818) (xy 282.886105 -289.07451)
			(xy 282.83725 -289.080442) (xy 282.788075 -289.078461) (xy 282.739856 -289.068617) (xy 282.69384 -289.051165)
			(xy 282.651219 -289.026558) (xy 282.613098 -288.995433) (xy 282.580463 -288.958596) (xy 282.55416 -288.917)
			(xy 282.534869 -288.871724) (xy 282.523092 -288.82394) (xy 282.519132 -288.774886) (xy 282.18003 -288.774886)
			(xy 282.179535 -288.799493) (xy 282.17164 -288.84807) (xy 282.156056 -288.894751) (xy 282.133185 -288.938328)
			(xy 282.10362 -288.977672) (xy 282.068127 -289.011764) (xy 282.027624 -289.03972) (xy 281.983162 -289.060818)
			(xy 281.935891 -289.07451) (xy 281.887036 -289.080442) (xy 281.837861 -289.078461) (xy 281.789642 -289.068617)
			(xy 281.743626 -289.051165) (xy 281.701005 -289.026558) (xy 281.662884 -288.995433) (xy 281.630249 -288.958596)
			(xy 281.603946 -288.917) (xy 281.584655 -288.871724) (xy 281.572878 -288.82394) (xy 281.568918 -288.774886)
			(xy 281.23007 -288.774886) (xy 281.229575 -288.799493) (xy 281.22168 -288.84807) (xy 281.206096 -288.894751)
			(xy 281.183225 -288.938328) (xy 281.15366 -288.977672) (xy 281.118167 -289.011764) (xy 281.077664 -289.03972)
			(xy 281.033202 -289.060818) (xy 280.985931 -289.07451) (xy 280.937076 -289.080442) (xy 280.887901 -289.078461)
			(xy 280.839682 -289.068617) (xy 280.793666 -289.051165) (xy 280.751045 -289.026558) (xy 280.712924 -288.995433)
			(xy 280.680289 -288.958596) (xy 280.653986 -288.917) (xy 280.634695 -288.871724) (xy 280.622918 -288.82394)
			(xy 280.618958 -288.774886) (xy 280.28011 -288.774886) (xy 280.279615 -288.799493) (xy 280.27172 -288.84807)
			(xy 280.256136 -288.894751) (xy 280.233265 -288.938328) (xy 280.2037 -288.977672) (xy 280.168207 -289.011764)
			(xy 280.127704 -289.03972) (xy 280.083242 -289.060818) (xy 280.035971 -289.07451) (xy 279.987116 -289.080442)
			(xy 279.937941 -289.078461) (xy 279.889722 -289.068617) (xy 279.843706 -289.051165) (xy 279.801085 -289.026558)
			(xy 279.762964 -288.995433) (xy 279.730329 -288.958596) (xy 279.704026 -288.917) (xy 279.684735 -288.871724)
			(xy 279.672958 -288.82394) (xy 279.668998 -288.774886) (xy 279.33015 -288.774886) (xy 279.329655 -288.799493)
			(xy 279.32176 -288.84807) (xy 279.306176 -288.894751) (xy 279.283305 -288.938328) (xy 279.25374 -288.977672)
			(xy 279.218247 -289.011764) (xy 279.177744 -289.03972) (xy 279.133282 -289.060818) (xy 279.086011 -289.07451)
			(xy 279.037156 -289.080442) (xy 278.987981 -289.078461) (xy 278.939762 -289.068617) (xy 278.893746 -289.051165)
			(xy 278.851125 -289.026558) (xy 278.813004 -288.995433) (xy 278.780369 -288.958596) (xy 278.754066 -288.917)
			(xy 278.734775 -288.871724) (xy 278.722998 -288.82394) (xy 278.719038 -288.774886) (xy 278.38019 -288.774886)
			(xy 278.379695 -288.799493) (xy 278.3718 -288.84807) (xy 278.356216 -288.894751) (xy 278.333345 -288.938328)
			(xy 278.30378 -288.977672) (xy 278.268287 -289.011764) (xy 278.227784 -289.03972) (xy 278.183322 -289.060818)
			(xy 278.136051 -289.07451) (xy 278.087196 -289.080442) (xy 278.038021 -289.078461) (xy 277.989802 -289.068617)
			(xy 277.943786 -289.051165) (xy 277.901165 -289.026558) (xy 277.863044 -288.995433) (xy 277.830409 -288.958596)
			(xy 277.804106 -288.917) (xy 277.784815 -288.871724) (xy 277.773038 -288.82394) (xy 277.769078 -288.774886)
			(xy 277.43023 -288.774886) (xy 277.429735 -288.799493) (xy 277.42184 -288.84807) (xy 277.406256 -288.894751)
			(xy 277.383385 -288.938328) (xy 277.35382 -288.977672) (xy 277.318327 -289.011764) (xy 277.277824 -289.03972)
			(xy 277.233362 -289.060818) (xy 277.186091 -289.07451) (xy 277.137236 -289.080442) (xy 277.088061 -289.078461)
			(xy 277.039842 -289.068617) (xy 276.993826 -289.051165) (xy 276.951205 -289.026558) (xy 276.913084 -288.995433)
			(xy 276.880449 -288.958596) (xy 276.854146 -288.917) (xy 276.834855 -288.871724) (xy 276.823078 -288.82394)
			(xy 276.819118 -288.774886) (xy 276.480016 -288.774886) (xy 276.479521 -288.799493) (xy 276.471626 -288.84807)
			(xy 276.456042 -288.894751) (xy 276.433171 -288.938328) (xy 276.403606 -288.977672) (xy 276.368113 -289.011764)
			(xy 276.32761 -289.03972) (xy 276.283148 -289.060818) (xy 276.235877 -289.07451) (xy 276.187022 -289.080442)
			(xy 276.137847 -289.078461) (xy 276.089628 -289.068617) (xy 276.043612 -289.051165) (xy 276.000991 -289.026558)
			(xy 275.96287 -288.995433) (xy 275.930235 -288.958596) (xy 275.903932 -288.917) (xy 275.884641 -288.871724)
			(xy 275.872864 -288.82394) (xy 275.868904 -288.774886) (xy 275.530056 -288.774886) (xy 275.529561 -288.799493)
			(xy 275.521666 -288.84807) (xy 275.506082 -288.894751) (xy 275.483211 -288.938328) (xy 275.453646 -288.977672)
			(xy 275.418153 -289.011764) (xy 275.37765 -289.03972) (xy 275.333188 -289.060818) (xy 275.285917 -289.07451)
			(xy 275.237062 -289.080442) (xy 275.187887 -289.078461) (xy 275.139668 -289.068617) (xy 275.093652 -289.051165)
			(xy 275.051031 -289.026558) (xy 275.01291 -288.995433) (xy 274.980275 -288.958596) (xy 274.953972 -288.917)
			(xy 274.934681 -288.871724) (xy 274.922904 -288.82394) (xy 274.918944 -288.774886) (xy 270.780256 -288.774886)
			(xy 270.779761 -288.799493) (xy 270.771866 -288.84807) (xy 270.756282 -288.894751) (xy 270.733411 -288.938328)
			(xy 270.703846 -288.977672) (xy 270.668353 -289.011764) (xy 270.62785 -289.03972) (xy 270.583388 -289.060818)
			(xy 270.536117 -289.07451) (xy 270.487262 -289.080442) (xy 270.438087 -289.078461) (xy 270.389868 -289.068617)
			(xy 270.343852 -289.051165) (xy 270.301231 -289.026558) (xy 270.26311 -288.995433) (xy 270.230475 -288.958596)
			(xy 270.204172 -288.917) (xy 270.184881 -288.871724) (xy 270.173104 -288.82394) (xy 270.169144 -288.774886)
			(xy 269.830042 -288.774886) (xy 269.829547 -288.799493) (xy 269.821652 -288.84807) (xy 269.806068 -288.894751)
			(xy 269.783197 -288.938328) (xy 269.753632 -288.977672) (xy 269.718139 -289.011764) (xy 269.677636 -289.03972)
			(xy 269.633174 -289.060818) (xy 269.585903 -289.07451) (xy 269.537048 -289.080442) (xy 269.487873 -289.078461)
			(xy 269.439654 -289.068617) (xy 269.393638 -289.051165) (xy 269.351017 -289.026558) (xy 269.312896 -288.995433)
			(xy 269.280261 -288.958596) (xy 269.253958 -288.917) (xy 269.234667 -288.871724) (xy 269.22289 -288.82394)
			(xy 269.21893 -288.774886) (xy 268.880082 -288.774886) (xy 268.879587 -288.799493) (xy 268.871692 -288.84807)
			(xy 268.856108 -288.894751) (xy 268.833237 -288.938328) (xy 268.803672 -288.977672) (xy 268.768179 -289.011764)
			(xy 268.727676 -289.03972) (xy 268.683214 -289.060818) (xy 268.635943 -289.07451) (xy 268.587088 -289.080442)
			(xy 268.537913 -289.078461) (xy 268.489694 -289.068617) (xy 268.443678 -289.051165) (xy 268.401057 -289.026558)
			(xy 268.362936 -288.995433) (xy 268.330301 -288.958596) (xy 268.303998 -288.917) (xy 268.284707 -288.871724)
			(xy 268.27293 -288.82394) (xy 268.26897 -288.774886) (xy 249.737118 -288.774886) (xy 249.737118 -289.532314)
			(xy 258.01142 -289.532314) (xy 258.015491 -289.476692) (xy 258.027617 -289.422255) (xy 258.04754 -289.370164)
			(xy 258.074836 -289.321529) (xy 258.108922 -289.277386) (xy 258.149071 -289.238677) (xy 258.194429 -289.206226)
			(xy 258.244029 -289.180725) (xy 258.296813 -289.162718) (xy 258.351656 -289.152588) (xy 258.40739 -289.150551)
			(xy 258.462827 -289.156651) (xy 258.516784 -289.170757) (xy 258.568113 -289.192569) (xy 258.615719 -289.221623)
			(xy 258.658587 -289.257298) (xy 258.695804 -289.298835) (xy 258.726577 -289.345348) (xy 258.750249 -289.395845)
			(xy 258.766317 -289.449252) (xy 258.774437 -289.504428) (xy 258.774946 -289.532314) (xy 259.486906 -289.532314)
			(xy 259.490977 -289.476692) (xy 259.503103 -289.422255) (xy 259.523026 -289.370164) (xy 259.550322 -289.321529)
			(xy 259.584408 -289.277386) (xy 259.624557 -289.238677) (xy 259.669915 -289.206226) (xy 259.719515 -289.180725)
			(xy 259.772299 -289.162718) (xy 259.827142 -289.152588) (xy 259.882876 -289.150551) (xy 259.938313 -289.156651)
			(xy 259.99227 -289.170757) (xy 260.043599 -289.192569) (xy 260.091205 -289.221623) (xy 260.134073 -289.257298)
			(xy 260.17129 -289.298835) (xy 260.202063 -289.345348) (xy 260.225735 -289.395845) (xy 260.241803 -289.449252)
			(xy 260.249923 -289.504428) (xy 260.250432 -289.532314) (xy 260.375906 -289.532314) (xy 260.379977 -289.476692)
			(xy 260.392103 -289.422255) (xy 260.412026 -289.370164) (xy 260.439322 -289.321529) (xy 260.473408 -289.277386)
			(xy 260.513557 -289.238677) (xy 260.558915 -289.206226) (xy 260.608515 -289.180725) (xy 260.661299 -289.162718)
			(xy 260.716142 -289.152588) (xy 260.771876 -289.150551) (xy 260.827313 -289.156651) (xy 260.88127 -289.170757)
			(xy 260.932599 -289.192569) (xy 260.980205 -289.221623) (xy 261.023073 -289.257298) (xy 261.06029 -289.298835)
			(xy 261.091063 -289.345348) (xy 261.114735 -289.395845) (xy 261.130803 -289.449252) (xy 261.138923 -289.504428)
			(xy 261.139432 -289.532314) (xy 261.138923 -289.5602) (xy 261.130803 -289.615376) (xy 261.114735 -289.668783)
			(xy 261.091063 -289.71928) (xy 261.06029 -289.765793) (xy 261.023073 -289.80733) (xy 260.980205 -289.843005)
			(xy 260.932599 -289.872059) (xy 260.88127 -289.893871) (xy 260.827313 -289.907977) (xy 260.771876 -289.914077)
			(xy 260.716142 -289.91204) (xy 260.661299 -289.90191) (xy 260.608515 -289.883903) (xy 260.558915 -289.858402)
			(xy 260.513557 -289.825951) (xy 260.473408 -289.787242) (xy 260.439322 -289.743099) (xy 260.412026 -289.694464)
			(xy 260.392103 -289.642373) (xy 260.379977 -289.587936) (xy 260.375906 -289.532314) (xy 260.250432 -289.532314)
			(xy 260.249923 -289.5602) (xy 260.241803 -289.615376) (xy 260.225735 -289.668783) (xy 260.202063 -289.71928)
			(xy 260.17129 -289.765793) (xy 260.134073 -289.80733) (xy 260.091205 -289.843005) (xy 260.043599 -289.872059)
			(xy 259.99227 -289.893871) (xy 259.938313 -289.907977) (xy 259.882876 -289.914077) (xy 259.827142 -289.91204)
			(xy 259.772299 -289.90191) (xy 259.719515 -289.883903) (xy 259.669915 -289.858402) (xy 259.624557 -289.825951)
			(xy 259.584408 -289.787242) (xy 259.550322 -289.743099) (xy 259.523026 -289.694464) (xy 259.503103 -289.642373)
			(xy 259.490977 -289.587936) (xy 259.486906 -289.532314) (xy 258.774946 -289.532314) (xy 258.774437 -289.5602)
			(xy 258.766317 -289.615376) (xy 258.750249 -289.668783) (xy 258.726577 -289.71928) (xy 258.695804 -289.765793)
			(xy 258.658587 -289.80733) (xy 258.615719 -289.843005) (xy 258.568113 -289.872059) (xy 258.516784 -289.893871)
			(xy 258.462827 -289.907977) (xy 258.40739 -289.914077) (xy 258.351656 -289.91204) (xy 258.296813 -289.90191)
			(xy 258.244029 -289.883903) (xy 258.194429 -289.858402) (xy 258.149071 -289.825951) (xy 258.108922 -289.787242)
			(xy 258.074836 -289.743099) (xy 258.04754 -289.694464) (xy 258.027617 -289.642373) (xy 258.015491 -289.587936)
			(xy 258.01142 -289.532314) (xy 249.737118 -289.532314) (xy 249.737118 -290.294314) (xy 263.537954 -290.294314)
			(xy 263.53852 -290.264933) (xy 263.547548 -290.206868) (xy 263.565376 -290.150875) (xy 263.591583 -290.09828)
			(xy 263.625547 -290.050328) (xy 263.666466 -290.008154) (xy 263.689592 -289.990022) (xy 263.69899 -289.982656)
			(xy 263.709404 -289.962082) (xy 263.710928 -289.858196) (xy 263.701022 -289.837114) (xy 263.691878 -289.829748)
			(xy 263.670018 -289.811556) (xy 263.63148 -289.769733) (xy 263.599575 -289.722655) (xy 263.57501 -289.671363)
			(xy 263.558329 -289.616993) (xy 263.549902 -289.56075) (xy 263.549384 -289.532314) (xy 263.54987 -289.505063)
			(xy 263.557626 -289.451115) (xy 263.572981 -289.39882) (xy 263.595623 -289.349243) (xy 263.625089 -289.303393)
			(xy 263.66078 -289.262202) (xy 263.701971 -289.226511) (xy 263.747821 -289.197045) (xy 263.797398 -289.174403)
			(xy 263.849693 -289.159048) (xy 263.903641 -289.151292) (xy 263.958143 -289.151292) (xy 264.012091 -289.159048)
			(xy 264.064386 -289.174403) (xy 264.113963 -289.197045) (xy 264.159813 -289.226511) (xy 264.201004 -289.262202)
			(xy 264.236695 -289.303393) (xy 264.266161 -289.349243) (xy 264.288803 -289.39882) (xy 264.304158 -289.451115)
			(xy 264.311914 -289.505063) (xy 264.3124 -289.532314) (xy 264.311872 -289.561697) (xy 264.302839 -289.619764)
			(xy 264.285005 -289.675759) (xy 264.260539 -289.724846) (xy 268.26897 -289.724846) (xy 268.27293 -289.675792)
			(xy 268.284707 -289.628008) (xy 268.303998 -289.582732) (xy 268.330301 -289.541136) (xy 268.362936 -289.504299)
			(xy 268.401057 -289.473174) (xy 268.443678 -289.448567) (xy 268.489694 -289.431115) (xy 268.537913 -289.421271)
			(xy 268.587088 -289.41929) (xy 268.635943 -289.425222) (xy 268.683214 -289.438914) (xy 268.727676 -289.460012)
			(xy 268.768179 -289.487968) (xy 268.803672 -289.52206) (xy 268.833237 -289.561404) (xy 268.856108 -289.604981)
			(xy 268.871692 -289.651662) (xy 268.879587 -289.700239) (xy 268.880082 -289.724846) (xy 269.21893 -289.724846)
			(xy 269.22289 -289.675792) (xy 269.234667 -289.628008) (xy 269.253958 -289.582732) (xy 269.280261 -289.541136)
			(xy 269.312896 -289.504299) (xy 269.351017 -289.473174) (xy 269.393638 -289.448567) (xy 269.439654 -289.431115)
			(xy 269.487873 -289.421271) (xy 269.537048 -289.41929) (xy 269.585903 -289.425222) (xy 269.633174 -289.438914)
			(xy 269.677636 -289.460012) (xy 269.718139 -289.487968) (xy 269.753632 -289.52206) (xy 269.783197 -289.561404)
			(xy 269.806068 -289.604981) (xy 269.821652 -289.651662) (xy 269.829547 -289.700239) (xy 269.830042 -289.724846)
			(xy 270.169144 -289.724846) (xy 270.173104 -289.675792) (xy 270.184881 -289.628008) (xy 270.204172 -289.582732)
			(xy 270.230475 -289.541136) (xy 270.26311 -289.504299) (xy 270.301231 -289.473174) (xy 270.343852 -289.448567)
			(xy 270.389868 -289.431115) (xy 270.438087 -289.421271) (xy 270.487262 -289.41929) (xy 270.536117 -289.425222)
			(xy 270.583388 -289.438914) (xy 270.62785 -289.460012) (xy 270.668353 -289.487968) (xy 270.703846 -289.52206)
			(xy 270.733411 -289.561404) (xy 270.756282 -289.604981) (xy 270.771866 -289.651662) (xy 270.779761 -289.700239)
			(xy 270.780256 -289.724846) (xy 271.119104 -289.724846) (xy 271.123064 -289.675792) (xy 271.134841 -289.628008)
			(xy 271.154132 -289.582732) (xy 271.180435 -289.541136) (xy 271.21307 -289.504299) (xy 271.251191 -289.473174)
			(xy 271.293812 -289.448567) (xy 271.339828 -289.431115) (xy 271.388047 -289.421271) (xy 271.437222 -289.41929)
			(xy 271.486077 -289.425222) (xy 271.533348 -289.438914) (xy 271.57781 -289.460012) (xy 271.618313 -289.487968)
			(xy 271.653806 -289.52206) (xy 271.683371 -289.561404) (xy 271.706242 -289.604981) (xy 271.721826 -289.651662)
			(xy 271.729721 -289.700239) (xy 271.730216 -289.724846) (xy 272.069064 -289.724846) (xy 272.073024 -289.675792)
			(xy 272.084801 -289.628008) (xy 272.104092 -289.582732) (xy 272.130395 -289.541136) (xy 272.16303 -289.504299)
			(xy 272.201151 -289.473174) (xy 272.243772 -289.448567) (xy 272.289788 -289.431115) (xy 272.338007 -289.421271)
			(xy 272.387182 -289.41929) (xy 272.436037 -289.425222) (xy 272.483308 -289.438914) (xy 272.52777 -289.460012)
			(xy 272.568273 -289.487968) (xy 272.603766 -289.52206) (xy 272.633331 -289.561404) (xy 272.656202 -289.604981)
			(xy 272.671786 -289.651662) (xy 272.679681 -289.700239) (xy 272.680176 -289.724846) (xy 273.019024 -289.724846)
			(xy 273.022984 -289.675792) (xy 273.034761 -289.628008) (xy 273.054052 -289.582732) (xy 273.080355 -289.541136)
			(xy 273.11299 -289.504299) (xy 273.151111 -289.473174) (xy 273.193732 -289.448567) (xy 273.239748 -289.431115)
			(xy 273.287967 -289.421271) (xy 273.337142 -289.41929) (xy 273.385997 -289.425222) (xy 273.433268 -289.438914)
			(xy 273.47773 -289.460012) (xy 273.518233 -289.487968) (xy 273.553726 -289.52206) (xy 273.583291 -289.561404)
			(xy 273.606162 -289.604981) (xy 273.621746 -289.651662) (xy 273.629641 -289.700239) (xy 273.630136 -289.724846)
			(xy 273.968984 -289.724846) (xy 273.972944 -289.675792) (xy 273.984721 -289.628008) (xy 274.004012 -289.582732)
			(xy 274.030315 -289.541136) (xy 274.06295 -289.504299) (xy 274.101071 -289.473174) (xy 274.143692 -289.448567)
			(xy 274.189708 -289.431115) (xy 274.237927 -289.421271) (xy 274.287102 -289.41929) (xy 274.335957 -289.425222)
			(xy 274.383228 -289.438914) (xy 274.42769 -289.460012) (xy 274.468193 -289.487968) (xy 274.503686 -289.52206)
			(xy 274.533251 -289.561404) (xy 274.556122 -289.604981) (xy 274.571706 -289.651662) (xy 274.579601 -289.700239)
			(xy 274.580096 -289.724846) (xy 274.918944 -289.724846) (xy 274.922904 -289.675792) (xy 274.934681 -289.628008)
			(xy 274.953972 -289.582732) (xy 274.980275 -289.541136) (xy 275.01291 -289.504299) (xy 275.051031 -289.473174)
			(xy 275.093652 -289.448567) (xy 275.139668 -289.431115) (xy 275.187887 -289.421271) (xy 275.237062 -289.41929)
			(xy 275.285917 -289.425222) (xy 275.333188 -289.438914) (xy 275.37765 -289.460012) (xy 275.418153 -289.487968)
			(xy 275.453646 -289.52206) (xy 275.483211 -289.561404) (xy 275.506082 -289.604981) (xy 275.521666 -289.651662)
			(xy 275.529561 -289.700239) (xy 275.530056 -289.724846) (xy 275.868904 -289.724846) (xy 275.872864 -289.675792)
			(xy 275.884641 -289.628008) (xy 275.903932 -289.582732) (xy 275.930235 -289.541136) (xy 275.96287 -289.504299)
			(xy 276.000991 -289.473174) (xy 276.043612 -289.448567) (xy 276.089628 -289.431115) (xy 276.137847 -289.421271)
			(xy 276.187022 -289.41929) (xy 276.235877 -289.425222) (xy 276.283148 -289.438914) (xy 276.32761 -289.460012)
			(xy 276.368113 -289.487968) (xy 276.403606 -289.52206) (xy 276.433171 -289.561404) (xy 276.456042 -289.604981)
			(xy 276.471626 -289.651662) (xy 276.479521 -289.700239) (xy 276.480016 -289.724846) (xy 276.819118 -289.724846)
			(xy 276.823078 -289.675792) (xy 276.834855 -289.628008) (xy 276.854146 -289.582732) (xy 276.880449 -289.541136)
			(xy 276.913084 -289.504299) (xy 276.951205 -289.473174) (xy 276.993826 -289.448567) (xy 277.039842 -289.431115)
			(xy 277.088061 -289.421271) (xy 277.137236 -289.41929) (xy 277.186091 -289.425222) (xy 277.233362 -289.438914)
			(xy 277.277824 -289.460012) (xy 277.318327 -289.487968) (xy 277.35382 -289.52206) (xy 277.383385 -289.561404)
			(xy 277.406256 -289.604981) (xy 277.42184 -289.651662) (xy 277.429735 -289.700239) (xy 277.43023 -289.724846)
			(xy 277.769078 -289.724846) (xy 277.773038 -289.675792) (xy 277.784815 -289.628008) (xy 277.804106 -289.582732)
			(xy 277.830409 -289.541136) (xy 277.863044 -289.504299) (xy 277.901165 -289.473174) (xy 277.943786 -289.448567)
			(xy 277.989802 -289.431115) (xy 278.038021 -289.421271) (xy 278.087196 -289.41929) (xy 278.136051 -289.425222)
			(xy 278.183322 -289.438914) (xy 278.227784 -289.460012) (xy 278.268287 -289.487968) (xy 278.30378 -289.52206)
			(xy 278.333345 -289.561404) (xy 278.356216 -289.604981) (xy 278.3718 -289.651662) (xy 278.379695 -289.700239)
			(xy 278.38019 -289.724846) (xy 278.719038 -289.724846) (xy 278.722998 -289.675792) (xy 278.734775 -289.628008)
			(xy 278.754066 -289.582732) (xy 278.780369 -289.541136) (xy 278.813004 -289.504299) (xy 278.851125 -289.473174)
			(xy 278.893746 -289.448567) (xy 278.939762 -289.431115) (xy 278.987981 -289.421271) (xy 279.037156 -289.41929)
			(xy 279.086011 -289.425222) (xy 279.133282 -289.438914) (xy 279.177744 -289.460012) (xy 279.218247 -289.487968)
			(xy 279.25374 -289.52206) (xy 279.283305 -289.561404) (xy 279.306176 -289.604981) (xy 279.32176 -289.651662)
			(xy 279.329655 -289.700239) (xy 279.33015 -289.724846) (xy 279.668998 -289.724846) (xy 279.672958 -289.675792)
			(xy 279.684735 -289.628008) (xy 279.704026 -289.582732) (xy 279.730329 -289.541136) (xy 279.762964 -289.504299)
			(xy 279.801085 -289.473174) (xy 279.843706 -289.448567) (xy 279.889722 -289.431115) (xy 279.937941 -289.421271)
			(xy 279.987116 -289.41929) (xy 280.035971 -289.425222) (xy 280.083242 -289.438914) (xy 280.127704 -289.460012)
			(xy 280.168207 -289.487968) (xy 280.2037 -289.52206) (xy 280.233265 -289.561404) (xy 280.256136 -289.604981)
			(xy 280.27172 -289.651662) (xy 280.279615 -289.700239) (xy 280.28011 -289.724846) (xy 280.618958 -289.724846)
			(xy 280.622918 -289.675792) (xy 280.634695 -289.628008) (xy 280.653986 -289.582732) (xy 280.680289 -289.541136)
			(xy 280.712924 -289.504299) (xy 280.751045 -289.473174) (xy 280.793666 -289.448567) (xy 280.839682 -289.431115)
			(xy 280.887901 -289.421271) (xy 280.937076 -289.41929) (xy 280.985931 -289.425222) (xy 281.033202 -289.438914)
			(xy 281.077664 -289.460012) (xy 281.118167 -289.487968) (xy 281.15366 -289.52206) (xy 281.183225 -289.561404)
			(xy 281.206096 -289.604981) (xy 281.22168 -289.651662) (xy 281.229575 -289.700239) (xy 281.23007 -289.724846)
			(xy 281.568918 -289.724846) (xy 281.572878 -289.675792) (xy 281.584655 -289.628008) (xy 281.603946 -289.582732)
			(xy 281.630249 -289.541136) (xy 281.662884 -289.504299) (xy 281.701005 -289.473174) (xy 281.743626 -289.448567)
			(xy 281.789642 -289.431115) (xy 281.837861 -289.421271) (xy 281.887036 -289.41929) (xy 281.935891 -289.425222)
			(xy 281.983162 -289.438914) (xy 282.027624 -289.460012) (xy 282.068127 -289.487968) (xy 282.10362 -289.52206)
			(xy 282.133185 -289.561404) (xy 282.156056 -289.604981) (xy 282.17164 -289.651662) (xy 282.179535 -289.700239)
			(xy 282.18003 -289.724846) (xy 282.519132 -289.724846) (xy 282.523092 -289.675792) (xy 282.534869 -289.628008)
			(xy 282.55416 -289.582732) (xy 282.580463 -289.541136) (xy 282.613098 -289.504299) (xy 282.651219 -289.473174)
			(xy 282.69384 -289.448567) (xy 282.739856 -289.431115) (xy 282.788075 -289.421271) (xy 282.83725 -289.41929)
			(xy 282.886105 -289.425222) (xy 282.933376 -289.438914) (xy 282.977838 -289.460012) (xy 283.018341 -289.487968)
			(xy 283.053834 -289.52206) (xy 283.083399 -289.561404) (xy 283.10627 -289.604981) (xy 283.121854 -289.651662)
			(xy 283.129749 -289.700239) (xy 283.130244 -289.724846) (xy 283.469092 -289.724846) (xy 283.473052 -289.675792)
			(xy 283.484829 -289.628008) (xy 283.50412 -289.582732) (xy 283.530423 -289.541136) (xy 283.563058 -289.504299)
			(xy 283.601179 -289.473174) (xy 283.6438 -289.448567) (xy 283.689816 -289.431115) (xy 283.738035 -289.421271)
			(xy 283.78721 -289.41929) (xy 283.836065 -289.425222) (xy 283.883336 -289.438914) (xy 283.927798 -289.460012)
			(xy 283.968301 -289.487968) (xy 284.003794 -289.52206) (xy 284.033359 -289.561404) (xy 284.05623 -289.604981)
			(xy 284.071814 -289.651662) (xy 284.079709 -289.700239) (xy 284.080204 -289.724846) (xy 284.419052 -289.724846)
			(xy 284.423012 -289.675792) (xy 284.434789 -289.628008) (xy 284.45408 -289.582732) (xy 284.480383 -289.541136)
			(xy 284.513018 -289.504299) (xy 284.551139 -289.473174) (xy 284.59376 -289.448567) (xy 284.639776 -289.431115)
			(xy 284.687995 -289.421271) (xy 284.73717 -289.41929) (xy 284.786025 -289.425222) (xy 284.833296 -289.438914)
			(xy 284.877758 -289.460012) (xy 284.918261 -289.487968) (xy 284.953754 -289.52206) (xy 284.983319 -289.561404)
			(xy 285.00619 -289.604981) (xy 285.021774 -289.651662) (xy 285.029669 -289.700239) (xy 285.030164 -289.724846)
			(xy 285.369012 -289.724846) (xy 285.372972 -289.675792) (xy 285.384749 -289.628008) (xy 285.40404 -289.582732)
			(xy 285.430343 -289.541136) (xy 285.462978 -289.504299) (xy 285.501099 -289.473174) (xy 285.54372 -289.448567)
			(xy 285.589736 -289.431115) (xy 285.637955 -289.421271) (xy 285.68713 -289.41929) (xy 285.735985 -289.425222)
			(xy 285.783256 -289.438914) (xy 285.827718 -289.460012) (xy 285.868221 -289.487968) (xy 285.903714 -289.52206)
			(xy 285.933279 -289.561404) (xy 285.95615 -289.604981) (xy 285.971734 -289.651662) (xy 285.979629 -289.700239)
			(xy 285.980124 -289.724846) (xy 286.318972 -289.724846) (xy 286.322932 -289.675792) (xy 286.334709 -289.628008)
			(xy 286.354 -289.582732) (xy 286.380303 -289.541136) (xy 286.412938 -289.504299) (xy 286.451059 -289.473174)
			(xy 286.49368 -289.448567) (xy 286.539696 -289.431115) (xy 286.587915 -289.421271) (xy 286.63709 -289.41929)
			(xy 286.685945 -289.425222) (xy 286.733216 -289.438914) (xy 286.777678 -289.460012) (xy 286.818181 -289.487968)
			(xy 286.853674 -289.52206) (xy 286.883239 -289.561404) (xy 286.90611 -289.604981) (xy 286.921694 -289.651662)
			(xy 286.929589 -289.700239) (xy 286.930084 -289.724846) (xy 287.268932 -289.724846) (xy 287.272892 -289.675792)
			(xy 287.284669 -289.628008) (xy 287.30396 -289.582732) (xy 287.330263 -289.541136) (xy 287.362898 -289.504299)
			(xy 287.401019 -289.473174) (xy 287.44364 -289.448567) (xy 287.489656 -289.431115) (xy 287.537875 -289.421271)
			(xy 287.58705 -289.41929) (xy 287.635905 -289.425222) (xy 287.683176 -289.438914) (xy 287.727638 -289.460012)
			(xy 287.768141 -289.487968) (xy 287.803634 -289.52206) (xy 287.833199 -289.561404) (xy 287.85607 -289.604981)
			(xy 287.871654 -289.651662) (xy 287.879549 -289.700239) (xy 287.880044 -289.724846) (xy 288.218892 -289.724846)
			(xy 288.222852 -289.675792) (xy 288.234629 -289.628008) (xy 288.25392 -289.582732) (xy 288.280223 -289.541136)
			(xy 288.312858 -289.504299) (xy 288.350979 -289.473174) (xy 288.3936 -289.448567) (xy 288.439616 -289.431115)
			(xy 288.487835 -289.421271) (xy 288.53701 -289.41929) (xy 288.585865 -289.425222) (xy 288.633136 -289.438914)
			(xy 288.677598 -289.460012) (xy 288.718101 -289.487968) (xy 288.753594 -289.52206) (xy 288.783159 -289.561404)
			(xy 288.80603 -289.604981) (xy 288.821614 -289.651662) (xy 288.829509 -289.700239) (xy 288.830004 -289.724846)
			(xy 289.169106 -289.724846) (xy 289.173066 -289.675792) (xy 289.184843 -289.628008) (xy 289.204134 -289.582732)
			(xy 289.230437 -289.541136) (xy 289.263072 -289.504299) (xy 289.301193 -289.473174) (xy 289.343814 -289.448567)
			(xy 289.38983 -289.431115) (xy 289.438049 -289.421271) (xy 289.487224 -289.41929) (xy 289.536079 -289.425222)
			(xy 289.58335 -289.438914) (xy 289.627812 -289.460012) (xy 289.668315 -289.487968) (xy 289.703808 -289.52206)
			(xy 289.733373 -289.561404) (xy 289.756244 -289.604981) (xy 289.771828 -289.651662) (xy 289.779723 -289.700239)
			(xy 289.780218 -289.724846) (xy 290.119066 -289.724846) (xy 290.123026 -289.675792) (xy 290.134803 -289.628008)
			(xy 290.154094 -289.582732) (xy 290.180397 -289.541136) (xy 290.213032 -289.504299) (xy 290.251153 -289.473174)
			(xy 290.293774 -289.448567) (xy 290.33979 -289.431115) (xy 290.388009 -289.421271) (xy 290.437184 -289.41929)
			(xy 290.486039 -289.425222) (xy 290.53331 -289.438914) (xy 290.577772 -289.460012) (xy 290.618275 -289.487968)
			(xy 290.653768 -289.52206) (xy 290.683333 -289.561404) (xy 290.706204 -289.604981) (xy 290.721788 -289.651662)
			(xy 290.729683 -289.700239) (xy 290.730178 -289.724846) (xy 292.018986 -289.724846) (xy 292.022946 -289.675792)
			(xy 292.034723 -289.628008) (xy 292.054014 -289.582732) (xy 292.080317 -289.541136) (xy 292.112952 -289.504299)
			(xy 292.151073 -289.473174) (xy 292.193694 -289.448567) (xy 292.23971 -289.431115) (xy 292.287929 -289.421271)
			(xy 292.337104 -289.41929) (xy 292.385959 -289.425222) (xy 292.43323 -289.438914) (xy 292.477692 -289.460012)
			(xy 292.518195 -289.487968) (xy 292.553688 -289.52206) (xy 292.583253 -289.561404) (xy 292.606124 -289.604981)
			(xy 292.621708 -289.651662) (xy 292.629603 -289.700239) (xy 292.630098 -289.724846) (xy 292.968946 -289.724846)
			(xy 292.972906 -289.675792) (xy 292.984683 -289.628008) (xy 293.003974 -289.582732) (xy 293.030277 -289.541136)
			(xy 293.062912 -289.504299) (xy 293.101033 -289.473174) (xy 293.143654 -289.448567) (xy 293.18967 -289.431115)
			(xy 293.237889 -289.421271) (xy 293.287064 -289.41929) (xy 293.335919 -289.425222) (xy 293.38319 -289.438914)
			(xy 293.427652 -289.460012) (xy 293.468155 -289.487968) (xy 293.503648 -289.52206) (xy 293.533213 -289.561404)
			(xy 293.556084 -289.604981) (xy 293.571668 -289.651662) (xy 293.579563 -289.700239) (xy 293.580058 -289.724846)
			(xy 293.918906 -289.724846) (xy 293.922866 -289.675792) (xy 293.934643 -289.628008) (xy 293.953934 -289.582732)
			(xy 293.980237 -289.541136) (xy 294.012872 -289.504299) (xy 294.050993 -289.473174) (xy 294.093614 -289.448567)
			(xy 294.13963 -289.431115) (xy 294.187849 -289.421271) (xy 294.237024 -289.41929) (xy 294.285879 -289.425222)
			(xy 294.33315 -289.438914) (xy 294.377612 -289.460012) (xy 294.418115 -289.487968) (xy 294.453608 -289.52206)
			(xy 294.483173 -289.561404) (xy 294.506044 -289.604981) (xy 294.521628 -289.651662) (xy 294.529523 -289.700239)
			(xy 294.530018 -289.724846) (xy 294.86912 -289.724846) (xy 294.87308 -289.675792) (xy 294.884857 -289.628008)
			(xy 294.904148 -289.582732) (xy 294.930451 -289.541136) (xy 294.963086 -289.504299) (xy 295.001207 -289.473174)
			(xy 295.043828 -289.448567) (xy 295.089844 -289.431115) (xy 295.138063 -289.421271) (xy 295.187238 -289.41929)
			(xy 295.236093 -289.425222) (xy 295.283364 -289.438914) (xy 295.327826 -289.460012) (xy 295.368329 -289.487968)
			(xy 295.403822 -289.52206) (xy 295.433387 -289.561404) (xy 295.456258 -289.604981) (xy 295.471842 -289.651662)
			(xy 295.479737 -289.700239) (xy 295.480232 -289.724846) (xy 295.81908 -289.724846) (xy 295.82304 -289.675792)
			(xy 295.834817 -289.628008) (xy 295.854108 -289.582732) (xy 295.880411 -289.541136) (xy 295.913046 -289.504299)
			(xy 295.951167 -289.473174) (xy 295.993788 -289.448567) (xy 296.039804 -289.431115) (xy 296.088023 -289.421271)
			(xy 296.137198 -289.41929) (xy 296.186053 -289.425222) (xy 296.233324 -289.438914) (xy 296.277786 -289.460012)
			(xy 296.318289 -289.487968) (xy 296.353782 -289.52206) (xy 296.383347 -289.561404) (xy 296.406218 -289.604981)
			(xy 296.421802 -289.651662) (xy 296.429697 -289.700239) (xy 296.430192 -289.724846) (xy 296.76904 -289.724846)
			(xy 296.773 -289.675792) (xy 296.784777 -289.628008) (xy 296.804068 -289.582732) (xy 296.830371 -289.541136)
			(xy 296.863006 -289.504299) (xy 296.901127 -289.473174) (xy 296.943748 -289.448567) (xy 296.989764 -289.431115)
			(xy 297.037983 -289.421271) (xy 297.087158 -289.41929) (xy 297.136013 -289.425222) (xy 297.183284 -289.438914)
			(xy 297.227746 -289.460012) (xy 297.268249 -289.487968) (xy 297.303742 -289.52206) (xy 297.333307 -289.561404)
			(xy 297.356178 -289.604981) (xy 297.371762 -289.651662) (xy 297.379657 -289.700239) (xy 297.380152 -289.724846)
			(xy 297.719 -289.724846) (xy 297.72296 -289.675792) (xy 297.734737 -289.628008) (xy 297.754028 -289.582732)
			(xy 297.780331 -289.541136) (xy 297.812966 -289.504299) (xy 297.851087 -289.473174) (xy 297.893708 -289.448567)
			(xy 297.939724 -289.431115) (xy 297.987943 -289.421271) (xy 298.037118 -289.41929) (xy 298.085973 -289.425222)
			(xy 298.133244 -289.438914) (xy 298.177706 -289.460012) (xy 298.218209 -289.487968) (xy 298.253702 -289.52206)
			(xy 298.283267 -289.561404) (xy 298.306138 -289.604981) (xy 298.321722 -289.651662) (xy 298.329617 -289.700239)
			(xy 298.330112 -289.724846) (xy 298.66896 -289.724846) (xy 298.67292 -289.675792) (xy 298.684697 -289.628008)
			(xy 298.703988 -289.582732) (xy 298.730291 -289.541136) (xy 298.762926 -289.504299) (xy 298.801047 -289.473174)
			(xy 298.843668 -289.448567) (xy 298.889684 -289.431115) (xy 298.937903 -289.421271) (xy 298.987078 -289.41929)
			(xy 299.035933 -289.425222) (xy 299.083204 -289.438914) (xy 299.127666 -289.460012) (xy 299.168169 -289.487968)
			(xy 299.203662 -289.52206) (xy 299.233227 -289.561404) (xy 299.256098 -289.604981) (xy 299.271682 -289.651662)
			(xy 299.279577 -289.700239) (xy 299.280072 -289.724846) (xy 299.61892 -289.724846) (xy 299.62288 -289.675792)
			(xy 299.634657 -289.628008) (xy 299.653948 -289.582732) (xy 299.680251 -289.541136) (xy 299.712886 -289.504299)
			(xy 299.751007 -289.473174) (xy 299.793628 -289.448567) (xy 299.839644 -289.431115) (xy 299.887863 -289.421271)
			(xy 299.937038 -289.41929) (xy 299.985893 -289.425222) (xy 300.033164 -289.438914) (xy 300.077626 -289.460012)
			(xy 300.118129 -289.487968) (xy 300.153622 -289.52206) (xy 300.183187 -289.561404) (xy 300.206058 -289.604981)
			(xy 300.221642 -289.651662) (xy 300.229537 -289.700239) (xy 300.230032 -289.724846) (xy 300.56888 -289.724846)
			(xy 300.57284 -289.675792) (xy 300.584617 -289.628008) (xy 300.603908 -289.582732) (xy 300.630211 -289.541136)
			(xy 300.662846 -289.504299) (xy 300.700967 -289.473174) (xy 300.743588 -289.448567) (xy 300.789604 -289.431115)
			(xy 300.837823 -289.421271) (xy 300.886998 -289.41929) (xy 300.935853 -289.425222) (xy 300.983124 -289.438914)
			(xy 301.027586 -289.460012) (xy 301.068089 -289.487968) (xy 301.103582 -289.52206) (xy 301.133147 -289.561404)
			(xy 301.156018 -289.604981) (xy 301.171602 -289.651662) (xy 301.179497 -289.700239) (xy 301.179992 -289.724846)
			(xy 301.519094 -289.724846) (xy 301.523054 -289.675792) (xy 301.534831 -289.628008) (xy 301.554122 -289.582732)
			(xy 301.580425 -289.541136) (xy 301.61306 -289.504299) (xy 301.651181 -289.473174) (xy 301.693802 -289.448567)
			(xy 301.739818 -289.431115) (xy 301.788037 -289.421271) (xy 301.837212 -289.41929) (xy 301.886067 -289.425222)
			(xy 301.933338 -289.438914) (xy 301.9778 -289.460012) (xy 302.018303 -289.487968) (xy 302.053796 -289.52206)
			(xy 302.083361 -289.561404) (xy 302.106232 -289.604981) (xy 302.121816 -289.651662) (xy 302.129711 -289.700239)
			(xy 302.130206 -289.724846) (xy 302.469054 -289.724846) (xy 302.473014 -289.675792) (xy 302.484791 -289.628008)
			(xy 302.504082 -289.582732) (xy 302.530385 -289.541136) (xy 302.56302 -289.504299) (xy 302.601141 -289.473174)
			(xy 302.643762 -289.448567) (xy 302.689778 -289.431115) (xy 302.737997 -289.421271) (xy 302.787172 -289.41929)
			(xy 302.836027 -289.425222) (xy 302.883298 -289.438914) (xy 302.92776 -289.460012) (xy 302.968263 -289.487968)
			(xy 303.003756 -289.52206) (xy 303.033321 -289.561404) (xy 303.056192 -289.604981) (xy 303.071776 -289.651662)
			(xy 303.079671 -289.700239) (xy 303.080166 -289.724846) (xy 303.419014 -289.724846) (xy 303.422974 -289.675792)
			(xy 303.434751 -289.628008) (xy 303.454042 -289.582732) (xy 303.480345 -289.541136) (xy 303.51298 -289.504299)
			(xy 303.551101 -289.473174) (xy 303.593722 -289.448567) (xy 303.639738 -289.431115) (xy 303.687957 -289.421271)
			(xy 303.737132 -289.41929) (xy 303.785987 -289.425222) (xy 303.833258 -289.438914) (xy 303.87772 -289.460012)
			(xy 303.918223 -289.487968) (xy 303.953716 -289.52206) (xy 303.983281 -289.561404) (xy 304.006152 -289.604981)
			(xy 304.021736 -289.651662) (xy 304.029631 -289.700239) (xy 304.030126 -289.724846) (xy 304.368974 -289.724846)
			(xy 304.372934 -289.675792) (xy 304.384711 -289.628008) (xy 304.404002 -289.582732) (xy 304.430305 -289.541136)
			(xy 304.46294 -289.504299) (xy 304.501061 -289.473174) (xy 304.543682 -289.448567) (xy 304.589698 -289.431115)
			(xy 304.637917 -289.421271) (xy 304.687092 -289.41929) (xy 304.735947 -289.425222) (xy 304.783218 -289.438914)
			(xy 304.82768 -289.460012) (xy 304.868183 -289.487968) (xy 304.903676 -289.52206) (xy 304.933241 -289.561404)
			(xy 304.956112 -289.604981) (xy 304.971696 -289.651662) (xy 304.979591 -289.700239) (xy 304.980086 -289.724846)
			(xy 304.979591 -289.749453) (xy 304.971696 -289.79803) (xy 304.956112 -289.844711) (xy 304.933241 -289.888288)
			(xy 304.903676 -289.927632) (xy 304.868183 -289.961724) (xy 304.82768 -289.98968) (xy 304.783218 -290.010778)
			(xy 304.735947 -290.02447) (xy 304.687092 -290.030402) (xy 304.637917 -290.028421) (xy 304.589698 -290.018577)
			(xy 304.543682 -290.001125) (xy 304.501061 -289.976518) (xy 304.46294 -289.945393) (xy 304.430305 -289.908556)
			(xy 304.404002 -289.86696) (xy 304.384711 -289.821684) (xy 304.372934 -289.7739) (xy 304.368974 -289.724846)
			(xy 304.030126 -289.724846) (xy 304.029631 -289.749453) (xy 304.021736 -289.79803) (xy 304.006152 -289.844711)
			(xy 303.983281 -289.888288) (xy 303.953716 -289.927632) (xy 303.918223 -289.961724) (xy 303.87772 -289.98968)
			(xy 303.833258 -290.010778) (xy 303.785987 -290.02447) (xy 303.737132 -290.030402) (xy 303.687957 -290.028421)
			(xy 303.639738 -290.018577) (xy 303.593722 -290.001125) (xy 303.551101 -289.976518) (xy 303.51298 -289.945393)
			(xy 303.480345 -289.908556) (xy 303.454042 -289.86696) (xy 303.434751 -289.821684) (xy 303.422974 -289.7739)
			(xy 303.419014 -289.724846) (xy 303.080166 -289.724846) (xy 303.079671 -289.749453) (xy 303.071776 -289.79803)
			(xy 303.056192 -289.844711) (xy 303.033321 -289.888288) (xy 303.003756 -289.927632) (xy 302.968263 -289.961724)
			(xy 302.92776 -289.98968) (xy 302.883298 -290.010778) (xy 302.836027 -290.02447) (xy 302.787172 -290.030402)
			(xy 302.737997 -290.028421) (xy 302.689778 -290.018577) (xy 302.643762 -290.001125) (xy 302.601141 -289.976518)
			(xy 302.56302 -289.945393) (xy 302.530385 -289.908556) (xy 302.504082 -289.86696) (xy 302.484791 -289.821684)
			(xy 302.473014 -289.7739) (xy 302.469054 -289.724846) (xy 302.130206 -289.724846) (xy 302.129711 -289.749453)
			(xy 302.121816 -289.79803) (xy 302.106232 -289.844711) (xy 302.083361 -289.888288) (xy 302.053796 -289.927632)
			(xy 302.018303 -289.961724) (xy 301.9778 -289.98968) (xy 301.933338 -290.010778) (xy 301.886067 -290.02447)
			(xy 301.837212 -290.030402) (xy 301.788037 -290.028421) (xy 301.739818 -290.018577) (xy 301.693802 -290.001125)
			(xy 301.651181 -289.976518) (xy 301.61306 -289.945393) (xy 301.580425 -289.908556) (xy 301.554122 -289.86696)
			(xy 301.534831 -289.821684) (xy 301.523054 -289.7739) (xy 301.519094 -289.724846) (xy 301.179992 -289.724846)
			(xy 301.179497 -289.749453) (xy 301.171602 -289.79803) (xy 301.156018 -289.844711) (xy 301.133147 -289.888288)
			(xy 301.103582 -289.927632) (xy 301.068089 -289.961724) (xy 301.027586 -289.98968) (xy 300.983124 -290.010778)
			(xy 300.935853 -290.02447) (xy 300.886998 -290.030402) (xy 300.837823 -290.028421) (xy 300.789604 -290.018577)
			(xy 300.743588 -290.001125) (xy 300.700967 -289.976518) (xy 300.662846 -289.945393) (xy 300.630211 -289.908556)
			(xy 300.603908 -289.86696) (xy 300.584617 -289.821684) (xy 300.57284 -289.7739) (xy 300.56888 -289.724846)
			(xy 300.230032 -289.724846) (xy 300.229537 -289.749453) (xy 300.221642 -289.79803) (xy 300.206058 -289.844711)
			(xy 300.183187 -289.888288) (xy 300.153622 -289.927632) (xy 300.118129 -289.961724) (xy 300.077626 -289.98968)
			(xy 300.033164 -290.010778) (xy 299.985893 -290.02447) (xy 299.937038 -290.030402) (xy 299.887863 -290.028421)
			(xy 299.839644 -290.018577) (xy 299.793628 -290.001125) (xy 299.751007 -289.976518) (xy 299.712886 -289.945393)
			(xy 299.680251 -289.908556) (xy 299.653948 -289.86696) (xy 299.634657 -289.821684) (xy 299.62288 -289.7739)
			(xy 299.61892 -289.724846) (xy 299.280072 -289.724846) (xy 299.279577 -289.749453) (xy 299.271682 -289.79803)
			(xy 299.256098 -289.844711) (xy 299.233227 -289.888288) (xy 299.203662 -289.927632) (xy 299.168169 -289.961724)
			(xy 299.127666 -289.98968) (xy 299.083204 -290.010778) (xy 299.035933 -290.02447) (xy 298.987078 -290.030402)
			(xy 298.937903 -290.028421) (xy 298.889684 -290.018577) (xy 298.843668 -290.001125) (xy 298.801047 -289.976518)
			(xy 298.762926 -289.945393) (xy 298.730291 -289.908556) (xy 298.703988 -289.86696) (xy 298.684697 -289.821684)
			(xy 298.67292 -289.7739) (xy 298.66896 -289.724846) (xy 298.330112 -289.724846) (xy 298.329617 -289.749453)
			(xy 298.321722 -289.79803) (xy 298.306138 -289.844711) (xy 298.283267 -289.888288) (xy 298.253702 -289.927632)
			(xy 298.218209 -289.961724) (xy 298.177706 -289.98968) (xy 298.133244 -290.010778) (xy 298.085973 -290.02447)
			(xy 298.037118 -290.030402) (xy 297.987943 -290.028421) (xy 297.939724 -290.018577) (xy 297.893708 -290.001125)
			(xy 297.851087 -289.976518) (xy 297.812966 -289.945393) (xy 297.780331 -289.908556) (xy 297.754028 -289.86696)
			(xy 297.734737 -289.821684) (xy 297.72296 -289.7739) (xy 297.719 -289.724846) (xy 297.380152 -289.724846)
			(xy 297.379657 -289.749453) (xy 297.371762 -289.79803) (xy 297.356178 -289.844711) (xy 297.333307 -289.888288)
			(xy 297.303742 -289.927632) (xy 297.268249 -289.961724) (xy 297.227746 -289.98968) (xy 297.183284 -290.010778)
			(xy 297.136013 -290.02447) (xy 297.087158 -290.030402) (xy 297.037983 -290.028421) (xy 296.989764 -290.018577)
			(xy 296.943748 -290.001125) (xy 296.901127 -289.976518) (xy 296.863006 -289.945393) (xy 296.830371 -289.908556)
			(xy 296.804068 -289.86696) (xy 296.784777 -289.821684) (xy 296.773 -289.7739) (xy 296.76904 -289.724846)
			(xy 296.430192 -289.724846) (xy 296.429697 -289.749453) (xy 296.421802 -289.79803) (xy 296.406218 -289.844711)
			(xy 296.383347 -289.888288) (xy 296.353782 -289.927632) (xy 296.318289 -289.961724) (xy 296.277786 -289.98968)
			(xy 296.233324 -290.010778) (xy 296.186053 -290.02447) (xy 296.137198 -290.030402) (xy 296.088023 -290.028421)
			(xy 296.039804 -290.018577) (xy 295.993788 -290.001125) (xy 295.951167 -289.976518) (xy 295.913046 -289.945393)
			(xy 295.880411 -289.908556) (xy 295.854108 -289.86696) (xy 295.834817 -289.821684) (xy 295.82304 -289.7739)
			(xy 295.81908 -289.724846) (xy 295.480232 -289.724846) (xy 295.479737 -289.749453) (xy 295.471842 -289.79803)
			(xy 295.456258 -289.844711) (xy 295.433387 -289.888288) (xy 295.403822 -289.927632) (xy 295.368329 -289.961724)
			(xy 295.327826 -289.98968) (xy 295.283364 -290.010778) (xy 295.236093 -290.02447) (xy 295.187238 -290.030402)
			(xy 295.138063 -290.028421) (xy 295.089844 -290.018577) (xy 295.043828 -290.001125) (xy 295.001207 -289.976518)
			(xy 294.963086 -289.945393) (xy 294.930451 -289.908556) (xy 294.904148 -289.86696) (xy 294.884857 -289.821684)
			(xy 294.87308 -289.7739) (xy 294.86912 -289.724846) (xy 294.530018 -289.724846) (xy 294.529523 -289.749453)
			(xy 294.521628 -289.79803) (xy 294.506044 -289.844711) (xy 294.483173 -289.888288) (xy 294.453608 -289.927632)
			(xy 294.418115 -289.961724) (xy 294.377612 -289.98968) (xy 294.33315 -290.010778) (xy 294.285879 -290.02447)
			(xy 294.237024 -290.030402) (xy 294.187849 -290.028421) (xy 294.13963 -290.018577) (xy 294.093614 -290.001125)
			(xy 294.050993 -289.976518) (xy 294.012872 -289.945393) (xy 293.980237 -289.908556) (xy 293.953934 -289.86696)
			(xy 293.934643 -289.821684) (xy 293.922866 -289.7739) (xy 293.918906 -289.724846) (xy 293.580058 -289.724846)
			(xy 293.579563 -289.749453) (xy 293.571668 -289.79803) (xy 293.556084 -289.844711) (xy 293.533213 -289.888288)
			(xy 293.503648 -289.927632) (xy 293.468155 -289.961724) (xy 293.427652 -289.98968) (xy 293.38319 -290.010778)
			(xy 293.335919 -290.02447) (xy 293.287064 -290.030402) (xy 293.237889 -290.028421) (xy 293.18967 -290.018577)
			(xy 293.143654 -290.001125) (xy 293.101033 -289.976518) (xy 293.062912 -289.945393) (xy 293.030277 -289.908556)
			(xy 293.003974 -289.86696) (xy 292.984683 -289.821684) (xy 292.972906 -289.7739) (xy 292.968946 -289.724846)
			(xy 292.630098 -289.724846) (xy 292.629603 -289.749453) (xy 292.621708 -289.79803) (xy 292.606124 -289.844711)
			(xy 292.583253 -289.888288) (xy 292.553688 -289.927632) (xy 292.518195 -289.961724) (xy 292.477692 -289.98968)
			(xy 292.43323 -290.010778) (xy 292.385959 -290.02447) (xy 292.337104 -290.030402) (xy 292.287929 -290.028421)
			(xy 292.23971 -290.018577) (xy 292.193694 -290.001125) (xy 292.151073 -289.976518) (xy 292.112952 -289.945393)
			(xy 292.080317 -289.908556) (xy 292.054014 -289.86696) (xy 292.034723 -289.821684) (xy 292.022946 -289.7739)
			(xy 292.018986 -289.724846) (xy 290.730178 -289.724846) (xy 290.729683 -289.749453) (xy 290.721788 -289.79803)
			(xy 290.706204 -289.844711) (xy 290.683333 -289.888288) (xy 290.653768 -289.927632) (xy 290.618275 -289.961724)
			(xy 290.577772 -289.98968) (xy 290.53331 -290.010778) (xy 290.486039 -290.02447) (xy 290.437184 -290.030402)
			(xy 290.388009 -290.028421) (xy 290.33979 -290.018577) (xy 290.293774 -290.001125) (xy 290.251153 -289.976518)
			(xy 290.213032 -289.945393) (xy 290.180397 -289.908556) (xy 290.154094 -289.86696) (xy 290.134803 -289.821684)
			(xy 290.123026 -289.7739) (xy 290.119066 -289.724846) (xy 289.780218 -289.724846) (xy 289.779723 -289.749453)
			(xy 289.771828 -289.79803) (xy 289.756244 -289.844711) (xy 289.733373 -289.888288) (xy 289.703808 -289.927632)
			(xy 289.668315 -289.961724) (xy 289.627812 -289.98968) (xy 289.58335 -290.010778) (xy 289.536079 -290.02447)
			(xy 289.487224 -290.030402) (xy 289.438049 -290.028421) (xy 289.38983 -290.018577) (xy 289.343814 -290.001125)
			(xy 289.301193 -289.976518) (xy 289.263072 -289.945393) (xy 289.230437 -289.908556) (xy 289.204134 -289.86696)
			(xy 289.184843 -289.821684) (xy 289.173066 -289.7739) (xy 289.169106 -289.724846) (xy 288.830004 -289.724846)
			(xy 288.829509 -289.749453) (xy 288.821614 -289.79803) (xy 288.80603 -289.844711) (xy 288.783159 -289.888288)
			(xy 288.753594 -289.927632) (xy 288.718101 -289.961724) (xy 288.677598 -289.98968) (xy 288.633136 -290.010778)
			(xy 288.585865 -290.02447) (xy 288.53701 -290.030402) (xy 288.487835 -290.028421) (xy 288.439616 -290.018577)
			(xy 288.3936 -290.001125) (xy 288.350979 -289.976518) (xy 288.312858 -289.945393) (xy 288.280223 -289.908556)
			(xy 288.25392 -289.86696) (xy 288.234629 -289.821684) (xy 288.222852 -289.7739) (xy 288.218892 -289.724846)
			(xy 287.880044 -289.724846) (xy 287.879549 -289.749453) (xy 287.871654 -289.79803) (xy 287.85607 -289.844711)
			(xy 287.833199 -289.888288) (xy 287.803634 -289.927632) (xy 287.768141 -289.961724) (xy 287.727638 -289.98968)
			(xy 287.683176 -290.010778) (xy 287.635905 -290.02447) (xy 287.58705 -290.030402) (xy 287.537875 -290.028421)
			(xy 287.489656 -290.018577) (xy 287.44364 -290.001125) (xy 287.401019 -289.976518) (xy 287.362898 -289.945393)
			(xy 287.330263 -289.908556) (xy 287.30396 -289.86696) (xy 287.284669 -289.821684) (xy 287.272892 -289.7739)
			(xy 287.268932 -289.724846) (xy 286.930084 -289.724846) (xy 286.929589 -289.749453) (xy 286.921694 -289.79803)
			(xy 286.90611 -289.844711) (xy 286.883239 -289.888288) (xy 286.853674 -289.927632) (xy 286.818181 -289.961724)
			(xy 286.777678 -289.98968) (xy 286.733216 -290.010778) (xy 286.685945 -290.02447) (xy 286.63709 -290.030402)
			(xy 286.587915 -290.028421) (xy 286.539696 -290.018577) (xy 286.49368 -290.001125) (xy 286.451059 -289.976518)
			(xy 286.412938 -289.945393) (xy 286.380303 -289.908556) (xy 286.354 -289.86696) (xy 286.334709 -289.821684)
			(xy 286.322932 -289.7739) (xy 286.318972 -289.724846) (xy 285.980124 -289.724846) (xy 285.979629 -289.749453)
			(xy 285.971734 -289.79803) (xy 285.95615 -289.844711) (xy 285.933279 -289.888288) (xy 285.903714 -289.927632)
			(xy 285.868221 -289.961724) (xy 285.827718 -289.98968) (xy 285.783256 -290.010778) (xy 285.735985 -290.02447)
			(xy 285.68713 -290.030402) (xy 285.637955 -290.028421) (xy 285.589736 -290.018577) (xy 285.54372 -290.001125)
			(xy 285.501099 -289.976518) (xy 285.462978 -289.945393) (xy 285.430343 -289.908556) (xy 285.40404 -289.86696)
			(xy 285.384749 -289.821684) (xy 285.372972 -289.7739) (xy 285.369012 -289.724846) (xy 285.030164 -289.724846)
			(xy 285.029669 -289.749453) (xy 285.021774 -289.79803) (xy 285.00619 -289.844711) (xy 284.983319 -289.888288)
			(xy 284.953754 -289.927632) (xy 284.918261 -289.961724) (xy 284.877758 -289.98968) (xy 284.833296 -290.010778)
			(xy 284.786025 -290.02447) (xy 284.73717 -290.030402) (xy 284.687995 -290.028421) (xy 284.639776 -290.018577)
			(xy 284.59376 -290.001125) (xy 284.551139 -289.976518) (xy 284.513018 -289.945393) (xy 284.480383 -289.908556)
			(xy 284.45408 -289.86696) (xy 284.434789 -289.821684) (xy 284.423012 -289.7739) (xy 284.419052 -289.724846)
			(xy 284.080204 -289.724846) (xy 284.079709 -289.749453) (xy 284.071814 -289.79803) (xy 284.05623 -289.844711)
			(xy 284.033359 -289.888288) (xy 284.003794 -289.927632) (xy 283.968301 -289.961724) (xy 283.927798 -289.98968)
			(xy 283.883336 -290.010778) (xy 283.836065 -290.02447) (xy 283.78721 -290.030402) (xy 283.738035 -290.028421)
			(xy 283.689816 -290.018577) (xy 283.6438 -290.001125) (xy 283.601179 -289.976518) (xy 283.563058 -289.945393)
			(xy 283.530423 -289.908556) (xy 283.50412 -289.86696) (xy 283.484829 -289.821684) (xy 283.473052 -289.7739)
			(xy 283.469092 -289.724846) (xy 283.130244 -289.724846) (xy 283.129749 -289.749453) (xy 283.121854 -289.79803)
			(xy 283.10627 -289.844711) (xy 283.083399 -289.888288) (xy 283.053834 -289.927632) (xy 283.018341 -289.961724)
			(xy 282.977838 -289.98968) (xy 282.933376 -290.010778) (xy 282.886105 -290.02447) (xy 282.83725 -290.030402)
			(xy 282.788075 -290.028421) (xy 282.739856 -290.018577) (xy 282.69384 -290.001125) (xy 282.651219 -289.976518)
			(xy 282.613098 -289.945393) (xy 282.580463 -289.908556) (xy 282.55416 -289.86696) (xy 282.534869 -289.821684)
			(xy 282.523092 -289.7739) (xy 282.519132 -289.724846) (xy 282.18003 -289.724846) (xy 282.179535 -289.749453)
			(xy 282.17164 -289.79803) (xy 282.156056 -289.844711) (xy 282.133185 -289.888288) (xy 282.10362 -289.927632)
			(xy 282.068127 -289.961724) (xy 282.027624 -289.98968) (xy 281.983162 -290.010778) (xy 281.935891 -290.02447)
			(xy 281.887036 -290.030402) (xy 281.837861 -290.028421) (xy 281.789642 -290.018577) (xy 281.743626 -290.001125)
			(xy 281.701005 -289.976518) (xy 281.662884 -289.945393) (xy 281.630249 -289.908556) (xy 281.603946 -289.86696)
			(xy 281.584655 -289.821684) (xy 281.572878 -289.7739) (xy 281.568918 -289.724846) (xy 281.23007 -289.724846)
			(xy 281.229575 -289.749453) (xy 281.22168 -289.79803) (xy 281.206096 -289.844711) (xy 281.183225 -289.888288)
			(xy 281.15366 -289.927632) (xy 281.118167 -289.961724) (xy 281.077664 -289.98968) (xy 281.033202 -290.010778)
			(xy 280.985931 -290.02447) (xy 280.937076 -290.030402) (xy 280.887901 -290.028421) (xy 280.839682 -290.018577)
			(xy 280.793666 -290.001125) (xy 280.751045 -289.976518) (xy 280.712924 -289.945393) (xy 280.680289 -289.908556)
			(xy 280.653986 -289.86696) (xy 280.634695 -289.821684) (xy 280.622918 -289.7739) (xy 280.618958 -289.724846)
			(xy 280.28011 -289.724846) (xy 280.279615 -289.749453) (xy 280.27172 -289.79803) (xy 280.256136 -289.844711)
			(xy 280.233265 -289.888288) (xy 280.2037 -289.927632) (xy 280.168207 -289.961724) (xy 280.127704 -289.98968)
			(xy 280.083242 -290.010778) (xy 280.035971 -290.02447) (xy 279.987116 -290.030402) (xy 279.937941 -290.028421)
			(xy 279.889722 -290.018577) (xy 279.843706 -290.001125) (xy 279.801085 -289.976518) (xy 279.762964 -289.945393)
			(xy 279.730329 -289.908556) (xy 279.704026 -289.86696) (xy 279.684735 -289.821684) (xy 279.672958 -289.7739)
			(xy 279.668998 -289.724846) (xy 279.33015 -289.724846) (xy 279.329655 -289.749453) (xy 279.32176 -289.79803)
			(xy 279.306176 -289.844711) (xy 279.283305 -289.888288) (xy 279.25374 -289.927632) (xy 279.218247 -289.961724)
			(xy 279.177744 -289.98968) (xy 279.133282 -290.010778) (xy 279.086011 -290.02447) (xy 279.037156 -290.030402)
			(xy 278.987981 -290.028421) (xy 278.939762 -290.018577) (xy 278.893746 -290.001125) (xy 278.851125 -289.976518)
			(xy 278.813004 -289.945393) (xy 278.780369 -289.908556) (xy 278.754066 -289.86696) (xy 278.734775 -289.821684)
			(xy 278.722998 -289.7739) (xy 278.719038 -289.724846) (xy 278.38019 -289.724846) (xy 278.379695 -289.749453)
			(xy 278.3718 -289.79803) (xy 278.356216 -289.844711) (xy 278.333345 -289.888288) (xy 278.30378 -289.927632)
			(xy 278.268287 -289.961724) (xy 278.227784 -289.98968) (xy 278.183322 -290.010778) (xy 278.136051 -290.02447)
			(xy 278.087196 -290.030402) (xy 278.038021 -290.028421) (xy 277.989802 -290.018577) (xy 277.943786 -290.001125)
			(xy 277.901165 -289.976518) (xy 277.863044 -289.945393) (xy 277.830409 -289.908556) (xy 277.804106 -289.86696)
			(xy 277.784815 -289.821684) (xy 277.773038 -289.7739) (xy 277.769078 -289.724846) (xy 277.43023 -289.724846)
			(xy 277.429735 -289.749453) (xy 277.42184 -289.79803) (xy 277.406256 -289.844711) (xy 277.383385 -289.888288)
			(xy 277.35382 -289.927632) (xy 277.318327 -289.961724) (xy 277.277824 -289.98968) (xy 277.233362 -290.010778)
			(xy 277.186091 -290.02447) (xy 277.137236 -290.030402) (xy 277.088061 -290.028421) (xy 277.039842 -290.018577)
			(xy 276.993826 -290.001125) (xy 276.951205 -289.976518) (xy 276.913084 -289.945393) (xy 276.880449 -289.908556)
			(xy 276.854146 -289.86696) (xy 276.834855 -289.821684) (xy 276.823078 -289.7739) (xy 276.819118 -289.724846)
			(xy 276.480016 -289.724846) (xy 276.479521 -289.749453) (xy 276.471626 -289.79803) (xy 276.456042 -289.844711)
			(xy 276.433171 -289.888288) (xy 276.403606 -289.927632) (xy 276.368113 -289.961724) (xy 276.32761 -289.98968)
			(xy 276.283148 -290.010778) (xy 276.235877 -290.02447) (xy 276.187022 -290.030402) (xy 276.137847 -290.028421)
			(xy 276.089628 -290.018577) (xy 276.043612 -290.001125) (xy 276.000991 -289.976518) (xy 275.96287 -289.945393)
			(xy 275.930235 -289.908556) (xy 275.903932 -289.86696) (xy 275.884641 -289.821684) (xy 275.872864 -289.7739)
			(xy 275.868904 -289.724846) (xy 275.530056 -289.724846) (xy 275.529561 -289.749453) (xy 275.521666 -289.79803)
			(xy 275.506082 -289.844711) (xy 275.483211 -289.888288) (xy 275.453646 -289.927632) (xy 275.418153 -289.961724)
			(xy 275.37765 -289.98968) (xy 275.333188 -290.010778) (xy 275.285917 -290.02447) (xy 275.237062 -290.030402)
			(xy 275.187887 -290.028421) (xy 275.139668 -290.018577) (xy 275.093652 -290.001125) (xy 275.051031 -289.976518)
			(xy 275.01291 -289.945393) (xy 274.980275 -289.908556) (xy 274.953972 -289.86696) (xy 274.934681 -289.821684)
			(xy 274.922904 -289.7739) (xy 274.918944 -289.724846) (xy 274.580096 -289.724846) (xy 274.579601 -289.749453)
			(xy 274.571706 -289.79803) (xy 274.556122 -289.844711) (xy 274.533251 -289.888288) (xy 274.503686 -289.927632)
			(xy 274.468193 -289.961724) (xy 274.42769 -289.98968) (xy 274.383228 -290.010778) (xy 274.335957 -290.02447)
			(xy 274.287102 -290.030402) (xy 274.237927 -290.028421) (xy 274.189708 -290.018577) (xy 274.143692 -290.001125)
			(xy 274.101071 -289.976518) (xy 274.06295 -289.945393) (xy 274.030315 -289.908556) (xy 274.004012 -289.86696)
			(xy 273.984721 -289.821684) (xy 273.972944 -289.7739) (xy 273.968984 -289.724846) (xy 273.630136 -289.724846)
			(xy 273.629641 -289.749453) (xy 273.621746 -289.79803) (xy 273.606162 -289.844711) (xy 273.583291 -289.888288)
			(xy 273.553726 -289.927632) (xy 273.518233 -289.961724) (xy 273.47773 -289.98968) (xy 273.433268 -290.010778)
			(xy 273.385997 -290.02447) (xy 273.337142 -290.030402) (xy 273.287967 -290.028421) (xy 273.239748 -290.018577)
			(xy 273.193732 -290.001125) (xy 273.151111 -289.976518) (xy 273.11299 -289.945393) (xy 273.080355 -289.908556)
			(xy 273.054052 -289.86696) (xy 273.034761 -289.821684) (xy 273.022984 -289.7739) (xy 273.019024 -289.724846)
			(xy 272.680176 -289.724846) (xy 272.679681 -289.749453) (xy 272.671786 -289.79803) (xy 272.656202 -289.844711)
			(xy 272.633331 -289.888288) (xy 272.603766 -289.927632) (xy 272.568273 -289.961724) (xy 272.52777 -289.98968)
			(xy 272.483308 -290.010778) (xy 272.436037 -290.02447) (xy 272.387182 -290.030402) (xy 272.338007 -290.028421)
			(xy 272.289788 -290.018577) (xy 272.243772 -290.001125) (xy 272.201151 -289.976518) (xy 272.16303 -289.945393)
			(xy 272.130395 -289.908556) (xy 272.104092 -289.86696) (xy 272.084801 -289.821684) (xy 272.073024 -289.7739)
			(xy 272.069064 -289.724846) (xy 271.730216 -289.724846) (xy 271.729721 -289.749453) (xy 271.721826 -289.79803)
			(xy 271.706242 -289.844711) (xy 271.683371 -289.888288) (xy 271.653806 -289.927632) (xy 271.618313 -289.961724)
			(xy 271.57781 -289.98968) (xy 271.533348 -290.010778) (xy 271.486077 -290.02447) (xy 271.437222 -290.030402)
			(xy 271.388047 -290.028421) (xy 271.339828 -290.018577) (xy 271.293812 -290.001125) (xy 271.251191 -289.976518)
			(xy 271.21307 -289.945393) (xy 271.180435 -289.908556) (xy 271.154132 -289.86696) (xy 271.134841 -289.821684)
			(xy 271.123064 -289.7739) (xy 271.119104 -289.724846) (xy 270.780256 -289.724846) (xy 270.779761 -289.749453)
			(xy 270.771866 -289.79803) (xy 270.756282 -289.844711) (xy 270.733411 -289.888288) (xy 270.703846 -289.927632)
			(xy 270.668353 -289.961724) (xy 270.62785 -289.98968) (xy 270.583388 -290.010778) (xy 270.536117 -290.02447)
			(xy 270.487262 -290.030402) (xy 270.438087 -290.028421) (xy 270.389868 -290.018577) (xy 270.343852 -290.001125)
			(xy 270.301231 -289.976518) (xy 270.26311 -289.945393) (xy 270.230475 -289.908556) (xy 270.204172 -289.86696)
			(xy 270.184881 -289.821684) (xy 270.173104 -289.7739) (xy 270.169144 -289.724846) (xy 269.830042 -289.724846)
			(xy 269.829547 -289.749453) (xy 269.821652 -289.79803) (xy 269.806068 -289.844711) (xy 269.783197 -289.888288)
			(xy 269.753632 -289.927632) (xy 269.718139 -289.961724) (xy 269.677636 -289.98968) (xy 269.633174 -290.010778)
			(xy 269.585903 -290.02447) (xy 269.537048 -290.030402) (xy 269.487873 -290.028421) (xy 269.439654 -290.018577)
			(xy 269.393638 -290.001125) (xy 269.351017 -289.976518) (xy 269.312896 -289.945393) (xy 269.280261 -289.908556)
			(xy 269.253958 -289.86696) (xy 269.234667 -289.821684) (xy 269.22289 -289.7739) (xy 269.21893 -289.724846)
			(xy 268.880082 -289.724846) (xy 268.879587 -289.749453) (xy 268.871692 -289.79803) (xy 268.856108 -289.844711)
			(xy 268.833237 -289.888288) (xy 268.803672 -289.927632) (xy 268.768179 -289.961724) (xy 268.727676 -289.98968)
			(xy 268.683214 -290.010778) (xy 268.635943 -290.02447) (xy 268.587088 -290.030402) (xy 268.537913 -290.028421)
			(xy 268.489694 -290.018577) (xy 268.443678 -290.001125) (xy 268.401057 -289.976518) (xy 268.362936 -289.945393)
			(xy 268.330301 -289.908556) (xy 268.303998 -289.86696) (xy 268.284707 -289.821684) (xy 268.27293 -289.7739)
			(xy 268.26897 -289.724846) (xy 264.260539 -289.724846) (xy 264.258791 -289.728354) (xy 264.224818 -289.776305)
			(xy 264.183891 -289.818476) (xy 264.160762 -289.836606) (xy 264.151364 -289.843972) (xy 264.14095 -289.864546)
			(xy 264.139426 -289.968432) (xy 264.149332 -289.989514) (xy 264.158476 -289.99688) (xy 264.180292 -290.015123)
			(xy 264.218835 -290.056933) (xy 264.250747 -290.104001) (xy 264.275319 -290.155284) (xy 264.292009 -290.209645)
			(xy 264.300447 -290.265881) (xy 264.30097 -290.294314) (xy 264.934444 -290.294314) (xy 264.938515 -290.238692)
			(xy 264.950641 -290.184255) (xy 264.970564 -290.132164) (xy 264.99786 -290.083529) (xy 265.031946 -290.039386)
			(xy 265.072095 -290.000677) (xy 265.117453 -289.968226) (xy 265.167053 -289.942725) (xy 265.219837 -289.924718)
			(xy 265.27468 -289.914588) (xy 265.330414 -289.912551) (xy 265.385851 -289.918651) (xy 265.439808 -289.932757)
			(xy 265.491137 -289.954569) (xy 265.538743 -289.983623) (xy 265.581611 -290.019298) (xy 265.618828 -290.060835)
			(xy 265.649601 -290.107348) (xy 265.673273 -290.157845) (xy 265.689341 -290.211252) (xy 265.697461 -290.266428)
			(xy 265.69797 -290.294314) (xy 265.820904 -290.294314) (xy 265.824975 -290.238692) (xy 265.837101 -290.184255)
			(xy 265.857024 -290.132164) (xy 265.88432 -290.083529) (xy 265.918406 -290.039386) (xy 265.958555 -290.000677)
			(xy 266.003913 -289.968226) (xy 266.053513 -289.942725) (xy 266.106297 -289.924718) (xy 266.16114 -289.914588)
			(xy 266.216874 -289.912551) (xy 266.272311 -289.918651) (xy 266.326268 -289.932757) (xy 266.377597 -289.954569)
			(xy 266.425203 -289.983623) (xy 266.468071 -290.019298) (xy 266.505288 -290.060835) (xy 266.536061 -290.107348)
			(xy 266.559733 -290.157845) (xy 266.575801 -290.211252) (xy 266.583921 -290.266428) (xy 266.58443 -290.294314)
			(xy 266.583921 -290.3222) (xy 266.575801 -290.377376) (xy 266.559733 -290.430783) (xy 266.536061 -290.48128)
			(xy 266.505288 -290.527793) (xy 266.468071 -290.56933) (xy 266.425203 -290.605005) (xy 266.377597 -290.634059)
			(xy 266.326268 -290.655871) (xy 266.272311 -290.669977) (xy 266.228425 -290.674806) (xy 268.26897 -290.674806)
			(xy 268.27293 -290.625752) (xy 268.284707 -290.577968) (xy 268.303998 -290.532692) (xy 268.330301 -290.491096)
			(xy 268.362936 -290.454259) (xy 268.401057 -290.423134) (xy 268.443678 -290.398527) (xy 268.489694 -290.381075)
			(xy 268.537913 -290.371231) (xy 268.587088 -290.36925) (xy 268.635943 -290.375182) (xy 268.683214 -290.388874)
			(xy 268.727676 -290.409972) (xy 268.768179 -290.437928) (xy 268.803672 -290.47202) (xy 268.833237 -290.511364)
			(xy 268.856108 -290.554941) (xy 268.871692 -290.601622) (xy 268.879587 -290.650199) (xy 268.880082 -290.674806)
			(xy 269.21893 -290.674806) (xy 269.22289 -290.625752) (xy 269.234667 -290.577968) (xy 269.253958 -290.532692)
			(xy 269.280261 -290.491096) (xy 269.312896 -290.454259) (xy 269.351017 -290.423134) (xy 269.393638 -290.398527)
			(xy 269.439654 -290.381075) (xy 269.487873 -290.371231) (xy 269.537048 -290.36925) (xy 269.585903 -290.375182)
			(xy 269.633174 -290.388874) (xy 269.677636 -290.409972) (xy 269.718139 -290.437928) (xy 269.753632 -290.47202)
			(xy 269.783197 -290.511364) (xy 269.806068 -290.554941) (xy 269.821652 -290.601622) (xy 269.829547 -290.650199)
			(xy 269.830042 -290.674806) (xy 270.169144 -290.674806) (xy 270.173104 -290.625752) (xy 270.184881 -290.577968)
			(xy 270.204172 -290.532692) (xy 270.230475 -290.491096) (xy 270.26311 -290.454259) (xy 270.301231 -290.423134)
			(xy 270.343852 -290.398527) (xy 270.389868 -290.381075) (xy 270.438087 -290.371231) (xy 270.487262 -290.36925)
			(xy 270.536117 -290.375182) (xy 270.583388 -290.388874) (xy 270.62785 -290.409972) (xy 270.668353 -290.437928)
			(xy 270.703846 -290.47202) (xy 270.733411 -290.511364) (xy 270.756282 -290.554941) (xy 270.771866 -290.601622)
			(xy 270.779761 -290.650199) (xy 270.780256 -290.674806) (xy 273.019024 -290.674806) (xy 273.022984 -290.625752)
			(xy 273.034761 -290.577968) (xy 273.054052 -290.532692) (xy 273.080355 -290.491096) (xy 273.11299 -290.454259)
			(xy 273.151111 -290.423134) (xy 273.193732 -290.398527) (xy 273.239748 -290.381075) (xy 273.287967 -290.371231)
			(xy 273.337142 -290.36925) (xy 273.385997 -290.375182) (xy 273.433268 -290.388874) (xy 273.47773 -290.409972)
			(xy 273.518233 -290.437928) (xy 273.553726 -290.47202) (xy 273.583291 -290.511364) (xy 273.606162 -290.554941)
			(xy 273.621746 -290.601622) (xy 273.629641 -290.650199) (xy 273.630136 -290.674806) (xy 273.968984 -290.674806)
			(xy 273.972944 -290.625752) (xy 273.984721 -290.577968) (xy 274.004012 -290.532692) (xy 274.030315 -290.491096)
			(xy 274.06295 -290.454259) (xy 274.101071 -290.423134) (xy 274.143692 -290.398527) (xy 274.189708 -290.381075)
			(xy 274.237927 -290.371231) (xy 274.287102 -290.36925) (xy 274.335957 -290.375182) (xy 274.383228 -290.388874)
			(xy 274.42769 -290.409972) (xy 274.468193 -290.437928) (xy 274.503686 -290.47202) (xy 274.533251 -290.511364)
			(xy 274.556122 -290.554941) (xy 274.571706 -290.601622) (xy 274.579601 -290.650199) (xy 274.580096 -290.674806)
			(xy 274.918944 -290.674806) (xy 274.922904 -290.625752) (xy 274.934681 -290.577968) (xy 274.953972 -290.532692)
			(xy 274.980275 -290.491096) (xy 275.01291 -290.454259) (xy 275.051031 -290.423134) (xy 275.093652 -290.398527)
			(xy 275.139668 -290.381075) (xy 275.187887 -290.371231) (xy 275.237062 -290.36925) (xy 275.285917 -290.375182)
			(xy 275.333188 -290.388874) (xy 275.37765 -290.409972) (xy 275.418153 -290.437928) (xy 275.453646 -290.47202)
			(xy 275.483211 -290.511364) (xy 275.506082 -290.554941) (xy 275.521666 -290.601622) (xy 275.529561 -290.650199)
			(xy 275.530056 -290.674806) (xy 275.868904 -290.674806) (xy 275.872864 -290.625752) (xy 275.884641 -290.577968)
			(xy 275.903932 -290.532692) (xy 275.930235 -290.491096) (xy 275.96287 -290.454259) (xy 276.000991 -290.423134)
			(xy 276.043612 -290.398527) (xy 276.089628 -290.381075) (xy 276.137847 -290.371231) (xy 276.187022 -290.36925)
			(xy 276.235877 -290.375182) (xy 276.283148 -290.388874) (xy 276.32761 -290.409972) (xy 276.368113 -290.437928)
			(xy 276.403606 -290.47202) (xy 276.433171 -290.511364) (xy 276.456042 -290.554941) (xy 276.471626 -290.601622)
			(xy 276.479521 -290.650199) (xy 276.480016 -290.674806) (xy 276.819118 -290.674806) (xy 276.823078 -290.625752)
			(xy 276.834855 -290.577968) (xy 276.854146 -290.532692) (xy 276.880449 -290.491096) (xy 276.913084 -290.454259)
			(xy 276.951205 -290.423134) (xy 276.993826 -290.398527) (xy 277.039842 -290.381075) (xy 277.088061 -290.371231)
			(xy 277.137236 -290.36925) (xy 277.186091 -290.375182) (xy 277.233362 -290.388874) (xy 277.277824 -290.409972)
			(xy 277.318327 -290.437928) (xy 277.35382 -290.47202) (xy 277.383385 -290.511364) (xy 277.406256 -290.554941)
			(xy 277.42184 -290.601622) (xy 277.429735 -290.650199) (xy 277.43023 -290.674806) (xy 277.769078 -290.674806)
			(xy 277.773038 -290.625752) (xy 277.784815 -290.577968) (xy 277.804106 -290.532692) (xy 277.830409 -290.491096)
			(xy 277.863044 -290.454259) (xy 277.901165 -290.423134) (xy 277.943786 -290.398527) (xy 277.989802 -290.381075)
			(xy 278.038021 -290.371231) (xy 278.087196 -290.36925) (xy 278.136051 -290.375182) (xy 278.183322 -290.388874)
			(xy 278.227784 -290.409972) (xy 278.268287 -290.437928) (xy 278.30378 -290.47202) (xy 278.333345 -290.511364)
			(xy 278.356216 -290.554941) (xy 278.3718 -290.601622) (xy 278.379695 -290.650199) (xy 278.38019 -290.674806)
			(xy 278.719038 -290.674806) (xy 278.722998 -290.625752) (xy 278.734775 -290.577968) (xy 278.754066 -290.532692)
			(xy 278.780369 -290.491096) (xy 278.813004 -290.454259) (xy 278.851125 -290.423134) (xy 278.893746 -290.398527)
			(xy 278.939762 -290.381075) (xy 278.987981 -290.371231) (xy 279.037156 -290.36925) (xy 279.086011 -290.375182)
			(xy 279.133282 -290.388874) (xy 279.177744 -290.409972) (xy 279.218247 -290.437928) (xy 279.25374 -290.47202)
			(xy 279.283305 -290.511364) (xy 279.306176 -290.554941) (xy 279.32176 -290.601622) (xy 279.329655 -290.650199)
			(xy 279.33015 -290.674806) (xy 279.668998 -290.674806) (xy 279.672958 -290.625752) (xy 279.684735 -290.577968)
			(xy 279.704026 -290.532692) (xy 279.730329 -290.491096) (xy 279.762964 -290.454259) (xy 279.801085 -290.423134)
			(xy 279.843706 -290.398527) (xy 279.889722 -290.381075) (xy 279.937941 -290.371231) (xy 279.987116 -290.36925)
			(xy 280.035971 -290.375182) (xy 280.083242 -290.388874) (xy 280.127704 -290.409972) (xy 280.168207 -290.437928)
			(xy 280.2037 -290.47202) (xy 280.233265 -290.511364) (xy 280.256136 -290.554941) (xy 280.27172 -290.601622)
			(xy 280.279615 -290.650199) (xy 280.28011 -290.674806) (xy 280.618958 -290.674806) (xy 280.622918 -290.625752)
			(xy 280.634695 -290.577968) (xy 280.653986 -290.532692) (xy 280.680289 -290.491096) (xy 280.712924 -290.454259)
			(xy 280.751045 -290.423134) (xy 280.793666 -290.398527) (xy 280.839682 -290.381075) (xy 280.887901 -290.371231)
			(xy 280.937076 -290.36925) (xy 280.985931 -290.375182) (xy 281.033202 -290.388874) (xy 281.077664 -290.409972)
			(xy 281.118167 -290.437928) (xy 281.15366 -290.47202) (xy 281.183225 -290.511364) (xy 281.206096 -290.554941)
			(xy 281.22168 -290.601622) (xy 281.229575 -290.650199) (xy 281.23007 -290.674806) (xy 281.568918 -290.674806)
			(xy 281.572878 -290.625752) (xy 281.584655 -290.577968) (xy 281.603946 -290.532692) (xy 281.630249 -290.491096)
			(xy 281.662884 -290.454259) (xy 281.701005 -290.423134) (xy 281.743626 -290.398527) (xy 281.789642 -290.381075)
			(xy 281.837861 -290.371231) (xy 281.887036 -290.36925) (xy 281.935891 -290.375182) (xy 281.983162 -290.388874)
			(xy 282.027624 -290.409972) (xy 282.068127 -290.437928) (xy 282.10362 -290.47202) (xy 282.133185 -290.511364)
			(xy 282.156056 -290.554941) (xy 282.17164 -290.601622) (xy 282.179535 -290.650199) (xy 282.18003 -290.674806)
			(xy 282.519132 -290.674806) (xy 282.523092 -290.625752) (xy 282.534869 -290.577968) (xy 282.55416 -290.532692)
			(xy 282.580463 -290.491096) (xy 282.613098 -290.454259) (xy 282.651219 -290.423134) (xy 282.69384 -290.398527)
			(xy 282.739856 -290.381075) (xy 282.788075 -290.371231) (xy 282.83725 -290.36925) (xy 282.886105 -290.375182)
			(xy 282.933376 -290.388874) (xy 282.977838 -290.409972) (xy 283.018341 -290.437928) (xy 283.053834 -290.47202)
			(xy 283.083399 -290.511364) (xy 283.10627 -290.554941) (xy 283.121854 -290.601622) (xy 283.129749 -290.650199)
			(xy 283.130244 -290.674806) (xy 283.469092 -290.674806) (xy 283.473052 -290.625752) (xy 283.484829 -290.577968)
			(xy 283.50412 -290.532692) (xy 283.530423 -290.491096) (xy 283.563058 -290.454259) (xy 283.601179 -290.423134)
			(xy 283.6438 -290.398527) (xy 283.689816 -290.381075) (xy 283.738035 -290.371231) (xy 283.78721 -290.36925)
			(xy 283.836065 -290.375182) (xy 283.883336 -290.388874) (xy 283.927798 -290.409972) (xy 283.968301 -290.437928)
			(xy 284.003794 -290.47202) (xy 284.033359 -290.511364) (xy 284.05623 -290.554941) (xy 284.071814 -290.601622)
			(xy 284.079709 -290.650199) (xy 284.080204 -290.674806) (xy 284.419052 -290.674806) (xy 284.423012 -290.625752)
			(xy 284.434789 -290.577968) (xy 284.45408 -290.532692) (xy 284.480383 -290.491096) (xy 284.513018 -290.454259)
			(xy 284.551139 -290.423134) (xy 284.59376 -290.398527) (xy 284.639776 -290.381075) (xy 284.687995 -290.371231)
			(xy 284.73717 -290.36925) (xy 284.786025 -290.375182) (xy 284.833296 -290.388874) (xy 284.877758 -290.409972)
			(xy 284.918261 -290.437928) (xy 284.953754 -290.47202) (xy 284.983319 -290.511364) (xy 285.00619 -290.554941)
			(xy 285.021774 -290.601622) (xy 285.029669 -290.650199) (xy 285.030164 -290.674806) (xy 285.369012 -290.674806)
			(xy 285.372972 -290.625752) (xy 285.384749 -290.577968) (xy 285.40404 -290.532692) (xy 285.430343 -290.491096)
			(xy 285.462978 -290.454259) (xy 285.501099 -290.423134) (xy 285.54372 -290.398527) (xy 285.589736 -290.381075)
			(xy 285.637955 -290.371231) (xy 285.68713 -290.36925) (xy 285.735985 -290.375182) (xy 285.783256 -290.388874)
			(xy 285.827718 -290.409972) (xy 285.868221 -290.437928) (xy 285.903714 -290.47202) (xy 285.933279 -290.511364)
			(xy 285.95615 -290.554941) (xy 285.971734 -290.601622) (xy 285.979629 -290.650199) (xy 285.980124 -290.674806)
			(xy 286.318972 -290.674806) (xy 286.322932 -290.625752) (xy 286.334709 -290.577968) (xy 286.354 -290.532692)
			(xy 286.380303 -290.491096) (xy 286.412938 -290.454259) (xy 286.451059 -290.423134) (xy 286.49368 -290.398527)
			(xy 286.539696 -290.381075) (xy 286.587915 -290.371231) (xy 286.63709 -290.36925) (xy 286.685945 -290.375182)
			(xy 286.733216 -290.388874) (xy 286.777678 -290.409972) (xy 286.818181 -290.437928) (xy 286.853674 -290.47202)
			(xy 286.883239 -290.511364) (xy 286.90611 -290.554941) (xy 286.921694 -290.601622) (xy 286.929589 -290.650199)
			(xy 286.930084 -290.674806) (xy 287.268932 -290.674806) (xy 287.272892 -290.625752) (xy 287.284669 -290.577968)
			(xy 287.30396 -290.532692) (xy 287.330263 -290.491096) (xy 287.362898 -290.454259) (xy 287.401019 -290.423134)
			(xy 287.44364 -290.398527) (xy 287.489656 -290.381075) (xy 287.537875 -290.371231) (xy 287.58705 -290.36925)
			(xy 287.635905 -290.375182) (xy 287.683176 -290.388874) (xy 287.727638 -290.409972) (xy 287.768141 -290.437928)
			(xy 287.803634 -290.47202) (xy 287.833199 -290.511364) (xy 287.85607 -290.554941) (xy 287.871654 -290.601622)
			(xy 287.879549 -290.650199) (xy 287.880044 -290.674806) (xy 288.218892 -290.674806) (xy 288.222852 -290.625752)
			(xy 288.234629 -290.577968) (xy 288.25392 -290.532692) (xy 288.280223 -290.491096) (xy 288.312858 -290.454259)
			(xy 288.350979 -290.423134) (xy 288.3936 -290.398527) (xy 288.439616 -290.381075) (xy 288.487835 -290.371231)
			(xy 288.53701 -290.36925) (xy 288.585865 -290.375182) (xy 288.633136 -290.388874) (xy 288.677598 -290.409972)
			(xy 288.718101 -290.437928) (xy 288.753594 -290.47202) (xy 288.783159 -290.511364) (xy 288.80603 -290.554941)
			(xy 288.821614 -290.601622) (xy 288.829509 -290.650199) (xy 288.830004 -290.674806) (xy 289.169106 -290.674806)
			(xy 289.173066 -290.625752) (xy 289.184843 -290.577968) (xy 289.204134 -290.532692) (xy 289.230437 -290.491096)
			(xy 289.263072 -290.454259) (xy 289.301193 -290.423134) (xy 289.343814 -290.398527) (xy 289.38983 -290.381075)
			(xy 289.438049 -290.371231) (xy 289.487224 -290.36925) (xy 289.536079 -290.375182) (xy 289.58335 -290.388874)
			(xy 289.627812 -290.409972) (xy 289.668315 -290.437928) (xy 289.703808 -290.47202) (xy 289.733373 -290.511364)
			(xy 289.756244 -290.554941) (xy 289.771828 -290.601622) (xy 289.779723 -290.650199) (xy 289.780218 -290.674806)
			(xy 290.119066 -290.674806) (xy 290.123026 -290.625752) (xy 290.134803 -290.577968) (xy 290.154094 -290.532692)
			(xy 290.180397 -290.491096) (xy 290.213032 -290.454259) (xy 290.251153 -290.423134) (xy 290.293774 -290.398527)
			(xy 290.33979 -290.381075) (xy 290.388009 -290.371231) (xy 290.437184 -290.36925) (xy 290.486039 -290.375182)
			(xy 290.53331 -290.388874) (xy 290.577772 -290.409972) (xy 290.618275 -290.437928) (xy 290.653768 -290.47202)
			(xy 290.683333 -290.511364) (xy 290.706204 -290.554941) (xy 290.721788 -290.601622) (xy 290.729683 -290.650199)
			(xy 290.730178 -290.674806) (xy 292.018986 -290.674806) (xy 292.022946 -290.625752) (xy 292.034723 -290.577968)
			(xy 292.054014 -290.532692) (xy 292.080317 -290.491096) (xy 292.112952 -290.454259) (xy 292.151073 -290.423134)
			(xy 292.193694 -290.398527) (xy 292.23971 -290.381075) (xy 292.287929 -290.371231) (xy 292.337104 -290.36925)
			(xy 292.385959 -290.375182) (xy 292.43323 -290.388874) (xy 292.477692 -290.409972) (xy 292.518195 -290.437928)
			(xy 292.553688 -290.47202) (xy 292.583253 -290.511364) (xy 292.606124 -290.554941) (xy 292.621708 -290.601622)
			(xy 292.629603 -290.650199) (xy 292.630098 -290.674806) (xy 292.968946 -290.674806) (xy 292.972906 -290.625752)
			(xy 292.984683 -290.577968) (xy 293.003974 -290.532692) (xy 293.030277 -290.491096) (xy 293.062912 -290.454259)
			(xy 293.101033 -290.423134) (xy 293.143654 -290.398527) (xy 293.18967 -290.381075) (xy 293.237889 -290.371231)
			(xy 293.287064 -290.36925) (xy 293.335919 -290.375182) (xy 293.38319 -290.388874) (xy 293.427652 -290.409972)
			(xy 293.468155 -290.437928) (xy 293.503648 -290.47202) (xy 293.533213 -290.511364) (xy 293.556084 -290.554941)
			(xy 293.571668 -290.601622) (xy 293.579563 -290.650199) (xy 293.580058 -290.674806) (xy 293.918906 -290.674806)
			(xy 293.922866 -290.625752) (xy 293.934643 -290.577968) (xy 293.953934 -290.532692) (xy 293.980237 -290.491096)
			(xy 294.012872 -290.454259) (xy 294.050993 -290.423134) (xy 294.093614 -290.398527) (xy 294.13963 -290.381075)
			(xy 294.187849 -290.371231) (xy 294.237024 -290.36925) (xy 294.285879 -290.375182) (xy 294.33315 -290.388874)
			(xy 294.377612 -290.409972) (xy 294.418115 -290.437928) (xy 294.453608 -290.47202) (xy 294.483173 -290.511364)
			(xy 294.506044 -290.554941) (xy 294.521628 -290.601622) (xy 294.529523 -290.650199) (xy 294.530018 -290.674806)
			(xy 294.86912 -290.674806) (xy 294.87308 -290.625752) (xy 294.884857 -290.577968) (xy 294.904148 -290.532692)
			(xy 294.930451 -290.491096) (xy 294.963086 -290.454259) (xy 295.001207 -290.423134) (xy 295.043828 -290.398527)
			(xy 295.089844 -290.381075) (xy 295.138063 -290.371231) (xy 295.187238 -290.36925) (xy 295.236093 -290.375182)
			(xy 295.283364 -290.388874) (xy 295.327826 -290.409972) (xy 295.368329 -290.437928) (xy 295.403822 -290.47202)
			(xy 295.433387 -290.511364) (xy 295.456258 -290.554941) (xy 295.471842 -290.601622) (xy 295.479737 -290.650199)
			(xy 295.480232 -290.674806) (xy 295.81908 -290.674806) (xy 295.82304 -290.625752) (xy 295.834817 -290.577968)
			(xy 295.854108 -290.532692) (xy 295.880411 -290.491096) (xy 295.913046 -290.454259) (xy 295.951167 -290.423134)
			(xy 295.993788 -290.398527) (xy 296.039804 -290.381075) (xy 296.088023 -290.371231) (xy 296.137198 -290.36925)
			(xy 296.186053 -290.375182) (xy 296.233324 -290.388874) (xy 296.277786 -290.409972) (xy 296.318289 -290.437928)
			(xy 296.353782 -290.47202) (xy 296.383347 -290.511364) (xy 296.406218 -290.554941) (xy 296.421802 -290.601622)
			(xy 296.429697 -290.650199) (xy 296.430192 -290.674806) (xy 296.76904 -290.674806) (xy 296.773 -290.625752)
			(xy 296.784777 -290.577968) (xy 296.804068 -290.532692) (xy 296.830371 -290.491096) (xy 296.863006 -290.454259)
			(xy 296.901127 -290.423134) (xy 296.943748 -290.398527) (xy 296.989764 -290.381075) (xy 297.037983 -290.371231)
			(xy 297.087158 -290.36925) (xy 297.136013 -290.375182) (xy 297.183284 -290.388874) (xy 297.227746 -290.409972)
			(xy 297.268249 -290.437928) (xy 297.303742 -290.47202) (xy 297.333307 -290.511364) (xy 297.356178 -290.554941)
			(xy 297.371762 -290.601622) (xy 297.379657 -290.650199) (xy 297.380152 -290.674806) (xy 297.719 -290.674806)
			(xy 297.72296 -290.625752) (xy 297.734737 -290.577968) (xy 297.754028 -290.532692) (xy 297.780331 -290.491096)
			(xy 297.812966 -290.454259) (xy 297.851087 -290.423134) (xy 297.893708 -290.398527) (xy 297.939724 -290.381075)
			(xy 297.987943 -290.371231) (xy 298.037118 -290.36925) (xy 298.085973 -290.375182) (xy 298.133244 -290.388874)
			(xy 298.177706 -290.409972) (xy 298.218209 -290.437928) (xy 298.253702 -290.47202) (xy 298.283267 -290.511364)
			(xy 298.306138 -290.554941) (xy 298.321722 -290.601622) (xy 298.329617 -290.650199) (xy 298.330112 -290.674806)
			(xy 298.66896 -290.674806) (xy 298.67292 -290.625752) (xy 298.684697 -290.577968) (xy 298.703988 -290.532692)
			(xy 298.730291 -290.491096) (xy 298.762926 -290.454259) (xy 298.801047 -290.423134) (xy 298.843668 -290.398527)
			(xy 298.889684 -290.381075) (xy 298.937903 -290.371231) (xy 298.987078 -290.36925) (xy 299.035933 -290.375182)
			(xy 299.083204 -290.388874) (xy 299.127666 -290.409972) (xy 299.168169 -290.437928) (xy 299.203662 -290.47202)
			(xy 299.233227 -290.511364) (xy 299.256098 -290.554941) (xy 299.271682 -290.601622) (xy 299.279577 -290.650199)
			(xy 299.280072 -290.674806) (xy 299.61892 -290.674806) (xy 299.62288 -290.625752) (xy 299.634657 -290.577968)
			(xy 299.653948 -290.532692) (xy 299.680251 -290.491096) (xy 299.712886 -290.454259) (xy 299.751007 -290.423134)
			(xy 299.793628 -290.398527) (xy 299.839644 -290.381075) (xy 299.887863 -290.371231) (xy 299.937038 -290.36925)
			(xy 299.985893 -290.375182) (xy 300.033164 -290.388874) (xy 300.077626 -290.409972) (xy 300.118129 -290.437928)
			(xy 300.153622 -290.47202) (xy 300.183187 -290.511364) (xy 300.206058 -290.554941) (xy 300.221642 -290.601622)
			(xy 300.229537 -290.650199) (xy 300.230032 -290.674806) (xy 300.56888 -290.674806) (xy 300.57284 -290.625752)
			(xy 300.584617 -290.577968) (xy 300.603908 -290.532692) (xy 300.630211 -290.491096) (xy 300.662846 -290.454259)
			(xy 300.700967 -290.423134) (xy 300.743588 -290.398527) (xy 300.789604 -290.381075) (xy 300.837823 -290.371231)
			(xy 300.886998 -290.36925) (xy 300.935853 -290.375182) (xy 300.983124 -290.388874) (xy 301.027586 -290.409972)
			(xy 301.068089 -290.437928) (xy 301.103582 -290.47202) (xy 301.133147 -290.511364) (xy 301.156018 -290.554941)
			(xy 301.171602 -290.601622) (xy 301.179497 -290.650199) (xy 301.179992 -290.674806) (xy 301.519094 -290.674806)
			(xy 301.523054 -290.625752) (xy 301.534831 -290.577968) (xy 301.554122 -290.532692) (xy 301.580425 -290.491096)
			(xy 301.61306 -290.454259) (xy 301.651181 -290.423134) (xy 301.693802 -290.398527) (xy 301.739818 -290.381075)
			(xy 301.788037 -290.371231) (xy 301.837212 -290.36925) (xy 301.886067 -290.375182) (xy 301.933338 -290.388874)
			(xy 301.9778 -290.409972) (xy 302.018303 -290.437928) (xy 302.053796 -290.47202) (xy 302.083361 -290.511364)
			(xy 302.106232 -290.554941) (xy 302.121816 -290.601622) (xy 302.129711 -290.650199) (xy 302.130206 -290.674806)
			(xy 302.469054 -290.674806) (xy 302.473014 -290.625752) (xy 302.484791 -290.577968) (xy 302.504082 -290.532692)
			(xy 302.530385 -290.491096) (xy 302.56302 -290.454259) (xy 302.601141 -290.423134) (xy 302.643762 -290.398527)
			(xy 302.689778 -290.381075) (xy 302.737997 -290.371231) (xy 302.787172 -290.36925) (xy 302.836027 -290.375182)
			(xy 302.883298 -290.388874) (xy 302.92776 -290.409972) (xy 302.968263 -290.437928) (xy 303.003756 -290.47202)
			(xy 303.033321 -290.511364) (xy 303.056192 -290.554941) (xy 303.071776 -290.601622) (xy 303.079671 -290.650199)
			(xy 303.080166 -290.674806) (xy 303.419014 -290.674806) (xy 303.422974 -290.625752) (xy 303.434751 -290.577968)
			(xy 303.454042 -290.532692) (xy 303.480345 -290.491096) (xy 303.51298 -290.454259) (xy 303.551101 -290.423134)
			(xy 303.593722 -290.398527) (xy 303.639738 -290.381075) (xy 303.687957 -290.371231) (xy 303.737132 -290.36925)
			(xy 303.785987 -290.375182) (xy 303.833258 -290.388874) (xy 303.87772 -290.409972) (xy 303.918223 -290.437928)
			(xy 303.953716 -290.47202) (xy 303.983281 -290.511364) (xy 304.006152 -290.554941) (xy 304.021736 -290.601622)
			(xy 304.029631 -290.650199) (xy 304.030126 -290.674806) (xy 304.368974 -290.674806) (xy 304.372934 -290.625752)
			(xy 304.384711 -290.577968) (xy 304.404002 -290.532692) (xy 304.430305 -290.491096) (xy 304.46294 -290.454259)
			(xy 304.501061 -290.423134) (xy 304.543682 -290.398527) (xy 304.589698 -290.381075) (xy 304.637917 -290.371231)
			(xy 304.687092 -290.36925) (xy 304.735947 -290.375182) (xy 304.783218 -290.388874) (xy 304.82768 -290.409972)
			(xy 304.868183 -290.437928) (xy 304.903676 -290.47202) (xy 304.933241 -290.511364) (xy 304.956112 -290.554941)
			(xy 304.971696 -290.601622) (xy 304.979591 -290.650199) (xy 304.980086 -290.674806) (xy 305.318934 -290.674806)
			(xy 305.322894 -290.625752) (xy 305.334671 -290.577968) (xy 305.353962 -290.532692) (xy 305.380265 -290.491096)
			(xy 305.4129 -290.454259) (xy 305.451021 -290.423134) (xy 305.493642 -290.398527) (xy 305.539658 -290.381075)
			(xy 305.587877 -290.371231) (xy 305.637052 -290.36925) (xy 305.685907 -290.375182) (xy 305.733178 -290.388874)
			(xy 305.77764 -290.409972) (xy 305.818143 -290.437928) (xy 305.853636 -290.47202) (xy 305.883201 -290.511364)
			(xy 305.906072 -290.554941) (xy 305.921656 -290.601622) (xy 305.929551 -290.650199) (xy 305.930046 -290.674806)
			(xy 306.268894 -290.674806) (xy 306.272854 -290.625752) (xy 306.284631 -290.577968) (xy 306.303922 -290.532692)
			(xy 306.330225 -290.491096) (xy 306.36286 -290.454259) (xy 306.400981 -290.423134) (xy 306.443602 -290.398527)
			(xy 306.489618 -290.381075) (xy 306.537837 -290.371231) (xy 306.587012 -290.36925) (xy 306.635867 -290.375182)
			(xy 306.683138 -290.388874) (xy 306.7276 -290.409972) (xy 306.768103 -290.437928) (xy 306.803596 -290.47202)
			(xy 306.833161 -290.511364) (xy 306.856032 -290.554941) (xy 306.871616 -290.601622) (xy 306.879511 -290.650199)
			(xy 306.880006 -290.674806) (xy 307.219108 -290.674806) (xy 307.223068 -290.625752) (xy 307.234845 -290.577968)
			(xy 307.254136 -290.532692) (xy 307.280439 -290.491096) (xy 307.313074 -290.454259) (xy 307.351195 -290.423134)
			(xy 307.393816 -290.398527) (xy 307.439832 -290.381075) (xy 307.488051 -290.371231) (xy 307.537226 -290.36925)
			(xy 307.586081 -290.375182) (xy 307.633352 -290.388874) (xy 307.677814 -290.409972) (xy 307.718317 -290.437928)
			(xy 307.75381 -290.47202) (xy 307.783375 -290.511364) (xy 307.806246 -290.554941) (xy 307.82183 -290.601622)
			(xy 307.829725 -290.650199) (xy 307.83022 -290.674806) (xy 308.169068 -290.674806) (xy 308.173028 -290.625752)
			(xy 308.184805 -290.577968) (xy 308.204096 -290.532692) (xy 308.230399 -290.491096) (xy 308.263034 -290.454259)
			(xy 308.301155 -290.423134) (xy 308.343776 -290.398527) (xy 308.389792 -290.381075) (xy 308.438011 -290.371231)
			(xy 308.487186 -290.36925) (xy 308.536041 -290.375182) (xy 308.583312 -290.388874) (xy 308.627774 -290.409972)
			(xy 308.668277 -290.437928) (xy 308.70377 -290.47202) (xy 308.733335 -290.511364) (xy 308.756206 -290.554941)
			(xy 308.77179 -290.601622) (xy 308.779685 -290.650199) (xy 308.78018 -290.674806) (xy 309.119028 -290.674806)
			(xy 309.122988 -290.625752) (xy 309.134765 -290.577968) (xy 309.154056 -290.532692) (xy 309.180359 -290.491096)
			(xy 309.212994 -290.454259) (xy 309.251115 -290.423134) (xy 309.293736 -290.398527) (xy 309.339752 -290.381075)
			(xy 309.387971 -290.371231) (xy 309.437146 -290.36925) (xy 309.486001 -290.375182) (xy 309.533272 -290.388874)
			(xy 309.577734 -290.409972) (xy 309.618237 -290.437928) (xy 309.65373 -290.47202) (xy 309.683295 -290.511364)
			(xy 309.706166 -290.554941) (xy 309.72175 -290.601622) (xy 309.729645 -290.650199) (xy 309.73014 -290.674806)
			(xy 310.068988 -290.674806) (xy 310.072948 -290.625752) (xy 310.084725 -290.577968) (xy 310.104016 -290.532692)
			(xy 310.130319 -290.491096) (xy 310.162954 -290.454259) (xy 310.201075 -290.423134) (xy 310.243696 -290.398527)
			(xy 310.289712 -290.381075) (xy 310.337931 -290.371231) (xy 310.387106 -290.36925) (xy 310.435961 -290.375182)
			(xy 310.483232 -290.388874) (xy 310.527694 -290.409972) (xy 310.568197 -290.437928) (xy 310.60369 -290.47202)
			(xy 310.633255 -290.511364) (xy 310.656126 -290.554941) (xy 310.67171 -290.601622) (xy 310.679605 -290.650199)
			(xy 310.6801 -290.674806) (xy 311.018948 -290.674806) (xy 311.022908 -290.625752) (xy 311.034685 -290.577968)
			(xy 311.053976 -290.532692) (xy 311.080279 -290.491096) (xy 311.112914 -290.454259) (xy 311.151035 -290.423134)
			(xy 311.193656 -290.398527) (xy 311.239672 -290.381075) (xy 311.287891 -290.371231) (xy 311.337066 -290.36925)
			(xy 311.385921 -290.375182) (xy 311.433192 -290.388874) (xy 311.477654 -290.409972) (xy 311.518157 -290.437928)
			(xy 311.55365 -290.47202) (xy 311.583215 -290.511364) (xy 311.606086 -290.554941) (xy 311.62167 -290.601622)
			(xy 311.629565 -290.650199) (xy 311.63006 -290.674806) (xy 311.968908 -290.674806) (xy 311.972868 -290.625752)
			(xy 311.984645 -290.577968) (xy 312.003936 -290.532692) (xy 312.030239 -290.491096) (xy 312.062874 -290.454259)
			(xy 312.100995 -290.423134) (xy 312.143616 -290.398527) (xy 312.189632 -290.381075) (xy 312.237851 -290.371231)
			(xy 312.287026 -290.36925) (xy 312.335881 -290.375182) (xy 312.383152 -290.388874) (xy 312.427614 -290.409972)
			(xy 312.468117 -290.437928) (xy 312.50361 -290.47202) (xy 312.533175 -290.511364) (xy 312.556046 -290.554941)
			(xy 312.57163 -290.601622) (xy 312.579525 -290.650199) (xy 312.58002 -290.674806) (xy 312.919122 -290.674806)
			(xy 312.923082 -290.625752) (xy 312.934859 -290.577968) (xy 312.95415 -290.532692) (xy 312.980453 -290.491096)
			(xy 313.013088 -290.454259) (xy 313.051209 -290.423134) (xy 313.09383 -290.398527) (xy 313.139846 -290.381075)
			(xy 313.188065 -290.371231) (xy 313.23724 -290.36925) (xy 313.286095 -290.375182) (xy 313.333366 -290.388874)
			(xy 313.377828 -290.409972) (xy 313.418331 -290.437928) (xy 313.453824 -290.47202) (xy 313.483389 -290.511364)
			(xy 313.50626 -290.554941) (xy 313.521844 -290.601622) (xy 313.529739 -290.650199) (xy 313.530234 -290.674806)
			(xy 313.869082 -290.674806) (xy 313.873042 -290.625752) (xy 313.884819 -290.577968) (xy 313.90411 -290.532692)
			(xy 313.930413 -290.491096) (xy 313.963048 -290.454259) (xy 314.001169 -290.423134) (xy 314.04379 -290.398527)
			(xy 314.089806 -290.381075) (xy 314.138025 -290.371231) (xy 314.1872 -290.36925) (xy 314.236055 -290.375182)
			(xy 314.283326 -290.388874) (xy 314.327788 -290.409972) (xy 314.368291 -290.437928) (xy 314.403784 -290.47202)
			(xy 314.433349 -290.511364) (xy 314.45622 -290.554941) (xy 314.471804 -290.601622) (xy 314.479699 -290.650199)
			(xy 314.480194 -290.674806) (xy 314.819042 -290.674806) (xy 314.823002 -290.625752) (xy 314.834779 -290.577968)
			(xy 314.85407 -290.532692) (xy 314.880373 -290.491096) (xy 314.913008 -290.454259) (xy 314.951129 -290.423134)
			(xy 314.99375 -290.398527) (xy 315.039766 -290.381075) (xy 315.087985 -290.371231) (xy 315.13716 -290.36925)
			(xy 315.186015 -290.375182) (xy 315.233286 -290.388874) (xy 315.277748 -290.409972) (xy 315.318251 -290.437928)
			(xy 315.353744 -290.47202) (xy 315.383309 -290.511364) (xy 315.40618 -290.554941) (xy 315.421764 -290.601622)
			(xy 315.429659 -290.650199) (xy 315.430154 -290.674806) (xy 315.429659 -290.699413) (xy 315.421764 -290.74799)
			(xy 315.40618 -290.794671) (xy 315.383309 -290.838248) (xy 315.353744 -290.877592) (xy 315.318251 -290.911684)
			(xy 315.277748 -290.93964) (xy 315.233286 -290.960738) (xy 315.186015 -290.97443) (xy 315.13716 -290.980362)
			(xy 315.087985 -290.978381) (xy 315.039766 -290.968537) (xy 314.99375 -290.951085) (xy 314.951129 -290.926478)
			(xy 314.913008 -290.895353) (xy 314.880373 -290.858516) (xy 314.85407 -290.81692) (xy 314.834779 -290.771644)
			(xy 314.823002 -290.72386) (xy 314.819042 -290.674806) (xy 314.480194 -290.674806) (xy 314.479699 -290.699413)
			(xy 314.471804 -290.74799) (xy 314.45622 -290.794671) (xy 314.433349 -290.838248) (xy 314.403784 -290.877592)
			(xy 314.368291 -290.911684) (xy 314.327788 -290.93964) (xy 314.283326 -290.960738) (xy 314.236055 -290.97443)
			(xy 314.1872 -290.980362) (xy 314.138025 -290.978381) (xy 314.089806 -290.968537) (xy 314.04379 -290.951085)
			(xy 314.001169 -290.926478) (xy 313.963048 -290.895353) (xy 313.930413 -290.858516) (xy 313.90411 -290.81692)
			(xy 313.884819 -290.771644) (xy 313.873042 -290.72386) (xy 313.869082 -290.674806) (xy 313.530234 -290.674806)
			(xy 313.529739 -290.699413) (xy 313.521844 -290.74799) (xy 313.50626 -290.794671) (xy 313.483389 -290.838248)
			(xy 313.453824 -290.877592) (xy 313.418331 -290.911684) (xy 313.377828 -290.93964) (xy 313.333366 -290.960738)
			(xy 313.286095 -290.97443) (xy 313.23724 -290.980362) (xy 313.188065 -290.978381) (xy 313.139846 -290.968537)
			(xy 313.09383 -290.951085) (xy 313.051209 -290.926478) (xy 313.013088 -290.895353) (xy 312.980453 -290.858516)
			(xy 312.95415 -290.81692) (xy 312.934859 -290.771644) (xy 312.923082 -290.72386) (xy 312.919122 -290.674806)
			(xy 312.58002 -290.674806) (xy 312.579525 -290.699413) (xy 312.57163 -290.74799) (xy 312.556046 -290.794671)
			(xy 312.533175 -290.838248) (xy 312.50361 -290.877592) (xy 312.468117 -290.911684) (xy 312.427614 -290.93964)
			(xy 312.383152 -290.960738) (xy 312.335881 -290.97443) (xy 312.287026 -290.980362) (xy 312.237851 -290.978381)
			(xy 312.189632 -290.968537) (xy 312.143616 -290.951085) (xy 312.100995 -290.926478) (xy 312.062874 -290.895353)
			(xy 312.030239 -290.858516) (xy 312.003936 -290.81692) (xy 311.984645 -290.771644) (xy 311.972868 -290.72386)
			(xy 311.968908 -290.674806) (xy 311.63006 -290.674806) (xy 311.629565 -290.699413) (xy 311.62167 -290.74799)
			(xy 311.606086 -290.794671) (xy 311.583215 -290.838248) (xy 311.55365 -290.877592) (xy 311.518157 -290.911684)
			(xy 311.477654 -290.93964) (xy 311.433192 -290.960738) (xy 311.385921 -290.97443) (xy 311.337066 -290.980362)
			(xy 311.287891 -290.978381) (xy 311.239672 -290.968537) (xy 311.193656 -290.951085) (xy 311.151035 -290.926478)
			(xy 311.112914 -290.895353) (xy 311.080279 -290.858516) (xy 311.053976 -290.81692) (xy 311.034685 -290.771644)
			(xy 311.022908 -290.72386) (xy 311.018948 -290.674806) (xy 310.6801 -290.674806) (xy 310.679605 -290.699413)
			(xy 310.67171 -290.74799) (xy 310.656126 -290.794671) (xy 310.633255 -290.838248) (xy 310.60369 -290.877592)
			(xy 310.568197 -290.911684) (xy 310.527694 -290.93964) (xy 310.483232 -290.960738) (xy 310.435961 -290.97443)
			(xy 310.387106 -290.980362) (xy 310.337931 -290.978381) (xy 310.289712 -290.968537) (xy 310.243696 -290.951085)
			(xy 310.201075 -290.926478) (xy 310.162954 -290.895353) (xy 310.130319 -290.858516) (xy 310.104016 -290.81692)
			(xy 310.084725 -290.771644) (xy 310.072948 -290.72386) (xy 310.068988 -290.674806) (xy 309.73014 -290.674806)
			(xy 309.729645 -290.699413) (xy 309.72175 -290.74799) (xy 309.706166 -290.794671) (xy 309.683295 -290.838248)
			(xy 309.65373 -290.877592) (xy 309.618237 -290.911684) (xy 309.577734 -290.93964) (xy 309.533272 -290.960738)
			(xy 309.486001 -290.97443) (xy 309.437146 -290.980362) (xy 309.387971 -290.978381) (xy 309.339752 -290.968537)
			(xy 309.293736 -290.951085) (xy 309.251115 -290.926478) (xy 309.212994 -290.895353) (xy 309.180359 -290.858516)
			(xy 309.154056 -290.81692) (xy 309.134765 -290.771644) (xy 309.122988 -290.72386) (xy 309.119028 -290.674806)
			(xy 308.78018 -290.674806) (xy 308.779685 -290.699413) (xy 308.77179 -290.74799) (xy 308.756206 -290.794671)
			(xy 308.733335 -290.838248) (xy 308.70377 -290.877592) (xy 308.668277 -290.911684) (xy 308.627774 -290.93964)
			(xy 308.583312 -290.960738) (xy 308.536041 -290.97443) (xy 308.487186 -290.980362) (xy 308.438011 -290.978381)
			(xy 308.389792 -290.968537) (xy 308.343776 -290.951085) (xy 308.301155 -290.926478) (xy 308.263034 -290.895353)
			(xy 308.230399 -290.858516) (xy 308.204096 -290.81692) (xy 308.184805 -290.771644) (xy 308.173028 -290.72386)
			(xy 308.169068 -290.674806) (xy 307.83022 -290.674806) (xy 307.829725 -290.699413) (xy 307.82183 -290.74799)
			(xy 307.806246 -290.794671) (xy 307.783375 -290.838248) (xy 307.75381 -290.877592) (xy 307.718317 -290.911684)
			(xy 307.677814 -290.93964) (xy 307.633352 -290.960738) (xy 307.586081 -290.97443) (xy 307.537226 -290.980362)
			(xy 307.488051 -290.978381) (xy 307.439832 -290.968537) (xy 307.393816 -290.951085) (xy 307.351195 -290.926478)
			(xy 307.313074 -290.895353) (xy 307.280439 -290.858516) (xy 307.254136 -290.81692) (xy 307.234845 -290.771644)
			(xy 307.223068 -290.72386) (xy 307.219108 -290.674806) (xy 306.880006 -290.674806) (xy 306.879511 -290.699413)
			(xy 306.871616 -290.74799) (xy 306.856032 -290.794671) (xy 306.833161 -290.838248) (xy 306.803596 -290.877592)
			(xy 306.768103 -290.911684) (xy 306.7276 -290.93964) (xy 306.683138 -290.960738) (xy 306.635867 -290.97443)
			(xy 306.587012 -290.980362) (xy 306.537837 -290.978381) (xy 306.489618 -290.968537) (xy 306.443602 -290.951085)
			(xy 306.400981 -290.926478) (xy 306.36286 -290.895353) (xy 306.330225 -290.858516) (xy 306.303922 -290.81692)
			(xy 306.284631 -290.771644) (xy 306.272854 -290.72386) (xy 306.268894 -290.674806) (xy 305.930046 -290.674806)
			(xy 305.929551 -290.699413) (xy 305.921656 -290.74799) (xy 305.906072 -290.794671) (xy 305.883201 -290.838248)
			(xy 305.853636 -290.877592) (xy 305.818143 -290.911684) (xy 305.77764 -290.93964) (xy 305.733178 -290.960738)
			(xy 305.685907 -290.97443) (xy 305.637052 -290.980362) (xy 305.587877 -290.978381) (xy 305.539658 -290.968537)
			(xy 305.493642 -290.951085) (xy 305.451021 -290.926478) (xy 305.4129 -290.895353) (xy 305.380265 -290.858516)
			(xy 305.353962 -290.81692) (xy 305.334671 -290.771644) (xy 305.322894 -290.72386) (xy 305.318934 -290.674806)
			(xy 304.980086 -290.674806) (xy 304.979591 -290.699413) (xy 304.971696 -290.74799) (xy 304.956112 -290.794671)
			(xy 304.933241 -290.838248) (xy 304.903676 -290.877592) (xy 304.868183 -290.911684) (xy 304.82768 -290.93964)
			(xy 304.783218 -290.960738) (xy 304.735947 -290.97443) (xy 304.687092 -290.980362) (xy 304.637917 -290.978381)
			(xy 304.589698 -290.968537) (xy 304.543682 -290.951085) (xy 304.501061 -290.926478) (xy 304.46294 -290.895353)
			(xy 304.430305 -290.858516) (xy 304.404002 -290.81692) (xy 304.384711 -290.771644) (xy 304.372934 -290.72386)
			(xy 304.368974 -290.674806) (xy 304.030126 -290.674806) (xy 304.029631 -290.699413) (xy 304.021736 -290.74799)
			(xy 304.006152 -290.794671) (xy 303.983281 -290.838248) (xy 303.953716 -290.877592) (xy 303.918223 -290.911684)
			(xy 303.87772 -290.93964) (xy 303.833258 -290.960738) (xy 303.785987 -290.97443) (xy 303.737132 -290.980362)
			(xy 303.687957 -290.978381) (xy 303.639738 -290.968537) (xy 303.593722 -290.951085) (xy 303.551101 -290.926478)
			(xy 303.51298 -290.895353) (xy 303.480345 -290.858516) (xy 303.454042 -290.81692) (xy 303.434751 -290.771644)
			(xy 303.422974 -290.72386) (xy 303.419014 -290.674806) (xy 303.080166 -290.674806) (xy 303.079671 -290.699413)
			(xy 303.071776 -290.74799) (xy 303.056192 -290.794671) (xy 303.033321 -290.838248) (xy 303.003756 -290.877592)
			(xy 302.968263 -290.911684) (xy 302.92776 -290.93964) (xy 302.883298 -290.960738) (xy 302.836027 -290.97443)
			(xy 302.787172 -290.980362) (xy 302.737997 -290.978381) (xy 302.689778 -290.968537) (xy 302.643762 -290.951085)
			(xy 302.601141 -290.926478) (xy 302.56302 -290.895353) (xy 302.530385 -290.858516) (xy 302.504082 -290.81692)
			(xy 302.484791 -290.771644) (xy 302.473014 -290.72386) (xy 302.469054 -290.674806) (xy 302.130206 -290.674806)
			(xy 302.129711 -290.699413) (xy 302.121816 -290.74799) (xy 302.106232 -290.794671) (xy 302.083361 -290.838248)
			(xy 302.053796 -290.877592) (xy 302.018303 -290.911684) (xy 301.9778 -290.93964) (xy 301.933338 -290.960738)
			(xy 301.886067 -290.97443) (xy 301.837212 -290.980362) (xy 301.788037 -290.978381) (xy 301.739818 -290.968537)
			(xy 301.693802 -290.951085) (xy 301.651181 -290.926478) (xy 301.61306 -290.895353) (xy 301.580425 -290.858516)
			(xy 301.554122 -290.81692) (xy 301.534831 -290.771644) (xy 301.523054 -290.72386) (xy 301.519094 -290.674806)
			(xy 301.179992 -290.674806) (xy 301.179497 -290.699413) (xy 301.171602 -290.74799) (xy 301.156018 -290.794671)
			(xy 301.133147 -290.838248) (xy 301.103582 -290.877592) (xy 301.068089 -290.911684) (xy 301.027586 -290.93964)
			(xy 300.983124 -290.960738) (xy 300.935853 -290.97443) (xy 300.886998 -290.980362) (xy 300.837823 -290.978381)
			(xy 300.789604 -290.968537) (xy 300.743588 -290.951085) (xy 300.700967 -290.926478) (xy 300.662846 -290.895353)
			(xy 300.630211 -290.858516) (xy 300.603908 -290.81692) (xy 300.584617 -290.771644) (xy 300.57284 -290.72386)
			(xy 300.56888 -290.674806) (xy 300.230032 -290.674806) (xy 300.229537 -290.699413) (xy 300.221642 -290.74799)
			(xy 300.206058 -290.794671) (xy 300.183187 -290.838248) (xy 300.153622 -290.877592) (xy 300.118129 -290.911684)
			(xy 300.077626 -290.93964) (xy 300.033164 -290.960738) (xy 299.985893 -290.97443) (xy 299.937038 -290.980362)
			(xy 299.887863 -290.978381) (xy 299.839644 -290.968537) (xy 299.793628 -290.951085) (xy 299.751007 -290.926478)
			(xy 299.712886 -290.895353) (xy 299.680251 -290.858516) (xy 299.653948 -290.81692) (xy 299.634657 -290.771644)
			(xy 299.62288 -290.72386) (xy 299.61892 -290.674806) (xy 299.280072 -290.674806) (xy 299.279577 -290.699413)
			(xy 299.271682 -290.74799) (xy 299.256098 -290.794671) (xy 299.233227 -290.838248) (xy 299.203662 -290.877592)
			(xy 299.168169 -290.911684) (xy 299.127666 -290.93964) (xy 299.083204 -290.960738) (xy 299.035933 -290.97443)
			(xy 298.987078 -290.980362) (xy 298.937903 -290.978381) (xy 298.889684 -290.968537) (xy 298.843668 -290.951085)
			(xy 298.801047 -290.926478) (xy 298.762926 -290.895353) (xy 298.730291 -290.858516) (xy 298.703988 -290.81692)
			(xy 298.684697 -290.771644) (xy 298.67292 -290.72386) (xy 298.66896 -290.674806) (xy 298.330112 -290.674806)
			(xy 298.329617 -290.699413) (xy 298.321722 -290.74799) (xy 298.306138 -290.794671) (xy 298.283267 -290.838248)
			(xy 298.253702 -290.877592) (xy 298.218209 -290.911684) (xy 298.177706 -290.93964) (xy 298.133244 -290.960738)
			(xy 298.085973 -290.97443) (xy 298.037118 -290.980362) (xy 297.987943 -290.978381) (xy 297.939724 -290.968537)
			(xy 297.893708 -290.951085) (xy 297.851087 -290.926478) (xy 297.812966 -290.895353) (xy 297.780331 -290.858516)
			(xy 297.754028 -290.81692) (xy 297.734737 -290.771644) (xy 297.72296 -290.72386) (xy 297.719 -290.674806)
			(xy 297.380152 -290.674806) (xy 297.379657 -290.699413) (xy 297.371762 -290.74799) (xy 297.356178 -290.794671)
			(xy 297.333307 -290.838248) (xy 297.303742 -290.877592) (xy 297.268249 -290.911684) (xy 297.227746 -290.93964)
			(xy 297.183284 -290.960738) (xy 297.136013 -290.97443) (xy 297.087158 -290.980362) (xy 297.037983 -290.978381)
			(xy 296.989764 -290.968537) (xy 296.943748 -290.951085) (xy 296.901127 -290.926478) (xy 296.863006 -290.895353)
			(xy 296.830371 -290.858516) (xy 296.804068 -290.81692) (xy 296.784777 -290.771644) (xy 296.773 -290.72386)
			(xy 296.76904 -290.674806) (xy 296.430192 -290.674806) (xy 296.429697 -290.699413) (xy 296.421802 -290.74799)
			(xy 296.406218 -290.794671) (xy 296.383347 -290.838248) (xy 296.353782 -290.877592) (xy 296.318289 -290.911684)
			(xy 296.277786 -290.93964) (xy 296.233324 -290.960738) (xy 296.186053 -290.97443) (xy 296.137198 -290.980362)
			(xy 296.088023 -290.978381) (xy 296.039804 -290.968537) (xy 295.993788 -290.951085) (xy 295.951167 -290.926478)
			(xy 295.913046 -290.895353) (xy 295.880411 -290.858516) (xy 295.854108 -290.81692) (xy 295.834817 -290.771644)
			(xy 295.82304 -290.72386) (xy 295.81908 -290.674806) (xy 295.480232 -290.674806) (xy 295.479737 -290.699413)
			(xy 295.471842 -290.74799) (xy 295.456258 -290.794671) (xy 295.433387 -290.838248) (xy 295.403822 -290.877592)
			(xy 295.368329 -290.911684) (xy 295.327826 -290.93964) (xy 295.283364 -290.960738) (xy 295.236093 -290.97443)
			(xy 295.187238 -290.980362) (xy 295.138063 -290.978381) (xy 295.089844 -290.968537) (xy 295.043828 -290.951085)
			(xy 295.001207 -290.926478) (xy 294.963086 -290.895353) (xy 294.930451 -290.858516) (xy 294.904148 -290.81692)
			(xy 294.884857 -290.771644) (xy 294.87308 -290.72386) (xy 294.86912 -290.674806) (xy 294.530018 -290.674806)
			(xy 294.529523 -290.699413) (xy 294.521628 -290.74799) (xy 294.506044 -290.794671) (xy 294.483173 -290.838248)
			(xy 294.453608 -290.877592) (xy 294.418115 -290.911684) (xy 294.377612 -290.93964) (xy 294.33315 -290.960738)
			(xy 294.285879 -290.97443) (xy 294.237024 -290.980362) (xy 294.187849 -290.978381) (xy 294.13963 -290.968537)
			(xy 294.093614 -290.951085) (xy 294.050993 -290.926478) (xy 294.012872 -290.895353) (xy 293.980237 -290.858516)
			(xy 293.953934 -290.81692) (xy 293.934643 -290.771644) (xy 293.922866 -290.72386) (xy 293.918906 -290.674806)
			(xy 293.580058 -290.674806) (xy 293.579563 -290.699413) (xy 293.571668 -290.74799) (xy 293.556084 -290.794671)
			(xy 293.533213 -290.838248) (xy 293.503648 -290.877592) (xy 293.468155 -290.911684) (xy 293.427652 -290.93964)
			(xy 293.38319 -290.960738) (xy 293.335919 -290.97443) (xy 293.287064 -290.980362) (xy 293.237889 -290.978381)
			(xy 293.18967 -290.968537) (xy 293.143654 -290.951085) (xy 293.101033 -290.926478) (xy 293.062912 -290.895353)
			(xy 293.030277 -290.858516) (xy 293.003974 -290.81692) (xy 292.984683 -290.771644) (xy 292.972906 -290.72386)
			(xy 292.968946 -290.674806) (xy 292.630098 -290.674806) (xy 292.629603 -290.699413) (xy 292.621708 -290.74799)
			(xy 292.606124 -290.794671) (xy 292.583253 -290.838248) (xy 292.553688 -290.877592) (xy 292.518195 -290.911684)
			(xy 292.477692 -290.93964) (xy 292.43323 -290.960738) (xy 292.385959 -290.97443) (xy 292.337104 -290.980362)
			(xy 292.287929 -290.978381) (xy 292.23971 -290.968537) (xy 292.193694 -290.951085) (xy 292.151073 -290.926478)
			(xy 292.112952 -290.895353) (xy 292.080317 -290.858516) (xy 292.054014 -290.81692) (xy 292.034723 -290.771644)
			(xy 292.022946 -290.72386) (xy 292.018986 -290.674806) (xy 290.730178 -290.674806) (xy 290.729683 -290.699413)
			(xy 290.721788 -290.74799) (xy 290.706204 -290.794671) (xy 290.683333 -290.838248) (xy 290.653768 -290.877592)
			(xy 290.618275 -290.911684) (xy 290.577772 -290.93964) (xy 290.53331 -290.960738) (xy 290.486039 -290.97443)
			(xy 290.437184 -290.980362) (xy 290.388009 -290.978381) (xy 290.33979 -290.968537) (xy 290.293774 -290.951085)
			(xy 290.251153 -290.926478) (xy 290.213032 -290.895353) (xy 290.180397 -290.858516) (xy 290.154094 -290.81692)
			(xy 290.134803 -290.771644) (xy 290.123026 -290.72386) (xy 290.119066 -290.674806) (xy 289.780218 -290.674806)
			(xy 289.779723 -290.699413) (xy 289.771828 -290.74799) (xy 289.756244 -290.794671) (xy 289.733373 -290.838248)
			(xy 289.703808 -290.877592) (xy 289.668315 -290.911684) (xy 289.627812 -290.93964) (xy 289.58335 -290.960738)
			(xy 289.536079 -290.97443) (xy 289.487224 -290.980362) (xy 289.438049 -290.978381) (xy 289.38983 -290.968537)
			(xy 289.343814 -290.951085) (xy 289.301193 -290.926478) (xy 289.263072 -290.895353) (xy 289.230437 -290.858516)
			(xy 289.204134 -290.81692) (xy 289.184843 -290.771644) (xy 289.173066 -290.72386) (xy 289.169106 -290.674806)
			(xy 288.830004 -290.674806) (xy 288.829509 -290.699413) (xy 288.821614 -290.74799) (xy 288.80603 -290.794671)
			(xy 288.783159 -290.838248) (xy 288.753594 -290.877592) (xy 288.718101 -290.911684) (xy 288.677598 -290.93964)
			(xy 288.633136 -290.960738) (xy 288.585865 -290.97443) (xy 288.53701 -290.980362) (xy 288.487835 -290.978381)
			(xy 288.439616 -290.968537) (xy 288.3936 -290.951085) (xy 288.350979 -290.926478) (xy 288.312858 -290.895353)
			(xy 288.280223 -290.858516) (xy 288.25392 -290.81692) (xy 288.234629 -290.771644) (xy 288.222852 -290.72386)
			(xy 288.218892 -290.674806) (xy 287.880044 -290.674806) (xy 287.879549 -290.699413) (xy 287.871654 -290.74799)
			(xy 287.85607 -290.794671) (xy 287.833199 -290.838248) (xy 287.803634 -290.877592) (xy 287.768141 -290.911684)
			(xy 287.727638 -290.93964) (xy 287.683176 -290.960738) (xy 287.635905 -290.97443) (xy 287.58705 -290.980362)
			(xy 287.537875 -290.978381) (xy 287.489656 -290.968537) (xy 287.44364 -290.951085) (xy 287.401019 -290.926478)
			(xy 287.362898 -290.895353) (xy 287.330263 -290.858516) (xy 287.30396 -290.81692) (xy 287.284669 -290.771644)
			(xy 287.272892 -290.72386) (xy 287.268932 -290.674806) (xy 286.930084 -290.674806) (xy 286.929589 -290.699413)
			(xy 286.921694 -290.74799) (xy 286.90611 -290.794671) (xy 286.883239 -290.838248) (xy 286.853674 -290.877592)
			(xy 286.818181 -290.911684) (xy 286.777678 -290.93964) (xy 286.733216 -290.960738) (xy 286.685945 -290.97443)
			(xy 286.63709 -290.980362) (xy 286.587915 -290.978381) (xy 286.539696 -290.968537) (xy 286.49368 -290.951085)
			(xy 286.451059 -290.926478) (xy 286.412938 -290.895353) (xy 286.380303 -290.858516) (xy 286.354 -290.81692)
			(xy 286.334709 -290.771644) (xy 286.322932 -290.72386) (xy 286.318972 -290.674806) (xy 285.980124 -290.674806)
			(xy 285.979629 -290.699413) (xy 285.971734 -290.74799) (xy 285.95615 -290.794671) (xy 285.933279 -290.838248)
			(xy 285.903714 -290.877592) (xy 285.868221 -290.911684) (xy 285.827718 -290.93964) (xy 285.783256 -290.960738)
			(xy 285.735985 -290.97443) (xy 285.68713 -290.980362) (xy 285.637955 -290.978381) (xy 285.589736 -290.968537)
			(xy 285.54372 -290.951085) (xy 285.501099 -290.926478) (xy 285.462978 -290.895353) (xy 285.430343 -290.858516)
			(xy 285.40404 -290.81692) (xy 285.384749 -290.771644) (xy 285.372972 -290.72386) (xy 285.369012 -290.674806)
			(xy 285.030164 -290.674806) (xy 285.029669 -290.699413) (xy 285.021774 -290.74799) (xy 285.00619 -290.794671)
			(xy 284.983319 -290.838248) (xy 284.953754 -290.877592) (xy 284.918261 -290.911684) (xy 284.877758 -290.93964)
			(xy 284.833296 -290.960738) (xy 284.786025 -290.97443) (xy 284.73717 -290.980362) (xy 284.687995 -290.978381)
			(xy 284.639776 -290.968537) (xy 284.59376 -290.951085) (xy 284.551139 -290.926478) (xy 284.513018 -290.895353)
			(xy 284.480383 -290.858516) (xy 284.45408 -290.81692) (xy 284.434789 -290.771644) (xy 284.423012 -290.72386)
			(xy 284.419052 -290.674806) (xy 284.080204 -290.674806) (xy 284.079709 -290.699413) (xy 284.071814 -290.74799)
			(xy 284.05623 -290.794671) (xy 284.033359 -290.838248) (xy 284.003794 -290.877592) (xy 283.968301 -290.911684)
			(xy 283.927798 -290.93964) (xy 283.883336 -290.960738) (xy 283.836065 -290.97443) (xy 283.78721 -290.980362)
			(xy 283.738035 -290.978381) (xy 283.689816 -290.968537) (xy 283.6438 -290.951085) (xy 283.601179 -290.926478)
			(xy 283.563058 -290.895353) (xy 283.530423 -290.858516) (xy 283.50412 -290.81692) (xy 283.484829 -290.771644)
			(xy 283.473052 -290.72386) (xy 283.469092 -290.674806) (xy 283.130244 -290.674806) (xy 283.129749 -290.699413)
			(xy 283.121854 -290.74799) (xy 283.10627 -290.794671) (xy 283.083399 -290.838248) (xy 283.053834 -290.877592)
			(xy 283.018341 -290.911684) (xy 282.977838 -290.93964) (xy 282.933376 -290.960738) (xy 282.886105 -290.97443)
			(xy 282.83725 -290.980362) (xy 282.788075 -290.978381) (xy 282.739856 -290.968537) (xy 282.69384 -290.951085)
			(xy 282.651219 -290.926478) (xy 282.613098 -290.895353) (xy 282.580463 -290.858516) (xy 282.55416 -290.81692)
			(xy 282.534869 -290.771644) (xy 282.523092 -290.72386) (xy 282.519132 -290.674806) (xy 282.18003 -290.674806)
			(xy 282.179535 -290.699413) (xy 282.17164 -290.74799) (xy 282.156056 -290.794671) (xy 282.133185 -290.838248)
			(xy 282.10362 -290.877592) (xy 282.068127 -290.911684) (xy 282.027624 -290.93964) (xy 281.983162 -290.960738)
			(xy 281.935891 -290.97443) (xy 281.887036 -290.980362) (xy 281.837861 -290.978381) (xy 281.789642 -290.968537)
			(xy 281.743626 -290.951085) (xy 281.701005 -290.926478) (xy 281.662884 -290.895353) (xy 281.630249 -290.858516)
			(xy 281.603946 -290.81692) (xy 281.584655 -290.771644) (xy 281.572878 -290.72386) (xy 281.568918 -290.674806)
			(xy 281.23007 -290.674806) (xy 281.229575 -290.699413) (xy 281.22168 -290.74799) (xy 281.206096 -290.794671)
			(xy 281.183225 -290.838248) (xy 281.15366 -290.877592) (xy 281.118167 -290.911684) (xy 281.077664 -290.93964)
			(xy 281.033202 -290.960738) (xy 280.985931 -290.97443) (xy 280.937076 -290.980362) (xy 280.887901 -290.978381)
			(xy 280.839682 -290.968537) (xy 280.793666 -290.951085) (xy 280.751045 -290.926478) (xy 280.712924 -290.895353)
			(xy 280.680289 -290.858516) (xy 280.653986 -290.81692) (xy 280.634695 -290.771644) (xy 280.622918 -290.72386)
			(xy 280.618958 -290.674806) (xy 280.28011 -290.674806) (xy 280.279615 -290.699413) (xy 280.27172 -290.74799)
			(xy 280.256136 -290.794671) (xy 280.233265 -290.838248) (xy 280.2037 -290.877592) (xy 280.168207 -290.911684)
			(xy 280.127704 -290.93964) (xy 280.083242 -290.960738) (xy 280.035971 -290.97443) (xy 279.987116 -290.980362)
			(xy 279.937941 -290.978381) (xy 279.889722 -290.968537) (xy 279.843706 -290.951085) (xy 279.801085 -290.926478)
			(xy 279.762964 -290.895353) (xy 279.730329 -290.858516) (xy 279.704026 -290.81692) (xy 279.684735 -290.771644)
			(xy 279.672958 -290.72386) (xy 279.668998 -290.674806) (xy 279.33015 -290.674806) (xy 279.329655 -290.699413)
			(xy 279.32176 -290.74799) (xy 279.306176 -290.794671) (xy 279.283305 -290.838248) (xy 279.25374 -290.877592)
			(xy 279.218247 -290.911684) (xy 279.177744 -290.93964) (xy 279.133282 -290.960738) (xy 279.086011 -290.97443)
			(xy 279.037156 -290.980362) (xy 278.987981 -290.978381) (xy 278.939762 -290.968537) (xy 278.893746 -290.951085)
			(xy 278.851125 -290.926478) (xy 278.813004 -290.895353) (xy 278.780369 -290.858516) (xy 278.754066 -290.81692)
			(xy 278.734775 -290.771644) (xy 278.722998 -290.72386) (xy 278.719038 -290.674806) (xy 278.38019 -290.674806)
			(xy 278.379695 -290.699413) (xy 278.3718 -290.74799) (xy 278.356216 -290.794671) (xy 278.333345 -290.838248)
			(xy 278.30378 -290.877592) (xy 278.268287 -290.911684) (xy 278.227784 -290.93964) (xy 278.183322 -290.960738)
			(xy 278.136051 -290.97443) (xy 278.087196 -290.980362) (xy 278.038021 -290.978381) (xy 277.989802 -290.968537)
			(xy 277.943786 -290.951085) (xy 277.901165 -290.926478) (xy 277.863044 -290.895353) (xy 277.830409 -290.858516)
			(xy 277.804106 -290.81692) (xy 277.784815 -290.771644) (xy 277.773038 -290.72386) (xy 277.769078 -290.674806)
			(xy 277.43023 -290.674806) (xy 277.429735 -290.699413) (xy 277.42184 -290.74799) (xy 277.406256 -290.794671)
			(xy 277.383385 -290.838248) (xy 277.35382 -290.877592) (xy 277.318327 -290.911684) (xy 277.277824 -290.93964)
			(xy 277.233362 -290.960738) (xy 277.186091 -290.97443) (xy 277.137236 -290.980362) (xy 277.088061 -290.978381)
			(xy 277.039842 -290.968537) (xy 276.993826 -290.951085) (xy 276.951205 -290.926478) (xy 276.913084 -290.895353)
			(xy 276.880449 -290.858516) (xy 276.854146 -290.81692) (xy 276.834855 -290.771644) (xy 276.823078 -290.72386)
			(xy 276.819118 -290.674806) (xy 276.480016 -290.674806) (xy 276.479521 -290.699413) (xy 276.471626 -290.74799)
			(xy 276.456042 -290.794671) (xy 276.433171 -290.838248) (xy 276.403606 -290.877592) (xy 276.368113 -290.911684)
			(xy 276.32761 -290.93964) (xy 276.283148 -290.960738) (xy 276.235877 -290.97443) (xy 276.187022 -290.980362)
			(xy 276.137847 -290.978381) (xy 276.089628 -290.968537) (xy 276.043612 -290.951085) (xy 276.000991 -290.926478)
			(xy 275.96287 -290.895353) (xy 275.930235 -290.858516) (xy 275.903932 -290.81692) (xy 275.884641 -290.771644)
			(xy 275.872864 -290.72386) (xy 275.868904 -290.674806) (xy 275.530056 -290.674806) (xy 275.529561 -290.699413)
			(xy 275.521666 -290.74799) (xy 275.506082 -290.794671) (xy 275.483211 -290.838248) (xy 275.453646 -290.877592)
			(xy 275.418153 -290.911684) (xy 275.37765 -290.93964) (xy 275.333188 -290.960738) (xy 275.285917 -290.97443)
			(xy 275.237062 -290.980362) (xy 275.187887 -290.978381) (xy 275.139668 -290.968537) (xy 275.093652 -290.951085)
			(xy 275.051031 -290.926478) (xy 275.01291 -290.895353) (xy 274.980275 -290.858516) (xy 274.953972 -290.81692)
			(xy 274.934681 -290.771644) (xy 274.922904 -290.72386) (xy 274.918944 -290.674806) (xy 274.580096 -290.674806)
			(xy 274.579601 -290.699413) (xy 274.571706 -290.74799) (xy 274.556122 -290.794671) (xy 274.533251 -290.838248)
			(xy 274.503686 -290.877592) (xy 274.468193 -290.911684) (xy 274.42769 -290.93964) (xy 274.383228 -290.960738)
			(xy 274.335957 -290.97443) (xy 274.287102 -290.980362) (xy 274.237927 -290.978381) (xy 274.189708 -290.968537)
			(xy 274.143692 -290.951085) (xy 274.101071 -290.926478) (xy 274.06295 -290.895353) (xy 274.030315 -290.858516)
			(xy 274.004012 -290.81692) (xy 273.984721 -290.771644) (xy 273.972944 -290.72386) (xy 273.968984 -290.674806)
			(xy 273.630136 -290.674806) (xy 273.629641 -290.699413) (xy 273.621746 -290.74799) (xy 273.606162 -290.794671)
			(xy 273.583291 -290.838248) (xy 273.553726 -290.877592) (xy 273.518233 -290.911684) (xy 273.47773 -290.93964)
			(xy 273.433268 -290.960738) (xy 273.385997 -290.97443) (xy 273.337142 -290.980362) (xy 273.287967 -290.978381)
			(xy 273.239748 -290.968537) (xy 273.193732 -290.951085) (xy 273.151111 -290.926478) (xy 273.11299 -290.895353)
			(xy 273.080355 -290.858516) (xy 273.054052 -290.81692) (xy 273.034761 -290.771644) (xy 273.022984 -290.72386)
			(xy 273.019024 -290.674806) (xy 270.780256 -290.674806) (xy 270.779761 -290.699413) (xy 270.771866 -290.74799)
			(xy 270.756282 -290.794671) (xy 270.733411 -290.838248) (xy 270.703846 -290.877592) (xy 270.668353 -290.911684)
			(xy 270.62785 -290.93964) (xy 270.583388 -290.960738) (xy 270.536117 -290.97443) (xy 270.487262 -290.980362)
			(xy 270.438087 -290.978381) (xy 270.389868 -290.968537) (xy 270.343852 -290.951085) (xy 270.301231 -290.926478)
			(xy 270.26311 -290.895353) (xy 270.230475 -290.858516) (xy 270.204172 -290.81692) (xy 270.184881 -290.771644)
			(xy 270.173104 -290.72386) (xy 270.169144 -290.674806) (xy 269.830042 -290.674806) (xy 269.829547 -290.699413)
			(xy 269.821652 -290.74799) (xy 269.806068 -290.794671) (xy 269.783197 -290.838248) (xy 269.753632 -290.877592)
			(xy 269.718139 -290.911684) (xy 269.677636 -290.93964) (xy 269.633174 -290.960738) (xy 269.585903 -290.97443)
			(xy 269.537048 -290.980362) (xy 269.487873 -290.978381) (xy 269.439654 -290.968537) (xy 269.393638 -290.951085)
			(xy 269.351017 -290.926478) (xy 269.312896 -290.895353) (xy 269.280261 -290.858516) (xy 269.253958 -290.81692)
			(xy 269.234667 -290.771644) (xy 269.22289 -290.72386) (xy 269.21893 -290.674806) (xy 268.880082 -290.674806)
			(xy 268.879587 -290.699413) (xy 268.871692 -290.74799) (xy 268.856108 -290.794671) (xy 268.833237 -290.838248)
			(xy 268.803672 -290.877592) (xy 268.768179 -290.911684) (xy 268.727676 -290.93964) (xy 268.683214 -290.960738)
			(xy 268.635943 -290.97443) (xy 268.587088 -290.980362) (xy 268.537913 -290.978381) (xy 268.489694 -290.968537)
			(xy 268.443678 -290.951085) (xy 268.401057 -290.926478) (xy 268.362936 -290.895353) (xy 268.330301 -290.858516)
			(xy 268.303998 -290.81692) (xy 268.284707 -290.771644) (xy 268.27293 -290.72386) (xy 268.26897 -290.674806)
			(xy 266.228425 -290.674806) (xy 266.216874 -290.676077) (xy 266.16114 -290.67404) (xy 266.106297 -290.66391)
			(xy 266.053513 -290.645903) (xy 266.003913 -290.620402) (xy 265.958555 -290.587951) (xy 265.918406 -290.549242)
			(xy 265.88432 -290.505099) (xy 265.857024 -290.456464) (xy 265.837101 -290.404373) (xy 265.824975 -290.349936)
			(xy 265.820904 -290.294314) (xy 265.69797 -290.294314) (xy 265.697461 -290.3222) (xy 265.689341 -290.377376)
			(xy 265.673273 -290.430783) (xy 265.649601 -290.48128) (xy 265.618828 -290.527793) (xy 265.581611 -290.56933)
			(xy 265.538743 -290.605005) (xy 265.491137 -290.634059) (xy 265.439808 -290.655871) (xy 265.385851 -290.669977)
			(xy 265.330414 -290.676077) (xy 265.27468 -290.67404) (xy 265.219837 -290.66391) (xy 265.167053 -290.645903)
			(xy 265.117453 -290.620402) (xy 265.072095 -290.587951) (xy 265.031946 -290.549242) (xy 264.99786 -290.505099)
			(xy 264.970564 -290.456464) (xy 264.950641 -290.404373) (xy 264.938515 -290.349936) (xy 264.934444 -290.294314)
			(xy 264.30097 -290.294314) (xy 264.300484 -290.321565) (xy 264.292728 -290.375513) (xy 264.277373 -290.427808)
			(xy 264.254731 -290.477385) (xy 264.225265 -290.523235) (xy 264.189574 -290.564426) (xy 264.148383 -290.600117)
			(xy 264.102533 -290.629583) (xy 264.052956 -290.652225) (xy 264.000661 -290.66758) (xy 263.946713 -290.675336)
			(xy 263.892211 -290.675336) (xy 263.838263 -290.66758) (xy 263.785968 -290.652225) (xy 263.736391 -290.629583)
			(xy 263.690541 -290.600117) (xy 263.64935 -290.564426) (xy 263.613659 -290.523235) (xy 263.584193 -290.477385)
			(xy 263.561551 -290.427808) (xy 263.546196 -290.375513) (xy 263.53844 -290.321565) (xy 263.537954 -290.294314)
			(xy 249.737118 -290.294314) (xy 249.737118 -291.430456) (xy 258.01142 -291.430456) (xy 258.015491 -291.374834)
			(xy 258.027617 -291.320397) (xy 258.04754 -291.268306) (xy 258.074836 -291.219671) (xy 258.108922 -291.175528)
			(xy 258.149071 -291.136819) (xy 258.194429 -291.104368) (xy 258.244029 -291.078867) (xy 258.296813 -291.06086)
			(xy 258.351656 -291.05073) (xy 258.40739 -291.048693) (xy 258.462827 -291.054793) (xy 258.516784 -291.068899)
			(xy 258.568113 -291.090711) (xy 258.615719 -291.119765) (xy 258.658587 -291.15544) (xy 258.695804 -291.196977)
			(xy 258.726577 -291.24349) (xy 258.750249 -291.293987) (xy 258.766317 -291.347394) (xy 258.774437 -291.40257)
			(xy 258.774946 -291.430456) (xy 259.496558 -291.430456) (xy 259.500629 -291.374834) (xy 259.512755 -291.320397)
			(xy 259.532678 -291.268306) (xy 259.559974 -291.219671) (xy 259.59406 -291.175528) (xy 259.634209 -291.136819)
			(xy 259.679567 -291.104368) (xy 259.729167 -291.078867) (xy 259.781951 -291.06086) (xy 259.836794 -291.05073)
			(xy 259.892528 -291.048693) (xy 259.947965 -291.054793) (xy 260.001922 -291.068899) (xy 260.053251 -291.090711)
			(xy 260.100857 -291.119765) (xy 260.143725 -291.15544) (xy 260.180942 -291.196977) (xy 260.211715 -291.24349)
			(xy 260.235387 -291.293987) (xy 260.251455 -291.347394) (xy 260.259575 -291.40257) (xy 260.260084 -291.430456)
			(xy 260.259575 -291.458342) (xy 260.251455 -291.513518) (xy 260.235387 -291.566925) (xy 260.211715 -291.617422)
			(xy 260.206856 -291.624766) (xy 268.26897 -291.624766) (xy 268.27293 -291.575712) (xy 268.284707 -291.527928)
			(xy 268.303998 -291.482652) (xy 268.330301 -291.441056) (xy 268.362936 -291.404219) (xy 268.401057 -291.373094)
			(xy 268.443678 -291.348487) (xy 268.489694 -291.331035) (xy 268.537913 -291.321191) (xy 268.587088 -291.31921)
			(xy 268.635943 -291.325142) (xy 268.683214 -291.338834) (xy 268.727676 -291.359932) (xy 268.768179 -291.387888)
			(xy 268.803672 -291.42198) (xy 268.833237 -291.461324) (xy 268.856108 -291.504901) (xy 268.871692 -291.551582)
			(xy 268.879587 -291.600159) (xy 268.880082 -291.624766) (xy 269.21893 -291.624766) (xy 269.22289 -291.575712)
			(xy 269.234667 -291.527928) (xy 269.253958 -291.482652) (xy 269.280261 -291.441056) (xy 269.312896 -291.404219)
			(xy 269.351017 -291.373094) (xy 269.393638 -291.348487) (xy 269.439654 -291.331035) (xy 269.487873 -291.321191)
			(xy 269.537048 -291.31921) (xy 269.585903 -291.325142) (xy 269.633174 -291.338834) (xy 269.677636 -291.359932)
			(xy 269.718139 -291.387888) (xy 269.753632 -291.42198) (xy 269.783197 -291.461324) (xy 269.806068 -291.504901)
			(xy 269.821652 -291.551582) (xy 269.829547 -291.600159) (xy 269.830042 -291.624766) (xy 270.169144 -291.624766)
			(xy 270.173104 -291.575712) (xy 270.184881 -291.527928) (xy 270.204172 -291.482652) (xy 270.230475 -291.441056)
			(xy 270.26311 -291.404219) (xy 270.301231 -291.373094) (xy 270.343852 -291.348487) (xy 270.389868 -291.331035)
			(xy 270.438087 -291.321191) (xy 270.487262 -291.31921) (xy 270.536117 -291.325142) (xy 270.583388 -291.338834)
			(xy 270.62785 -291.359932) (xy 270.668353 -291.387888) (xy 270.703846 -291.42198) (xy 270.733411 -291.461324)
			(xy 270.756282 -291.504901) (xy 270.771866 -291.551582) (xy 270.779761 -291.600159) (xy 270.780256 -291.624766)
			(xy 273.019024 -291.624766) (xy 273.022984 -291.575712) (xy 273.034761 -291.527928) (xy 273.054052 -291.482652)
			(xy 273.080355 -291.441056) (xy 273.11299 -291.404219) (xy 273.151111 -291.373094) (xy 273.193732 -291.348487)
			(xy 273.239748 -291.331035) (xy 273.287967 -291.321191) (xy 273.337142 -291.31921) (xy 273.385997 -291.325142)
			(xy 273.433268 -291.338834) (xy 273.47773 -291.359932) (xy 273.518233 -291.387888) (xy 273.553726 -291.42198)
			(xy 273.583291 -291.461324) (xy 273.606162 -291.504901) (xy 273.621746 -291.551582) (xy 273.629641 -291.600159)
			(xy 273.630136 -291.624766) (xy 273.968984 -291.624766) (xy 273.972944 -291.575712) (xy 273.984721 -291.527928)
			(xy 274.004012 -291.482652) (xy 274.030315 -291.441056) (xy 274.06295 -291.404219) (xy 274.101071 -291.373094)
			(xy 274.143692 -291.348487) (xy 274.189708 -291.331035) (xy 274.237927 -291.321191) (xy 274.287102 -291.31921)
			(xy 274.335957 -291.325142) (xy 274.383228 -291.338834) (xy 274.42769 -291.359932) (xy 274.468193 -291.387888)
			(xy 274.503686 -291.42198) (xy 274.533251 -291.461324) (xy 274.556122 -291.504901) (xy 274.571706 -291.551582)
			(xy 274.579601 -291.600159) (xy 274.580096 -291.624766) (xy 274.918944 -291.624766) (xy 274.922904 -291.575712)
			(xy 274.934681 -291.527928) (xy 274.953972 -291.482652) (xy 274.980275 -291.441056) (xy 275.01291 -291.404219)
			(xy 275.051031 -291.373094) (xy 275.093652 -291.348487) (xy 275.139668 -291.331035) (xy 275.187887 -291.321191)
			(xy 275.237062 -291.31921) (xy 275.285917 -291.325142) (xy 275.333188 -291.338834) (xy 275.37765 -291.359932)
			(xy 275.418153 -291.387888) (xy 275.453646 -291.42198) (xy 275.483211 -291.461324) (xy 275.506082 -291.504901)
			(xy 275.521666 -291.551582) (xy 275.529561 -291.600159) (xy 275.530056 -291.624766) (xy 275.868904 -291.624766)
			(xy 275.872864 -291.575712) (xy 275.884641 -291.527928) (xy 275.903932 -291.482652) (xy 275.930235 -291.441056)
			(xy 275.96287 -291.404219) (xy 276.000991 -291.373094) (xy 276.043612 -291.348487) (xy 276.089628 -291.331035)
			(xy 276.137847 -291.321191) (xy 276.187022 -291.31921) (xy 276.235877 -291.325142) (xy 276.283148 -291.338834)
			(xy 276.32761 -291.359932) (xy 276.368113 -291.387888) (xy 276.403606 -291.42198) (xy 276.433171 -291.461324)
			(xy 276.456042 -291.504901) (xy 276.471626 -291.551582) (xy 276.479521 -291.600159) (xy 276.480016 -291.624766)
			(xy 276.819118 -291.624766) (xy 276.823078 -291.575712) (xy 276.834855 -291.527928) (xy 276.854146 -291.482652)
			(xy 276.880449 -291.441056) (xy 276.913084 -291.404219) (xy 276.951205 -291.373094) (xy 276.993826 -291.348487)
			(xy 277.039842 -291.331035) (xy 277.088061 -291.321191) (xy 277.137236 -291.31921) (xy 277.186091 -291.325142)
			(xy 277.233362 -291.338834) (xy 277.277824 -291.359932) (xy 277.318327 -291.387888) (xy 277.35382 -291.42198)
			(xy 277.383385 -291.461324) (xy 277.406256 -291.504901) (xy 277.42184 -291.551582) (xy 277.429735 -291.600159)
			(xy 277.43023 -291.624766) (xy 277.769078 -291.624766) (xy 277.773038 -291.575712) (xy 277.784815 -291.527928)
			(xy 277.804106 -291.482652) (xy 277.830409 -291.441056) (xy 277.863044 -291.404219) (xy 277.901165 -291.373094)
			(xy 277.943786 -291.348487) (xy 277.989802 -291.331035) (xy 278.038021 -291.321191) (xy 278.087196 -291.31921)
			(xy 278.136051 -291.325142) (xy 278.183322 -291.338834) (xy 278.227784 -291.359932) (xy 278.268287 -291.387888)
			(xy 278.30378 -291.42198) (xy 278.333345 -291.461324) (xy 278.356216 -291.504901) (xy 278.3718 -291.551582)
			(xy 278.379695 -291.600159) (xy 278.38019 -291.624766) (xy 279.668998 -291.624766) (xy 279.672958 -291.575712)
			(xy 279.684735 -291.527928) (xy 279.704026 -291.482652) (xy 279.730329 -291.441056) (xy 279.762964 -291.404219)
			(xy 279.801085 -291.373094) (xy 279.843706 -291.348487) (xy 279.889722 -291.331035) (xy 279.937941 -291.321191)
			(xy 279.987116 -291.31921) (xy 280.035971 -291.325142) (xy 280.083242 -291.338834) (xy 280.127704 -291.359932)
			(xy 280.168207 -291.387888) (xy 280.2037 -291.42198) (xy 280.233265 -291.461324) (xy 280.256136 -291.504901)
			(xy 280.27172 -291.551582) (xy 280.279615 -291.600159) (xy 280.28011 -291.624766) (xy 280.618958 -291.624766)
			(xy 280.622918 -291.575712) (xy 280.634695 -291.527928) (xy 280.653986 -291.482652) (xy 280.680289 -291.441056)
			(xy 280.712924 -291.404219) (xy 280.751045 -291.373094) (xy 280.793666 -291.348487) (xy 280.839682 -291.331035)
			(xy 280.887901 -291.321191) (xy 280.937076 -291.31921) (xy 280.985931 -291.325142) (xy 281.033202 -291.338834)
			(xy 281.077664 -291.359932) (xy 281.118167 -291.387888) (xy 281.15366 -291.42198) (xy 281.183225 -291.461324)
			(xy 281.206096 -291.504901) (xy 281.22168 -291.551582) (xy 281.229575 -291.600159) (xy 281.23007 -291.624766)
			(xy 281.568918 -291.624766) (xy 281.572878 -291.575712) (xy 281.584655 -291.527928) (xy 281.603946 -291.482652)
			(xy 281.630249 -291.441056) (xy 281.662884 -291.404219) (xy 281.701005 -291.373094) (xy 281.743626 -291.348487)
			(xy 281.789642 -291.331035) (xy 281.837861 -291.321191) (xy 281.887036 -291.31921) (xy 281.935891 -291.325142)
			(xy 281.983162 -291.338834) (xy 282.027624 -291.359932) (xy 282.068127 -291.387888) (xy 282.10362 -291.42198)
			(xy 282.133185 -291.461324) (xy 282.156056 -291.504901) (xy 282.17164 -291.551582) (xy 282.179535 -291.600159)
			(xy 282.18003 -291.624766) (xy 282.519132 -291.624766) (xy 282.523092 -291.575712) (xy 282.534869 -291.527928)
			(xy 282.55416 -291.482652) (xy 282.580463 -291.441056) (xy 282.613098 -291.404219) (xy 282.651219 -291.373094)
			(xy 282.69384 -291.348487) (xy 282.739856 -291.331035) (xy 282.788075 -291.321191) (xy 282.83725 -291.31921)
			(xy 282.886105 -291.325142) (xy 282.933376 -291.338834) (xy 282.977838 -291.359932) (xy 283.018341 -291.387888)
			(xy 283.053834 -291.42198) (xy 283.083399 -291.461324) (xy 283.10627 -291.504901) (xy 283.121854 -291.551582)
			(xy 283.129749 -291.600159) (xy 283.130244 -291.624766) (xy 283.469092 -291.624766) (xy 283.473052 -291.575712)
			(xy 283.484829 -291.527928) (xy 283.50412 -291.482652) (xy 283.530423 -291.441056) (xy 283.563058 -291.404219)
			(xy 283.601179 -291.373094) (xy 283.6438 -291.348487) (xy 283.689816 -291.331035) (xy 283.738035 -291.321191)
			(xy 283.78721 -291.31921) (xy 283.836065 -291.325142) (xy 283.883336 -291.338834) (xy 283.927798 -291.359932)
			(xy 283.968301 -291.387888) (xy 284.003794 -291.42198) (xy 284.033359 -291.461324) (xy 284.05623 -291.504901)
			(xy 284.071814 -291.551582) (xy 284.079709 -291.600159) (xy 284.080204 -291.624766) (xy 284.419052 -291.624766)
			(xy 284.423012 -291.575712) (xy 284.434789 -291.527928) (xy 284.45408 -291.482652) (xy 284.480383 -291.441056)
			(xy 284.513018 -291.404219) (xy 284.551139 -291.373094) (xy 284.59376 -291.348487) (xy 284.639776 -291.331035)
			(xy 284.687995 -291.321191) (xy 284.73717 -291.31921) (xy 284.786025 -291.325142) (xy 284.833296 -291.338834)
			(xy 284.877758 -291.359932) (xy 284.918261 -291.387888) (xy 284.953754 -291.42198) (xy 284.983319 -291.461324)
			(xy 285.00619 -291.504901) (xy 285.021774 -291.551582) (xy 285.029669 -291.600159) (xy 285.030164 -291.624766)
			(xy 285.369012 -291.624766) (xy 285.372972 -291.575712) (xy 285.384749 -291.527928) (xy 285.40404 -291.482652)
			(xy 285.430343 -291.441056) (xy 285.462978 -291.404219) (xy 285.501099 -291.373094) (xy 285.54372 -291.348487)
			(xy 285.589736 -291.331035) (xy 285.637955 -291.321191) (xy 285.68713 -291.31921) (xy 285.735985 -291.325142)
			(xy 285.783256 -291.338834) (xy 285.827718 -291.359932) (xy 285.868221 -291.387888) (xy 285.903714 -291.42198)
			(xy 285.933279 -291.461324) (xy 285.95615 -291.504901) (xy 285.971734 -291.551582) (xy 285.979629 -291.600159)
			(xy 285.980124 -291.624766) (xy 286.318972 -291.624766) (xy 286.322932 -291.575712) (xy 286.334709 -291.527928)
			(xy 286.354 -291.482652) (xy 286.380303 -291.441056) (xy 286.412938 -291.404219) (xy 286.451059 -291.373094)
			(xy 286.49368 -291.348487) (xy 286.539696 -291.331035) (xy 286.587915 -291.321191) (xy 286.63709 -291.31921)
			(xy 286.685945 -291.325142) (xy 286.733216 -291.338834) (xy 286.777678 -291.359932) (xy 286.818181 -291.387888)
			(xy 286.853674 -291.42198) (xy 286.883239 -291.461324) (xy 286.90611 -291.504901) (xy 286.921694 -291.551582)
			(xy 286.929589 -291.600159) (xy 286.930084 -291.624766) (xy 287.268932 -291.624766) (xy 287.272892 -291.575712)
			(xy 287.284669 -291.527928) (xy 287.30396 -291.482652) (xy 287.330263 -291.441056) (xy 287.362898 -291.404219)
			(xy 287.401019 -291.373094) (xy 287.44364 -291.348487) (xy 287.489656 -291.331035) (xy 287.537875 -291.321191)
			(xy 287.58705 -291.31921) (xy 287.635905 -291.325142) (xy 287.683176 -291.338834) (xy 287.727638 -291.359932)
			(xy 287.768141 -291.387888) (xy 287.803634 -291.42198) (xy 287.833199 -291.461324) (xy 287.85607 -291.504901)
			(xy 287.871654 -291.551582) (xy 287.879549 -291.600159) (xy 287.880044 -291.624766) (xy 288.218892 -291.624766)
			(xy 288.222852 -291.575712) (xy 288.234629 -291.527928) (xy 288.25392 -291.482652) (xy 288.280223 -291.441056)
			(xy 288.312858 -291.404219) (xy 288.350979 -291.373094) (xy 288.3936 -291.348487) (xy 288.439616 -291.331035)
			(xy 288.487835 -291.321191) (xy 288.53701 -291.31921) (xy 288.585865 -291.325142) (xy 288.633136 -291.338834)
			(xy 288.677598 -291.359932) (xy 288.718101 -291.387888) (xy 288.753594 -291.42198) (xy 288.783159 -291.461324)
			(xy 288.80603 -291.504901) (xy 288.821614 -291.551582) (xy 288.829509 -291.600159) (xy 288.830004 -291.624766)
			(xy 289.169106 -291.624766) (xy 289.173066 -291.575712) (xy 289.184843 -291.527928) (xy 289.204134 -291.482652)
			(xy 289.230437 -291.441056) (xy 289.263072 -291.404219) (xy 289.301193 -291.373094) (xy 289.343814 -291.348487)
			(xy 289.38983 -291.331035) (xy 289.438049 -291.321191) (xy 289.487224 -291.31921) (xy 289.536079 -291.325142)
			(xy 289.58335 -291.338834) (xy 289.627812 -291.359932) (xy 289.668315 -291.387888) (xy 289.703808 -291.42198)
			(xy 289.733373 -291.461324) (xy 289.756244 -291.504901) (xy 289.771828 -291.551582) (xy 289.779723 -291.600159)
			(xy 289.780218 -291.624766) (xy 290.119066 -291.624766) (xy 290.123026 -291.575712) (xy 290.134803 -291.527928)
			(xy 290.154094 -291.482652) (xy 290.180397 -291.441056) (xy 290.213032 -291.404219) (xy 290.251153 -291.373094)
			(xy 290.293774 -291.348487) (xy 290.33979 -291.331035) (xy 290.388009 -291.321191) (xy 290.437184 -291.31921)
			(xy 290.486039 -291.325142) (xy 290.53331 -291.338834) (xy 290.577772 -291.359932) (xy 290.618275 -291.387888)
			(xy 290.653768 -291.42198) (xy 290.683333 -291.461324) (xy 290.706204 -291.504901) (xy 290.721788 -291.551582)
			(xy 290.729683 -291.600159) (xy 290.730178 -291.624766) (xy 292.018986 -291.624766) (xy 292.022946 -291.575712)
			(xy 292.034723 -291.527928) (xy 292.054014 -291.482652) (xy 292.080317 -291.441056) (xy 292.112952 -291.404219)
			(xy 292.151073 -291.373094) (xy 292.193694 -291.348487) (xy 292.23971 -291.331035) (xy 292.287929 -291.321191)
			(xy 292.337104 -291.31921) (xy 292.385959 -291.325142) (xy 292.43323 -291.338834) (xy 292.477692 -291.359932)
			(xy 292.518195 -291.387888) (xy 292.553688 -291.42198) (xy 292.583253 -291.461324) (xy 292.606124 -291.504901)
			(xy 292.621708 -291.551582) (xy 292.629603 -291.600159) (xy 292.630098 -291.624766) (xy 292.968946 -291.624766)
			(xy 292.972906 -291.575712) (xy 292.984683 -291.527928) (xy 293.003974 -291.482652) (xy 293.030277 -291.441056)
			(xy 293.062912 -291.404219) (xy 293.101033 -291.373094) (xy 293.143654 -291.348487) (xy 293.18967 -291.331035)
			(xy 293.237889 -291.321191) (xy 293.287064 -291.31921) (xy 293.335919 -291.325142) (xy 293.38319 -291.338834)
			(xy 293.427652 -291.359932) (xy 293.468155 -291.387888) (xy 293.503648 -291.42198) (xy 293.533213 -291.461324)
			(xy 293.556084 -291.504901) (xy 293.571668 -291.551582) (xy 293.579563 -291.600159) (xy 293.580058 -291.624766)
			(xy 293.918906 -291.624766) (xy 293.922866 -291.575712) (xy 293.934643 -291.527928) (xy 293.953934 -291.482652)
			(xy 293.980237 -291.441056) (xy 294.012872 -291.404219) (xy 294.050993 -291.373094) (xy 294.093614 -291.348487)
			(xy 294.13963 -291.331035) (xy 294.187849 -291.321191) (xy 294.237024 -291.31921) (xy 294.285879 -291.325142)
			(xy 294.33315 -291.338834) (xy 294.377612 -291.359932) (xy 294.418115 -291.387888) (xy 294.453608 -291.42198)
			(xy 294.483173 -291.461324) (xy 294.506044 -291.504901) (xy 294.521628 -291.551582) (xy 294.529523 -291.600159)
			(xy 294.530018 -291.624766) (xy 294.86912 -291.624766) (xy 294.87308 -291.575712) (xy 294.884857 -291.527928)
			(xy 294.904148 -291.482652) (xy 294.930451 -291.441056) (xy 294.963086 -291.404219) (xy 295.001207 -291.373094)
			(xy 295.043828 -291.348487) (xy 295.089844 -291.331035) (xy 295.138063 -291.321191) (xy 295.187238 -291.31921)
			(xy 295.236093 -291.325142) (xy 295.283364 -291.338834) (xy 295.327826 -291.359932) (xy 295.368329 -291.387888)
			(xy 295.403822 -291.42198) (xy 295.433387 -291.461324) (xy 295.456258 -291.504901) (xy 295.471842 -291.551582)
			(xy 295.479737 -291.600159) (xy 295.480232 -291.624766) (xy 295.81908 -291.624766) (xy 295.82304 -291.575712)
			(xy 295.834817 -291.527928) (xy 295.854108 -291.482652) (xy 295.880411 -291.441056) (xy 295.913046 -291.404219)
			(xy 295.951167 -291.373094) (xy 295.993788 -291.348487) (xy 296.039804 -291.331035) (xy 296.088023 -291.321191)
			(xy 296.137198 -291.31921) (xy 296.186053 -291.325142) (xy 296.233324 -291.338834) (xy 296.277786 -291.359932)
			(xy 296.318289 -291.387888) (xy 296.353782 -291.42198) (xy 296.383347 -291.461324) (xy 296.406218 -291.504901)
			(xy 296.421802 -291.551582) (xy 296.429697 -291.600159) (xy 296.430192 -291.624766) (xy 296.76904 -291.624766)
			(xy 296.773 -291.575712) (xy 296.784777 -291.527928) (xy 296.804068 -291.482652) (xy 296.830371 -291.441056)
			(xy 296.863006 -291.404219) (xy 296.901127 -291.373094) (xy 296.943748 -291.348487) (xy 296.989764 -291.331035)
			(xy 297.037983 -291.321191) (xy 297.087158 -291.31921) (xy 297.136013 -291.325142) (xy 297.183284 -291.338834)
			(xy 297.227746 -291.359932) (xy 297.268249 -291.387888) (xy 297.303742 -291.42198) (xy 297.333307 -291.461324)
			(xy 297.356178 -291.504901) (xy 297.371762 -291.551582) (xy 297.379657 -291.600159) (xy 297.380152 -291.624766)
			(xy 297.719 -291.624766) (xy 297.72296 -291.575712) (xy 297.734737 -291.527928) (xy 297.754028 -291.482652)
			(xy 297.780331 -291.441056) (xy 297.812966 -291.404219) (xy 297.851087 -291.373094) (xy 297.893708 -291.348487)
			(xy 297.939724 -291.331035) (xy 297.987943 -291.321191) (xy 298.037118 -291.31921) (xy 298.085973 -291.325142)
			(xy 298.133244 -291.338834) (xy 298.177706 -291.359932) (xy 298.218209 -291.387888) (xy 298.253702 -291.42198)
			(xy 298.283267 -291.461324) (xy 298.306138 -291.504901) (xy 298.321722 -291.551582) (xy 298.329617 -291.600159)
			(xy 298.330112 -291.624766) (xy 298.66896 -291.624766) (xy 298.67292 -291.575712) (xy 298.684697 -291.527928)
			(xy 298.703988 -291.482652) (xy 298.730291 -291.441056) (xy 298.762926 -291.404219) (xy 298.801047 -291.373094)
			(xy 298.843668 -291.348487) (xy 298.889684 -291.331035) (xy 298.937903 -291.321191) (xy 298.987078 -291.31921)
			(xy 299.035933 -291.325142) (xy 299.083204 -291.338834) (xy 299.127666 -291.359932) (xy 299.168169 -291.387888)
			(xy 299.203662 -291.42198) (xy 299.233227 -291.461324) (xy 299.256098 -291.504901) (xy 299.271682 -291.551582)
			(xy 299.279577 -291.600159) (xy 299.280072 -291.624766) (xy 299.61892 -291.624766) (xy 299.62288 -291.575712)
			(xy 299.634657 -291.527928) (xy 299.653948 -291.482652) (xy 299.680251 -291.441056) (xy 299.712886 -291.404219)
			(xy 299.751007 -291.373094) (xy 299.793628 -291.348487) (xy 299.839644 -291.331035) (xy 299.887863 -291.321191)
			(xy 299.937038 -291.31921) (xy 299.985893 -291.325142) (xy 300.033164 -291.338834) (xy 300.077626 -291.359932)
			(xy 300.118129 -291.387888) (xy 300.153622 -291.42198) (xy 300.183187 -291.461324) (xy 300.206058 -291.504901)
			(xy 300.221642 -291.551582) (xy 300.229537 -291.600159) (xy 300.230032 -291.624766) (xy 300.56888 -291.624766)
			(xy 300.57284 -291.575712) (xy 300.584617 -291.527928) (xy 300.603908 -291.482652) (xy 300.630211 -291.441056)
			(xy 300.662846 -291.404219) (xy 300.700967 -291.373094) (xy 300.743588 -291.348487) (xy 300.789604 -291.331035)
			(xy 300.837823 -291.321191) (xy 300.886998 -291.31921) (xy 300.935853 -291.325142) (xy 300.983124 -291.338834)
			(xy 301.027586 -291.359932) (xy 301.068089 -291.387888) (xy 301.103582 -291.42198) (xy 301.133147 -291.461324)
			(xy 301.156018 -291.504901) (xy 301.171602 -291.551582) (xy 301.179497 -291.600159) (xy 301.179992 -291.624766)
			(xy 301.519094 -291.624766) (xy 301.523054 -291.575712) (xy 301.534831 -291.527928) (xy 301.554122 -291.482652)
			(xy 301.580425 -291.441056) (xy 301.61306 -291.404219) (xy 301.651181 -291.373094) (xy 301.693802 -291.348487)
			(xy 301.739818 -291.331035) (xy 301.788037 -291.321191) (xy 301.837212 -291.31921) (xy 301.886067 -291.325142)
			(xy 301.933338 -291.338834) (xy 301.9778 -291.359932) (xy 302.018303 -291.387888) (xy 302.053796 -291.42198)
			(xy 302.083361 -291.461324) (xy 302.106232 -291.504901) (xy 302.121816 -291.551582) (xy 302.129711 -291.600159)
			(xy 302.130206 -291.624766) (xy 302.469054 -291.624766) (xy 302.473014 -291.575712) (xy 302.484791 -291.527928)
			(xy 302.504082 -291.482652) (xy 302.530385 -291.441056) (xy 302.56302 -291.404219) (xy 302.601141 -291.373094)
			(xy 302.643762 -291.348487) (xy 302.689778 -291.331035) (xy 302.737997 -291.321191) (xy 302.787172 -291.31921)
			(xy 302.836027 -291.325142) (xy 302.883298 -291.338834) (xy 302.92776 -291.359932) (xy 302.968263 -291.387888)
			(xy 303.003756 -291.42198) (xy 303.033321 -291.461324) (xy 303.056192 -291.504901) (xy 303.071776 -291.551582)
			(xy 303.079671 -291.600159) (xy 303.080166 -291.624766) (xy 303.419014 -291.624766) (xy 303.422974 -291.575712)
			(xy 303.434751 -291.527928) (xy 303.454042 -291.482652) (xy 303.480345 -291.441056) (xy 303.51298 -291.404219)
			(xy 303.551101 -291.373094) (xy 303.593722 -291.348487) (xy 303.639738 -291.331035) (xy 303.687957 -291.321191)
			(xy 303.737132 -291.31921) (xy 303.785987 -291.325142) (xy 303.833258 -291.338834) (xy 303.87772 -291.359932)
			(xy 303.918223 -291.387888) (xy 303.953716 -291.42198) (xy 303.983281 -291.461324) (xy 304.006152 -291.504901)
			(xy 304.021736 -291.551582) (xy 304.029631 -291.600159) (xy 304.030126 -291.624766) (xy 304.368974 -291.624766)
			(xy 304.372934 -291.575712) (xy 304.384711 -291.527928) (xy 304.404002 -291.482652) (xy 304.430305 -291.441056)
			(xy 304.46294 -291.404219) (xy 304.501061 -291.373094) (xy 304.543682 -291.348487) (xy 304.589698 -291.331035)
			(xy 304.637917 -291.321191) (xy 304.687092 -291.31921) (xy 304.735947 -291.325142) (xy 304.783218 -291.338834)
			(xy 304.82768 -291.359932) (xy 304.868183 -291.387888) (xy 304.903676 -291.42198) (xy 304.933241 -291.461324)
			(xy 304.956112 -291.504901) (xy 304.971696 -291.551582) (xy 304.979591 -291.600159) (xy 304.980086 -291.624766)
			(xy 305.318934 -291.624766) (xy 305.322894 -291.575712) (xy 305.334671 -291.527928) (xy 305.353962 -291.482652)
			(xy 305.380265 -291.441056) (xy 305.4129 -291.404219) (xy 305.451021 -291.373094) (xy 305.493642 -291.348487)
			(xy 305.539658 -291.331035) (xy 305.587877 -291.321191) (xy 305.637052 -291.31921) (xy 305.685907 -291.325142)
			(xy 305.733178 -291.338834) (xy 305.77764 -291.359932) (xy 305.818143 -291.387888) (xy 305.853636 -291.42198)
			(xy 305.883201 -291.461324) (xy 305.906072 -291.504901) (xy 305.921656 -291.551582) (xy 305.929551 -291.600159)
			(xy 305.930046 -291.624766) (xy 306.269148 -291.624766) (xy 306.273108 -291.575712) (xy 306.284885 -291.527928)
			(xy 306.304176 -291.482652) (xy 306.330479 -291.441056) (xy 306.363114 -291.404219) (xy 306.401235 -291.373094)
			(xy 306.443856 -291.348487) (xy 306.489872 -291.331035) (xy 306.538091 -291.321191) (xy 306.587266 -291.31921)
			(xy 306.636121 -291.325142) (xy 306.683392 -291.338834) (xy 306.727854 -291.359932) (xy 306.768357 -291.387888)
			(xy 306.80385 -291.42198) (xy 306.833415 -291.461324) (xy 306.856286 -291.504901) (xy 306.87187 -291.551582)
			(xy 306.879765 -291.600159) (xy 306.88026 -291.624766) (xy 308.169068 -291.624766) (xy 308.173028 -291.575712)
			(xy 308.184805 -291.527928) (xy 308.204096 -291.482652) (xy 308.230399 -291.441056) (xy 308.263034 -291.404219)
			(xy 308.301155 -291.373094) (xy 308.343776 -291.348487) (xy 308.389792 -291.331035) (xy 308.438011 -291.321191)
			(xy 308.487186 -291.31921) (xy 308.536041 -291.325142) (xy 308.583312 -291.338834) (xy 308.627774 -291.359932)
			(xy 308.668277 -291.387888) (xy 308.70377 -291.42198) (xy 308.733335 -291.461324) (xy 308.756206 -291.504901)
			(xy 308.77179 -291.551582) (xy 308.779685 -291.600159) (xy 308.78018 -291.624766) (xy 309.119028 -291.624766)
			(xy 309.122988 -291.575712) (xy 309.134765 -291.527928) (xy 309.154056 -291.482652) (xy 309.180359 -291.441056)
			(xy 309.212994 -291.404219) (xy 309.251115 -291.373094) (xy 309.293736 -291.348487) (xy 309.339752 -291.331035)
			(xy 309.387971 -291.321191) (xy 309.437146 -291.31921) (xy 309.486001 -291.325142) (xy 309.533272 -291.338834)
			(xy 309.577734 -291.359932) (xy 309.618237 -291.387888) (xy 309.65373 -291.42198) (xy 309.683295 -291.461324)
			(xy 309.706166 -291.504901) (xy 309.72175 -291.551582) (xy 309.729645 -291.600159) (xy 309.73014 -291.624766)
			(xy 310.068988 -291.624766) (xy 310.072948 -291.575712) (xy 310.084725 -291.527928) (xy 310.104016 -291.482652)
			(xy 310.130319 -291.441056) (xy 310.162954 -291.404219) (xy 310.201075 -291.373094) (xy 310.243696 -291.348487)
			(xy 310.289712 -291.331035) (xy 310.337931 -291.321191) (xy 310.387106 -291.31921) (xy 310.435961 -291.325142)
			(xy 310.483232 -291.338834) (xy 310.527694 -291.359932) (xy 310.568197 -291.387888) (xy 310.60369 -291.42198)
			(xy 310.633255 -291.461324) (xy 310.656126 -291.504901) (xy 310.67171 -291.551582) (xy 310.679605 -291.600159)
			(xy 310.6801 -291.624766) (xy 311.018948 -291.624766) (xy 311.022908 -291.575712) (xy 311.034685 -291.527928)
			(xy 311.053976 -291.482652) (xy 311.080279 -291.441056) (xy 311.112914 -291.404219) (xy 311.151035 -291.373094)
			(xy 311.193656 -291.348487) (xy 311.239672 -291.331035) (xy 311.287891 -291.321191) (xy 311.337066 -291.31921)
			(xy 311.385921 -291.325142) (xy 311.433192 -291.338834) (xy 311.477654 -291.359932) (xy 311.518157 -291.387888)
			(xy 311.55365 -291.42198) (xy 311.583215 -291.461324) (xy 311.606086 -291.504901) (xy 311.62167 -291.551582)
			(xy 311.629565 -291.600159) (xy 311.63006 -291.624766) (xy 311.968908 -291.624766) (xy 311.972868 -291.575712)
			(xy 311.984645 -291.527928) (xy 312.003936 -291.482652) (xy 312.030239 -291.441056) (xy 312.062874 -291.404219)
			(xy 312.100995 -291.373094) (xy 312.143616 -291.348487) (xy 312.189632 -291.331035) (xy 312.237851 -291.321191)
			(xy 312.287026 -291.31921) (xy 312.335881 -291.325142) (xy 312.383152 -291.338834) (xy 312.427614 -291.359932)
			(xy 312.468117 -291.387888) (xy 312.50361 -291.42198) (xy 312.533175 -291.461324) (xy 312.556046 -291.504901)
			(xy 312.57163 -291.551582) (xy 312.579525 -291.600159) (xy 312.58002 -291.624766) (xy 312.919122 -291.624766)
			(xy 312.923082 -291.575712) (xy 312.934859 -291.527928) (xy 312.95415 -291.482652) (xy 312.980453 -291.441056)
			(xy 313.013088 -291.404219) (xy 313.051209 -291.373094) (xy 313.09383 -291.348487) (xy 313.139846 -291.331035)
			(xy 313.188065 -291.321191) (xy 313.23724 -291.31921) (xy 313.286095 -291.325142) (xy 313.333366 -291.338834)
			(xy 313.377828 -291.359932) (xy 313.418331 -291.387888) (xy 313.453824 -291.42198) (xy 313.483389 -291.461324)
			(xy 313.50626 -291.504901) (xy 313.521844 -291.551582) (xy 313.529739 -291.600159) (xy 313.530234 -291.624766)
			(xy 313.869082 -291.624766) (xy 313.873042 -291.575712) (xy 313.884819 -291.527928) (xy 313.90411 -291.482652)
			(xy 313.930413 -291.441056) (xy 313.963048 -291.404219) (xy 314.001169 -291.373094) (xy 314.04379 -291.348487)
			(xy 314.089806 -291.331035) (xy 314.138025 -291.321191) (xy 314.1872 -291.31921) (xy 314.236055 -291.325142)
			(xy 314.283326 -291.338834) (xy 314.327788 -291.359932) (xy 314.368291 -291.387888) (xy 314.403784 -291.42198)
			(xy 314.433349 -291.461324) (xy 314.45622 -291.504901) (xy 314.471804 -291.551582) (xy 314.479699 -291.600159)
			(xy 314.480194 -291.624766) (xy 314.819042 -291.624766) (xy 314.823002 -291.575712) (xy 314.834779 -291.527928)
			(xy 314.85407 -291.482652) (xy 314.880373 -291.441056) (xy 314.913008 -291.404219) (xy 314.951129 -291.373094)
			(xy 314.99375 -291.348487) (xy 315.039766 -291.331035) (xy 315.087985 -291.321191) (xy 315.13716 -291.31921)
			(xy 315.186015 -291.325142) (xy 315.233286 -291.338834) (xy 315.277748 -291.359932) (xy 315.318251 -291.387888)
			(xy 315.353744 -291.42198) (xy 315.383309 -291.461324) (xy 315.40618 -291.504901) (xy 315.421764 -291.551582)
			(xy 315.429659 -291.600159) (xy 315.430154 -291.624766) (xy 315.429659 -291.649373) (xy 315.421764 -291.69795)
			(xy 315.40618 -291.744631) (xy 315.383309 -291.788208) (xy 315.353744 -291.827552) (xy 315.318251 -291.861644)
			(xy 315.277748 -291.8896) (xy 315.233286 -291.910698) (xy 315.186015 -291.92439) (xy 315.13716 -291.930322)
			(xy 315.087985 -291.928341) (xy 315.039766 -291.918497) (xy 314.99375 -291.901045) (xy 314.951129 -291.876438)
			(xy 314.913008 -291.845313) (xy 314.880373 -291.808476) (xy 314.85407 -291.76688) (xy 314.834779 -291.721604)
			(xy 314.823002 -291.67382) (xy 314.819042 -291.624766) (xy 314.480194 -291.624766) (xy 314.479699 -291.649373)
			(xy 314.471804 -291.69795) (xy 314.45622 -291.744631) (xy 314.433349 -291.788208) (xy 314.403784 -291.827552)
			(xy 314.368291 -291.861644) (xy 314.327788 -291.8896) (xy 314.283326 -291.910698) (xy 314.236055 -291.92439)
			(xy 314.1872 -291.930322) (xy 314.138025 -291.928341) (xy 314.089806 -291.918497) (xy 314.04379 -291.901045)
			(xy 314.001169 -291.876438) (xy 313.963048 -291.845313) (xy 313.930413 -291.808476) (xy 313.90411 -291.76688)
			(xy 313.884819 -291.721604) (xy 313.873042 -291.67382) (xy 313.869082 -291.624766) (xy 313.530234 -291.624766)
			(xy 313.529739 -291.649373) (xy 313.521844 -291.69795) (xy 313.50626 -291.744631) (xy 313.483389 -291.788208)
			(xy 313.453824 -291.827552) (xy 313.418331 -291.861644) (xy 313.377828 -291.8896) (xy 313.333366 -291.910698)
			(xy 313.286095 -291.92439) (xy 313.23724 -291.930322) (xy 313.188065 -291.928341) (xy 313.139846 -291.918497)
			(xy 313.09383 -291.901045) (xy 313.051209 -291.876438) (xy 313.013088 -291.845313) (xy 312.980453 -291.808476)
			(xy 312.95415 -291.76688) (xy 312.934859 -291.721604) (xy 312.923082 -291.67382) (xy 312.919122 -291.624766)
			(xy 312.58002 -291.624766) (xy 312.579525 -291.649373) (xy 312.57163 -291.69795) (xy 312.556046 -291.744631)
			(xy 312.533175 -291.788208) (xy 312.50361 -291.827552) (xy 312.468117 -291.861644) (xy 312.427614 -291.8896)
			(xy 312.383152 -291.910698) (xy 312.335881 -291.92439) (xy 312.287026 -291.930322) (xy 312.237851 -291.928341)
			(xy 312.189632 -291.918497) (xy 312.143616 -291.901045) (xy 312.100995 -291.876438) (xy 312.062874 -291.845313)
			(xy 312.030239 -291.808476) (xy 312.003936 -291.76688) (xy 311.984645 -291.721604) (xy 311.972868 -291.67382)
			(xy 311.968908 -291.624766) (xy 311.63006 -291.624766) (xy 311.629565 -291.649373) (xy 311.62167 -291.69795)
			(xy 311.606086 -291.744631) (xy 311.583215 -291.788208) (xy 311.55365 -291.827552) (xy 311.518157 -291.861644)
			(xy 311.477654 -291.8896) (xy 311.433192 -291.910698) (xy 311.385921 -291.92439) (xy 311.337066 -291.930322)
			(xy 311.287891 -291.928341) (xy 311.239672 -291.918497) (xy 311.193656 -291.901045) (xy 311.151035 -291.876438)
			(xy 311.112914 -291.845313) (xy 311.080279 -291.808476) (xy 311.053976 -291.76688) (xy 311.034685 -291.721604)
			(xy 311.022908 -291.67382) (xy 311.018948 -291.624766) (xy 310.6801 -291.624766) (xy 310.679605 -291.649373)
			(xy 310.67171 -291.69795) (xy 310.656126 -291.744631) (xy 310.633255 -291.788208) (xy 310.60369 -291.827552)
			(xy 310.568197 -291.861644) (xy 310.527694 -291.8896) (xy 310.483232 -291.910698) (xy 310.435961 -291.92439)
			(xy 310.387106 -291.930322) (xy 310.337931 -291.928341) (xy 310.289712 -291.918497) (xy 310.243696 -291.901045)
			(xy 310.201075 -291.876438) (xy 310.162954 -291.845313) (xy 310.130319 -291.808476) (xy 310.104016 -291.76688)
			(xy 310.084725 -291.721604) (xy 310.072948 -291.67382) (xy 310.068988 -291.624766) (xy 309.73014 -291.624766)
			(xy 309.729645 -291.649373) (xy 309.72175 -291.69795) (xy 309.706166 -291.744631) (xy 309.683295 -291.788208)
			(xy 309.65373 -291.827552) (xy 309.618237 -291.861644) (xy 309.577734 -291.8896) (xy 309.533272 -291.910698)
			(xy 309.486001 -291.92439) (xy 309.437146 -291.930322) (xy 309.387971 -291.928341) (xy 309.339752 -291.918497)
			(xy 309.293736 -291.901045) (xy 309.251115 -291.876438) (xy 309.212994 -291.845313) (xy 309.180359 -291.808476)
			(xy 309.154056 -291.76688) (xy 309.134765 -291.721604) (xy 309.122988 -291.67382) (xy 309.119028 -291.624766)
			(xy 308.78018 -291.624766) (xy 308.779685 -291.649373) (xy 308.77179 -291.69795) (xy 308.756206 -291.744631)
			(xy 308.733335 -291.788208) (xy 308.70377 -291.827552) (xy 308.668277 -291.861644) (xy 308.627774 -291.8896)
			(xy 308.583312 -291.910698) (xy 308.536041 -291.92439) (xy 308.487186 -291.930322) (xy 308.438011 -291.928341)
			(xy 308.389792 -291.918497) (xy 308.343776 -291.901045) (xy 308.301155 -291.876438) (xy 308.263034 -291.845313)
			(xy 308.230399 -291.808476) (xy 308.204096 -291.76688) (xy 308.184805 -291.721604) (xy 308.173028 -291.67382)
			(xy 308.169068 -291.624766) (xy 306.88026 -291.624766) (xy 306.879765 -291.649373) (xy 306.87187 -291.69795)
			(xy 306.856286 -291.744631) (xy 306.833415 -291.788208) (xy 306.80385 -291.827552) (xy 306.768357 -291.861644)
			(xy 306.727854 -291.8896) (xy 306.683392 -291.910698) (xy 306.636121 -291.92439) (xy 306.587266 -291.930322)
			(xy 306.538091 -291.928341) (xy 306.489872 -291.918497) (xy 306.443856 -291.901045) (xy 306.401235 -291.876438)
			(xy 306.363114 -291.845313) (xy 306.330479 -291.808476) (xy 306.304176 -291.76688) (xy 306.284885 -291.721604)
			(xy 306.273108 -291.67382) (xy 306.269148 -291.624766) (xy 305.930046 -291.624766) (xy 305.929551 -291.649373)
			(xy 305.921656 -291.69795) (xy 305.906072 -291.744631) (xy 305.883201 -291.788208) (xy 305.853636 -291.827552)
			(xy 305.818143 -291.861644) (xy 305.77764 -291.8896) (xy 305.733178 -291.910698) (xy 305.685907 -291.92439)
			(xy 305.637052 -291.930322) (xy 305.587877 -291.928341) (xy 305.539658 -291.918497) (xy 305.493642 -291.901045)
			(xy 305.451021 -291.876438) (xy 305.4129 -291.845313) (xy 305.380265 -291.808476) (xy 305.353962 -291.76688)
			(xy 305.334671 -291.721604) (xy 305.322894 -291.67382) (xy 305.318934 -291.624766) (xy 304.980086 -291.624766)
			(xy 304.979591 -291.649373) (xy 304.971696 -291.69795) (xy 304.956112 -291.744631) (xy 304.933241 -291.788208)
			(xy 304.903676 -291.827552) (xy 304.868183 -291.861644) (xy 304.82768 -291.8896) (xy 304.783218 -291.910698)
			(xy 304.735947 -291.92439) (xy 304.687092 -291.930322) (xy 304.637917 -291.928341) (xy 304.589698 -291.918497)
			(xy 304.543682 -291.901045) (xy 304.501061 -291.876438) (xy 304.46294 -291.845313) (xy 304.430305 -291.808476)
			(xy 304.404002 -291.76688) (xy 304.384711 -291.721604) (xy 304.372934 -291.67382) (xy 304.368974 -291.624766)
			(xy 304.030126 -291.624766) (xy 304.029631 -291.649373) (xy 304.021736 -291.69795) (xy 304.006152 -291.744631)
			(xy 303.983281 -291.788208) (xy 303.953716 -291.827552) (xy 303.918223 -291.861644) (xy 303.87772 -291.8896)
			(xy 303.833258 -291.910698) (xy 303.785987 -291.92439) (xy 303.737132 -291.930322) (xy 303.687957 -291.928341)
			(xy 303.639738 -291.918497) (xy 303.593722 -291.901045) (xy 303.551101 -291.876438) (xy 303.51298 -291.845313)
			(xy 303.480345 -291.808476) (xy 303.454042 -291.76688) (xy 303.434751 -291.721604) (xy 303.422974 -291.67382)
			(xy 303.419014 -291.624766) (xy 303.080166 -291.624766) (xy 303.079671 -291.649373) (xy 303.071776 -291.69795)
			(xy 303.056192 -291.744631) (xy 303.033321 -291.788208) (xy 303.003756 -291.827552) (xy 302.968263 -291.861644)
			(xy 302.92776 -291.8896) (xy 302.883298 -291.910698) (xy 302.836027 -291.92439) (xy 302.787172 -291.930322)
			(xy 302.737997 -291.928341) (xy 302.689778 -291.918497) (xy 302.643762 -291.901045) (xy 302.601141 -291.876438)
			(xy 302.56302 -291.845313) (xy 302.530385 -291.808476) (xy 302.504082 -291.76688) (xy 302.484791 -291.721604)
			(xy 302.473014 -291.67382) (xy 302.469054 -291.624766) (xy 302.130206 -291.624766) (xy 302.129711 -291.649373)
			(xy 302.121816 -291.69795) (xy 302.106232 -291.744631) (xy 302.083361 -291.788208) (xy 302.053796 -291.827552)
			(xy 302.018303 -291.861644) (xy 301.9778 -291.8896) (xy 301.933338 -291.910698) (xy 301.886067 -291.92439)
			(xy 301.837212 -291.930322) (xy 301.788037 -291.928341) (xy 301.739818 -291.918497) (xy 301.693802 -291.901045)
			(xy 301.651181 -291.876438) (xy 301.61306 -291.845313) (xy 301.580425 -291.808476) (xy 301.554122 -291.76688)
			(xy 301.534831 -291.721604) (xy 301.523054 -291.67382) (xy 301.519094 -291.624766) (xy 301.179992 -291.624766)
			(xy 301.179497 -291.649373) (xy 301.171602 -291.69795) (xy 301.156018 -291.744631) (xy 301.133147 -291.788208)
			(xy 301.103582 -291.827552) (xy 301.068089 -291.861644) (xy 301.027586 -291.8896) (xy 300.983124 -291.910698)
			(xy 300.935853 -291.92439) (xy 300.886998 -291.930322) (xy 300.837823 -291.928341) (xy 300.789604 -291.918497)
			(xy 300.743588 -291.901045) (xy 300.700967 -291.876438) (xy 300.662846 -291.845313) (xy 300.630211 -291.808476)
			(xy 300.603908 -291.76688) (xy 300.584617 -291.721604) (xy 300.57284 -291.67382) (xy 300.56888 -291.624766)
			(xy 300.230032 -291.624766) (xy 300.229537 -291.649373) (xy 300.221642 -291.69795) (xy 300.206058 -291.744631)
			(xy 300.183187 -291.788208) (xy 300.153622 -291.827552) (xy 300.118129 -291.861644) (xy 300.077626 -291.8896)
			(xy 300.033164 -291.910698) (xy 299.985893 -291.92439) (xy 299.937038 -291.930322) (xy 299.887863 -291.928341)
			(xy 299.839644 -291.918497) (xy 299.793628 -291.901045) (xy 299.751007 -291.876438) (xy 299.712886 -291.845313)
			(xy 299.680251 -291.808476) (xy 299.653948 -291.76688) (xy 299.634657 -291.721604) (xy 299.62288 -291.67382)
			(xy 299.61892 -291.624766) (xy 299.280072 -291.624766) (xy 299.279577 -291.649373) (xy 299.271682 -291.69795)
			(xy 299.256098 -291.744631) (xy 299.233227 -291.788208) (xy 299.203662 -291.827552) (xy 299.168169 -291.861644)
			(xy 299.127666 -291.8896) (xy 299.083204 -291.910698) (xy 299.035933 -291.92439) (xy 298.987078 -291.930322)
			(xy 298.937903 -291.928341) (xy 298.889684 -291.918497) (xy 298.843668 -291.901045) (xy 298.801047 -291.876438)
			(xy 298.762926 -291.845313) (xy 298.730291 -291.808476) (xy 298.703988 -291.76688) (xy 298.684697 -291.721604)
			(xy 298.67292 -291.67382) (xy 298.66896 -291.624766) (xy 298.330112 -291.624766) (xy 298.329617 -291.649373)
			(xy 298.321722 -291.69795) (xy 298.306138 -291.744631) (xy 298.283267 -291.788208) (xy 298.253702 -291.827552)
			(xy 298.218209 -291.861644) (xy 298.177706 -291.8896) (xy 298.133244 -291.910698) (xy 298.085973 -291.92439)
			(xy 298.037118 -291.930322) (xy 297.987943 -291.928341) (xy 297.939724 -291.918497) (xy 297.893708 -291.901045)
			(xy 297.851087 -291.876438) (xy 297.812966 -291.845313) (xy 297.780331 -291.808476) (xy 297.754028 -291.76688)
			(xy 297.734737 -291.721604) (xy 297.72296 -291.67382) (xy 297.719 -291.624766) (xy 297.380152 -291.624766)
			(xy 297.379657 -291.649373) (xy 297.371762 -291.69795) (xy 297.356178 -291.744631) (xy 297.333307 -291.788208)
			(xy 297.303742 -291.827552) (xy 297.268249 -291.861644) (xy 297.227746 -291.8896) (xy 297.183284 -291.910698)
			(xy 297.136013 -291.92439) (xy 297.087158 -291.930322) (xy 297.037983 -291.928341) (xy 296.989764 -291.918497)
			(xy 296.943748 -291.901045) (xy 296.901127 -291.876438) (xy 296.863006 -291.845313) (xy 296.830371 -291.808476)
			(xy 296.804068 -291.76688) (xy 296.784777 -291.721604) (xy 296.773 -291.67382) (xy 296.76904 -291.624766)
			(xy 296.430192 -291.624766) (xy 296.429697 -291.649373) (xy 296.421802 -291.69795) (xy 296.406218 -291.744631)
			(xy 296.383347 -291.788208) (xy 296.353782 -291.827552) (xy 296.318289 -291.861644) (xy 296.277786 -291.8896)
			(xy 296.233324 -291.910698) (xy 296.186053 -291.92439) (xy 296.137198 -291.930322) (xy 296.088023 -291.928341)
			(xy 296.039804 -291.918497) (xy 295.993788 -291.901045) (xy 295.951167 -291.876438) (xy 295.913046 -291.845313)
			(xy 295.880411 -291.808476) (xy 295.854108 -291.76688) (xy 295.834817 -291.721604) (xy 295.82304 -291.67382)
			(xy 295.81908 -291.624766) (xy 295.480232 -291.624766) (xy 295.479737 -291.649373) (xy 295.471842 -291.69795)
			(xy 295.456258 -291.744631) (xy 295.433387 -291.788208) (xy 295.403822 -291.827552) (xy 295.368329 -291.861644)
			(xy 295.327826 -291.8896) (xy 295.283364 -291.910698) (xy 295.236093 -291.92439) (xy 295.187238 -291.930322)
			(xy 295.138063 -291.928341) (xy 295.089844 -291.918497) (xy 295.043828 -291.901045) (xy 295.001207 -291.876438)
			(xy 294.963086 -291.845313) (xy 294.930451 -291.808476) (xy 294.904148 -291.76688) (xy 294.884857 -291.721604)
			(xy 294.87308 -291.67382) (xy 294.86912 -291.624766) (xy 294.530018 -291.624766) (xy 294.529523 -291.649373)
			(xy 294.521628 -291.69795) (xy 294.506044 -291.744631) (xy 294.483173 -291.788208) (xy 294.453608 -291.827552)
			(xy 294.418115 -291.861644) (xy 294.377612 -291.8896) (xy 294.33315 -291.910698) (xy 294.285879 -291.92439)
			(xy 294.237024 -291.930322) (xy 294.187849 -291.928341) (xy 294.13963 -291.918497) (xy 294.093614 -291.901045)
			(xy 294.050993 -291.876438) (xy 294.012872 -291.845313) (xy 293.980237 -291.808476) (xy 293.953934 -291.76688)
			(xy 293.934643 -291.721604) (xy 293.922866 -291.67382) (xy 293.918906 -291.624766) (xy 293.580058 -291.624766)
			(xy 293.579563 -291.649373) (xy 293.571668 -291.69795) (xy 293.556084 -291.744631) (xy 293.533213 -291.788208)
			(xy 293.503648 -291.827552) (xy 293.468155 -291.861644) (xy 293.427652 -291.8896) (xy 293.38319 -291.910698)
			(xy 293.335919 -291.92439) (xy 293.287064 -291.930322) (xy 293.237889 -291.928341) (xy 293.18967 -291.918497)
			(xy 293.143654 -291.901045) (xy 293.101033 -291.876438) (xy 293.062912 -291.845313) (xy 293.030277 -291.808476)
			(xy 293.003974 -291.76688) (xy 292.984683 -291.721604) (xy 292.972906 -291.67382) (xy 292.968946 -291.624766)
			(xy 292.630098 -291.624766) (xy 292.629603 -291.649373) (xy 292.621708 -291.69795) (xy 292.606124 -291.744631)
			(xy 292.583253 -291.788208) (xy 292.553688 -291.827552) (xy 292.518195 -291.861644) (xy 292.477692 -291.8896)
			(xy 292.43323 -291.910698) (xy 292.385959 -291.92439) (xy 292.337104 -291.930322) (xy 292.287929 -291.928341)
			(xy 292.23971 -291.918497) (xy 292.193694 -291.901045) (xy 292.151073 -291.876438) (xy 292.112952 -291.845313)
			(xy 292.080317 -291.808476) (xy 292.054014 -291.76688) (xy 292.034723 -291.721604) (xy 292.022946 -291.67382)
			(xy 292.018986 -291.624766) (xy 290.730178 -291.624766) (xy 290.729683 -291.649373) (xy 290.721788 -291.69795)
			(xy 290.706204 -291.744631) (xy 290.683333 -291.788208) (xy 290.653768 -291.827552) (xy 290.618275 -291.861644)
			(xy 290.577772 -291.8896) (xy 290.53331 -291.910698) (xy 290.486039 -291.92439) (xy 290.437184 -291.930322)
			(xy 290.388009 -291.928341) (xy 290.33979 -291.918497) (xy 290.293774 -291.901045) (xy 290.251153 -291.876438)
			(xy 290.213032 -291.845313) (xy 290.180397 -291.808476) (xy 290.154094 -291.76688) (xy 290.134803 -291.721604)
			(xy 290.123026 -291.67382) (xy 290.119066 -291.624766) (xy 289.780218 -291.624766) (xy 289.779723 -291.649373)
			(xy 289.771828 -291.69795) (xy 289.756244 -291.744631) (xy 289.733373 -291.788208) (xy 289.703808 -291.827552)
			(xy 289.668315 -291.861644) (xy 289.627812 -291.8896) (xy 289.58335 -291.910698) (xy 289.536079 -291.92439)
			(xy 289.487224 -291.930322) (xy 289.438049 -291.928341) (xy 289.38983 -291.918497) (xy 289.343814 -291.901045)
			(xy 289.301193 -291.876438) (xy 289.263072 -291.845313) (xy 289.230437 -291.808476) (xy 289.204134 -291.76688)
			(xy 289.184843 -291.721604) (xy 289.173066 -291.67382) (xy 289.169106 -291.624766) (xy 288.830004 -291.624766)
			(xy 288.829509 -291.649373) (xy 288.821614 -291.69795) (xy 288.80603 -291.744631) (xy 288.783159 -291.788208)
			(xy 288.753594 -291.827552) (xy 288.718101 -291.861644) (xy 288.677598 -291.8896) (xy 288.633136 -291.910698)
			(xy 288.585865 -291.92439) (xy 288.53701 -291.930322) (xy 288.487835 -291.928341) (xy 288.439616 -291.918497)
			(xy 288.3936 -291.901045) (xy 288.350979 -291.876438) (xy 288.312858 -291.845313) (xy 288.280223 -291.808476)
			(xy 288.25392 -291.76688) (xy 288.234629 -291.721604) (xy 288.222852 -291.67382) (xy 288.218892 -291.624766)
			(xy 287.880044 -291.624766) (xy 287.879549 -291.649373) (xy 287.871654 -291.69795) (xy 287.85607 -291.744631)
			(xy 287.833199 -291.788208) (xy 287.803634 -291.827552) (xy 287.768141 -291.861644) (xy 287.727638 -291.8896)
			(xy 287.683176 -291.910698) (xy 287.635905 -291.92439) (xy 287.58705 -291.930322) (xy 287.537875 -291.928341)
			(xy 287.489656 -291.918497) (xy 287.44364 -291.901045) (xy 287.401019 -291.876438) (xy 287.362898 -291.845313)
			(xy 287.330263 -291.808476) (xy 287.30396 -291.76688) (xy 287.284669 -291.721604) (xy 287.272892 -291.67382)
			(xy 287.268932 -291.624766) (xy 286.930084 -291.624766) (xy 286.929589 -291.649373) (xy 286.921694 -291.69795)
			(xy 286.90611 -291.744631) (xy 286.883239 -291.788208) (xy 286.853674 -291.827552) (xy 286.818181 -291.861644)
			(xy 286.777678 -291.8896) (xy 286.733216 -291.910698) (xy 286.685945 -291.92439) (xy 286.63709 -291.930322)
			(xy 286.587915 -291.928341) (xy 286.539696 -291.918497) (xy 286.49368 -291.901045) (xy 286.451059 -291.876438)
			(xy 286.412938 -291.845313) (xy 286.380303 -291.808476) (xy 286.354 -291.76688) (xy 286.334709 -291.721604)
			(xy 286.322932 -291.67382) (xy 286.318972 -291.624766) (xy 285.980124 -291.624766) (xy 285.979629 -291.649373)
			(xy 285.971734 -291.69795) (xy 285.95615 -291.744631) (xy 285.933279 -291.788208) (xy 285.903714 -291.827552)
			(xy 285.868221 -291.861644) (xy 285.827718 -291.8896) (xy 285.783256 -291.910698) (xy 285.735985 -291.92439)
			(xy 285.68713 -291.930322) (xy 285.637955 -291.928341) (xy 285.589736 -291.918497) (xy 285.54372 -291.901045)
			(xy 285.501099 -291.876438) (xy 285.462978 -291.845313) (xy 285.430343 -291.808476) (xy 285.40404 -291.76688)
			(xy 285.384749 -291.721604) (xy 285.372972 -291.67382) (xy 285.369012 -291.624766) (xy 285.030164 -291.624766)
			(xy 285.029669 -291.649373) (xy 285.021774 -291.69795) (xy 285.00619 -291.744631) (xy 284.983319 -291.788208)
			(xy 284.953754 -291.827552) (xy 284.918261 -291.861644) (xy 284.877758 -291.8896) (xy 284.833296 -291.910698)
			(xy 284.786025 -291.92439) (xy 284.73717 -291.930322) (xy 284.687995 -291.928341) (xy 284.639776 -291.918497)
			(xy 284.59376 -291.901045) (xy 284.551139 -291.876438) (xy 284.513018 -291.845313) (xy 284.480383 -291.808476)
			(xy 284.45408 -291.76688) (xy 284.434789 -291.721604) (xy 284.423012 -291.67382) (xy 284.419052 -291.624766)
			(xy 284.080204 -291.624766) (xy 284.079709 -291.649373) (xy 284.071814 -291.69795) (xy 284.05623 -291.744631)
			(xy 284.033359 -291.788208) (xy 284.003794 -291.827552) (xy 283.968301 -291.861644) (xy 283.927798 -291.8896)
			(xy 283.883336 -291.910698) (xy 283.836065 -291.92439) (xy 283.78721 -291.930322) (xy 283.738035 -291.928341)
			(xy 283.689816 -291.918497) (xy 283.6438 -291.901045) (xy 283.601179 -291.876438) (xy 283.563058 -291.845313)
			(xy 283.530423 -291.808476) (xy 283.50412 -291.76688) (xy 283.484829 -291.721604) (xy 283.473052 -291.67382)
			(xy 283.469092 -291.624766) (xy 283.130244 -291.624766) (xy 283.129749 -291.649373) (xy 283.121854 -291.69795)
			(xy 283.10627 -291.744631) (xy 283.083399 -291.788208) (xy 283.053834 -291.827552) (xy 283.018341 -291.861644)
			(xy 282.977838 -291.8896) (xy 282.933376 -291.910698) (xy 282.886105 -291.92439) (xy 282.83725 -291.930322)
			(xy 282.788075 -291.928341) (xy 282.739856 -291.918497) (xy 282.69384 -291.901045) (xy 282.651219 -291.876438)
			(xy 282.613098 -291.845313) (xy 282.580463 -291.808476) (xy 282.55416 -291.76688) (xy 282.534869 -291.721604)
			(xy 282.523092 -291.67382) (xy 282.519132 -291.624766) (xy 282.18003 -291.624766) (xy 282.179535 -291.649373)
			(xy 282.17164 -291.69795) (xy 282.156056 -291.744631) (xy 282.133185 -291.788208) (xy 282.10362 -291.827552)
			(xy 282.068127 -291.861644) (xy 282.027624 -291.8896) (xy 281.983162 -291.910698) (xy 281.935891 -291.92439)
			(xy 281.887036 -291.930322) (xy 281.837861 -291.928341) (xy 281.789642 -291.918497) (xy 281.743626 -291.901045)
			(xy 281.701005 -291.876438) (xy 281.662884 -291.845313) (xy 281.630249 -291.808476) (xy 281.603946 -291.76688)
			(xy 281.584655 -291.721604) (xy 281.572878 -291.67382) (xy 281.568918 -291.624766) (xy 281.23007 -291.624766)
			(xy 281.229575 -291.649373) (xy 281.22168 -291.69795) (xy 281.206096 -291.744631) (xy 281.183225 -291.788208)
			(xy 281.15366 -291.827552) (xy 281.118167 -291.861644) (xy 281.077664 -291.8896) (xy 281.033202 -291.910698)
			(xy 280.985931 -291.92439) (xy 280.937076 -291.930322) (xy 280.887901 -291.928341) (xy 280.839682 -291.918497)
			(xy 280.793666 -291.901045) (xy 280.751045 -291.876438) (xy 280.712924 -291.845313) (xy 280.680289 -291.808476)
			(xy 280.653986 -291.76688) (xy 280.634695 -291.721604) (xy 280.622918 -291.67382) (xy 280.618958 -291.624766)
			(xy 280.28011 -291.624766) (xy 280.279615 -291.649373) (xy 280.27172 -291.69795) (xy 280.256136 -291.744631)
			(xy 280.233265 -291.788208) (xy 280.2037 -291.827552) (xy 280.168207 -291.861644) (xy 280.127704 -291.8896)
			(xy 280.083242 -291.910698) (xy 280.035971 -291.92439) (xy 279.987116 -291.930322) (xy 279.937941 -291.928341)
			(xy 279.889722 -291.918497) (xy 279.843706 -291.901045) (xy 279.801085 -291.876438) (xy 279.762964 -291.845313)
			(xy 279.730329 -291.808476) (xy 279.704026 -291.76688) (xy 279.684735 -291.721604) (xy 279.672958 -291.67382)
			(xy 279.668998 -291.624766) (xy 278.38019 -291.624766) (xy 278.379695 -291.649373) (xy 278.3718 -291.69795)
			(xy 278.356216 -291.744631) (xy 278.333345 -291.788208) (xy 278.30378 -291.827552) (xy 278.268287 -291.861644)
			(xy 278.227784 -291.8896) (xy 278.183322 -291.910698) (xy 278.136051 -291.92439) (xy 278.087196 -291.930322)
			(xy 278.038021 -291.928341) (xy 277.989802 -291.918497) (xy 277.943786 -291.901045) (xy 277.901165 -291.876438)
			(xy 277.863044 -291.845313) (xy 277.830409 -291.808476) (xy 277.804106 -291.76688) (xy 277.784815 -291.721604)
			(xy 277.773038 -291.67382) (xy 277.769078 -291.624766) (xy 277.43023 -291.624766) (xy 277.429735 -291.649373)
			(xy 277.42184 -291.69795) (xy 277.406256 -291.744631) (xy 277.383385 -291.788208) (xy 277.35382 -291.827552)
			(xy 277.318327 -291.861644) (xy 277.277824 -291.8896) (xy 277.233362 -291.910698) (xy 277.186091 -291.92439)
			(xy 277.137236 -291.930322) (xy 277.088061 -291.928341) (xy 277.039842 -291.918497) (xy 276.993826 -291.901045)
			(xy 276.951205 -291.876438) (xy 276.913084 -291.845313) (xy 276.880449 -291.808476) (xy 276.854146 -291.76688)
			(xy 276.834855 -291.721604) (xy 276.823078 -291.67382) (xy 276.819118 -291.624766) (xy 276.480016 -291.624766)
			(xy 276.479521 -291.649373) (xy 276.471626 -291.69795) (xy 276.456042 -291.744631) (xy 276.433171 -291.788208)
			(xy 276.403606 -291.827552) (xy 276.368113 -291.861644) (xy 276.32761 -291.8896) (xy 276.283148 -291.910698)
			(xy 276.235877 -291.92439) (xy 276.187022 -291.930322) (xy 276.137847 -291.928341) (xy 276.089628 -291.918497)
			(xy 276.043612 -291.901045) (xy 276.000991 -291.876438) (xy 275.96287 -291.845313) (xy 275.930235 -291.808476)
			(xy 275.903932 -291.76688) (xy 275.884641 -291.721604) (xy 275.872864 -291.67382) (xy 275.868904 -291.624766)
			(xy 275.530056 -291.624766) (xy 275.529561 -291.649373) (xy 275.521666 -291.69795) (xy 275.506082 -291.744631)
			(xy 275.483211 -291.788208) (xy 275.453646 -291.827552) (xy 275.418153 -291.861644) (xy 275.37765 -291.8896)
			(xy 275.333188 -291.910698) (xy 275.285917 -291.92439) (xy 275.237062 -291.930322) (xy 275.187887 -291.928341)
			(xy 275.139668 -291.918497) (xy 275.093652 -291.901045) (xy 275.051031 -291.876438) (xy 275.01291 -291.845313)
			(xy 274.980275 -291.808476) (xy 274.953972 -291.76688) (xy 274.934681 -291.721604) (xy 274.922904 -291.67382)
			(xy 274.918944 -291.624766) (xy 274.580096 -291.624766) (xy 274.579601 -291.649373) (xy 274.571706 -291.69795)
			(xy 274.556122 -291.744631) (xy 274.533251 -291.788208) (xy 274.503686 -291.827552) (xy 274.468193 -291.861644)
			(xy 274.42769 -291.8896) (xy 274.383228 -291.910698) (xy 274.335957 -291.92439) (xy 274.287102 -291.930322)
			(xy 274.237927 -291.928341) (xy 274.189708 -291.918497) (xy 274.143692 -291.901045) (xy 274.101071 -291.876438)
			(xy 274.06295 -291.845313) (xy 274.030315 -291.808476) (xy 274.004012 -291.76688) (xy 273.984721 -291.721604)
			(xy 273.972944 -291.67382) (xy 273.968984 -291.624766) (xy 273.630136 -291.624766) (xy 273.629641 -291.649373)
			(xy 273.621746 -291.69795) (xy 273.606162 -291.744631) (xy 273.583291 -291.788208) (xy 273.553726 -291.827552)
			(xy 273.518233 -291.861644) (xy 273.47773 -291.8896) (xy 273.433268 -291.910698) (xy 273.385997 -291.92439)
			(xy 273.337142 -291.930322) (xy 273.287967 -291.928341) (xy 273.239748 -291.918497) (xy 273.193732 -291.901045)
			(xy 273.151111 -291.876438) (xy 273.11299 -291.845313) (xy 273.080355 -291.808476) (xy 273.054052 -291.76688)
			(xy 273.034761 -291.721604) (xy 273.022984 -291.67382) (xy 273.019024 -291.624766) (xy 270.780256 -291.624766)
			(xy 270.779761 -291.649373) (xy 270.771866 -291.69795) (xy 270.756282 -291.744631) (xy 270.733411 -291.788208)
			(xy 270.703846 -291.827552) (xy 270.668353 -291.861644) (xy 270.62785 -291.8896) (xy 270.583388 -291.910698)
			(xy 270.536117 -291.92439) (xy 270.487262 -291.930322) (xy 270.438087 -291.928341) (xy 270.389868 -291.918497)
			(xy 270.343852 -291.901045) (xy 270.301231 -291.876438) (xy 270.26311 -291.845313) (xy 270.230475 -291.808476)
			(xy 270.204172 -291.76688) (xy 270.184881 -291.721604) (xy 270.173104 -291.67382) (xy 270.169144 -291.624766)
			(xy 269.830042 -291.624766) (xy 269.829547 -291.649373) (xy 269.821652 -291.69795) (xy 269.806068 -291.744631)
			(xy 269.783197 -291.788208) (xy 269.753632 -291.827552) (xy 269.718139 -291.861644) (xy 269.677636 -291.8896)
			(xy 269.633174 -291.910698) (xy 269.585903 -291.92439) (xy 269.537048 -291.930322) (xy 269.487873 -291.928341)
			(xy 269.439654 -291.918497) (xy 269.393638 -291.901045) (xy 269.351017 -291.876438) (xy 269.312896 -291.845313)
			(xy 269.280261 -291.808476) (xy 269.253958 -291.76688) (xy 269.234667 -291.721604) (xy 269.22289 -291.67382)
			(xy 269.21893 -291.624766) (xy 268.880082 -291.624766) (xy 268.879587 -291.649373) (xy 268.871692 -291.69795)
			(xy 268.856108 -291.744631) (xy 268.833237 -291.788208) (xy 268.803672 -291.827552) (xy 268.768179 -291.861644)
			(xy 268.727676 -291.8896) (xy 268.683214 -291.910698) (xy 268.635943 -291.92439) (xy 268.587088 -291.930322)
			(xy 268.537913 -291.928341) (xy 268.489694 -291.918497) (xy 268.443678 -291.901045) (xy 268.401057 -291.876438)
			(xy 268.362936 -291.845313) (xy 268.330301 -291.808476) (xy 268.303998 -291.76688) (xy 268.284707 -291.721604)
			(xy 268.27293 -291.67382) (xy 268.26897 -291.624766) (xy 260.206856 -291.624766) (xy 260.180942 -291.663935)
			(xy 260.143725 -291.705472) (xy 260.100857 -291.741147) (xy 260.053251 -291.770201) (xy 260.001922 -291.792013)
			(xy 259.947965 -291.806119) (xy 259.892528 -291.812219) (xy 259.836794 -291.810182) (xy 259.781951 -291.800052)
			(xy 259.729167 -291.782045) (xy 259.679567 -291.756544) (xy 259.634209 -291.724093) (xy 259.59406 -291.685384)
			(xy 259.559974 -291.641241) (xy 259.532678 -291.592606) (xy 259.512755 -291.540515) (xy 259.500629 -291.486078)
			(xy 259.496558 -291.430456) (xy 258.774946 -291.430456) (xy 258.774437 -291.458342) (xy 258.766317 -291.513518)
			(xy 258.750249 -291.566925) (xy 258.726577 -291.617422) (xy 258.695804 -291.663935) (xy 258.658587 -291.705472)
			(xy 258.615719 -291.741147) (xy 258.568113 -291.770201) (xy 258.516784 -291.792013) (xy 258.462827 -291.806119)
			(xy 258.40739 -291.812219) (xy 258.351656 -291.810182) (xy 258.296813 -291.800052) (xy 258.244029 -291.782045)
			(xy 258.194429 -291.756544) (xy 258.149071 -291.724093) (xy 258.108922 -291.685384) (xy 258.074836 -291.641241)
			(xy 258.04754 -291.592606) (xy 258.027617 -291.540515) (xy 258.015491 -291.486078) (xy 258.01142 -291.430456)
			(xy 249.737118 -291.430456) (xy 249.737118 -292.732714) (xy 258.01142 -292.732714) (xy 258.015491 -292.677092)
			(xy 258.027617 -292.622655) (xy 258.04754 -292.570564) (xy 258.074836 -292.521929) (xy 258.108922 -292.477786)
			(xy 258.149071 -292.439077) (xy 258.194429 -292.406626) (xy 258.244029 -292.381125) (xy 258.296813 -292.363118)
			(xy 258.351656 -292.352988) (xy 258.40739 -292.350951) (xy 258.462827 -292.357051) (xy 258.516784 -292.371157)
			(xy 258.568113 -292.392969) (xy 258.615719 -292.422023) (xy 258.658587 -292.457698) (xy 258.695804 -292.499235)
			(xy 258.726577 -292.545748) (xy 258.750249 -292.596245) (xy 258.766317 -292.649652) (xy 258.774437 -292.704828)
			(xy 258.774946 -292.732714) (xy 259.486906 -292.732714) (xy 259.490977 -292.677092) (xy 259.503103 -292.622655)
			(xy 259.523026 -292.570564) (xy 259.550322 -292.521929) (xy 259.584408 -292.477786) (xy 259.624557 -292.439077)
			(xy 259.669915 -292.406626) (xy 259.719515 -292.381125) (xy 259.772299 -292.363118) (xy 259.827142 -292.352988)
			(xy 259.882876 -292.350951) (xy 259.938313 -292.357051) (xy 259.99227 -292.371157) (xy 260.043599 -292.392969)
			(xy 260.091205 -292.422023) (xy 260.134073 -292.457698) (xy 260.17129 -292.499235) (xy 260.202063 -292.545748)
			(xy 260.225735 -292.596245) (xy 260.241803 -292.649652) (xy 260.249923 -292.704828) (xy 260.250432 -292.732714)
			(xy 260.375906 -292.732714) (xy 260.379977 -292.677092) (xy 260.392103 -292.622655) (xy 260.412026 -292.570564)
			(xy 260.439322 -292.521929) (xy 260.473408 -292.477786) (xy 260.513557 -292.439077) (xy 260.558915 -292.406626)
			(xy 260.608515 -292.381125) (xy 260.661299 -292.363118) (xy 260.716142 -292.352988) (xy 260.771876 -292.350951)
			(xy 260.827313 -292.357051) (xy 260.88127 -292.371157) (xy 260.932599 -292.392969) (xy 260.980205 -292.422023)
			(xy 261.023073 -292.457698) (xy 261.06029 -292.499235) (xy 261.091063 -292.545748) (xy 261.114735 -292.596245)
			(xy 261.130803 -292.649652) (xy 261.138923 -292.704828) (xy 261.139432 -292.732714) (xy 261.138923 -292.7606)
			(xy 261.130803 -292.815776) (xy 261.114735 -292.869183) (xy 261.091063 -292.91968) (xy 261.06029 -292.966193)
			(xy 261.023073 -293.00773) (xy 260.980205 -293.043405) (xy 260.932599 -293.072459) (xy 260.88127 -293.094271)
			(xy 260.827313 -293.108377) (xy 260.771876 -293.114477) (xy 260.716142 -293.11244) (xy 260.661299 -293.10231)
			(xy 260.608515 -293.084303) (xy 260.558915 -293.058802) (xy 260.513557 -293.026351) (xy 260.473408 -292.987642)
			(xy 260.439322 -292.943499) (xy 260.412026 -292.894864) (xy 260.392103 -292.842773) (xy 260.379977 -292.788336)
			(xy 260.375906 -292.732714) (xy 260.250432 -292.732714) (xy 260.249923 -292.7606) (xy 260.241803 -292.815776)
			(xy 260.225735 -292.869183) (xy 260.202063 -292.91968) (xy 260.17129 -292.966193) (xy 260.134073 -293.00773)
			(xy 260.091205 -293.043405) (xy 260.043599 -293.072459) (xy 259.99227 -293.094271) (xy 259.938313 -293.108377)
			(xy 259.882876 -293.114477) (xy 259.827142 -293.11244) (xy 259.772299 -293.10231) (xy 259.719515 -293.084303)
			(xy 259.669915 -293.058802) (xy 259.624557 -293.026351) (xy 259.584408 -292.987642) (xy 259.550322 -292.943499)
			(xy 259.523026 -292.894864) (xy 259.503103 -292.842773) (xy 259.490977 -292.788336) (xy 259.486906 -292.732714)
			(xy 258.774946 -292.732714) (xy 258.774437 -292.7606) (xy 258.766317 -292.815776) (xy 258.750249 -292.869183)
			(xy 258.726577 -292.91968) (xy 258.695804 -292.966193) (xy 258.658587 -293.00773) (xy 258.615719 -293.043405)
			(xy 258.568113 -293.072459) (xy 258.516784 -293.094271) (xy 258.462827 -293.108377) (xy 258.40739 -293.114477)
			(xy 258.351656 -293.11244) (xy 258.296813 -293.10231) (xy 258.244029 -293.084303) (xy 258.194429 -293.058802)
			(xy 258.149071 -293.026351) (xy 258.108922 -292.987642) (xy 258.074836 -292.943499) (xy 258.04754 -292.894864)
			(xy 258.027617 -292.842773) (xy 258.015491 -292.788336) (xy 258.01142 -292.732714) (xy 249.737118 -292.732714)
			(xy 249.737118 -293.494714) (xy 263.537954 -293.494714) (xy 263.53852 -293.465333) (xy 263.547548 -293.407268)
			(xy 263.565376 -293.351275) (xy 263.591583 -293.29868) (xy 263.625547 -293.250728) (xy 263.666466 -293.208554)
			(xy 263.689592 -293.190422) (xy 263.69899 -293.183056) (xy 263.709404 -293.162482) (xy 263.710928 -293.058596)
			(xy 263.701022 -293.037514) (xy 263.691878 -293.030148) (xy 263.670018 -293.011956) (xy 263.63148 -292.970133)
			(xy 263.599575 -292.923055) (xy 263.57501 -292.871763) (xy 263.558329 -292.817393) (xy 263.549902 -292.76115)
			(xy 263.549384 -292.732714) (xy 263.54987 -292.705463) (xy 263.557626 -292.651515) (xy 263.572981 -292.59922)
			(xy 263.595623 -292.549643) (xy 263.625089 -292.503793) (xy 263.66078 -292.462602) (xy 263.701971 -292.426911)
			(xy 263.747821 -292.397445) (xy 263.797398 -292.374803) (xy 263.849693 -292.359448) (xy 263.903641 -292.351692)
			(xy 263.958143 -292.351692) (xy 264.012091 -292.359448) (xy 264.064386 -292.374803) (xy 264.113963 -292.397445)
			(xy 264.159813 -292.426911) (xy 264.201004 -292.462602) (xy 264.236695 -292.503793) (xy 264.266161 -292.549643)
			(xy 264.277733 -292.57498) (xy 268.26897 -292.57498) (xy 268.27293 -292.525926) (xy 268.284707 -292.478142)
			(xy 268.303998 -292.432866) (xy 268.330301 -292.39127) (xy 268.362936 -292.354433) (xy 268.401057 -292.323308)
			(xy 268.443678 -292.298701) (xy 268.489694 -292.281249) (xy 268.537913 -292.271405) (xy 268.587088 -292.269424)
			(xy 268.635943 -292.275356) (xy 268.683214 -292.289048) (xy 268.727676 -292.310146) (xy 268.768179 -292.338102)
			(xy 268.803672 -292.372194) (xy 268.833237 -292.411538) (xy 268.856108 -292.455115) (xy 268.871692 -292.501796)
			(xy 268.879587 -292.550373) (xy 268.880082 -292.57498) (xy 269.21893 -292.57498) (xy 269.22289 -292.525926)
			(xy 269.234667 -292.478142) (xy 269.253958 -292.432866) (xy 269.280261 -292.39127) (xy 269.312896 -292.354433)
			(xy 269.351017 -292.323308) (xy 269.393638 -292.298701) (xy 269.439654 -292.281249) (xy 269.487873 -292.271405)
			(xy 269.537048 -292.269424) (xy 269.585903 -292.275356) (xy 269.633174 -292.289048) (xy 269.677636 -292.310146)
			(xy 269.718139 -292.338102) (xy 269.753632 -292.372194) (xy 269.783197 -292.411538) (xy 269.806068 -292.455115)
			(xy 269.821652 -292.501796) (xy 269.829547 -292.550373) (xy 269.830042 -292.57498) (xy 270.169144 -292.57498)
			(xy 270.173104 -292.525926) (xy 270.184881 -292.478142) (xy 270.204172 -292.432866) (xy 270.230475 -292.39127)
			(xy 270.26311 -292.354433) (xy 270.301231 -292.323308) (xy 270.343852 -292.298701) (xy 270.389868 -292.281249)
			(xy 270.438087 -292.271405) (xy 270.487262 -292.269424) (xy 270.536117 -292.275356) (xy 270.583388 -292.289048)
			(xy 270.62785 -292.310146) (xy 270.668353 -292.338102) (xy 270.703846 -292.372194) (xy 270.733411 -292.411538)
			(xy 270.756282 -292.455115) (xy 270.771866 -292.501796) (xy 270.779761 -292.550373) (xy 270.780251 -292.574726)
			(xy 271.119104 -292.574726) (xy 271.123064 -292.525672) (xy 271.134841 -292.477888) (xy 271.154132 -292.432612)
			(xy 271.180435 -292.391016) (xy 271.21307 -292.354179) (xy 271.251191 -292.323054) (xy 271.293812 -292.298447)
			(xy 271.339828 -292.280995) (xy 271.388047 -292.271151) (xy 271.437222 -292.26917) (xy 271.486077 -292.275102)
			(xy 271.533348 -292.288794) (xy 271.57781 -292.309892) (xy 271.618313 -292.337848) (xy 271.653806 -292.37194)
			(xy 271.683371 -292.411284) (xy 271.706242 -292.454861) (xy 271.721826 -292.501542) (xy 271.729721 -292.550119)
			(xy 271.730216 -292.574726) (xy 272.069064 -292.574726) (xy 272.073024 -292.525672) (xy 272.084801 -292.477888)
			(xy 272.104092 -292.432612) (xy 272.130395 -292.391016) (xy 272.16303 -292.354179) (xy 272.201151 -292.323054)
			(xy 272.243772 -292.298447) (xy 272.289788 -292.280995) (xy 272.338007 -292.271151) (xy 272.387182 -292.26917)
			(xy 272.436037 -292.275102) (xy 272.483308 -292.288794) (xy 272.52777 -292.309892) (xy 272.568273 -292.337848)
			(xy 272.603766 -292.37194) (xy 272.633331 -292.411284) (xy 272.656202 -292.454861) (xy 272.671786 -292.501542)
			(xy 272.679681 -292.550119) (xy 272.680176 -292.574726) (xy 272.680171 -292.57498) (xy 273.019024 -292.57498)
			(xy 273.022984 -292.525926) (xy 273.034761 -292.478142) (xy 273.054052 -292.432866) (xy 273.080355 -292.39127)
			(xy 273.11299 -292.354433) (xy 273.151111 -292.323308) (xy 273.193732 -292.298701) (xy 273.239748 -292.281249)
			(xy 273.287967 -292.271405) (xy 273.337142 -292.269424) (xy 273.385997 -292.275356) (xy 273.433268 -292.289048)
			(xy 273.47773 -292.310146) (xy 273.518233 -292.338102) (xy 273.553726 -292.372194) (xy 273.583291 -292.411538)
			(xy 273.606162 -292.455115) (xy 273.621746 -292.501796) (xy 273.629641 -292.550373) (xy 273.630136 -292.57498)
			(xy 273.629641 -292.599587) (xy 273.629309 -292.601629) (xy 273.919178 -292.601629) (xy 273.919178 -292.548331)
			(xy 273.927121 -292.495627) (xy 273.942831 -292.444697) (xy 273.965957 -292.396676) (xy 273.995981 -292.352639)
			(xy 274.032233 -292.313568) (xy 274.073904 -292.280337) (xy 274.120062 -292.253688) (xy 274.169676 -292.234216)
			(xy 274.221638 -292.222356) (xy 274.274788 -292.218373) (xy 274.327938 -292.222356) (xy 274.3799 -292.234216)
			(xy 274.429514 -292.253688) (xy 274.475672 -292.280337) (xy 274.517343 -292.313568) (xy 274.553595 -292.352639)
			(xy 274.583619 -292.396676) (xy 274.606745 -292.444697) (xy 274.622455 -292.495627) (xy 274.630398 -292.548331)
			(xy 274.630896 -292.57498) (xy 274.918944 -292.57498) (xy 274.922904 -292.525926) (xy 274.934681 -292.478142)
			(xy 274.953972 -292.432866) (xy 274.980275 -292.39127) (xy 275.01291 -292.354433) (xy 275.051031 -292.323308)
			(xy 275.093652 -292.298701) (xy 275.139668 -292.281249) (xy 275.187887 -292.271405) (xy 275.237062 -292.269424)
			(xy 275.285917 -292.275356) (xy 275.333188 -292.289048) (xy 275.37765 -292.310146) (xy 275.418153 -292.338102)
			(xy 275.453646 -292.372194) (xy 275.483211 -292.411538) (xy 275.506082 -292.455115) (xy 275.521666 -292.501796)
			(xy 275.529561 -292.550373) (xy 275.530056 -292.57498) (xy 275.868904 -292.57498) (xy 275.872864 -292.525926)
			(xy 275.884641 -292.478142) (xy 275.903932 -292.432866) (xy 275.930235 -292.39127) (xy 275.96287 -292.354433)
			(xy 276.000991 -292.323308) (xy 276.043612 -292.298701) (xy 276.089628 -292.281249) (xy 276.137847 -292.271405)
			(xy 276.187022 -292.269424) (xy 276.235877 -292.275356) (xy 276.283148 -292.289048) (xy 276.32761 -292.310146)
			(xy 276.368113 -292.338102) (xy 276.403606 -292.372194) (xy 276.433171 -292.411538) (xy 276.456042 -292.455115)
			(xy 276.471626 -292.501796) (xy 276.479521 -292.550373) (xy 276.480016 -292.57498) (xy 276.819118 -292.57498)
			(xy 276.823078 -292.525926) (xy 276.834855 -292.478142) (xy 276.854146 -292.432866) (xy 276.880449 -292.39127)
			(xy 276.913084 -292.354433) (xy 276.951205 -292.323308) (xy 276.993826 -292.298701) (xy 277.039842 -292.281249)
			(xy 277.088061 -292.271405) (xy 277.137236 -292.269424) (xy 277.186091 -292.275356) (xy 277.233362 -292.289048)
			(xy 277.277824 -292.310146) (xy 277.318327 -292.338102) (xy 277.35382 -292.372194) (xy 277.383385 -292.411538)
			(xy 277.406256 -292.455115) (xy 277.42184 -292.501796) (xy 277.429735 -292.550373) (xy 277.43023 -292.57498)
			(xy 277.769078 -292.57498) (xy 277.773038 -292.525926) (xy 277.784815 -292.478142) (xy 277.804106 -292.432866)
			(xy 277.830409 -292.39127) (xy 277.863044 -292.354433) (xy 277.901165 -292.323308) (xy 277.943786 -292.298701)
			(xy 277.989802 -292.281249) (xy 278.038021 -292.271405) (xy 278.087196 -292.269424) (xy 278.136051 -292.275356)
			(xy 278.183322 -292.289048) (xy 278.227784 -292.310146) (xy 278.268287 -292.338102) (xy 278.30378 -292.372194)
			(xy 278.333345 -292.411538) (xy 278.356216 -292.455115) (xy 278.3718 -292.501796) (xy 278.379695 -292.550373)
			(xy 278.38019 -292.57498) (xy 278.719038 -292.57498) (xy 278.722998 -292.525926) (xy 278.734775 -292.478142)
			(xy 278.754066 -292.432866) (xy 278.780369 -292.39127) (xy 278.813004 -292.354433) (xy 278.851125 -292.323308)
			(xy 278.893746 -292.298701) (xy 278.939762 -292.281249) (xy 278.987981 -292.271405) (xy 279.037156 -292.269424)
			(xy 279.086011 -292.275356) (xy 279.133282 -292.289048) (xy 279.177744 -292.310146) (xy 279.218247 -292.338102)
			(xy 279.25374 -292.372194) (xy 279.283305 -292.411538) (xy 279.306176 -292.455115) (xy 279.32176 -292.501796)
			(xy 279.329655 -292.550373) (xy 279.33015 -292.57498) (xy 279.668998 -292.57498) (xy 279.672958 -292.525926)
			(xy 279.684735 -292.478142) (xy 279.704026 -292.432866) (xy 279.730329 -292.39127) (xy 279.762964 -292.354433)
			(xy 279.801085 -292.323308) (xy 279.843706 -292.298701) (xy 279.889722 -292.281249) (xy 279.937941 -292.271405)
			(xy 279.987116 -292.269424) (xy 280.035971 -292.275356) (xy 280.083242 -292.289048) (xy 280.127704 -292.310146)
			(xy 280.168207 -292.338102) (xy 280.2037 -292.372194) (xy 280.233265 -292.411538) (xy 280.256136 -292.455115)
			(xy 280.27172 -292.501796) (xy 280.279615 -292.550373) (xy 280.280105 -292.574726) (xy 280.618958 -292.574726)
			(xy 280.622918 -292.525672) (xy 280.634695 -292.477888) (xy 280.653986 -292.432612) (xy 280.680289 -292.391016)
			(xy 280.712924 -292.354179) (xy 280.751045 -292.323054) (xy 280.793666 -292.298447) (xy 280.839682 -292.280995)
			(xy 280.887901 -292.271151) (xy 280.937076 -292.26917) (xy 280.985931 -292.275102) (xy 281.033202 -292.288794)
			(xy 281.077664 -292.309892) (xy 281.118167 -292.337848) (xy 281.15366 -292.37194) (xy 281.183225 -292.411284)
			(xy 281.206096 -292.454861) (xy 281.22168 -292.501542) (xy 281.229575 -292.550119) (xy 281.23007 -292.574726)
			(xy 281.568918 -292.574726) (xy 281.572878 -292.525672) (xy 281.584655 -292.477888) (xy 281.603946 -292.432612)
			(xy 281.630249 -292.391016) (xy 281.662884 -292.354179) (xy 281.701005 -292.323054) (xy 281.743626 -292.298447)
			(xy 281.789642 -292.280995) (xy 281.837861 -292.271151) (xy 281.887036 -292.26917) (xy 281.935891 -292.275102)
			(xy 281.983162 -292.288794) (xy 282.027624 -292.309892) (xy 282.068127 -292.337848) (xy 282.10362 -292.37194)
			(xy 282.133185 -292.411284) (xy 282.156056 -292.454861) (xy 282.17164 -292.501542) (xy 282.179535 -292.550119)
			(xy 282.18003 -292.574726) (xy 282.180025 -292.57498) (xy 282.519132 -292.57498) (xy 282.523092 -292.525926)
			(xy 282.534869 -292.478142) (xy 282.55416 -292.432866) (xy 282.580463 -292.39127) (xy 282.613098 -292.354433)
			(xy 282.651219 -292.323308) (xy 282.69384 -292.298701) (xy 282.739856 -292.281249) (xy 282.788075 -292.271405)
			(xy 282.83725 -292.269424) (xy 282.886105 -292.275356) (xy 282.933376 -292.289048) (xy 282.977838 -292.310146)
			(xy 283.018341 -292.338102) (xy 283.053834 -292.372194) (xy 283.083399 -292.411538) (xy 283.10627 -292.455115)
			(xy 283.121854 -292.501796) (xy 283.129749 -292.550373) (xy 283.130244 -292.57498) (xy 283.469092 -292.57498)
			(xy 283.473052 -292.525926) (xy 283.484829 -292.478142) (xy 283.50412 -292.432866) (xy 283.530423 -292.39127)
			(xy 283.563058 -292.354433) (xy 283.601179 -292.323308) (xy 283.6438 -292.298701) (xy 283.689816 -292.281249)
			(xy 283.738035 -292.271405) (xy 283.78721 -292.269424) (xy 283.836065 -292.275356) (xy 283.883336 -292.289048)
			(xy 283.927798 -292.310146) (xy 283.968301 -292.338102) (xy 284.003794 -292.372194) (xy 284.033359 -292.411538)
			(xy 284.05623 -292.455115) (xy 284.071814 -292.501796) (xy 284.079709 -292.550373) (xy 284.080204 -292.57498)
			(xy 284.419052 -292.57498) (xy 284.423012 -292.525926) (xy 284.434789 -292.478142) (xy 284.45408 -292.432866)
			(xy 284.480383 -292.39127) (xy 284.513018 -292.354433) (xy 284.551139 -292.323308) (xy 284.59376 -292.298701)
			(xy 284.639776 -292.281249) (xy 284.687995 -292.271405) (xy 284.73717 -292.269424) (xy 284.786025 -292.275356)
			(xy 284.833296 -292.289048) (xy 284.877758 -292.310146) (xy 284.918261 -292.338102) (xy 284.953754 -292.372194)
			(xy 284.983319 -292.411538) (xy 285.00619 -292.455115) (xy 285.021774 -292.501796) (xy 285.029669 -292.550373)
			(xy 285.030164 -292.57498) (xy 285.369012 -292.57498) (xy 285.372972 -292.525926) (xy 285.384749 -292.478142)
			(xy 285.40404 -292.432866) (xy 285.430343 -292.39127) (xy 285.462978 -292.354433) (xy 285.501099 -292.323308)
			(xy 285.54372 -292.298701) (xy 285.589736 -292.281249) (xy 285.637955 -292.271405) (xy 285.68713 -292.269424)
			(xy 285.735985 -292.275356) (xy 285.783256 -292.289048) (xy 285.827718 -292.310146) (xy 285.868221 -292.338102)
			(xy 285.903714 -292.372194) (xy 285.933279 -292.411538) (xy 285.95615 -292.455115) (xy 285.971734 -292.501796)
			(xy 285.979629 -292.550373) (xy 285.980124 -292.57498) (xy 286.318972 -292.57498) (xy 286.322932 -292.525926)
			(xy 286.334709 -292.478142) (xy 286.354 -292.432866) (xy 286.380303 -292.39127) (xy 286.412938 -292.354433)
			(xy 286.451059 -292.323308) (xy 286.49368 -292.298701) (xy 286.539696 -292.281249) (xy 286.587915 -292.271405)
			(xy 286.63709 -292.269424) (xy 286.685945 -292.275356) (xy 286.733216 -292.289048) (xy 286.777678 -292.310146)
			(xy 286.818181 -292.338102) (xy 286.853674 -292.372194) (xy 286.883239 -292.411538) (xy 286.90611 -292.455115)
			(xy 286.921694 -292.501796) (xy 286.929589 -292.550373) (xy 286.930084 -292.57498) (xy 287.268932 -292.57498)
			(xy 287.272892 -292.525926) (xy 287.284669 -292.478142) (xy 287.30396 -292.432866) (xy 287.330263 -292.39127)
			(xy 287.362898 -292.354433) (xy 287.401019 -292.323308) (xy 287.44364 -292.298701) (xy 287.489656 -292.281249)
			(xy 287.537875 -292.271405) (xy 287.58705 -292.269424) (xy 287.635905 -292.275356) (xy 287.683176 -292.289048)
			(xy 287.727638 -292.310146) (xy 287.768141 -292.338102) (xy 287.803634 -292.372194) (xy 287.833199 -292.411538)
			(xy 287.85607 -292.455115) (xy 287.871654 -292.501796) (xy 287.879549 -292.550373) (xy 287.880044 -292.57498)
			(xy 288.219146 -292.57498) (xy 288.223106 -292.525926) (xy 288.234883 -292.478142) (xy 288.254174 -292.432866)
			(xy 288.280477 -292.39127) (xy 288.313112 -292.354433) (xy 288.351233 -292.323308) (xy 288.393854 -292.298701)
			(xy 288.43987 -292.281249) (xy 288.488089 -292.271405) (xy 288.537264 -292.269424) (xy 288.586119 -292.275356)
			(xy 288.63339 -292.289048) (xy 288.677852 -292.310146) (xy 288.718355 -292.338102) (xy 288.753848 -292.372194)
			(xy 288.783413 -292.411538) (xy 288.806284 -292.455115) (xy 288.821868 -292.501796) (xy 288.829763 -292.550373)
			(xy 288.830258 -292.57498) (xy 289.169106 -292.57498) (xy 289.173066 -292.525926) (xy 289.184843 -292.478142)
			(xy 289.204134 -292.432866) (xy 289.230437 -292.39127) (xy 289.263072 -292.354433) (xy 289.301193 -292.323308)
			(xy 289.343814 -292.298701) (xy 289.38983 -292.281249) (xy 289.438049 -292.271405) (xy 289.487224 -292.269424)
			(xy 289.536079 -292.275356) (xy 289.58335 -292.289048) (xy 289.627812 -292.310146) (xy 289.668315 -292.338102)
			(xy 289.703808 -292.372194) (xy 289.733373 -292.411538) (xy 289.756244 -292.455115) (xy 289.771828 -292.501796)
			(xy 289.779723 -292.550373) (xy 289.780218 -292.57498) (xy 290.119066 -292.57498) (xy 290.123026 -292.525926)
			(xy 290.134803 -292.478142) (xy 290.154094 -292.432866) (xy 290.180397 -292.39127) (xy 290.213032 -292.354433)
			(xy 290.251153 -292.323308) (xy 290.293774 -292.298701) (xy 290.33979 -292.281249) (xy 290.388009 -292.271405)
			(xy 290.437184 -292.269424) (xy 290.486039 -292.275356) (xy 290.53331 -292.289048) (xy 290.577772 -292.310146)
			(xy 290.618275 -292.338102) (xy 290.653768 -292.372194) (xy 290.683333 -292.411538) (xy 290.706204 -292.455115)
			(xy 290.721788 -292.501796) (xy 290.729683 -292.550373) (xy 290.730173 -292.574726) (xy 292.018986 -292.574726)
			(xy 292.022946 -292.525672) (xy 292.034723 -292.477888) (xy 292.054014 -292.432612) (xy 292.080317 -292.391016)
			(xy 292.112952 -292.354179) (xy 292.151073 -292.323054) (xy 292.193694 -292.298447) (xy 292.23971 -292.280995)
			(xy 292.287929 -292.271151) (xy 292.337104 -292.26917) (xy 292.385959 -292.275102) (xy 292.43323 -292.288794)
			(xy 292.477692 -292.309892) (xy 292.518195 -292.337848) (xy 292.553688 -292.37194) (xy 292.583253 -292.411284)
			(xy 292.606124 -292.454861) (xy 292.621708 -292.501542) (xy 292.629603 -292.550119) (xy 292.630098 -292.574726)
			(xy 292.968946 -292.574726) (xy 292.972906 -292.525672) (xy 292.984683 -292.477888) (xy 293.003974 -292.432612)
			(xy 293.030277 -292.391016) (xy 293.062912 -292.354179) (xy 293.101033 -292.323054) (xy 293.143654 -292.298447)
			(xy 293.18967 -292.280995) (xy 293.237889 -292.271151) (xy 293.287064 -292.26917) (xy 293.335919 -292.275102)
			(xy 293.38319 -292.288794) (xy 293.427652 -292.309892) (xy 293.468155 -292.337848) (xy 293.503648 -292.37194)
			(xy 293.533213 -292.411284) (xy 293.556084 -292.454861) (xy 293.571668 -292.501542) (xy 293.579563 -292.550119)
			(xy 293.580058 -292.574726) (xy 293.918906 -292.574726) (xy 293.922866 -292.525672) (xy 293.934643 -292.477888)
			(xy 293.953934 -292.432612) (xy 293.980237 -292.391016) (xy 294.012872 -292.354179) (xy 294.050993 -292.323054)
			(xy 294.093614 -292.298447) (xy 294.13963 -292.280995) (xy 294.187849 -292.271151) (xy 294.237024 -292.26917)
			(xy 294.285879 -292.275102) (xy 294.33315 -292.288794) (xy 294.377612 -292.309892) (xy 294.418115 -292.337848)
			(xy 294.453608 -292.37194) (xy 294.483173 -292.411284) (xy 294.506044 -292.454861) (xy 294.521628 -292.501542)
			(xy 294.529523 -292.550119) (xy 294.530018 -292.574726) (xy 294.86912 -292.574726) (xy 294.87308 -292.525672)
			(xy 294.884857 -292.477888) (xy 294.904148 -292.432612) (xy 294.930451 -292.391016) (xy 294.963086 -292.354179)
			(xy 295.001207 -292.323054) (xy 295.043828 -292.298447) (xy 295.089844 -292.280995) (xy 295.138063 -292.271151)
			(xy 295.187238 -292.26917) (xy 295.236093 -292.275102) (xy 295.283364 -292.288794) (xy 295.327826 -292.309892)
			(xy 295.368329 -292.337848) (xy 295.403822 -292.37194) (xy 295.433387 -292.411284) (xy 295.456258 -292.454861)
			(xy 295.471842 -292.501542) (xy 295.479737 -292.550119) (xy 295.480232 -292.574726) (xy 295.81908 -292.574726)
			(xy 295.82304 -292.525672) (xy 295.834817 -292.477888) (xy 295.854108 -292.432612) (xy 295.880411 -292.391016)
			(xy 295.913046 -292.354179) (xy 295.951167 -292.323054) (xy 295.993788 -292.298447) (xy 296.039804 -292.280995)
			(xy 296.088023 -292.271151) (xy 296.137198 -292.26917) (xy 296.186053 -292.275102) (xy 296.233324 -292.288794)
			(xy 296.277786 -292.309892) (xy 296.318289 -292.337848) (xy 296.353782 -292.37194) (xy 296.383347 -292.411284)
			(xy 296.406218 -292.454861) (xy 296.421802 -292.501542) (xy 296.429697 -292.550119) (xy 296.430192 -292.574726)
			(xy 296.76904 -292.574726) (xy 296.773 -292.525672) (xy 296.784777 -292.477888) (xy 296.804068 -292.432612)
			(xy 296.830371 -292.391016) (xy 296.863006 -292.354179) (xy 296.901127 -292.323054) (xy 296.943748 -292.298447)
			(xy 296.989764 -292.280995) (xy 297.037983 -292.271151) (xy 297.087158 -292.26917) (xy 297.136013 -292.275102)
			(xy 297.183284 -292.288794) (xy 297.227746 -292.309892) (xy 297.268249 -292.337848) (xy 297.303742 -292.37194)
			(xy 297.333307 -292.411284) (xy 297.356178 -292.454861) (xy 297.371762 -292.501542) (xy 297.379657 -292.550119)
			(xy 297.380152 -292.574726) (xy 297.719 -292.574726) (xy 297.72296 -292.525672) (xy 297.734737 -292.477888)
			(xy 297.754028 -292.432612) (xy 297.780331 -292.391016) (xy 297.812966 -292.354179) (xy 297.851087 -292.323054)
			(xy 297.893708 -292.298447) (xy 297.939724 -292.280995) (xy 297.987943 -292.271151) (xy 298.037118 -292.26917)
			(xy 298.085973 -292.275102) (xy 298.133244 -292.288794) (xy 298.177706 -292.309892) (xy 298.218209 -292.337848)
			(xy 298.253702 -292.37194) (xy 298.283267 -292.411284) (xy 298.306138 -292.454861) (xy 298.321722 -292.501542)
			(xy 298.329617 -292.550119) (xy 298.330112 -292.574726) (xy 298.66896 -292.574726) (xy 298.67292 -292.525672)
			(xy 298.684697 -292.477888) (xy 298.703988 -292.432612) (xy 298.730291 -292.391016) (xy 298.762926 -292.354179)
			(xy 298.801047 -292.323054) (xy 298.843668 -292.298447) (xy 298.889684 -292.280995) (xy 298.937903 -292.271151)
			(xy 298.987078 -292.26917) (xy 299.035933 -292.275102) (xy 299.083204 -292.288794) (xy 299.127666 -292.309892)
			(xy 299.168169 -292.337848) (xy 299.203662 -292.37194) (xy 299.233227 -292.411284) (xy 299.256098 -292.454861)
			(xy 299.271682 -292.501542) (xy 299.279577 -292.550119) (xy 299.280072 -292.574726) (xy 299.61892 -292.574726)
			(xy 299.62288 -292.525672) (xy 299.634657 -292.477888) (xy 299.653948 -292.432612) (xy 299.680251 -292.391016)
			(xy 299.712886 -292.354179) (xy 299.751007 -292.323054) (xy 299.793628 -292.298447) (xy 299.839644 -292.280995)
			(xy 299.887863 -292.271151) (xy 299.937038 -292.26917) (xy 299.985893 -292.275102) (xy 300.033164 -292.288794)
			(xy 300.077626 -292.309892) (xy 300.118129 -292.337848) (xy 300.153622 -292.37194) (xy 300.183187 -292.411284)
			(xy 300.206058 -292.454861) (xy 300.221642 -292.501542) (xy 300.229537 -292.550119) (xy 300.230032 -292.574726)
			(xy 300.56888 -292.574726) (xy 300.57284 -292.525672) (xy 300.584617 -292.477888) (xy 300.603908 -292.432612)
			(xy 300.630211 -292.391016) (xy 300.662846 -292.354179) (xy 300.700967 -292.323054) (xy 300.743588 -292.298447)
			(xy 300.789604 -292.280995) (xy 300.837823 -292.271151) (xy 300.886998 -292.26917) (xy 300.935853 -292.275102)
			(xy 300.983124 -292.288794) (xy 301.027586 -292.309892) (xy 301.068089 -292.337848) (xy 301.103582 -292.37194)
			(xy 301.133147 -292.411284) (xy 301.156018 -292.454861) (xy 301.171602 -292.501542) (xy 301.179497 -292.550119)
			(xy 301.179992 -292.574726) (xy 301.519094 -292.574726) (xy 301.523054 -292.525672) (xy 301.534831 -292.477888)
			(xy 301.554122 -292.432612) (xy 301.580425 -292.391016) (xy 301.61306 -292.354179) (xy 301.651181 -292.323054)
			(xy 301.693802 -292.298447) (xy 301.739818 -292.280995) (xy 301.788037 -292.271151) (xy 301.837212 -292.26917)
			(xy 301.886067 -292.275102) (xy 301.933338 -292.288794) (xy 301.9778 -292.309892) (xy 302.018303 -292.337848)
			(xy 302.053796 -292.37194) (xy 302.083361 -292.411284) (xy 302.106232 -292.454861) (xy 302.121816 -292.501542)
			(xy 302.129711 -292.550119) (xy 302.130206 -292.574726) (xy 302.130201 -292.57498) (xy 302.469054 -292.57498)
			(xy 302.473014 -292.525926) (xy 302.484791 -292.478142) (xy 302.504082 -292.432866) (xy 302.530385 -292.39127)
			(xy 302.56302 -292.354433) (xy 302.601141 -292.323308) (xy 302.643762 -292.298701) (xy 302.689778 -292.281249)
			(xy 302.737997 -292.271405) (xy 302.787172 -292.269424) (xy 302.836027 -292.275356) (xy 302.883298 -292.289048)
			(xy 302.92776 -292.310146) (xy 302.968263 -292.338102) (xy 303.003756 -292.372194) (xy 303.033321 -292.411538)
			(xy 303.056192 -292.455115) (xy 303.071776 -292.501796) (xy 303.079671 -292.550373) (xy 303.080161 -292.574726)
			(xy 303.419014 -292.574726) (xy 303.422974 -292.525672) (xy 303.434751 -292.477888) (xy 303.454042 -292.432612)
			(xy 303.480345 -292.391016) (xy 303.51298 -292.354179) (xy 303.551101 -292.323054) (xy 303.593722 -292.298447)
			(xy 303.639738 -292.280995) (xy 303.687957 -292.271151) (xy 303.737132 -292.26917) (xy 303.785987 -292.275102)
			(xy 303.833258 -292.288794) (xy 303.87772 -292.309892) (xy 303.918223 -292.337848) (xy 303.953716 -292.37194)
			(xy 303.983281 -292.411284) (xy 304.006152 -292.454861) (xy 304.021736 -292.501542) (xy 304.029631 -292.550119)
			(xy 304.030126 -292.574726) (xy 304.368974 -292.574726) (xy 304.372934 -292.525672) (xy 304.384711 -292.477888)
			(xy 304.404002 -292.432612) (xy 304.430305 -292.391016) (xy 304.46294 -292.354179) (xy 304.501061 -292.323054)
			(xy 304.543682 -292.298447) (xy 304.589698 -292.280995) (xy 304.637917 -292.271151) (xy 304.687092 -292.26917)
			(xy 304.735947 -292.275102) (xy 304.783218 -292.288794) (xy 304.82768 -292.309892) (xy 304.868183 -292.337848)
			(xy 304.903676 -292.37194) (xy 304.933241 -292.411284) (xy 304.956112 -292.454861) (xy 304.971696 -292.501542)
			(xy 304.979591 -292.550119) (xy 304.980086 -292.574726) (xy 305.318934 -292.574726) (xy 305.322894 -292.525672)
			(xy 305.334671 -292.477888) (xy 305.353962 -292.432612) (xy 305.380265 -292.391016) (xy 305.4129 -292.354179)
			(xy 305.451021 -292.323054) (xy 305.493642 -292.298447) (xy 305.539658 -292.280995) (xy 305.587877 -292.271151)
			(xy 305.637052 -292.26917) (xy 305.685907 -292.275102) (xy 305.733178 -292.288794) (xy 305.77764 -292.309892)
			(xy 305.818143 -292.337848) (xy 305.853636 -292.37194) (xy 305.883201 -292.411284) (xy 305.906072 -292.454861)
			(xy 305.921656 -292.501542) (xy 305.929551 -292.550119) (xy 305.930046 -292.574726) (xy 306.268894 -292.574726)
			(xy 306.272854 -292.525672) (xy 306.284631 -292.477888) (xy 306.303922 -292.432612) (xy 306.330225 -292.391016)
			(xy 306.36286 -292.354179) (xy 306.400981 -292.323054) (xy 306.443602 -292.298447) (xy 306.489618 -292.280995)
			(xy 306.537837 -292.271151) (xy 306.587012 -292.26917) (xy 306.635867 -292.275102) (xy 306.683138 -292.288794)
			(xy 306.7276 -292.309892) (xy 306.768103 -292.337848) (xy 306.803596 -292.37194) (xy 306.833161 -292.411284)
			(xy 306.856032 -292.454861) (xy 306.871616 -292.501542) (xy 306.879511 -292.550119) (xy 306.880006 -292.574726)
			(xy 307.219108 -292.574726) (xy 307.223068 -292.525672) (xy 307.234845 -292.477888) (xy 307.254136 -292.432612)
			(xy 307.280439 -292.391016) (xy 307.313074 -292.354179) (xy 307.351195 -292.323054) (xy 307.393816 -292.298447)
			(xy 307.439832 -292.280995) (xy 307.488051 -292.271151) (xy 307.537226 -292.26917) (xy 307.586081 -292.275102)
			(xy 307.633352 -292.288794) (xy 307.677814 -292.309892) (xy 307.718317 -292.337848) (xy 307.75381 -292.37194)
			(xy 307.783375 -292.411284) (xy 307.806246 -292.454861) (xy 307.82183 -292.501542) (xy 307.829725 -292.550119)
			(xy 307.83022 -292.574726) (xy 308.169068 -292.574726) (xy 308.173028 -292.525672) (xy 308.184805 -292.477888)
			(xy 308.204096 -292.432612) (xy 308.230399 -292.391016) (xy 308.263034 -292.354179) (xy 308.301155 -292.323054)
			(xy 308.343776 -292.298447) (xy 308.389792 -292.280995) (xy 308.438011 -292.271151) (xy 308.487186 -292.26917)
			(xy 308.536041 -292.275102) (xy 308.583312 -292.288794) (xy 308.627774 -292.309892) (xy 308.668277 -292.337848)
			(xy 308.70377 -292.37194) (xy 308.733335 -292.411284) (xy 308.756206 -292.454861) (xy 308.77179 -292.501542)
			(xy 308.779685 -292.550119) (xy 308.78018 -292.574726) (xy 309.119028 -292.574726) (xy 309.122988 -292.525672)
			(xy 309.134765 -292.477888) (xy 309.154056 -292.432612) (xy 309.180359 -292.391016) (xy 309.212994 -292.354179)
			(xy 309.251115 -292.323054) (xy 309.293736 -292.298447) (xy 309.339752 -292.280995) (xy 309.387971 -292.271151)
			(xy 309.437146 -292.26917) (xy 309.486001 -292.275102) (xy 309.533272 -292.288794) (xy 309.577734 -292.309892)
			(xy 309.618237 -292.337848) (xy 309.65373 -292.37194) (xy 309.683295 -292.411284) (xy 309.706166 -292.454861)
			(xy 309.72175 -292.501542) (xy 309.729645 -292.550119) (xy 309.73014 -292.574726) (xy 310.068988 -292.574726)
			(xy 310.072948 -292.525672) (xy 310.084725 -292.477888) (xy 310.104016 -292.432612) (xy 310.130319 -292.391016)
			(xy 310.162954 -292.354179) (xy 310.201075 -292.323054) (xy 310.243696 -292.298447) (xy 310.289712 -292.280995)
			(xy 310.337931 -292.271151) (xy 310.387106 -292.26917) (xy 310.435961 -292.275102) (xy 310.483232 -292.288794)
			(xy 310.527694 -292.309892) (xy 310.568197 -292.337848) (xy 310.60369 -292.37194) (xy 310.633255 -292.411284)
			(xy 310.656126 -292.454861) (xy 310.67171 -292.501542) (xy 310.679605 -292.550119) (xy 310.6801 -292.574726)
			(xy 311.018948 -292.574726) (xy 311.022908 -292.525672) (xy 311.034685 -292.477888) (xy 311.053976 -292.432612)
			(xy 311.080279 -292.391016) (xy 311.112914 -292.354179) (xy 311.151035 -292.323054) (xy 311.193656 -292.298447)
			(xy 311.239672 -292.280995) (xy 311.287891 -292.271151) (xy 311.337066 -292.26917) (xy 311.385921 -292.275102)
			(xy 311.433192 -292.288794) (xy 311.477654 -292.309892) (xy 311.518157 -292.337848) (xy 311.55365 -292.37194)
			(xy 311.583215 -292.411284) (xy 311.606086 -292.454861) (xy 311.62167 -292.501542) (xy 311.629565 -292.550119)
			(xy 311.63006 -292.574726) (xy 311.968908 -292.574726) (xy 311.972868 -292.525672) (xy 311.984645 -292.477888)
			(xy 312.003936 -292.432612) (xy 312.030239 -292.391016) (xy 312.062874 -292.354179) (xy 312.100995 -292.323054)
			(xy 312.143616 -292.298447) (xy 312.189632 -292.280995) (xy 312.237851 -292.271151) (xy 312.287026 -292.26917)
			(xy 312.335881 -292.275102) (xy 312.383152 -292.288794) (xy 312.427614 -292.309892) (xy 312.468117 -292.337848)
			(xy 312.50361 -292.37194) (xy 312.533175 -292.411284) (xy 312.556046 -292.454861) (xy 312.57163 -292.501542)
			(xy 312.579525 -292.550119) (xy 312.58002 -292.574726) (xy 312.919122 -292.574726) (xy 312.923082 -292.525672)
			(xy 312.934859 -292.477888) (xy 312.95415 -292.432612) (xy 312.980453 -292.391016) (xy 313.013088 -292.354179)
			(xy 313.051209 -292.323054) (xy 313.09383 -292.298447) (xy 313.139846 -292.280995) (xy 313.188065 -292.271151)
			(xy 313.23724 -292.26917) (xy 313.286095 -292.275102) (xy 313.333366 -292.288794) (xy 313.377828 -292.309892)
			(xy 313.418331 -292.337848) (xy 313.453824 -292.37194) (xy 313.483389 -292.411284) (xy 313.50626 -292.454861)
			(xy 313.521844 -292.501542) (xy 313.529739 -292.550119) (xy 313.530234 -292.574726) (xy 313.530229 -292.57498)
			(xy 313.869082 -292.57498) (xy 313.873042 -292.525926) (xy 313.884819 -292.478142) (xy 313.90411 -292.432866)
			(xy 313.930413 -292.39127) (xy 313.963048 -292.354433) (xy 314.001169 -292.323308) (xy 314.04379 -292.298701)
			(xy 314.089806 -292.281249) (xy 314.138025 -292.271405) (xy 314.1872 -292.269424) (xy 314.236055 -292.275356)
			(xy 314.283326 -292.289048) (xy 314.327788 -292.310146) (xy 314.368291 -292.338102) (xy 314.403784 -292.372194)
			(xy 314.433349 -292.411538) (xy 314.45622 -292.455115) (xy 314.471804 -292.501796) (xy 314.479699 -292.550373)
			(xy 314.480194 -292.57498) (xy 314.819042 -292.57498) (xy 314.823002 -292.525926) (xy 314.834779 -292.478142)
			(xy 314.85407 -292.432866) (xy 314.880373 -292.39127) (xy 314.913008 -292.354433) (xy 314.951129 -292.323308)
			(xy 314.99375 -292.298701) (xy 315.039766 -292.281249) (xy 315.087985 -292.271405) (xy 315.13716 -292.269424)
			(xy 315.186015 -292.275356) (xy 315.233286 -292.289048) (xy 315.277748 -292.310146) (xy 315.318251 -292.338102)
			(xy 315.353744 -292.372194) (xy 315.383309 -292.411538) (xy 315.40618 -292.455115) (xy 315.421764 -292.501796)
			(xy 315.429659 -292.550373) (xy 315.430154 -292.57498) (xy 315.429659 -292.599587) (xy 315.421764 -292.648164)
			(xy 315.40618 -292.694845) (xy 315.383309 -292.738422) (xy 315.353744 -292.777766) (xy 315.318251 -292.811858)
			(xy 315.277748 -292.839814) (xy 315.233286 -292.860912) (xy 315.186015 -292.874604) (xy 315.13716 -292.880536)
			(xy 315.087985 -292.878555) (xy 315.039766 -292.868711) (xy 314.99375 -292.851259) (xy 314.951129 -292.826652)
			(xy 314.913008 -292.795527) (xy 314.880373 -292.75869) (xy 314.85407 -292.717094) (xy 314.834779 -292.671818)
			(xy 314.823002 -292.624034) (xy 314.819042 -292.57498) (xy 314.480194 -292.57498) (xy 314.479699 -292.599587)
			(xy 314.471804 -292.648164) (xy 314.45622 -292.694845) (xy 314.433349 -292.738422) (xy 314.403784 -292.777766)
			(xy 314.368291 -292.811858) (xy 314.327788 -292.839814) (xy 314.283326 -292.860912) (xy 314.236055 -292.874604)
			(xy 314.1872 -292.880536) (xy 314.138025 -292.878555) (xy 314.089806 -292.868711) (xy 314.04379 -292.851259)
			(xy 314.001169 -292.826652) (xy 313.963048 -292.795527) (xy 313.930413 -292.75869) (xy 313.90411 -292.717094)
			(xy 313.884819 -292.671818) (xy 313.873042 -292.624034) (xy 313.869082 -292.57498) (xy 313.530229 -292.57498)
			(xy 313.529739 -292.599333) (xy 313.521844 -292.64791) (xy 313.50626 -292.694591) (xy 313.483389 -292.738168)
			(xy 313.453824 -292.777512) (xy 313.418331 -292.811604) (xy 313.377828 -292.83956) (xy 313.333366 -292.860658)
			(xy 313.286095 -292.87435) (xy 313.23724 -292.880282) (xy 313.188065 -292.878301) (xy 313.139846 -292.868457)
			(xy 313.09383 -292.851005) (xy 313.051209 -292.826398) (xy 313.013088 -292.795273) (xy 312.980453 -292.758436)
			(xy 312.95415 -292.71684) (xy 312.934859 -292.671564) (xy 312.923082 -292.62378) (xy 312.919122 -292.574726)
			(xy 312.58002 -292.574726) (xy 312.579525 -292.599333) (xy 312.57163 -292.64791) (xy 312.556046 -292.694591)
			(xy 312.533175 -292.738168) (xy 312.50361 -292.777512) (xy 312.468117 -292.811604) (xy 312.427614 -292.83956)
			(xy 312.383152 -292.860658) (xy 312.335881 -292.87435) (xy 312.287026 -292.880282) (xy 312.237851 -292.878301)
			(xy 312.189632 -292.868457) (xy 312.143616 -292.851005) (xy 312.100995 -292.826398) (xy 312.062874 -292.795273)
			(xy 312.030239 -292.758436) (xy 312.003936 -292.71684) (xy 311.984645 -292.671564) (xy 311.972868 -292.62378)
			(xy 311.968908 -292.574726) (xy 311.63006 -292.574726) (xy 311.629565 -292.599333) (xy 311.62167 -292.64791)
			(xy 311.606086 -292.694591) (xy 311.583215 -292.738168) (xy 311.55365 -292.777512) (xy 311.518157 -292.811604)
			(xy 311.477654 -292.83956) (xy 311.433192 -292.860658) (xy 311.385921 -292.87435) (xy 311.337066 -292.880282)
			(xy 311.287891 -292.878301) (xy 311.239672 -292.868457) (xy 311.193656 -292.851005) (xy 311.151035 -292.826398)
			(xy 311.112914 -292.795273) (xy 311.080279 -292.758436) (xy 311.053976 -292.71684) (xy 311.034685 -292.671564)
			(xy 311.022908 -292.62378) (xy 311.018948 -292.574726) (xy 310.6801 -292.574726) (xy 310.679605 -292.599333)
			(xy 310.67171 -292.64791) (xy 310.656126 -292.694591) (xy 310.633255 -292.738168) (xy 310.60369 -292.777512)
			(xy 310.568197 -292.811604) (xy 310.527694 -292.83956) (xy 310.483232 -292.860658) (xy 310.435961 -292.87435)
			(xy 310.387106 -292.880282) (xy 310.337931 -292.878301) (xy 310.289712 -292.868457) (xy 310.243696 -292.851005)
			(xy 310.201075 -292.826398) (xy 310.162954 -292.795273) (xy 310.130319 -292.758436) (xy 310.104016 -292.71684)
			(xy 310.084725 -292.671564) (xy 310.072948 -292.62378) (xy 310.068988 -292.574726) (xy 309.73014 -292.574726)
			(xy 309.729645 -292.599333) (xy 309.72175 -292.64791) (xy 309.706166 -292.694591) (xy 309.683295 -292.738168)
			(xy 309.65373 -292.777512) (xy 309.618237 -292.811604) (xy 309.577734 -292.83956) (xy 309.533272 -292.860658)
			(xy 309.486001 -292.87435) (xy 309.437146 -292.880282) (xy 309.387971 -292.878301) (xy 309.339752 -292.868457)
			(xy 309.293736 -292.851005) (xy 309.251115 -292.826398) (xy 309.212994 -292.795273) (xy 309.180359 -292.758436)
			(xy 309.154056 -292.71684) (xy 309.134765 -292.671564) (xy 309.122988 -292.62378) (xy 309.119028 -292.574726)
			(xy 308.78018 -292.574726) (xy 308.779685 -292.599333) (xy 308.77179 -292.64791) (xy 308.756206 -292.694591)
			(xy 308.733335 -292.738168) (xy 308.70377 -292.777512) (xy 308.668277 -292.811604) (xy 308.627774 -292.83956)
			(xy 308.583312 -292.860658) (xy 308.536041 -292.87435) (xy 308.487186 -292.880282) (xy 308.438011 -292.878301)
			(xy 308.389792 -292.868457) (xy 308.343776 -292.851005) (xy 308.301155 -292.826398) (xy 308.263034 -292.795273)
			(xy 308.230399 -292.758436) (xy 308.204096 -292.71684) (xy 308.184805 -292.671564) (xy 308.173028 -292.62378)
			(xy 308.169068 -292.574726) (xy 307.83022 -292.574726) (xy 307.829725 -292.599333) (xy 307.82183 -292.64791)
			(xy 307.806246 -292.694591) (xy 307.783375 -292.738168) (xy 307.75381 -292.777512) (xy 307.718317 -292.811604)
			(xy 307.677814 -292.83956) (xy 307.633352 -292.860658) (xy 307.586081 -292.87435) (xy 307.537226 -292.880282)
			(xy 307.488051 -292.878301) (xy 307.439832 -292.868457) (xy 307.393816 -292.851005) (xy 307.351195 -292.826398)
			(xy 307.313074 -292.795273) (xy 307.280439 -292.758436) (xy 307.254136 -292.71684) (xy 307.234845 -292.671564)
			(xy 307.223068 -292.62378) (xy 307.219108 -292.574726) (xy 306.880006 -292.574726) (xy 306.879511 -292.599333)
			(xy 306.871616 -292.64791) (xy 306.856032 -292.694591) (xy 306.833161 -292.738168) (xy 306.803596 -292.777512)
			(xy 306.768103 -292.811604) (xy 306.7276 -292.83956) (xy 306.683138 -292.860658) (xy 306.635867 -292.87435)
			(xy 306.587012 -292.880282) (xy 306.537837 -292.878301) (xy 306.489618 -292.868457) (xy 306.443602 -292.851005)
			(xy 306.400981 -292.826398) (xy 306.36286 -292.795273) (xy 306.330225 -292.758436) (xy 306.303922 -292.71684)
			(xy 306.284631 -292.671564) (xy 306.272854 -292.62378) (xy 306.268894 -292.574726) (xy 305.930046 -292.574726)
			(xy 305.929551 -292.599333) (xy 305.921656 -292.64791) (xy 305.906072 -292.694591) (xy 305.883201 -292.738168)
			(xy 305.853636 -292.777512) (xy 305.818143 -292.811604) (xy 305.77764 -292.83956) (xy 305.733178 -292.860658)
			(xy 305.685907 -292.87435) (xy 305.637052 -292.880282) (xy 305.587877 -292.878301) (xy 305.539658 -292.868457)
			(xy 305.493642 -292.851005) (xy 305.451021 -292.826398) (xy 305.4129 -292.795273) (xy 305.380265 -292.758436)
			(xy 305.353962 -292.71684) (xy 305.334671 -292.671564) (xy 305.322894 -292.62378) (xy 305.318934 -292.574726)
			(xy 304.980086 -292.574726) (xy 304.979591 -292.599333) (xy 304.971696 -292.64791) (xy 304.956112 -292.694591)
			(xy 304.933241 -292.738168) (xy 304.903676 -292.777512) (xy 304.868183 -292.811604) (xy 304.82768 -292.83956)
			(xy 304.783218 -292.860658) (xy 304.735947 -292.87435) (xy 304.687092 -292.880282) (xy 304.637917 -292.878301)
			(xy 304.589698 -292.868457) (xy 304.543682 -292.851005) (xy 304.501061 -292.826398) (xy 304.46294 -292.795273)
			(xy 304.430305 -292.758436) (xy 304.404002 -292.71684) (xy 304.384711 -292.671564) (xy 304.372934 -292.62378)
			(xy 304.368974 -292.574726) (xy 304.030126 -292.574726) (xy 304.029631 -292.599333) (xy 304.021736 -292.64791)
			(xy 304.006152 -292.694591) (xy 303.983281 -292.738168) (xy 303.953716 -292.777512) (xy 303.918223 -292.811604)
			(xy 303.87772 -292.83956) (xy 303.833258 -292.860658) (xy 303.785987 -292.87435) (xy 303.737132 -292.880282)
			(xy 303.687957 -292.878301) (xy 303.639738 -292.868457) (xy 303.593722 -292.851005) (xy 303.551101 -292.826398)
			(xy 303.51298 -292.795273) (xy 303.480345 -292.758436) (xy 303.454042 -292.71684) (xy 303.434751 -292.671564)
			(xy 303.422974 -292.62378) (xy 303.419014 -292.574726) (xy 303.080161 -292.574726) (xy 303.080166 -292.57498)
			(xy 303.079671 -292.599587) (xy 303.071776 -292.648164) (xy 303.056192 -292.694845) (xy 303.033321 -292.738422)
			(xy 303.003756 -292.777766) (xy 302.968263 -292.811858) (xy 302.92776 -292.839814) (xy 302.883298 -292.860912)
			(xy 302.836027 -292.874604) (xy 302.787172 -292.880536) (xy 302.737997 -292.878555) (xy 302.689778 -292.868711)
			(xy 302.643762 -292.851259) (xy 302.601141 -292.826652) (xy 302.56302 -292.795527) (xy 302.530385 -292.75869)
			(xy 302.504082 -292.717094) (xy 302.484791 -292.671818) (xy 302.473014 -292.624034) (xy 302.469054 -292.57498)
			(xy 302.130201 -292.57498) (xy 302.129711 -292.599333) (xy 302.121816 -292.64791) (xy 302.106232 -292.694591)
			(xy 302.083361 -292.738168) (xy 302.053796 -292.777512) (xy 302.018303 -292.811604) (xy 301.9778 -292.83956)
			(xy 301.933338 -292.860658) (xy 301.886067 -292.87435) (xy 301.837212 -292.880282) (xy 301.788037 -292.878301)
			(xy 301.739818 -292.868457) (xy 301.693802 -292.851005) (xy 301.651181 -292.826398) (xy 301.61306 -292.795273)
			(xy 301.580425 -292.758436) (xy 301.554122 -292.71684) (xy 301.534831 -292.671564) (xy 301.523054 -292.62378)
			(xy 301.519094 -292.574726) (xy 301.179992 -292.574726) (xy 301.179497 -292.599333) (xy 301.171602 -292.64791)
			(xy 301.156018 -292.694591) (xy 301.133147 -292.738168) (xy 301.103582 -292.777512) (xy 301.068089 -292.811604)
			(xy 301.027586 -292.83956) (xy 300.983124 -292.860658) (xy 300.935853 -292.87435) (xy 300.886998 -292.880282)
			(xy 300.837823 -292.878301) (xy 300.789604 -292.868457) (xy 300.743588 -292.851005) (xy 300.700967 -292.826398)
			(xy 300.662846 -292.795273) (xy 300.630211 -292.758436) (xy 300.603908 -292.71684) (xy 300.584617 -292.671564)
			(xy 300.57284 -292.62378) (xy 300.56888 -292.574726) (xy 300.230032 -292.574726) (xy 300.229537 -292.599333)
			(xy 300.221642 -292.64791) (xy 300.206058 -292.694591) (xy 300.183187 -292.738168) (xy 300.153622 -292.777512)
			(xy 300.118129 -292.811604) (xy 300.077626 -292.83956) (xy 300.033164 -292.860658) (xy 299.985893 -292.87435)
			(xy 299.937038 -292.880282) (xy 299.887863 -292.878301) (xy 299.839644 -292.868457) (xy 299.793628 -292.851005)
			(xy 299.751007 -292.826398) (xy 299.712886 -292.795273) (xy 299.680251 -292.758436) (xy 299.653948 -292.71684)
			(xy 299.634657 -292.671564) (xy 299.62288 -292.62378) (xy 299.61892 -292.574726) (xy 299.280072 -292.574726)
			(xy 299.279577 -292.599333) (xy 299.271682 -292.64791) (xy 299.256098 -292.694591) (xy 299.233227 -292.738168)
			(xy 299.203662 -292.777512) (xy 299.168169 -292.811604) (xy 299.127666 -292.83956) (xy 299.083204 -292.860658)
			(xy 299.035933 -292.87435) (xy 298.987078 -292.880282) (xy 298.937903 -292.878301) (xy 298.889684 -292.868457)
			(xy 298.843668 -292.851005) (xy 298.801047 -292.826398) (xy 298.762926 -292.795273) (xy 298.730291 -292.758436)
			(xy 298.703988 -292.71684) (xy 298.684697 -292.671564) (xy 298.67292 -292.62378) (xy 298.66896 -292.574726)
			(xy 298.330112 -292.574726) (xy 298.329617 -292.599333) (xy 298.321722 -292.64791) (xy 298.306138 -292.694591)
			(xy 298.283267 -292.738168) (xy 298.253702 -292.777512) (xy 298.218209 -292.811604) (xy 298.177706 -292.83956)
			(xy 298.133244 -292.860658) (xy 298.085973 -292.87435) (xy 298.037118 -292.880282) (xy 297.987943 -292.878301)
			(xy 297.939724 -292.868457) (xy 297.893708 -292.851005) (xy 297.851087 -292.826398) (xy 297.812966 -292.795273)
			(xy 297.780331 -292.758436) (xy 297.754028 -292.71684) (xy 297.734737 -292.671564) (xy 297.72296 -292.62378)
			(xy 297.719 -292.574726) (xy 297.380152 -292.574726) (xy 297.379657 -292.599333) (xy 297.371762 -292.64791)
			(xy 297.356178 -292.694591) (xy 297.333307 -292.738168) (xy 297.303742 -292.777512) (xy 297.268249 -292.811604)
			(xy 297.227746 -292.83956) (xy 297.183284 -292.860658) (xy 297.136013 -292.87435) (xy 297.087158 -292.880282)
			(xy 297.037983 -292.878301) (xy 296.989764 -292.868457) (xy 296.943748 -292.851005) (xy 296.901127 -292.826398)
			(xy 296.863006 -292.795273) (xy 296.830371 -292.758436) (xy 296.804068 -292.71684) (xy 296.784777 -292.671564)
			(xy 296.773 -292.62378) (xy 296.76904 -292.574726) (xy 296.430192 -292.574726) (xy 296.429697 -292.599333)
			(xy 296.421802 -292.64791) (xy 296.406218 -292.694591) (xy 296.383347 -292.738168) (xy 296.353782 -292.777512)
			(xy 296.318289 -292.811604) (xy 296.277786 -292.83956) (xy 296.233324 -292.860658) (xy 296.186053 -292.87435)
			(xy 296.137198 -292.880282) (xy 296.088023 -292.878301) (xy 296.039804 -292.868457) (xy 295.993788 -292.851005)
			(xy 295.951167 -292.826398) (xy 295.913046 -292.795273) (xy 295.880411 -292.758436) (xy 295.854108 -292.71684)
			(xy 295.834817 -292.671564) (xy 295.82304 -292.62378) (xy 295.81908 -292.574726) (xy 295.480232 -292.574726)
			(xy 295.479737 -292.599333) (xy 295.471842 -292.64791) (xy 295.456258 -292.694591) (xy 295.433387 -292.738168)
			(xy 295.403822 -292.777512) (xy 295.368329 -292.811604) (xy 295.327826 -292.83956) (xy 295.283364 -292.860658)
			(xy 295.236093 -292.87435) (xy 295.187238 -292.880282) (xy 295.138063 -292.878301) (xy 295.089844 -292.868457)
			(xy 295.043828 -292.851005) (xy 295.001207 -292.826398) (xy 294.963086 -292.795273) (xy 294.930451 -292.758436)
			(xy 294.904148 -292.71684) (xy 294.884857 -292.671564) (xy 294.87308 -292.62378) (xy 294.86912 -292.574726)
			(xy 294.530018 -292.574726) (xy 294.529523 -292.599333) (xy 294.521628 -292.64791) (xy 294.506044 -292.694591)
			(xy 294.483173 -292.738168) (xy 294.453608 -292.777512) (xy 294.418115 -292.811604) (xy 294.377612 -292.83956)
			(xy 294.33315 -292.860658) (xy 294.285879 -292.87435) (xy 294.237024 -292.880282) (xy 294.187849 -292.878301)
			(xy 294.13963 -292.868457) (xy 294.093614 -292.851005) (xy 294.050993 -292.826398) (xy 294.012872 -292.795273)
			(xy 293.980237 -292.758436) (xy 293.953934 -292.71684) (xy 293.934643 -292.671564) (xy 293.922866 -292.62378)
			(xy 293.918906 -292.574726) (xy 293.580058 -292.574726) (xy 293.579563 -292.599333) (xy 293.571668 -292.64791)
			(xy 293.556084 -292.694591) (xy 293.533213 -292.738168) (xy 293.503648 -292.777512) (xy 293.468155 -292.811604)
			(xy 293.427652 -292.83956) (xy 293.38319 -292.860658) (xy 293.335919 -292.87435) (xy 293.287064 -292.880282)
			(xy 293.237889 -292.878301) (xy 293.18967 -292.868457) (xy 293.143654 -292.851005) (xy 293.101033 -292.826398)
			(xy 293.062912 -292.795273) (xy 293.030277 -292.758436) (xy 293.003974 -292.71684) (xy 292.984683 -292.671564)
			(xy 292.972906 -292.62378) (xy 292.968946 -292.574726) (xy 292.630098 -292.574726) (xy 292.629603 -292.599333)
			(xy 292.621708 -292.64791) (xy 292.606124 -292.694591) (xy 292.583253 -292.738168) (xy 292.553688 -292.777512)
			(xy 292.518195 -292.811604) (xy 292.477692 -292.83956) (xy 292.43323 -292.860658) (xy 292.385959 -292.87435)
			(xy 292.337104 -292.880282) (xy 292.287929 -292.878301) (xy 292.23971 -292.868457) (xy 292.193694 -292.851005)
			(xy 292.151073 -292.826398) (xy 292.112952 -292.795273) (xy 292.080317 -292.758436) (xy 292.054014 -292.71684)
			(xy 292.034723 -292.671564) (xy 292.022946 -292.62378) (xy 292.018986 -292.574726) (xy 290.730173 -292.574726)
			(xy 290.730178 -292.57498) (xy 290.729683 -292.599587) (xy 290.721788 -292.648164) (xy 290.706204 -292.694845)
			(xy 290.683333 -292.738422) (xy 290.653768 -292.777766) (xy 290.618275 -292.811858) (xy 290.577772 -292.839814)
			(xy 290.53331 -292.860912) (xy 290.486039 -292.874604) (xy 290.437184 -292.880536) (xy 290.388009 -292.878555)
			(xy 290.33979 -292.868711) (xy 290.293774 -292.851259) (xy 290.251153 -292.826652) (xy 290.213032 -292.795527)
			(xy 290.180397 -292.75869) (xy 290.154094 -292.717094) (xy 290.134803 -292.671818) (xy 290.123026 -292.624034)
			(xy 290.119066 -292.57498) (xy 289.780218 -292.57498) (xy 289.779723 -292.599587) (xy 289.771828 -292.648164)
			(xy 289.756244 -292.694845) (xy 289.733373 -292.738422) (xy 289.703808 -292.777766) (xy 289.668315 -292.811858)
			(xy 289.627812 -292.839814) (xy 289.58335 -292.860912) (xy 289.536079 -292.874604) (xy 289.487224 -292.880536)
			(xy 289.438049 -292.878555) (xy 289.38983 -292.868711) (xy 289.343814 -292.851259) (xy 289.301193 -292.826652)
			(xy 289.263072 -292.795527) (xy 289.230437 -292.75869) (xy 289.204134 -292.717094) (xy 289.184843 -292.671818)
			(xy 289.173066 -292.624034) (xy 289.169106 -292.57498) (xy 288.830258 -292.57498) (xy 288.829763 -292.599587)
			(xy 288.821868 -292.648164) (xy 288.806284 -292.694845) (xy 288.783413 -292.738422) (xy 288.753848 -292.777766)
			(xy 288.718355 -292.811858) (xy 288.677852 -292.839814) (xy 288.63339 -292.860912) (xy 288.586119 -292.874604)
			(xy 288.537264 -292.880536) (xy 288.488089 -292.878555) (xy 288.43987 -292.868711) (xy 288.393854 -292.851259)
			(xy 288.351233 -292.826652) (xy 288.313112 -292.795527) (xy 288.280477 -292.75869) (xy 288.254174 -292.717094)
			(xy 288.234883 -292.671818) (xy 288.223106 -292.624034) (xy 288.219146 -292.57498) (xy 287.880044 -292.57498)
			(xy 287.879549 -292.599587) (xy 287.871654 -292.648164) (xy 287.85607 -292.694845) (xy 287.833199 -292.738422)
			(xy 287.803634 -292.777766) (xy 287.768141 -292.811858) (xy 287.727638 -292.839814) (xy 287.683176 -292.860912)
			(xy 287.635905 -292.874604) (xy 287.58705 -292.880536) (xy 287.537875 -292.878555) (xy 287.489656 -292.868711)
			(xy 287.44364 -292.851259) (xy 287.401019 -292.826652) (xy 287.362898 -292.795527) (xy 287.330263 -292.75869)
			(xy 287.30396 -292.717094) (xy 287.284669 -292.671818) (xy 287.272892 -292.624034) (xy 287.268932 -292.57498)
			(xy 286.930084 -292.57498) (xy 286.929589 -292.599587) (xy 286.921694 -292.648164) (xy 286.90611 -292.694845)
			(xy 286.883239 -292.738422) (xy 286.853674 -292.777766) (xy 286.818181 -292.811858) (xy 286.777678 -292.839814)
			(xy 286.733216 -292.860912) (xy 286.685945 -292.874604) (xy 286.63709 -292.880536) (xy 286.587915 -292.878555)
			(xy 286.539696 -292.868711) (xy 286.49368 -292.851259) (xy 286.451059 -292.826652) (xy 286.412938 -292.795527)
			(xy 286.380303 -292.75869) (xy 286.354 -292.717094) (xy 286.334709 -292.671818) (xy 286.322932 -292.624034)
			(xy 286.318972 -292.57498) (xy 285.980124 -292.57498) (xy 285.979629 -292.599587) (xy 285.971734 -292.648164)
			(xy 285.95615 -292.694845) (xy 285.933279 -292.738422) (xy 285.903714 -292.777766) (xy 285.868221 -292.811858)
			(xy 285.827718 -292.839814) (xy 285.783256 -292.860912) (xy 285.735985 -292.874604) (xy 285.68713 -292.880536)
			(xy 285.637955 -292.878555) (xy 285.589736 -292.868711) (xy 285.54372 -292.851259) (xy 285.501099 -292.826652)
			(xy 285.462978 -292.795527) (xy 285.430343 -292.75869) (xy 285.40404 -292.717094) (xy 285.384749 -292.671818)
			(xy 285.372972 -292.624034) (xy 285.369012 -292.57498) (xy 285.030164 -292.57498) (xy 285.029669 -292.599587)
			(xy 285.021774 -292.648164) (xy 285.00619 -292.694845) (xy 284.983319 -292.738422) (xy 284.953754 -292.777766)
			(xy 284.918261 -292.811858) (xy 284.877758 -292.839814) (xy 284.833296 -292.860912) (xy 284.786025 -292.874604)
			(xy 284.73717 -292.880536) (xy 284.687995 -292.878555) (xy 284.639776 -292.868711) (xy 284.59376 -292.851259)
			(xy 284.551139 -292.826652) (xy 284.513018 -292.795527) (xy 284.480383 -292.75869) (xy 284.45408 -292.717094)
			(xy 284.434789 -292.671818) (xy 284.423012 -292.624034) (xy 284.419052 -292.57498) (xy 284.080204 -292.57498)
			(xy 284.079709 -292.599587) (xy 284.071814 -292.648164) (xy 284.05623 -292.694845) (xy 284.033359 -292.738422)
			(xy 284.003794 -292.777766) (xy 283.968301 -292.811858) (xy 283.927798 -292.839814) (xy 283.883336 -292.860912)
			(xy 283.836065 -292.874604) (xy 283.78721 -292.880536) (xy 283.738035 -292.878555) (xy 283.689816 -292.868711)
			(xy 283.6438 -292.851259) (xy 283.601179 -292.826652) (xy 283.563058 -292.795527) (xy 283.530423 -292.75869)
			(xy 283.50412 -292.717094) (xy 283.484829 -292.671818) (xy 283.473052 -292.624034) (xy 283.469092 -292.57498)
			(xy 283.130244 -292.57498) (xy 283.129749 -292.599587) (xy 283.121854 -292.648164) (xy 283.10627 -292.694845)
			(xy 283.083399 -292.738422) (xy 283.053834 -292.777766) (xy 283.018341 -292.811858) (xy 282.977838 -292.839814)
			(xy 282.933376 -292.860912) (xy 282.886105 -292.874604) (xy 282.83725 -292.880536) (xy 282.788075 -292.878555)
			(xy 282.739856 -292.868711) (xy 282.69384 -292.851259) (xy 282.651219 -292.826652) (xy 282.613098 -292.795527)
			(xy 282.580463 -292.75869) (xy 282.55416 -292.717094) (xy 282.534869 -292.671818) (xy 282.523092 -292.624034)
			(xy 282.519132 -292.57498) (xy 282.180025 -292.57498) (xy 282.179535 -292.599333) (xy 282.17164 -292.64791)
			(xy 282.156056 -292.694591) (xy 282.133185 -292.738168) (xy 282.10362 -292.777512) (xy 282.068127 -292.811604)
			(xy 282.027624 -292.83956) (xy 281.983162 -292.860658) (xy 281.935891 -292.87435) (xy 281.887036 -292.880282)
			(xy 281.837861 -292.878301) (xy 281.789642 -292.868457) (xy 281.743626 -292.851005) (xy 281.701005 -292.826398)
			(xy 281.662884 -292.795273) (xy 281.630249 -292.758436) (xy 281.603946 -292.71684) (xy 281.584655 -292.671564)
			(xy 281.572878 -292.62378) (xy 281.568918 -292.574726) (xy 281.23007 -292.574726) (xy 281.229575 -292.599333)
			(xy 281.22168 -292.64791) (xy 281.206096 -292.694591) (xy 281.183225 -292.738168) (xy 281.15366 -292.777512)
			(xy 281.118167 -292.811604) (xy 281.077664 -292.83956) (xy 281.033202 -292.860658) (xy 280.985931 -292.87435)
			(xy 280.937076 -292.880282) (xy 280.887901 -292.878301) (xy 280.839682 -292.868457) (xy 280.793666 -292.851005)
			(xy 280.751045 -292.826398) (xy 280.712924 -292.795273) (xy 280.680289 -292.758436) (xy 280.653986 -292.71684)
			(xy 280.634695 -292.671564) (xy 280.622918 -292.62378) (xy 280.618958 -292.574726) (xy 280.280105 -292.574726)
			(xy 280.28011 -292.57498) (xy 280.279615 -292.599587) (xy 280.27172 -292.648164) (xy 280.256136 -292.694845)
			(xy 280.233265 -292.738422) (xy 280.2037 -292.777766) (xy 280.168207 -292.811858) (xy 280.127704 -292.839814)
			(xy 280.083242 -292.860912) (xy 280.035971 -292.874604) (xy 279.987116 -292.880536) (xy 279.937941 -292.878555)
			(xy 279.889722 -292.868711) (xy 279.843706 -292.851259) (xy 279.801085 -292.826652) (xy 279.762964 -292.795527)
			(xy 279.730329 -292.75869) (xy 279.704026 -292.717094) (xy 279.684735 -292.671818) (xy 279.672958 -292.624034)
			(xy 279.668998 -292.57498) (xy 279.33015 -292.57498) (xy 279.329655 -292.599587) (xy 279.32176 -292.648164)
			(xy 279.306176 -292.694845) (xy 279.283305 -292.738422) (xy 279.25374 -292.777766) (xy 279.218247 -292.811858)
			(xy 279.177744 -292.839814) (xy 279.133282 -292.860912) (xy 279.086011 -292.874604) (xy 279.037156 -292.880536)
			(xy 278.987981 -292.878555) (xy 278.939762 -292.868711) (xy 278.893746 -292.851259) (xy 278.851125 -292.826652)
			(xy 278.813004 -292.795527) (xy 278.780369 -292.75869) (xy 278.754066 -292.717094) (xy 278.734775 -292.671818)
			(xy 278.722998 -292.624034) (xy 278.719038 -292.57498) (xy 278.38019 -292.57498) (xy 278.379695 -292.599587)
			(xy 278.3718 -292.648164) (xy 278.356216 -292.694845) (xy 278.333345 -292.738422) (xy 278.30378 -292.777766)
			(xy 278.268287 -292.811858) (xy 278.227784 -292.839814) (xy 278.183322 -292.860912) (xy 278.136051 -292.874604)
			(xy 278.087196 -292.880536) (xy 278.038021 -292.878555) (xy 277.989802 -292.868711) (xy 277.943786 -292.851259)
			(xy 277.901165 -292.826652) (xy 277.863044 -292.795527) (xy 277.830409 -292.75869) (xy 277.804106 -292.717094)
			(xy 277.784815 -292.671818) (xy 277.773038 -292.624034) (xy 277.769078 -292.57498) (xy 277.43023 -292.57498)
			(xy 277.429735 -292.599587) (xy 277.42184 -292.648164) (xy 277.406256 -292.694845) (xy 277.383385 -292.738422)
			(xy 277.35382 -292.777766) (xy 277.318327 -292.811858) (xy 277.277824 -292.839814) (xy 277.233362 -292.860912)
			(xy 277.186091 -292.874604) (xy 277.137236 -292.880536) (xy 277.088061 -292.878555) (xy 277.039842 -292.868711)
			(xy 276.993826 -292.851259) (xy 276.951205 -292.826652) (xy 276.913084 -292.795527) (xy 276.880449 -292.75869)
			(xy 276.854146 -292.717094) (xy 276.834855 -292.671818) (xy 276.823078 -292.624034) (xy 276.819118 -292.57498)
			(xy 276.480016 -292.57498) (xy 276.479521 -292.599587) (xy 276.471626 -292.648164) (xy 276.456042 -292.694845)
			(xy 276.433171 -292.738422) (xy 276.403606 -292.777766) (xy 276.368113 -292.811858) (xy 276.32761 -292.839814)
			(xy 276.283148 -292.860912) (xy 276.235877 -292.874604) (xy 276.187022 -292.880536) (xy 276.137847 -292.878555)
			(xy 276.089628 -292.868711) (xy 276.043612 -292.851259) (xy 276.000991 -292.826652) (xy 275.96287 -292.795527)
			(xy 275.930235 -292.75869) (xy 275.903932 -292.717094) (xy 275.884641 -292.671818) (xy 275.872864 -292.624034)
			(xy 275.868904 -292.57498) (xy 275.530056 -292.57498) (xy 275.529561 -292.599587) (xy 275.521666 -292.648164)
			(xy 275.506082 -292.694845) (xy 275.483211 -292.738422) (xy 275.453646 -292.777766) (xy 275.418153 -292.811858)
			(xy 275.37765 -292.839814) (xy 275.333188 -292.860912) (xy 275.285917 -292.874604) (xy 275.237062 -292.880536)
			(xy 275.187887 -292.878555) (xy 275.139668 -292.868711) (xy 275.093652 -292.851259) (xy 275.051031 -292.826652)
			(xy 275.01291 -292.795527) (xy 274.980275 -292.75869) (xy 274.953972 -292.717094) (xy 274.934681 -292.671818)
			(xy 274.922904 -292.624034) (xy 274.918944 -292.57498) (xy 274.630896 -292.57498) (xy 274.630398 -292.601629)
			(xy 274.622455 -292.654333) (xy 274.606745 -292.705263) (xy 274.583619 -292.753284) (xy 274.553595 -292.797321)
			(xy 274.517343 -292.836392) (xy 274.475672 -292.869623) (xy 274.429514 -292.896272) (xy 274.3799 -292.915744)
			(xy 274.327938 -292.927604) (xy 274.274788 -292.931588) (xy 274.221638 -292.927604) (xy 274.169676 -292.915744)
			(xy 274.120062 -292.896272) (xy 274.073904 -292.869623) (xy 274.032233 -292.836392) (xy 273.995981 -292.797321)
			(xy 273.965957 -292.753284) (xy 273.942831 -292.705263) (xy 273.927121 -292.654333) (xy 273.919178 -292.601629)
			(xy 273.629309 -292.601629) (xy 273.621746 -292.648164) (xy 273.606162 -292.694845) (xy 273.583291 -292.738422)
			(xy 273.553726 -292.777766) (xy 273.518233 -292.811858) (xy 273.47773 -292.839814) (xy 273.433268 -292.860912)
			(xy 273.385997 -292.874604) (xy 273.337142 -292.880536) (xy 273.287967 -292.878555) (xy 273.239748 -292.868711)
			(xy 273.193732 -292.851259) (xy 273.151111 -292.826652) (xy 273.11299 -292.795527) (xy 273.080355 -292.75869)
			(xy 273.054052 -292.717094) (xy 273.034761 -292.671818) (xy 273.022984 -292.624034) (xy 273.019024 -292.57498)
			(xy 272.680171 -292.57498) (xy 272.679681 -292.599333) (xy 272.671786 -292.64791) (xy 272.656202 -292.694591)
			(xy 272.633331 -292.738168) (xy 272.603766 -292.777512) (xy 272.568273 -292.811604) (xy 272.52777 -292.83956)
			(xy 272.483308 -292.860658) (xy 272.436037 -292.87435) (xy 272.387182 -292.880282) (xy 272.338007 -292.878301)
			(xy 272.289788 -292.868457) (xy 272.243772 -292.851005) (xy 272.201151 -292.826398) (xy 272.16303 -292.795273)
			(xy 272.130395 -292.758436) (xy 272.104092 -292.71684) (xy 272.084801 -292.671564) (xy 272.073024 -292.62378)
			(xy 272.069064 -292.574726) (xy 271.730216 -292.574726) (xy 271.729721 -292.599333) (xy 271.721826 -292.64791)
			(xy 271.706242 -292.694591) (xy 271.683371 -292.738168) (xy 271.653806 -292.777512) (xy 271.618313 -292.811604)
			(xy 271.57781 -292.83956) (xy 271.533348 -292.860658) (xy 271.486077 -292.87435) (xy 271.437222 -292.880282)
			(xy 271.388047 -292.878301) (xy 271.339828 -292.868457) (xy 271.293812 -292.851005) (xy 271.251191 -292.826398)
			(xy 271.21307 -292.795273) (xy 271.180435 -292.758436) (xy 271.154132 -292.71684) (xy 271.134841 -292.671564)
			(xy 271.123064 -292.62378) (xy 271.119104 -292.574726) (xy 270.780251 -292.574726) (xy 270.780256 -292.57498)
			(xy 270.779761 -292.599587) (xy 270.771866 -292.648164) (xy 270.756282 -292.694845) (xy 270.733411 -292.738422)
			(xy 270.703846 -292.777766) (xy 270.668353 -292.811858) (xy 270.62785 -292.839814) (xy 270.583388 -292.860912)
			(xy 270.536117 -292.874604) (xy 270.487262 -292.880536) (xy 270.438087 -292.878555) (xy 270.389868 -292.868711)
			(xy 270.343852 -292.851259) (xy 270.301231 -292.826652) (xy 270.26311 -292.795527) (xy 270.230475 -292.75869)
			(xy 270.204172 -292.717094) (xy 270.184881 -292.671818) (xy 270.173104 -292.624034) (xy 270.169144 -292.57498)
			(xy 269.830042 -292.57498) (xy 269.829547 -292.599587) (xy 269.821652 -292.648164) (xy 269.806068 -292.694845)
			(xy 269.783197 -292.738422) (xy 269.753632 -292.777766) (xy 269.718139 -292.811858) (xy 269.677636 -292.839814)
			(xy 269.633174 -292.860912) (xy 269.585903 -292.874604) (xy 269.537048 -292.880536) (xy 269.487873 -292.878555)
			(xy 269.439654 -292.868711) (xy 269.393638 -292.851259) (xy 269.351017 -292.826652) (xy 269.312896 -292.795527)
			(xy 269.280261 -292.75869) (xy 269.253958 -292.717094) (xy 269.234667 -292.671818) (xy 269.22289 -292.624034)
			(xy 269.21893 -292.57498) (xy 268.880082 -292.57498) (xy 268.879587 -292.599587) (xy 268.871692 -292.648164)
			(xy 268.856108 -292.694845) (xy 268.833237 -292.738422) (xy 268.803672 -292.777766) (xy 268.768179 -292.811858)
			(xy 268.727676 -292.839814) (xy 268.683214 -292.860912) (xy 268.635943 -292.874604) (xy 268.587088 -292.880536)
			(xy 268.537913 -292.878555) (xy 268.489694 -292.868711) (xy 268.443678 -292.851259) (xy 268.401057 -292.826652)
			(xy 268.362936 -292.795527) (xy 268.330301 -292.75869) (xy 268.303998 -292.717094) (xy 268.284707 -292.671818)
			(xy 268.27293 -292.624034) (xy 268.26897 -292.57498) (xy 264.277733 -292.57498) (xy 264.288803 -292.59922)
			(xy 264.304158 -292.651515) (xy 264.311914 -292.705463) (xy 264.3124 -292.732714) (xy 264.311872 -292.762097)
			(xy 264.302839 -292.820164) (xy 264.285005 -292.876159) (xy 264.258791 -292.928754) (xy 264.224818 -292.976705)
			(xy 264.183891 -293.018876) (xy 264.160762 -293.037006) (xy 264.151364 -293.044372) (xy 264.14095 -293.064946)
			(xy 264.139426 -293.168832) (xy 264.149332 -293.189914) (xy 264.158476 -293.19728) (xy 264.180292 -293.215523)
			(xy 264.218835 -293.257333) (xy 264.250747 -293.304401) (xy 264.275319 -293.355684) (xy 264.292009 -293.410045)
			(xy 264.300447 -293.466281) (xy 264.30097 -293.494714) (xy 264.934444 -293.494714) (xy 264.938515 -293.439092)
			(xy 264.950641 -293.384655) (xy 264.970564 -293.332564) (xy 264.99786 -293.283929) (xy 265.031946 -293.239786)
			(xy 265.072095 -293.201077) (xy 265.117453 -293.168626) (xy 265.167053 -293.143125) (xy 265.219837 -293.125118)
			(xy 265.27468 -293.114988) (xy 265.330414 -293.112951) (xy 265.385851 -293.119051) (xy 265.439808 -293.133157)
			(xy 265.491137 -293.154969) (xy 265.538743 -293.184023) (xy 265.581611 -293.219698) (xy 265.618828 -293.261235)
			(xy 265.649601 -293.307748) (xy 265.673273 -293.358245) (xy 265.689341 -293.411652) (xy 265.697461 -293.466828)
			(xy 265.69797 -293.494714) (xy 265.820904 -293.494714) (xy 265.824975 -293.439092) (xy 265.837101 -293.384655)
			(xy 265.857024 -293.332564) (xy 265.88432 -293.283929) (xy 265.918406 -293.239786) (xy 265.958555 -293.201077)
			(xy 266.003913 -293.168626) (xy 266.053513 -293.143125) (xy 266.106297 -293.125118) (xy 266.16114 -293.114988)
			(xy 266.216874 -293.112951) (xy 266.272311 -293.119051) (xy 266.326268 -293.133157) (xy 266.377597 -293.154969)
			(xy 266.425203 -293.184023) (xy 266.468071 -293.219698) (xy 266.505288 -293.261235) (xy 266.536061 -293.307748)
			(xy 266.559733 -293.358245) (xy 266.575801 -293.411652) (xy 266.583921 -293.466828) (xy 266.58443 -293.494714)
			(xy 266.583921 -293.5226) (xy 266.583577 -293.52494) (xy 270.169144 -293.52494) (xy 270.173104 -293.475886)
			(xy 270.184881 -293.428102) (xy 270.204172 -293.382826) (xy 270.230475 -293.34123) (xy 270.26311 -293.304393)
			(xy 270.301231 -293.273268) (xy 270.343852 -293.248661) (xy 270.389868 -293.231209) (xy 270.438087 -293.221365)
			(xy 270.487262 -293.219384) (xy 270.536117 -293.225316) (xy 270.583388 -293.239008) (xy 270.62785 -293.260106)
			(xy 270.668353 -293.288062) (xy 270.703846 -293.322154) (xy 270.733411 -293.361498) (xy 270.756282 -293.405075)
			(xy 270.771866 -293.451756) (xy 270.779761 -293.500333) (xy 270.780256 -293.52494) (xy 271.119104 -293.52494)
			(xy 271.123064 -293.475886) (xy 271.134841 -293.428102) (xy 271.154132 -293.382826) (xy 271.180435 -293.34123)
			(xy 271.21307 -293.304393) (xy 271.251191 -293.273268) (xy 271.293812 -293.248661) (xy 271.339828 -293.231209)
			(xy 271.388047 -293.221365) (xy 271.437222 -293.219384) (xy 271.486077 -293.225316) (xy 271.533348 -293.239008)
			(xy 271.57781 -293.260106) (xy 271.618313 -293.288062) (xy 271.653806 -293.322154) (xy 271.683371 -293.361498)
			(xy 271.706242 -293.405075) (xy 271.721826 -293.451756) (xy 271.729721 -293.500333) (xy 271.730216 -293.52494)
			(xy 272.069064 -293.52494) (xy 272.073024 -293.475886) (xy 272.084801 -293.428102) (xy 272.104092 -293.382826)
			(xy 272.130395 -293.34123) (xy 272.16303 -293.304393) (xy 272.201151 -293.273268) (xy 272.243772 -293.248661)
			(xy 272.289788 -293.231209) (xy 272.338007 -293.221365) (xy 272.387182 -293.219384) (xy 272.436037 -293.225316)
			(xy 272.483308 -293.239008) (xy 272.52777 -293.260106) (xy 272.568273 -293.288062) (xy 272.603766 -293.322154)
			(xy 272.633331 -293.361498) (xy 272.656202 -293.405075) (xy 272.671786 -293.451756) (xy 272.679681 -293.500333)
			(xy 272.680176 -293.52494) (xy 273.019024 -293.52494) (xy 273.022984 -293.475886) (xy 273.034761 -293.428102)
			(xy 273.054052 -293.382826) (xy 273.080355 -293.34123) (xy 273.11299 -293.304393) (xy 273.151111 -293.273268)
			(xy 273.193732 -293.248661) (xy 273.239748 -293.231209) (xy 273.287967 -293.221365) (xy 273.337142 -293.219384)
			(xy 273.385997 -293.225316) (xy 273.433268 -293.239008) (xy 273.47773 -293.260106) (xy 273.518233 -293.288062)
			(xy 273.553726 -293.322154) (xy 273.583291 -293.361498) (xy 273.606162 -293.405075) (xy 273.621746 -293.451756)
			(xy 273.629641 -293.500333) (xy 273.630136 -293.52494) (xy 273.968984 -293.52494) (xy 273.972944 -293.475886)
			(xy 273.984721 -293.428102) (xy 274.004012 -293.382826) (xy 274.030315 -293.34123) (xy 274.06295 -293.304393)
			(xy 274.101071 -293.273268) (xy 274.143692 -293.248661) (xy 274.189708 -293.231209) (xy 274.237927 -293.221365)
			(xy 274.287102 -293.219384) (xy 274.335957 -293.225316) (xy 274.383228 -293.239008) (xy 274.42769 -293.260106)
			(xy 274.468193 -293.288062) (xy 274.503686 -293.322154) (xy 274.533251 -293.361498) (xy 274.556122 -293.405075)
			(xy 274.571706 -293.451756) (xy 274.579601 -293.500333) (xy 274.580096 -293.52494) (xy 274.579601 -293.549547)
			(xy 274.579269 -293.551589) (xy 274.869138 -293.551589) (xy 274.869138 -293.498291) (xy 274.877081 -293.445587)
			(xy 274.892791 -293.394657) (xy 274.915917 -293.346636) (xy 274.945941 -293.302599) (xy 274.982193 -293.263528)
			(xy 275.023864 -293.230297) (xy 275.070022 -293.203648) (xy 275.119636 -293.184176) (xy 275.171598 -293.172316)
			(xy 275.224748 -293.168333) (xy 275.277898 -293.172316) (xy 275.32986 -293.184176) (xy 275.379474 -293.203648)
			(xy 275.425632 -293.230297) (xy 275.467303 -293.263528) (xy 275.503555 -293.302599) (xy 275.533579 -293.346636)
			(xy 275.556705 -293.394657) (xy 275.572415 -293.445587) (xy 275.580358 -293.498291) (xy 275.580856 -293.52494)
			(xy 275.868904 -293.52494) (xy 275.872864 -293.475886) (xy 275.884641 -293.428102) (xy 275.903932 -293.382826)
			(xy 275.930235 -293.34123) (xy 275.96287 -293.304393) (xy 276.000991 -293.273268) (xy 276.043612 -293.248661)
			(xy 276.089628 -293.231209) (xy 276.137847 -293.221365) (xy 276.187022 -293.219384) (xy 276.235877 -293.225316)
			(xy 276.283148 -293.239008) (xy 276.32761 -293.260106) (xy 276.368113 -293.288062) (xy 276.403606 -293.322154)
			(xy 276.433171 -293.361498) (xy 276.456042 -293.405075) (xy 276.471626 -293.451756) (xy 276.479521 -293.500333)
			(xy 276.480016 -293.52494) (xy 277.769078 -293.52494) (xy 277.773038 -293.475886) (xy 277.784815 -293.428102)
			(xy 277.804106 -293.382826) (xy 277.830409 -293.34123) (xy 277.863044 -293.304393) (xy 277.901165 -293.273268)
			(xy 277.943786 -293.248661) (xy 277.989802 -293.231209) (xy 278.038021 -293.221365) (xy 278.087196 -293.219384)
			(xy 278.136051 -293.225316) (xy 278.183322 -293.239008) (xy 278.227784 -293.260106) (xy 278.268287 -293.288062)
			(xy 278.30378 -293.322154) (xy 278.333345 -293.361498) (xy 278.356216 -293.405075) (xy 278.3718 -293.451756)
			(xy 278.379695 -293.500333) (xy 278.38019 -293.52494) (xy 279.668998 -293.52494) (xy 279.672958 -293.475886)
			(xy 279.684735 -293.428102) (xy 279.704026 -293.382826) (xy 279.730329 -293.34123) (xy 279.762964 -293.304393)
			(xy 279.801085 -293.273268) (xy 279.843706 -293.248661) (xy 279.889722 -293.231209) (xy 279.937941 -293.221365)
			(xy 279.987116 -293.219384) (xy 280.035971 -293.225316) (xy 280.083242 -293.239008) (xy 280.127704 -293.260106)
			(xy 280.168207 -293.288062) (xy 280.2037 -293.322154) (xy 280.233265 -293.361498) (xy 280.256136 -293.405075)
			(xy 280.27172 -293.451756) (xy 280.279615 -293.500333) (xy 280.28011 -293.52494) (xy 280.618958 -293.52494)
			(xy 280.622918 -293.475886) (xy 280.634695 -293.428102) (xy 280.653986 -293.382826) (xy 280.680289 -293.34123)
			(xy 280.712924 -293.304393) (xy 280.751045 -293.273268) (xy 280.793666 -293.248661) (xy 280.839682 -293.231209)
			(xy 280.887901 -293.221365) (xy 280.937076 -293.219384) (xy 280.985931 -293.225316) (xy 281.033202 -293.239008)
			(xy 281.077664 -293.260106) (xy 281.118167 -293.288062) (xy 281.15366 -293.322154) (xy 281.183225 -293.361498)
			(xy 281.206096 -293.405075) (xy 281.22168 -293.451756) (xy 281.229575 -293.500333) (xy 281.23007 -293.52494)
			(xy 281.568918 -293.52494) (xy 281.572878 -293.475886) (xy 281.584655 -293.428102) (xy 281.603946 -293.382826)
			(xy 281.630249 -293.34123) (xy 281.662884 -293.304393) (xy 281.701005 -293.273268) (xy 281.743626 -293.248661)
			(xy 281.789642 -293.231209) (xy 281.837861 -293.221365) (xy 281.887036 -293.219384) (xy 281.935891 -293.225316)
			(xy 281.983162 -293.239008) (xy 282.027624 -293.260106) (xy 282.068127 -293.288062) (xy 282.10362 -293.322154)
			(xy 282.133185 -293.361498) (xy 282.156056 -293.405075) (xy 282.17164 -293.451756) (xy 282.179535 -293.500333)
			(xy 282.18003 -293.52494) (xy 282.519132 -293.52494) (xy 282.523092 -293.475886) (xy 282.534869 -293.428102)
			(xy 282.55416 -293.382826) (xy 282.580463 -293.34123) (xy 282.613098 -293.304393) (xy 282.651219 -293.273268)
			(xy 282.69384 -293.248661) (xy 282.739856 -293.231209) (xy 282.788075 -293.221365) (xy 282.83725 -293.219384)
			(xy 282.886105 -293.225316) (xy 282.933376 -293.239008) (xy 282.977838 -293.260106) (xy 283.018341 -293.288062)
			(xy 283.053834 -293.322154) (xy 283.083399 -293.361498) (xy 283.10627 -293.405075) (xy 283.121854 -293.451756)
			(xy 283.129749 -293.500333) (xy 283.130244 -293.52494) (xy 283.469092 -293.52494) (xy 283.473052 -293.475886)
			(xy 283.484829 -293.428102) (xy 283.50412 -293.382826) (xy 283.530423 -293.34123) (xy 283.563058 -293.304393)
			(xy 283.601179 -293.273268) (xy 283.6438 -293.248661) (xy 283.689816 -293.231209) (xy 283.738035 -293.221365)
			(xy 283.78721 -293.219384) (xy 283.836065 -293.225316) (xy 283.883336 -293.239008) (xy 283.927798 -293.260106)
			(xy 283.968301 -293.288062) (xy 284.003794 -293.322154) (xy 284.033359 -293.361498) (xy 284.05623 -293.405075)
			(xy 284.071814 -293.451756) (xy 284.079709 -293.500333) (xy 284.080204 -293.52494) (xy 284.419052 -293.52494)
			(xy 284.423012 -293.475886) (xy 284.434789 -293.428102) (xy 284.45408 -293.382826) (xy 284.480383 -293.34123)
			(xy 284.513018 -293.304393) (xy 284.551139 -293.273268) (xy 284.59376 -293.248661) (xy 284.639776 -293.231209)
			(xy 284.687995 -293.221365) (xy 284.73717 -293.219384) (xy 284.786025 -293.225316) (xy 284.833296 -293.239008)
			(xy 284.877758 -293.260106) (xy 284.918261 -293.288062) (xy 284.953754 -293.322154) (xy 284.983319 -293.361498)
			(xy 285.00619 -293.405075) (xy 285.021774 -293.451756) (xy 285.029669 -293.500333) (xy 285.030164 -293.52494)
			(xy 285.369012 -293.52494) (xy 285.372972 -293.475886) (xy 285.384749 -293.428102) (xy 285.40404 -293.382826)
			(xy 285.430343 -293.34123) (xy 285.462978 -293.304393) (xy 285.501099 -293.273268) (xy 285.54372 -293.248661)
			(xy 285.589736 -293.231209) (xy 285.637955 -293.221365) (xy 285.68713 -293.219384) (xy 285.735985 -293.225316)
			(xy 285.783256 -293.239008) (xy 285.827718 -293.260106) (xy 285.868221 -293.288062) (xy 285.903714 -293.322154)
			(xy 285.933279 -293.361498) (xy 285.95615 -293.405075) (xy 285.971734 -293.451756) (xy 285.979629 -293.500333)
			(xy 285.980124 -293.52494) (xy 286.318972 -293.52494) (xy 286.322932 -293.475886) (xy 286.334709 -293.428102)
			(xy 286.354 -293.382826) (xy 286.380303 -293.34123) (xy 286.412938 -293.304393) (xy 286.451059 -293.273268)
			(xy 286.49368 -293.248661) (xy 286.539696 -293.231209) (xy 286.587915 -293.221365) (xy 286.63709 -293.219384)
			(xy 286.685945 -293.225316) (xy 286.733216 -293.239008) (xy 286.777678 -293.260106) (xy 286.818181 -293.288062)
			(xy 286.853674 -293.322154) (xy 286.883239 -293.361498) (xy 286.90611 -293.405075) (xy 286.921694 -293.451756)
			(xy 286.929589 -293.500333) (xy 286.930084 -293.52494) (xy 287.268932 -293.52494) (xy 287.272892 -293.475886)
			(xy 287.284669 -293.428102) (xy 287.30396 -293.382826) (xy 287.330263 -293.34123) (xy 287.362898 -293.304393)
			(xy 287.401019 -293.273268) (xy 287.44364 -293.248661) (xy 287.489656 -293.231209) (xy 287.537875 -293.221365)
			(xy 287.58705 -293.219384) (xy 287.635905 -293.225316) (xy 287.683176 -293.239008) (xy 287.727638 -293.260106)
			(xy 287.768141 -293.288062) (xy 287.803634 -293.322154) (xy 287.833199 -293.361498) (xy 287.85607 -293.405075)
			(xy 287.871654 -293.451756) (xy 287.879549 -293.500333) (xy 287.880044 -293.52494) (xy 288.218892 -293.52494)
			(xy 288.222852 -293.475886) (xy 288.234629 -293.428102) (xy 288.25392 -293.382826) (xy 288.280223 -293.34123)
			(xy 288.312858 -293.304393) (xy 288.350979 -293.273268) (xy 288.3936 -293.248661) (xy 288.439616 -293.231209)
			(xy 288.487835 -293.221365) (xy 288.53701 -293.219384) (xy 288.585865 -293.225316) (xy 288.633136 -293.239008)
			(xy 288.677598 -293.260106) (xy 288.718101 -293.288062) (xy 288.753594 -293.322154) (xy 288.783159 -293.361498)
			(xy 288.80603 -293.405075) (xy 288.821614 -293.451756) (xy 288.829509 -293.500333) (xy 288.830004 -293.52494)
			(xy 289.169106 -293.52494) (xy 289.173066 -293.475886) (xy 289.184843 -293.428102) (xy 289.204134 -293.382826)
			(xy 289.230437 -293.34123) (xy 289.263072 -293.304393) (xy 289.301193 -293.273268) (xy 289.343814 -293.248661)
			(xy 289.38983 -293.231209) (xy 289.438049 -293.221365) (xy 289.487224 -293.219384) (xy 289.536079 -293.225316)
			(xy 289.58335 -293.239008) (xy 289.627812 -293.260106) (xy 289.668315 -293.288062) (xy 289.703808 -293.322154)
			(xy 289.733373 -293.361498) (xy 289.756244 -293.405075) (xy 289.771828 -293.451756) (xy 289.779723 -293.500333)
			(xy 289.780218 -293.52494) (xy 290.119066 -293.52494) (xy 290.123026 -293.475886) (xy 290.134803 -293.428102)
			(xy 290.154094 -293.382826) (xy 290.180397 -293.34123) (xy 290.213032 -293.304393) (xy 290.251153 -293.273268)
			(xy 290.293774 -293.248661) (xy 290.33979 -293.231209) (xy 290.388009 -293.221365) (xy 290.437184 -293.219384)
			(xy 290.486039 -293.225316) (xy 290.53331 -293.239008) (xy 290.577772 -293.260106) (xy 290.618275 -293.288062)
			(xy 290.653768 -293.322154) (xy 290.683333 -293.361498) (xy 290.706204 -293.405075) (xy 290.721788 -293.451756)
			(xy 290.729683 -293.500333) (xy 290.730178 -293.52494) (xy 292.018986 -293.52494) (xy 292.022946 -293.475886)
			(xy 292.034723 -293.428102) (xy 292.054014 -293.382826) (xy 292.080317 -293.34123) (xy 292.112952 -293.304393)
			(xy 292.151073 -293.273268) (xy 292.193694 -293.248661) (xy 292.23971 -293.231209) (xy 292.287929 -293.221365)
			(xy 292.337104 -293.219384) (xy 292.385959 -293.225316) (xy 292.43323 -293.239008) (xy 292.477692 -293.260106)
			(xy 292.518195 -293.288062) (xy 292.553688 -293.322154) (xy 292.583253 -293.361498) (xy 292.606124 -293.405075)
			(xy 292.621708 -293.451756) (xy 292.629603 -293.500333) (xy 292.630098 -293.52494) (xy 292.968946 -293.52494)
			(xy 292.972906 -293.475886) (xy 292.984683 -293.428102) (xy 293.003974 -293.382826) (xy 293.030277 -293.34123)
			(xy 293.062912 -293.304393) (xy 293.101033 -293.273268) (xy 293.143654 -293.248661) (xy 293.18967 -293.231209)
			(xy 293.237889 -293.221365) (xy 293.287064 -293.219384) (xy 293.335919 -293.225316) (xy 293.38319 -293.239008)
			(xy 293.427652 -293.260106) (xy 293.468155 -293.288062) (xy 293.503648 -293.322154) (xy 293.533213 -293.361498)
			(xy 293.556084 -293.405075) (xy 293.571668 -293.451756) (xy 293.579563 -293.500333) (xy 293.580058 -293.52494)
			(xy 293.918906 -293.52494) (xy 293.922866 -293.475886) (xy 293.934643 -293.428102) (xy 293.953934 -293.382826)
			(xy 293.980237 -293.34123) (xy 294.012872 -293.304393) (xy 294.050993 -293.273268) (xy 294.093614 -293.248661)
			(xy 294.13963 -293.231209) (xy 294.187849 -293.221365) (xy 294.237024 -293.219384) (xy 294.285879 -293.225316)
			(xy 294.33315 -293.239008) (xy 294.377612 -293.260106) (xy 294.418115 -293.288062) (xy 294.453608 -293.322154)
			(xy 294.483173 -293.361498) (xy 294.506044 -293.405075) (xy 294.521628 -293.451756) (xy 294.529523 -293.500333)
			(xy 294.530018 -293.52494) (xy 294.86912 -293.52494) (xy 294.87308 -293.475886) (xy 294.884857 -293.428102)
			(xy 294.904148 -293.382826) (xy 294.930451 -293.34123) (xy 294.963086 -293.304393) (xy 295.001207 -293.273268)
			(xy 295.043828 -293.248661) (xy 295.089844 -293.231209) (xy 295.138063 -293.221365) (xy 295.187238 -293.219384)
			(xy 295.236093 -293.225316) (xy 295.283364 -293.239008) (xy 295.327826 -293.260106) (xy 295.368329 -293.288062)
			(xy 295.403822 -293.322154) (xy 295.433387 -293.361498) (xy 295.456258 -293.405075) (xy 295.471842 -293.451756)
			(xy 295.479737 -293.500333) (xy 295.480232 -293.52494) (xy 295.81908 -293.52494) (xy 295.82304 -293.475886)
			(xy 295.834817 -293.428102) (xy 295.854108 -293.382826) (xy 295.880411 -293.34123) (xy 295.913046 -293.304393)
			(xy 295.951167 -293.273268) (xy 295.993788 -293.248661) (xy 296.039804 -293.231209) (xy 296.088023 -293.221365)
			(xy 296.137198 -293.219384) (xy 296.186053 -293.225316) (xy 296.233324 -293.239008) (xy 296.277786 -293.260106)
			(xy 296.318289 -293.288062) (xy 296.353782 -293.322154) (xy 296.383347 -293.361498) (xy 296.406218 -293.405075)
			(xy 296.421802 -293.451756) (xy 296.429697 -293.500333) (xy 296.430192 -293.52494) (xy 296.76904 -293.52494)
			(xy 296.773 -293.475886) (xy 296.784777 -293.428102) (xy 296.804068 -293.382826) (xy 296.830371 -293.34123)
			(xy 296.863006 -293.304393) (xy 296.901127 -293.273268) (xy 296.943748 -293.248661) (xy 296.989764 -293.231209)
			(xy 297.037983 -293.221365) (xy 297.087158 -293.219384) (xy 297.136013 -293.225316) (xy 297.183284 -293.239008)
			(xy 297.227746 -293.260106) (xy 297.268249 -293.288062) (xy 297.303742 -293.322154) (xy 297.333307 -293.361498)
			(xy 297.356178 -293.405075) (xy 297.371762 -293.451756) (xy 297.379657 -293.500333) (xy 297.380152 -293.52494)
			(xy 297.719 -293.52494) (xy 297.72296 -293.475886) (xy 297.734737 -293.428102) (xy 297.754028 -293.382826)
			(xy 297.780331 -293.34123) (xy 297.812966 -293.304393) (xy 297.851087 -293.273268) (xy 297.893708 -293.248661)
			(xy 297.939724 -293.231209) (xy 297.987943 -293.221365) (xy 298.037118 -293.219384) (xy 298.085973 -293.225316)
			(xy 298.133244 -293.239008) (xy 298.177706 -293.260106) (xy 298.218209 -293.288062) (xy 298.253702 -293.322154)
			(xy 298.283267 -293.361498) (xy 298.306138 -293.405075) (xy 298.321722 -293.451756) (xy 298.329617 -293.500333)
			(xy 298.330112 -293.52494) (xy 298.66896 -293.52494) (xy 298.67292 -293.475886) (xy 298.684697 -293.428102)
			(xy 298.703988 -293.382826) (xy 298.730291 -293.34123) (xy 298.762926 -293.304393) (xy 298.801047 -293.273268)
			(xy 298.843668 -293.248661) (xy 298.889684 -293.231209) (xy 298.937903 -293.221365) (xy 298.987078 -293.219384)
			(xy 299.035933 -293.225316) (xy 299.083204 -293.239008) (xy 299.127666 -293.260106) (xy 299.168169 -293.288062)
			(xy 299.203662 -293.322154) (xy 299.233227 -293.361498) (xy 299.256098 -293.405075) (xy 299.271682 -293.451756)
			(xy 299.279577 -293.500333) (xy 299.280072 -293.52494) (xy 299.61892 -293.52494) (xy 299.62288 -293.475886)
			(xy 299.634657 -293.428102) (xy 299.653948 -293.382826) (xy 299.680251 -293.34123) (xy 299.712886 -293.304393)
			(xy 299.751007 -293.273268) (xy 299.793628 -293.248661) (xy 299.839644 -293.231209) (xy 299.887863 -293.221365)
			(xy 299.937038 -293.219384) (xy 299.985893 -293.225316) (xy 300.033164 -293.239008) (xy 300.077626 -293.260106)
			(xy 300.118129 -293.288062) (xy 300.153622 -293.322154) (xy 300.183187 -293.361498) (xy 300.206058 -293.405075)
			(xy 300.221642 -293.451756) (xy 300.229537 -293.500333) (xy 300.230032 -293.52494) (xy 300.56888 -293.52494)
			(xy 300.57284 -293.475886) (xy 300.584617 -293.428102) (xy 300.603908 -293.382826) (xy 300.630211 -293.34123)
			(xy 300.662846 -293.304393) (xy 300.700967 -293.273268) (xy 300.743588 -293.248661) (xy 300.789604 -293.231209)
			(xy 300.837823 -293.221365) (xy 300.886998 -293.219384) (xy 300.935853 -293.225316) (xy 300.983124 -293.239008)
			(xy 301.027586 -293.260106) (xy 301.068089 -293.288062) (xy 301.103582 -293.322154) (xy 301.133147 -293.361498)
			(xy 301.156018 -293.405075) (xy 301.171602 -293.451756) (xy 301.179497 -293.500333) (xy 301.179992 -293.52494)
			(xy 301.519094 -293.52494) (xy 301.523054 -293.475886) (xy 301.534831 -293.428102) (xy 301.554122 -293.382826)
			(xy 301.580425 -293.34123) (xy 301.61306 -293.304393) (xy 301.651181 -293.273268) (xy 301.693802 -293.248661)
			(xy 301.739818 -293.231209) (xy 301.788037 -293.221365) (xy 301.837212 -293.219384) (xy 301.886067 -293.225316)
			(xy 301.933338 -293.239008) (xy 301.9778 -293.260106) (xy 302.018303 -293.288062) (xy 302.053796 -293.322154)
			(xy 302.083361 -293.361498) (xy 302.106232 -293.405075) (xy 302.121816 -293.451756) (xy 302.129711 -293.500333)
			(xy 302.130206 -293.52494) (xy 302.469054 -293.52494) (xy 302.473014 -293.475886) (xy 302.484791 -293.428102)
			(xy 302.504082 -293.382826) (xy 302.530385 -293.34123) (xy 302.56302 -293.304393) (xy 302.601141 -293.273268)
			(xy 302.643762 -293.248661) (xy 302.689778 -293.231209) (xy 302.737997 -293.221365) (xy 302.787172 -293.219384)
			(xy 302.836027 -293.225316) (xy 302.883298 -293.239008) (xy 302.92776 -293.260106) (xy 302.968263 -293.288062)
			(xy 303.003756 -293.322154) (xy 303.033321 -293.361498) (xy 303.056192 -293.405075) (xy 303.071776 -293.451756)
			(xy 303.079671 -293.500333) (xy 303.080166 -293.52494) (xy 303.419014 -293.52494) (xy 303.422974 -293.475886)
			(xy 303.434751 -293.428102) (xy 303.454042 -293.382826) (xy 303.480345 -293.34123) (xy 303.51298 -293.304393)
			(xy 303.551101 -293.273268) (xy 303.593722 -293.248661) (xy 303.639738 -293.231209) (xy 303.687957 -293.221365)
			(xy 303.737132 -293.219384) (xy 303.785987 -293.225316) (xy 303.833258 -293.239008) (xy 303.87772 -293.260106)
			(xy 303.918223 -293.288062) (xy 303.953716 -293.322154) (xy 303.983281 -293.361498) (xy 304.006152 -293.405075)
			(xy 304.021736 -293.451756) (xy 304.029631 -293.500333) (xy 304.030126 -293.52494) (xy 305.318934 -293.52494)
			(xy 305.322894 -293.475886) (xy 305.334671 -293.428102) (xy 305.353962 -293.382826) (xy 305.380265 -293.34123)
			(xy 305.4129 -293.304393) (xy 305.451021 -293.273268) (xy 305.493642 -293.248661) (xy 305.539658 -293.231209)
			(xy 305.587877 -293.221365) (xy 305.637052 -293.219384) (xy 305.685907 -293.225316) (xy 305.733178 -293.239008)
			(xy 305.77764 -293.260106) (xy 305.818143 -293.288062) (xy 305.853636 -293.322154) (xy 305.883201 -293.361498)
			(xy 305.906072 -293.405075) (xy 305.921656 -293.451756) (xy 305.929551 -293.500333) (xy 305.930046 -293.52494)
			(xy 306.269148 -293.52494) (xy 306.273108 -293.475886) (xy 306.284885 -293.428102) (xy 306.304176 -293.382826)
			(xy 306.330479 -293.34123) (xy 306.363114 -293.304393) (xy 306.401235 -293.273268) (xy 306.443856 -293.248661)
			(xy 306.489872 -293.231209) (xy 306.538091 -293.221365) (xy 306.587266 -293.219384) (xy 306.636121 -293.225316)
			(xy 306.683392 -293.239008) (xy 306.727854 -293.260106) (xy 306.768357 -293.288062) (xy 306.80385 -293.322154)
			(xy 306.833415 -293.361498) (xy 306.856286 -293.405075) (xy 306.87187 -293.451756) (xy 306.879765 -293.500333)
			(xy 306.88026 -293.52494) (xy 307.219108 -293.52494) (xy 307.223068 -293.475886) (xy 307.234845 -293.428102)
			(xy 307.254136 -293.382826) (xy 307.280439 -293.34123) (xy 307.313074 -293.304393) (xy 307.351195 -293.273268)
			(xy 307.393816 -293.248661) (xy 307.439832 -293.231209) (xy 307.488051 -293.221365) (xy 307.537226 -293.219384)
			(xy 307.586081 -293.225316) (xy 307.633352 -293.239008) (xy 307.677814 -293.260106) (xy 307.718317 -293.288062)
			(xy 307.75381 -293.322154) (xy 307.783375 -293.361498) (xy 307.806246 -293.405075) (xy 307.82183 -293.451756)
			(xy 307.829725 -293.500333) (xy 307.83022 -293.52494) (xy 308.169068 -293.52494) (xy 308.173028 -293.475886)
			(xy 308.184805 -293.428102) (xy 308.204096 -293.382826) (xy 308.230399 -293.34123) (xy 308.263034 -293.304393)
			(xy 308.301155 -293.273268) (xy 308.343776 -293.248661) (xy 308.389792 -293.231209) (xy 308.438011 -293.221365)
			(xy 308.487186 -293.219384) (xy 308.536041 -293.225316) (xy 308.583312 -293.239008) (xy 308.627774 -293.260106)
			(xy 308.668277 -293.288062) (xy 308.70377 -293.322154) (xy 308.733335 -293.361498) (xy 308.756206 -293.405075)
			(xy 308.77179 -293.451756) (xy 308.779685 -293.500333) (xy 308.78018 -293.52494) (xy 309.119028 -293.52494)
			(xy 309.122988 -293.475886) (xy 309.134765 -293.428102) (xy 309.154056 -293.382826) (xy 309.180359 -293.34123)
			(xy 309.212994 -293.304393) (xy 309.251115 -293.273268) (xy 309.293736 -293.248661) (xy 309.339752 -293.231209)
			(xy 309.387971 -293.221365) (xy 309.437146 -293.219384) (xy 309.486001 -293.225316) (xy 309.533272 -293.239008)
			(xy 309.577734 -293.260106) (xy 309.618237 -293.288062) (xy 309.65373 -293.322154) (xy 309.683295 -293.361498)
			(xy 309.706166 -293.405075) (xy 309.72175 -293.451756) (xy 309.729645 -293.500333) (xy 309.73014 -293.52494)
			(xy 310.068988 -293.52494) (xy 310.072948 -293.475886) (xy 310.084725 -293.428102) (xy 310.104016 -293.382826)
			(xy 310.130319 -293.34123) (xy 310.162954 -293.304393) (xy 310.201075 -293.273268) (xy 310.243696 -293.248661)
			(xy 310.289712 -293.231209) (xy 310.337931 -293.221365) (xy 310.387106 -293.219384) (xy 310.435961 -293.225316)
			(xy 310.483232 -293.239008) (xy 310.527694 -293.260106) (xy 310.568197 -293.288062) (xy 310.60369 -293.322154)
			(xy 310.633255 -293.361498) (xy 310.656126 -293.405075) (xy 310.67171 -293.451756) (xy 310.679605 -293.500333)
			(xy 310.6801 -293.52494) (xy 311.018948 -293.52494) (xy 311.022908 -293.475886) (xy 311.034685 -293.428102)
			(xy 311.053976 -293.382826) (xy 311.080279 -293.34123) (xy 311.112914 -293.304393) (xy 311.151035 -293.273268)
			(xy 311.193656 -293.248661) (xy 311.239672 -293.231209) (xy 311.287891 -293.221365) (xy 311.337066 -293.219384)
			(xy 311.385921 -293.225316) (xy 311.433192 -293.239008) (xy 311.477654 -293.260106) (xy 311.518157 -293.288062)
			(xy 311.55365 -293.322154) (xy 311.583215 -293.361498) (xy 311.606086 -293.405075) (xy 311.62167 -293.451756)
			(xy 311.629565 -293.500333) (xy 311.63006 -293.52494) (xy 311.968908 -293.52494) (xy 311.972868 -293.475886)
			(xy 311.984645 -293.428102) (xy 312.003936 -293.382826) (xy 312.030239 -293.34123) (xy 312.062874 -293.304393)
			(xy 312.100995 -293.273268) (xy 312.143616 -293.248661) (xy 312.189632 -293.231209) (xy 312.237851 -293.221365)
			(xy 312.287026 -293.219384) (xy 312.335881 -293.225316) (xy 312.383152 -293.239008) (xy 312.427614 -293.260106)
			(xy 312.468117 -293.288062) (xy 312.50361 -293.322154) (xy 312.533175 -293.361498) (xy 312.556046 -293.405075)
			(xy 312.57163 -293.451756) (xy 312.579525 -293.500333) (xy 312.58002 -293.52494) (xy 312.919122 -293.52494)
			(xy 312.923082 -293.475886) (xy 312.934859 -293.428102) (xy 312.95415 -293.382826) (xy 312.980453 -293.34123)
			(xy 313.013088 -293.304393) (xy 313.051209 -293.273268) (xy 313.09383 -293.248661) (xy 313.139846 -293.231209)
			(xy 313.188065 -293.221365) (xy 313.23724 -293.219384) (xy 313.286095 -293.225316) (xy 313.333366 -293.239008)
			(xy 313.377828 -293.260106) (xy 313.418331 -293.288062) (xy 313.453824 -293.322154) (xy 313.483389 -293.361498)
			(xy 313.50626 -293.405075) (xy 313.521844 -293.451756) (xy 313.529739 -293.500333) (xy 313.530234 -293.52494)
			(xy 313.869082 -293.52494) (xy 313.873042 -293.475886) (xy 313.884819 -293.428102) (xy 313.90411 -293.382826)
			(xy 313.930413 -293.34123) (xy 313.963048 -293.304393) (xy 314.001169 -293.273268) (xy 314.04379 -293.248661)
			(xy 314.089806 -293.231209) (xy 314.138025 -293.221365) (xy 314.1872 -293.219384) (xy 314.236055 -293.225316)
			(xy 314.283326 -293.239008) (xy 314.327788 -293.260106) (xy 314.368291 -293.288062) (xy 314.403784 -293.322154)
			(xy 314.433349 -293.361498) (xy 314.45622 -293.405075) (xy 314.471804 -293.451756) (xy 314.479699 -293.500333)
			(xy 314.480194 -293.52494) (xy 314.819042 -293.52494) (xy 314.823002 -293.475886) (xy 314.834779 -293.428102)
			(xy 314.85407 -293.382826) (xy 314.880373 -293.34123) (xy 314.913008 -293.304393) (xy 314.951129 -293.273268)
			(xy 314.99375 -293.248661) (xy 315.039766 -293.231209) (xy 315.087985 -293.221365) (xy 315.13716 -293.219384)
			(xy 315.186015 -293.225316) (xy 315.233286 -293.239008) (xy 315.277748 -293.260106) (xy 315.318251 -293.288062)
			(xy 315.353744 -293.322154) (xy 315.383309 -293.361498) (xy 315.40618 -293.405075) (xy 315.421764 -293.451756)
			(xy 315.429659 -293.500333) (xy 315.430154 -293.52494) (xy 315.429659 -293.549547) (xy 315.421764 -293.598124)
			(xy 315.40618 -293.644805) (xy 315.383309 -293.688382) (xy 315.353744 -293.727726) (xy 315.318251 -293.761818)
			(xy 315.277748 -293.789774) (xy 315.233286 -293.810872) (xy 315.186015 -293.824564) (xy 315.13716 -293.830496)
			(xy 315.087985 -293.828515) (xy 315.039766 -293.818671) (xy 314.99375 -293.801219) (xy 314.951129 -293.776612)
			(xy 314.913008 -293.745487) (xy 314.880373 -293.70865) (xy 314.85407 -293.667054) (xy 314.834779 -293.621778)
			(xy 314.823002 -293.573994) (xy 314.819042 -293.52494) (xy 314.480194 -293.52494) (xy 314.479699 -293.549547)
			(xy 314.471804 -293.598124) (xy 314.45622 -293.644805) (xy 314.433349 -293.688382) (xy 314.403784 -293.727726)
			(xy 314.368291 -293.761818) (xy 314.327788 -293.789774) (xy 314.283326 -293.810872) (xy 314.236055 -293.824564)
			(xy 314.1872 -293.830496) (xy 314.138025 -293.828515) (xy 314.089806 -293.818671) (xy 314.04379 -293.801219)
			(xy 314.001169 -293.776612) (xy 313.963048 -293.745487) (xy 313.930413 -293.70865) (xy 313.90411 -293.667054)
			(xy 313.884819 -293.621778) (xy 313.873042 -293.573994) (xy 313.869082 -293.52494) (xy 313.530234 -293.52494)
			(xy 313.529739 -293.549547) (xy 313.521844 -293.598124) (xy 313.50626 -293.644805) (xy 313.483389 -293.688382)
			(xy 313.453824 -293.727726) (xy 313.418331 -293.761818) (xy 313.377828 -293.789774) (xy 313.333366 -293.810872)
			(xy 313.286095 -293.824564) (xy 313.23724 -293.830496) (xy 313.188065 -293.828515) (xy 313.139846 -293.818671)
			(xy 313.09383 -293.801219) (xy 313.051209 -293.776612) (xy 313.013088 -293.745487) (xy 312.980453 -293.70865)
			(xy 312.95415 -293.667054) (xy 312.934859 -293.621778) (xy 312.923082 -293.573994) (xy 312.919122 -293.52494)
			(xy 312.58002 -293.52494) (xy 312.579525 -293.549547) (xy 312.57163 -293.598124) (xy 312.556046 -293.644805)
			(xy 312.533175 -293.688382) (xy 312.50361 -293.727726) (xy 312.468117 -293.761818) (xy 312.427614 -293.789774)
			(xy 312.383152 -293.810872) (xy 312.335881 -293.824564) (xy 312.287026 -293.830496) (xy 312.237851 -293.828515)
			(xy 312.189632 -293.818671) (xy 312.143616 -293.801219) (xy 312.100995 -293.776612) (xy 312.062874 -293.745487)
			(xy 312.030239 -293.70865) (xy 312.003936 -293.667054) (xy 311.984645 -293.621778) (xy 311.972868 -293.573994)
			(xy 311.968908 -293.52494) (xy 311.63006 -293.52494) (xy 311.629565 -293.549547) (xy 311.62167 -293.598124)
			(xy 311.606086 -293.644805) (xy 311.583215 -293.688382) (xy 311.55365 -293.727726) (xy 311.518157 -293.761818)
			(xy 311.477654 -293.789774) (xy 311.433192 -293.810872) (xy 311.385921 -293.824564) (xy 311.337066 -293.830496)
			(xy 311.287891 -293.828515) (xy 311.239672 -293.818671) (xy 311.193656 -293.801219) (xy 311.151035 -293.776612)
			(xy 311.112914 -293.745487) (xy 311.080279 -293.70865) (xy 311.053976 -293.667054) (xy 311.034685 -293.621778)
			(xy 311.022908 -293.573994) (xy 311.018948 -293.52494) (xy 310.6801 -293.52494) (xy 310.679605 -293.549547)
			(xy 310.67171 -293.598124) (xy 310.656126 -293.644805) (xy 310.633255 -293.688382) (xy 310.60369 -293.727726)
			(xy 310.568197 -293.761818) (xy 310.527694 -293.789774) (xy 310.483232 -293.810872) (xy 310.435961 -293.824564)
			(xy 310.387106 -293.830496) (xy 310.337931 -293.828515) (xy 310.289712 -293.818671) (xy 310.243696 -293.801219)
			(xy 310.201075 -293.776612) (xy 310.162954 -293.745487) (xy 310.130319 -293.70865) (xy 310.104016 -293.667054)
			(xy 310.084725 -293.621778) (xy 310.072948 -293.573994) (xy 310.068988 -293.52494) (xy 309.73014 -293.52494)
			(xy 309.729645 -293.549547) (xy 309.72175 -293.598124) (xy 309.706166 -293.644805) (xy 309.683295 -293.688382)
			(xy 309.65373 -293.727726) (xy 309.618237 -293.761818) (xy 309.577734 -293.789774) (xy 309.533272 -293.810872)
			(xy 309.486001 -293.824564) (xy 309.437146 -293.830496) (xy 309.387971 -293.828515) (xy 309.339752 -293.818671)
			(xy 309.293736 -293.801219) (xy 309.251115 -293.776612) (xy 309.212994 -293.745487) (xy 309.180359 -293.70865)
			(xy 309.154056 -293.667054) (xy 309.134765 -293.621778) (xy 309.122988 -293.573994) (xy 309.119028 -293.52494)
			(xy 308.78018 -293.52494) (xy 308.779685 -293.549547) (xy 308.77179 -293.598124) (xy 308.756206 -293.644805)
			(xy 308.733335 -293.688382) (xy 308.70377 -293.727726) (xy 308.668277 -293.761818) (xy 308.627774 -293.789774)
			(xy 308.583312 -293.810872) (xy 308.536041 -293.824564) (xy 308.487186 -293.830496) (xy 308.438011 -293.828515)
			(xy 308.389792 -293.818671) (xy 308.343776 -293.801219) (xy 308.301155 -293.776612) (xy 308.263034 -293.745487)
			(xy 308.230399 -293.70865) (xy 308.204096 -293.667054) (xy 308.184805 -293.621778) (xy 308.173028 -293.573994)
			(xy 308.169068 -293.52494) (xy 307.83022 -293.52494) (xy 307.829725 -293.549547) (xy 307.82183 -293.598124)
			(xy 307.806246 -293.644805) (xy 307.783375 -293.688382) (xy 307.75381 -293.727726) (xy 307.718317 -293.761818)
			(xy 307.677814 -293.789774) (xy 307.633352 -293.810872) (xy 307.586081 -293.824564) (xy 307.537226 -293.830496)
			(xy 307.488051 -293.828515) (xy 307.439832 -293.818671) (xy 307.393816 -293.801219) (xy 307.351195 -293.776612)
			(xy 307.313074 -293.745487) (xy 307.280439 -293.70865) (xy 307.254136 -293.667054) (xy 307.234845 -293.621778)
			(xy 307.223068 -293.573994) (xy 307.219108 -293.52494) (xy 306.88026 -293.52494) (xy 306.879765 -293.549547)
			(xy 306.87187 -293.598124) (xy 306.856286 -293.644805) (xy 306.833415 -293.688382) (xy 306.80385 -293.727726)
			(xy 306.768357 -293.761818) (xy 306.727854 -293.789774) (xy 306.683392 -293.810872) (xy 306.636121 -293.824564)
			(xy 306.587266 -293.830496) (xy 306.538091 -293.828515) (xy 306.489872 -293.818671) (xy 306.443856 -293.801219)
			(xy 306.401235 -293.776612) (xy 306.363114 -293.745487) (xy 306.330479 -293.70865) (xy 306.304176 -293.667054)
			(xy 306.284885 -293.621778) (xy 306.273108 -293.573994) (xy 306.269148 -293.52494) (xy 305.930046 -293.52494)
			(xy 305.929551 -293.549547) (xy 305.921656 -293.598124) (xy 305.906072 -293.644805) (xy 305.883201 -293.688382)
			(xy 305.853636 -293.727726) (xy 305.818143 -293.761818) (xy 305.77764 -293.789774) (xy 305.733178 -293.810872)
			(xy 305.685907 -293.824564) (xy 305.637052 -293.830496) (xy 305.587877 -293.828515) (xy 305.539658 -293.818671)
			(xy 305.493642 -293.801219) (xy 305.451021 -293.776612) (xy 305.4129 -293.745487) (xy 305.380265 -293.70865)
			(xy 305.353962 -293.667054) (xy 305.334671 -293.621778) (xy 305.322894 -293.573994) (xy 305.318934 -293.52494)
			(xy 304.030126 -293.52494) (xy 304.029631 -293.549547) (xy 304.021736 -293.598124) (xy 304.006152 -293.644805)
			(xy 303.983281 -293.688382) (xy 303.953716 -293.727726) (xy 303.918223 -293.761818) (xy 303.87772 -293.789774)
			(xy 303.833258 -293.810872) (xy 303.785987 -293.824564) (xy 303.737132 -293.830496) (xy 303.687957 -293.828515)
			(xy 303.639738 -293.818671) (xy 303.593722 -293.801219) (xy 303.551101 -293.776612) (xy 303.51298 -293.745487)
			(xy 303.480345 -293.70865) (xy 303.454042 -293.667054) (xy 303.434751 -293.621778) (xy 303.422974 -293.573994)
			(xy 303.419014 -293.52494) (xy 303.080166 -293.52494) (xy 303.079671 -293.549547) (xy 303.071776 -293.598124)
			(xy 303.056192 -293.644805) (xy 303.033321 -293.688382) (xy 303.003756 -293.727726) (xy 302.968263 -293.761818)
			(xy 302.92776 -293.789774) (xy 302.883298 -293.810872) (xy 302.836027 -293.824564) (xy 302.787172 -293.830496)
			(xy 302.737997 -293.828515) (xy 302.689778 -293.818671) (xy 302.643762 -293.801219) (xy 302.601141 -293.776612)
			(xy 302.56302 -293.745487) (xy 302.530385 -293.70865) (xy 302.504082 -293.667054) (xy 302.484791 -293.621778)
			(xy 302.473014 -293.573994) (xy 302.469054 -293.52494) (xy 302.130206 -293.52494) (xy 302.129711 -293.549547)
			(xy 302.121816 -293.598124) (xy 302.106232 -293.644805) (xy 302.083361 -293.688382) (xy 302.053796 -293.727726)
			(xy 302.018303 -293.761818) (xy 301.9778 -293.789774) (xy 301.933338 -293.810872) (xy 301.886067 -293.824564)
			(xy 301.837212 -293.830496) (xy 301.788037 -293.828515) (xy 301.739818 -293.818671) (xy 301.693802 -293.801219)
			(xy 301.651181 -293.776612) (xy 301.61306 -293.745487) (xy 301.580425 -293.70865) (xy 301.554122 -293.667054)
			(xy 301.534831 -293.621778) (xy 301.523054 -293.573994) (xy 301.519094 -293.52494) (xy 301.179992 -293.52494)
			(xy 301.179497 -293.549547) (xy 301.171602 -293.598124) (xy 301.156018 -293.644805) (xy 301.133147 -293.688382)
			(xy 301.103582 -293.727726) (xy 301.068089 -293.761818) (xy 301.027586 -293.789774) (xy 300.983124 -293.810872)
			(xy 300.935853 -293.824564) (xy 300.886998 -293.830496) (xy 300.837823 -293.828515) (xy 300.789604 -293.818671)
			(xy 300.743588 -293.801219) (xy 300.700967 -293.776612) (xy 300.662846 -293.745487) (xy 300.630211 -293.70865)
			(xy 300.603908 -293.667054) (xy 300.584617 -293.621778) (xy 300.57284 -293.573994) (xy 300.56888 -293.52494)
			(xy 300.230032 -293.52494) (xy 300.229537 -293.549547) (xy 300.221642 -293.598124) (xy 300.206058 -293.644805)
			(xy 300.183187 -293.688382) (xy 300.153622 -293.727726) (xy 300.118129 -293.761818) (xy 300.077626 -293.789774)
			(xy 300.033164 -293.810872) (xy 299.985893 -293.824564) (xy 299.937038 -293.830496) (xy 299.887863 -293.828515)
			(xy 299.839644 -293.818671) (xy 299.793628 -293.801219) (xy 299.751007 -293.776612) (xy 299.712886 -293.745487)
			(xy 299.680251 -293.70865) (xy 299.653948 -293.667054) (xy 299.634657 -293.621778) (xy 299.62288 -293.573994)
			(xy 299.61892 -293.52494) (xy 299.280072 -293.52494) (xy 299.279577 -293.549547) (xy 299.271682 -293.598124)
			(xy 299.256098 -293.644805) (xy 299.233227 -293.688382) (xy 299.203662 -293.727726) (xy 299.168169 -293.761818)
			(xy 299.127666 -293.789774) (xy 299.083204 -293.810872) (xy 299.035933 -293.824564) (xy 298.987078 -293.830496)
			(xy 298.937903 -293.828515) (xy 298.889684 -293.818671) (xy 298.843668 -293.801219) (xy 298.801047 -293.776612)
			(xy 298.762926 -293.745487) (xy 298.730291 -293.70865) (xy 298.703988 -293.667054) (xy 298.684697 -293.621778)
			(xy 298.67292 -293.573994) (xy 298.66896 -293.52494) (xy 298.330112 -293.52494) (xy 298.329617 -293.549547)
			(xy 298.321722 -293.598124) (xy 298.306138 -293.644805) (xy 298.283267 -293.688382) (xy 298.253702 -293.727726)
			(xy 298.218209 -293.761818) (xy 298.177706 -293.789774) (xy 298.133244 -293.810872) (xy 298.085973 -293.824564)
			(xy 298.037118 -293.830496) (xy 297.987943 -293.828515) (xy 297.939724 -293.818671) (xy 297.893708 -293.801219)
			(xy 297.851087 -293.776612) (xy 297.812966 -293.745487) (xy 297.780331 -293.70865) (xy 297.754028 -293.667054)
			(xy 297.734737 -293.621778) (xy 297.72296 -293.573994) (xy 297.719 -293.52494) (xy 297.380152 -293.52494)
			(xy 297.379657 -293.549547) (xy 297.371762 -293.598124) (xy 297.356178 -293.644805) (xy 297.333307 -293.688382)
			(xy 297.303742 -293.727726) (xy 297.268249 -293.761818) (xy 297.227746 -293.789774) (xy 297.183284 -293.810872)
			(xy 297.136013 -293.824564) (xy 297.087158 -293.830496) (xy 297.037983 -293.828515) (xy 296.989764 -293.818671)
			(xy 296.943748 -293.801219) (xy 296.901127 -293.776612) (xy 296.863006 -293.745487) (xy 296.830371 -293.70865)
			(xy 296.804068 -293.667054) (xy 296.784777 -293.621778) (xy 296.773 -293.573994) (xy 296.76904 -293.52494)
			(xy 296.430192 -293.52494) (xy 296.429697 -293.549547) (xy 296.421802 -293.598124) (xy 296.406218 -293.644805)
			(xy 296.383347 -293.688382) (xy 296.353782 -293.727726) (xy 296.318289 -293.761818) (xy 296.277786 -293.789774)
			(xy 296.233324 -293.810872) (xy 296.186053 -293.824564) (xy 296.137198 -293.830496) (xy 296.088023 -293.828515)
			(xy 296.039804 -293.818671) (xy 295.993788 -293.801219) (xy 295.951167 -293.776612) (xy 295.913046 -293.745487)
			(xy 295.880411 -293.70865) (xy 295.854108 -293.667054) (xy 295.834817 -293.621778) (xy 295.82304 -293.573994)
			(xy 295.81908 -293.52494) (xy 295.480232 -293.52494) (xy 295.479737 -293.549547) (xy 295.471842 -293.598124)
			(xy 295.456258 -293.644805) (xy 295.433387 -293.688382) (xy 295.403822 -293.727726) (xy 295.368329 -293.761818)
			(xy 295.327826 -293.789774) (xy 295.283364 -293.810872) (xy 295.236093 -293.824564) (xy 295.187238 -293.830496)
			(xy 295.138063 -293.828515) (xy 295.089844 -293.818671) (xy 295.043828 -293.801219) (xy 295.001207 -293.776612)
			(xy 294.963086 -293.745487) (xy 294.930451 -293.70865) (xy 294.904148 -293.667054) (xy 294.884857 -293.621778)
			(xy 294.87308 -293.573994) (xy 294.86912 -293.52494) (xy 294.530018 -293.52494) (xy 294.529523 -293.549547)
			(xy 294.521628 -293.598124) (xy 294.506044 -293.644805) (xy 294.483173 -293.688382) (xy 294.453608 -293.727726)
			(xy 294.418115 -293.761818) (xy 294.377612 -293.789774) (xy 294.33315 -293.810872) (xy 294.285879 -293.824564)
			(xy 294.237024 -293.830496) (xy 294.187849 -293.828515) (xy 294.13963 -293.818671) (xy 294.093614 -293.801219)
			(xy 294.050993 -293.776612) (xy 294.012872 -293.745487) (xy 293.980237 -293.70865) (xy 293.953934 -293.667054)
			(xy 293.934643 -293.621778) (xy 293.922866 -293.573994) (xy 293.918906 -293.52494) (xy 293.580058 -293.52494)
			(xy 293.579563 -293.549547) (xy 293.571668 -293.598124) (xy 293.556084 -293.644805) (xy 293.533213 -293.688382)
			(xy 293.503648 -293.727726) (xy 293.468155 -293.761818) (xy 293.427652 -293.789774) (xy 293.38319 -293.810872)
			(xy 293.335919 -293.824564) (xy 293.287064 -293.830496) (xy 293.237889 -293.828515) (xy 293.18967 -293.818671)
			(xy 293.143654 -293.801219) (xy 293.101033 -293.776612) (xy 293.062912 -293.745487) (xy 293.030277 -293.70865)
			(xy 293.003974 -293.667054) (xy 292.984683 -293.621778) (xy 292.972906 -293.573994) (xy 292.968946 -293.52494)
			(xy 292.630098 -293.52494) (xy 292.629603 -293.549547) (xy 292.621708 -293.598124) (xy 292.606124 -293.644805)
			(xy 292.583253 -293.688382) (xy 292.553688 -293.727726) (xy 292.518195 -293.761818) (xy 292.477692 -293.789774)
			(xy 292.43323 -293.810872) (xy 292.385959 -293.824564) (xy 292.337104 -293.830496) (xy 292.287929 -293.828515)
			(xy 292.23971 -293.818671) (xy 292.193694 -293.801219) (xy 292.151073 -293.776612) (xy 292.112952 -293.745487)
			(xy 292.080317 -293.70865) (xy 292.054014 -293.667054) (xy 292.034723 -293.621778) (xy 292.022946 -293.573994)
			(xy 292.018986 -293.52494) (xy 290.730178 -293.52494) (xy 290.729683 -293.549547) (xy 290.721788 -293.598124)
			(xy 290.706204 -293.644805) (xy 290.683333 -293.688382) (xy 290.653768 -293.727726) (xy 290.618275 -293.761818)
			(xy 290.577772 -293.789774) (xy 290.53331 -293.810872) (xy 290.486039 -293.824564) (xy 290.437184 -293.830496)
			(xy 290.388009 -293.828515) (xy 290.33979 -293.818671) (xy 290.293774 -293.801219) (xy 290.251153 -293.776612)
			(xy 290.213032 -293.745487) (xy 290.180397 -293.70865) (xy 290.154094 -293.667054) (xy 290.134803 -293.621778)
			(xy 290.123026 -293.573994) (xy 290.119066 -293.52494) (xy 289.780218 -293.52494) (xy 289.779723 -293.549547)
			(xy 289.771828 -293.598124) (xy 289.756244 -293.644805) (xy 289.733373 -293.688382) (xy 289.703808 -293.727726)
			(xy 289.668315 -293.761818) (xy 289.627812 -293.789774) (xy 289.58335 -293.810872) (xy 289.536079 -293.824564)
			(xy 289.487224 -293.830496) (xy 289.438049 -293.828515) (xy 289.38983 -293.818671) (xy 289.343814 -293.801219)
			(xy 289.301193 -293.776612) (xy 289.263072 -293.745487) (xy 289.230437 -293.70865) (xy 289.204134 -293.667054)
			(xy 289.184843 -293.621778) (xy 289.173066 -293.573994) (xy 289.169106 -293.52494) (xy 288.830004 -293.52494)
			(xy 288.829509 -293.549547) (xy 288.821614 -293.598124) (xy 288.80603 -293.644805) (xy 288.783159 -293.688382)
			(xy 288.753594 -293.727726) (xy 288.718101 -293.761818) (xy 288.677598 -293.789774) (xy 288.633136 -293.810872)
			(xy 288.585865 -293.824564) (xy 288.53701 -293.830496) (xy 288.487835 -293.828515) (xy 288.439616 -293.818671)
			(xy 288.3936 -293.801219) (xy 288.350979 -293.776612) (xy 288.312858 -293.745487) (xy 288.280223 -293.70865)
			(xy 288.25392 -293.667054) (xy 288.234629 -293.621778) (xy 288.222852 -293.573994) (xy 288.218892 -293.52494)
			(xy 287.880044 -293.52494) (xy 287.879549 -293.549547) (xy 287.871654 -293.598124) (xy 287.85607 -293.644805)
			(xy 287.833199 -293.688382) (xy 287.803634 -293.727726) (xy 287.768141 -293.761818) (xy 287.727638 -293.789774)
			(xy 287.683176 -293.810872) (xy 287.635905 -293.824564) (xy 287.58705 -293.830496) (xy 287.537875 -293.828515)
			(xy 287.489656 -293.818671) (xy 287.44364 -293.801219) (xy 287.401019 -293.776612) (xy 287.362898 -293.745487)
			(xy 287.330263 -293.70865) (xy 287.30396 -293.667054) (xy 287.284669 -293.621778) (xy 287.272892 -293.573994)
			(xy 287.268932 -293.52494) (xy 286.930084 -293.52494) (xy 286.929589 -293.549547) (xy 286.921694 -293.598124)
			(xy 286.90611 -293.644805) (xy 286.883239 -293.688382) (xy 286.853674 -293.727726) (xy 286.818181 -293.761818)
			(xy 286.777678 -293.789774) (xy 286.733216 -293.810872) (xy 286.685945 -293.824564) (xy 286.63709 -293.830496)
			(xy 286.587915 -293.828515) (xy 286.539696 -293.818671) (xy 286.49368 -293.801219) (xy 286.451059 -293.776612)
			(xy 286.412938 -293.745487) (xy 286.380303 -293.70865) (xy 286.354 -293.667054) (xy 286.334709 -293.621778)
			(xy 286.322932 -293.573994) (xy 286.318972 -293.52494) (xy 285.980124 -293.52494) (xy 285.979629 -293.549547)
			(xy 285.971734 -293.598124) (xy 285.95615 -293.644805) (xy 285.933279 -293.688382) (xy 285.903714 -293.727726)
			(xy 285.868221 -293.761818) (xy 285.827718 -293.789774) (xy 285.783256 -293.810872) (xy 285.735985 -293.824564)
			(xy 285.68713 -293.830496) (xy 285.637955 -293.828515) (xy 285.589736 -293.818671) (xy 285.54372 -293.801219)
			(xy 285.501099 -293.776612) (xy 285.462978 -293.745487) (xy 285.430343 -293.70865) (xy 285.40404 -293.667054)
			(xy 285.384749 -293.621778) (xy 285.372972 -293.573994) (xy 285.369012 -293.52494) (xy 285.030164 -293.52494)
			(xy 285.029669 -293.549547) (xy 285.021774 -293.598124) (xy 285.00619 -293.644805) (xy 284.983319 -293.688382)
			(xy 284.953754 -293.727726) (xy 284.918261 -293.761818) (xy 284.877758 -293.789774) (xy 284.833296 -293.810872)
			(xy 284.786025 -293.824564) (xy 284.73717 -293.830496) (xy 284.687995 -293.828515) (xy 284.639776 -293.818671)
			(xy 284.59376 -293.801219) (xy 284.551139 -293.776612) (xy 284.513018 -293.745487) (xy 284.480383 -293.70865)
			(xy 284.45408 -293.667054) (xy 284.434789 -293.621778) (xy 284.423012 -293.573994) (xy 284.419052 -293.52494)
			(xy 284.080204 -293.52494) (xy 284.079709 -293.549547) (xy 284.071814 -293.598124) (xy 284.05623 -293.644805)
			(xy 284.033359 -293.688382) (xy 284.003794 -293.727726) (xy 283.968301 -293.761818) (xy 283.927798 -293.789774)
			(xy 283.883336 -293.810872) (xy 283.836065 -293.824564) (xy 283.78721 -293.830496) (xy 283.738035 -293.828515)
			(xy 283.689816 -293.818671) (xy 283.6438 -293.801219) (xy 283.601179 -293.776612) (xy 283.563058 -293.745487)
			(xy 283.530423 -293.70865) (xy 283.50412 -293.667054) (xy 283.484829 -293.621778) (xy 283.473052 -293.573994)
			(xy 283.469092 -293.52494) (xy 283.130244 -293.52494) (xy 283.129749 -293.549547) (xy 283.121854 -293.598124)
			(xy 283.10627 -293.644805) (xy 283.083399 -293.688382) (xy 283.053834 -293.727726) (xy 283.018341 -293.761818)
			(xy 282.977838 -293.789774) (xy 282.933376 -293.810872) (xy 282.886105 -293.824564) (xy 282.83725 -293.830496)
			(xy 282.788075 -293.828515) (xy 282.739856 -293.818671) (xy 282.69384 -293.801219) (xy 282.651219 -293.776612)
			(xy 282.613098 -293.745487) (xy 282.580463 -293.70865) (xy 282.55416 -293.667054) (xy 282.534869 -293.621778)
			(xy 282.523092 -293.573994) (xy 282.519132 -293.52494) (xy 282.18003 -293.52494) (xy 282.179535 -293.549547)
			(xy 282.17164 -293.598124) (xy 282.156056 -293.644805) (xy 282.133185 -293.688382) (xy 282.10362 -293.727726)
			(xy 282.068127 -293.761818) (xy 282.027624 -293.789774) (xy 281.983162 -293.810872) (xy 281.935891 -293.824564)
			(xy 281.887036 -293.830496) (xy 281.837861 -293.828515) (xy 281.789642 -293.818671) (xy 281.743626 -293.801219)
			(xy 281.701005 -293.776612) (xy 281.662884 -293.745487) (xy 281.630249 -293.70865) (xy 281.603946 -293.667054)
			(xy 281.584655 -293.621778) (xy 281.572878 -293.573994) (xy 281.568918 -293.52494) (xy 281.23007 -293.52494)
			(xy 281.229575 -293.549547) (xy 281.22168 -293.598124) (xy 281.206096 -293.644805) (xy 281.183225 -293.688382)
			(xy 281.15366 -293.727726) (xy 281.118167 -293.761818) (xy 281.077664 -293.789774) (xy 281.033202 -293.810872)
			(xy 280.985931 -293.824564) (xy 280.937076 -293.830496) (xy 280.887901 -293.828515) (xy 280.839682 -293.818671)
			(xy 280.793666 -293.801219) (xy 280.751045 -293.776612) (xy 280.712924 -293.745487) (xy 280.680289 -293.70865)
			(xy 280.653986 -293.667054) (xy 280.634695 -293.621778) (xy 280.622918 -293.573994) (xy 280.618958 -293.52494)
			(xy 280.28011 -293.52494) (xy 280.279615 -293.549547) (xy 280.27172 -293.598124) (xy 280.256136 -293.644805)
			(xy 280.233265 -293.688382) (xy 280.2037 -293.727726) (xy 280.168207 -293.761818) (xy 280.127704 -293.789774)
			(xy 280.083242 -293.810872) (xy 280.035971 -293.824564) (xy 279.987116 -293.830496) (xy 279.937941 -293.828515)
			(xy 279.889722 -293.818671) (xy 279.843706 -293.801219) (xy 279.801085 -293.776612) (xy 279.762964 -293.745487)
			(xy 279.730329 -293.70865) (xy 279.704026 -293.667054) (xy 279.684735 -293.621778) (xy 279.672958 -293.573994)
			(xy 279.668998 -293.52494) (xy 278.38019 -293.52494) (xy 278.379695 -293.549547) (xy 278.3718 -293.598124)
			(xy 278.356216 -293.644805) (xy 278.333345 -293.688382) (xy 278.30378 -293.727726) (xy 278.268287 -293.761818)
			(xy 278.227784 -293.789774) (xy 278.183322 -293.810872) (xy 278.136051 -293.824564) (xy 278.087196 -293.830496)
			(xy 278.038021 -293.828515) (xy 277.989802 -293.818671) (xy 277.943786 -293.801219) (xy 277.901165 -293.776612)
			(xy 277.863044 -293.745487) (xy 277.830409 -293.70865) (xy 277.804106 -293.667054) (xy 277.784815 -293.621778)
			(xy 277.773038 -293.573994) (xy 277.769078 -293.52494) (xy 276.480016 -293.52494) (xy 276.479521 -293.549547)
			(xy 276.471626 -293.598124) (xy 276.456042 -293.644805) (xy 276.433171 -293.688382) (xy 276.403606 -293.727726)
			(xy 276.368113 -293.761818) (xy 276.32761 -293.789774) (xy 276.283148 -293.810872) (xy 276.235877 -293.824564)
			(xy 276.187022 -293.830496) (xy 276.137847 -293.828515) (xy 276.089628 -293.818671) (xy 276.043612 -293.801219)
			(xy 276.000991 -293.776612) (xy 275.96287 -293.745487) (xy 275.930235 -293.70865) (xy 275.903932 -293.667054)
			(xy 275.884641 -293.621778) (xy 275.872864 -293.573994) (xy 275.868904 -293.52494) (xy 275.580856 -293.52494)
			(xy 275.580358 -293.551589) (xy 275.572415 -293.604293) (xy 275.556705 -293.655223) (xy 275.533579 -293.703244)
			(xy 275.503555 -293.747281) (xy 275.467303 -293.786352) (xy 275.425632 -293.819583) (xy 275.379474 -293.846232)
			(xy 275.32986 -293.865704) (xy 275.277898 -293.877564) (xy 275.224748 -293.881548) (xy 275.171598 -293.877564)
			(xy 275.119636 -293.865704) (xy 275.070022 -293.846232) (xy 275.023864 -293.819583) (xy 274.982193 -293.786352)
			(xy 274.945941 -293.747281) (xy 274.915917 -293.703244) (xy 274.892791 -293.655223) (xy 274.877081 -293.604293)
			(xy 274.869138 -293.551589) (xy 274.579269 -293.551589) (xy 274.571706 -293.598124) (xy 274.556122 -293.644805)
			(xy 274.533251 -293.688382) (xy 274.503686 -293.727726) (xy 274.468193 -293.761818) (xy 274.42769 -293.789774)
			(xy 274.383228 -293.810872) (xy 274.335957 -293.824564) (xy 274.287102 -293.830496) (xy 274.237927 -293.828515)
			(xy 274.189708 -293.818671) (xy 274.143692 -293.801219) (xy 274.101071 -293.776612) (xy 274.06295 -293.745487)
			(xy 274.030315 -293.70865) (xy 274.004012 -293.667054) (xy 273.984721 -293.621778) (xy 273.972944 -293.573994)
			(xy 273.968984 -293.52494) (xy 273.630136 -293.52494) (xy 273.629641 -293.549547) (xy 273.621746 -293.598124)
			(xy 273.606162 -293.644805) (xy 273.583291 -293.688382) (xy 273.553726 -293.727726) (xy 273.518233 -293.761818)
			(xy 273.47773 -293.789774) (xy 273.433268 -293.810872) (xy 273.385997 -293.824564) (xy 273.337142 -293.830496)
			(xy 273.287967 -293.828515) (xy 273.239748 -293.818671) (xy 273.193732 -293.801219) (xy 273.151111 -293.776612)
			(xy 273.11299 -293.745487) (xy 273.080355 -293.70865) (xy 273.054052 -293.667054) (xy 273.034761 -293.621778)
			(xy 273.022984 -293.573994) (xy 273.019024 -293.52494) (xy 272.680176 -293.52494) (xy 272.679681 -293.549547)
			(xy 272.671786 -293.598124) (xy 272.656202 -293.644805) (xy 272.633331 -293.688382) (xy 272.603766 -293.727726)
			(xy 272.568273 -293.761818) (xy 272.52777 -293.789774) (xy 272.483308 -293.810872) (xy 272.436037 -293.824564)
			(xy 272.387182 -293.830496) (xy 272.338007 -293.828515) (xy 272.289788 -293.818671) (xy 272.243772 -293.801219)
			(xy 272.201151 -293.776612) (xy 272.16303 -293.745487) (xy 272.130395 -293.70865) (xy 272.104092 -293.667054)
			(xy 272.084801 -293.621778) (xy 272.073024 -293.573994) (xy 272.069064 -293.52494) (xy 271.730216 -293.52494)
			(xy 271.729721 -293.549547) (xy 271.721826 -293.598124) (xy 271.706242 -293.644805) (xy 271.683371 -293.688382)
			(xy 271.653806 -293.727726) (xy 271.618313 -293.761818) (xy 271.57781 -293.789774) (xy 271.533348 -293.810872)
			(xy 271.486077 -293.824564) (xy 271.437222 -293.830496) (xy 271.388047 -293.828515) (xy 271.339828 -293.818671)
			(xy 271.293812 -293.801219) (xy 271.251191 -293.776612) (xy 271.21307 -293.745487) (xy 271.180435 -293.70865)
			(xy 271.154132 -293.667054) (xy 271.134841 -293.621778) (xy 271.123064 -293.573994) (xy 271.119104 -293.52494)
			(xy 270.780256 -293.52494) (xy 270.779761 -293.549547) (xy 270.771866 -293.598124) (xy 270.756282 -293.644805)
			(xy 270.733411 -293.688382) (xy 270.703846 -293.727726) (xy 270.668353 -293.761818) (xy 270.62785 -293.789774)
			(xy 270.583388 -293.810872) (xy 270.536117 -293.824564) (xy 270.487262 -293.830496) (xy 270.438087 -293.828515)
			(xy 270.389868 -293.818671) (xy 270.343852 -293.801219) (xy 270.301231 -293.776612) (xy 270.26311 -293.745487)
			(xy 270.230475 -293.70865) (xy 270.204172 -293.667054) (xy 270.184881 -293.621778) (xy 270.173104 -293.573994)
			(xy 270.169144 -293.52494) (xy 266.583577 -293.52494) (xy 266.575801 -293.577776) (xy 266.559733 -293.631183)
			(xy 266.536061 -293.68168) (xy 266.505288 -293.728193) (xy 266.468071 -293.76973) (xy 266.425203 -293.805405)
			(xy 266.377597 -293.834459) (xy 266.326268 -293.856271) (xy 266.272311 -293.870377) (xy 266.216874 -293.876477)
			(xy 266.16114 -293.87444) (xy 266.106297 -293.86431) (xy 266.053513 -293.846303) (xy 266.003913 -293.820802)
			(xy 265.958555 -293.788351) (xy 265.918406 -293.749642) (xy 265.88432 -293.705499) (xy 265.857024 -293.656864)
			(xy 265.837101 -293.604773) (xy 265.824975 -293.550336) (xy 265.820904 -293.494714) (xy 265.69797 -293.494714)
			(xy 265.697461 -293.5226) (xy 265.689341 -293.577776) (xy 265.673273 -293.631183) (xy 265.649601 -293.68168)
			(xy 265.618828 -293.728193) (xy 265.581611 -293.76973) (xy 265.538743 -293.805405) (xy 265.491137 -293.834459)
			(xy 265.439808 -293.856271) (xy 265.385851 -293.870377) (xy 265.330414 -293.876477) (xy 265.27468 -293.87444)
			(xy 265.219837 -293.86431) (xy 265.167053 -293.846303) (xy 265.117453 -293.820802) (xy 265.072095 -293.788351)
			(xy 265.031946 -293.749642) (xy 264.99786 -293.705499) (xy 264.970564 -293.656864) (xy 264.950641 -293.604773)
			(xy 264.938515 -293.550336) (xy 264.934444 -293.494714) (xy 264.30097 -293.494714) (xy 264.300484 -293.521965)
			(xy 264.292728 -293.575913) (xy 264.277373 -293.628208) (xy 264.254731 -293.677785) (xy 264.225265 -293.723635)
			(xy 264.189574 -293.764826) (xy 264.148383 -293.800517) (xy 264.102533 -293.829983) (xy 264.052956 -293.852625)
			(xy 264.000661 -293.86798) (xy 263.946713 -293.875736) (xy 263.892211 -293.875736) (xy 263.838263 -293.86798)
			(xy 263.785968 -293.852625) (xy 263.736391 -293.829983) (xy 263.690541 -293.800517) (xy 263.64935 -293.764826)
			(xy 263.613659 -293.723635) (xy 263.584193 -293.677785) (xy 263.561551 -293.628208) (xy 263.546196 -293.575913)
			(xy 263.53844 -293.521965) (xy 263.537954 -293.494714) (xy 249.737118 -293.494714) (xy 249.737118 -293.808658)
			(xy 249.737552 -293.818723) (xy 249.745283 -293.837311) (xy 249.752104 -293.844726) (xy 250.114308 -294.20693)
			(xy 250.121704 -294.213783) (xy 250.140302 -294.221525) (xy 250.150376 -294.221916) (xy 251.123196 -294.221916)
			(xy 251.131832 -294.218614) (xy 251.204647 -294.19094) (xy 251.35239 -294.141516) (xy 251.502254 -294.098955)
			(xy 251.65392 -294.063348) (xy 251.807067 -294.03477) (xy 251.961368 -294.013283) (xy 252.116496 -293.998931)
			(xy 252.272121 -293.991745) (xy 252.350016 -293.991284) (xy 252.427911 -293.991738) (xy 252.583535 -293.998932)
			(xy 252.738662 -294.01329) (xy 252.892962 -294.034782) (xy 253.046108 -294.063362) (xy 253.197775 -294.098968)
			(xy 253.347639 -294.141527) (xy 253.495383 -294.190947) (xy 253.5682 -294.218614) (xy 253.572609 -294.220176)
			(xy 253.581811 -294.221841) (xy 253.586488 -294.221916) (xy 268.388846 -294.221916) (xy 268.395863 -294.22172)
			(xy 268.409386 -294.217971) (xy 268.415516 -294.21455) (xy 268.439675 -294.200479) (xy 268.49186 -294.180436)
			(xy 268.546823 -294.170232) (xy 268.574774 -294.169592) (xy 268.602724 -294.170241) (xy 268.657684 -294.180451)
			(xy 268.709873 -294.20048) (xy 268.734032 -294.21455) (xy 268.740143 -294.218017) (xy 268.753678 -294.22177)
			(xy 268.760702 -294.221916) (xy 269.338806 -294.221916) (xy 269.345825 -294.221726) (xy 269.359353 -294.217986)
			(xy 269.365476 -294.21455) (xy 269.389634 -294.200475) (xy 269.441819 -294.180425) (xy 269.496782 -294.170215)
			(xy 269.524734 -294.169592) (xy 269.552682 -294.170246) (xy 269.607638 -294.180466) (xy 269.659821 -294.200504)
			(xy 269.683992 -294.21455) (xy 269.690105 -294.218009) (xy 269.70364 -294.221746) (xy 269.710662 -294.221916)
			(xy 270.28902 -294.221916) (xy 270.296038 -294.221724) (xy 270.309564 -294.217981) (xy 270.31569 -294.21455)
			(xy 270.339848 -294.200477) (xy 270.392033 -294.180429) (xy 270.446997 -294.170221) (xy 270.474948 -294.169592)
			(xy 270.502898 -294.170238) (xy 270.557861 -294.180444) (xy 270.610053 -294.20047) (xy 270.634206 -294.21455)
			(xy 270.64032 -294.218008) (xy 270.653854 -294.22174) (xy 270.660876 -294.221916) (xy 273.1389 -294.221916)
			(xy 273.145919 -294.221726) (xy 273.159448 -294.217988) (xy 273.16557 -294.21455) (xy 273.189728 -294.200475)
			(xy 273.241913 -294.180424) (xy 273.296876 -294.170212) (xy 273.324828 -294.169592) (xy 273.352776 -294.170245)
			(xy 273.407732 -294.180464) (xy 273.459916 -294.200501) (xy 273.484086 -294.21455) (xy 273.490199 -294.21801)
			(xy 273.503734 -294.221748) (xy 273.510756 -294.221916) (xy 273.994372 -294.221916) (xy 273.999126 -294.22182)
			(xy 274.008463 -294.220032) (xy 274.012914 -294.21836) (xy 274.03806 -294.208708) (xy 274.044664 -294.20312)
			(xy 274.066238 -294.185555) (xy 274.113768 -294.156645) (xy 274.165214 -294.135478) (xy 274.219326 -294.122568)
			(xy 274.274788 -294.11823) (xy 274.33025 -294.122568) (xy 274.384362 -294.135478) (xy 274.435808 -294.156645)
			(xy 274.483338 -294.185555) (xy 274.504912 -294.20312) (xy 274.511516 -294.208708) (xy 274.536662 -294.21836)
			(xy 274.541125 -294.219988) (xy 274.550455 -294.22178) (xy 274.555204 -294.221916) (xy 275.03882 -294.221916)
			(xy 275.045838 -294.221724) (xy 275.059364 -294.217981) (xy 275.06549 -294.21455) (xy 275.089648 -294.200477)
			(xy 275.141833 -294.180429) (xy 275.196797 -294.170221) (xy 275.224748 -294.169592) (xy 275.252698 -294.170238)
			(xy 275.307661 -294.180444) (xy 275.359853 -294.20047) (xy 275.384006 -294.21455) (xy 275.39012 -294.218008)
			(xy 275.403654 -294.22174) (xy 275.410676 -294.221916) (xy 275.98878 -294.221916) (xy 275.9958 -294.221729)
			(xy 276.009331 -294.217995) (xy 276.01545 -294.21455) (xy 276.03961 -294.200481) (xy 276.091795 -294.180444)
			(xy 276.146758 -294.170246) (xy 276.174708 -294.169592) (xy 276.202657 -294.170244) (xy 276.257615 -294.180459)
			(xy 276.3098 -294.200494) (xy 276.333966 -294.21455) (xy 276.340078 -294.218013) (xy 276.353613 -294.221756)
			(xy 276.360636 -294.221916) (xy 276.938994 -294.221916) (xy 276.946013 -294.221727) (xy 276.959543 -294.21799)
			(xy 276.965664 -294.21455) (xy 276.989822 -294.200475) (xy 277.042006 -294.180422) (xy 277.09697 -294.170209)
			(xy 277.124922 -294.169592) (xy 277.152871 -294.170245) (xy 277.207827 -294.180463) (xy 277.260011 -294.200499)
			(xy 277.28418 -294.21455) (xy 277.290293 -294.218011) (xy 277.303827 -294.221751) (xy 277.31085 -294.221916)
			(xy 277.888954 -294.221916) (xy 277.895971 -294.221719) (xy 277.909492 -294.217969) (xy 277.915624 -294.21455)
			(xy 277.939783 -294.200479) (xy 277.991969 -294.180438) (xy 278.046931 -294.170235) (xy 278.074882 -294.169592)
			(xy 278.102832 -294.170241) (xy 278.157791 -294.180453) (xy 278.20998 -294.200483) (xy 278.23414 -294.21455)
			(xy 278.240252 -294.218016) (xy 278.253786 -294.221767) (xy 278.26081 -294.221916) (xy 278.838914 -294.221916)
			(xy 278.845932 -294.221724) (xy 278.859459 -294.217983) (xy 278.865584 -294.21455) (xy 278.889742 -294.200476)
			(xy 278.941927 -294.180428) (xy 278.996891 -294.170218) (xy 279.024842 -294.169592) (xy 279.05279 -294.170247)
			(xy 279.107745 -294.180468) (xy 279.159927 -294.200507) (xy 279.1841 -294.21455) (xy 279.190213 -294.218009)
			(xy 279.203748 -294.221743) (xy 279.21077 -294.221916) (xy 279.789382 -294.221916) (xy 279.804368 -294.221662)
			(xy 279.826111 -294.20767) (xy 279.873245 -294.186424) (xy 279.923286 -294.173429) (xy 279.974802 -294.169056)
			(xy 280.026318 -294.173429) (xy 280.076359 -294.186424) (xy 280.123493 -294.20767) (xy 280.145236 -294.221662)
			(xy 280.160222 -294.221916) (xy 280.739342 -294.221916) (xy 280.754328 -294.221662) (xy 280.776071 -294.20767)
			(xy 280.823205 -294.186424) (xy 280.873246 -294.173429) (xy 280.924762 -294.169056) (xy 280.976278 -294.173429)
			(xy 281.026319 -294.186424) (xy 281.073453 -294.20767) (xy 281.095196 -294.221662) (xy 281.110182 -294.221916)
			(xy 281.689302 -294.221916) (xy 281.704288 -294.221662) (xy 281.726031 -294.20767) (xy 281.773165 -294.186424)
			(xy 281.823206 -294.173429) (xy 281.874722 -294.169056) (xy 281.926238 -294.173429) (xy 281.976279 -294.186424)
			(xy 282.023413 -294.20767) (xy 282.045156 -294.221662) (xy 282.060142 -294.221916) (xy 282.639516 -294.221916)
			(xy 282.654502 -294.221662) (xy 282.676245 -294.20767) (xy 282.723379 -294.186424) (xy 282.77342 -294.173429)
			(xy 282.824936 -294.169056) (xy 282.876452 -294.173429) (xy 282.926493 -294.186424) (xy 282.973627 -294.20767)
			(xy 282.99537 -294.221662) (xy 283.010356 -294.221916) (xy 283.589476 -294.221916) (xy 283.604462 -294.221662)
			(xy 283.626205 -294.20767) (xy 283.673339 -294.186424) (xy 283.72338 -294.173429) (xy 283.774896 -294.169056)
			(xy 283.826412 -294.173429) (xy 283.876453 -294.186424) (xy 283.923587 -294.20767) (xy 283.94533 -294.221662)
			(xy 283.960316 -294.221916) (xy 284.539436 -294.221916) (xy 284.554422 -294.221662) (xy 284.576165 -294.20767)
			(xy 284.623299 -294.186424) (xy 284.67334 -294.173429) (xy 284.724856 -294.169056) (xy 284.776372 -294.173429)
			(xy 284.826413 -294.186424) (xy 284.873547 -294.20767) (xy 284.89529 -294.221662) (xy 284.910276 -294.221916)
			(xy 285.489396 -294.221916) (xy 285.504382 -294.221662) (xy 285.526125 -294.20767) (xy 285.573259 -294.186424)
			(xy 285.6233 -294.173429) (xy 285.674816 -294.169056) (xy 285.726332 -294.173429) (xy 285.776373 -294.186424)
			(xy 285.823507 -294.20767) (xy 285.84525 -294.221662) (xy 285.860236 -294.221916) (xy 286.439356 -294.221916)
			(xy 286.454342 -294.221662) (xy 286.476085 -294.20767) (xy 286.523219 -294.186424) (xy 286.57326 -294.173429)
			(xy 286.624776 -294.169056) (xy 286.676292 -294.173429) (xy 286.726333 -294.186424) (xy 286.773467 -294.20767)
			(xy 286.79521 -294.221662) (xy 286.810196 -294.221916) (xy 287.389316 -294.221916) (xy 287.404302 -294.221662)
			(xy 287.426045 -294.20767) (xy 287.473179 -294.186424) (xy 287.52322 -294.173429) (xy 287.574736 -294.169056)
			(xy 287.626252 -294.173429) (xy 287.676293 -294.186424) (xy 287.723427 -294.20767) (xy 287.74517 -294.221662)
			(xy 287.760156 -294.221916) (xy 288.339276 -294.221916) (xy 288.354262 -294.221662) (xy 288.376005 -294.20767)
			(xy 288.423139 -294.186424) (xy 288.47318 -294.173429) (xy 288.524696 -294.169056) (xy 288.576212 -294.173429)
			(xy 288.626253 -294.186424) (xy 288.673387 -294.20767) (xy 288.69513 -294.221662) (xy 288.710116 -294.221916)
			(xy 289.28949 -294.221916) (xy 289.304476 -294.221662) (xy 289.326219 -294.20767) (xy 289.373353 -294.186424)
			(xy 289.423394 -294.173429) (xy 289.47491 -294.169056) (xy 289.526426 -294.173429) (xy 289.576467 -294.186424)
			(xy 289.623601 -294.20767) (xy 289.645344 -294.221662) (xy 289.66033 -294.221916) (xy 290.23945 -294.221916)
			(xy 290.254436 -294.221662) (xy 290.273424 -294.20937) (xy 290.31426 -294.189919) (xy 290.357519 -294.176709)
			(xy 290.402254 -294.170029) (xy 290.42487 -294.169592) (xy 290.45281 -294.170189) (xy 290.507766 -294.180305)
			(xy 290.559961 -294.200261) (xy 290.584128 -294.214296) (xy 290.590224 -294.218106) (xy 290.597082 -294.220138)
			(xy 290.610798 -294.221916) (xy 290.684458 -294.221916) (xy 290.694523 -294.22235) (xy 290.713111 -294.230081)
			(xy 290.720526 -294.236902) (xy 290.958524 -294.4749) (xy 292.018986 -294.4749) (xy 292.022946 -294.425846)
			(xy 292.034723 -294.378062) (xy 292.054014 -294.332786) (xy 292.080317 -294.29119) (xy 292.112952 -294.254353)
			(xy 292.151073 -294.223228) (xy 292.193694 -294.198621) (xy 292.23971 -294.181169) (xy 292.287929 -294.171325)
			(xy 292.337104 -294.169344) (xy 292.385959 -294.175276) (xy 292.43323 -294.188968) (xy 292.477692 -294.210066)
			(xy 292.518195 -294.238022) (xy 292.553688 -294.272114) (xy 292.583253 -294.311458) (xy 292.606124 -294.355035)
			(xy 292.621708 -294.401716) (xy 292.629603 -294.450293) (xy 292.630098 -294.4749) (xy 292.968946 -294.4749)
			(xy 292.972906 -294.425846) (xy 292.984683 -294.378062) (xy 293.003974 -294.332786) (xy 293.030277 -294.29119)
			(xy 293.062912 -294.254353) (xy 293.101033 -294.223228) (xy 293.143654 -294.198621) (xy 293.18967 -294.181169)
			(xy 293.237889 -294.171325) (xy 293.287064 -294.169344) (xy 293.335919 -294.175276) (xy 293.38319 -294.188968)
			(xy 293.427652 -294.210066) (xy 293.468155 -294.238022) (xy 293.503648 -294.272114) (xy 293.533213 -294.311458)
			(xy 293.556084 -294.355035) (xy 293.571668 -294.401716) (xy 293.579563 -294.450293) (xy 293.580058 -294.4749)
			(xy 293.918906 -294.4749) (xy 293.922866 -294.425846) (xy 293.934643 -294.378062) (xy 293.953934 -294.332786)
			(xy 293.980237 -294.29119) (xy 294.012872 -294.254353) (xy 294.050993 -294.223228) (xy 294.093614 -294.198621)
			(xy 294.13963 -294.181169) (xy 294.187849 -294.171325) (xy 294.237024 -294.169344) (xy 294.285879 -294.175276)
			(xy 294.33315 -294.188968) (xy 294.377612 -294.210066) (xy 294.418115 -294.238022) (xy 294.453608 -294.272114)
			(xy 294.483173 -294.311458) (xy 294.506044 -294.355035) (xy 294.521628 -294.401716) (xy 294.529523 -294.450293)
			(xy 294.530018 -294.4749) (xy 294.86912 -294.4749) (xy 294.87308 -294.425846) (xy 294.884857 -294.378062)
			(xy 294.904148 -294.332786) (xy 294.930451 -294.29119) (xy 294.963086 -294.254353) (xy 295.001207 -294.223228)
			(xy 295.043828 -294.198621) (xy 295.089844 -294.181169) (xy 295.138063 -294.171325) (xy 295.187238 -294.169344)
			(xy 295.236093 -294.175276) (xy 295.283364 -294.188968) (xy 295.327826 -294.210066) (xy 295.368329 -294.238022)
			(xy 295.403822 -294.272114) (xy 295.433387 -294.311458) (xy 295.456258 -294.355035) (xy 295.471842 -294.401716)
			(xy 295.479737 -294.450293) (xy 295.480232 -294.4749) (xy 295.81908 -294.4749) (xy 295.82304 -294.425846)
			(xy 295.834817 -294.378062) (xy 295.854108 -294.332786) (xy 295.880411 -294.29119) (xy 295.913046 -294.254353)
			(xy 295.951167 -294.223228) (xy 295.993788 -294.198621) (xy 296.039804 -294.181169) (xy 296.088023 -294.171325)
			(xy 296.137198 -294.169344) (xy 296.186053 -294.175276) (xy 296.233324 -294.188968) (xy 296.277786 -294.210066)
			(xy 296.318289 -294.238022) (xy 296.353782 -294.272114) (xy 296.383347 -294.311458) (xy 296.406218 -294.355035)
			(xy 296.421802 -294.401716) (xy 296.429697 -294.450293) (xy 296.430192 -294.4749) (xy 296.76904 -294.4749)
			(xy 296.773 -294.425846) (xy 296.784777 -294.378062) (xy 296.804068 -294.332786) (xy 296.830371 -294.29119)
			(xy 296.863006 -294.254353) (xy 296.901127 -294.223228) (xy 296.943748 -294.198621) (xy 296.989764 -294.181169)
			(xy 297.037983 -294.171325) (xy 297.087158 -294.169344) (xy 297.136013 -294.175276) (xy 297.183284 -294.188968)
			(xy 297.227746 -294.210066) (xy 297.268249 -294.238022) (xy 297.303742 -294.272114) (xy 297.333307 -294.311458)
			(xy 297.356178 -294.355035) (xy 297.371762 -294.401716) (xy 297.379657 -294.450293) (xy 297.380152 -294.4749)
			(xy 297.719 -294.4749) (xy 297.72296 -294.425846) (xy 297.734737 -294.378062) (xy 297.754028 -294.332786)
			(xy 297.780331 -294.29119) (xy 297.812966 -294.254353) (xy 297.851087 -294.223228) (xy 297.893708 -294.198621)
			(xy 297.939724 -294.181169) (xy 297.987943 -294.171325) (xy 298.037118 -294.169344) (xy 298.085973 -294.175276)
			(xy 298.133244 -294.188968) (xy 298.177706 -294.210066) (xy 298.218209 -294.238022) (xy 298.253702 -294.272114)
			(xy 298.283267 -294.311458) (xy 298.306138 -294.355035) (xy 298.321722 -294.401716) (xy 298.329617 -294.450293)
			(xy 298.330112 -294.4749) (xy 298.66896 -294.4749) (xy 298.67292 -294.425846) (xy 298.684697 -294.378062)
			(xy 298.703988 -294.332786) (xy 298.730291 -294.29119) (xy 298.762926 -294.254353) (xy 298.801047 -294.223228)
			(xy 298.843668 -294.198621) (xy 298.889684 -294.181169) (xy 298.937903 -294.171325) (xy 298.987078 -294.169344)
			(xy 299.035933 -294.175276) (xy 299.083204 -294.188968) (xy 299.127666 -294.210066) (xy 299.168169 -294.238022)
			(xy 299.203662 -294.272114) (xy 299.233227 -294.311458) (xy 299.256098 -294.355035) (xy 299.271682 -294.401716)
			(xy 299.279577 -294.450293) (xy 299.280072 -294.4749) (xy 299.61892 -294.4749) (xy 299.62288 -294.425846)
			(xy 299.634657 -294.378062) (xy 299.653948 -294.332786) (xy 299.680251 -294.29119) (xy 299.712886 -294.254353)
			(xy 299.751007 -294.223228) (xy 299.793628 -294.198621) (xy 299.839644 -294.181169) (xy 299.887863 -294.171325)
			(xy 299.937038 -294.169344) (xy 299.985893 -294.175276) (xy 300.033164 -294.188968) (xy 300.077626 -294.210066)
			(xy 300.118129 -294.238022) (xy 300.153622 -294.272114) (xy 300.183187 -294.311458) (xy 300.206058 -294.355035)
			(xy 300.221642 -294.401716) (xy 300.229537 -294.450293) (xy 300.230032 -294.4749) (xy 300.56888 -294.4749)
			(xy 300.57284 -294.425846) (xy 300.584617 -294.378062) (xy 300.603908 -294.332786) (xy 300.630211 -294.29119)
			(xy 300.662846 -294.254353) (xy 300.700967 -294.223228) (xy 300.743588 -294.198621) (xy 300.789604 -294.181169)
			(xy 300.837823 -294.171325) (xy 300.886998 -294.169344) (xy 300.935853 -294.175276) (xy 300.983124 -294.188968)
			(xy 301.027586 -294.210066) (xy 301.068089 -294.238022) (xy 301.103582 -294.272114) (xy 301.133147 -294.311458)
			(xy 301.156018 -294.355035) (xy 301.171602 -294.401716) (xy 301.179497 -294.450293) (xy 301.179992 -294.4749)
			(xy 301.519094 -294.4749) (xy 301.523054 -294.425846) (xy 301.534831 -294.378062) (xy 301.554122 -294.332786)
			(xy 301.580425 -294.29119) (xy 301.61306 -294.254353) (xy 301.651181 -294.223228) (xy 301.693802 -294.198621)
			(xy 301.739818 -294.181169) (xy 301.788037 -294.171325) (xy 301.837212 -294.169344) (xy 301.886067 -294.175276)
			(xy 301.933338 -294.188968) (xy 301.9778 -294.210066) (xy 302.018303 -294.238022) (xy 302.053796 -294.272114)
			(xy 302.083361 -294.311458) (xy 302.106232 -294.355035) (xy 302.121816 -294.401716) (xy 302.129711 -294.450293)
			(xy 302.130206 -294.4749) (xy 302.469054 -294.4749) (xy 302.473014 -294.425846) (xy 302.484791 -294.378062)
			(xy 302.504082 -294.332786) (xy 302.530385 -294.29119) (xy 302.56302 -294.254353) (xy 302.601141 -294.223228)
			(xy 302.643762 -294.198621) (xy 302.689778 -294.181169) (xy 302.737997 -294.171325) (xy 302.787172 -294.169344)
			(xy 302.836027 -294.175276) (xy 302.883298 -294.188968) (xy 302.92776 -294.210066) (xy 302.968263 -294.238022)
			(xy 303.003756 -294.272114) (xy 303.033321 -294.311458) (xy 303.056192 -294.355035) (xy 303.071776 -294.401716)
			(xy 303.079671 -294.450293) (xy 303.080166 -294.4749) (xy 303.419014 -294.4749) (xy 303.422974 -294.425846)
			(xy 303.434751 -294.378062) (xy 303.454042 -294.332786) (xy 303.480345 -294.29119) (xy 303.51298 -294.254353)
			(xy 303.551101 -294.223228) (xy 303.593722 -294.198621) (xy 303.639738 -294.181169) (xy 303.687957 -294.171325)
			(xy 303.737132 -294.169344) (xy 303.785987 -294.175276) (xy 303.833258 -294.188968) (xy 303.87772 -294.210066)
			(xy 303.918223 -294.238022) (xy 303.953716 -294.272114) (xy 303.983281 -294.311458) (xy 304.006152 -294.355035)
			(xy 304.021736 -294.401716) (xy 304.029631 -294.450293) (xy 304.030126 -294.4749) (xy 305.318934 -294.4749)
			(xy 305.322894 -294.425846) (xy 305.334671 -294.378062) (xy 305.353962 -294.332786) (xy 305.380265 -294.29119)
			(xy 305.4129 -294.254353) (xy 305.451021 -294.223228) (xy 305.493642 -294.198621) (xy 305.539658 -294.181169)
			(xy 305.587877 -294.171325) (xy 305.637052 -294.169344) (xy 305.685907 -294.175276) (xy 305.733178 -294.188968)
			(xy 305.77764 -294.210066) (xy 305.818143 -294.238022) (xy 305.853636 -294.272114) (xy 305.883201 -294.311458)
			(xy 305.906072 -294.355035) (xy 305.921656 -294.401716) (xy 305.929551 -294.450293) (xy 305.930046 -294.4749)
			(xy 306.268894 -294.4749) (xy 306.272854 -294.425846) (xy 306.284631 -294.378062) (xy 306.303922 -294.332786)
			(xy 306.330225 -294.29119) (xy 306.36286 -294.254353) (xy 306.400981 -294.223228) (xy 306.443602 -294.198621)
			(xy 306.489618 -294.181169) (xy 306.537837 -294.171325) (xy 306.587012 -294.169344) (xy 306.635867 -294.175276)
			(xy 306.683138 -294.188968) (xy 306.7276 -294.210066) (xy 306.768103 -294.238022) (xy 306.803596 -294.272114)
			(xy 306.833161 -294.311458) (xy 306.856032 -294.355035) (xy 306.871616 -294.401716) (xy 306.879511 -294.450293)
			(xy 306.880006 -294.4749) (xy 307.219108 -294.4749) (xy 307.223068 -294.425846) (xy 307.234845 -294.378062)
			(xy 307.254136 -294.332786) (xy 307.280439 -294.29119) (xy 307.313074 -294.254353) (xy 307.351195 -294.223228)
			(xy 307.393816 -294.198621) (xy 307.439832 -294.181169) (xy 307.488051 -294.171325) (xy 307.537226 -294.169344)
			(xy 307.586081 -294.175276) (xy 307.633352 -294.188968) (xy 307.677814 -294.210066) (xy 307.718317 -294.238022)
			(xy 307.75381 -294.272114) (xy 307.783375 -294.311458) (xy 307.806246 -294.355035) (xy 307.82183 -294.401716)
			(xy 307.829725 -294.450293) (xy 307.83022 -294.4749) (xy 308.169068 -294.4749) (xy 308.173028 -294.425846)
			(xy 308.184805 -294.378062) (xy 308.204096 -294.332786) (xy 308.230399 -294.29119) (xy 308.263034 -294.254353)
			(xy 308.301155 -294.223228) (xy 308.343776 -294.198621) (xy 308.389792 -294.181169) (xy 308.438011 -294.171325)
			(xy 308.487186 -294.169344) (xy 308.536041 -294.175276) (xy 308.583312 -294.188968) (xy 308.627774 -294.210066)
			(xy 308.668277 -294.238022) (xy 308.70377 -294.272114) (xy 308.733335 -294.311458) (xy 308.756206 -294.355035)
			(xy 308.77179 -294.401716) (xy 308.779685 -294.450293) (xy 308.78018 -294.4749) (xy 309.119028 -294.4749)
			(xy 309.122988 -294.425846) (xy 309.134765 -294.378062) (xy 309.154056 -294.332786) (xy 309.180359 -294.29119)
			(xy 309.212994 -294.254353) (xy 309.251115 -294.223228) (xy 309.293736 -294.198621) (xy 309.339752 -294.181169)
			(xy 309.387971 -294.171325) (xy 309.437146 -294.169344) (xy 309.486001 -294.175276) (xy 309.533272 -294.188968)
			(xy 309.577734 -294.210066) (xy 309.618237 -294.238022) (xy 309.65373 -294.272114) (xy 309.683295 -294.311458)
			(xy 309.706166 -294.355035) (xy 309.72175 -294.401716) (xy 309.729645 -294.450293) (xy 309.73014 -294.4749)
			(xy 310.068988 -294.4749) (xy 310.072948 -294.425846) (xy 310.084725 -294.378062) (xy 310.104016 -294.332786)
			(xy 310.130319 -294.29119) (xy 310.162954 -294.254353) (xy 310.201075 -294.223228) (xy 310.243696 -294.198621)
			(xy 310.289712 -294.181169) (xy 310.337931 -294.171325) (xy 310.387106 -294.169344) (xy 310.435961 -294.175276)
			(xy 310.483232 -294.188968) (xy 310.527694 -294.210066) (xy 310.568197 -294.238022) (xy 310.60369 -294.272114)
			(xy 310.633255 -294.311458) (xy 310.656126 -294.355035) (xy 310.67171 -294.401716) (xy 310.679605 -294.450293)
			(xy 310.6801 -294.4749) (xy 311.018948 -294.4749) (xy 311.022908 -294.425846) (xy 311.034685 -294.378062)
			(xy 311.053976 -294.332786) (xy 311.080279 -294.29119) (xy 311.112914 -294.254353) (xy 311.151035 -294.223228)
			(xy 311.193656 -294.198621) (xy 311.239672 -294.181169) (xy 311.287891 -294.171325) (xy 311.337066 -294.169344)
			(xy 311.385921 -294.175276) (xy 311.433192 -294.188968) (xy 311.477654 -294.210066) (xy 311.518157 -294.238022)
			(xy 311.55365 -294.272114) (xy 311.583215 -294.311458) (xy 311.606086 -294.355035) (xy 311.62167 -294.401716)
			(xy 311.629565 -294.450293) (xy 311.63006 -294.4749) (xy 311.968908 -294.4749) (xy 311.972868 -294.425846)
			(xy 311.984645 -294.378062) (xy 312.003936 -294.332786) (xy 312.030239 -294.29119) (xy 312.062874 -294.254353)
			(xy 312.100995 -294.223228) (xy 312.143616 -294.198621) (xy 312.189632 -294.181169) (xy 312.237851 -294.171325)
			(xy 312.287026 -294.169344) (xy 312.335881 -294.175276) (xy 312.383152 -294.188968) (xy 312.427614 -294.210066)
			(xy 312.468117 -294.238022) (xy 312.50361 -294.272114) (xy 312.533175 -294.311458) (xy 312.556046 -294.355035)
			(xy 312.57163 -294.401716) (xy 312.579525 -294.450293) (xy 312.58002 -294.4749) (xy 312.919122 -294.4749)
			(xy 312.923082 -294.425846) (xy 312.934859 -294.378062) (xy 312.95415 -294.332786) (xy 312.980453 -294.29119)
			(xy 313.013088 -294.254353) (xy 313.051209 -294.223228) (xy 313.09383 -294.198621) (xy 313.139846 -294.181169)
			(xy 313.188065 -294.171325) (xy 313.23724 -294.169344) (xy 313.286095 -294.175276) (xy 313.333366 -294.188968)
			(xy 313.377828 -294.210066) (xy 313.418331 -294.238022) (xy 313.453824 -294.272114) (xy 313.483389 -294.311458)
			(xy 313.50626 -294.355035) (xy 313.521844 -294.401716) (xy 313.529739 -294.450293) (xy 313.530234 -294.4749)
			(xy 313.869082 -294.4749) (xy 313.873042 -294.425846) (xy 313.884819 -294.378062) (xy 313.90411 -294.332786)
			(xy 313.930413 -294.29119) (xy 313.963048 -294.254353) (xy 314.001169 -294.223228) (xy 314.04379 -294.198621)
			(xy 314.089806 -294.181169) (xy 314.138025 -294.171325) (xy 314.1872 -294.169344) (xy 314.236055 -294.175276)
			(xy 314.283326 -294.188968) (xy 314.327788 -294.210066) (xy 314.368291 -294.238022) (xy 314.403784 -294.272114)
			(xy 314.433349 -294.311458) (xy 314.45622 -294.355035) (xy 314.471804 -294.401716) (xy 314.479699 -294.450293)
			(xy 314.480194 -294.4749) (xy 314.819042 -294.4749) (xy 314.823002 -294.425846) (xy 314.834779 -294.378062)
			(xy 314.85407 -294.332786) (xy 314.880373 -294.29119) (xy 314.913008 -294.254353) (xy 314.951129 -294.223228)
			(xy 314.99375 -294.198621) (xy 315.039766 -294.181169) (xy 315.087985 -294.171325) (xy 315.13716 -294.169344)
			(xy 315.186015 -294.175276) (xy 315.233286 -294.188968) (xy 315.277748 -294.210066) (xy 315.318251 -294.238022)
			(xy 315.353744 -294.272114) (xy 315.383309 -294.311458) (xy 315.40618 -294.355035) (xy 315.421764 -294.401716)
			(xy 315.429659 -294.450293) (xy 315.430154 -294.4749) (xy 315.429659 -294.499507) (xy 315.421764 -294.548084)
			(xy 315.40618 -294.594765) (xy 315.383309 -294.638342) (xy 315.353744 -294.677686) (xy 315.318251 -294.711778)
			(xy 315.277748 -294.739734) (xy 315.233286 -294.760832) (xy 315.186015 -294.774524) (xy 315.13716 -294.780456)
			(xy 315.087985 -294.778475) (xy 315.039766 -294.768631) (xy 314.99375 -294.751179) (xy 314.951129 -294.726572)
			(xy 314.913008 -294.695447) (xy 314.880373 -294.65861) (xy 314.85407 -294.617014) (xy 314.834779 -294.571738)
			(xy 314.823002 -294.523954) (xy 314.819042 -294.4749) (xy 314.480194 -294.4749) (xy 314.479699 -294.499507)
			(xy 314.471804 -294.548084) (xy 314.45622 -294.594765) (xy 314.433349 -294.638342) (xy 314.403784 -294.677686)
			(xy 314.368291 -294.711778) (xy 314.327788 -294.739734) (xy 314.283326 -294.760832) (xy 314.236055 -294.774524)
			(xy 314.1872 -294.780456) (xy 314.138025 -294.778475) (xy 314.089806 -294.768631) (xy 314.04379 -294.751179)
			(xy 314.001169 -294.726572) (xy 313.963048 -294.695447) (xy 313.930413 -294.65861) (xy 313.90411 -294.617014)
			(xy 313.884819 -294.571738) (xy 313.873042 -294.523954) (xy 313.869082 -294.4749) (xy 313.530234 -294.4749)
			(xy 313.529739 -294.499507) (xy 313.521844 -294.548084) (xy 313.50626 -294.594765) (xy 313.483389 -294.638342)
			(xy 313.453824 -294.677686) (xy 313.418331 -294.711778) (xy 313.377828 -294.739734) (xy 313.333366 -294.760832)
			(xy 313.286095 -294.774524) (xy 313.23724 -294.780456) (xy 313.188065 -294.778475) (xy 313.139846 -294.768631)
			(xy 313.09383 -294.751179) (xy 313.051209 -294.726572) (xy 313.013088 -294.695447) (xy 312.980453 -294.65861)
			(xy 312.95415 -294.617014) (xy 312.934859 -294.571738) (xy 312.923082 -294.523954) (xy 312.919122 -294.4749)
			(xy 312.58002 -294.4749) (xy 312.579525 -294.499507) (xy 312.57163 -294.548084) (xy 312.556046 -294.594765)
			(xy 312.533175 -294.638342) (xy 312.50361 -294.677686) (xy 312.468117 -294.711778) (xy 312.427614 -294.739734)
			(xy 312.383152 -294.760832) (xy 312.335881 -294.774524) (xy 312.287026 -294.780456) (xy 312.237851 -294.778475)
			(xy 312.189632 -294.768631) (xy 312.143616 -294.751179) (xy 312.100995 -294.726572) (xy 312.062874 -294.695447)
			(xy 312.030239 -294.65861) (xy 312.003936 -294.617014) (xy 311.984645 -294.571738) (xy 311.972868 -294.523954)
			(xy 311.968908 -294.4749) (xy 311.63006 -294.4749) (xy 311.629565 -294.499507) (xy 311.62167 -294.548084)
			(xy 311.606086 -294.594765) (xy 311.583215 -294.638342) (xy 311.55365 -294.677686) (xy 311.518157 -294.711778)
			(xy 311.477654 -294.739734) (xy 311.433192 -294.760832) (xy 311.385921 -294.774524) (xy 311.337066 -294.780456)
			(xy 311.287891 -294.778475) (xy 311.239672 -294.768631) (xy 311.193656 -294.751179) (xy 311.151035 -294.726572)
			(xy 311.112914 -294.695447) (xy 311.080279 -294.65861) (xy 311.053976 -294.617014) (xy 311.034685 -294.571738)
			(xy 311.022908 -294.523954) (xy 311.018948 -294.4749) (xy 310.6801 -294.4749) (xy 310.679605 -294.499507)
			(xy 310.67171 -294.548084) (xy 310.656126 -294.594765) (xy 310.633255 -294.638342) (xy 310.60369 -294.677686)
			(xy 310.568197 -294.711778) (xy 310.527694 -294.739734) (xy 310.483232 -294.760832) (xy 310.435961 -294.774524)
			(xy 310.387106 -294.780456) (xy 310.337931 -294.778475) (xy 310.289712 -294.768631) (xy 310.243696 -294.751179)
			(xy 310.201075 -294.726572) (xy 310.162954 -294.695447) (xy 310.130319 -294.65861) (xy 310.104016 -294.617014)
			(xy 310.084725 -294.571738) (xy 310.072948 -294.523954) (xy 310.068988 -294.4749) (xy 309.73014 -294.4749)
			(xy 309.729645 -294.499507) (xy 309.72175 -294.548084) (xy 309.706166 -294.594765) (xy 309.683295 -294.638342)
			(xy 309.65373 -294.677686) (xy 309.618237 -294.711778) (xy 309.577734 -294.739734) (xy 309.533272 -294.760832)
			(xy 309.486001 -294.774524) (xy 309.437146 -294.780456) (xy 309.387971 -294.778475) (xy 309.339752 -294.768631)
			(xy 309.293736 -294.751179) (xy 309.251115 -294.726572) (xy 309.212994 -294.695447) (xy 309.180359 -294.65861)
			(xy 309.154056 -294.617014) (xy 309.134765 -294.571738) (xy 309.122988 -294.523954) (xy 309.119028 -294.4749)
			(xy 308.78018 -294.4749) (xy 308.779685 -294.499507) (xy 308.77179 -294.548084) (xy 308.756206 -294.594765)
			(xy 308.733335 -294.638342) (xy 308.70377 -294.677686) (xy 308.668277 -294.711778) (xy 308.627774 -294.739734)
			(xy 308.583312 -294.760832) (xy 308.536041 -294.774524) (xy 308.487186 -294.780456) (xy 308.438011 -294.778475)
			(xy 308.389792 -294.768631) (xy 308.343776 -294.751179) (xy 308.301155 -294.726572) (xy 308.263034 -294.695447)
			(xy 308.230399 -294.65861) (xy 308.204096 -294.617014) (xy 308.184805 -294.571738) (xy 308.173028 -294.523954)
			(xy 308.169068 -294.4749) (xy 307.83022 -294.4749) (xy 307.829725 -294.499507) (xy 307.82183 -294.548084)
			(xy 307.806246 -294.594765) (xy 307.783375 -294.638342) (xy 307.75381 -294.677686) (xy 307.718317 -294.711778)
			(xy 307.677814 -294.739734) (xy 307.633352 -294.760832) (xy 307.586081 -294.774524) (xy 307.537226 -294.780456)
			(xy 307.488051 -294.778475) (xy 307.439832 -294.768631) (xy 307.393816 -294.751179) (xy 307.351195 -294.726572)
			(xy 307.313074 -294.695447) (xy 307.280439 -294.65861) (xy 307.254136 -294.617014) (xy 307.234845 -294.571738)
			(xy 307.223068 -294.523954) (xy 307.219108 -294.4749) (xy 306.880006 -294.4749) (xy 306.879511 -294.499507)
			(xy 306.871616 -294.548084) (xy 306.856032 -294.594765) (xy 306.833161 -294.638342) (xy 306.803596 -294.677686)
			(xy 306.768103 -294.711778) (xy 306.7276 -294.739734) (xy 306.683138 -294.760832) (xy 306.635867 -294.774524)
			(xy 306.587012 -294.780456) (xy 306.537837 -294.778475) (xy 306.489618 -294.768631) (xy 306.443602 -294.751179)
			(xy 306.400981 -294.726572) (xy 306.36286 -294.695447) (xy 306.330225 -294.65861) (xy 306.303922 -294.617014)
			(xy 306.284631 -294.571738) (xy 306.272854 -294.523954) (xy 306.268894 -294.4749) (xy 305.930046 -294.4749)
			(xy 305.929551 -294.499507) (xy 305.921656 -294.548084) (xy 305.906072 -294.594765) (xy 305.883201 -294.638342)
			(xy 305.853636 -294.677686) (xy 305.818143 -294.711778) (xy 305.77764 -294.739734) (xy 305.733178 -294.760832)
			(xy 305.685907 -294.774524) (xy 305.637052 -294.780456) (xy 305.587877 -294.778475) (xy 305.539658 -294.768631)
			(xy 305.493642 -294.751179) (xy 305.451021 -294.726572) (xy 305.4129 -294.695447) (xy 305.380265 -294.65861)
			(xy 305.353962 -294.617014) (xy 305.334671 -294.571738) (xy 305.322894 -294.523954) (xy 305.318934 -294.4749)
			(xy 304.030126 -294.4749) (xy 304.029631 -294.499507) (xy 304.021736 -294.548084) (xy 304.006152 -294.594765)
			(xy 303.983281 -294.638342) (xy 303.953716 -294.677686) (xy 303.918223 -294.711778) (xy 303.87772 -294.739734)
			(xy 303.833258 -294.760832) (xy 303.785987 -294.774524) (xy 303.737132 -294.780456) (xy 303.687957 -294.778475)
			(xy 303.639738 -294.768631) (xy 303.593722 -294.751179) (xy 303.551101 -294.726572) (xy 303.51298 -294.695447)
			(xy 303.480345 -294.65861) (xy 303.454042 -294.617014) (xy 303.434751 -294.571738) (xy 303.422974 -294.523954)
			(xy 303.419014 -294.4749) (xy 303.080166 -294.4749) (xy 303.079671 -294.499507) (xy 303.071776 -294.548084)
			(xy 303.056192 -294.594765) (xy 303.033321 -294.638342) (xy 303.003756 -294.677686) (xy 302.968263 -294.711778)
			(xy 302.92776 -294.739734) (xy 302.883298 -294.760832) (xy 302.836027 -294.774524) (xy 302.787172 -294.780456)
			(xy 302.737997 -294.778475) (xy 302.689778 -294.768631) (xy 302.643762 -294.751179) (xy 302.601141 -294.726572)
			(xy 302.56302 -294.695447) (xy 302.530385 -294.65861) (xy 302.504082 -294.617014) (xy 302.484791 -294.571738)
			(xy 302.473014 -294.523954) (xy 302.469054 -294.4749) (xy 302.130206 -294.4749) (xy 302.129711 -294.499507)
			(xy 302.121816 -294.548084) (xy 302.106232 -294.594765) (xy 302.083361 -294.638342) (xy 302.053796 -294.677686)
			(xy 302.018303 -294.711778) (xy 301.9778 -294.739734) (xy 301.933338 -294.760832) (xy 301.886067 -294.774524)
			(xy 301.837212 -294.780456) (xy 301.788037 -294.778475) (xy 301.739818 -294.768631) (xy 301.693802 -294.751179)
			(xy 301.651181 -294.726572) (xy 301.61306 -294.695447) (xy 301.580425 -294.65861) (xy 301.554122 -294.617014)
			(xy 301.534831 -294.571738) (xy 301.523054 -294.523954) (xy 301.519094 -294.4749) (xy 301.179992 -294.4749)
			(xy 301.179497 -294.499507) (xy 301.171602 -294.548084) (xy 301.156018 -294.594765) (xy 301.133147 -294.638342)
			(xy 301.103582 -294.677686) (xy 301.068089 -294.711778) (xy 301.027586 -294.739734) (xy 300.983124 -294.760832)
			(xy 300.935853 -294.774524) (xy 300.886998 -294.780456) (xy 300.837823 -294.778475) (xy 300.789604 -294.768631)
			(xy 300.743588 -294.751179) (xy 300.700967 -294.726572) (xy 300.662846 -294.695447) (xy 300.630211 -294.65861)
			(xy 300.603908 -294.617014) (xy 300.584617 -294.571738) (xy 300.57284 -294.523954) (xy 300.56888 -294.4749)
			(xy 300.230032 -294.4749) (xy 300.229537 -294.499507) (xy 300.221642 -294.548084) (xy 300.206058 -294.594765)
			(xy 300.183187 -294.638342) (xy 300.153622 -294.677686) (xy 300.118129 -294.711778) (xy 300.077626 -294.739734)
			(xy 300.033164 -294.760832) (xy 299.985893 -294.774524) (xy 299.937038 -294.780456) (xy 299.887863 -294.778475)
			(xy 299.839644 -294.768631) (xy 299.793628 -294.751179) (xy 299.751007 -294.726572) (xy 299.712886 -294.695447)
			(xy 299.680251 -294.65861) (xy 299.653948 -294.617014) (xy 299.634657 -294.571738) (xy 299.62288 -294.523954)
			(xy 299.61892 -294.4749) (xy 299.280072 -294.4749) (xy 299.279577 -294.499507) (xy 299.271682 -294.548084)
			(xy 299.256098 -294.594765) (xy 299.233227 -294.638342) (xy 299.203662 -294.677686) (xy 299.168169 -294.711778)
			(xy 299.127666 -294.739734) (xy 299.083204 -294.760832) (xy 299.035933 -294.774524) (xy 298.987078 -294.780456)
			(xy 298.937903 -294.778475) (xy 298.889684 -294.768631) (xy 298.843668 -294.751179) (xy 298.801047 -294.726572)
			(xy 298.762926 -294.695447) (xy 298.730291 -294.65861) (xy 298.703988 -294.617014) (xy 298.684697 -294.571738)
			(xy 298.67292 -294.523954) (xy 298.66896 -294.4749) (xy 298.330112 -294.4749) (xy 298.329617 -294.499507)
			(xy 298.321722 -294.548084) (xy 298.306138 -294.594765) (xy 298.283267 -294.638342) (xy 298.253702 -294.677686)
			(xy 298.218209 -294.711778) (xy 298.177706 -294.739734) (xy 298.133244 -294.760832) (xy 298.085973 -294.774524)
			(xy 298.037118 -294.780456) (xy 297.987943 -294.778475) (xy 297.939724 -294.768631) (xy 297.893708 -294.751179)
			(xy 297.851087 -294.726572) (xy 297.812966 -294.695447) (xy 297.780331 -294.65861) (xy 297.754028 -294.617014)
			(xy 297.734737 -294.571738) (xy 297.72296 -294.523954) (xy 297.719 -294.4749) (xy 297.380152 -294.4749)
			(xy 297.379657 -294.499507) (xy 297.371762 -294.548084) (xy 297.356178 -294.594765) (xy 297.333307 -294.638342)
			(xy 297.303742 -294.677686) (xy 297.268249 -294.711778) (xy 297.227746 -294.739734) (xy 297.183284 -294.760832)
			(xy 297.136013 -294.774524) (xy 297.087158 -294.780456) (xy 297.037983 -294.778475) (xy 296.989764 -294.768631)
			(xy 296.943748 -294.751179) (xy 296.901127 -294.726572) (xy 296.863006 -294.695447) (xy 296.830371 -294.65861)
			(xy 296.804068 -294.617014) (xy 296.784777 -294.571738) (xy 296.773 -294.523954) (xy 296.76904 -294.4749)
			(xy 296.430192 -294.4749) (xy 296.429697 -294.499507) (xy 296.421802 -294.548084) (xy 296.406218 -294.594765)
			(xy 296.383347 -294.638342) (xy 296.353782 -294.677686) (xy 296.318289 -294.711778) (xy 296.277786 -294.739734)
			(xy 296.233324 -294.760832) (xy 296.186053 -294.774524) (xy 296.137198 -294.780456) (xy 296.088023 -294.778475)
			(xy 296.039804 -294.768631) (xy 295.993788 -294.751179) (xy 295.951167 -294.726572) (xy 295.913046 -294.695447)
			(xy 295.880411 -294.65861) (xy 295.854108 -294.617014) (xy 295.834817 -294.571738) (xy 295.82304 -294.523954)
			(xy 295.81908 -294.4749) (xy 295.480232 -294.4749) (xy 295.479737 -294.499507) (xy 295.471842 -294.548084)
			(xy 295.456258 -294.594765) (xy 295.433387 -294.638342) (xy 295.403822 -294.677686) (xy 295.368329 -294.711778)
			(xy 295.327826 -294.739734) (xy 295.283364 -294.760832) (xy 295.236093 -294.774524) (xy 295.187238 -294.780456)
			(xy 295.138063 -294.778475) (xy 295.089844 -294.768631) (xy 295.043828 -294.751179) (xy 295.001207 -294.726572)
			(xy 294.963086 -294.695447) (xy 294.930451 -294.65861) (xy 294.904148 -294.617014) (xy 294.884857 -294.571738)
			(xy 294.87308 -294.523954) (xy 294.86912 -294.4749) (xy 294.530018 -294.4749) (xy 294.529523 -294.499507)
			(xy 294.521628 -294.548084) (xy 294.506044 -294.594765) (xy 294.483173 -294.638342) (xy 294.453608 -294.677686)
			(xy 294.418115 -294.711778) (xy 294.377612 -294.739734) (xy 294.33315 -294.760832) (xy 294.285879 -294.774524)
			(xy 294.237024 -294.780456) (xy 294.187849 -294.778475) (xy 294.13963 -294.768631) (xy 294.093614 -294.751179)
			(xy 294.050993 -294.726572) (xy 294.012872 -294.695447) (xy 293.980237 -294.65861) (xy 293.953934 -294.617014)
			(xy 293.934643 -294.571738) (xy 293.922866 -294.523954) (xy 293.918906 -294.4749) (xy 293.580058 -294.4749)
			(xy 293.579563 -294.499507) (xy 293.571668 -294.548084) (xy 293.556084 -294.594765) (xy 293.533213 -294.638342)
			(xy 293.503648 -294.677686) (xy 293.468155 -294.711778) (xy 293.427652 -294.739734) (xy 293.38319 -294.760832)
			(xy 293.335919 -294.774524) (xy 293.287064 -294.780456) (xy 293.237889 -294.778475) (xy 293.18967 -294.768631)
			(xy 293.143654 -294.751179) (xy 293.101033 -294.726572) (xy 293.062912 -294.695447) (xy 293.030277 -294.65861)
			(xy 293.003974 -294.617014) (xy 292.984683 -294.571738) (xy 292.972906 -294.523954) (xy 292.968946 -294.4749)
			(xy 292.630098 -294.4749) (xy 292.629603 -294.499507) (xy 292.621708 -294.548084) (xy 292.606124 -294.594765)
			(xy 292.583253 -294.638342) (xy 292.553688 -294.677686) (xy 292.518195 -294.711778) (xy 292.477692 -294.739734)
			(xy 292.43323 -294.760832) (xy 292.385959 -294.774524) (xy 292.337104 -294.780456) (xy 292.287929 -294.778475)
			(xy 292.23971 -294.768631) (xy 292.193694 -294.751179) (xy 292.151073 -294.726572) (xy 292.112952 -294.695447)
			(xy 292.080317 -294.65861) (xy 292.054014 -294.617014) (xy 292.034723 -294.571738) (xy 292.022946 -294.523954)
			(xy 292.018986 -294.4749) (xy 290.958524 -294.4749) (xy 292.324028 -295.840404) (xy 292.330881 -295.847799)
			(xy 292.338626 -295.866398) (xy 292.339014 -295.876472) (xy 292.339014 -296.024554) (xy 292.339637 -296.036398)
			(xy 292.350216 -296.057594) (xy 292.369132 -296.071855) (xy 292.38067 -296.074592) (xy 292.381432 -296.074846)
			(xy 292.405779 -296.079942) (xy 292.452513 -296.096972) (xy 292.495867 -296.121353) (xy 292.534695 -296.152441)
			(xy 292.567968 -296.189413) (xy 292.594808 -296.231291) (xy 292.614502 -296.276965) (xy 292.626531 -296.325229)
			(xy 292.630576 -296.374804) (xy 292.630575 -296.37482) (xy 292.968946 -296.37482) (xy 292.972906 -296.325766)
			(xy 292.984683 -296.277982) (xy 293.003974 -296.232706) (xy 293.030277 -296.19111) (xy 293.062912 -296.154273)
			(xy 293.101033 -296.123148) (xy 293.143654 -296.098541) (xy 293.18967 -296.081089) (xy 293.237889 -296.071245)
			(xy 293.287064 -296.069264) (xy 293.335919 -296.075196) (xy 293.38319 -296.088888) (xy 293.427652 -296.109986)
			(xy 293.468155 -296.137942) (xy 293.503648 -296.172034) (xy 293.533213 -296.211378) (xy 293.556084 -296.254955)
			(xy 293.571668 -296.301636) (xy 293.579563 -296.350213) (xy 293.580058 -296.37482) (xy 293.918906 -296.37482)
			(xy 293.922866 -296.325766) (xy 293.934643 -296.277982) (xy 293.953934 -296.232706) (xy 293.980237 -296.19111)
			(xy 294.012872 -296.154273) (xy 294.050993 -296.123148) (xy 294.093614 -296.098541) (xy 294.13963 -296.081089)
			(xy 294.187849 -296.071245) (xy 294.237024 -296.069264) (xy 294.285879 -296.075196) (xy 294.33315 -296.088888)
			(xy 294.377612 -296.109986) (xy 294.418115 -296.137942) (xy 294.453608 -296.172034) (xy 294.483173 -296.211378)
			(xy 294.506044 -296.254955) (xy 294.521628 -296.301636) (xy 294.529523 -296.350213) (xy 294.530018 -296.37482)
			(xy 294.86912 -296.37482) (xy 294.87308 -296.325766) (xy 294.884857 -296.277982) (xy 294.904148 -296.232706)
			(xy 294.930451 -296.19111) (xy 294.963086 -296.154273) (xy 295.001207 -296.123148) (xy 295.043828 -296.098541)
			(xy 295.089844 -296.081089) (xy 295.138063 -296.071245) (xy 295.187238 -296.069264) (xy 295.236093 -296.075196)
			(xy 295.283364 -296.088888) (xy 295.327826 -296.109986) (xy 295.368329 -296.137942) (xy 295.403822 -296.172034)
			(xy 295.433387 -296.211378) (xy 295.456258 -296.254955) (xy 295.471842 -296.301636) (xy 295.479737 -296.350213)
			(xy 295.480232 -296.37482) (xy 295.81908 -296.37482) (xy 295.82304 -296.325766) (xy 295.834817 -296.277982)
			(xy 295.854108 -296.232706) (xy 295.880411 -296.19111) (xy 295.913046 -296.154273) (xy 295.951167 -296.123148)
			(xy 295.993788 -296.098541) (xy 296.039804 -296.081089) (xy 296.088023 -296.071245) (xy 296.137198 -296.069264)
			(xy 296.186053 -296.075196) (xy 296.233324 -296.088888) (xy 296.277786 -296.109986) (xy 296.318289 -296.137942)
			(xy 296.353782 -296.172034) (xy 296.383347 -296.211378) (xy 296.406218 -296.254955) (xy 296.421802 -296.301636)
			(xy 296.429697 -296.350213) (xy 296.430192 -296.37482) (xy 296.76904 -296.37482) (xy 296.773 -296.325766)
			(xy 296.784777 -296.277982) (xy 296.804068 -296.232706) (xy 296.830371 -296.19111) (xy 296.863006 -296.154273)
			(xy 296.901127 -296.123148) (xy 296.943748 -296.098541) (xy 296.989764 -296.081089) (xy 297.037983 -296.071245)
			(xy 297.087158 -296.069264) (xy 297.136013 -296.075196) (xy 297.183284 -296.088888) (xy 297.227746 -296.109986)
			(xy 297.268249 -296.137942) (xy 297.303742 -296.172034) (xy 297.333307 -296.211378) (xy 297.356178 -296.254955)
			(xy 297.371762 -296.301636) (xy 297.379657 -296.350213) (xy 297.380152 -296.37482) (xy 297.719 -296.37482)
			(xy 297.72296 -296.325766) (xy 297.734737 -296.277982) (xy 297.754028 -296.232706) (xy 297.780331 -296.19111)
			(xy 297.812966 -296.154273) (xy 297.851087 -296.123148) (xy 297.893708 -296.098541) (xy 297.939724 -296.081089)
			(xy 297.987943 -296.071245) (xy 298.037118 -296.069264) (xy 298.085973 -296.075196) (xy 298.133244 -296.088888)
			(xy 298.177706 -296.109986) (xy 298.218209 -296.137942) (xy 298.253702 -296.172034) (xy 298.283267 -296.211378)
			(xy 298.306138 -296.254955) (xy 298.321722 -296.301636) (xy 298.329617 -296.350213) (xy 298.330112 -296.37482)
			(xy 298.66896 -296.37482) (xy 298.67292 -296.325766) (xy 298.684697 -296.277982) (xy 298.703988 -296.232706)
			(xy 298.730291 -296.19111) (xy 298.762926 -296.154273) (xy 298.801047 -296.123148) (xy 298.843668 -296.098541)
			(xy 298.889684 -296.081089) (xy 298.937903 -296.071245) (xy 298.987078 -296.069264) (xy 299.035933 -296.075196)
			(xy 299.083204 -296.088888) (xy 299.127666 -296.109986) (xy 299.168169 -296.137942) (xy 299.203662 -296.172034)
			(xy 299.233227 -296.211378) (xy 299.256098 -296.254955) (xy 299.271682 -296.301636) (xy 299.279577 -296.350213)
			(xy 299.280072 -296.37482) (xy 299.61892 -296.37482) (xy 299.62288 -296.325766) (xy 299.634657 -296.277982)
			(xy 299.653948 -296.232706) (xy 299.680251 -296.19111) (xy 299.712886 -296.154273) (xy 299.751007 -296.123148)
			(xy 299.793628 -296.098541) (xy 299.839644 -296.081089) (xy 299.887863 -296.071245) (xy 299.937038 -296.069264)
			(xy 299.985893 -296.075196) (xy 300.033164 -296.088888) (xy 300.077626 -296.109986) (xy 300.118129 -296.137942)
			(xy 300.153622 -296.172034) (xy 300.183187 -296.211378) (xy 300.206058 -296.254955) (xy 300.221642 -296.301636)
			(xy 300.229537 -296.350213) (xy 300.230032 -296.37482) (xy 300.56888 -296.37482) (xy 300.57284 -296.325766)
			(xy 300.584617 -296.277982) (xy 300.603908 -296.232706) (xy 300.630211 -296.19111) (xy 300.662846 -296.154273)
			(xy 300.700967 -296.123148) (xy 300.743588 -296.098541) (xy 300.789604 -296.081089) (xy 300.837823 -296.071245)
			(xy 300.886998 -296.069264) (xy 300.935853 -296.075196) (xy 300.983124 -296.088888) (xy 301.027586 -296.109986)
			(xy 301.068089 -296.137942) (xy 301.103582 -296.172034) (xy 301.133147 -296.211378) (xy 301.156018 -296.254955)
			(xy 301.171602 -296.301636) (xy 301.179497 -296.350213) (xy 301.179992 -296.37482) (xy 301.519094 -296.37482)
			(xy 301.523054 -296.325766) (xy 301.534831 -296.277982) (xy 301.554122 -296.232706) (xy 301.580425 -296.19111)
			(xy 301.61306 -296.154273) (xy 301.651181 -296.123148) (xy 301.693802 -296.098541) (xy 301.739818 -296.081089)
			(xy 301.788037 -296.071245) (xy 301.837212 -296.069264) (xy 301.886067 -296.075196) (xy 301.933338 -296.088888)
			(xy 301.9778 -296.109986) (xy 302.018303 -296.137942) (xy 302.053796 -296.172034) (xy 302.083361 -296.211378)
			(xy 302.106232 -296.254955) (xy 302.121816 -296.301636) (xy 302.129711 -296.350213) (xy 302.130206 -296.37482)
			(xy 302.469054 -296.37482) (xy 302.473014 -296.325766) (xy 302.484791 -296.277982) (xy 302.504082 -296.232706)
			(xy 302.530385 -296.19111) (xy 302.56302 -296.154273) (xy 302.601141 -296.123148) (xy 302.643762 -296.098541)
			(xy 302.689778 -296.081089) (xy 302.737997 -296.071245) (xy 302.787172 -296.069264) (xy 302.836027 -296.075196)
			(xy 302.883298 -296.088888) (xy 302.92776 -296.109986) (xy 302.968263 -296.137942) (xy 303.003756 -296.172034)
			(xy 303.033321 -296.211378) (xy 303.056192 -296.254955) (xy 303.071776 -296.301636) (xy 303.079671 -296.350213)
			(xy 303.080166 -296.37482) (xy 303.419014 -296.37482) (xy 303.422974 -296.325766) (xy 303.434751 -296.277982)
			(xy 303.454042 -296.232706) (xy 303.480345 -296.19111) (xy 303.51298 -296.154273) (xy 303.551101 -296.123148)
			(xy 303.593722 -296.098541) (xy 303.639738 -296.081089) (xy 303.687957 -296.071245) (xy 303.737132 -296.069264)
			(xy 303.785987 -296.075196) (xy 303.833258 -296.088888) (xy 303.87772 -296.109986) (xy 303.918223 -296.137942)
			(xy 303.953716 -296.172034) (xy 303.983281 -296.211378) (xy 304.006152 -296.254955) (xy 304.021736 -296.301636)
			(xy 304.029631 -296.350213) (xy 304.030126 -296.37482) (xy 305.318934 -296.37482) (xy 305.322894 -296.325766)
			(xy 305.334671 -296.277982) (xy 305.353962 -296.232706) (xy 305.380265 -296.19111) (xy 305.4129 -296.154273)
			(xy 305.451021 -296.123148) (xy 305.493642 -296.098541) (xy 305.539658 -296.081089) (xy 305.587877 -296.071245)
			(xy 305.637052 -296.069264) (xy 305.685907 -296.075196) (xy 305.733178 -296.088888) (xy 305.77764 -296.109986)
			(xy 305.818143 -296.137942) (xy 305.853636 -296.172034) (xy 305.883201 -296.211378) (xy 305.906072 -296.254955)
			(xy 305.921656 -296.301636) (xy 305.929551 -296.350213) (xy 305.930046 -296.37482) (xy 306.268894 -296.37482)
			(xy 306.272854 -296.325766) (xy 306.284631 -296.277982) (xy 306.303922 -296.232706) (xy 306.330225 -296.19111)
			(xy 306.36286 -296.154273) (xy 306.400981 -296.123148) (xy 306.443602 -296.098541) (xy 306.489618 -296.081089)
			(xy 306.537837 -296.071245) (xy 306.587012 -296.069264) (xy 306.635867 -296.075196) (xy 306.683138 -296.088888)
			(xy 306.7276 -296.109986) (xy 306.768103 -296.137942) (xy 306.803596 -296.172034) (xy 306.833161 -296.211378)
			(xy 306.856032 -296.254955) (xy 306.871616 -296.301636) (xy 306.879511 -296.350213) (xy 306.880006 -296.37482)
			(xy 307.219108 -296.37482) (xy 307.223068 -296.325766) (xy 307.234845 -296.277982) (xy 307.254136 -296.232706)
			(xy 307.280439 -296.19111) (xy 307.313074 -296.154273) (xy 307.351195 -296.123148) (xy 307.393816 -296.098541)
			(xy 307.439832 -296.081089) (xy 307.488051 -296.071245) (xy 307.537226 -296.069264) (xy 307.586081 -296.075196)
			(xy 307.633352 -296.088888) (xy 307.677814 -296.109986) (xy 307.718317 -296.137942) (xy 307.75381 -296.172034)
			(xy 307.783375 -296.211378) (xy 307.806246 -296.254955) (xy 307.82183 -296.301636) (xy 307.829725 -296.350213)
			(xy 307.83022 -296.37482) (xy 308.169068 -296.37482) (xy 308.173028 -296.325766) (xy 308.184805 -296.277982)
			(xy 308.204096 -296.232706) (xy 308.230399 -296.19111) (xy 308.263034 -296.154273) (xy 308.301155 -296.123148)
			(xy 308.343776 -296.098541) (xy 308.389792 -296.081089) (xy 308.438011 -296.071245) (xy 308.487186 -296.069264)
			(xy 308.536041 -296.075196) (xy 308.583312 -296.088888) (xy 308.627774 -296.109986) (xy 308.668277 -296.137942)
			(xy 308.70377 -296.172034) (xy 308.733335 -296.211378) (xy 308.756206 -296.254955) (xy 308.77179 -296.301636)
			(xy 308.779685 -296.350213) (xy 308.78018 -296.37482) (xy 309.119028 -296.37482) (xy 309.122988 -296.325766)
			(xy 309.134765 -296.277982) (xy 309.154056 -296.232706) (xy 309.180359 -296.19111) (xy 309.212994 -296.154273)
			(xy 309.251115 -296.123148) (xy 309.293736 -296.098541) (xy 309.339752 -296.081089) (xy 309.387971 -296.071245)
			(xy 309.437146 -296.069264) (xy 309.486001 -296.075196) (xy 309.533272 -296.088888) (xy 309.577734 -296.109986)
			(xy 309.618237 -296.137942) (xy 309.65373 -296.172034) (xy 309.683295 -296.211378) (xy 309.706166 -296.254955)
			(xy 309.72175 -296.301636) (xy 309.729645 -296.350213) (xy 309.73014 -296.37482) (xy 310.068988 -296.37482)
			(xy 310.072948 -296.325766) (xy 310.084725 -296.277982) (xy 310.104016 -296.232706) (xy 310.130319 -296.19111)
			(xy 310.162954 -296.154273) (xy 310.201075 -296.123148) (xy 310.243696 -296.098541) (xy 310.289712 -296.081089)
			(xy 310.337931 -296.071245) (xy 310.387106 -296.069264) (xy 310.435961 -296.075196) (xy 310.483232 -296.088888)
			(xy 310.527694 -296.109986) (xy 310.568197 -296.137942) (xy 310.60369 -296.172034) (xy 310.633255 -296.211378)
			(xy 310.656126 -296.254955) (xy 310.67171 -296.301636) (xy 310.679605 -296.350213) (xy 310.6801 -296.37482)
			(xy 311.018948 -296.37482) (xy 311.022908 -296.325766) (xy 311.034685 -296.277982) (xy 311.053976 -296.232706)
			(xy 311.080279 -296.19111) (xy 311.112914 -296.154273) (xy 311.151035 -296.123148) (xy 311.193656 -296.098541)
			(xy 311.239672 -296.081089) (xy 311.287891 -296.071245) (xy 311.337066 -296.069264) (xy 311.385921 -296.075196)
			(xy 311.433192 -296.088888) (xy 311.477654 -296.109986) (xy 311.518157 -296.137942) (xy 311.55365 -296.172034)
			(xy 311.583215 -296.211378) (xy 311.606086 -296.254955) (xy 311.62167 -296.301636) (xy 311.629565 -296.350213)
			(xy 311.63006 -296.37482) (xy 311.968908 -296.37482) (xy 311.972868 -296.325766) (xy 311.984645 -296.277982)
			(xy 312.003936 -296.232706) (xy 312.030239 -296.19111) (xy 312.062874 -296.154273) (xy 312.100995 -296.123148)
			(xy 312.143616 -296.098541) (xy 312.189632 -296.081089) (xy 312.237851 -296.071245) (xy 312.287026 -296.069264)
			(xy 312.335881 -296.075196) (xy 312.383152 -296.088888) (xy 312.427614 -296.109986) (xy 312.468117 -296.137942)
			(xy 312.50361 -296.172034) (xy 312.533175 -296.211378) (xy 312.556046 -296.254955) (xy 312.57163 -296.301636)
			(xy 312.579525 -296.350213) (xy 312.58002 -296.37482) (xy 312.919122 -296.37482) (xy 312.923082 -296.325766)
			(xy 312.934859 -296.277982) (xy 312.95415 -296.232706) (xy 312.980453 -296.19111) (xy 313.013088 -296.154273)
			(xy 313.051209 -296.123148) (xy 313.09383 -296.098541) (xy 313.139846 -296.081089) (xy 313.188065 -296.071245)
			(xy 313.23724 -296.069264) (xy 313.286095 -296.075196) (xy 313.333366 -296.088888) (xy 313.377828 -296.109986)
			(xy 313.418331 -296.137942) (xy 313.453824 -296.172034) (xy 313.483389 -296.211378) (xy 313.50626 -296.254955)
			(xy 313.521844 -296.301636) (xy 313.529739 -296.350213) (xy 313.530234 -296.37482) (xy 313.869082 -296.37482)
			(xy 313.873042 -296.325766) (xy 313.884819 -296.277982) (xy 313.90411 -296.232706) (xy 313.930413 -296.19111)
			(xy 313.963048 -296.154273) (xy 314.001169 -296.123148) (xy 314.04379 -296.098541) (xy 314.089806 -296.081089)
			(xy 314.138025 -296.071245) (xy 314.1872 -296.069264) (xy 314.236055 -296.075196) (xy 314.283326 -296.088888)
			(xy 314.327788 -296.109986) (xy 314.368291 -296.137942) (xy 314.403784 -296.172034) (xy 314.433349 -296.211378)
			(xy 314.45622 -296.254955) (xy 314.471804 -296.301636) (xy 314.479699 -296.350213) (xy 314.480194 -296.37482)
			(xy 314.819042 -296.37482) (xy 314.823002 -296.325766) (xy 314.834779 -296.277982) (xy 314.85407 -296.232706)
			(xy 314.880373 -296.19111) (xy 314.913008 -296.154273) (xy 314.951129 -296.123148) (xy 314.99375 -296.098541)
			(xy 315.039766 -296.081089) (xy 315.087985 -296.071245) (xy 315.13716 -296.069264) (xy 315.186015 -296.075196)
			(xy 315.233286 -296.088888) (xy 315.277748 -296.109986) (xy 315.318251 -296.137942) (xy 315.353744 -296.172034)
			(xy 315.383309 -296.211378) (xy 315.40618 -296.254955) (xy 315.421764 -296.301636) (xy 315.429659 -296.350213)
			(xy 315.430154 -296.37482) (xy 315.429659 -296.399427) (xy 315.421764 -296.448004) (xy 315.40618 -296.494685)
			(xy 315.383309 -296.538262) (xy 315.353744 -296.577606) (xy 315.318251 -296.611698) (xy 315.277748 -296.639654)
			(xy 315.233286 -296.660752) (xy 315.186015 -296.674444) (xy 315.13716 -296.680376) (xy 315.087985 -296.678395)
			(xy 315.039766 -296.668551) (xy 314.99375 -296.651099) (xy 314.951129 -296.626492) (xy 314.913008 -296.595367)
			(xy 314.880373 -296.55853) (xy 314.85407 -296.516934) (xy 314.834779 -296.471658) (xy 314.823002 -296.423874)
			(xy 314.819042 -296.37482) (xy 314.480194 -296.37482) (xy 314.479699 -296.399427) (xy 314.471804 -296.448004)
			(xy 314.45622 -296.494685) (xy 314.433349 -296.538262) (xy 314.403784 -296.577606) (xy 314.368291 -296.611698)
			(xy 314.327788 -296.639654) (xy 314.283326 -296.660752) (xy 314.236055 -296.674444) (xy 314.1872 -296.680376)
			(xy 314.138025 -296.678395) (xy 314.089806 -296.668551) (xy 314.04379 -296.651099) (xy 314.001169 -296.626492)
			(xy 313.963048 -296.595367) (xy 313.930413 -296.55853) (xy 313.90411 -296.516934) (xy 313.884819 -296.471658)
			(xy 313.873042 -296.423874) (xy 313.869082 -296.37482) (xy 313.530234 -296.37482) (xy 313.529739 -296.399427)
			(xy 313.521844 -296.448004) (xy 313.50626 -296.494685) (xy 313.483389 -296.538262) (xy 313.453824 -296.577606)
			(xy 313.418331 -296.611698) (xy 313.377828 -296.639654) (xy 313.333366 -296.660752) (xy 313.286095 -296.674444)
			(xy 313.23724 -296.680376) (xy 313.188065 -296.678395) (xy 313.139846 -296.668551) (xy 313.09383 -296.651099)
			(xy 313.051209 -296.626492) (xy 313.013088 -296.595367) (xy 312.980453 -296.55853) (xy 312.95415 -296.516934)
			(xy 312.934859 -296.471658) (xy 312.923082 -296.423874) (xy 312.919122 -296.37482) (xy 312.58002 -296.37482)
			(xy 312.579525 -296.399427) (xy 312.57163 -296.448004) (xy 312.556046 -296.494685) (xy 312.533175 -296.538262)
			(xy 312.50361 -296.577606) (xy 312.468117 -296.611698) (xy 312.427614 -296.639654) (xy 312.383152 -296.660752)
			(xy 312.335881 -296.674444) (xy 312.287026 -296.680376) (xy 312.237851 -296.678395) (xy 312.189632 -296.668551)
			(xy 312.143616 -296.651099) (xy 312.100995 -296.626492) (xy 312.062874 -296.595367) (xy 312.030239 -296.55853)
			(xy 312.003936 -296.516934) (xy 311.984645 -296.471658) (xy 311.972868 -296.423874) (xy 311.968908 -296.37482)
			(xy 311.63006 -296.37482) (xy 311.629565 -296.399427) (xy 311.62167 -296.448004) (xy 311.606086 -296.494685)
			(xy 311.583215 -296.538262) (xy 311.55365 -296.577606) (xy 311.518157 -296.611698) (xy 311.477654 -296.639654)
			(xy 311.433192 -296.660752) (xy 311.385921 -296.674444) (xy 311.337066 -296.680376) (xy 311.287891 -296.678395)
			(xy 311.239672 -296.668551) (xy 311.193656 -296.651099) (xy 311.151035 -296.626492) (xy 311.112914 -296.595367)
			(xy 311.080279 -296.55853) (xy 311.053976 -296.516934) (xy 311.034685 -296.471658) (xy 311.022908 -296.423874)
			(xy 311.018948 -296.37482) (xy 310.6801 -296.37482) (xy 310.679605 -296.399427) (xy 310.67171 -296.448004)
			(xy 310.656126 -296.494685) (xy 310.633255 -296.538262) (xy 310.60369 -296.577606) (xy 310.568197 -296.611698)
			(xy 310.527694 -296.639654) (xy 310.483232 -296.660752) (xy 310.435961 -296.674444) (xy 310.387106 -296.680376)
			(xy 310.337931 -296.678395) (xy 310.289712 -296.668551) (xy 310.243696 -296.651099) (xy 310.201075 -296.626492)
			(xy 310.162954 -296.595367) (xy 310.130319 -296.55853) (xy 310.104016 -296.516934) (xy 310.084725 -296.471658)
			(xy 310.072948 -296.423874) (xy 310.068988 -296.37482) (xy 309.73014 -296.37482) (xy 309.729645 -296.399427)
			(xy 309.72175 -296.448004) (xy 309.706166 -296.494685) (xy 309.683295 -296.538262) (xy 309.65373 -296.577606)
			(xy 309.618237 -296.611698) (xy 309.577734 -296.639654) (xy 309.533272 -296.660752) (xy 309.486001 -296.674444)
			(xy 309.437146 -296.680376) (xy 309.387971 -296.678395) (xy 309.339752 -296.668551) (xy 309.293736 -296.651099)
			(xy 309.251115 -296.626492) (xy 309.212994 -296.595367) (xy 309.180359 -296.55853) (xy 309.154056 -296.516934)
			(xy 309.134765 -296.471658) (xy 309.122988 -296.423874) (xy 309.119028 -296.37482) (xy 308.78018 -296.37482)
			(xy 308.779685 -296.399427) (xy 308.77179 -296.448004) (xy 308.756206 -296.494685) (xy 308.733335 -296.538262)
			(xy 308.70377 -296.577606) (xy 308.668277 -296.611698) (xy 308.627774 -296.639654) (xy 308.583312 -296.660752)
			(xy 308.536041 -296.674444) (xy 308.487186 -296.680376) (xy 308.438011 -296.678395) (xy 308.389792 -296.668551)
			(xy 308.343776 -296.651099) (xy 308.301155 -296.626492) (xy 308.263034 -296.595367) (xy 308.230399 -296.55853)
			(xy 308.204096 -296.516934) (xy 308.184805 -296.471658) (xy 308.173028 -296.423874) (xy 308.169068 -296.37482)
			(xy 307.83022 -296.37482) (xy 307.829725 -296.399427) (xy 307.82183 -296.448004) (xy 307.806246 -296.494685)
			(xy 307.783375 -296.538262) (xy 307.75381 -296.577606) (xy 307.718317 -296.611698) (xy 307.677814 -296.639654)
			(xy 307.633352 -296.660752) (xy 307.586081 -296.674444) (xy 307.537226 -296.680376) (xy 307.488051 -296.678395)
			(xy 307.439832 -296.668551) (xy 307.393816 -296.651099) (xy 307.351195 -296.626492) (xy 307.313074 -296.595367)
			(xy 307.280439 -296.55853) (xy 307.254136 -296.516934) (xy 307.234845 -296.471658) (xy 307.223068 -296.423874)
			(xy 307.219108 -296.37482) (xy 306.880006 -296.37482) (xy 306.879511 -296.399427) (xy 306.871616 -296.448004)
			(xy 306.856032 -296.494685) (xy 306.833161 -296.538262) (xy 306.803596 -296.577606) (xy 306.768103 -296.611698)
			(xy 306.7276 -296.639654) (xy 306.683138 -296.660752) (xy 306.635867 -296.674444) (xy 306.587012 -296.680376)
			(xy 306.537837 -296.678395) (xy 306.489618 -296.668551) (xy 306.443602 -296.651099) (xy 306.400981 -296.626492)
			(xy 306.36286 -296.595367) (xy 306.330225 -296.55853) (xy 306.303922 -296.516934) (xy 306.284631 -296.471658)
			(xy 306.272854 -296.423874) (xy 306.268894 -296.37482) (xy 305.930046 -296.37482) (xy 305.929551 -296.399427)
			(xy 305.921656 -296.448004) (xy 305.906072 -296.494685) (xy 305.883201 -296.538262) (xy 305.853636 -296.577606)
			(xy 305.818143 -296.611698) (xy 305.77764 -296.639654) (xy 305.733178 -296.660752) (xy 305.685907 -296.674444)
			(xy 305.637052 -296.680376) (xy 305.587877 -296.678395) (xy 305.539658 -296.668551) (xy 305.493642 -296.651099)
			(xy 305.451021 -296.626492) (xy 305.4129 -296.595367) (xy 305.380265 -296.55853) (xy 305.353962 -296.516934)
			(xy 305.334671 -296.471658) (xy 305.322894 -296.423874) (xy 305.318934 -296.37482) (xy 304.030126 -296.37482)
			(xy 304.029631 -296.399427) (xy 304.021736 -296.448004) (xy 304.006152 -296.494685) (xy 303.983281 -296.538262)
			(xy 303.953716 -296.577606) (xy 303.918223 -296.611698) (xy 303.87772 -296.639654) (xy 303.833258 -296.660752)
			(xy 303.785987 -296.674444) (xy 303.737132 -296.680376) (xy 303.687957 -296.678395) (xy 303.639738 -296.668551)
			(xy 303.593722 -296.651099) (xy 303.551101 -296.626492) (xy 303.51298 -296.595367) (xy 303.480345 -296.55853)
			(xy 303.454042 -296.516934) (xy 303.434751 -296.471658) (xy 303.422974 -296.423874) (xy 303.419014 -296.37482)
			(xy 303.080166 -296.37482) (xy 303.079671 -296.399427) (xy 303.071776 -296.448004) (xy 303.056192 -296.494685)
			(xy 303.033321 -296.538262) (xy 303.003756 -296.577606) (xy 302.968263 -296.611698) (xy 302.92776 -296.639654)
			(xy 302.883298 -296.660752) (xy 302.836027 -296.674444) (xy 302.787172 -296.680376) (xy 302.737997 -296.678395)
			(xy 302.689778 -296.668551) (xy 302.643762 -296.651099) (xy 302.601141 -296.626492) (xy 302.56302 -296.595367)
			(xy 302.530385 -296.55853) (xy 302.504082 -296.516934) (xy 302.484791 -296.471658) (xy 302.473014 -296.423874)
			(xy 302.469054 -296.37482) (xy 302.130206 -296.37482) (xy 302.129711 -296.399427) (xy 302.121816 -296.448004)
			(xy 302.106232 -296.494685) (xy 302.083361 -296.538262) (xy 302.053796 -296.577606) (xy 302.018303 -296.611698)
			(xy 301.9778 -296.639654) (xy 301.933338 -296.660752) (xy 301.886067 -296.674444) (xy 301.837212 -296.680376)
			(xy 301.788037 -296.678395) (xy 301.739818 -296.668551) (xy 301.693802 -296.651099) (xy 301.651181 -296.626492)
			(xy 301.61306 -296.595367) (xy 301.580425 -296.55853) (xy 301.554122 -296.516934) (xy 301.534831 -296.471658)
			(xy 301.523054 -296.423874) (xy 301.519094 -296.37482) (xy 301.179992 -296.37482) (xy 301.179497 -296.399427)
			(xy 301.171602 -296.448004) (xy 301.156018 -296.494685) (xy 301.133147 -296.538262) (xy 301.103582 -296.577606)
			(xy 301.068089 -296.611698) (xy 301.027586 -296.639654) (xy 300.983124 -296.660752) (xy 300.935853 -296.674444)
			(xy 300.886998 -296.680376) (xy 300.837823 -296.678395) (xy 300.789604 -296.668551) (xy 300.743588 -296.651099)
			(xy 300.700967 -296.626492) (xy 300.662846 -296.595367) (xy 300.630211 -296.55853) (xy 300.603908 -296.516934)
			(xy 300.584617 -296.471658) (xy 300.57284 -296.423874) (xy 300.56888 -296.37482) (xy 300.230032 -296.37482)
			(xy 300.229537 -296.399427) (xy 300.221642 -296.448004) (xy 300.206058 -296.494685) (xy 300.183187 -296.538262)
			(xy 300.153622 -296.577606) (xy 300.118129 -296.611698) (xy 300.077626 -296.639654) (xy 300.033164 -296.660752)
			(xy 299.985893 -296.674444) (xy 299.937038 -296.680376) (xy 299.887863 -296.678395) (xy 299.839644 -296.668551)
			(xy 299.793628 -296.651099) (xy 299.751007 -296.626492) (xy 299.712886 -296.595367) (xy 299.680251 -296.55853)
			(xy 299.653948 -296.516934) (xy 299.634657 -296.471658) (xy 299.62288 -296.423874) (xy 299.61892 -296.37482)
			(xy 299.280072 -296.37482) (xy 299.279577 -296.399427) (xy 299.271682 -296.448004) (xy 299.256098 -296.494685)
			(xy 299.233227 -296.538262) (xy 299.203662 -296.577606) (xy 299.168169 -296.611698) (xy 299.127666 -296.639654)
			(xy 299.083204 -296.660752) (xy 299.035933 -296.674444) (xy 298.987078 -296.680376) (xy 298.937903 -296.678395)
			(xy 298.889684 -296.668551) (xy 298.843668 -296.651099) (xy 298.801047 -296.626492) (xy 298.762926 -296.595367)
			(xy 298.730291 -296.55853) (xy 298.703988 -296.516934) (xy 298.684697 -296.471658) (xy 298.67292 -296.423874)
			(xy 298.66896 -296.37482) (xy 298.330112 -296.37482) (xy 298.329617 -296.399427) (xy 298.321722 -296.448004)
			(xy 298.306138 -296.494685) (xy 298.283267 -296.538262) (xy 298.253702 -296.577606) (xy 298.218209 -296.611698)
			(xy 298.177706 -296.639654) (xy 298.133244 -296.660752) (xy 298.085973 -296.674444) (xy 298.037118 -296.680376)
			(xy 297.987943 -296.678395) (xy 297.939724 -296.668551) (xy 297.893708 -296.651099) (xy 297.851087 -296.626492)
			(xy 297.812966 -296.595367) (xy 297.780331 -296.55853) (xy 297.754028 -296.516934) (xy 297.734737 -296.471658)
			(xy 297.72296 -296.423874) (xy 297.719 -296.37482) (xy 297.380152 -296.37482) (xy 297.379657 -296.399427)
			(xy 297.371762 -296.448004) (xy 297.356178 -296.494685) (xy 297.333307 -296.538262) (xy 297.303742 -296.577606)
			(xy 297.268249 -296.611698) (xy 297.227746 -296.639654) (xy 297.183284 -296.660752) (xy 297.136013 -296.674444)
			(xy 297.087158 -296.680376) (xy 297.037983 -296.678395) (xy 296.989764 -296.668551) (xy 296.943748 -296.651099)
			(xy 296.901127 -296.626492) (xy 296.863006 -296.595367) (xy 296.830371 -296.55853) (xy 296.804068 -296.516934)
			(xy 296.784777 -296.471658) (xy 296.773 -296.423874) (xy 296.76904 -296.37482) (xy 296.430192 -296.37482)
			(xy 296.429697 -296.399427) (xy 296.421802 -296.448004) (xy 296.406218 -296.494685) (xy 296.383347 -296.538262)
			(xy 296.353782 -296.577606) (xy 296.318289 -296.611698) (xy 296.277786 -296.639654) (xy 296.233324 -296.660752)
			(xy 296.186053 -296.674444) (xy 296.137198 -296.680376) (xy 296.088023 -296.678395) (xy 296.039804 -296.668551)
			(xy 295.993788 -296.651099) (xy 295.951167 -296.626492) (xy 295.913046 -296.595367) (xy 295.880411 -296.55853)
			(xy 295.854108 -296.516934) (xy 295.834817 -296.471658) (xy 295.82304 -296.423874) (xy 295.81908 -296.37482)
			(xy 295.480232 -296.37482) (xy 295.479737 -296.399427) (xy 295.471842 -296.448004) (xy 295.456258 -296.494685)
			(xy 295.433387 -296.538262) (xy 295.403822 -296.577606) (xy 295.368329 -296.611698) (xy 295.327826 -296.639654)
			(xy 295.283364 -296.660752) (xy 295.236093 -296.674444) (xy 295.187238 -296.680376) (xy 295.138063 -296.678395)
			(xy 295.089844 -296.668551) (xy 295.043828 -296.651099) (xy 295.001207 -296.626492) (xy 294.963086 -296.595367)
			(xy 294.930451 -296.55853) (xy 294.904148 -296.516934) (xy 294.884857 -296.471658) (xy 294.87308 -296.423874)
			(xy 294.86912 -296.37482) (xy 294.530018 -296.37482) (xy 294.529523 -296.399427) (xy 294.521628 -296.448004)
			(xy 294.506044 -296.494685) (xy 294.483173 -296.538262) (xy 294.453608 -296.577606) (xy 294.418115 -296.611698)
			(xy 294.377612 -296.639654) (xy 294.33315 -296.660752) (xy 294.285879 -296.674444) (xy 294.237024 -296.680376)
			(xy 294.187849 -296.678395) (xy 294.13963 -296.668551) (xy 294.093614 -296.651099) (xy 294.050993 -296.626492)
			(xy 294.012872 -296.595367) (xy 293.980237 -296.55853) (xy 293.953934 -296.516934) (xy 293.934643 -296.471658)
			(xy 293.922866 -296.423874) (xy 293.918906 -296.37482) (xy 293.580058 -296.37482) (xy 293.579563 -296.399427)
			(xy 293.571668 -296.448004) (xy 293.556084 -296.494685) (xy 293.533213 -296.538262) (xy 293.503648 -296.577606)
			(xy 293.468155 -296.611698) (xy 293.427652 -296.639654) (xy 293.38319 -296.660752) (xy 293.335919 -296.674444)
			(xy 293.287064 -296.680376) (xy 293.237889 -296.678395) (xy 293.18967 -296.668551) (xy 293.143654 -296.651099)
			(xy 293.101033 -296.626492) (xy 293.062912 -296.595367) (xy 293.030277 -296.55853) (xy 293.003974 -296.516934)
			(xy 292.984683 -296.471658) (xy 292.972906 -296.423874) (xy 292.968946 -296.37482) (xy 292.630575 -296.37482)
			(xy 292.62653 -296.424379) (xy 292.6145 -296.472642) (xy 292.594804 -296.518316) (xy 292.567964 -296.560193)
			(xy 292.534689 -296.597164) (xy 292.495861 -296.628251) (xy 292.452506 -296.652631) (xy 292.405772 -296.66966)
			(xy 292.381432 -296.674794) (xy 292.38067 -296.675048) (xy 292.372013 -296.677002) (xy 292.356689 -296.685924)
			(xy 292.345332 -296.699542) (xy 292.339306 -296.716219) (xy 292.339014 -296.725086) (xy 292.339014 -296.974514)
			(xy 292.339629 -296.986364) (xy 292.350201 -297.007575) (xy 292.36912 -297.021849) (xy 292.38067 -297.024552)
			(xy 292.381432 -297.024806) (xy 292.405783 -297.029902) (xy 292.452523 -297.046933) (xy 292.495883 -297.071317)
			(xy 292.534716 -297.102408) (xy 292.567995 -297.139383) (xy 292.594839 -297.181265) (xy 292.614537 -297.226946)
			(xy 292.626569 -297.275215) (xy 292.630615 -297.32478) (xy 292.968946 -297.32478) (xy 292.972906 -297.275726)
			(xy 292.984683 -297.227942) (xy 293.003974 -297.182666) (xy 293.030277 -297.14107) (xy 293.062912 -297.104233)
			(xy 293.101033 -297.073108) (xy 293.143654 -297.048501) (xy 293.18967 -297.031049) (xy 293.237889 -297.021205)
			(xy 293.287064 -297.019224) (xy 293.335919 -297.025156) (xy 293.38319 -297.038848) (xy 293.427652 -297.059946)
			(xy 293.468155 -297.087902) (xy 293.503648 -297.121994) (xy 293.533213 -297.161338) (xy 293.556084 -297.204915)
			(xy 293.571668 -297.251596) (xy 293.579563 -297.300173) (xy 293.580058 -297.32478) (xy 293.918906 -297.32478)
			(xy 293.922866 -297.275726) (xy 293.934643 -297.227942) (xy 293.953934 -297.182666) (xy 293.980237 -297.14107)
			(xy 294.012872 -297.104233) (xy 294.050993 -297.073108) (xy 294.093614 -297.048501) (xy 294.13963 -297.031049)
			(xy 294.187849 -297.021205) (xy 294.237024 -297.019224) (xy 294.285879 -297.025156) (xy 294.33315 -297.038848)
			(xy 294.377612 -297.059946) (xy 294.418115 -297.087902) (xy 294.453608 -297.121994) (xy 294.483173 -297.161338)
			(xy 294.506044 -297.204915) (xy 294.521628 -297.251596) (xy 294.529523 -297.300173) (xy 294.530018 -297.32478)
			(xy 294.86912 -297.32478) (xy 294.87308 -297.275726) (xy 294.884857 -297.227942) (xy 294.904148 -297.182666)
			(xy 294.930451 -297.14107) (xy 294.963086 -297.104233) (xy 295.001207 -297.073108) (xy 295.043828 -297.048501)
			(xy 295.089844 -297.031049) (xy 295.138063 -297.021205) (xy 295.187238 -297.019224) (xy 295.236093 -297.025156)
			(xy 295.283364 -297.038848) (xy 295.327826 -297.059946) (xy 295.368329 -297.087902) (xy 295.403822 -297.121994)
			(xy 295.433387 -297.161338) (xy 295.456258 -297.204915) (xy 295.471842 -297.251596) (xy 295.479737 -297.300173)
			(xy 295.480232 -297.32478) (xy 295.81908 -297.32478) (xy 295.82304 -297.275726) (xy 295.834817 -297.227942)
			(xy 295.854108 -297.182666) (xy 295.880411 -297.14107) (xy 295.913046 -297.104233) (xy 295.951167 -297.073108)
			(xy 295.993788 -297.048501) (xy 296.039804 -297.031049) (xy 296.088023 -297.021205) (xy 296.137198 -297.019224)
			(xy 296.186053 -297.025156) (xy 296.233324 -297.038848) (xy 296.277786 -297.059946) (xy 296.318289 -297.087902)
			(xy 296.353782 -297.121994) (xy 296.383347 -297.161338) (xy 296.406218 -297.204915) (xy 296.421802 -297.251596)
			(xy 296.429697 -297.300173) (xy 296.430192 -297.32478) (xy 296.76904 -297.32478) (xy 296.773 -297.275726)
			(xy 296.784777 -297.227942) (xy 296.804068 -297.182666) (xy 296.830371 -297.14107) (xy 296.863006 -297.104233)
			(xy 296.901127 -297.073108) (xy 296.943748 -297.048501) (xy 296.989764 -297.031049) (xy 297.037983 -297.021205)
			(xy 297.087158 -297.019224) (xy 297.136013 -297.025156) (xy 297.183284 -297.038848) (xy 297.227746 -297.059946)
			(xy 297.268249 -297.087902) (xy 297.303742 -297.121994) (xy 297.333307 -297.161338) (xy 297.356178 -297.204915)
			(xy 297.371762 -297.251596) (xy 297.379657 -297.300173) (xy 297.380152 -297.32478) (xy 297.719 -297.32478)
			(xy 297.72296 -297.275726) (xy 297.734737 -297.227942) (xy 297.754028 -297.182666) (xy 297.780331 -297.14107)
			(xy 297.812966 -297.104233) (xy 297.851087 -297.073108) (xy 297.893708 -297.048501) (xy 297.939724 -297.031049)
			(xy 297.987943 -297.021205) (xy 298.037118 -297.019224) (xy 298.085973 -297.025156) (xy 298.133244 -297.038848)
			(xy 298.177706 -297.059946) (xy 298.218209 -297.087902) (xy 298.253702 -297.121994) (xy 298.283267 -297.161338)
			(xy 298.306138 -297.204915) (xy 298.321722 -297.251596) (xy 298.329617 -297.300173) (xy 298.330112 -297.32478)
			(xy 298.66896 -297.32478) (xy 298.67292 -297.275726) (xy 298.684697 -297.227942) (xy 298.703988 -297.182666)
			(xy 298.730291 -297.14107) (xy 298.762926 -297.104233) (xy 298.801047 -297.073108) (xy 298.843668 -297.048501)
			(xy 298.889684 -297.031049) (xy 298.937903 -297.021205) (xy 298.987078 -297.019224) (xy 299.035933 -297.025156)
			(xy 299.083204 -297.038848) (xy 299.127666 -297.059946) (xy 299.168169 -297.087902) (xy 299.203662 -297.121994)
			(xy 299.233227 -297.161338) (xy 299.256098 -297.204915) (xy 299.271682 -297.251596) (xy 299.279577 -297.300173)
			(xy 299.280072 -297.32478) (xy 299.61892 -297.32478) (xy 299.62288 -297.275726) (xy 299.634657 -297.227942)
			(xy 299.653948 -297.182666) (xy 299.680251 -297.14107) (xy 299.712886 -297.104233) (xy 299.751007 -297.073108)
			(xy 299.793628 -297.048501) (xy 299.839644 -297.031049) (xy 299.887863 -297.021205) (xy 299.937038 -297.019224)
			(xy 299.985893 -297.025156) (xy 300.033164 -297.038848) (xy 300.077626 -297.059946) (xy 300.118129 -297.087902)
			(xy 300.153622 -297.121994) (xy 300.183187 -297.161338) (xy 300.206058 -297.204915) (xy 300.221642 -297.251596)
			(xy 300.229537 -297.300173) (xy 300.230032 -297.32478) (xy 300.56888 -297.32478) (xy 300.57284 -297.275726)
			(xy 300.584617 -297.227942) (xy 300.603908 -297.182666) (xy 300.630211 -297.14107) (xy 300.662846 -297.104233)
			(xy 300.700967 -297.073108) (xy 300.743588 -297.048501) (xy 300.789604 -297.031049) (xy 300.837823 -297.021205)
			(xy 300.886998 -297.019224) (xy 300.935853 -297.025156) (xy 300.983124 -297.038848) (xy 301.027586 -297.059946)
			(xy 301.068089 -297.087902) (xy 301.103582 -297.121994) (xy 301.133147 -297.161338) (xy 301.156018 -297.204915)
			(xy 301.171602 -297.251596) (xy 301.179497 -297.300173) (xy 301.179992 -297.32478) (xy 301.519094 -297.32478)
			(xy 301.523054 -297.275726) (xy 301.534831 -297.227942) (xy 301.554122 -297.182666) (xy 301.580425 -297.14107)
			(xy 301.61306 -297.104233) (xy 301.651181 -297.073108) (xy 301.693802 -297.048501) (xy 301.739818 -297.031049)
			(xy 301.788037 -297.021205) (xy 301.837212 -297.019224) (xy 301.886067 -297.025156) (xy 301.933338 -297.038848)
			(xy 301.9778 -297.059946) (xy 302.018303 -297.087902) (xy 302.053796 -297.121994) (xy 302.083361 -297.161338)
			(xy 302.106232 -297.204915) (xy 302.121816 -297.251596) (xy 302.129711 -297.300173) (xy 302.130206 -297.32478)
			(xy 302.469054 -297.32478) (xy 302.473014 -297.275726) (xy 302.484791 -297.227942) (xy 302.504082 -297.182666)
			(xy 302.530385 -297.14107) (xy 302.56302 -297.104233) (xy 302.601141 -297.073108) (xy 302.643762 -297.048501)
			(xy 302.689778 -297.031049) (xy 302.737997 -297.021205) (xy 302.787172 -297.019224) (xy 302.836027 -297.025156)
			(xy 302.883298 -297.038848) (xy 302.92776 -297.059946) (xy 302.968263 -297.087902) (xy 303.003756 -297.121994)
			(xy 303.033321 -297.161338) (xy 303.056192 -297.204915) (xy 303.071776 -297.251596) (xy 303.079671 -297.300173)
			(xy 303.080166 -297.32478) (xy 303.419014 -297.32478) (xy 303.422974 -297.275726) (xy 303.434751 -297.227942)
			(xy 303.454042 -297.182666) (xy 303.480345 -297.14107) (xy 303.51298 -297.104233) (xy 303.551101 -297.073108)
			(xy 303.593722 -297.048501) (xy 303.639738 -297.031049) (xy 303.687957 -297.021205) (xy 303.737132 -297.019224)
			(xy 303.785987 -297.025156) (xy 303.833258 -297.038848) (xy 303.87772 -297.059946) (xy 303.918223 -297.087902)
			(xy 303.953716 -297.121994) (xy 303.983281 -297.161338) (xy 304.006152 -297.204915) (xy 304.021736 -297.251596)
			(xy 304.029631 -297.300173) (xy 304.030126 -297.32478) (xy 305.318934 -297.32478) (xy 305.322894 -297.275726)
			(xy 305.334671 -297.227942) (xy 305.353962 -297.182666) (xy 305.380265 -297.14107) (xy 305.4129 -297.104233)
			(xy 305.451021 -297.073108) (xy 305.493642 -297.048501) (xy 305.539658 -297.031049) (xy 305.587877 -297.021205)
			(xy 305.637052 -297.019224) (xy 305.685907 -297.025156) (xy 305.733178 -297.038848) (xy 305.77764 -297.059946)
			(xy 305.818143 -297.087902) (xy 305.853636 -297.121994) (xy 305.883201 -297.161338) (xy 305.906072 -297.204915)
			(xy 305.921656 -297.251596) (xy 305.929551 -297.300173) (xy 305.930046 -297.32478) (xy 306.269148 -297.32478)
			(xy 306.273108 -297.275726) (xy 306.284885 -297.227942) (xy 306.304176 -297.182666) (xy 306.330479 -297.14107)
			(xy 306.363114 -297.104233) (xy 306.401235 -297.073108) (xy 306.443856 -297.048501) (xy 306.489872 -297.031049)
			(xy 306.538091 -297.021205) (xy 306.587266 -297.019224) (xy 306.636121 -297.025156) (xy 306.683392 -297.038848)
			(xy 306.727854 -297.059946) (xy 306.768357 -297.087902) (xy 306.80385 -297.121994) (xy 306.833415 -297.161338)
			(xy 306.856286 -297.204915) (xy 306.87187 -297.251596) (xy 306.879765 -297.300173) (xy 306.88026 -297.32478)
			(xy 307.219108 -297.32478) (xy 307.223068 -297.275726) (xy 307.234845 -297.227942) (xy 307.254136 -297.182666)
			(xy 307.280439 -297.14107) (xy 307.313074 -297.104233) (xy 307.351195 -297.073108) (xy 307.393816 -297.048501)
			(xy 307.439832 -297.031049) (xy 307.488051 -297.021205) (xy 307.537226 -297.019224) (xy 307.586081 -297.025156)
			(xy 307.633352 -297.038848) (xy 307.677814 -297.059946) (xy 307.718317 -297.087902) (xy 307.75381 -297.121994)
			(xy 307.783375 -297.161338) (xy 307.806246 -297.204915) (xy 307.82183 -297.251596) (xy 307.829725 -297.300173)
			(xy 307.83022 -297.32478) (xy 308.169068 -297.32478) (xy 308.173028 -297.275726) (xy 308.184805 -297.227942)
			(xy 308.204096 -297.182666) (xy 308.230399 -297.14107) (xy 308.263034 -297.104233) (xy 308.301155 -297.073108)
			(xy 308.343776 -297.048501) (xy 308.389792 -297.031049) (xy 308.438011 -297.021205) (xy 308.487186 -297.019224)
			(xy 308.536041 -297.025156) (xy 308.583312 -297.038848) (xy 308.627774 -297.059946) (xy 308.668277 -297.087902)
			(xy 308.70377 -297.121994) (xy 308.733335 -297.161338) (xy 308.756206 -297.204915) (xy 308.77179 -297.251596)
			(xy 308.779685 -297.300173) (xy 308.78018 -297.32478) (xy 309.119028 -297.32478) (xy 309.122988 -297.275726)
			(xy 309.134765 -297.227942) (xy 309.154056 -297.182666) (xy 309.180359 -297.14107) (xy 309.212994 -297.104233)
			(xy 309.251115 -297.073108) (xy 309.293736 -297.048501) (xy 309.339752 -297.031049) (xy 309.387971 -297.021205)
			(xy 309.437146 -297.019224) (xy 309.486001 -297.025156) (xy 309.533272 -297.038848) (xy 309.577734 -297.059946)
			(xy 309.618237 -297.087902) (xy 309.65373 -297.121994) (xy 309.683295 -297.161338) (xy 309.706166 -297.204915)
			(xy 309.72175 -297.251596) (xy 309.729645 -297.300173) (xy 309.73014 -297.32478) (xy 310.068988 -297.32478)
			(xy 310.072948 -297.275726) (xy 310.084725 -297.227942) (xy 310.104016 -297.182666) (xy 310.130319 -297.14107)
			(xy 310.162954 -297.104233) (xy 310.201075 -297.073108) (xy 310.243696 -297.048501) (xy 310.289712 -297.031049)
			(xy 310.337931 -297.021205) (xy 310.387106 -297.019224) (xy 310.435961 -297.025156) (xy 310.483232 -297.038848)
			(xy 310.527694 -297.059946) (xy 310.568197 -297.087902) (xy 310.60369 -297.121994) (xy 310.633255 -297.161338)
			(xy 310.656126 -297.204915) (xy 310.67171 -297.251596) (xy 310.679605 -297.300173) (xy 310.6801 -297.32478)
			(xy 311.018948 -297.32478) (xy 311.022908 -297.275726) (xy 311.034685 -297.227942) (xy 311.053976 -297.182666)
			(xy 311.080279 -297.14107) (xy 311.112914 -297.104233) (xy 311.151035 -297.073108) (xy 311.193656 -297.048501)
			(xy 311.239672 -297.031049) (xy 311.287891 -297.021205) (xy 311.337066 -297.019224) (xy 311.385921 -297.025156)
			(xy 311.433192 -297.038848) (xy 311.477654 -297.059946) (xy 311.518157 -297.087902) (xy 311.55365 -297.121994)
			(xy 311.583215 -297.161338) (xy 311.606086 -297.204915) (xy 311.62167 -297.251596) (xy 311.629565 -297.300173)
			(xy 311.63006 -297.32478) (xy 311.968908 -297.32478) (xy 311.972868 -297.275726) (xy 311.984645 -297.227942)
			(xy 312.003936 -297.182666) (xy 312.030239 -297.14107) (xy 312.062874 -297.104233) (xy 312.100995 -297.073108)
			(xy 312.143616 -297.048501) (xy 312.189632 -297.031049) (xy 312.237851 -297.021205) (xy 312.287026 -297.019224)
			(xy 312.335881 -297.025156) (xy 312.383152 -297.038848) (xy 312.427614 -297.059946) (xy 312.468117 -297.087902)
			(xy 312.50361 -297.121994) (xy 312.533175 -297.161338) (xy 312.556046 -297.204915) (xy 312.57163 -297.251596)
			(xy 312.579525 -297.300173) (xy 312.58002 -297.32478) (xy 312.919122 -297.32478) (xy 312.923082 -297.275726)
			(xy 312.934859 -297.227942) (xy 312.95415 -297.182666) (xy 312.980453 -297.14107) (xy 313.013088 -297.104233)
			(xy 313.051209 -297.073108) (xy 313.09383 -297.048501) (xy 313.139846 -297.031049) (xy 313.188065 -297.021205)
			(xy 313.23724 -297.019224) (xy 313.286095 -297.025156) (xy 313.333366 -297.038848) (xy 313.377828 -297.059946)
			(xy 313.418331 -297.087902) (xy 313.453824 -297.121994) (xy 313.483389 -297.161338) (xy 313.50626 -297.204915)
			(xy 313.521844 -297.251596) (xy 313.529739 -297.300173) (xy 313.530234 -297.32478) (xy 313.869082 -297.32478)
			(xy 313.873042 -297.275726) (xy 313.884819 -297.227942) (xy 313.90411 -297.182666) (xy 313.930413 -297.14107)
			(xy 313.963048 -297.104233) (xy 314.001169 -297.073108) (xy 314.04379 -297.048501) (xy 314.089806 -297.031049)
			(xy 314.138025 -297.021205) (xy 314.1872 -297.019224) (xy 314.236055 -297.025156) (xy 314.283326 -297.038848)
			(xy 314.327788 -297.059946) (xy 314.368291 -297.087902) (xy 314.403784 -297.121994) (xy 314.433349 -297.161338)
			(xy 314.45622 -297.204915) (xy 314.471804 -297.251596) (xy 314.479699 -297.300173) (xy 314.480194 -297.32478)
			(xy 314.819042 -297.32478) (xy 314.823002 -297.275726) (xy 314.834779 -297.227942) (xy 314.85407 -297.182666)
			(xy 314.880373 -297.14107) (xy 314.913008 -297.104233) (xy 314.951129 -297.073108) (xy 314.99375 -297.048501)
			(xy 315.039766 -297.031049) (xy 315.087985 -297.021205) (xy 315.13716 -297.019224) (xy 315.186015 -297.025156)
			(xy 315.233286 -297.038848) (xy 315.277748 -297.059946) (xy 315.318251 -297.087902) (xy 315.353744 -297.121994)
			(xy 315.383309 -297.161338) (xy 315.40618 -297.204915) (xy 315.421764 -297.251596) (xy 315.429659 -297.300173)
			(xy 315.430154 -297.32478) (xy 315.429659 -297.349387) (xy 315.421764 -297.397964) (xy 315.40618 -297.444645)
			(xy 315.383309 -297.488222) (xy 315.353744 -297.527566) (xy 315.318251 -297.561658) (xy 315.277748 -297.589614)
			(xy 315.233286 -297.610712) (xy 315.186015 -297.624404) (xy 315.13716 -297.630336) (xy 315.087985 -297.628355)
			(xy 315.039766 -297.618511) (xy 314.99375 -297.601059) (xy 314.951129 -297.576452) (xy 314.913008 -297.545327)
			(xy 314.880373 -297.50849) (xy 314.85407 -297.466894) (xy 314.834779 -297.421618) (xy 314.823002 -297.373834)
			(xy 314.819042 -297.32478) (xy 314.480194 -297.32478) (xy 314.479699 -297.349387) (xy 314.471804 -297.397964)
			(xy 314.45622 -297.444645) (xy 314.433349 -297.488222) (xy 314.403784 -297.527566) (xy 314.368291 -297.561658)
			(xy 314.327788 -297.589614) (xy 314.283326 -297.610712) (xy 314.236055 -297.624404) (xy 314.1872 -297.630336)
			(xy 314.138025 -297.628355) (xy 314.089806 -297.618511) (xy 314.04379 -297.601059) (xy 314.001169 -297.576452)
			(xy 313.963048 -297.545327) (xy 313.930413 -297.50849) (xy 313.90411 -297.466894) (xy 313.884819 -297.421618)
			(xy 313.873042 -297.373834) (xy 313.869082 -297.32478) (xy 313.530234 -297.32478) (xy 313.529739 -297.349387)
			(xy 313.521844 -297.397964) (xy 313.50626 -297.444645) (xy 313.483389 -297.488222) (xy 313.453824 -297.527566)
			(xy 313.418331 -297.561658) (xy 313.377828 -297.589614) (xy 313.333366 -297.610712) (xy 313.286095 -297.624404)
			(xy 313.23724 -297.630336) (xy 313.188065 -297.628355) (xy 313.139846 -297.618511) (xy 313.09383 -297.601059)
			(xy 313.051209 -297.576452) (xy 313.013088 -297.545327) (xy 312.980453 -297.50849) (xy 312.95415 -297.466894)
			(xy 312.934859 -297.421618) (xy 312.923082 -297.373834) (xy 312.919122 -297.32478) (xy 312.58002 -297.32478)
			(xy 312.579525 -297.349387) (xy 312.57163 -297.397964) (xy 312.556046 -297.444645) (xy 312.533175 -297.488222)
			(xy 312.50361 -297.527566) (xy 312.468117 -297.561658) (xy 312.427614 -297.589614) (xy 312.383152 -297.610712)
			(xy 312.335881 -297.624404) (xy 312.287026 -297.630336) (xy 312.237851 -297.628355) (xy 312.189632 -297.618511)
			(xy 312.143616 -297.601059) (xy 312.100995 -297.576452) (xy 312.062874 -297.545327) (xy 312.030239 -297.50849)
			(xy 312.003936 -297.466894) (xy 311.984645 -297.421618) (xy 311.972868 -297.373834) (xy 311.968908 -297.32478)
			(xy 311.63006 -297.32478) (xy 311.629565 -297.349387) (xy 311.62167 -297.397964) (xy 311.606086 -297.444645)
			(xy 311.583215 -297.488222) (xy 311.55365 -297.527566) (xy 311.518157 -297.561658) (xy 311.477654 -297.589614)
			(xy 311.433192 -297.610712) (xy 311.385921 -297.624404) (xy 311.337066 -297.630336) (xy 311.287891 -297.628355)
			(xy 311.239672 -297.618511) (xy 311.193656 -297.601059) (xy 311.151035 -297.576452) (xy 311.112914 -297.545327)
			(xy 311.080279 -297.50849) (xy 311.053976 -297.466894) (xy 311.034685 -297.421618) (xy 311.022908 -297.373834)
			(xy 311.018948 -297.32478) (xy 310.6801 -297.32478) (xy 310.679605 -297.349387) (xy 310.67171 -297.397964)
			(xy 310.656126 -297.444645) (xy 310.633255 -297.488222) (xy 310.60369 -297.527566) (xy 310.568197 -297.561658)
			(xy 310.527694 -297.589614) (xy 310.483232 -297.610712) (xy 310.435961 -297.624404) (xy 310.387106 -297.630336)
			(xy 310.337931 -297.628355) (xy 310.289712 -297.618511) (xy 310.243696 -297.601059) (xy 310.201075 -297.576452)
			(xy 310.162954 -297.545327) (xy 310.130319 -297.50849) (xy 310.104016 -297.466894) (xy 310.084725 -297.421618)
			(xy 310.072948 -297.373834) (xy 310.068988 -297.32478) (xy 309.73014 -297.32478) (xy 309.729645 -297.349387)
			(xy 309.72175 -297.397964) (xy 309.706166 -297.444645) (xy 309.683295 -297.488222) (xy 309.65373 -297.527566)
			(xy 309.618237 -297.561658) (xy 309.577734 -297.589614) (xy 309.533272 -297.610712) (xy 309.486001 -297.624404)
			(xy 309.437146 -297.630336) (xy 309.387971 -297.628355) (xy 309.339752 -297.618511) (xy 309.293736 -297.601059)
			(xy 309.251115 -297.576452) (xy 309.212994 -297.545327) (xy 309.180359 -297.50849) (xy 309.154056 -297.466894)
			(xy 309.134765 -297.421618) (xy 309.122988 -297.373834) (xy 309.119028 -297.32478) (xy 308.78018 -297.32478)
			(xy 308.779685 -297.349387) (xy 308.77179 -297.397964) (xy 308.756206 -297.444645) (xy 308.733335 -297.488222)
			(xy 308.70377 -297.527566) (xy 308.668277 -297.561658) (xy 308.627774 -297.589614) (xy 308.583312 -297.610712)
			(xy 308.536041 -297.624404) (xy 308.487186 -297.630336) (xy 308.438011 -297.628355) (xy 308.389792 -297.618511)
			(xy 308.343776 -297.601059) (xy 308.301155 -297.576452) (xy 308.263034 -297.545327) (xy 308.230399 -297.50849)
			(xy 308.204096 -297.466894) (xy 308.184805 -297.421618) (xy 308.173028 -297.373834) (xy 308.169068 -297.32478)
			(xy 307.83022 -297.32478) (xy 307.829725 -297.349387) (xy 307.82183 -297.397964) (xy 307.806246 -297.444645)
			(xy 307.783375 -297.488222) (xy 307.75381 -297.527566) (xy 307.718317 -297.561658) (xy 307.677814 -297.589614)
			(xy 307.633352 -297.610712) (xy 307.586081 -297.624404) (xy 307.537226 -297.630336) (xy 307.488051 -297.628355)
			(xy 307.439832 -297.618511) (xy 307.393816 -297.601059) (xy 307.351195 -297.576452) (xy 307.313074 -297.545327)
			(xy 307.280439 -297.50849) (xy 307.254136 -297.466894) (xy 307.234845 -297.421618) (xy 307.223068 -297.373834)
			(xy 307.219108 -297.32478) (xy 306.88026 -297.32478) (xy 306.879765 -297.349387) (xy 306.87187 -297.397964)
			(xy 306.856286 -297.444645) (xy 306.833415 -297.488222) (xy 306.80385 -297.527566) (xy 306.768357 -297.561658)
			(xy 306.727854 -297.589614) (xy 306.683392 -297.610712) (xy 306.636121 -297.624404) (xy 306.587266 -297.630336)
			(xy 306.538091 -297.628355) (xy 306.489872 -297.618511) (xy 306.443856 -297.601059) (xy 306.401235 -297.576452)
			(xy 306.363114 -297.545327) (xy 306.330479 -297.50849) (xy 306.304176 -297.466894) (xy 306.284885 -297.421618)
			(xy 306.273108 -297.373834) (xy 306.269148 -297.32478) (xy 305.930046 -297.32478) (xy 305.929551 -297.349387)
			(xy 305.921656 -297.397964) (xy 305.906072 -297.444645) (xy 305.883201 -297.488222) (xy 305.853636 -297.527566)
			(xy 305.818143 -297.561658) (xy 305.77764 -297.589614) (xy 305.733178 -297.610712) (xy 305.685907 -297.624404)
			(xy 305.637052 -297.630336) (xy 305.587877 -297.628355) (xy 305.539658 -297.618511) (xy 305.493642 -297.601059)
			(xy 305.451021 -297.576452) (xy 305.4129 -297.545327) (xy 305.380265 -297.50849) (xy 305.353962 -297.466894)
			(xy 305.334671 -297.421618) (xy 305.322894 -297.373834) (xy 305.318934 -297.32478) (xy 304.030126 -297.32478)
			(xy 304.029631 -297.349387) (xy 304.021736 -297.397964) (xy 304.006152 -297.444645) (xy 303.983281 -297.488222)
			(xy 303.953716 -297.527566) (xy 303.918223 -297.561658) (xy 303.87772 -297.589614) (xy 303.833258 -297.610712)
			(xy 303.785987 -297.624404) (xy 303.737132 -297.630336) (xy 303.687957 -297.628355) (xy 303.639738 -297.618511)
			(xy 303.593722 -297.601059) (xy 303.551101 -297.576452) (xy 303.51298 -297.545327) (xy 303.480345 -297.50849)
			(xy 303.454042 -297.466894) (xy 303.434751 -297.421618) (xy 303.422974 -297.373834) (xy 303.419014 -297.32478)
			(xy 303.080166 -297.32478) (xy 303.079671 -297.349387) (xy 303.071776 -297.397964) (xy 303.056192 -297.444645)
			(xy 303.033321 -297.488222) (xy 303.003756 -297.527566) (xy 302.968263 -297.561658) (xy 302.92776 -297.589614)
			(xy 302.883298 -297.610712) (xy 302.836027 -297.624404) (xy 302.787172 -297.630336) (xy 302.737997 -297.628355)
			(xy 302.689778 -297.618511) (xy 302.643762 -297.601059) (xy 302.601141 -297.576452) (xy 302.56302 -297.545327)
			(xy 302.530385 -297.50849) (xy 302.504082 -297.466894) (xy 302.484791 -297.421618) (xy 302.473014 -297.373834)
			(xy 302.469054 -297.32478) (xy 302.130206 -297.32478) (xy 302.129711 -297.349387) (xy 302.121816 -297.397964)
			(xy 302.106232 -297.444645) (xy 302.083361 -297.488222) (xy 302.053796 -297.527566) (xy 302.018303 -297.561658)
			(xy 301.9778 -297.589614) (xy 301.933338 -297.610712) (xy 301.886067 -297.624404) (xy 301.837212 -297.630336)
			(xy 301.788037 -297.628355) (xy 301.739818 -297.618511) (xy 301.693802 -297.601059) (xy 301.651181 -297.576452)
			(xy 301.61306 -297.545327) (xy 301.580425 -297.50849) (xy 301.554122 -297.466894) (xy 301.534831 -297.421618)
			(xy 301.523054 -297.373834) (xy 301.519094 -297.32478) (xy 301.179992 -297.32478) (xy 301.179497 -297.349387)
			(xy 301.171602 -297.397964) (xy 301.156018 -297.444645) (xy 301.133147 -297.488222) (xy 301.103582 -297.527566)
			(xy 301.068089 -297.561658) (xy 301.027586 -297.589614) (xy 300.983124 -297.610712) (xy 300.935853 -297.624404)
			(xy 300.886998 -297.630336) (xy 300.837823 -297.628355) (xy 300.789604 -297.618511) (xy 300.743588 -297.601059)
			(xy 300.700967 -297.576452) (xy 300.662846 -297.545327) (xy 300.630211 -297.50849) (xy 300.603908 -297.466894)
			(xy 300.584617 -297.421618) (xy 300.57284 -297.373834) (xy 300.56888 -297.32478) (xy 300.230032 -297.32478)
			(xy 300.229537 -297.349387) (xy 300.221642 -297.397964) (xy 300.206058 -297.444645) (xy 300.183187 -297.488222)
			(xy 300.153622 -297.527566) (xy 300.118129 -297.561658) (xy 300.077626 -297.589614) (xy 300.033164 -297.610712)
			(xy 299.985893 -297.624404) (xy 299.937038 -297.630336) (xy 299.887863 -297.628355) (xy 299.839644 -297.618511)
			(xy 299.793628 -297.601059) (xy 299.751007 -297.576452) (xy 299.712886 -297.545327) (xy 299.680251 -297.50849)
			(xy 299.653948 -297.466894) (xy 299.634657 -297.421618) (xy 299.62288 -297.373834) (xy 299.61892 -297.32478)
			(xy 299.280072 -297.32478) (xy 299.279577 -297.349387) (xy 299.271682 -297.397964) (xy 299.256098 -297.444645)
			(xy 299.233227 -297.488222) (xy 299.203662 -297.527566) (xy 299.168169 -297.561658) (xy 299.127666 -297.589614)
			(xy 299.083204 -297.610712) (xy 299.035933 -297.624404) (xy 298.987078 -297.630336) (xy 298.937903 -297.628355)
			(xy 298.889684 -297.618511) (xy 298.843668 -297.601059) (xy 298.801047 -297.576452) (xy 298.762926 -297.545327)
			(xy 298.730291 -297.50849) (xy 298.703988 -297.466894) (xy 298.684697 -297.421618) (xy 298.67292 -297.373834)
			(xy 298.66896 -297.32478) (xy 298.330112 -297.32478) (xy 298.329617 -297.349387) (xy 298.321722 -297.397964)
			(xy 298.306138 -297.444645) (xy 298.283267 -297.488222) (xy 298.253702 -297.527566) (xy 298.218209 -297.561658)
			(xy 298.177706 -297.589614) (xy 298.133244 -297.610712) (xy 298.085973 -297.624404) (xy 298.037118 -297.630336)
			(xy 297.987943 -297.628355) (xy 297.939724 -297.618511) (xy 297.893708 -297.601059) (xy 297.851087 -297.576452)
			(xy 297.812966 -297.545327) (xy 297.780331 -297.50849) (xy 297.754028 -297.466894) (xy 297.734737 -297.421618)
			(xy 297.72296 -297.373834) (xy 297.719 -297.32478) (xy 297.380152 -297.32478) (xy 297.379657 -297.349387)
			(xy 297.371762 -297.397964) (xy 297.356178 -297.444645) (xy 297.333307 -297.488222) (xy 297.303742 -297.527566)
			(xy 297.268249 -297.561658) (xy 297.227746 -297.589614) (xy 297.183284 -297.610712) (xy 297.136013 -297.624404)
			(xy 297.087158 -297.630336) (xy 297.037983 -297.628355) (xy 296.989764 -297.618511) (xy 296.943748 -297.601059)
			(xy 296.901127 -297.576452) (xy 296.863006 -297.545327) (xy 296.830371 -297.50849) (xy 296.804068 -297.466894)
			(xy 296.784777 -297.421618) (xy 296.773 -297.373834) (xy 296.76904 -297.32478) (xy 296.430192 -297.32478)
			(xy 296.429697 -297.349387) (xy 296.421802 -297.397964) (xy 296.406218 -297.444645) (xy 296.383347 -297.488222)
			(xy 296.353782 -297.527566) (xy 296.318289 -297.561658) (xy 296.277786 -297.589614) (xy 296.233324 -297.610712)
			(xy 296.186053 -297.624404) (xy 296.137198 -297.630336) (xy 296.088023 -297.628355) (xy 296.039804 -297.618511)
			(xy 295.993788 -297.601059) (xy 295.951167 -297.576452) (xy 295.913046 -297.545327) (xy 295.880411 -297.50849)
			(xy 295.854108 -297.466894) (xy 295.834817 -297.421618) (xy 295.82304 -297.373834) (xy 295.81908 -297.32478)
			(xy 295.480232 -297.32478) (xy 295.479737 -297.349387) (xy 295.471842 -297.397964) (xy 295.456258 -297.444645)
			(xy 295.433387 -297.488222) (xy 295.403822 -297.527566) (xy 295.368329 -297.561658) (xy 295.327826 -297.589614)
			(xy 295.283364 -297.610712) (xy 295.236093 -297.624404) (xy 295.187238 -297.630336) (xy 295.138063 -297.628355)
			(xy 295.089844 -297.618511) (xy 295.043828 -297.601059) (xy 295.001207 -297.576452) (xy 294.963086 -297.545327)
			(xy 294.930451 -297.50849) (xy 294.904148 -297.466894) (xy 294.884857 -297.421618) (xy 294.87308 -297.373834)
			(xy 294.86912 -297.32478) (xy 294.530018 -297.32478) (xy 294.529523 -297.349387) (xy 294.521628 -297.397964)
			(xy 294.506044 -297.444645) (xy 294.483173 -297.488222) (xy 294.453608 -297.527566) (xy 294.418115 -297.561658)
			(xy 294.377612 -297.589614) (xy 294.33315 -297.610712) (xy 294.285879 -297.624404) (xy 294.237024 -297.630336)
			(xy 294.187849 -297.628355) (xy 294.13963 -297.618511) (xy 294.093614 -297.601059) (xy 294.050993 -297.576452)
			(xy 294.012872 -297.545327) (xy 293.980237 -297.50849) (xy 293.953934 -297.466894) (xy 293.934643 -297.421618)
			(xy 293.922866 -297.373834) (xy 293.918906 -297.32478) (xy 293.580058 -297.32478) (xy 293.579563 -297.349387)
			(xy 293.571668 -297.397964) (xy 293.556084 -297.444645) (xy 293.533213 -297.488222) (xy 293.503648 -297.527566)
			(xy 293.468155 -297.561658) (xy 293.427652 -297.589614) (xy 293.38319 -297.610712) (xy 293.335919 -297.624404)
			(xy 293.287064 -297.630336) (xy 293.237889 -297.628355) (xy 293.18967 -297.618511) (xy 293.143654 -297.601059)
			(xy 293.101033 -297.576452) (xy 293.062912 -297.545327) (xy 293.030277 -297.50849) (xy 293.003974 -297.466894)
			(xy 292.984683 -297.421618) (xy 292.972906 -297.373834) (xy 292.968946 -297.32478) (xy 292.630615 -297.32478)
			(xy 292.630616 -297.324796) (xy 292.62657 -297.374378) (xy 292.61454 -297.422647) (xy 292.594842 -297.468328)
			(xy 292.568 -297.510211) (xy 292.534722 -297.547187) (xy 292.495889 -297.578279) (xy 292.452529 -297.602664)
			(xy 292.40579 -297.619696) (xy 292.381432 -297.624754) (xy 292.38067 -297.625008) (xy 292.372018 -297.626964)
			(xy 292.356705 -297.635889) (xy 292.345363 -297.649508) (xy 292.339356 -297.666183) (xy 292.339014 -297.675046)
			(xy 292.339014 -297.924474) (xy 292.339641 -297.936315) (xy 292.350224 -297.957503) (xy 292.369138 -297.971757)
			(xy 292.38067 -297.974512) (xy 292.381432 -297.974766) (xy 292.405778 -297.979861) (xy 292.452508 -297.996891)
			(xy 292.495859 -298.021272) (xy 292.534684 -298.052358) (xy 292.567955 -298.089328) (xy 292.594792 -298.131203)
			(xy 292.614485 -298.176875) (xy 292.626513 -298.225135) (xy 292.630557 -298.274707) (xy 292.630554 -298.27474)
			(xy 292.968946 -298.27474) (xy 292.972906 -298.225686) (xy 292.984683 -298.177902) (xy 293.003974 -298.132626)
			(xy 293.030277 -298.09103) (xy 293.062912 -298.054193) (xy 293.101033 -298.023068) (xy 293.143654 -297.998461)
			(xy 293.18967 -297.981009) (xy 293.237889 -297.971165) (xy 293.287064 -297.969184) (xy 293.335919 -297.975116)
			(xy 293.38319 -297.988808) (xy 293.427652 -298.009906) (xy 293.468155 -298.037862) (xy 293.503648 -298.071954)
			(xy 293.533213 -298.111298) (xy 293.556084 -298.154875) (xy 293.571668 -298.201556) (xy 293.579563 -298.250133)
			(xy 293.580058 -298.27474) (xy 293.918906 -298.27474) (xy 293.922866 -298.225686) (xy 293.934643 -298.177902)
			(xy 293.953934 -298.132626) (xy 293.980237 -298.09103) (xy 294.012872 -298.054193) (xy 294.050993 -298.023068)
			(xy 294.093614 -297.998461) (xy 294.13963 -297.981009) (xy 294.187849 -297.971165) (xy 294.237024 -297.969184)
			(xy 294.285879 -297.975116) (xy 294.33315 -297.988808) (xy 294.377612 -298.009906) (xy 294.418115 -298.037862)
			(xy 294.453608 -298.071954) (xy 294.483173 -298.111298) (xy 294.506044 -298.154875) (xy 294.521628 -298.201556)
			(xy 294.529523 -298.250133) (xy 294.530018 -298.27474) (xy 294.86912 -298.27474) (xy 294.87308 -298.225686)
			(xy 294.884857 -298.177902) (xy 294.904148 -298.132626) (xy 294.930451 -298.09103) (xy 294.963086 -298.054193)
			(xy 295.001207 -298.023068) (xy 295.043828 -297.998461) (xy 295.089844 -297.981009) (xy 295.138063 -297.971165)
			(xy 295.187238 -297.969184) (xy 295.236093 -297.975116) (xy 295.283364 -297.988808) (xy 295.327826 -298.009906)
			(xy 295.368329 -298.037862) (xy 295.403822 -298.071954) (xy 295.433387 -298.111298) (xy 295.456258 -298.154875)
			(xy 295.471842 -298.201556) (xy 295.479737 -298.250133) (xy 295.480232 -298.27474) (xy 295.81908 -298.27474)
			(xy 295.82304 -298.225686) (xy 295.834817 -298.177902) (xy 295.854108 -298.132626) (xy 295.880411 -298.09103)
			(xy 295.913046 -298.054193) (xy 295.951167 -298.023068) (xy 295.993788 -297.998461) (xy 296.039804 -297.981009)
			(xy 296.088023 -297.971165) (xy 296.137198 -297.969184) (xy 296.186053 -297.975116) (xy 296.233324 -297.988808)
			(xy 296.277786 -298.009906) (xy 296.318289 -298.037862) (xy 296.353782 -298.071954) (xy 296.383347 -298.111298)
			(xy 296.406218 -298.154875) (xy 296.421802 -298.201556) (xy 296.429697 -298.250133) (xy 296.430192 -298.27474)
			(xy 296.76904 -298.27474) (xy 296.773 -298.225686) (xy 296.784777 -298.177902) (xy 296.804068 -298.132626)
			(xy 296.830371 -298.09103) (xy 296.863006 -298.054193) (xy 296.901127 -298.023068) (xy 296.943748 -297.998461)
			(xy 296.989764 -297.981009) (xy 297.037983 -297.971165) (xy 297.087158 -297.969184) (xy 297.136013 -297.975116)
			(xy 297.183284 -297.988808) (xy 297.227746 -298.009906) (xy 297.268249 -298.037862) (xy 297.303742 -298.071954)
			(xy 297.333307 -298.111298) (xy 297.356178 -298.154875) (xy 297.371762 -298.201556) (xy 297.379657 -298.250133)
			(xy 297.380152 -298.27474) (xy 297.719 -298.27474) (xy 297.72296 -298.225686) (xy 297.734737 -298.177902)
			(xy 297.754028 -298.132626) (xy 297.780331 -298.09103) (xy 297.812966 -298.054193) (xy 297.851087 -298.023068)
			(xy 297.893708 -297.998461) (xy 297.939724 -297.981009) (xy 297.987943 -297.971165) (xy 298.037118 -297.969184)
			(xy 298.085973 -297.975116) (xy 298.133244 -297.988808) (xy 298.177706 -298.009906) (xy 298.218209 -298.037862)
			(xy 298.253702 -298.071954) (xy 298.283267 -298.111298) (xy 298.306138 -298.154875) (xy 298.321722 -298.201556)
			(xy 298.329617 -298.250133) (xy 298.330112 -298.27474) (xy 298.66896 -298.27474) (xy 298.67292 -298.225686)
			(xy 298.684697 -298.177902) (xy 298.703988 -298.132626) (xy 298.730291 -298.09103) (xy 298.762926 -298.054193)
			(xy 298.801047 -298.023068) (xy 298.843668 -297.998461) (xy 298.889684 -297.981009) (xy 298.937903 -297.971165)
			(xy 298.987078 -297.969184) (xy 299.035933 -297.975116) (xy 299.083204 -297.988808) (xy 299.127666 -298.009906)
			(xy 299.168169 -298.037862) (xy 299.203662 -298.071954) (xy 299.233227 -298.111298) (xy 299.256098 -298.154875)
			(xy 299.271682 -298.201556) (xy 299.279577 -298.250133) (xy 299.280072 -298.27474) (xy 299.61892 -298.27474)
			(xy 299.62288 -298.225686) (xy 299.634657 -298.177902) (xy 299.653948 -298.132626) (xy 299.680251 -298.09103)
			(xy 299.712886 -298.054193) (xy 299.751007 -298.023068) (xy 299.793628 -297.998461) (xy 299.839644 -297.981009)
			(xy 299.887863 -297.971165) (xy 299.937038 -297.969184) (xy 299.985893 -297.975116) (xy 300.033164 -297.988808)
			(xy 300.077626 -298.009906) (xy 300.118129 -298.037862) (xy 300.153622 -298.071954) (xy 300.183187 -298.111298)
			(xy 300.206058 -298.154875) (xy 300.221642 -298.201556) (xy 300.229537 -298.250133) (xy 300.230032 -298.27474)
			(xy 300.56888 -298.27474) (xy 300.57284 -298.225686) (xy 300.584617 -298.177902) (xy 300.603908 -298.132626)
			(xy 300.630211 -298.09103) (xy 300.662846 -298.054193) (xy 300.700967 -298.023068) (xy 300.743588 -297.998461)
			(xy 300.789604 -297.981009) (xy 300.837823 -297.971165) (xy 300.886998 -297.969184) (xy 300.935853 -297.975116)
			(xy 300.983124 -297.988808) (xy 301.027586 -298.009906) (xy 301.068089 -298.037862) (xy 301.103582 -298.071954)
			(xy 301.133147 -298.111298) (xy 301.156018 -298.154875) (xy 301.171602 -298.201556) (xy 301.179497 -298.250133)
			(xy 301.179992 -298.27474) (xy 301.519094 -298.27474) (xy 301.523054 -298.225686) (xy 301.534831 -298.177902)
			(xy 301.554122 -298.132626) (xy 301.580425 -298.09103) (xy 301.61306 -298.054193) (xy 301.651181 -298.023068)
			(xy 301.693802 -297.998461) (xy 301.739818 -297.981009) (xy 301.788037 -297.971165) (xy 301.837212 -297.969184)
			(xy 301.886067 -297.975116) (xy 301.933338 -297.988808) (xy 301.9778 -298.009906) (xy 302.018303 -298.037862)
			(xy 302.053796 -298.071954) (xy 302.083361 -298.111298) (xy 302.106232 -298.154875) (xy 302.121816 -298.201556)
			(xy 302.129711 -298.250133) (xy 302.130206 -298.27474) (xy 302.469054 -298.27474) (xy 302.473014 -298.225686)
			(xy 302.484791 -298.177902) (xy 302.504082 -298.132626) (xy 302.530385 -298.09103) (xy 302.56302 -298.054193)
			(xy 302.601141 -298.023068) (xy 302.643762 -297.998461) (xy 302.689778 -297.981009) (xy 302.737997 -297.971165)
			(xy 302.787172 -297.969184) (xy 302.836027 -297.975116) (xy 302.883298 -297.988808) (xy 302.92776 -298.009906)
			(xy 302.968263 -298.037862) (xy 303.003756 -298.071954) (xy 303.033321 -298.111298) (xy 303.056192 -298.154875)
			(xy 303.071776 -298.201556) (xy 303.079671 -298.250133) (xy 303.080166 -298.27474) (xy 303.419014 -298.27474)
			(xy 303.422974 -298.225686) (xy 303.434751 -298.177902) (xy 303.454042 -298.132626) (xy 303.480345 -298.09103)
			(xy 303.51298 -298.054193) (xy 303.551101 -298.023068) (xy 303.593722 -297.998461) (xy 303.639738 -297.981009)
			(xy 303.687957 -297.971165) (xy 303.737132 -297.969184) (xy 303.785987 -297.975116) (xy 303.833258 -297.988808)
			(xy 303.87772 -298.009906) (xy 303.918223 -298.037862) (xy 303.953716 -298.071954) (xy 303.983281 -298.111298)
			(xy 304.006152 -298.154875) (xy 304.021736 -298.201556) (xy 304.029631 -298.250133) (xy 304.030126 -298.27474)
			(xy 305.318934 -298.27474) (xy 305.322894 -298.225686) (xy 305.334671 -298.177902) (xy 305.353962 -298.132626)
			(xy 305.380265 -298.09103) (xy 305.4129 -298.054193) (xy 305.451021 -298.023068) (xy 305.493642 -297.998461)
			(xy 305.539658 -297.981009) (xy 305.587877 -297.971165) (xy 305.637052 -297.969184) (xy 305.685907 -297.975116)
			(xy 305.733178 -297.988808) (xy 305.77764 -298.009906) (xy 305.818143 -298.037862) (xy 305.853636 -298.071954)
			(xy 305.883201 -298.111298) (xy 305.906072 -298.154875) (xy 305.921656 -298.201556) (xy 305.929551 -298.250133)
			(xy 305.930046 -298.27474) (xy 306.268894 -298.27474) (xy 306.272854 -298.225686) (xy 306.284631 -298.177902)
			(xy 306.303922 -298.132626) (xy 306.330225 -298.09103) (xy 306.36286 -298.054193) (xy 306.400981 -298.023068)
			(xy 306.443602 -297.998461) (xy 306.489618 -297.981009) (xy 306.537837 -297.971165) (xy 306.587012 -297.969184)
			(xy 306.635867 -297.975116) (xy 306.683138 -297.988808) (xy 306.7276 -298.009906) (xy 306.768103 -298.037862)
			(xy 306.803596 -298.071954) (xy 306.833161 -298.111298) (xy 306.856032 -298.154875) (xy 306.871616 -298.201556)
			(xy 306.879511 -298.250133) (xy 306.880006 -298.27474) (xy 307.219108 -298.27474) (xy 307.223068 -298.225686)
			(xy 307.234845 -298.177902) (xy 307.254136 -298.132626) (xy 307.280439 -298.09103) (xy 307.313074 -298.054193)
			(xy 307.351195 -298.023068) (xy 307.393816 -297.998461) (xy 307.439832 -297.981009) (xy 307.488051 -297.971165)
			(xy 307.537226 -297.969184) (xy 307.586081 -297.975116) (xy 307.633352 -297.988808) (xy 307.677814 -298.009906)
			(xy 307.718317 -298.037862) (xy 307.75381 -298.071954) (xy 307.783375 -298.111298) (xy 307.806246 -298.154875)
			(xy 307.82183 -298.201556) (xy 307.829725 -298.250133) (xy 307.83022 -298.27474) (xy 308.169068 -298.27474)
			(xy 308.173028 -298.225686) (xy 308.184805 -298.177902) (xy 308.204096 -298.132626) (xy 308.230399 -298.09103)
			(xy 308.263034 -298.054193) (xy 308.301155 -298.023068) (xy 308.343776 -297.998461) (xy 308.389792 -297.981009)
			(xy 308.438011 -297.971165) (xy 308.487186 -297.969184) (xy 308.536041 -297.975116) (xy 308.583312 -297.988808)
			(xy 308.627774 -298.009906) (xy 308.668277 -298.037862) (xy 308.70377 -298.071954) (xy 308.733335 -298.111298)
			(xy 308.756206 -298.154875) (xy 308.77179 -298.201556) (xy 308.779685 -298.250133) (xy 308.78018 -298.27474)
			(xy 309.119028 -298.27474) (xy 309.122988 -298.225686) (xy 309.134765 -298.177902) (xy 309.154056 -298.132626)
			(xy 309.180359 -298.09103) (xy 309.212994 -298.054193) (xy 309.251115 -298.023068) (xy 309.293736 -297.998461)
			(xy 309.339752 -297.981009) (xy 309.387971 -297.971165) (xy 309.437146 -297.969184) (xy 309.486001 -297.975116)
			(xy 309.533272 -297.988808) (xy 309.577734 -298.009906) (xy 309.618237 -298.037862) (xy 309.65373 -298.071954)
			(xy 309.683295 -298.111298) (xy 309.706166 -298.154875) (xy 309.72175 -298.201556) (xy 309.729645 -298.250133)
			(xy 309.73014 -298.27474) (xy 310.068988 -298.27474) (xy 310.072948 -298.225686) (xy 310.084725 -298.177902)
			(xy 310.104016 -298.132626) (xy 310.130319 -298.09103) (xy 310.162954 -298.054193) (xy 310.201075 -298.023068)
			(xy 310.243696 -297.998461) (xy 310.289712 -297.981009) (xy 310.337931 -297.971165) (xy 310.387106 -297.969184)
			(xy 310.435961 -297.975116) (xy 310.483232 -297.988808) (xy 310.527694 -298.009906) (xy 310.568197 -298.037862)
			(xy 310.60369 -298.071954) (xy 310.633255 -298.111298) (xy 310.656126 -298.154875) (xy 310.67171 -298.201556)
			(xy 310.679605 -298.250133) (xy 310.6801 -298.27474) (xy 311.018948 -298.27474) (xy 311.022908 -298.225686)
			(xy 311.034685 -298.177902) (xy 311.053976 -298.132626) (xy 311.080279 -298.09103) (xy 311.112914 -298.054193)
			(xy 311.151035 -298.023068) (xy 311.193656 -297.998461) (xy 311.239672 -297.981009) (xy 311.287891 -297.971165)
			(xy 311.337066 -297.969184) (xy 311.385921 -297.975116) (xy 311.433192 -297.988808) (xy 311.477654 -298.009906)
			(xy 311.518157 -298.037862) (xy 311.55365 -298.071954) (xy 311.583215 -298.111298) (xy 311.606086 -298.154875)
			(xy 311.62167 -298.201556) (xy 311.629565 -298.250133) (xy 311.63006 -298.27474) (xy 311.968908 -298.27474)
			(xy 311.972868 -298.225686) (xy 311.984645 -298.177902) (xy 312.003936 -298.132626) (xy 312.030239 -298.09103)
			(xy 312.062874 -298.054193) (xy 312.100995 -298.023068) (xy 312.143616 -297.998461) (xy 312.189632 -297.981009)
			(xy 312.237851 -297.971165) (xy 312.287026 -297.969184) (xy 312.335881 -297.975116) (xy 312.383152 -297.988808)
			(xy 312.427614 -298.009906) (xy 312.468117 -298.037862) (xy 312.50361 -298.071954) (xy 312.533175 -298.111298)
			(xy 312.556046 -298.154875) (xy 312.57163 -298.201556) (xy 312.579525 -298.250133) (xy 312.58002 -298.27474)
			(xy 312.919122 -298.27474) (xy 312.923082 -298.225686) (xy 312.934859 -298.177902) (xy 312.95415 -298.132626)
			(xy 312.980453 -298.09103) (xy 313.013088 -298.054193) (xy 313.051209 -298.023068) (xy 313.09383 -297.998461)
			(xy 313.139846 -297.981009) (xy 313.188065 -297.971165) (xy 313.23724 -297.969184) (xy 313.286095 -297.975116)
			(xy 313.333366 -297.988808) (xy 313.377828 -298.009906) (xy 313.418331 -298.037862) (xy 313.453824 -298.071954)
			(xy 313.483389 -298.111298) (xy 313.50626 -298.154875) (xy 313.521844 -298.201556) (xy 313.529739 -298.250133)
			(xy 313.530234 -298.27474) (xy 313.869082 -298.27474) (xy 313.873042 -298.225686) (xy 313.884819 -298.177902)
			(xy 313.90411 -298.132626) (xy 313.930413 -298.09103) (xy 313.963048 -298.054193) (xy 314.001169 -298.023068)
			(xy 314.04379 -297.998461) (xy 314.089806 -297.981009) (xy 314.138025 -297.971165) (xy 314.1872 -297.969184)
			(xy 314.236055 -297.975116) (xy 314.283326 -297.988808) (xy 314.327788 -298.009906) (xy 314.368291 -298.037862)
			(xy 314.403784 -298.071954) (xy 314.433349 -298.111298) (xy 314.45622 -298.154875) (xy 314.471804 -298.201556)
			(xy 314.479699 -298.250133) (xy 314.480194 -298.27474) (xy 314.819042 -298.27474) (xy 314.823002 -298.225686)
			(xy 314.834779 -298.177902) (xy 314.85407 -298.132626) (xy 314.880373 -298.09103) (xy 314.913008 -298.054193)
			(xy 314.951129 -298.023068) (xy 314.99375 -297.998461) (xy 315.039766 -297.981009) (xy 315.087985 -297.971165)
			(xy 315.13716 -297.969184) (xy 315.186015 -297.975116) (xy 315.233286 -297.988808) (xy 315.277748 -298.009906)
			(xy 315.318251 -298.037862) (xy 315.353744 -298.071954) (xy 315.383309 -298.111298) (xy 315.40618 -298.154875)
			(xy 315.421764 -298.201556) (xy 315.429659 -298.250133) (xy 315.430154 -298.27474) (xy 315.429659 -298.299347)
			(xy 315.421764 -298.347924) (xy 315.40618 -298.394605) (xy 315.383309 -298.438182) (xy 315.353744 -298.477526)
			(xy 315.318251 -298.511618) (xy 315.277748 -298.539574) (xy 315.233286 -298.560672) (xy 315.186015 -298.574364)
			(xy 315.13716 -298.580296) (xy 315.087985 -298.578315) (xy 315.039766 -298.568471) (xy 314.99375 -298.551019)
			(xy 314.951129 -298.526412) (xy 314.913008 -298.495287) (xy 314.880373 -298.45845) (xy 314.85407 -298.416854)
			(xy 314.834779 -298.371578) (xy 314.823002 -298.323794) (xy 314.819042 -298.27474) (xy 314.480194 -298.27474)
			(xy 314.479699 -298.299347) (xy 314.471804 -298.347924) (xy 314.45622 -298.394605) (xy 314.433349 -298.438182)
			(xy 314.403784 -298.477526) (xy 314.368291 -298.511618) (xy 314.327788 -298.539574) (xy 314.283326 -298.560672)
			(xy 314.236055 -298.574364) (xy 314.1872 -298.580296) (xy 314.138025 -298.578315) (xy 314.089806 -298.568471)
			(xy 314.04379 -298.551019) (xy 314.001169 -298.526412) (xy 313.963048 -298.495287) (xy 313.930413 -298.45845)
			(xy 313.90411 -298.416854) (xy 313.884819 -298.371578) (xy 313.873042 -298.323794) (xy 313.869082 -298.27474)
			(xy 313.530234 -298.27474) (xy 313.529739 -298.299347) (xy 313.521844 -298.347924) (xy 313.50626 -298.394605)
			(xy 313.483389 -298.438182) (xy 313.453824 -298.477526) (xy 313.418331 -298.511618) (xy 313.377828 -298.539574)
			(xy 313.333366 -298.560672) (xy 313.286095 -298.574364) (xy 313.23724 -298.580296) (xy 313.188065 -298.578315)
			(xy 313.139846 -298.568471) (xy 313.09383 -298.551019) (xy 313.051209 -298.526412) (xy 313.013088 -298.495287)
			(xy 312.980453 -298.45845) (xy 312.95415 -298.416854) (xy 312.934859 -298.371578) (xy 312.923082 -298.323794)
			(xy 312.919122 -298.27474) (xy 312.58002 -298.27474) (xy 312.579525 -298.299347) (xy 312.57163 -298.347924)
			(xy 312.556046 -298.394605) (xy 312.533175 -298.438182) (xy 312.50361 -298.477526) (xy 312.468117 -298.511618)
			(xy 312.427614 -298.539574) (xy 312.383152 -298.560672) (xy 312.335881 -298.574364) (xy 312.287026 -298.580296)
			(xy 312.237851 -298.578315) (xy 312.189632 -298.568471) (xy 312.143616 -298.551019) (xy 312.100995 -298.526412)
			(xy 312.062874 -298.495287) (xy 312.030239 -298.45845) (xy 312.003936 -298.416854) (xy 311.984645 -298.371578)
			(xy 311.972868 -298.323794) (xy 311.968908 -298.27474) (xy 311.63006 -298.27474) (xy 311.629565 -298.299347)
			(xy 311.62167 -298.347924) (xy 311.606086 -298.394605) (xy 311.583215 -298.438182) (xy 311.55365 -298.477526)
			(xy 311.518157 -298.511618) (xy 311.477654 -298.539574) (xy 311.433192 -298.560672) (xy 311.385921 -298.574364)
			(xy 311.337066 -298.580296) (xy 311.287891 -298.578315) (xy 311.239672 -298.568471) (xy 311.193656 -298.551019)
			(xy 311.151035 -298.526412) (xy 311.112914 -298.495287) (xy 311.080279 -298.45845) (xy 311.053976 -298.416854)
			(xy 311.034685 -298.371578) (xy 311.022908 -298.323794) (xy 311.018948 -298.27474) (xy 310.6801 -298.27474)
			(xy 310.679605 -298.299347) (xy 310.67171 -298.347924) (xy 310.656126 -298.394605) (xy 310.633255 -298.438182)
			(xy 310.60369 -298.477526) (xy 310.568197 -298.511618) (xy 310.527694 -298.539574) (xy 310.483232 -298.560672)
			(xy 310.435961 -298.574364) (xy 310.387106 -298.580296) (xy 310.337931 -298.578315) (xy 310.289712 -298.568471)
			(xy 310.243696 -298.551019) (xy 310.201075 -298.526412) (xy 310.162954 -298.495287) (xy 310.130319 -298.45845)
			(xy 310.104016 -298.416854) (xy 310.084725 -298.371578) (xy 310.072948 -298.323794) (xy 310.068988 -298.27474)
			(xy 309.73014 -298.27474) (xy 309.729645 -298.299347) (xy 309.72175 -298.347924) (xy 309.706166 -298.394605)
			(xy 309.683295 -298.438182) (xy 309.65373 -298.477526) (xy 309.618237 -298.511618) (xy 309.577734 -298.539574)
			(xy 309.533272 -298.560672) (xy 309.486001 -298.574364) (xy 309.437146 -298.580296) (xy 309.387971 -298.578315)
			(xy 309.339752 -298.568471) (xy 309.293736 -298.551019) (xy 309.251115 -298.526412) (xy 309.212994 -298.495287)
			(xy 309.180359 -298.45845) (xy 309.154056 -298.416854) (xy 309.134765 -298.371578) (xy 309.122988 -298.323794)
			(xy 309.119028 -298.27474) (xy 308.78018 -298.27474) (xy 308.779685 -298.299347) (xy 308.77179 -298.347924)
			(xy 308.756206 -298.394605) (xy 308.733335 -298.438182) (xy 308.70377 -298.477526) (xy 308.668277 -298.511618)
			(xy 308.627774 -298.539574) (xy 308.583312 -298.560672) (xy 308.536041 -298.574364) (xy 308.487186 -298.580296)
			(xy 308.438011 -298.578315) (xy 308.389792 -298.568471) (xy 308.343776 -298.551019) (xy 308.301155 -298.526412)
			(xy 308.263034 -298.495287) (xy 308.230399 -298.45845) (xy 308.204096 -298.416854) (xy 308.184805 -298.371578)
			(xy 308.173028 -298.323794) (xy 308.169068 -298.27474) (xy 307.83022 -298.27474) (xy 307.829725 -298.299347)
			(xy 307.82183 -298.347924) (xy 307.806246 -298.394605) (xy 307.783375 -298.438182) (xy 307.75381 -298.477526)
			(xy 307.718317 -298.511618) (xy 307.677814 -298.539574) (xy 307.633352 -298.560672) (xy 307.586081 -298.574364)
			(xy 307.537226 -298.580296) (xy 307.488051 -298.578315) (xy 307.439832 -298.568471) (xy 307.393816 -298.551019)
			(xy 307.351195 -298.526412) (xy 307.313074 -298.495287) (xy 307.280439 -298.45845) (xy 307.254136 -298.416854)
			(xy 307.234845 -298.371578) (xy 307.223068 -298.323794) (xy 307.219108 -298.27474) (xy 306.880006 -298.27474)
			(xy 306.879511 -298.299347) (xy 306.871616 -298.347924) (xy 306.856032 -298.394605) (xy 306.833161 -298.438182)
			(xy 306.803596 -298.477526) (xy 306.768103 -298.511618) (xy 306.7276 -298.539574) (xy 306.683138 -298.560672)
			(xy 306.635867 -298.574364) (xy 306.587012 -298.580296) (xy 306.537837 -298.578315) (xy 306.489618 -298.568471)
			(xy 306.443602 -298.551019) (xy 306.400981 -298.526412) (xy 306.36286 -298.495287) (xy 306.330225 -298.45845)
			(xy 306.303922 -298.416854) (xy 306.284631 -298.371578) (xy 306.272854 -298.323794) (xy 306.268894 -298.27474)
			(xy 305.930046 -298.27474) (xy 305.929551 -298.299347) (xy 305.921656 -298.347924) (xy 305.906072 -298.394605)
			(xy 305.883201 -298.438182) (xy 305.853636 -298.477526) (xy 305.818143 -298.511618) (xy 305.77764 -298.539574)
			(xy 305.733178 -298.560672) (xy 305.685907 -298.574364) (xy 305.637052 -298.580296) (xy 305.587877 -298.578315)
			(xy 305.539658 -298.568471) (xy 305.493642 -298.551019) (xy 305.451021 -298.526412) (xy 305.4129 -298.495287)
			(xy 305.380265 -298.45845) (xy 305.353962 -298.416854) (xy 305.334671 -298.371578) (xy 305.322894 -298.323794)
			(xy 305.318934 -298.27474) (xy 304.030126 -298.27474) (xy 304.029631 -298.299347) (xy 304.021736 -298.347924)
			(xy 304.006152 -298.394605) (xy 303.983281 -298.438182) (xy 303.953716 -298.477526) (xy 303.918223 -298.511618)
			(xy 303.87772 -298.539574) (xy 303.833258 -298.560672) (xy 303.785987 -298.574364) (xy 303.737132 -298.580296)
			(xy 303.687957 -298.578315) (xy 303.639738 -298.568471) (xy 303.593722 -298.551019) (xy 303.551101 -298.526412)
			(xy 303.51298 -298.495287) (xy 303.480345 -298.45845) (xy 303.454042 -298.416854) (xy 303.434751 -298.371578)
			(xy 303.422974 -298.323794) (xy 303.419014 -298.27474) (xy 303.080166 -298.27474) (xy 303.079671 -298.299347)
			(xy 303.071776 -298.347924) (xy 303.056192 -298.394605) (xy 303.033321 -298.438182) (xy 303.003756 -298.477526)
			(xy 302.968263 -298.511618) (xy 302.92776 -298.539574) (xy 302.883298 -298.560672) (xy 302.836027 -298.574364)
			(xy 302.787172 -298.580296) (xy 302.737997 -298.578315) (xy 302.689778 -298.568471) (xy 302.643762 -298.551019)
			(xy 302.601141 -298.526412) (xy 302.56302 -298.495287) (xy 302.530385 -298.45845) (xy 302.504082 -298.416854)
			(xy 302.484791 -298.371578) (xy 302.473014 -298.323794) (xy 302.469054 -298.27474) (xy 302.130206 -298.27474)
			(xy 302.129711 -298.299347) (xy 302.121816 -298.347924) (xy 302.106232 -298.394605) (xy 302.083361 -298.438182)
			(xy 302.053796 -298.477526) (xy 302.018303 -298.511618) (xy 301.9778 -298.539574) (xy 301.933338 -298.560672)
			(xy 301.886067 -298.574364) (xy 301.837212 -298.580296) (xy 301.788037 -298.578315) (xy 301.739818 -298.568471)
			(xy 301.693802 -298.551019) (xy 301.651181 -298.526412) (xy 301.61306 -298.495287) (xy 301.580425 -298.45845)
			(xy 301.554122 -298.416854) (xy 301.534831 -298.371578) (xy 301.523054 -298.323794) (xy 301.519094 -298.27474)
			(xy 301.179992 -298.27474) (xy 301.179497 -298.299347) (xy 301.171602 -298.347924) (xy 301.156018 -298.394605)
			(xy 301.133147 -298.438182) (xy 301.103582 -298.477526) (xy 301.068089 -298.511618) (xy 301.027586 -298.539574)
			(xy 300.983124 -298.560672) (xy 300.935853 -298.574364) (xy 300.886998 -298.580296) (xy 300.837823 -298.578315)
			(xy 300.789604 -298.568471) (xy 300.743588 -298.551019) (xy 300.700967 -298.526412) (xy 300.662846 -298.495287)
			(xy 300.630211 -298.45845) (xy 300.603908 -298.416854) (xy 300.584617 -298.371578) (xy 300.57284 -298.323794)
			(xy 300.56888 -298.27474) (xy 300.230032 -298.27474) (xy 300.229537 -298.299347) (xy 300.221642 -298.347924)
			(xy 300.206058 -298.394605) (xy 300.183187 -298.438182) (xy 300.153622 -298.477526) (xy 300.118129 -298.511618)
			(xy 300.077626 -298.539574) (xy 300.033164 -298.560672) (xy 299.985893 -298.574364) (xy 299.937038 -298.580296)
			(xy 299.887863 -298.578315) (xy 299.839644 -298.568471) (xy 299.793628 -298.551019) (xy 299.751007 -298.526412)
			(xy 299.712886 -298.495287) (xy 299.680251 -298.45845) (xy 299.653948 -298.416854) (xy 299.634657 -298.371578)
			(xy 299.62288 -298.323794) (xy 299.61892 -298.27474) (xy 299.280072 -298.27474) (xy 299.279577 -298.299347)
			(xy 299.271682 -298.347924) (xy 299.256098 -298.394605) (xy 299.233227 -298.438182) (xy 299.203662 -298.477526)
			(xy 299.168169 -298.511618) (xy 299.127666 -298.539574) (xy 299.083204 -298.560672) (xy 299.035933 -298.574364)
			(xy 298.987078 -298.580296) (xy 298.937903 -298.578315) (xy 298.889684 -298.568471) (xy 298.843668 -298.551019)
			(xy 298.801047 -298.526412) (xy 298.762926 -298.495287) (xy 298.730291 -298.45845) (xy 298.703988 -298.416854)
			(xy 298.684697 -298.371578) (xy 298.67292 -298.323794) (xy 298.66896 -298.27474) (xy 298.330112 -298.27474)
			(xy 298.329617 -298.299347) (xy 298.321722 -298.347924) (xy 298.306138 -298.394605) (xy 298.283267 -298.438182)
			(xy 298.253702 -298.477526) (xy 298.218209 -298.511618) (xy 298.177706 -298.539574) (xy 298.133244 -298.560672)
			(xy 298.085973 -298.574364) (xy 298.037118 -298.580296) (xy 297.987943 -298.578315) (xy 297.939724 -298.568471)
			(xy 297.893708 -298.551019) (xy 297.851087 -298.526412) (xy 297.812966 -298.495287) (xy 297.780331 -298.45845)
			(xy 297.754028 -298.416854) (xy 297.734737 -298.371578) (xy 297.72296 -298.323794) (xy 297.719 -298.27474)
			(xy 297.380152 -298.27474) (xy 297.379657 -298.299347) (xy 297.371762 -298.347924) (xy 297.356178 -298.394605)
			(xy 297.333307 -298.438182) (xy 297.303742 -298.477526) (xy 297.268249 -298.511618) (xy 297.227746 -298.539574)
			(xy 297.183284 -298.560672) (xy 297.136013 -298.574364) (xy 297.087158 -298.580296) (xy 297.037983 -298.578315)
			(xy 296.989764 -298.568471) (xy 296.943748 -298.551019) (xy 296.901127 -298.526412) (xy 296.863006 -298.495287)
			(xy 296.830371 -298.45845) (xy 296.804068 -298.416854) (xy 296.784777 -298.371578) (xy 296.773 -298.323794)
			(xy 296.76904 -298.27474) (xy 296.430192 -298.27474) (xy 296.429697 -298.299347) (xy 296.421802 -298.347924)
			(xy 296.406218 -298.394605) (xy 296.383347 -298.438182) (xy 296.353782 -298.477526) (xy 296.318289 -298.511618)
			(xy 296.277786 -298.539574) (xy 296.233324 -298.560672) (xy 296.186053 -298.574364) (xy 296.137198 -298.580296)
			(xy 296.088023 -298.578315) (xy 296.039804 -298.568471) (xy 295.993788 -298.551019) (xy 295.951167 -298.526412)
			(xy 295.913046 -298.495287) (xy 295.880411 -298.45845) (xy 295.854108 -298.416854) (xy 295.834817 -298.371578)
			(xy 295.82304 -298.323794) (xy 295.81908 -298.27474) (xy 295.480232 -298.27474) (xy 295.479737 -298.299347)
			(xy 295.471842 -298.347924) (xy 295.456258 -298.394605) (xy 295.433387 -298.438182) (xy 295.403822 -298.477526)
			(xy 295.368329 -298.511618) (xy 295.327826 -298.539574) (xy 295.283364 -298.560672) (xy 295.236093 -298.574364)
			(xy 295.187238 -298.580296) (xy 295.138063 -298.578315) (xy 295.089844 -298.568471) (xy 295.043828 -298.551019)
			(xy 295.001207 -298.526412) (xy 294.963086 -298.495287) (xy 294.930451 -298.45845) (xy 294.904148 -298.416854)
			(xy 294.884857 -298.371578) (xy 294.87308 -298.323794) (xy 294.86912 -298.27474) (xy 294.530018 -298.27474)
			(xy 294.529523 -298.299347) (xy 294.521628 -298.347924) (xy 294.506044 -298.394605) (xy 294.483173 -298.438182)
			(xy 294.453608 -298.477526) (xy 294.418115 -298.511618) (xy 294.377612 -298.539574) (xy 294.33315 -298.560672)
			(xy 294.285879 -298.574364) (xy 294.237024 -298.580296) (xy 294.187849 -298.578315) (xy 294.13963 -298.568471)
			(xy 294.093614 -298.551019) (xy 294.050993 -298.526412) (xy 294.012872 -298.495287) (xy 293.980237 -298.45845)
			(xy 293.953934 -298.416854) (xy 293.934643 -298.371578) (xy 293.922866 -298.323794) (xy 293.918906 -298.27474)
			(xy 293.580058 -298.27474) (xy 293.579563 -298.299347) (xy 293.571668 -298.347924) (xy 293.556084 -298.394605)
			(xy 293.533213 -298.438182) (xy 293.503648 -298.477526) (xy 293.468155 -298.511618) (xy 293.427652 -298.539574)
			(xy 293.38319 -298.560672) (xy 293.335919 -298.574364) (xy 293.287064 -298.580296) (xy 293.237889 -298.578315)
			(xy 293.18967 -298.568471) (xy 293.143654 -298.551019) (xy 293.101033 -298.526412) (xy 293.062912 -298.495287)
			(xy 293.030277 -298.45845) (xy 293.003974 -298.416854) (xy 292.984683 -298.371578) (xy 292.972906 -298.323794)
			(xy 292.968946 -298.27474) (xy 292.630554 -298.27474) (xy 292.62651 -298.324279) (xy 292.61448 -298.372539)
			(xy 292.594785 -298.41821) (xy 292.567946 -298.460084) (xy 292.534673 -298.497052) (xy 292.495847 -298.528137)
			(xy 292.452495 -298.552515) (xy 292.405763 -298.569542) (xy 292.381432 -298.574714) (xy 292.38067 -298.574968)
			(xy 292.372015 -298.576922) (xy 292.356694 -298.585845) (xy 292.345342 -298.599464) (xy 292.339322 -298.616141)
			(xy 292.339014 -298.625006) (xy 292.339014 -298.874688) (xy 292.339644 -298.886527) (xy 292.350229 -298.907709)
			(xy 292.369142 -298.921959) (xy 292.38067 -298.924726) (xy 292.381432 -298.92498) (xy 292.405785 -298.930076)
			(xy 292.452529 -298.947108) (xy 292.495893 -298.971493) (xy 292.53473 -299.002586) (xy 292.568013 -299.039564)
			(xy 292.594859 -299.081449) (xy 292.61456 -299.127133) (xy 292.626593 -299.175406) (xy 292.630638 -299.224954)
			(xy 292.968946 -299.224954) (xy 292.972906 -299.1759) (xy 292.984683 -299.128116) (xy 293.003974 -299.08284)
			(xy 293.030277 -299.041244) (xy 293.062912 -299.004407) (xy 293.101033 -298.973282) (xy 293.143654 -298.948675)
			(xy 293.18967 -298.931223) (xy 293.237889 -298.921379) (xy 293.287064 -298.919398) (xy 293.335919 -298.92533)
			(xy 293.38319 -298.939022) (xy 293.427652 -298.96012) (xy 293.468155 -298.988076) (xy 293.503648 -299.022168)
			(xy 293.533213 -299.061512) (xy 293.556084 -299.105089) (xy 293.571668 -299.15177) (xy 293.579563 -299.200347)
			(xy 293.580058 -299.224954) (xy 293.918906 -299.224954) (xy 293.922866 -299.1759) (xy 293.934643 -299.128116)
			(xy 293.953934 -299.08284) (xy 293.980237 -299.041244) (xy 294.012872 -299.004407) (xy 294.050993 -298.973282)
			(xy 294.093614 -298.948675) (xy 294.13963 -298.931223) (xy 294.187849 -298.921379) (xy 294.237024 -298.919398)
			(xy 294.285879 -298.92533) (xy 294.33315 -298.939022) (xy 294.377612 -298.96012) (xy 294.418115 -298.988076)
			(xy 294.453608 -299.022168) (xy 294.483173 -299.061512) (xy 294.506044 -299.105089) (xy 294.521628 -299.15177)
			(xy 294.529523 -299.200347) (xy 294.530018 -299.224954) (xy 294.86912 -299.224954) (xy 294.87308 -299.1759)
			(xy 294.884857 -299.128116) (xy 294.904148 -299.08284) (xy 294.930451 -299.041244) (xy 294.963086 -299.004407)
			(xy 295.001207 -298.973282) (xy 295.043828 -298.948675) (xy 295.089844 -298.931223) (xy 295.138063 -298.921379)
			(xy 295.187238 -298.919398) (xy 295.236093 -298.92533) (xy 295.283364 -298.939022) (xy 295.327826 -298.96012)
			(xy 295.368329 -298.988076) (xy 295.403822 -299.022168) (xy 295.433387 -299.061512) (xy 295.456258 -299.105089)
			(xy 295.471842 -299.15177) (xy 295.479737 -299.200347) (xy 295.480232 -299.224954) (xy 295.81908 -299.224954)
			(xy 295.82304 -299.1759) (xy 295.834817 -299.128116) (xy 295.854108 -299.08284) (xy 295.880411 -299.041244)
			(xy 295.913046 -299.004407) (xy 295.951167 -298.973282) (xy 295.993788 -298.948675) (xy 296.039804 -298.931223)
			(xy 296.088023 -298.921379) (xy 296.137198 -298.919398) (xy 296.186053 -298.92533) (xy 296.233324 -298.939022)
			(xy 296.277786 -298.96012) (xy 296.318289 -298.988076) (xy 296.353782 -299.022168) (xy 296.383347 -299.061512)
			(xy 296.406218 -299.105089) (xy 296.421802 -299.15177) (xy 296.429697 -299.200347) (xy 296.430192 -299.224954)
			(xy 296.76904 -299.224954) (xy 296.773 -299.1759) (xy 296.784777 -299.128116) (xy 296.804068 -299.08284)
			(xy 296.830371 -299.041244) (xy 296.863006 -299.004407) (xy 296.901127 -298.973282) (xy 296.943748 -298.948675)
			(xy 296.989764 -298.931223) (xy 297.037983 -298.921379) (xy 297.087158 -298.919398) (xy 297.136013 -298.92533)
			(xy 297.183284 -298.939022) (xy 297.227746 -298.96012) (xy 297.268249 -298.988076) (xy 297.303742 -299.022168)
			(xy 297.333307 -299.061512) (xy 297.356178 -299.105089) (xy 297.371762 -299.15177) (xy 297.379657 -299.200347)
			(xy 297.380152 -299.224954) (xy 297.719 -299.224954) (xy 297.72296 -299.1759) (xy 297.734737 -299.128116)
			(xy 297.754028 -299.08284) (xy 297.780331 -299.041244) (xy 297.812966 -299.004407) (xy 297.851087 -298.973282)
			(xy 297.893708 -298.948675) (xy 297.939724 -298.931223) (xy 297.987943 -298.921379) (xy 298.037118 -298.919398)
			(xy 298.085973 -298.92533) (xy 298.133244 -298.939022) (xy 298.177706 -298.96012) (xy 298.218209 -298.988076)
			(xy 298.253702 -299.022168) (xy 298.283267 -299.061512) (xy 298.306138 -299.105089) (xy 298.321722 -299.15177)
			(xy 298.329617 -299.200347) (xy 298.330112 -299.224954) (xy 298.66896 -299.224954) (xy 298.67292 -299.1759)
			(xy 298.684697 -299.128116) (xy 298.703988 -299.08284) (xy 298.730291 -299.041244) (xy 298.762926 -299.004407)
			(xy 298.801047 -298.973282) (xy 298.843668 -298.948675) (xy 298.889684 -298.931223) (xy 298.937903 -298.921379)
			(xy 298.987078 -298.919398) (xy 299.035933 -298.92533) (xy 299.083204 -298.939022) (xy 299.127666 -298.96012)
			(xy 299.168169 -298.988076) (xy 299.203662 -299.022168) (xy 299.233227 -299.061512) (xy 299.256098 -299.105089)
			(xy 299.271682 -299.15177) (xy 299.279577 -299.200347) (xy 299.280072 -299.224954) (xy 299.61892 -299.224954)
			(xy 299.62288 -299.1759) (xy 299.634657 -299.128116) (xy 299.653948 -299.08284) (xy 299.680251 -299.041244)
			(xy 299.712886 -299.004407) (xy 299.751007 -298.973282) (xy 299.793628 -298.948675) (xy 299.839644 -298.931223)
			(xy 299.887863 -298.921379) (xy 299.937038 -298.919398) (xy 299.985893 -298.92533) (xy 300.033164 -298.939022)
			(xy 300.077626 -298.96012) (xy 300.118129 -298.988076) (xy 300.153622 -299.022168) (xy 300.183187 -299.061512)
			(xy 300.206058 -299.105089) (xy 300.221642 -299.15177) (xy 300.229537 -299.200347) (xy 300.230032 -299.224954)
			(xy 300.56888 -299.224954) (xy 300.57284 -299.1759) (xy 300.584617 -299.128116) (xy 300.603908 -299.08284)
			(xy 300.630211 -299.041244) (xy 300.662846 -299.004407) (xy 300.700967 -298.973282) (xy 300.743588 -298.948675)
			(xy 300.789604 -298.931223) (xy 300.837823 -298.921379) (xy 300.886998 -298.919398) (xy 300.935853 -298.92533)
			(xy 300.983124 -298.939022) (xy 301.027586 -298.96012) (xy 301.068089 -298.988076) (xy 301.103582 -299.022168)
			(xy 301.133147 -299.061512) (xy 301.156018 -299.105089) (xy 301.171602 -299.15177) (xy 301.179497 -299.200347)
			(xy 301.179992 -299.224954) (xy 301.519094 -299.224954) (xy 301.523054 -299.1759) (xy 301.534831 -299.128116)
			(xy 301.554122 -299.08284) (xy 301.580425 -299.041244) (xy 301.61306 -299.004407) (xy 301.651181 -298.973282)
			(xy 301.693802 -298.948675) (xy 301.739818 -298.931223) (xy 301.788037 -298.921379) (xy 301.837212 -298.919398)
			(xy 301.886067 -298.92533) (xy 301.933338 -298.939022) (xy 301.9778 -298.96012) (xy 302.018303 -298.988076)
			(xy 302.053796 -299.022168) (xy 302.083361 -299.061512) (xy 302.106232 -299.105089) (xy 302.121816 -299.15177)
			(xy 302.129711 -299.200347) (xy 302.130206 -299.224954) (xy 302.469054 -299.224954) (xy 302.473014 -299.1759)
			(xy 302.484791 -299.128116) (xy 302.504082 -299.08284) (xy 302.530385 -299.041244) (xy 302.56302 -299.004407)
			(xy 302.601141 -298.973282) (xy 302.643762 -298.948675) (xy 302.689778 -298.931223) (xy 302.737997 -298.921379)
			(xy 302.787172 -298.919398) (xy 302.836027 -298.92533) (xy 302.883298 -298.939022) (xy 302.92776 -298.96012)
			(xy 302.968263 -298.988076) (xy 303.003756 -299.022168) (xy 303.033321 -299.061512) (xy 303.056192 -299.105089)
			(xy 303.071776 -299.15177) (xy 303.079671 -299.200347) (xy 303.080166 -299.224954) (xy 303.419014 -299.224954)
			(xy 303.422974 -299.1759) (xy 303.434751 -299.128116) (xy 303.454042 -299.08284) (xy 303.480345 -299.041244)
			(xy 303.51298 -299.004407) (xy 303.551101 -298.973282) (xy 303.593722 -298.948675) (xy 303.639738 -298.931223)
			(xy 303.687957 -298.921379) (xy 303.737132 -298.919398) (xy 303.785987 -298.92533) (xy 303.833258 -298.939022)
			(xy 303.87772 -298.96012) (xy 303.918223 -298.988076) (xy 303.953716 -299.022168) (xy 303.983281 -299.061512)
			(xy 304.006152 -299.105089) (xy 304.021736 -299.15177) (xy 304.029631 -299.200347) (xy 304.030126 -299.224954)
			(xy 304.368974 -299.224954) (xy 304.372934 -299.1759) (xy 304.384711 -299.128116) (xy 304.404002 -299.08284)
			(xy 304.430305 -299.041244) (xy 304.46294 -299.004407) (xy 304.501061 -298.973282) (xy 304.543682 -298.948675)
			(xy 304.589698 -298.931223) (xy 304.637917 -298.921379) (xy 304.687092 -298.919398) (xy 304.735947 -298.92533)
			(xy 304.783218 -298.939022) (xy 304.82768 -298.96012) (xy 304.868183 -298.988076) (xy 304.903676 -299.022168)
			(xy 304.933241 -299.061512) (xy 304.956112 -299.105089) (xy 304.971696 -299.15177) (xy 304.979591 -299.200347)
			(xy 304.980086 -299.224954) (xy 305.318934 -299.224954) (xy 305.322894 -299.1759) (xy 305.334671 -299.128116)
			(xy 305.353962 -299.08284) (xy 305.380265 -299.041244) (xy 305.4129 -299.004407) (xy 305.451021 -298.973282)
			(xy 305.493642 -298.948675) (xy 305.539658 -298.931223) (xy 305.587877 -298.921379) (xy 305.637052 -298.919398)
			(xy 305.685907 -298.92533) (xy 305.733178 -298.939022) (xy 305.77764 -298.96012) (xy 305.818143 -298.988076)
			(xy 305.853636 -299.022168) (xy 305.883201 -299.061512) (xy 305.906072 -299.105089) (xy 305.921656 -299.15177)
			(xy 305.929551 -299.200347) (xy 305.930046 -299.224954) (xy 308.169068 -299.224954) (xy 308.173028 -299.1759)
			(xy 308.184805 -299.128116) (xy 308.204096 -299.08284) (xy 308.230399 -299.041244) (xy 308.263034 -299.004407)
			(xy 308.301155 -298.973282) (xy 308.343776 -298.948675) (xy 308.389792 -298.931223) (xy 308.438011 -298.921379)
			(xy 308.487186 -298.919398) (xy 308.536041 -298.92533) (xy 308.583312 -298.939022) (xy 308.627774 -298.96012)
			(xy 308.668277 -298.988076) (xy 308.70377 -299.022168) (xy 308.733335 -299.061512) (xy 308.756206 -299.105089)
			(xy 308.77179 -299.15177) (xy 308.779685 -299.200347) (xy 308.78018 -299.224954) (xy 309.119028 -299.224954)
			(xy 309.122988 -299.1759) (xy 309.134765 -299.128116) (xy 309.154056 -299.08284) (xy 309.180359 -299.041244)
			(xy 309.212994 -299.004407) (xy 309.251115 -298.973282) (xy 309.293736 -298.948675) (xy 309.339752 -298.931223)
			(xy 309.387971 -298.921379) (xy 309.437146 -298.919398) (xy 309.486001 -298.92533) (xy 309.533272 -298.939022)
			(xy 309.577734 -298.96012) (xy 309.618237 -298.988076) (xy 309.65373 -299.022168) (xy 309.683295 -299.061512)
			(xy 309.706166 -299.105089) (xy 309.72175 -299.15177) (xy 309.729645 -299.200347) (xy 309.73014 -299.224954)
			(xy 310.068988 -299.224954) (xy 310.072948 -299.1759) (xy 310.084725 -299.128116) (xy 310.104016 -299.08284)
			(xy 310.130319 -299.041244) (xy 310.162954 -299.004407) (xy 310.201075 -298.973282) (xy 310.243696 -298.948675)
			(xy 310.289712 -298.931223) (xy 310.337931 -298.921379) (xy 310.387106 -298.919398) (xy 310.435961 -298.92533)
			(xy 310.483232 -298.939022) (xy 310.527694 -298.96012) (xy 310.568197 -298.988076) (xy 310.60369 -299.022168)
			(xy 310.633255 -299.061512) (xy 310.656126 -299.105089) (xy 310.67171 -299.15177) (xy 310.679605 -299.200347)
			(xy 310.6801 -299.224954) (xy 311.018948 -299.224954) (xy 311.022908 -299.1759) (xy 311.034685 -299.128116)
			(xy 311.053976 -299.08284) (xy 311.080279 -299.041244) (xy 311.112914 -299.004407) (xy 311.151035 -298.973282)
			(xy 311.193656 -298.948675) (xy 311.239672 -298.931223) (xy 311.287891 -298.921379) (xy 311.337066 -298.919398)
			(xy 311.385921 -298.92533) (xy 311.433192 -298.939022) (xy 311.477654 -298.96012) (xy 311.518157 -298.988076)
			(xy 311.55365 -299.022168) (xy 311.583215 -299.061512) (xy 311.606086 -299.105089) (xy 311.62167 -299.15177)
			(xy 311.629565 -299.200347) (xy 311.63006 -299.224954) (xy 311.968908 -299.224954) (xy 311.972868 -299.1759)
			(xy 311.984645 -299.128116) (xy 312.003936 -299.08284) (xy 312.030239 -299.041244) (xy 312.062874 -299.004407)
			(xy 312.100995 -298.973282) (xy 312.143616 -298.948675) (xy 312.189632 -298.931223) (xy 312.237851 -298.921379)
			(xy 312.287026 -298.919398) (xy 312.335881 -298.92533) (xy 312.383152 -298.939022) (xy 312.427614 -298.96012)
			(xy 312.468117 -298.988076) (xy 312.50361 -299.022168) (xy 312.533175 -299.061512) (xy 312.556046 -299.105089)
			(xy 312.57163 -299.15177) (xy 312.579525 -299.200347) (xy 312.58002 -299.224954) (xy 312.919122 -299.224954)
			(xy 312.923082 -299.1759) (xy 312.934859 -299.128116) (xy 312.95415 -299.08284) (xy 312.980453 -299.041244)
			(xy 313.013088 -299.004407) (xy 313.051209 -298.973282) (xy 313.09383 -298.948675) (xy 313.139846 -298.931223)
			(xy 313.188065 -298.921379) (xy 313.23724 -298.919398) (xy 313.286095 -298.92533) (xy 313.333366 -298.939022)
			(xy 313.377828 -298.96012) (xy 313.418331 -298.988076) (xy 313.453824 -299.022168) (xy 313.483389 -299.061512)
			(xy 313.50626 -299.105089) (xy 313.521844 -299.15177) (xy 313.529739 -299.200347) (xy 313.530234 -299.224954)
			(xy 313.869082 -299.224954) (xy 313.873042 -299.1759) (xy 313.884819 -299.128116) (xy 313.90411 -299.08284)
			(xy 313.930413 -299.041244) (xy 313.963048 -299.004407) (xy 314.001169 -298.973282) (xy 314.04379 -298.948675)
			(xy 314.089806 -298.931223) (xy 314.138025 -298.921379) (xy 314.1872 -298.919398) (xy 314.236055 -298.92533)
			(xy 314.283326 -298.939022) (xy 314.327788 -298.96012) (xy 314.368291 -298.988076) (xy 314.403784 -299.022168)
			(xy 314.433349 -299.061512) (xy 314.45622 -299.105089) (xy 314.471804 -299.15177) (xy 314.479699 -299.200347)
			(xy 314.480194 -299.224954) (xy 314.819042 -299.224954) (xy 314.823002 -299.1759) (xy 314.834779 -299.128116)
			(xy 314.85407 -299.08284) (xy 314.880373 -299.041244) (xy 314.913008 -299.004407) (xy 314.951129 -298.973282)
			(xy 314.99375 -298.948675) (xy 315.039766 -298.931223) (xy 315.087985 -298.921379) (xy 315.13716 -298.919398)
			(xy 315.186015 -298.92533) (xy 315.233286 -298.939022) (xy 315.277748 -298.96012) (xy 315.318251 -298.988076)
			(xy 315.353744 -299.022168) (xy 315.383309 -299.061512) (xy 315.40618 -299.105089) (xy 315.421764 -299.15177)
			(xy 315.429659 -299.200347) (xy 315.430154 -299.224954) (xy 315.429659 -299.249561) (xy 315.421764 -299.298138)
			(xy 315.40618 -299.344819) (xy 315.383309 -299.388396) (xy 315.353744 -299.42774) (xy 315.318251 -299.461832)
			(xy 315.277748 -299.489788) (xy 315.233286 -299.510886) (xy 315.186015 -299.524578) (xy 315.13716 -299.53051)
			(xy 315.087985 -299.528529) (xy 315.039766 -299.518685) (xy 314.99375 -299.501233) (xy 314.951129 -299.476626)
			(xy 314.913008 -299.445501) (xy 314.880373 -299.408664) (xy 314.85407 -299.367068) (xy 314.834779 -299.321792)
			(xy 314.823002 -299.274008) (xy 314.819042 -299.224954) (xy 314.480194 -299.224954) (xy 314.479699 -299.249561)
			(xy 314.471804 -299.298138) (xy 314.45622 -299.344819) (xy 314.433349 -299.388396) (xy 314.403784 -299.42774)
			(xy 314.368291 -299.461832) (xy 314.327788 -299.489788) (xy 314.283326 -299.510886) (xy 314.236055 -299.524578)
			(xy 314.1872 -299.53051) (xy 314.138025 -299.528529) (xy 314.089806 -299.518685) (xy 314.04379 -299.501233)
			(xy 314.001169 -299.476626) (xy 313.963048 -299.445501) (xy 313.930413 -299.408664) (xy 313.90411 -299.367068)
			(xy 313.884819 -299.321792) (xy 313.873042 -299.274008) (xy 313.869082 -299.224954) (xy 313.530234 -299.224954)
			(xy 313.529739 -299.249561) (xy 313.521844 -299.298138) (xy 313.50626 -299.344819) (xy 313.483389 -299.388396)
			(xy 313.453824 -299.42774) (xy 313.418331 -299.461832) (xy 313.377828 -299.489788) (xy 313.333366 -299.510886)
			(xy 313.286095 -299.524578) (xy 313.23724 -299.53051) (xy 313.188065 -299.528529) (xy 313.139846 -299.518685)
			(xy 313.09383 -299.501233) (xy 313.051209 -299.476626) (xy 313.013088 -299.445501) (xy 312.980453 -299.408664)
			(xy 312.95415 -299.367068) (xy 312.934859 -299.321792) (xy 312.923082 -299.274008) (xy 312.919122 -299.224954)
			(xy 312.58002 -299.224954) (xy 312.579525 -299.249561) (xy 312.57163 -299.298138) (xy 312.556046 -299.344819)
			(xy 312.533175 -299.388396) (xy 312.50361 -299.42774) (xy 312.468117 -299.461832) (xy 312.427614 -299.489788)
			(xy 312.383152 -299.510886) (xy 312.335881 -299.524578) (xy 312.287026 -299.53051) (xy 312.237851 -299.528529)
			(xy 312.189632 -299.518685) (xy 312.143616 -299.501233) (xy 312.100995 -299.476626) (xy 312.062874 -299.445501)
			(xy 312.030239 -299.408664) (xy 312.003936 -299.367068) (xy 311.984645 -299.321792) (xy 311.972868 -299.274008)
			(xy 311.968908 -299.224954) (xy 311.63006 -299.224954) (xy 311.629565 -299.249561) (xy 311.62167 -299.298138)
			(xy 311.606086 -299.344819) (xy 311.583215 -299.388396) (xy 311.55365 -299.42774) (xy 311.518157 -299.461832)
			(xy 311.477654 -299.489788) (xy 311.433192 -299.510886) (xy 311.385921 -299.524578) (xy 311.337066 -299.53051)
			(xy 311.287891 -299.528529) (xy 311.239672 -299.518685) (xy 311.193656 -299.501233) (xy 311.151035 -299.476626)
			(xy 311.112914 -299.445501) (xy 311.080279 -299.408664) (xy 311.053976 -299.367068) (xy 311.034685 -299.321792)
			(xy 311.022908 -299.274008) (xy 311.018948 -299.224954) (xy 310.6801 -299.224954) (xy 310.679605 -299.249561)
			(xy 310.67171 -299.298138) (xy 310.656126 -299.344819) (xy 310.633255 -299.388396) (xy 310.60369 -299.42774)
			(xy 310.568197 -299.461832) (xy 310.527694 -299.489788) (xy 310.483232 -299.510886) (xy 310.435961 -299.524578)
			(xy 310.387106 -299.53051) (xy 310.337931 -299.528529) (xy 310.289712 -299.518685) (xy 310.243696 -299.501233)
			(xy 310.201075 -299.476626) (xy 310.162954 -299.445501) (xy 310.130319 -299.408664) (xy 310.104016 -299.367068)
			(xy 310.084725 -299.321792) (xy 310.072948 -299.274008) (xy 310.068988 -299.224954) (xy 309.73014 -299.224954)
			(xy 309.729645 -299.249561) (xy 309.72175 -299.298138) (xy 309.706166 -299.344819) (xy 309.683295 -299.388396)
			(xy 309.65373 -299.42774) (xy 309.618237 -299.461832) (xy 309.577734 -299.489788) (xy 309.533272 -299.510886)
			(xy 309.486001 -299.524578) (xy 309.437146 -299.53051) (xy 309.387971 -299.528529) (xy 309.339752 -299.518685)
			(xy 309.293736 -299.501233) (xy 309.251115 -299.476626) (xy 309.212994 -299.445501) (xy 309.180359 -299.408664)
			(xy 309.154056 -299.367068) (xy 309.134765 -299.321792) (xy 309.122988 -299.274008) (xy 309.119028 -299.224954)
			(xy 308.78018 -299.224954) (xy 308.779685 -299.249561) (xy 308.77179 -299.298138) (xy 308.756206 -299.344819)
			(xy 308.733335 -299.388396) (xy 308.70377 -299.42774) (xy 308.668277 -299.461832) (xy 308.627774 -299.489788)
			(xy 308.583312 -299.510886) (xy 308.536041 -299.524578) (xy 308.487186 -299.53051) (xy 308.438011 -299.528529)
			(xy 308.389792 -299.518685) (xy 308.343776 -299.501233) (xy 308.301155 -299.476626) (xy 308.263034 -299.445501)
			(xy 308.230399 -299.408664) (xy 308.204096 -299.367068) (xy 308.184805 -299.321792) (xy 308.173028 -299.274008)
			(xy 308.169068 -299.224954) (xy 305.930046 -299.224954) (xy 305.929551 -299.249561) (xy 305.921656 -299.298138)
			(xy 305.906072 -299.344819) (xy 305.883201 -299.388396) (xy 305.853636 -299.42774) (xy 305.818143 -299.461832)
			(xy 305.77764 -299.489788) (xy 305.733178 -299.510886) (xy 305.685907 -299.524578) (xy 305.637052 -299.53051)
			(xy 305.587877 -299.528529) (xy 305.539658 -299.518685) (xy 305.493642 -299.501233) (xy 305.451021 -299.476626)
			(xy 305.4129 -299.445501) (xy 305.380265 -299.408664) (xy 305.353962 -299.367068) (xy 305.334671 -299.321792)
			(xy 305.322894 -299.274008) (xy 305.318934 -299.224954) (xy 304.980086 -299.224954) (xy 304.979591 -299.249561)
			(xy 304.971696 -299.298138) (xy 304.956112 -299.344819) (xy 304.933241 -299.388396) (xy 304.903676 -299.42774)
			(xy 304.868183 -299.461832) (xy 304.82768 -299.489788) (xy 304.783218 -299.510886) (xy 304.735947 -299.524578)
			(xy 304.687092 -299.53051) (xy 304.637917 -299.528529) (xy 304.589698 -299.518685) (xy 304.543682 -299.501233)
			(xy 304.501061 -299.476626) (xy 304.46294 -299.445501) (xy 304.430305 -299.408664) (xy 304.404002 -299.367068)
			(xy 304.384711 -299.321792) (xy 304.372934 -299.274008) (xy 304.368974 -299.224954) (xy 304.030126 -299.224954)
			(xy 304.029631 -299.249561) (xy 304.021736 -299.298138) (xy 304.006152 -299.344819) (xy 303.983281 -299.388396)
			(xy 303.953716 -299.42774) (xy 303.918223 -299.461832) (xy 303.87772 -299.489788) (xy 303.833258 -299.510886)
			(xy 303.785987 -299.524578) (xy 303.737132 -299.53051) (xy 303.687957 -299.528529) (xy 303.639738 -299.518685)
			(xy 303.593722 -299.501233) (xy 303.551101 -299.476626) (xy 303.51298 -299.445501) (xy 303.480345 -299.408664)
			(xy 303.454042 -299.367068) (xy 303.434751 -299.321792) (xy 303.422974 -299.274008) (xy 303.419014 -299.224954)
			(xy 303.080166 -299.224954) (xy 303.079671 -299.249561) (xy 303.071776 -299.298138) (xy 303.056192 -299.344819)
			(xy 303.033321 -299.388396) (xy 303.003756 -299.42774) (xy 302.968263 -299.461832) (xy 302.92776 -299.489788)
			(xy 302.883298 -299.510886) (xy 302.836027 -299.524578) (xy 302.787172 -299.53051) (xy 302.737997 -299.528529)
			(xy 302.689778 -299.518685) (xy 302.643762 -299.501233) (xy 302.601141 -299.476626) (xy 302.56302 -299.445501)
			(xy 302.530385 -299.408664) (xy 302.504082 -299.367068) (xy 302.484791 -299.321792) (xy 302.473014 -299.274008)
			(xy 302.469054 -299.224954) (xy 302.130206 -299.224954) (xy 302.129711 -299.249561) (xy 302.121816 -299.298138)
			(xy 302.106232 -299.344819) (xy 302.083361 -299.388396) (xy 302.053796 -299.42774) (xy 302.018303 -299.461832)
			(xy 301.9778 -299.489788) (xy 301.933338 -299.510886) (xy 301.886067 -299.524578) (xy 301.837212 -299.53051)
			(xy 301.788037 -299.528529) (xy 301.739818 -299.518685) (xy 301.693802 -299.501233) (xy 301.651181 -299.476626)
			(xy 301.61306 -299.445501) (xy 301.580425 -299.408664) (xy 301.554122 -299.367068) (xy 301.534831 -299.321792)
			(xy 301.523054 -299.274008) (xy 301.519094 -299.224954) (xy 301.179992 -299.224954) (xy 301.179497 -299.249561)
			(xy 301.171602 -299.298138) (xy 301.156018 -299.344819) (xy 301.133147 -299.388396) (xy 301.103582 -299.42774)
			(xy 301.068089 -299.461832) (xy 301.027586 -299.489788) (xy 300.983124 -299.510886) (xy 300.935853 -299.524578)
			(xy 300.886998 -299.53051) (xy 300.837823 -299.528529) (xy 300.789604 -299.518685) (xy 300.743588 -299.501233)
			(xy 300.700967 -299.476626) (xy 300.662846 -299.445501) (xy 300.630211 -299.408664) (xy 300.603908 -299.367068)
			(xy 300.584617 -299.321792) (xy 300.57284 -299.274008) (xy 300.56888 -299.224954) (xy 300.230032 -299.224954)
			(xy 300.229537 -299.249561) (xy 300.221642 -299.298138) (xy 300.206058 -299.344819) (xy 300.183187 -299.388396)
			(xy 300.153622 -299.42774) (xy 300.118129 -299.461832) (xy 300.077626 -299.489788) (xy 300.033164 -299.510886)
			(xy 299.985893 -299.524578) (xy 299.937038 -299.53051) (xy 299.887863 -299.528529) (xy 299.839644 -299.518685)
			(xy 299.793628 -299.501233) (xy 299.751007 -299.476626) (xy 299.712886 -299.445501) (xy 299.680251 -299.408664)
			(xy 299.653948 -299.367068) (xy 299.634657 -299.321792) (xy 299.62288 -299.274008) (xy 299.61892 -299.224954)
			(xy 299.280072 -299.224954) (xy 299.279577 -299.249561) (xy 299.271682 -299.298138) (xy 299.256098 -299.344819)
			(xy 299.233227 -299.388396) (xy 299.203662 -299.42774) (xy 299.168169 -299.461832) (xy 299.127666 -299.489788)
			(xy 299.083204 -299.510886) (xy 299.035933 -299.524578) (xy 298.987078 -299.53051) (xy 298.937903 -299.528529)
			(xy 298.889684 -299.518685) (xy 298.843668 -299.501233) (xy 298.801047 -299.476626) (xy 298.762926 -299.445501)
			(xy 298.730291 -299.408664) (xy 298.703988 -299.367068) (xy 298.684697 -299.321792) (xy 298.67292 -299.274008)
			(xy 298.66896 -299.224954) (xy 298.330112 -299.224954) (xy 298.329617 -299.249561) (xy 298.321722 -299.298138)
			(xy 298.306138 -299.344819) (xy 298.283267 -299.388396) (xy 298.253702 -299.42774) (xy 298.218209 -299.461832)
			(xy 298.177706 -299.489788) (xy 298.133244 -299.510886) (xy 298.085973 -299.524578) (xy 298.037118 -299.53051)
			(xy 297.987943 -299.528529) (xy 297.939724 -299.518685) (xy 297.893708 -299.501233) (xy 297.851087 -299.476626)
			(xy 297.812966 -299.445501) (xy 297.780331 -299.408664) (xy 297.754028 -299.367068) (xy 297.734737 -299.321792)
			(xy 297.72296 -299.274008) (xy 297.719 -299.224954) (xy 297.380152 -299.224954) (xy 297.379657 -299.249561)
			(xy 297.371762 -299.298138) (xy 297.356178 -299.344819) (xy 297.333307 -299.388396) (xy 297.303742 -299.42774)
			(xy 297.268249 -299.461832) (xy 297.227746 -299.489788) (xy 297.183284 -299.510886) (xy 297.136013 -299.524578)
			(xy 297.087158 -299.53051) (xy 297.037983 -299.528529) (xy 296.989764 -299.518685) (xy 296.943748 -299.501233)
			(xy 296.901127 -299.476626) (xy 296.863006 -299.445501) (xy 296.830371 -299.408664) (xy 296.804068 -299.367068)
			(xy 296.784777 -299.321792) (xy 296.773 -299.274008) (xy 296.76904 -299.224954) (xy 296.430192 -299.224954)
			(xy 296.429697 -299.249561) (xy 296.421802 -299.298138) (xy 296.406218 -299.344819) (xy 296.383347 -299.388396)
			(xy 296.353782 -299.42774) (xy 296.318289 -299.461832) (xy 296.277786 -299.489788) (xy 296.233324 -299.510886)
			(xy 296.186053 -299.524578) (xy 296.137198 -299.53051) (xy 296.088023 -299.528529) (xy 296.039804 -299.518685)
			(xy 295.993788 -299.501233) (xy 295.951167 -299.476626) (xy 295.913046 -299.445501) (xy 295.880411 -299.408664)
			(xy 295.854108 -299.367068) (xy 295.834817 -299.321792) (xy 295.82304 -299.274008) (xy 295.81908 -299.224954)
			(xy 295.480232 -299.224954) (xy 295.479737 -299.249561) (xy 295.471842 -299.298138) (xy 295.456258 -299.344819)
			(xy 295.433387 -299.388396) (xy 295.403822 -299.42774) (xy 295.368329 -299.461832) (xy 295.327826 -299.489788)
			(xy 295.283364 -299.510886) (xy 295.236093 -299.524578) (xy 295.187238 -299.53051) (xy 295.138063 -299.528529)
			(xy 295.089844 -299.518685) (xy 295.043828 -299.501233) (xy 295.001207 -299.476626) (xy 294.963086 -299.445501)
			(xy 294.930451 -299.408664) (xy 294.904148 -299.367068) (xy 294.884857 -299.321792) (xy 294.87308 -299.274008)
			(xy 294.86912 -299.224954) (xy 294.530018 -299.224954) (xy 294.529523 -299.249561) (xy 294.521628 -299.298138)
			(xy 294.506044 -299.344819) (xy 294.483173 -299.388396) (xy 294.453608 -299.42774) (xy 294.418115 -299.461832)
			(xy 294.377612 -299.489788) (xy 294.33315 -299.510886) (xy 294.285879 -299.524578) (xy 294.237024 -299.53051)
			(xy 294.187849 -299.528529) (xy 294.13963 -299.518685) (xy 294.093614 -299.501233) (xy 294.050993 -299.476626)
			(xy 294.012872 -299.445501) (xy 293.980237 -299.408664) (xy 293.953934 -299.367068) (xy 293.934643 -299.321792)
			(xy 293.922866 -299.274008) (xy 293.918906 -299.224954) (xy 293.580058 -299.224954) (xy 293.579563 -299.249561)
			(xy 293.571668 -299.298138) (xy 293.556084 -299.344819) (xy 293.533213 -299.388396) (xy 293.503648 -299.42774)
			(xy 293.468155 -299.461832) (xy 293.427652 -299.489788) (xy 293.38319 -299.510886) (xy 293.335919 -299.524578)
			(xy 293.287064 -299.53051) (xy 293.237889 -299.528529) (xy 293.18967 -299.518685) (xy 293.143654 -299.501233)
			(xy 293.101033 -299.476626) (xy 293.062912 -299.445501) (xy 293.030277 -299.408664) (xy 293.003974 -299.367068)
			(xy 292.984683 -299.321792) (xy 292.972906 -299.274008) (xy 292.968946 -299.224954) (xy 292.630638 -299.224954)
			(xy 292.630641 -299.224991) (xy 292.626596 -299.274577) (xy 292.614565 -299.322851) (xy 292.594867 -299.368536)
			(xy 292.568023 -299.410422) (xy 292.534743 -299.447402) (xy 292.495907 -299.478498) (xy 292.452544 -299.502885)
			(xy 292.405801 -299.51992) (xy 292.381432 -299.524928) (xy 292.38067 -299.525182) (xy 292.372016 -299.527137)
			(xy 292.356698 -299.53606) (xy 292.345349 -299.549679) (xy 292.339334 -299.566355) (xy 292.339014 -299.57522)
			(xy 292.339014 -299.824648) (xy 292.339636 -299.836493) (xy 292.350214 -299.857691) (xy 292.36913 -299.871954)
			(xy 292.38067 -299.874686) (xy 292.381432 -299.87494) (xy 292.40578 -299.880036) (xy 292.452514 -299.897066)
			(xy 292.495869 -299.921448) (xy 292.534698 -299.952536) (xy 292.567972 -299.989509) (xy 292.594812 -300.031387)
			(xy 292.614508 -300.077062) (xy 292.626537 -300.125327) (xy 292.630582 -300.174903) (xy 292.630581 -300.174914)
			(xy 292.968946 -300.174914) (xy 292.972906 -300.12586) (xy 292.984683 -300.078076) (xy 293.003974 -300.0328)
			(xy 293.030277 -299.991204) (xy 293.062912 -299.954367) (xy 293.101033 -299.923242) (xy 293.143654 -299.898635)
			(xy 293.18967 -299.881183) (xy 293.237889 -299.871339) (xy 293.287064 -299.869358) (xy 293.335919 -299.87529)
			(xy 293.38319 -299.888982) (xy 293.427652 -299.91008) (xy 293.468155 -299.938036) (xy 293.503648 -299.972128)
			(xy 293.533213 -300.011472) (xy 293.556084 -300.055049) (xy 293.571668 -300.10173) (xy 293.579563 -300.150307)
			(xy 293.580058 -300.174914) (xy 293.918906 -300.174914) (xy 293.922866 -300.12586) (xy 293.934643 -300.078076)
			(xy 293.953934 -300.0328) (xy 293.980237 -299.991204) (xy 294.012872 -299.954367) (xy 294.050993 -299.923242)
			(xy 294.093614 -299.898635) (xy 294.13963 -299.881183) (xy 294.187849 -299.871339) (xy 294.237024 -299.869358)
			(xy 294.285879 -299.87529) (xy 294.33315 -299.888982) (xy 294.377612 -299.91008) (xy 294.418115 -299.938036)
			(xy 294.453608 -299.972128) (xy 294.483173 -300.011472) (xy 294.506044 -300.055049) (xy 294.521628 -300.10173)
			(xy 294.529523 -300.150307) (xy 294.530018 -300.174914) (xy 294.86912 -300.174914) (xy 294.87308 -300.12586)
			(xy 294.884857 -300.078076) (xy 294.904148 -300.0328) (xy 294.930451 -299.991204) (xy 294.963086 -299.954367)
			(xy 295.001207 -299.923242) (xy 295.043828 -299.898635) (xy 295.089844 -299.881183) (xy 295.138063 -299.871339)
			(xy 295.187238 -299.869358) (xy 295.236093 -299.87529) (xy 295.283364 -299.888982) (xy 295.327826 -299.91008)
			(xy 295.368329 -299.938036) (xy 295.403822 -299.972128) (xy 295.433387 -300.011472) (xy 295.456258 -300.055049)
			(xy 295.471842 -300.10173) (xy 295.479737 -300.150307) (xy 295.480232 -300.174914) (xy 295.81908 -300.174914)
			(xy 295.82304 -300.12586) (xy 295.834817 -300.078076) (xy 295.854108 -300.0328) (xy 295.880411 -299.991204)
			(xy 295.913046 -299.954367) (xy 295.951167 -299.923242) (xy 295.993788 -299.898635) (xy 296.039804 -299.881183)
			(xy 296.088023 -299.871339) (xy 296.137198 -299.869358) (xy 296.186053 -299.87529) (xy 296.233324 -299.888982)
			(xy 296.277786 -299.91008) (xy 296.318289 -299.938036) (xy 296.353782 -299.972128) (xy 296.383347 -300.011472)
			(xy 296.406218 -300.055049) (xy 296.421802 -300.10173) (xy 296.429697 -300.150307) (xy 296.430192 -300.174914)
			(xy 296.76904 -300.174914) (xy 296.773 -300.12586) (xy 296.784777 -300.078076) (xy 296.804068 -300.0328)
			(xy 296.830371 -299.991204) (xy 296.863006 -299.954367) (xy 296.901127 -299.923242) (xy 296.943748 -299.898635)
			(xy 296.989764 -299.881183) (xy 297.037983 -299.871339) (xy 297.087158 -299.869358) (xy 297.136013 -299.87529)
			(xy 297.183284 -299.888982) (xy 297.227746 -299.91008) (xy 297.268249 -299.938036) (xy 297.303742 -299.972128)
			(xy 297.333307 -300.011472) (xy 297.356178 -300.055049) (xy 297.371762 -300.10173) (xy 297.379657 -300.150307)
			(xy 297.380152 -300.174914) (xy 297.719 -300.174914) (xy 297.72296 -300.12586) (xy 297.734737 -300.078076)
			(xy 297.754028 -300.0328) (xy 297.780331 -299.991204) (xy 297.812966 -299.954367) (xy 297.851087 -299.923242)
			(xy 297.893708 -299.898635) (xy 297.939724 -299.881183) (xy 297.987943 -299.871339) (xy 298.037118 -299.869358)
			(xy 298.085973 -299.87529) (xy 298.133244 -299.888982) (xy 298.177706 -299.91008) (xy 298.218209 -299.938036)
			(xy 298.253702 -299.972128) (xy 298.283267 -300.011472) (xy 298.306138 -300.055049) (xy 298.321722 -300.10173)
			(xy 298.329617 -300.150307) (xy 298.330112 -300.174914) (xy 298.66896 -300.174914) (xy 298.67292 -300.12586)
			(xy 298.684697 -300.078076) (xy 298.703988 -300.0328) (xy 298.730291 -299.991204) (xy 298.762926 -299.954367)
			(xy 298.801047 -299.923242) (xy 298.843668 -299.898635) (xy 298.889684 -299.881183) (xy 298.937903 -299.871339)
			(xy 298.987078 -299.869358) (xy 299.035933 -299.87529) (xy 299.083204 -299.888982) (xy 299.127666 -299.91008)
			(xy 299.168169 -299.938036) (xy 299.203662 -299.972128) (xy 299.233227 -300.011472) (xy 299.256098 -300.055049)
			(xy 299.271682 -300.10173) (xy 299.279577 -300.150307) (xy 299.280072 -300.174914) (xy 299.61892 -300.174914)
			(xy 299.62288 -300.12586) (xy 299.634657 -300.078076) (xy 299.653948 -300.0328) (xy 299.680251 -299.991204)
			(xy 299.712886 -299.954367) (xy 299.751007 -299.923242) (xy 299.793628 -299.898635) (xy 299.839644 -299.881183)
			(xy 299.887863 -299.871339) (xy 299.937038 -299.869358) (xy 299.985893 -299.87529) (xy 300.033164 -299.888982)
			(xy 300.077626 -299.91008) (xy 300.118129 -299.938036) (xy 300.153622 -299.972128) (xy 300.183187 -300.011472)
			(xy 300.206058 -300.055049) (xy 300.221642 -300.10173) (xy 300.229537 -300.150307) (xy 300.230032 -300.174914)
			(xy 300.56888 -300.174914) (xy 300.57284 -300.12586) (xy 300.584617 -300.078076) (xy 300.603908 -300.0328)
			(xy 300.630211 -299.991204) (xy 300.662846 -299.954367) (xy 300.700967 -299.923242) (xy 300.743588 -299.898635)
			(xy 300.789604 -299.881183) (xy 300.837823 -299.871339) (xy 300.886998 -299.869358) (xy 300.935853 -299.87529)
			(xy 300.983124 -299.888982) (xy 301.027586 -299.91008) (xy 301.068089 -299.938036) (xy 301.103582 -299.972128)
			(xy 301.133147 -300.011472) (xy 301.156018 -300.055049) (xy 301.171602 -300.10173) (xy 301.179497 -300.150307)
			(xy 301.179992 -300.174914) (xy 301.519094 -300.174914) (xy 301.523054 -300.12586) (xy 301.534831 -300.078076)
			(xy 301.554122 -300.0328) (xy 301.580425 -299.991204) (xy 301.61306 -299.954367) (xy 301.651181 -299.923242)
			(xy 301.693802 -299.898635) (xy 301.739818 -299.881183) (xy 301.788037 -299.871339) (xy 301.837212 -299.869358)
			(xy 301.886067 -299.87529) (xy 301.933338 -299.888982) (xy 301.9778 -299.91008) (xy 302.018303 -299.938036)
			(xy 302.053796 -299.972128) (xy 302.083361 -300.011472) (xy 302.106232 -300.055049) (xy 302.121816 -300.10173)
			(xy 302.129711 -300.150307) (xy 302.130206 -300.174914) (xy 302.469054 -300.174914) (xy 302.473014 -300.12586)
			(xy 302.484791 -300.078076) (xy 302.504082 -300.0328) (xy 302.530385 -299.991204) (xy 302.56302 -299.954367)
			(xy 302.601141 -299.923242) (xy 302.643762 -299.898635) (xy 302.689778 -299.881183) (xy 302.737997 -299.871339)
			(xy 302.787172 -299.869358) (xy 302.836027 -299.87529) (xy 302.883298 -299.888982) (xy 302.92776 -299.91008)
			(xy 302.968263 -299.938036) (xy 303.003756 -299.972128) (xy 303.033321 -300.011472) (xy 303.056192 -300.055049)
			(xy 303.071776 -300.10173) (xy 303.079671 -300.150307) (xy 303.080166 -300.174914) (xy 303.419014 -300.174914)
			(xy 303.422974 -300.12586) (xy 303.434751 -300.078076) (xy 303.454042 -300.0328) (xy 303.480345 -299.991204)
			(xy 303.51298 -299.954367) (xy 303.551101 -299.923242) (xy 303.593722 -299.898635) (xy 303.639738 -299.881183)
			(xy 303.687957 -299.871339) (xy 303.737132 -299.869358) (xy 303.785987 -299.87529) (xy 303.833258 -299.888982)
			(xy 303.87772 -299.91008) (xy 303.918223 -299.938036) (xy 303.953716 -299.972128) (xy 303.983281 -300.011472)
			(xy 304.006152 -300.055049) (xy 304.021736 -300.10173) (xy 304.029631 -300.150307) (xy 304.030126 -300.174914)
			(xy 304.368974 -300.174914) (xy 304.372934 -300.12586) (xy 304.384711 -300.078076) (xy 304.404002 -300.0328)
			(xy 304.430305 -299.991204) (xy 304.46294 -299.954367) (xy 304.501061 -299.923242) (xy 304.543682 -299.898635)
			(xy 304.589698 -299.881183) (xy 304.637917 -299.871339) (xy 304.687092 -299.869358) (xy 304.735947 -299.87529)
			(xy 304.783218 -299.888982) (xy 304.82768 -299.91008) (xy 304.868183 -299.938036) (xy 304.903676 -299.972128)
			(xy 304.933241 -300.011472) (xy 304.956112 -300.055049) (xy 304.971696 -300.10173) (xy 304.979591 -300.150307)
			(xy 304.980086 -300.174914) (xy 305.318934 -300.174914) (xy 305.322894 -300.12586) (xy 305.334671 -300.078076)
			(xy 305.353962 -300.0328) (xy 305.380265 -299.991204) (xy 305.4129 -299.954367) (xy 305.451021 -299.923242)
			(xy 305.493642 -299.898635) (xy 305.539658 -299.881183) (xy 305.587877 -299.871339) (xy 305.637052 -299.869358)
			(xy 305.685907 -299.87529) (xy 305.733178 -299.888982) (xy 305.77764 -299.91008) (xy 305.818143 -299.938036)
			(xy 305.853636 -299.972128) (xy 305.883201 -300.011472) (xy 305.906072 -300.055049) (xy 305.921656 -300.10173)
			(xy 305.929551 -300.150307) (xy 305.930046 -300.174914) (xy 306.268894 -300.174914) (xy 306.272854 -300.12586)
			(xy 306.284631 -300.078076) (xy 306.303922 -300.0328) (xy 306.330225 -299.991204) (xy 306.36286 -299.954367)
			(xy 306.400981 -299.923242) (xy 306.443602 -299.898635) (xy 306.489618 -299.881183) (xy 306.537837 -299.871339)
			(xy 306.587012 -299.869358) (xy 306.635867 -299.87529) (xy 306.683138 -299.888982) (xy 306.7276 -299.91008)
			(xy 306.768103 -299.938036) (xy 306.803596 -299.972128) (xy 306.833161 -300.011472) (xy 306.856032 -300.055049)
			(xy 306.871616 -300.10173) (xy 306.879511 -300.150307) (xy 306.880006 -300.174914) (xy 307.219108 -300.174914)
			(xy 307.223068 -300.12586) (xy 307.234845 -300.078076) (xy 307.254136 -300.0328) (xy 307.280439 -299.991204)
			(xy 307.313074 -299.954367) (xy 307.351195 -299.923242) (xy 307.393816 -299.898635) (xy 307.439832 -299.881183)
			(xy 307.488051 -299.871339) (xy 307.537226 -299.869358) (xy 307.586081 -299.87529) (xy 307.633352 -299.888982)
			(xy 307.677814 -299.91008) (xy 307.718317 -299.938036) (xy 307.75381 -299.972128) (xy 307.783375 -300.011472)
			(xy 307.806246 -300.055049) (xy 307.82183 -300.10173) (xy 307.829725 -300.150307) (xy 307.83022 -300.174914)
			(xy 308.169068 -300.174914) (xy 308.173028 -300.12586) (xy 308.184805 -300.078076) (xy 308.204096 -300.0328)
			(xy 308.230399 -299.991204) (xy 308.263034 -299.954367) (xy 308.301155 -299.923242) (xy 308.343776 -299.898635)
			(xy 308.389792 -299.881183) (xy 308.438011 -299.871339) (xy 308.487186 -299.869358) (xy 308.536041 -299.87529)
			(xy 308.583312 -299.888982) (xy 308.627774 -299.91008) (xy 308.668277 -299.938036) (xy 308.70377 -299.972128)
			(xy 308.733335 -300.011472) (xy 308.756206 -300.055049) (xy 308.77179 -300.10173) (xy 308.779685 -300.150307)
			(xy 308.78018 -300.174914) (xy 309.119028 -300.174914) (xy 309.122988 -300.12586) (xy 309.134765 -300.078076)
			(xy 309.154056 -300.0328) (xy 309.180359 -299.991204) (xy 309.212994 -299.954367) (xy 309.251115 -299.923242)
			(xy 309.293736 -299.898635) (xy 309.339752 -299.881183) (xy 309.387971 -299.871339) (xy 309.437146 -299.869358)
			(xy 309.486001 -299.87529) (xy 309.533272 -299.888982) (xy 309.577734 -299.91008) (xy 309.618237 -299.938036)
			(xy 309.65373 -299.972128) (xy 309.683295 -300.011472) (xy 309.706166 -300.055049) (xy 309.72175 -300.10173)
			(xy 309.729645 -300.150307) (xy 309.73014 -300.174914) (xy 310.068988 -300.174914) (xy 310.072948 -300.12586)
			(xy 310.084725 -300.078076) (xy 310.104016 -300.0328) (xy 310.130319 -299.991204) (xy 310.162954 -299.954367)
			(xy 310.201075 -299.923242) (xy 310.243696 -299.898635) (xy 310.289712 -299.881183) (xy 310.337931 -299.871339)
			(xy 310.387106 -299.869358) (xy 310.435961 -299.87529) (xy 310.483232 -299.888982) (xy 310.527694 -299.91008)
			(xy 310.568197 -299.938036) (xy 310.60369 -299.972128) (xy 310.633255 -300.011472) (xy 310.656126 -300.055049)
			(xy 310.67171 -300.10173) (xy 310.679605 -300.150307) (xy 310.6801 -300.174914) (xy 311.018948 -300.174914)
			(xy 311.022908 -300.12586) (xy 311.034685 -300.078076) (xy 311.053976 -300.0328) (xy 311.080279 -299.991204)
			(xy 311.112914 -299.954367) (xy 311.151035 -299.923242) (xy 311.193656 -299.898635) (xy 311.239672 -299.881183)
			(xy 311.287891 -299.871339) (xy 311.337066 -299.869358) (xy 311.385921 -299.87529) (xy 311.433192 -299.888982)
			(xy 311.477654 -299.91008) (xy 311.518157 -299.938036) (xy 311.55365 -299.972128) (xy 311.583215 -300.011472)
			(xy 311.606086 -300.055049) (xy 311.62167 -300.10173) (xy 311.629565 -300.150307) (xy 311.63006 -300.174914)
			(xy 311.968908 -300.174914) (xy 311.972868 -300.12586) (xy 311.984645 -300.078076) (xy 312.003936 -300.0328)
			(xy 312.030239 -299.991204) (xy 312.062874 -299.954367) (xy 312.100995 -299.923242) (xy 312.143616 -299.898635)
			(xy 312.189632 -299.881183) (xy 312.237851 -299.871339) (xy 312.287026 -299.869358) (xy 312.335881 -299.87529)
			(xy 312.383152 -299.888982) (xy 312.427614 -299.91008) (xy 312.468117 -299.938036) (xy 312.50361 -299.972128)
			(xy 312.533175 -300.011472) (xy 312.556046 -300.055049) (xy 312.57163 -300.10173) (xy 312.579525 -300.150307)
			(xy 312.58002 -300.174914) (xy 312.919122 -300.174914) (xy 312.923082 -300.12586) (xy 312.934859 -300.078076)
			(xy 312.95415 -300.0328) (xy 312.980453 -299.991204) (xy 313.013088 -299.954367) (xy 313.051209 -299.923242)
			(xy 313.09383 -299.898635) (xy 313.139846 -299.881183) (xy 313.188065 -299.871339) (xy 313.23724 -299.869358)
			(xy 313.286095 -299.87529) (xy 313.333366 -299.888982) (xy 313.377828 -299.91008) (xy 313.418331 -299.938036)
			(xy 313.453824 -299.972128) (xy 313.483389 -300.011472) (xy 313.50626 -300.055049) (xy 313.521844 -300.10173)
			(xy 313.529739 -300.150307) (xy 313.530234 -300.174914) (xy 313.869082 -300.174914) (xy 313.873042 -300.12586)
			(xy 313.884819 -300.078076) (xy 313.90411 -300.0328) (xy 313.930413 -299.991204) (xy 313.963048 -299.954367)
			(xy 314.001169 -299.923242) (xy 314.04379 -299.898635) (xy 314.089806 -299.881183) (xy 314.138025 -299.871339)
			(xy 314.1872 -299.869358) (xy 314.236055 -299.87529) (xy 314.283326 -299.888982) (xy 314.327788 -299.91008)
			(xy 314.368291 -299.938036) (xy 314.403784 -299.972128) (xy 314.433349 -300.011472) (xy 314.45622 -300.055049)
			(xy 314.471804 -300.10173) (xy 314.479699 -300.150307) (xy 314.480194 -300.174914) (xy 314.819042 -300.174914)
			(xy 314.823002 -300.12586) (xy 314.834779 -300.078076) (xy 314.85407 -300.0328) (xy 314.880373 -299.991204)
			(xy 314.913008 -299.954367) (xy 314.951129 -299.923242) (xy 314.99375 -299.898635) (xy 315.039766 -299.881183)
			(xy 315.087985 -299.871339) (xy 315.13716 -299.869358) (xy 315.186015 -299.87529) (xy 315.233286 -299.888982)
			(xy 315.277748 -299.91008) (xy 315.318251 -299.938036) (xy 315.353744 -299.972128) (xy 315.383309 -300.011472)
			(xy 315.40618 -300.055049) (xy 315.421764 -300.10173) (xy 315.429659 -300.150307) (xy 315.430154 -300.174914)
			(xy 315.429659 -300.199521) (xy 315.421764 -300.248098) (xy 315.40618 -300.294779) (xy 315.383309 -300.338356)
			(xy 315.353744 -300.3777) (xy 315.318251 -300.411792) (xy 315.277748 -300.439748) (xy 315.233286 -300.460846)
			(xy 315.186015 -300.474538) (xy 315.13716 -300.48047) (xy 315.087985 -300.478489) (xy 315.039766 -300.468645)
			(xy 314.99375 -300.451193) (xy 314.951129 -300.426586) (xy 314.913008 -300.395461) (xy 314.880373 -300.358624)
			(xy 314.85407 -300.317028) (xy 314.834779 -300.271752) (xy 314.823002 -300.223968) (xy 314.819042 -300.174914)
			(xy 314.480194 -300.174914) (xy 314.479699 -300.199521) (xy 314.471804 -300.248098) (xy 314.45622 -300.294779)
			(xy 314.433349 -300.338356) (xy 314.403784 -300.3777) (xy 314.368291 -300.411792) (xy 314.327788 -300.439748)
			(xy 314.283326 -300.460846) (xy 314.236055 -300.474538) (xy 314.1872 -300.48047) (xy 314.138025 -300.478489)
			(xy 314.089806 -300.468645) (xy 314.04379 -300.451193) (xy 314.001169 -300.426586) (xy 313.963048 -300.395461)
			(xy 313.930413 -300.358624) (xy 313.90411 -300.317028) (xy 313.884819 -300.271752) (xy 313.873042 -300.223968)
			(xy 313.869082 -300.174914) (xy 313.530234 -300.174914) (xy 313.529739 -300.199521) (xy 313.521844 -300.248098)
			(xy 313.50626 -300.294779) (xy 313.483389 -300.338356) (xy 313.453824 -300.3777) (xy 313.418331 -300.411792)
			(xy 313.377828 -300.439748) (xy 313.333366 -300.460846) (xy 313.286095 -300.474538) (xy 313.23724 -300.48047)
			(xy 313.188065 -300.478489) (xy 313.139846 -300.468645) (xy 313.09383 -300.451193) (xy 313.051209 -300.426586)
			(xy 313.013088 -300.395461) (xy 312.980453 -300.358624) (xy 312.95415 -300.317028) (xy 312.934859 -300.271752)
			(xy 312.923082 -300.223968) (xy 312.919122 -300.174914) (xy 312.58002 -300.174914) (xy 312.579525 -300.199521)
			(xy 312.57163 -300.248098) (xy 312.556046 -300.294779) (xy 312.533175 -300.338356) (xy 312.50361 -300.3777)
			(xy 312.468117 -300.411792) (xy 312.427614 -300.439748) (xy 312.383152 -300.460846) (xy 312.335881 -300.474538)
			(xy 312.287026 -300.48047) (xy 312.237851 -300.478489) (xy 312.189632 -300.468645) (xy 312.143616 -300.451193)
			(xy 312.100995 -300.426586) (xy 312.062874 -300.395461) (xy 312.030239 -300.358624) (xy 312.003936 -300.317028)
			(xy 311.984645 -300.271752) (xy 311.972868 -300.223968) (xy 311.968908 -300.174914) (xy 311.63006 -300.174914)
			(xy 311.629565 -300.199521) (xy 311.62167 -300.248098) (xy 311.606086 -300.294779) (xy 311.583215 -300.338356)
			(xy 311.55365 -300.3777) (xy 311.518157 -300.411792) (xy 311.477654 -300.439748) (xy 311.433192 -300.460846)
			(xy 311.385921 -300.474538) (xy 311.337066 -300.48047) (xy 311.287891 -300.478489) (xy 311.239672 -300.468645)
			(xy 311.193656 -300.451193) (xy 311.151035 -300.426586) (xy 311.112914 -300.395461) (xy 311.080279 -300.358624)
			(xy 311.053976 -300.317028) (xy 311.034685 -300.271752) (xy 311.022908 -300.223968) (xy 311.018948 -300.174914)
			(xy 310.6801 -300.174914) (xy 310.679605 -300.199521) (xy 310.67171 -300.248098) (xy 310.656126 -300.294779)
			(xy 310.633255 -300.338356) (xy 310.60369 -300.3777) (xy 310.568197 -300.411792) (xy 310.527694 -300.439748)
			(xy 310.483232 -300.460846) (xy 310.435961 -300.474538) (xy 310.387106 -300.48047) (xy 310.337931 -300.478489)
			(xy 310.289712 -300.468645) (xy 310.243696 -300.451193) (xy 310.201075 -300.426586) (xy 310.162954 -300.395461)
			(xy 310.130319 -300.358624) (xy 310.104016 -300.317028) (xy 310.084725 -300.271752) (xy 310.072948 -300.223968)
			(xy 310.068988 -300.174914) (xy 309.73014 -300.174914) (xy 309.729645 -300.199521) (xy 309.72175 -300.248098)
			(xy 309.706166 -300.294779) (xy 309.683295 -300.338356) (xy 309.65373 -300.3777) (xy 309.618237 -300.411792)
			(xy 309.577734 -300.439748) (xy 309.533272 -300.460846) (xy 309.486001 -300.474538) (xy 309.437146 -300.48047)
			(xy 309.387971 -300.478489) (xy 309.339752 -300.468645) (xy 309.293736 -300.451193) (xy 309.251115 -300.426586)
			(xy 309.212994 -300.395461) (xy 309.180359 -300.358624) (xy 309.154056 -300.317028) (xy 309.134765 -300.271752)
			(xy 309.122988 -300.223968) (xy 309.119028 -300.174914) (xy 308.78018 -300.174914) (xy 308.779685 -300.199521)
			(xy 308.77179 -300.248098) (xy 308.756206 -300.294779) (xy 308.733335 -300.338356) (xy 308.70377 -300.3777)
			(xy 308.668277 -300.411792) (xy 308.627774 -300.439748) (xy 308.583312 -300.460846) (xy 308.536041 -300.474538)
			(xy 308.487186 -300.48047) (xy 308.438011 -300.478489) (xy 308.389792 -300.468645) (xy 308.343776 -300.451193)
			(xy 308.301155 -300.426586) (xy 308.263034 -300.395461) (xy 308.230399 -300.358624) (xy 308.204096 -300.317028)
			(xy 308.184805 -300.271752) (xy 308.173028 -300.223968) (xy 308.169068 -300.174914) (xy 307.83022 -300.174914)
			(xy 307.829725 -300.199521) (xy 307.82183 -300.248098) (xy 307.806246 -300.294779) (xy 307.783375 -300.338356)
			(xy 307.75381 -300.3777) (xy 307.718317 -300.411792) (xy 307.677814 -300.439748) (xy 307.633352 -300.460846)
			(xy 307.586081 -300.474538) (xy 307.537226 -300.48047) (xy 307.488051 -300.478489) (xy 307.439832 -300.468645)
			(xy 307.393816 -300.451193) (xy 307.351195 -300.426586) (xy 307.313074 -300.395461) (xy 307.280439 -300.358624)
			(xy 307.254136 -300.317028) (xy 307.234845 -300.271752) (xy 307.223068 -300.223968) (xy 307.219108 -300.174914)
			(xy 306.880006 -300.174914) (xy 306.879511 -300.199521) (xy 306.871616 -300.248098) (xy 306.856032 -300.294779)
			(xy 306.833161 -300.338356) (xy 306.803596 -300.3777) (xy 306.768103 -300.411792) (xy 306.7276 -300.439748)
			(xy 306.683138 -300.460846) (xy 306.635867 -300.474538) (xy 306.587012 -300.48047) (xy 306.537837 -300.478489)
			(xy 306.489618 -300.468645) (xy 306.443602 -300.451193) (xy 306.400981 -300.426586) (xy 306.36286 -300.395461)
			(xy 306.330225 -300.358624) (xy 306.303922 -300.317028) (xy 306.284631 -300.271752) (xy 306.272854 -300.223968)
			(xy 306.268894 -300.174914) (xy 305.930046 -300.174914) (xy 305.929551 -300.199521) (xy 305.921656 -300.248098)
			(xy 305.906072 -300.294779) (xy 305.883201 -300.338356) (xy 305.853636 -300.3777) (xy 305.818143 -300.411792)
			(xy 305.77764 -300.439748) (xy 305.733178 -300.460846) (xy 305.685907 -300.474538) (xy 305.637052 -300.48047)
			(xy 305.587877 -300.478489) (xy 305.539658 -300.468645) (xy 305.493642 -300.451193) (xy 305.451021 -300.426586)
			(xy 305.4129 -300.395461) (xy 305.380265 -300.358624) (xy 305.353962 -300.317028) (xy 305.334671 -300.271752)
			(xy 305.322894 -300.223968) (xy 305.318934 -300.174914) (xy 304.980086 -300.174914) (xy 304.979591 -300.199521)
			(xy 304.971696 -300.248098) (xy 304.956112 -300.294779) (xy 304.933241 -300.338356) (xy 304.903676 -300.3777)
			(xy 304.868183 -300.411792) (xy 304.82768 -300.439748) (xy 304.783218 -300.460846) (xy 304.735947 -300.474538)
			(xy 304.687092 -300.48047) (xy 304.637917 -300.478489) (xy 304.589698 -300.468645) (xy 304.543682 -300.451193)
			(xy 304.501061 -300.426586) (xy 304.46294 -300.395461) (xy 304.430305 -300.358624) (xy 304.404002 -300.317028)
			(xy 304.384711 -300.271752) (xy 304.372934 -300.223968) (xy 304.368974 -300.174914) (xy 304.030126 -300.174914)
			(xy 304.029631 -300.199521) (xy 304.021736 -300.248098) (xy 304.006152 -300.294779) (xy 303.983281 -300.338356)
			(xy 303.953716 -300.3777) (xy 303.918223 -300.411792) (xy 303.87772 -300.439748) (xy 303.833258 -300.460846)
			(xy 303.785987 -300.474538) (xy 303.737132 -300.48047) (xy 303.687957 -300.478489) (xy 303.639738 -300.468645)
			(xy 303.593722 -300.451193) (xy 303.551101 -300.426586) (xy 303.51298 -300.395461) (xy 303.480345 -300.358624)
			(xy 303.454042 -300.317028) (xy 303.434751 -300.271752) (xy 303.422974 -300.223968) (xy 303.419014 -300.174914)
			(xy 303.080166 -300.174914) (xy 303.079671 -300.199521) (xy 303.071776 -300.248098) (xy 303.056192 -300.294779)
			(xy 303.033321 -300.338356) (xy 303.003756 -300.3777) (xy 302.968263 -300.411792) (xy 302.92776 -300.439748)
			(xy 302.883298 -300.460846) (xy 302.836027 -300.474538) (xy 302.787172 -300.48047) (xy 302.737997 -300.478489)
			(xy 302.689778 -300.468645) (xy 302.643762 -300.451193) (xy 302.601141 -300.426586) (xy 302.56302 -300.395461)
			(xy 302.530385 -300.358624) (xy 302.504082 -300.317028) (xy 302.484791 -300.271752) (xy 302.473014 -300.223968)
			(xy 302.469054 -300.174914) (xy 302.130206 -300.174914) (xy 302.129711 -300.199521) (xy 302.121816 -300.248098)
			(xy 302.106232 -300.294779) (xy 302.083361 -300.338356) (xy 302.053796 -300.3777) (xy 302.018303 -300.411792)
			(xy 301.9778 -300.439748) (xy 301.933338 -300.460846) (xy 301.886067 -300.474538) (xy 301.837212 -300.48047)
			(xy 301.788037 -300.478489) (xy 301.739818 -300.468645) (xy 301.693802 -300.451193) (xy 301.651181 -300.426586)
			(xy 301.61306 -300.395461) (xy 301.580425 -300.358624) (xy 301.554122 -300.317028) (xy 301.534831 -300.271752)
			(xy 301.523054 -300.223968) (xy 301.519094 -300.174914) (xy 301.179992 -300.174914) (xy 301.179497 -300.199521)
			(xy 301.171602 -300.248098) (xy 301.156018 -300.294779) (xy 301.133147 -300.338356) (xy 301.103582 -300.3777)
			(xy 301.068089 -300.411792) (xy 301.027586 -300.439748) (xy 300.983124 -300.460846) (xy 300.935853 -300.474538)
			(xy 300.886998 -300.48047) (xy 300.837823 -300.478489) (xy 300.789604 -300.468645) (xy 300.743588 -300.451193)
			(xy 300.700967 -300.426586) (xy 300.662846 -300.395461) (xy 300.630211 -300.358624) (xy 300.603908 -300.317028)
			(xy 300.584617 -300.271752) (xy 300.57284 -300.223968) (xy 300.56888 -300.174914) (xy 300.230032 -300.174914)
			(xy 300.229537 -300.199521) (xy 300.221642 -300.248098) (xy 300.206058 -300.294779) (xy 300.183187 -300.338356)
			(xy 300.153622 -300.3777) (xy 300.118129 -300.411792) (xy 300.077626 -300.439748) (xy 300.033164 -300.460846)
			(xy 299.985893 -300.474538) (xy 299.937038 -300.48047) (xy 299.887863 -300.478489) (xy 299.839644 -300.468645)
			(xy 299.793628 -300.451193) (xy 299.751007 -300.426586) (xy 299.712886 -300.395461) (xy 299.680251 -300.358624)
			(xy 299.653948 -300.317028) (xy 299.634657 -300.271752) (xy 299.62288 -300.223968) (xy 299.61892 -300.174914)
			(xy 299.280072 -300.174914) (xy 299.279577 -300.199521) (xy 299.271682 -300.248098) (xy 299.256098 -300.294779)
			(xy 299.233227 -300.338356) (xy 299.203662 -300.3777) (xy 299.168169 -300.411792) (xy 299.127666 -300.439748)
			(xy 299.083204 -300.460846) (xy 299.035933 -300.474538) (xy 298.987078 -300.48047) (xy 298.937903 -300.478489)
			(xy 298.889684 -300.468645) (xy 298.843668 -300.451193) (xy 298.801047 -300.426586) (xy 298.762926 -300.395461)
			(xy 298.730291 -300.358624) (xy 298.703988 -300.317028) (xy 298.684697 -300.271752) (xy 298.67292 -300.223968)
			(xy 298.66896 -300.174914) (xy 298.330112 -300.174914) (xy 298.329617 -300.199521) (xy 298.321722 -300.248098)
			(xy 298.306138 -300.294779) (xy 298.283267 -300.338356) (xy 298.253702 -300.3777) (xy 298.218209 -300.411792)
			(xy 298.177706 -300.439748) (xy 298.133244 -300.460846) (xy 298.085973 -300.474538) (xy 298.037118 -300.48047)
			(xy 297.987943 -300.478489) (xy 297.939724 -300.468645) (xy 297.893708 -300.451193) (xy 297.851087 -300.426586)
			(xy 297.812966 -300.395461) (xy 297.780331 -300.358624) (xy 297.754028 -300.317028) (xy 297.734737 -300.271752)
			(xy 297.72296 -300.223968) (xy 297.719 -300.174914) (xy 297.380152 -300.174914) (xy 297.379657 -300.199521)
			(xy 297.371762 -300.248098) (xy 297.356178 -300.294779) (xy 297.333307 -300.338356) (xy 297.303742 -300.3777)
			(xy 297.268249 -300.411792) (xy 297.227746 -300.439748) (xy 297.183284 -300.460846) (xy 297.136013 -300.474538)
			(xy 297.087158 -300.48047) (xy 297.037983 -300.478489) (xy 296.989764 -300.468645) (xy 296.943748 -300.451193)
			(xy 296.901127 -300.426586) (xy 296.863006 -300.395461) (xy 296.830371 -300.358624) (xy 296.804068 -300.317028)
			(xy 296.784777 -300.271752) (xy 296.773 -300.223968) (xy 296.76904 -300.174914) (xy 296.430192 -300.174914)
			(xy 296.429697 -300.199521) (xy 296.421802 -300.248098) (xy 296.406218 -300.294779) (xy 296.383347 -300.338356)
			(xy 296.353782 -300.3777) (xy 296.318289 -300.411792) (xy 296.277786 -300.439748) (xy 296.233324 -300.460846)
			(xy 296.186053 -300.474538) (xy 296.137198 -300.48047) (xy 296.088023 -300.478489) (xy 296.039804 -300.468645)
			(xy 295.993788 -300.451193) (xy 295.951167 -300.426586) (xy 295.913046 -300.395461) (xy 295.880411 -300.358624)
			(xy 295.854108 -300.317028) (xy 295.834817 -300.271752) (xy 295.82304 -300.223968) (xy 295.81908 -300.174914)
			(xy 295.480232 -300.174914) (xy 295.479737 -300.199521) (xy 295.471842 -300.248098) (xy 295.456258 -300.294779)
			(xy 295.433387 -300.338356) (xy 295.403822 -300.3777) (xy 295.368329 -300.411792) (xy 295.327826 -300.439748)
			(xy 295.283364 -300.460846) (xy 295.236093 -300.474538) (xy 295.187238 -300.48047) (xy 295.138063 -300.478489)
			(xy 295.089844 -300.468645) (xy 295.043828 -300.451193) (xy 295.001207 -300.426586) (xy 294.963086 -300.395461)
			(xy 294.930451 -300.358624) (xy 294.904148 -300.317028) (xy 294.884857 -300.271752) (xy 294.87308 -300.223968)
			(xy 294.86912 -300.174914) (xy 294.530018 -300.174914) (xy 294.529523 -300.199521) (xy 294.521628 -300.248098)
			(xy 294.506044 -300.294779) (xy 294.483173 -300.338356) (xy 294.453608 -300.3777) (xy 294.418115 -300.411792)
			(xy 294.377612 -300.439748) (xy 294.33315 -300.460846) (xy 294.285879 -300.474538) (xy 294.237024 -300.48047)
			(xy 294.187849 -300.478489) (xy 294.13963 -300.468645) (xy 294.093614 -300.451193) (xy 294.050993 -300.426586)
			(xy 294.012872 -300.395461) (xy 293.980237 -300.358624) (xy 293.953934 -300.317028) (xy 293.934643 -300.271752)
			(xy 293.922866 -300.223968) (xy 293.918906 -300.174914) (xy 293.580058 -300.174914) (xy 293.579563 -300.199521)
			(xy 293.571668 -300.248098) (xy 293.556084 -300.294779) (xy 293.533213 -300.338356) (xy 293.503648 -300.3777)
			(xy 293.468155 -300.411792) (xy 293.427652 -300.439748) (xy 293.38319 -300.460846) (xy 293.335919 -300.474538)
			(xy 293.287064 -300.48047) (xy 293.237889 -300.478489) (xy 293.18967 -300.468645) (xy 293.143654 -300.451193)
			(xy 293.101033 -300.426586) (xy 293.062912 -300.395461) (xy 293.030277 -300.358624) (xy 293.003974 -300.317028)
			(xy 292.984683 -300.271752) (xy 292.972906 -300.223968) (xy 292.968946 -300.174914) (xy 292.630581 -300.174914)
			(xy 292.626536 -300.224479) (xy 292.614506 -300.272743) (xy 292.59481 -300.318418) (xy 292.567969 -300.360295)
			(xy 292.534694 -300.397267) (xy 292.495865 -300.428355) (xy 292.45251 -300.452736) (xy 292.405775 -300.469766)
			(xy 292.381432 -300.474888) (xy 292.38067 -300.475142) (xy 292.372021 -300.477098) (xy 292.356714 -300.486025)
			(xy 292.34538 -300.499645) (xy 292.339383 -300.516319) (xy 292.339014 -300.52518) (xy 292.339014 -300.774608)
			(xy 292.339628 -300.786459) (xy 292.350198 -300.807672) (xy 292.369118 -300.821949) (xy 292.38067 -300.824646)
			(xy 292.381432 -300.8249) (xy 292.405783 -300.829996) (xy 292.452524 -300.847027) (xy 292.495885 -300.871411)
			(xy 292.53472 -300.902503) (xy 292.567999 -300.939479) (xy 292.594844 -300.981362) (xy 292.614543 -301.027043)
			(xy 292.626575 -301.075313) (xy 292.63062 -301.124874) (xy 292.968946 -301.124874) (xy 292.972906 -301.07582)
			(xy 292.984683 -301.028036) (xy 293.003974 -300.98276) (xy 293.030277 -300.941164) (xy 293.062912 -300.904327)
			(xy 293.101033 -300.873202) (xy 293.143654 -300.848595) (xy 293.18967 -300.831143) (xy 293.237889 -300.821299)
			(xy 293.287064 -300.819318) (xy 293.335919 -300.82525) (xy 293.38319 -300.838942) (xy 293.427652 -300.86004)
			(xy 293.468155 -300.887996) (xy 293.503648 -300.922088) (xy 293.533213 -300.961432) (xy 293.556084 -301.005009)
			(xy 293.571668 -301.05169) (xy 293.579563 -301.100267) (xy 293.580058 -301.124874) (xy 293.918906 -301.124874)
			(xy 293.922866 -301.07582) (xy 293.934643 -301.028036) (xy 293.953934 -300.98276) (xy 293.980237 -300.941164)
			(xy 294.012872 -300.904327) (xy 294.050993 -300.873202) (xy 294.093614 -300.848595) (xy 294.13963 -300.831143)
			(xy 294.187849 -300.821299) (xy 294.237024 -300.819318) (xy 294.285879 -300.82525) (xy 294.33315 -300.838942)
			(xy 294.377612 -300.86004) (xy 294.418115 -300.887996) (xy 294.453608 -300.922088) (xy 294.483173 -300.961432)
			(xy 294.506044 -301.005009) (xy 294.521628 -301.05169) (xy 294.529523 -301.100267) (xy 294.530018 -301.124874)
			(xy 294.86912 -301.124874) (xy 294.87308 -301.07582) (xy 294.884857 -301.028036) (xy 294.904148 -300.98276)
			(xy 294.930451 -300.941164) (xy 294.963086 -300.904327) (xy 295.001207 -300.873202) (xy 295.043828 -300.848595)
			(xy 295.089844 -300.831143) (xy 295.138063 -300.821299) (xy 295.187238 -300.819318) (xy 295.236093 -300.82525)
			(xy 295.283364 -300.838942) (xy 295.327826 -300.86004) (xy 295.368329 -300.887996) (xy 295.403822 -300.922088)
			(xy 295.433387 -300.961432) (xy 295.456258 -301.005009) (xy 295.471842 -301.05169) (xy 295.479737 -301.100267)
			(xy 295.480232 -301.124874) (xy 295.81908 -301.124874) (xy 295.82304 -301.07582) (xy 295.834817 -301.028036)
			(xy 295.854108 -300.98276) (xy 295.880411 -300.941164) (xy 295.913046 -300.904327) (xy 295.951167 -300.873202)
			(xy 295.993788 -300.848595) (xy 296.039804 -300.831143) (xy 296.088023 -300.821299) (xy 296.137198 -300.819318)
			(xy 296.186053 -300.82525) (xy 296.233324 -300.838942) (xy 296.277786 -300.86004) (xy 296.318289 -300.887996)
			(xy 296.353782 -300.922088) (xy 296.383347 -300.961432) (xy 296.406218 -301.005009) (xy 296.421802 -301.05169)
			(xy 296.429697 -301.100267) (xy 296.430192 -301.124874) (xy 296.76904 -301.124874) (xy 296.773 -301.07582)
			(xy 296.784777 -301.028036) (xy 296.804068 -300.98276) (xy 296.830371 -300.941164) (xy 296.863006 -300.904327)
			(xy 296.901127 -300.873202) (xy 296.943748 -300.848595) (xy 296.989764 -300.831143) (xy 297.037983 -300.821299)
			(xy 297.087158 -300.819318) (xy 297.136013 -300.82525) (xy 297.183284 -300.838942) (xy 297.227746 -300.86004)
			(xy 297.268249 -300.887996) (xy 297.303742 -300.922088) (xy 297.333307 -300.961432) (xy 297.356178 -301.005009)
			(xy 297.371762 -301.05169) (xy 297.379657 -301.100267) (xy 297.380152 -301.124874) (xy 297.719 -301.124874)
			(xy 297.72296 -301.07582) (xy 297.734737 -301.028036) (xy 297.754028 -300.98276) (xy 297.780331 -300.941164)
			(xy 297.812966 -300.904327) (xy 297.851087 -300.873202) (xy 297.893708 -300.848595) (xy 297.939724 -300.831143)
			(xy 297.987943 -300.821299) (xy 298.037118 -300.819318) (xy 298.085973 -300.82525) (xy 298.133244 -300.838942)
			(xy 298.177706 -300.86004) (xy 298.218209 -300.887996) (xy 298.253702 -300.922088) (xy 298.283267 -300.961432)
			(xy 298.306138 -301.005009) (xy 298.321722 -301.05169) (xy 298.329617 -301.100267) (xy 298.330112 -301.124874)
			(xy 298.66896 -301.124874) (xy 298.67292 -301.07582) (xy 298.684697 -301.028036) (xy 298.703988 -300.98276)
			(xy 298.730291 -300.941164) (xy 298.762926 -300.904327) (xy 298.801047 -300.873202) (xy 298.843668 -300.848595)
			(xy 298.889684 -300.831143) (xy 298.937903 -300.821299) (xy 298.987078 -300.819318) (xy 299.035933 -300.82525)
			(xy 299.083204 -300.838942) (xy 299.127666 -300.86004) (xy 299.168169 -300.887996) (xy 299.203662 -300.922088)
			(xy 299.233227 -300.961432) (xy 299.256098 -301.005009) (xy 299.271682 -301.05169) (xy 299.279577 -301.100267)
			(xy 299.280072 -301.124874) (xy 299.61892 -301.124874) (xy 299.62288 -301.07582) (xy 299.634657 -301.028036)
			(xy 299.653948 -300.98276) (xy 299.680251 -300.941164) (xy 299.712886 -300.904327) (xy 299.751007 -300.873202)
			(xy 299.793628 -300.848595) (xy 299.839644 -300.831143) (xy 299.887863 -300.821299) (xy 299.937038 -300.819318)
			(xy 299.985893 -300.82525) (xy 300.033164 -300.838942) (xy 300.077626 -300.86004) (xy 300.118129 -300.887996)
			(xy 300.153622 -300.922088) (xy 300.183187 -300.961432) (xy 300.206058 -301.005009) (xy 300.221642 -301.05169)
			(xy 300.229537 -301.100267) (xy 300.230032 -301.124874) (xy 300.56888 -301.124874) (xy 300.57284 -301.07582)
			(xy 300.584617 -301.028036) (xy 300.603908 -300.98276) (xy 300.630211 -300.941164) (xy 300.662846 -300.904327)
			(xy 300.700967 -300.873202) (xy 300.743588 -300.848595) (xy 300.789604 -300.831143) (xy 300.837823 -300.821299)
			(xy 300.886998 -300.819318) (xy 300.935853 -300.82525) (xy 300.983124 -300.838942) (xy 301.027586 -300.86004)
			(xy 301.068089 -300.887996) (xy 301.103582 -300.922088) (xy 301.133147 -300.961432) (xy 301.156018 -301.005009)
			(xy 301.171602 -301.05169) (xy 301.179497 -301.100267) (xy 301.179992 -301.124874) (xy 301.519094 -301.124874)
			(xy 301.523054 -301.07582) (xy 301.534831 -301.028036) (xy 301.554122 -300.98276) (xy 301.580425 -300.941164)
			(xy 301.61306 -300.904327) (xy 301.651181 -300.873202) (xy 301.693802 -300.848595) (xy 301.739818 -300.831143)
			(xy 301.788037 -300.821299) (xy 301.837212 -300.819318) (xy 301.886067 -300.82525) (xy 301.933338 -300.838942)
			(xy 301.9778 -300.86004) (xy 302.018303 -300.887996) (xy 302.053796 -300.922088) (xy 302.083361 -300.961432)
			(xy 302.106232 -301.005009) (xy 302.121816 -301.05169) (xy 302.129711 -301.100267) (xy 302.130206 -301.124874)
			(xy 302.469054 -301.124874) (xy 302.473014 -301.07582) (xy 302.484791 -301.028036) (xy 302.504082 -300.98276)
			(xy 302.530385 -300.941164) (xy 302.56302 -300.904327) (xy 302.601141 -300.873202) (xy 302.643762 -300.848595)
			(xy 302.689778 -300.831143) (xy 302.737997 -300.821299) (xy 302.787172 -300.819318) (xy 302.836027 -300.82525)
			(xy 302.883298 -300.838942) (xy 302.92776 -300.86004) (xy 302.968263 -300.887996) (xy 303.003756 -300.922088)
			(xy 303.033321 -300.961432) (xy 303.056192 -301.005009) (xy 303.071776 -301.05169) (xy 303.079671 -301.100267)
			(xy 303.080166 -301.124874) (xy 303.419014 -301.124874) (xy 303.422974 -301.07582) (xy 303.434751 -301.028036)
			(xy 303.454042 -300.98276) (xy 303.480345 -300.941164) (xy 303.51298 -300.904327) (xy 303.551101 -300.873202)
			(xy 303.593722 -300.848595) (xy 303.639738 -300.831143) (xy 303.687957 -300.821299) (xy 303.737132 -300.819318)
			(xy 303.785987 -300.82525) (xy 303.833258 -300.838942) (xy 303.87772 -300.86004) (xy 303.918223 -300.887996)
			(xy 303.953716 -300.922088) (xy 303.983281 -300.961432) (xy 304.006152 -301.005009) (xy 304.021736 -301.05169)
			(xy 304.029631 -301.100267) (xy 304.030126 -301.124874) (xy 304.368974 -301.124874) (xy 304.372934 -301.07582)
			(xy 304.384711 -301.028036) (xy 304.404002 -300.98276) (xy 304.430305 -300.941164) (xy 304.46294 -300.904327)
			(xy 304.501061 -300.873202) (xy 304.543682 -300.848595) (xy 304.589698 -300.831143) (xy 304.637917 -300.821299)
			(xy 304.687092 -300.819318) (xy 304.735947 -300.82525) (xy 304.783218 -300.838942) (xy 304.82768 -300.86004)
			(xy 304.868183 -300.887996) (xy 304.903676 -300.922088) (xy 304.933241 -300.961432) (xy 304.956112 -301.005009)
			(xy 304.971696 -301.05169) (xy 304.979591 -301.100267) (xy 304.980086 -301.124874) (xy 305.318934 -301.124874)
			(xy 305.322894 -301.07582) (xy 305.334671 -301.028036) (xy 305.353962 -300.98276) (xy 305.380265 -300.941164)
			(xy 305.4129 -300.904327) (xy 305.451021 -300.873202) (xy 305.493642 -300.848595) (xy 305.539658 -300.831143)
			(xy 305.587877 -300.821299) (xy 305.637052 -300.819318) (xy 305.685907 -300.82525) (xy 305.733178 -300.838942)
			(xy 305.77764 -300.86004) (xy 305.818143 -300.887996) (xy 305.853636 -300.922088) (xy 305.883201 -300.961432)
			(xy 305.906072 -301.005009) (xy 305.921656 -301.05169) (xy 305.929551 -301.100267) (xy 305.930046 -301.124874)
			(xy 308.169068 -301.124874) (xy 308.173028 -301.07582) (xy 308.184805 -301.028036) (xy 308.204096 -300.98276)
			(xy 308.230399 -300.941164) (xy 308.263034 -300.904327) (xy 308.301155 -300.873202) (xy 308.343776 -300.848595)
			(xy 308.389792 -300.831143) (xy 308.438011 -300.821299) (xy 308.487186 -300.819318) (xy 308.536041 -300.82525)
			(xy 308.583312 -300.838942) (xy 308.627774 -300.86004) (xy 308.668277 -300.887996) (xy 308.70377 -300.922088)
			(xy 308.733335 -300.961432) (xy 308.756206 -301.005009) (xy 308.77179 -301.05169) (xy 308.779685 -301.100267)
			(xy 308.78018 -301.124874) (xy 309.119028 -301.124874) (xy 309.122988 -301.07582) (xy 309.134765 -301.028036)
			(xy 309.154056 -300.98276) (xy 309.180359 -300.941164) (xy 309.212994 -300.904327) (xy 309.251115 -300.873202)
			(xy 309.293736 -300.848595) (xy 309.339752 -300.831143) (xy 309.387971 -300.821299) (xy 309.437146 -300.819318)
			(xy 309.486001 -300.82525) (xy 309.533272 -300.838942) (xy 309.577734 -300.86004) (xy 309.618237 -300.887996)
			(xy 309.65373 -300.922088) (xy 309.683295 -300.961432) (xy 309.706166 -301.005009) (xy 309.72175 -301.05169)
			(xy 309.729645 -301.100267) (xy 309.73014 -301.124874) (xy 310.068988 -301.124874) (xy 310.072948 -301.07582)
			(xy 310.084725 -301.028036) (xy 310.104016 -300.98276) (xy 310.130319 -300.941164) (xy 310.162954 -300.904327)
			(xy 310.201075 -300.873202) (xy 310.243696 -300.848595) (xy 310.289712 -300.831143) (xy 310.337931 -300.821299)
			(xy 310.387106 -300.819318) (xy 310.435961 -300.82525) (xy 310.483232 -300.838942) (xy 310.527694 -300.86004)
			(xy 310.568197 -300.887996) (xy 310.60369 -300.922088) (xy 310.633255 -300.961432) (xy 310.656126 -301.005009)
			(xy 310.67171 -301.05169) (xy 310.679605 -301.100267) (xy 310.6801 -301.124874) (xy 311.018948 -301.124874)
			(xy 311.022908 -301.07582) (xy 311.034685 -301.028036) (xy 311.053976 -300.98276) (xy 311.080279 -300.941164)
			(xy 311.112914 -300.904327) (xy 311.151035 -300.873202) (xy 311.193656 -300.848595) (xy 311.239672 -300.831143)
			(xy 311.287891 -300.821299) (xy 311.337066 -300.819318) (xy 311.385921 -300.82525) (xy 311.433192 -300.838942)
			(xy 311.477654 -300.86004) (xy 311.518157 -300.887996) (xy 311.55365 -300.922088) (xy 311.583215 -300.961432)
			(xy 311.606086 -301.005009) (xy 311.62167 -301.05169) (xy 311.629565 -301.100267) (xy 311.63006 -301.124874)
			(xy 311.968908 -301.124874) (xy 311.972868 -301.07582) (xy 311.984645 -301.028036) (xy 312.003936 -300.98276)
			(xy 312.030239 -300.941164) (xy 312.062874 -300.904327) (xy 312.100995 -300.873202) (xy 312.143616 -300.848595)
			(xy 312.189632 -300.831143) (xy 312.237851 -300.821299) (xy 312.287026 -300.819318) (xy 312.335881 -300.82525)
			(xy 312.383152 -300.838942) (xy 312.427614 -300.86004) (xy 312.468117 -300.887996) (xy 312.50361 -300.922088)
			(xy 312.533175 -300.961432) (xy 312.556046 -301.005009) (xy 312.57163 -301.05169) (xy 312.579525 -301.100267)
			(xy 312.58002 -301.124874) (xy 312.919122 -301.124874) (xy 312.923082 -301.07582) (xy 312.934859 -301.028036)
			(xy 312.95415 -300.98276) (xy 312.980453 -300.941164) (xy 313.013088 -300.904327) (xy 313.051209 -300.873202)
			(xy 313.09383 -300.848595) (xy 313.139846 -300.831143) (xy 313.188065 -300.821299) (xy 313.23724 -300.819318)
			(xy 313.286095 -300.82525) (xy 313.333366 -300.838942) (xy 313.377828 -300.86004) (xy 313.418331 -300.887996)
			(xy 313.453824 -300.922088) (xy 313.483389 -300.961432) (xy 313.50626 -301.005009) (xy 313.521844 -301.05169)
			(xy 313.529739 -301.100267) (xy 313.530234 -301.124874) (xy 313.869082 -301.124874) (xy 313.873042 -301.07582)
			(xy 313.884819 -301.028036) (xy 313.90411 -300.98276) (xy 313.930413 -300.941164) (xy 313.963048 -300.904327)
			(xy 314.001169 -300.873202) (xy 314.04379 -300.848595) (xy 314.089806 -300.831143) (xy 314.138025 -300.821299)
			(xy 314.1872 -300.819318) (xy 314.236055 -300.82525) (xy 314.283326 -300.838942) (xy 314.327788 -300.86004)
			(xy 314.368291 -300.887996) (xy 314.403784 -300.922088) (xy 314.433349 -300.961432) (xy 314.45622 -301.005009)
			(xy 314.471804 -301.05169) (xy 314.479699 -301.100267) (xy 314.480194 -301.124874) (xy 314.819042 -301.124874)
			(xy 314.823002 -301.07582) (xy 314.834779 -301.028036) (xy 314.85407 -300.98276) (xy 314.880373 -300.941164)
			(xy 314.913008 -300.904327) (xy 314.951129 -300.873202) (xy 314.99375 -300.848595) (xy 315.039766 -300.831143)
			(xy 315.087985 -300.821299) (xy 315.13716 -300.819318) (xy 315.186015 -300.82525) (xy 315.233286 -300.838942)
			(xy 315.277748 -300.86004) (xy 315.318251 -300.887996) (xy 315.353744 -300.922088) (xy 315.383309 -300.961432)
			(xy 315.40618 -301.005009) (xy 315.421764 -301.05169) (xy 315.429659 -301.100267) (xy 315.430154 -301.124874)
			(xy 315.429659 -301.149481) (xy 315.421764 -301.198058) (xy 315.40618 -301.244739) (xy 315.383309 -301.288316)
			(xy 315.353744 -301.32766) (xy 315.318251 -301.361752) (xy 315.277748 -301.389708) (xy 315.233286 -301.410806)
			(xy 315.186015 -301.424498) (xy 315.13716 -301.43043) (xy 315.087985 -301.428449) (xy 315.039766 -301.418605)
			(xy 314.99375 -301.401153) (xy 314.951129 -301.376546) (xy 314.913008 -301.345421) (xy 314.880373 -301.308584)
			(xy 314.85407 -301.266988) (xy 314.834779 -301.221712) (xy 314.823002 -301.173928) (xy 314.819042 -301.124874)
			(xy 314.480194 -301.124874) (xy 314.479699 -301.149481) (xy 314.471804 -301.198058) (xy 314.45622 -301.244739)
			(xy 314.433349 -301.288316) (xy 314.403784 -301.32766) (xy 314.368291 -301.361752) (xy 314.327788 -301.389708)
			(xy 314.283326 -301.410806) (xy 314.236055 -301.424498) (xy 314.1872 -301.43043) (xy 314.138025 -301.428449)
			(xy 314.089806 -301.418605) (xy 314.04379 -301.401153) (xy 314.001169 -301.376546) (xy 313.963048 -301.345421)
			(xy 313.930413 -301.308584) (xy 313.90411 -301.266988) (xy 313.884819 -301.221712) (xy 313.873042 -301.173928)
			(xy 313.869082 -301.124874) (xy 313.530234 -301.124874) (xy 313.529739 -301.149481) (xy 313.521844 -301.198058)
			(xy 313.50626 -301.244739) (xy 313.483389 -301.288316) (xy 313.453824 -301.32766) (xy 313.418331 -301.361752)
			(xy 313.377828 -301.389708) (xy 313.333366 -301.410806) (xy 313.286095 -301.424498) (xy 313.23724 -301.43043)
			(xy 313.188065 -301.428449) (xy 313.139846 -301.418605) (xy 313.09383 -301.401153) (xy 313.051209 -301.376546)
			(xy 313.013088 -301.345421) (xy 312.980453 -301.308584) (xy 312.95415 -301.266988) (xy 312.934859 -301.221712)
			(xy 312.923082 -301.173928) (xy 312.919122 -301.124874) (xy 312.58002 -301.124874) (xy 312.579525 -301.149481)
			(xy 312.57163 -301.198058) (xy 312.556046 -301.244739) (xy 312.533175 -301.288316) (xy 312.50361 -301.32766)
			(xy 312.468117 -301.361752) (xy 312.427614 -301.389708) (xy 312.383152 -301.410806) (xy 312.335881 -301.424498)
			(xy 312.287026 -301.43043) (xy 312.237851 -301.428449) (xy 312.189632 -301.418605) (xy 312.143616 -301.401153)
			(xy 312.100995 -301.376546) (xy 312.062874 -301.345421) (xy 312.030239 -301.308584) (xy 312.003936 -301.266988)
			(xy 311.984645 -301.221712) (xy 311.972868 -301.173928) (xy 311.968908 -301.124874) (xy 311.63006 -301.124874)
			(xy 311.629565 -301.149481) (xy 311.62167 -301.198058) (xy 311.606086 -301.244739) (xy 311.583215 -301.288316)
			(xy 311.55365 -301.32766) (xy 311.518157 -301.361752) (xy 311.477654 -301.389708) (xy 311.433192 -301.410806)
			(xy 311.385921 -301.424498) (xy 311.337066 -301.43043) (xy 311.287891 -301.428449) (xy 311.239672 -301.418605)
			(xy 311.193656 -301.401153) (xy 311.151035 -301.376546) (xy 311.112914 -301.345421) (xy 311.080279 -301.308584)
			(xy 311.053976 -301.266988) (xy 311.034685 -301.221712) (xy 311.022908 -301.173928) (xy 311.018948 -301.124874)
			(xy 310.6801 -301.124874) (xy 310.679605 -301.149481) (xy 310.67171 -301.198058) (xy 310.656126 -301.244739)
			(xy 310.633255 -301.288316) (xy 310.60369 -301.32766) (xy 310.568197 -301.361752) (xy 310.527694 -301.389708)
			(xy 310.483232 -301.410806) (xy 310.435961 -301.424498) (xy 310.387106 -301.43043) (xy 310.337931 -301.428449)
			(xy 310.289712 -301.418605) (xy 310.243696 -301.401153) (xy 310.201075 -301.376546) (xy 310.162954 -301.345421)
			(xy 310.130319 -301.308584) (xy 310.104016 -301.266988) (xy 310.084725 -301.221712) (xy 310.072948 -301.173928)
			(xy 310.068988 -301.124874) (xy 309.73014 -301.124874) (xy 309.729645 -301.149481) (xy 309.72175 -301.198058)
			(xy 309.706166 -301.244739) (xy 309.683295 -301.288316) (xy 309.65373 -301.32766) (xy 309.618237 -301.361752)
			(xy 309.577734 -301.389708) (xy 309.533272 -301.410806) (xy 309.486001 -301.424498) (xy 309.437146 -301.43043)
			(xy 309.387971 -301.428449) (xy 309.339752 -301.418605) (xy 309.293736 -301.401153) (xy 309.251115 -301.376546)
			(xy 309.212994 -301.345421) (xy 309.180359 -301.308584) (xy 309.154056 -301.266988) (xy 309.134765 -301.221712)
			(xy 309.122988 -301.173928) (xy 309.119028 -301.124874) (xy 308.78018 -301.124874) (xy 308.779685 -301.149481)
			(xy 308.77179 -301.198058) (xy 308.756206 -301.244739) (xy 308.733335 -301.288316) (xy 308.70377 -301.32766)
			(xy 308.668277 -301.361752) (xy 308.627774 -301.389708) (xy 308.583312 -301.410806) (xy 308.536041 -301.424498)
			(xy 308.487186 -301.43043) (xy 308.438011 -301.428449) (xy 308.389792 -301.418605) (xy 308.343776 -301.401153)
			(xy 308.301155 -301.376546) (xy 308.263034 -301.345421) (xy 308.230399 -301.308584) (xy 308.204096 -301.266988)
			(xy 308.184805 -301.221712) (xy 308.173028 -301.173928) (xy 308.169068 -301.124874) (xy 305.930046 -301.124874)
			(xy 305.929551 -301.149481) (xy 305.921656 -301.198058) (xy 305.906072 -301.244739) (xy 305.883201 -301.288316)
			(xy 305.853636 -301.32766) (xy 305.818143 -301.361752) (xy 305.77764 -301.389708) (xy 305.733178 -301.410806)
			(xy 305.685907 -301.424498) (xy 305.637052 -301.43043) (xy 305.587877 -301.428449) (xy 305.539658 -301.418605)
			(xy 305.493642 -301.401153) (xy 305.451021 -301.376546) (xy 305.4129 -301.345421) (xy 305.380265 -301.308584)
			(xy 305.353962 -301.266988) (xy 305.334671 -301.221712) (xy 305.322894 -301.173928) (xy 305.318934 -301.124874)
			(xy 304.980086 -301.124874) (xy 304.979591 -301.149481) (xy 304.971696 -301.198058) (xy 304.956112 -301.244739)
			(xy 304.933241 -301.288316) (xy 304.903676 -301.32766) (xy 304.868183 -301.361752) (xy 304.82768 -301.389708)
			(xy 304.783218 -301.410806) (xy 304.735947 -301.424498) (xy 304.687092 -301.43043) (xy 304.637917 -301.428449)
			(xy 304.589698 -301.418605) (xy 304.543682 -301.401153) (xy 304.501061 -301.376546) (xy 304.46294 -301.345421)
			(xy 304.430305 -301.308584) (xy 304.404002 -301.266988) (xy 304.384711 -301.221712) (xy 304.372934 -301.173928)
			(xy 304.368974 -301.124874) (xy 304.030126 -301.124874) (xy 304.029631 -301.149481) (xy 304.021736 -301.198058)
			(xy 304.006152 -301.244739) (xy 303.983281 -301.288316) (xy 303.953716 -301.32766) (xy 303.918223 -301.361752)
			(xy 303.87772 -301.389708) (xy 303.833258 -301.410806) (xy 303.785987 -301.424498) (xy 303.737132 -301.43043)
			(xy 303.687957 -301.428449) (xy 303.639738 -301.418605) (xy 303.593722 -301.401153) (xy 303.551101 -301.376546)
			(xy 303.51298 -301.345421) (xy 303.480345 -301.308584) (xy 303.454042 -301.266988) (xy 303.434751 -301.221712)
			(xy 303.422974 -301.173928) (xy 303.419014 -301.124874) (xy 303.080166 -301.124874) (xy 303.079671 -301.149481)
			(xy 303.071776 -301.198058) (xy 303.056192 -301.244739) (xy 303.033321 -301.288316) (xy 303.003756 -301.32766)
			(xy 302.968263 -301.361752) (xy 302.92776 -301.389708) (xy 302.883298 -301.410806) (xy 302.836027 -301.424498)
			(xy 302.787172 -301.43043) (xy 302.737997 -301.428449) (xy 302.689778 -301.418605) (xy 302.643762 -301.401153)
			(xy 302.601141 -301.376546) (xy 302.56302 -301.345421) (xy 302.530385 -301.308584) (xy 302.504082 -301.266988)
			(xy 302.484791 -301.221712) (xy 302.473014 -301.173928) (xy 302.469054 -301.124874) (xy 302.130206 -301.124874)
			(xy 302.129711 -301.149481) (xy 302.121816 -301.198058) (xy 302.106232 -301.244739) (xy 302.083361 -301.288316)
			(xy 302.053796 -301.32766) (xy 302.018303 -301.361752) (xy 301.9778 -301.389708) (xy 301.933338 -301.410806)
			(xy 301.886067 -301.424498) (xy 301.837212 -301.43043) (xy 301.788037 -301.428449) (xy 301.739818 -301.418605)
			(xy 301.693802 -301.401153) (xy 301.651181 -301.376546) (xy 301.61306 -301.345421) (xy 301.580425 -301.308584)
			(xy 301.554122 -301.266988) (xy 301.534831 -301.221712) (xy 301.523054 -301.173928) (xy 301.519094 -301.124874)
			(xy 301.179992 -301.124874) (xy 301.179497 -301.149481) (xy 301.171602 -301.198058) (xy 301.156018 -301.244739)
			(xy 301.133147 -301.288316) (xy 301.103582 -301.32766) (xy 301.068089 -301.361752) (xy 301.027586 -301.389708)
			(xy 300.983124 -301.410806) (xy 300.935853 -301.424498) (xy 300.886998 -301.43043) (xy 300.837823 -301.428449)
			(xy 300.789604 -301.418605) (xy 300.743588 -301.401153) (xy 300.700967 -301.376546) (xy 300.662846 -301.345421)
			(xy 300.630211 -301.308584) (xy 300.603908 -301.266988) (xy 300.584617 -301.221712) (xy 300.57284 -301.173928)
			(xy 300.56888 -301.124874) (xy 300.230032 -301.124874) (xy 300.229537 -301.149481) (xy 300.221642 -301.198058)
			(xy 300.206058 -301.244739) (xy 300.183187 -301.288316) (xy 300.153622 -301.32766) (xy 300.118129 -301.361752)
			(xy 300.077626 -301.389708) (xy 300.033164 -301.410806) (xy 299.985893 -301.424498) (xy 299.937038 -301.43043)
			(xy 299.887863 -301.428449) (xy 299.839644 -301.418605) (xy 299.793628 -301.401153) (xy 299.751007 -301.376546)
			(xy 299.712886 -301.345421) (xy 299.680251 -301.308584) (xy 299.653948 -301.266988) (xy 299.634657 -301.221712)
			(xy 299.62288 -301.173928) (xy 299.61892 -301.124874) (xy 299.280072 -301.124874) (xy 299.279577 -301.149481)
			(xy 299.271682 -301.198058) (xy 299.256098 -301.244739) (xy 299.233227 -301.288316) (xy 299.203662 -301.32766)
			(xy 299.168169 -301.361752) (xy 299.127666 -301.389708) (xy 299.083204 -301.410806) (xy 299.035933 -301.424498)
			(xy 298.987078 -301.43043) (xy 298.937903 -301.428449) (xy 298.889684 -301.418605) (xy 298.843668 -301.401153)
			(xy 298.801047 -301.376546) (xy 298.762926 -301.345421) (xy 298.730291 -301.308584) (xy 298.703988 -301.266988)
			(xy 298.684697 -301.221712) (xy 298.67292 -301.173928) (xy 298.66896 -301.124874) (xy 298.330112 -301.124874)
			(xy 298.329617 -301.149481) (xy 298.321722 -301.198058) (xy 298.306138 -301.244739) (xy 298.283267 -301.288316)
			(xy 298.253702 -301.32766) (xy 298.218209 -301.361752) (xy 298.177706 -301.389708) (xy 298.133244 -301.410806)
			(xy 298.085973 -301.424498) (xy 298.037118 -301.43043) (xy 297.987943 -301.428449) (xy 297.939724 -301.418605)
			(xy 297.893708 -301.401153) (xy 297.851087 -301.376546) (xy 297.812966 -301.345421) (xy 297.780331 -301.308584)
			(xy 297.754028 -301.266988) (xy 297.734737 -301.221712) (xy 297.72296 -301.173928) (xy 297.719 -301.124874)
			(xy 297.380152 -301.124874) (xy 297.379657 -301.149481) (xy 297.371762 -301.198058) (xy 297.356178 -301.244739)
			(xy 297.333307 -301.288316) (xy 297.303742 -301.32766) (xy 297.268249 -301.361752) (xy 297.227746 -301.389708)
			(xy 297.183284 -301.410806) (xy 297.136013 -301.424498) (xy 297.087158 -301.43043) (xy 297.037983 -301.428449)
			(xy 296.989764 -301.418605) (xy 296.943748 -301.401153) (xy 296.901127 -301.376546) (xy 296.863006 -301.345421)
			(xy 296.830371 -301.308584) (xy 296.804068 -301.266988) (xy 296.784777 -301.221712) (xy 296.773 -301.173928)
			(xy 296.76904 -301.124874) (xy 296.430192 -301.124874) (xy 296.429697 -301.149481) (xy 296.421802 -301.198058)
			(xy 296.406218 -301.244739) (xy 296.383347 -301.288316) (xy 296.353782 -301.32766) (xy 296.318289 -301.361752)
			(xy 296.277786 -301.389708) (xy 296.233324 -301.410806) (xy 296.186053 -301.424498) (xy 296.137198 -301.43043)
			(xy 296.088023 -301.428449) (xy 296.039804 -301.418605) (xy 295.993788 -301.401153) (xy 295.951167 -301.376546)
			(xy 295.913046 -301.345421) (xy 295.880411 -301.308584) (xy 295.854108 -301.266988) (xy 295.834817 -301.221712)
			(xy 295.82304 -301.173928) (xy 295.81908 -301.124874) (xy 295.480232 -301.124874) (xy 295.479737 -301.149481)
			(xy 295.471842 -301.198058) (xy 295.456258 -301.244739) (xy 295.433387 -301.288316) (xy 295.403822 -301.32766)
			(xy 295.368329 -301.361752) (xy 295.327826 -301.389708) (xy 295.283364 -301.410806) (xy 295.236093 -301.424498)
			(xy 295.187238 -301.43043) (xy 295.138063 -301.428449) (xy 295.089844 -301.418605) (xy 295.043828 -301.401153)
			(xy 295.001207 -301.376546) (xy 294.963086 -301.345421) (xy 294.930451 -301.308584) (xy 294.904148 -301.266988)
			(xy 294.884857 -301.221712) (xy 294.87308 -301.173928) (xy 294.86912 -301.124874) (xy 294.530018 -301.124874)
			(xy 294.529523 -301.149481) (xy 294.521628 -301.198058) (xy 294.506044 -301.244739) (xy 294.483173 -301.288316)
			(xy 294.453608 -301.32766) (xy 294.418115 -301.361752) (xy 294.377612 -301.389708) (xy 294.33315 -301.410806)
			(xy 294.285879 -301.424498) (xy 294.237024 -301.43043) (xy 294.187849 -301.428449) (xy 294.13963 -301.418605)
			(xy 294.093614 -301.401153) (xy 294.050993 -301.376546) (xy 294.012872 -301.345421) (xy 293.980237 -301.308584)
			(xy 293.953934 -301.266988) (xy 293.934643 -301.221712) (xy 293.922866 -301.173928) (xy 293.918906 -301.124874)
			(xy 293.580058 -301.124874) (xy 293.579563 -301.149481) (xy 293.571668 -301.198058) (xy 293.556084 -301.244739)
			(xy 293.533213 -301.288316) (xy 293.503648 -301.32766) (xy 293.468155 -301.361752) (xy 293.427652 -301.389708)
			(xy 293.38319 -301.410806) (xy 293.335919 -301.424498) (xy 293.287064 -301.43043) (xy 293.237889 -301.428449)
			(xy 293.18967 -301.418605) (xy 293.143654 -301.401153) (xy 293.101033 -301.376546) (xy 293.062912 -301.345421)
			(xy 293.030277 -301.308584) (xy 293.003974 -301.266988) (xy 292.984683 -301.221712) (xy 292.972906 -301.173928)
			(xy 292.968946 -301.124874) (xy 292.63062 -301.124874) (xy 292.630622 -301.124895) (xy 292.626576 -301.174478)
			(xy 292.614546 -301.222748) (xy 292.594848 -301.26843) (xy 292.568005 -301.310313) (xy 292.534727 -301.347291)
			(xy 292.495893 -301.378383) (xy 292.452533 -301.402769) (xy 292.405792 -301.419802) (xy 292.381432 -301.424848)
			(xy 292.38067 -301.425102) (xy 292.372018 -301.427057) (xy 292.356704 -301.435982) (xy 292.34536 -301.449601)
			(xy 292.339351 -301.466277) (xy 292.339014 -301.47514) (xy 292.339014 -301.724568) (xy 292.33964 -301.73641)
			(xy 292.350221 -301.7576) (xy 292.369136 -301.771857) (xy 292.38067 -301.774606) (xy 292.381432 -301.77486)
			(xy 292.405778 -301.779955) (xy 292.452509 -301.796985) (xy 292.495862 -301.821366) (xy 292.534687 -301.852453)
			(xy 292.567959 -301.889424) (xy 292.594797 -301.931299) (xy 292.61449 -301.976972) (xy 292.626518 -302.025233)
			(xy 292.630563 -302.074806) (xy 292.630561 -302.074834) (xy 292.968946 -302.074834) (xy 292.972906 -302.02578)
			(xy 292.984683 -301.977996) (xy 293.003974 -301.93272) (xy 293.030277 -301.891124) (xy 293.062912 -301.854287)
			(xy 293.101033 -301.823162) (xy 293.143654 -301.798555) (xy 293.18967 -301.781103) (xy 293.237889 -301.771259)
			(xy 293.287064 -301.769278) (xy 293.335919 -301.77521) (xy 293.38319 -301.788902) (xy 293.427652 -301.81)
			(xy 293.468155 -301.837956) (xy 293.503648 -301.872048) (xy 293.533213 -301.911392) (xy 293.556084 -301.954969)
			(xy 293.571668 -302.00165) (xy 293.579563 -302.050227) (xy 293.580058 -302.074834) (xy 293.918906 -302.074834)
			(xy 293.922866 -302.02578) (xy 293.934643 -301.977996) (xy 293.953934 -301.93272) (xy 293.980237 -301.891124)
			(xy 294.012872 -301.854287) (xy 294.050993 -301.823162) (xy 294.093614 -301.798555) (xy 294.13963 -301.781103)
			(xy 294.187849 -301.771259) (xy 294.237024 -301.769278) (xy 294.285879 -301.77521) (xy 294.33315 -301.788902)
			(xy 294.377612 -301.81) (xy 294.418115 -301.837956) (xy 294.453608 -301.872048) (xy 294.483173 -301.911392)
			(xy 294.506044 -301.954969) (xy 294.521628 -302.00165) (xy 294.529523 -302.050227) (xy 294.530018 -302.074834)
			(xy 294.86912 -302.074834) (xy 294.87308 -302.02578) (xy 294.884857 -301.977996) (xy 294.904148 -301.93272)
			(xy 294.930451 -301.891124) (xy 294.963086 -301.854287) (xy 295.001207 -301.823162) (xy 295.043828 -301.798555)
			(xy 295.089844 -301.781103) (xy 295.138063 -301.771259) (xy 295.187238 -301.769278) (xy 295.236093 -301.77521)
			(xy 295.283364 -301.788902) (xy 295.327826 -301.81) (xy 295.368329 -301.837956) (xy 295.403822 -301.872048)
			(xy 295.433387 -301.911392) (xy 295.456258 -301.954969) (xy 295.471842 -302.00165) (xy 295.479737 -302.050227)
			(xy 295.480232 -302.074834) (xy 295.81908 -302.074834) (xy 295.82304 -302.02578) (xy 295.834817 -301.977996)
			(xy 295.854108 -301.93272) (xy 295.880411 -301.891124) (xy 295.913046 -301.854287) (xy 295.951167 -301.823162)
			(xy 295.993788 -301.798555) (xy 296.039804 -301.781103) (xy 296.088023 -301.771259) (xy 296.137198 -301.769278)
			(xy 296.186053 -301.77521) (xy 296.233324 -301.788902) (xy 296.277786 -301.81) (xy 296.318289 -301.837956)
			(xy 296.353782 -301.872048) (xy 296.383347 -301.911392) (xy 296.406218 -301.954969) (xy 296.421802 -302.00165)
			(xy 296.429697 -302.050227) (xy 296.430192 -302.074834) (xy 296.76904 -302.074834) (xy 296.773 -302.02578)
			(xy 296.784777 -301.977996) (xy 296.804068 -301.93272) (xy 296.830371 -301.891124) (xy 296.863006 -301.854287)
			(xy 296.901127 -301.823162) (xy 296.943748 -301.798555) (xy 296.989764 -301.781103) (xy 297.037983 -301.771259)
			(xy 297.087158 -301.769278) (xy 297.136013 -301.77521) (xy 297.183284 -301.788902) (xy 297.227746 -301.81)
			(xy 297.268249 -301.837956) (xy 297.303742 -301.872048) (xy 297.333307 -301.911392) (xy 297.356178 -301.954969)
			(xy 297.371762 -302.00165) (xy 297.379657 -302.050227) (xy 297.380152 -302.074834) (xy 297.719 -302.074834)
			(xy 297.72296 -302.02578) (xy 297.734737 -301.977996) (xy 297.754028 -301.93272) (xy 297.780331 -301.891124)
			(xy 297.812966 -301.854287) (xy 297.851087 -301.823162) (xy 297.893708 -301.798555) (xy 297.939724 -301.781103)
			(xy 297.987943 -301.771259) (xy 298.037118 -301.769278) (xy 298.085973 -301.77521) (xy 298.133244 -301.788902)
			(xy 298.177706 -301.81) (xy 298.218209 -301.837956) (xy 298.253702 -301.872048) (xy 298.283267 -301.911392)
			(xy 298.306138 -301.954969) (xy 298.321722 -302.00165) (xy 298.329617 -302.050227) (xy 298.330112 -302.074834)
			(xy 298.66896 -302.074834) (xy 298.67292 -302.02578) (xy 298.684697 -301.977996) (xy 298.703988 -301.93272)
			(xy 298.730291 -301.891124) (xy 298.762926 -301.854287) (xy 298.801047 -301.823162) (xy 298.843668 -301.798555)
			(xy 298.889684 -301.781103) (xy 298.937903 -301.771259) (xy 298.987078 -301.769278) (xy 299.035933 -301.77521)
			(xy 299.083204 -301.788902) (xy 299.127666 -301.81) (xy 299.168169 -301.837956) (xy 299.203662 -301.872048)
			(xy 299.233227 -301.911392) (xy 299.256098 -301.954969) (xy 299.271682 -302.00165) (xy 299.279577 -302.050227)
			(xy 299.280072 -302.074834) (xy 299.61892 -302.074834) (xy 299.62288 -302.02578) (xy 299.634657 -301.977996)
			(xy 299.653948 -301.93272) (xy 299.680251 -301.891124) (xy 299.712886 -301.854287) (xy 299.751007 -301.823162)
			(xy 299.793628 -301.798555) (xy 299.839644 -301.781103) (xy 299.887863 -301.771259) (xy 299.937038 -301.769278)
			(xy 299.985893 -301.77521) (xy 300.033164 -301.788902) (xy 300.077626 -301.81) (xy 300.118129 -301.837956)
			(xy 300.153622 -301.872048) (xy 300.183187 -301.911392) (xy 300.206058 -301.954969) (xy 300.221642 -302.00165)
			(xy 300.229537 -302.050227) (xy 300.230032 -302.074834) (xy 300.56888 -302.074834) (xy 300.57284 -302.02578)
			(xy 300.584617 -301.977996) (xy 300.603908 -301.93272) (xy 300.630211 -301.891124) (xy 300.662846 -301.854287)
			(xy 300.700967 -301.823162) (xy 300.743588 -301.798555) (xy 300.789604 -301.781103) (xy 300.837823 -301.771259)
			(xy 300.886998 -301.769278) (xy 300.935853 -301.77521) (xy 300.983124 -301.788902) (xy 301.027586 -301.81)
			(xy 301.068089 -301.837956) (xy 301.103582 -301.872048) (xy 301.133147 -301.911392) (xy 301.156018 -301.954969)
			(xy 301.171602 -302.00165) (xy 301.179497 -302.050227) (xy 301.179992 -302.074834) (xy 301.519094 -302.074834)
			(xy 301.523054 -302.02578) (xy 301.534831 -301.977996) (xy 301.554122 -301.93272) (xy 301.580425 -301.891124)
			(xy 301.61306 -301.854287) (xy 301.651181 -301.823162) (xy 301.693802 -301.798555) (xy 301.739818 -301.781103)
			(xy 301.788037 -301.771259) (xy 301.837212 -301.769278) (xy 301.886067 -301.77521) (xy 301.933338 -301.788902)
			(xy 301.9778 -301.81) (xy 302.018303 -301.837956) (xy 302.053796 -301.872048) (xy 302.083361 -301.911392)
			(xy 302.106232 -301.954969) (xy 302.121816 -302.00165) (xy 302.129711 -302.050227) (xy 302.130206 -302.074834)
			(xy 302.469054 -302.074834) (xy 302.473014 -302.02578) (xy 302.484791 -301.977996) (xy 302.504082 -301.93272)
			(xy 302.530385 -301.891124) (xy 302.56302 -301.854287) (xy 302.601141 -301.823162) (xy 302.643762 -301.798555)
			(xy 302.689778 -301.781103) (xy 302.737997 -301.771259) (xy 302.787172 -301.769278) (xy 302.836027 -301.77521)
			(xy 302.883298 -301.788902) (xy 302.92776 -301.81) (xy 302.968263 -301.837956) (xy 303.003756 -301.872048)
			(xy 303.033321 -301.911392) (xy 303.056192 -301.954969) (xy 303.071776 -302.00165) (xy 303.079671 -302.050227)
			(xy 303.080166 -302.074834) (xy 303.419014 -302.074834) (xy 303.422974 -302.02578) (xy 303.434751 -301.977996)
			(xy 303.454042 -301.93272) (xy 303.480345 -301.891124) (xy 303.51298 -301.854287) (xy 303.551101 -301.823162)
			(xy 303.593722 -301.798555) (xy 303.639738 -301.781103) (xy 303.687957 -301.771259) (xy 303.737132 -301.769278)
			(xy 303.785987 -301.77521) (xy 303.833258 -301.788902) (xy 303.87772 -301.81) (xy 303.918223 -301.837956)
			(xy 303.953716 -301.872048) (xy 303.983281 -301.911392) (xy 304.006152 -301.954969) (xy 304.021736 -302.00165)
			(xy 304.029631 -302.050227) (xy 304.030126 -302.074834) (xy 304.368974 -302.074834) (xy 304.372934 -302.02578)
			(xy 304.384711 -301.977996) (xy 304.404002 -301.93272) (xy 304.430305 -301.891124) (xy 304.46294 -301.854287)
			(xy 304.501061 -301.823162) (xy 304.543682 -301.798555) (xy 304.589698 -301.781103) (xy 304.637917 -301.771259)
			(xy 304.687092 -301.769278) (xy 304.735947 -301.77521) (xy 304.783218 -301.788902) (xy 304.82768 -301.81)
			(xy 304.868183 -301.837956) (xy 304.903676 -301.872048) (xy 304.933241 -301.911392) (xy 304.956112 -301.954969)
			(xy 304.971696 -302.00165) (xy 304.979591 -302.050227) (xy 304.980086 -302.074834) (xy 305.318934 -302.074834)
			(xy 305.322894 -302.02578) (xy 305.334671 -301.977996) (xy 305.353962 -301.93272) (xy 305.380265 -301.891124)
			(xy 305.4129 -301.854287) (xy 305.451021 -301.823162) (xy 305.493642 -301.798555) (xy 305.539658 -301.781103)
			(xy 305.587877 -301.771259) (xy 305.637052 -301.769278) (xy 305.685907 -301.77521) (xy 305.733178 -301.788902)
			(xy 305.77764 -301.81) (xy 305.818143 -301.837956) (xy 305.853636 -301.872048) (xy 305.883201 -301.911392)
			(xy 305.906072 -301.954969) (xy 305.921656 -302.00165) (xy 305.929551 -302.050227) (xy 305.930046 -302.074834)
			(xy 306.268894 -302.074834) (xy 306.272854 -302.02578) (xy 306.284631 -301.977996) (xy 306.303922 -301.93272)
			(xy 306.330225 -301.891124) (xy 306.36286 -301.854287) (xy 306.400981 -301.823162) (xy 306.443602 -301.798555)
			(xy 306.489618 -301.781103) (xy 306.537837 -301.771259) (xy 306.587012 -301.769278) (xy 306.635867 -301.77521)
			(xy 306.683138 -301.788902) (xy 306.7276 -301.81) (xy 306.768103 -301.837956) (xy 306.803596 -301.872048)
			(xy 306.833161 -301.911392) (xy 306.856032 -301.954969) (xy 306.871616 -302.00165) (xy 306.879511 -302.050227)
			(xy 306.880006 -302.074834) (xy 307.219108 -302.074834) (xy 307.223068 -302.02578) (xy 307.234845 -301.977996)
			(xy 307.254136 -301.93272) (xy 307.280439 -301.891124) (xy 307.313074 -301.854287) (xy 307.351195 -301.823162)
			(xy 307.393816 -301.798555) (xy 307.439832 -301.781103) (xy 307.488051 -301.771259) (xy 307.537226 -301.769278)
			(xy 307.586081 -301.77521) (xy 307.633352 -301.788902) (xy 307.677814 -301.81) (xy 307.718317 -301.837956)
			(xy 307.75381 -301.872048) (xy 307.783375 -301.911392) (xy 307.806246 -301.954969) (xy 307.82183 -302.00165)
			(xy 307.829725 -302.050227) (xy 307.83022 -302.074834) (xy 308.169068 -302.074834) (xy 308.173028 -302.02578)
			(xy 308.184805 -301.977996) (xy 308.204096 -301.93272) (xy 308.230399 -301.891124) (xy 308.263034 -301.854287)
			(xy 308.301155 -301.823162) (xy 308.343776 -301.798555) (xy 308.389792 -301.781103) (xy 308.438011 -301.771259)
			(xy 308.487186 -301.769278) (xy 308.536041 -301.77521) (xy 308.583312 -301.788902) (xy 308.627774 -301.81)
			(xy 308.668277 -301.837956) (xy 308.70377 -301.872048) (xy 308.733335 -301.911392) (xy 308.756206 -301.954969)
			(xy 308.77179 -302.00165) (xy 308.779685 -302.050227) (xy 308.78018 -302.074834) (xy 309.119028 -302.074834)
			(xy 309.122988 -302.02578) (xy 309.134765 -301.977996) (xy 309.154056 -301.93272) (xy 309.180359 -301.891124)
			(xy 309.212994 -301.854287) (xy 309.251115 -301.823162) (xy 309.293736 -301.798555) (xy 309.339752 -301.781103)
			(xy 309.387971 -301.771259) (xy 309.437146 -301.769278) (xy 309.486001 -301.77521) (xy 309.533272 -301.788902)
			(xy 309.577734 -301.81) (xy 309.618237 -301.837956) (xy 309.65373 -301.872048) (xy 309.683295 -301.911392)
			(xy 309.706166 -301.954969) (xy 309.72175 -302.00165) (xy 309.729645 -302.050227) (xy 309.73014 -302.074834)
			(xy 310.068988 -302.074834) (xy 310.072948 -302.02578) (xy 310.084725 -301.977996) (xy 310.104016 -301.93272)
			(xy 310.130319 -301.891124) (xy 310.162954 -301.854287) (xy 310.201075 -301.823162) (xy 310.243696 -301.798555)
			(xy 310.289712 -301.781103) (xy 310.337931 -301.771259) (xy 310.387106 -301.769278) (xy 310.435961 -301.77521)
			(xy 310.483232 -301.788902) (xy 310.527694 -301.81) (xy 310.568197 -301.837956) (xy 310.60369 -301.872048)
			(xy 310.633255 -301.911392) (xy 310.656126 -301.954969) (xy 310.67171 -302.00165) (xy 310.679605 -302.050227)
			(xy 310.6801 -302.074834) (xy 311.018948 -302.074834) (xy 311.022908 -302.02578) (xy 311.034685 -301.977996)
			(xy 311.053976 -301.93272) (xy 311.080279 -301.891124) (xy 311.112914 -301.854287) (xy 311.151035 -301.823162)
			(xy 311.193656 -301.798555) (xy 311.239672 -301.781103) (xy 311.287891 -301.771259) (xy 311.337066 -301.769278)
			(xy 311.385921 -301.77521) (xy 311.433192 -301.788902) (xy 311.477654 -301.81) (xy 311.518157 -301.837956)
			(xy 311.55365 -301.872048) (xy 311.583215 -301.911392) (xy 311.606086 -301.954969) (xy 311.62167 -302.00165)
			(xy 311.629565 -302.050227) (xy 311.63006 -302.074834) (xy 311.968908 -302.074834) (xy 311.972868 -302.02578)
			(xy 311.984645 -301.977996) (xy 312.003936 -301.93272) (xy 312.030239 -301.891124) (xy 312.062874 -301.854287)
			(xy 312.100995 -301.823162) (xy 312.143616 -301.798555) (xy 312.189632 -301.781103) (xy 312.237851 -301.771259)
			(xy 312.287026 -301.769278) (xy 312.335881 -301.77521) (xy 312.383152 -301.788902) (xy 312.427614 -301.81)
			(xy 312.468117 -301.837956) (xy 312.50361 -301.872048) (xy 312.533175 -301.911392) (xy 312.556046 -301.954969)
			(xy 312.57163 -302.00165) (xy 312.579525 -302.050227) (xy 312.58002 -302.074834) (xy 312.919122 -302.074834)
			(xy 312.923082 -302.02578) (xy 312.934859 -301.977996) (xy 312.95415 -301.93272) (xy 312.980453 -301.891124)
			(xy 313.013088 -301.854287) (xy 313.051209 -301.823162) (xy 313.09383 -301.798555) (xy 313.139846 -301.781103)
			(xy 313.188065 -301.771259) (xy 313.23724 -301.769278) (xy 313.286095 -301.77521) (xy 313.333366 -301.788902)
			(xy 313.377828 -301.81) (xy 313.418331 -301.837956) (xy 313.453824 -301.872048) (xy 313.483389 -301.911392)
			(xy 313.50626 -301.954969) (xy 313.521844 -302.00165) (xy 313.529739 -302.050227) (xy 313.530234 -302.074834)
			(xy 313.869082 -302.074834) (xy 313.873042 -302.02578) (xy 313.884819 -301.977996) (xy 313.90411 -301.93272)
			(xy 313.930413 -301.891124) (xy 313.963048 -301.854287) (xy 314.001169 -301.823162) (xy 314.04379 -301.798555)
			(xy 314.089806 -301.781103) (xy 314.138025 -301.771259) (xy 314.1872 -301.769278) (xy 314.236055 -301.77521)
			(xy 314.283326 -301.788902) (xy 314.327788 -301.81) (xy 314.368291 -301.837956) (xy 314.403784 -301.872048)
			(xy 314.433349 -301.911392) (xy 314.45622 -301.954969) (xy 314.471804 -302.00165) (xy 314.479699 -302.050227)
			(xy 314.480194 -302.074834) (xy 314.819042 -302.074834) (xy 314.823002 -302.02578) (xy 314.834779 -301.977996)
			(xy 314.85407 -301.93272) (xy 314.880373 -301.891124) (xy 314.913008 -301.854287) (xy 314.951129 -301.823162)
			(xy 314.99375 -301.798555) (xy 315.039766 -301.781103) (xy 315.087985 -301.771259) (xy 315.13716 -301.769278)
			(xy 315.186015 -301.77521) (xy 315.233286 -301.788902) (xy 315.277748 -301.81) (xy 315.318251 -301.837956)
			(xy 315.353744 -301.872048) (xy 315.383309 -301.911392) (xy 315.40618 -301.954969) (xy 315.421764 -302.00165)
			(xy 315.429659 -302.050227) (xy 315.430154 -302.074834) (xy 315.429659 -302.099441) (xy 315.421764 -302.148018)
			(xy 315.40618 -302.194699) (xy 315.383309 -302.238276) (xy 315.353744 -302.27762) (xy 315.318251 -302.311712)
			(xy 315.277748 -302.339668) (xy 315.233286 -302.360766) (xy 315.186015 -302.374458) (xy 315.13716 -302.38039)
			(xy 315.087985 -302.378409) (xy 315.039766 -302.368565) (xy 314.99375 -302.351113) (xy 314.951129 -302.326506)
			(xy 314.913008 -302.295381) (xy 314.880373 -302.258544) (xy 314.85407 -302.216948) (xy 314.834779 -302.171672)
			(xy 314.823002 -302.123888) (xy 314.819042 -302.074834) (xy 314.480194 -302.074834) (xy 314.479699 -302.099441)
			(xy 314.471804 -302.148018) (xy 314.45622 -302.194699) (xy 314.433349 -302.238276) (xy 314.403784 -302.27762)
			(xy 314.368291 -302.311712) (xy 314.327788 -302.339668) (xy 314.283326 -302.360766) (xy 314.236055 -302.374458)
			(xy 314.1872 -302.38039) (xy 314.138025 -302.378409) (xy 314.089806 -302.368565) (xy 314.04379 -302.351113)
			(xy 314.001169 -302.326506) (xy 313.963048 -302.295381) (xy 313.930413 -302.258544) (xy 313.90411 -302.216948)
			(xy 313.884819 -302.171672) (xy 313.873042 -302.123888) (xy 313.869082 -302.074834) (xy 313.530234 -302.074834)
			(xy 313.529739 -302.099441) (xy 313.521844 -302.148018) (xy 313.50626 -302.194699) (xy 313.483389 -302.238276)
			(xy 313.453824 -302.27762) (xy 313.418331 -302.311712) (xy 313.377828 -302.339668) (xy 313.333366 -302.360766)
			(xy 313.286095 -302.374458) (xy 313.23724 -302.38039) (xy 313.188065 -302.378409) (xy 313.139846 -302.368565)
			(xy 313.09383 -302.351113) (xy 313.051209 -302.326506) (xy 313.013088 -302.295381) (xy 312.980453 -302.258544)
			(xy 312.95415 -302.216948) (xy 312.934859 -302.171672) (xy 312.923082 -302.123888) (xy 312.919122 -302.074834)
			(xy 312.58002 -302.074834) (xy 312.579525 -302.099441) (xy 312.57163 -302.148018) (xy 312.556046 -302.194699)
			(xy 312.533175 -302.238276) (xy 312.50361 -302.27762) (xy 312.468117 -302.311712) (xy 312.427614 -302.339668)
			(xy 312.383152 -302.360766) (xy 312.335881 -302.374458) (xy 312.287026 -302.38039) (xy 312.237851 -302.378409)
			(xy 312.189632 -302.368565) (xy 312.143616 -302.351113) (xy 312.100995 -302.326506) (xy 312.062874 -302.295381)
			(xy 312.030239 -302.258544) (xy 312.003936 -302.216948) (xy 311.984645 -302.171672) (xy 311.972868 -302.123888)
			(xy 311.968908 -302.074834) (xy 311.63006 -302.074834) (xy 311.629565 -302.099441) (xy 311.62167 -302.148018)
			(xy 311.606086 -302.194699) (xy 311.583215 -302.238276) (xy 311.55365 -302.27762) (xy 311.518157 -302.311712)
			(xy 311.477654 -302.339668) (xy 311.433192 -302.360766) (xy 311.385921 -302.374458) (xy 311.337066 -302.38039)
			(xy 311.287891 -302.378409) (xy 311.239672 -302.368565) (xy 311.193656 -302.351113) (xy 311.151035 -302.326506)
			(xy 311.112914 -302.295381) (xy 311.080279 -302.258544) (xy 311.053976 -302.216948) (xy 311.034685 -302.171672)
			(xy 311.022908 -302.123888) (xy 311.018948 -302.074834) (xy 310.6801 -302.074834) (xy 310.679605 -302.099441)
			(xy 310.67171 -302.148018) (xy 310.656126 -302.194699) (xy 310.633255 -302.238276) (xy 310.60369 -302.27762)
			(xy 310.568197 -302.311712) (xy 310.527694 -302.339668) (xy 310.483232 -302.360766) (xy 310.435961 -302.374458)
			(xy 310.387106 -302.38039) (xy 310.337931 -302.378409) (xy 310.289712 -302.368565) (xy 310.243696 -302.351113)
			(xy 310.201075 -302.326506) (xy 310.162954 -302.295381) (xy 310.130319 -302.258544) (xy 310.104016 -302.216948)
			(xy 310.084725 -302.171672) (xy 310.072948 -302.123888) (xy 310.068988 -302.074834) (xy 309.73014 -302.074834)
			(xy 309.729645 -302.099441) (xy 309.72175 -302.148018) (xy 309.706166 -302.194699) (xy 309.683295 -302.238276)
			(xy 309.65373 -302.27762) (xy 309.618237 -302.311712) (xy 309.577734 -302.339668) (xy 309.533272 -302.360766)
			(xy 309.486001 -302.374458) (xy 309.437146 -302.38039) (xy 309.387971 -302.378409) (xy 309.339752 -302.368565)
			(xy 309.293736 -302.351113) (xy 309.251115 -302.326506) (xy 309.212994 -302.295381) (xy 309.180359 -302.258544)
			(xy 309.154056 -302.216948) (xy 309.134765 -302.171672) (xy 309.122988 -302.123888) (xy 309.119028 -302.074834)
			(xy 308.78018 -302.074834) (xy 308.779685 -302.099441) (xy 308.77179 -302.148018) (xy 308.756206 -302.194699)
			(xy 308.733335 -302.238276) (xy 308.70377 -302.27762) (xy 308.668277 -302.311712) (xy 308.627774 -302.339668)
			(xy 308.583312 -302.360766) (xy 308.536041 -302.374458) (xy 308.487186 -302.38039) (xy 308.438011 -302.378409)
			(xy 308.389792 -302.368565) (xy 308.343776 -302.351113) (xy 308.301155 -302.326506) (xy 308.263034 -302.295381)
			(xy 308.230399 -302.258544) (xy 308.204096 -302.216948) (xy 308.184805 -302.171672) (xy 308.173028 -302.123888)
			(xy 308.169068 -302.074834) (xy 307.83022 -302.074834) (xy 307.829725 -302.099441) (xy 307.82183 -302.148018)
			(xy 307.806246 -302.194699) (xy 307.783375 -302.238276) (xy 307.75381 -302.27762) (xy 307.718317 -302.311712)
			(xy 307.677814 -302.339668) (xy 307.633352 -302.360766) (xy 307.586081 -302.374458) (xy 307.537226 -302.38039)
			(xy 307.488051 -302.378409) (xy 307.439832 -302.368565) (xy 307.393816 -302.351113) (xy 307.351195 -302.326506)
			(xy 307.313074 -302.295381) (xy 307.280439 -302.258544) (xy 307.254136 -302.216948) (xy 307.234845 -302.171672)
			(xy 307.223068 -302.123888) (xy 307.219108 -302.074834) (xy 306.880006 -302.074834) (xy 306.879511 -302.099441)
			(xy 306.871616 -302.148018) (xy 306.856032 -302.194699) (xy 306.833161 -302.238276) (xy 306.803596 -302.27762)
			(xy 306.768103 -302.311712) (xy 306.7276 -302.339668) (xy 306.683138 -302.360766) (xy 306.635867 -302.374458)
			(xy 306.587012 -302.38039) (xy 306.537837 -302.378409) (xy 306.489618 -302.368565) (xy 306.443602 -302.351113)
			(xy 306.400981 -302.326506) (xy 306.36286 -302.295381) (xy 306.330225 -302.258544) (xy 306.303922 -302.216948)
			(xy 306.284631 -302.171672) (xy 306.272854 -302.123888) (xy 306.268894 -302.074834) (xy 305.930046 -302.074834)
			(xy 305.929551 -302.099441) (xy 305.921656 -302.148018) (xy 305.906072 -302.194699) (xy 305.883201 -302.238276)
			(xy 305.853636 -302.27762) (xy 305.818143 -302.311712) (xy 305.77764 -302.339668) (xy 305.733178 -302.360766)
			(xy 305.685907 -302.374458) (xy 305.637052 -302.38039) (xy 305.587877 -302.378409) (xy 305.539658 -302.368565)
			(xy 305.493642 -302.351113) (xy 305.451021 -302.326506) (xy 305.4129 -302.295381) (xy 305.380265 -302.258544)
			(xy 305.353962 -302.216948) (xy 305.334671 -302.171672) (xy 305.322894 -302.123888) (xy 305.318934 -302.074834)
			(xy 304.980086 -302.074834) (xy 304.979591 -302.099441) (xy 304.971696 -302.148018) (xy 304.956112 -302.194699)
			(xy 304.933241 -302.238276) (xy 304.903676 -302.27762) (xy 304.868183 -302.311712) (xy 304.82768 -302.339668)
			(xy 304.783218 -302.360766) (xy 304.735947 -302.374458) (xy 304.687092 -302.38039) (xy 304.637917 -302.378409)
			(xy 304.589698 -302.368565) (xy 304.543682 -302.351113) (xy 304.501061 -302.326506) (xy 304.46294 -302.295381)
			(xy 304.430305 -302.258544) (xy 304.404002 -302.216948) (xy 304.384711 -302.171672) (xy 304.372934 -302.123888)
			(xy 304.368974 -302.074834) (xy 304.030126 -302.074834) (xy 304.029631 -302.099441) (xy 304.021736 -302.148018)
			(xy 304.006152 -302.194699) (xy 303.983281 -302.238276) (xy 303.953716 -302.27762) (xy 303.918223 -302.311712)
			(xy 303.87772 -302.339668) (xy 303.833258 -302.360766) (xy 303.785987 -302.374458) (xy 303.737132 -302.38039)
			(xy 303.687957 -302.378409) (xy 303.639738 -302.368565) (xy 303.593722 -302.351113) (xy 303.551101 -302.326506)
			(xy 303.51298 -302.295381) (xy 303.480345 -302.258544) (xy 303.454042 -302.216948) (xy 303.434751 -302.171672)
			(xy 303.422974 -302.123888) (xy 303.419014 -302.074834) (xy 303.080166 -302.074834) (xy 303.079671 -302.099441)
			(xy 303.071776 -302.148018) (xy 303.056192 -302.194699) (xy 303.033321 -302.238276) (xy 303.003756 -302.27762)
			(xy 302.968263 -302.311712) (xy 302.92776 -302.339668) (xy 302.883298 -302.360766) (xy 302.836027 -302.374458)
			(xy 302.787172 -302.38039) (xy 302.737997 -302.378409) (xy 302.689778 -302.368565) (xy 302.643762 -302.351113)
			(xy 302.601141 -302.326506) (xy 302.56302 -302.295381) (xy 302.530385 -302.258544) (xy 302.504082 -302.216948)
			(xy 302.484791 -302.171672) (xy 302.473014 -302.123888) (xy 302.469054 -302.074834) (xy 302.130206 -302.074834)
			(xy 302.129711 -302.099441) (xy 302.121816 -302.148018) (xy 302.106232 -302.194699) (xy 302.083361 -302.238276)
			(xy 302.053796 -302.27762) (xy 302.018303 -302.311712) (xy 301.9778 -302.339668) (xy 301.933338 -302.360766)
			(xy 301.886067 -302.374458) (xy 301.837212 -302.38039) (xy 301.788037 -302.378409) (xy 301.739818 -302.368565)
			(xy 301.693802 -302.351113) (xy 301.651181 -302.326506) (xy 301.61306 -302.295381) (xy 301.580425 -302.258544)
			(xy 301.554122 -302.216948) (xy 301.534831 -302.171672) (xy 301.523054 -302.123888) (xy 301.519094 -302.074834)
			(xy 301.179992 -302.074834) (xy 301.179497 -302.099441) (xy 301.171602 -302.148018) (xy 301.156018 -302.194699)
			(xy 301.133147 -302.238276) (xy 301.103582 -302.27762) (xy 301.068089 -302.311712) (xy 301.027586 -302.339668)
			(xy 300.983124 -302.360766) (xy 300.935853 -302.374458) (xy 300.886998 -302.38039) (xy 300.837823 -302.378409)
			(xy 300.789604 -302.368565) (xy 300.743588 -302.351113) (xy 300.700967 -302.326506) (xy 300.662846 -302.295381)
			(xy 300.630211 -302.258544) (xy 300.603908 -302.216948) (xy 300.584617 -302.171672) (xy 300.57284 -302.123888)
			(xy 300.56888 -302.074834) (xy 300.230032 -302.074834) (xy 300.229537 -302.099441) (xy 300.221642 -302.148018)
			(xy 300.206058 -302.194699) (xy 300.183187 -302.238276) (xy 300.153622 -302.27762) (xy 300.118129 -302.311712)
			(xy 300.077626 -302.339668) (xy 300.033164 -302.360766) (xy 299.985893 -302.374458) (xy 299.937038 -302.38039)
			(xy 299.887863 -302.378409) (xy 299.839644 -302.368565) (xy 299.793628 -302.351113) (xy 299.751007 -302.326506)
			(xy 299.712886 -302.295381) (xy 299.680251 -302.258544) (xy 299.653948 -302.216948) (xy 299.634657 -302.171672)
			(xy 299.62288 -302.123888) (xy 299.61892 -302.074834) (xy 299.280072 -302.074834) (xy 299.279577 -302.099441)
			(xy 299.271682 -302.148018) (xy 299.256098 -302.194699) (xy 299.233227 -302.238276) (xy 299.203662 -302.27762)
			(xy 299.168169 -302.311712) (xy 299.127666 -302.339668) (xy 299.083204 -302.360766) (xy 299.035933 -302.374458)
			(xy 298.987078 -302.38039) (xy 298.937903 -302.378409) (xy 298.889684 -302.368565) (xy 298.843668 -302.351113)
			(xy 298.801047 -302.326506) (xy 298.762926 -302.295381) (xy 298.730291 -302.258544) (xy 298.703988 -302.216948)
			(xy 298.684697 -302.171672) (xy 298.67292 -302.123888) (xy 298.66896 -302.074834) (xy 298.330112 -302.074834)
			(xy 298.329617 -302.099441) (xy 298.321722 -302.148018) (xy 298.306138 -302.194699) (xy 298.283267 -302.238276)
			(xy 298.253702 -302.27762) (xy 298.218209 -302.311712) (xy 298.177706 -302.339668) (xy 298.133244 -302.360766)
			(xy 298.085973 -302.374458) (xy 298.037118 -302.38039) (xy 297.987943 -302.378409) (xy 297.939724 -302.368565)
			(xy 297.893708 -302.351113) (xy 297.851087 -302.326506) (xy 297.812966 -302.295381) (xy 297.780331 -302.258544)
			(xy 297.754028 -302.216948) (xy 297.734737 -302.171672) (xy 297.72296 -302.123888) (xy 297.719 -302.074834)
			(xy 297.380152 -302.074834) (xy 297.379657 -302.099441) (xy 297.371762 -302.148018) (xy 297.356178 -302.194699)
			(xy 297.333307 -302.238276) (xy 297.303742 -302.27762) (xy 297.268249 -302.311712) (xy 297.227746 -302.339668)
			(xy 297.183284 -302.360766) (xy 297.136013 -302.374458) (xy 297.087158 -302.38039) (xy 297.037983 -302.378409)
			(xy 296.989764 -302.368565) (xy 296.943748 -302.351113) (xy 296.901127 -302.326506) (xy 296.863006 -302.295381)
			(xy 296.830371 -302.258544) (xy 296.804068 -302.216948) (xy 296.784777 -302.171672) (xy 296.773 -302.123888)
			(xy 296.76904 -302.074834) (xy 296.430192 -302.074834) (xy 296.429697 -302.099441) (xy 296.421802 -302.148018)
			(xy 296.406218 -302.194699) (xy 296.383347 -302.238276) (xy 296.353782 -302.27762) (xy 296.318289 -302.311712)
			(xy 296.277786 -302.339668) (xy 296.233324 -302.360766) (xy 296.186053 -302.374458) (xy 296.137198 -302.38039)
			(xy 296.088023 -302.378409) (xy 296.039804 -302.368565) (xy 295.993788 -302.351113) (xy 295.951167 -302.326506)
			(xy 295.913046 -302.295381) (xy 295.880411 -302.258544) (xy 295.854108 -302.216948) (xy 295.834817 -302.171672)
			(xy 295.82304 -302.123888) (xy 295.81908 -302.074834) (xy 295.480232 -302.074834) (xy 295.479737 -302.099441)
			(xy 295.471842 -302.148018) (xy 295.456258 -302.194699) (xy 295.433387 -302.238276) (xy 295.403822 -302.27762)
			(xy 295.368329 -302.311712) (xy 295.327826 -302.339668) (xy 295.283364 -302.360766) (xy 295.236093 -302.374458)
			(xy 295.187238 -302.38039) (xy 295.138063 -302.378409) (xy 295.089844 -302.368565) (xy 295.043828 -302.351113)
			(xy 295.001207 -302.326506) (xy 294.963086 -302.295381) (xy 294.930451 -302.258544) (xy 294.904148 -302.216948)
			(xy 294.884857 -302.171672) (xy 294.87308 -302.123888) (xy 294.86912 -302.074834) (xy 294.530018 -302.074834)
			(xy 294.529523 -302.099441) (xy 294.521628 -302.148018) (xy 294.506044 -302.194699) (xy 294.483173 -302.238276)
			(xy 294.453608 -302.27762) (xy 294.418115 -302.311712) (xy 294.377612 -302.339668) (xy 294.33315 -302.360766)
			(xy 294.285879 -302.374458) (xy 294.237024 -302.38039) (xy 294.187849 -302.378409) (xy 294.13963 -302.368565)
			(xy 294.093614 -302.351113) (xy 294.050993 -302.326506) (xy 294.012872 -302.295381) (xy 293.980237 -302.258544)
			(xy 293.953934 -302.216948) (xy 293.934643 -302.171672) (xy 293.922866 -302.123888) (xy 293.918906 -302.074834)
			(xy 293.580058 -302.074834) (xy 293.579563 -302.099441) (xy 293.571668 -302.148018) (xy 293.556084 -302.194699)
			(xy 293.533213 -302.238276) (xy 293.503648 -302.27762) (xy 293.468155 -302.311712) (xy 293.427652 -302.339668)
			(xy 293.38319 -302.360766) (xy 293.335919 -302.374458) (xy 293.287064 -302.38039) (xy 293.237889 -302.378409)
			(xy 293.18967 -302.368565) (xy 293.143654 -302.351113) (xy 293.101033 -302.326506) (xy 293.062912 -302.295381)
			(xy 293.030277 -302.258544) (xy 293.003974 -302.216948) (xy 292.984683 -302.171672) (xy 292.972906 -302.123888)
			(xy 292.968946 -302.074834) (xy 292.630561 -302.074834) (xy 292.626516 -302.124379) (xy 292.614486 -302.17264)
			(xy 292.594791 -302.218312) (xy 292.567951 -302.260186) (xy 292.534678 -302.297155) (xy 292.495851 -302.328241)
			(xy 292.452498 -302.35262) (xy 292.405766 -302.369648) (xy 292.381432 -302.374808) (xy 292.38067 -302.375062)
			(xy 292.372014 -302.377016) (xy 292.356693 -302.385939) (xy 292.345339 -302.399557) (xy 292.339318 -302.416234)
			(xy 292.339014 -302.4251) (xy 292.339014 -302.693324) (xy 292.362128 -302.721264) (xy 292.380416 -302.724566)
			(xy 292.406061 -302.729865) (xy 292.455167 -302.748043) (xy 292.500454 -302.774329) (xy 292.540595 -302.807953)
			(xy 292.574414 -302.84793) (xy 292.60092 -302.893088) (xy 292.619336 -302.942105) (xy 292.629124 -302.993545)
			(xy 292.630098 -303.019714) (xy 292.630098 -303.024032) (xy 292.630083 -303.024794) (xy 292.968946 -303.024794)
			(xy 292.972906 -302.97574) (xy 292.984683 -302.927956) (xy 293.003974 -302.88268) (xy 293.030277 -302.841084)
			(xy 293.062912 -302.804247) (xy 293.101033 -302.773122) (xy 293.143654 -302.748515) (xy 293.18967 -302.731063)
			(xy 293.237889 -302.721219) (xy 293.287064 -302.719238) (xy 293.335919 -302.72517) (xy 293.38319 -302.738862)
			(xy 293.427652 -302.75996) (xy 293.468155 -302.787916) (xy 293.503648 -302.822008) (xy 293.533213 -302.861352)
			(xy 293.556084 -302.904929) (xy 293.571668 -302.95161) (xy 293.579563 -303.000187) (xy 293.580058 -303.024794)
			(xy 293.918906 -303.024794) (xy 293.922866 -302.97574) (xy 293.934643 -302.927956) (xy 293.953934 -302.88268)
			(xy 293.980237 -302.841084) (xy 294.012872 -302.804247) (xy 294.050993 -302.773122) (xy 294.093614 -302.748515)
			(xy 294.13963 -302.731063) (xy 294.187849 -302.721219) (xy 294.237024 -302.719238) (xy 294.285879 -302.72517)
			(xy 294.33315 -302.738862) (xy 294.377612 -302.75996) (xy 294.418115 -302.787916) (xy 294.453608 -302.822008)
			(xy 294.483173 -302.861352) (xy 294.506044 -302.904929) (xy 294.521628 -302.95161) (xy 294.529523 -303.000187)
			(xy 294.530018 -303.024794) (xy 294.86912 -303.024794) (xy 294.87308 -302.97574) (xy 294.884857 -302.927956)
			(xy 294.904148 -302.88268) (xy 294.930451 -302.841084) (xy 294.963086 -302.804247) (xy 295.001207 -302.773122)
			(xy 295.043828 -302.748515) (xy 295.089844 -302.731063) (xy 295.138063 -302.721219) (xy 295.187238 -302.719238)
			(xy 295.236093 -302.72517) (xy 295.283364 -302.738862) (xy 295.327826 -302.75996) (xy 295.368329 -302.787916)
			(xy 295.403822 -302.822008) (xy 295.433387 -302.861352) (xy 295.456258 -302.904929) (xy 295.471842 -302.95161)
			(xy 295.479737 -303.000187) (xy 295.480232 -303.024794) (xy 295.81908 -303.024794) (xy 295.82304 -302.97574)
			(xy 295.834817 -302.927956) (xy 295.854108 -302.88268) (xy 295.880411 -302.841084) (xy 295.913046 -302.804247)
			(xy 295.951167 -302.773122) (xy 295.993788 -302.748515) (xy 296.039804 -302.731063) (xy 296.088023 -302.721219)
			(xy 296.137198 -302.719238) (xy 296.186053 -302.72517) (xy 296.233324 -302.738862) (xy 296.277786 -302.75996)
			(xy 296.318289 -302.787916) (xy 296.353782 -302.822008) (xy 296.383347 -302.861352) (xy 296.406218 -302.904929)
			(xy 296.421802 -302.95161) (xy 296.429697 -303.000187) (xy 296.430192 -303.024794) (xy 296.76904 -303.024794)
			(xy 296.773 -302.97574) (xy 296.784777 -302.927956) (xy 296.804068 -302.88268) (xy 296.830371 -302.841084)
			(xy 296.863006 -302.804247) (xy 296.901127 -302.773122) (xy 296.943748 -302.748515) (xy 296.989764 -302.731063)
			(xy 297.037983 -302.721219) (xy 297.087158 -302.719238) (xy 297.136013 -302.72517) (xy 297.183284 -302.738862)
			(xy 297.227746 -302.75996) (xy 297.268249 -302.787916) (xy 297.303742 -302.822008) (xy 297.333307 -302.861352)
			(xy 297.356178 -302.904929) (xy 297.371762 -302.95161) (xy 297.379657 -303.000187) (xy 297.380152 -303.024794)
			(xy 297.719 -303.024794) (xy 297.72296 -302.97574) (xy 297.734737 -302.927956) (xy 297.754028 -302.88268)
			(xy 297.780331 -302.841084) (xy 297.812966 -302.804247) (xy 297.851087 -302.773122) (xy 297.893708 -302.748515)
			(xy 297.939724 -302.731063) (xy 297.987943 -302.721219) (xy 298.037118 -302.719238) (xy 298.085973 -302.72517)
			(xy 298.133244 -302.738862) (xy 298.177706 -302.75996) (xy 298.218209 -302.787916) (xy 298.253702 -302.822008)
			(xy 298.283267 -302.861352) (xy 298.306138 -302.904929) (xy 298.321722 -302.95161) (xy 298.329617 -303.000187)
			(xy 298.330112 -303.024794) (xy 298.66896 -303.024794) (xy 298.67292 -302.97574) (xy 298.684697 -302.927956)
			(xy 298.703988 -302.88268) (xy 298.730291 -302.841084) (xy 298.762926 -302.804247) (xy 298.801047 -302.773122)
			(xy 298.843668 -302.748515) (xy 298.889684 -302.731063) (xy 298.937903 -302.721219) (xy 298.987078 -302.719238)
			(xy 299.035933 -302.72517) (xy 299.083204 -302.738862) (xy 299.127666 -302.75996) (xy 299.168169 -302.787916)
			(xy 299.203662 -302.822008) (xy 299.233227 -302.861352) (xy 299.256098 -302.904929) (xy 299.271682 -302.95161)
			(xy 299.279577 -303.000187) (xy 299.280072 -303.024794) (xy 299.61892 -303.024794) (xy 299.62288 -302.97574)
			(xy 299.634657 -302.927956) (xy 299.653948 -302.88268) (xy 299.680251 -302.841084) (xy 299.712886 -302.804247)
			(xy 299.751007 -302.773122) (xy 299.793628 -302.748515) (xy 299.839644 -302.731063) (xy 299.887863 -302.721219)
			(xy 299.937038 -302.719238) (xy 299.985893 -302.72517) (xy 300.033164 -302.738862) (xy 300.077626 -302.75996)
			(xy 300.118129 -302.787916) (xy 300.153622 -302.822008) (xy 300.183187 -302.861352) (xy 300.206058 -302.904929)
			(xy 300.221642 -302.95161) (xy 300.229537 -303.000187) (xy 300.230032 -303.024794) (xy 300.56888 -303.024794)
			(xy 300.57284 -302.97574) (xy 300.584617 -302.927956) (xy 300.603908 -302.88268) (xy 300.630211 -302.841084)
			(xy 300.662846 -302.804247) (xy 300.700967 -302.773122) (xy 300.743588 -302.748515) (xy 300.789604 -302.731063)
			(xy 300.837823 -302.721219) (xy 300.886998 -302.719238) (xy 300.935853 -302.72517) (xy 300.983124 -302.738862)
			(xy 301.027586 -302.75996) (xy 301.068089 -302.787916) (xy 301.103582 -302.822008) (xy 301.133147 -302.861352)
			(xy 301.156018 -302.904929) (xy 301.171602 -302.95161) (xy 301.179497 -303.000187) (xy 301.179992 -303.024794)
			(xy 301.519094 -303.024794) (xy 301.523054 -302.97574) (xy 301.534831 -302.927956) (xy 301.554122 -302.88268)
			(xy 301.580425 -302.841084) (xy 301.61306 -302.804247) (xy 301.651181 -302.773122) (xy 301.693802 -302.748515)
			(xy 301.739818 -302.731063) (xy 301.788037 -302.721219) (xy 301.837212 -302.719238) (xy 301.886067 -302.72517)
			(xy 301.933338 -302.738862) (xy 301.9778 -302.75996) (xy 302.018303 -302.787916) (xy 302.053796 -302.822008)
			(xy 302.083361 -302.861352) (xy 302.106232 -302.904929) (xy 302.121816 -302.95161) (xy 302.129711 -303.000187)
			(xy 302.130206 -303.024794) (xy 302.469054 -303.024794) (xy 302.473014 -302.97574) (xy 302.484791 -302.927956)
			(xy 302.504082 -302.88268) (xy 302.530385 -302.841084) (xy 302.56302 -302.804247) (xy 302.601141 -302.773122)
			(xy 302.643762 -302.748515) (xy 302.689778 -302.731063) (xy 302.737997 -302.721219) (xy 302.787172 -302.719238)
			(xy 302.836027 -302.72517) (xy 302.883298 -302.738862) (xy 302.92776 -302.75996) (xy 302.968263 -302.787916)
			(xy 303.003756 -302.822008) (xy 303.033321 -302.861352) (xy 303.056192 -302.904929) (xy 303.071776 -302.95161)
			(xy 303.079671 -303.000187) (xy 303.080166 -303.024794) (xy 303.419014 -303.024794) (xy 303.422974 -302.97574)
			(xy 303.434751 -302.927956) (xy 303.454042 -302.88268) (xy 303.480345 -302.841084) (xy 303.51298 -302.804247)
			(xy 303.551101 -302.773122) (xy 303.593722 -302.748515) (xy 303.639738 -302.731063) (xy 303.687957 -302.721219)
			(xy 303.737132 -302.719238) (xy 303.785987 -302.72517) (xy 303.833258 -302.738862) (xy 303.87772 -302.75996)
			(xy 303.918223 -302.787916) (xy 303.953716 -302.822008) (xy 303.983281 -302.861352) (xy 304.006152 -302.904929)
			(xy 304.021736 -302.95161) (xy 304.029631 -303.000187) (xy 304.030126 -303.024794) (xy 304.368974 -303.024794)
			(xy 304.372934 -302.97574) (xy 304.384711 -302.927956) (xy 304.404002 -302.88268) (xy 304.430305 -302.841084)
			(xy 304.46294 -302.804247) (xy 304.501061 -302.773122) (xy 304.543682 -302.748515) (xy 304.589698 -302.731063)
			(xy 304.637917 -302.721219) (xy 304.687092 -302.719238) (xy 304.735947 -302.72517) (xy 304.783218 -302.738862)
			(xy 304.82768 -302.75996) (xy 304.868183 -302.787916) (xy 304.903676 -302.822008) (xy 304.933241 -302.861352)
			(xy 304.956112 -302.904929) (xy 304.971696 -302.95161) (xy 304.979591 -303.000187) (xy 304.980086 -303.024794)
			(xy 305.318934 -303.024794) (xy 305.322894 -302.97574) (xy 305.334671 -302.927956) (xy 305.353962 -302.88268)
			(xy 305.380265 -302.841084) (xy 305.4129 -302.804247) (xy 305.451021 -302.773122) (xy 305.493642 -302.748515)
			(xy 305.539658 -302.731063) (xy 305.587877 -302.721219) (xy 305.637052 -302.719238) (xy 305.685907 -302.72517)
			(xy 305.733178 -302.738862) (xy 305.77764 -302.75996) (xy 305.818143 -302.787916) (xy 305.853636 -302.822008)
			(xy 305.883201 -302.861352) (xy 305.906072 -302.904929) (xy 305.921656 -302.95161) (xy 305.929551 -303.000187)
			(xy 305.930046 -303.024794) (xy 305.929551 -303.049401) (xy 305.921656 -303.097978) (xy 305.906072 -303.144659)
			(xy 305.883201 -303.188236) (xy 305.853636 -303.22758) (xy 305.818143 -303.261672) (xy 305.77764 -303.289628)
			(xy 305.733178 -303.310726) (xy 305.685907 -303.324418) (xy 305.637052 -303.33035) (xy 305.587877 -303.328369)
			(xy 305.539658 -303.318525) (xy 305.493642 -303.301073) (xy 305.451021 -303.276466) (xy 305.4129 -303.245341)
			(xy 305.380265 -303.208504) (xy 305.353962 -303.166908) (xy 305.334671 -303.121632) (xy 305.322894 -303.073848)
			(xy 305.318934 -303.024794) (xy 304.980086 -303.024794) (xy 304.979591 -303.049401) (xy 304.971696 -303.097978)
			(xy 304.956112 -303.144659) (xy 304.933241 -303.188236) (xy 304.903676 -303.22758) (xy 304.868183 -303.261672)
			(xy 304.82768 -303.289628) (xy 304.783218 -303.310726) (xy 304.735947 -303.324418) (xy 304.687092 -303.33035)
			(xy 304.637917 -303.328369) (xy 304.589698 -303.318525) (xy 304.543682 -303.301073) (xy 304.501061 -303.276466)
			(xy 304.46294 -303.245341) (xy 304.430305 -303.208504) (xy 304.404002 -303.166908) (xy 304.384711 -303.121632)
			(xy 304.372934 -303.073848) (xy 304.368974 -303.024794) (xy 304.030126 -303.024794) (xy 304.029631 -303.049401)
			(xy 304.021736 -303.097978) (xy 304.006152 -303.144659) (xy 303.983281 -303.188236) (xy 303.953716 -303.22758)
			(xy 303.918223 -303.261672) (xy 303.87772 -303.289628) (xy 303.833258 -303.310726) (xy 303.785987 -303.324418)
			(xy 303.737132 -303.33035) (xy 303.687957 -303.328369) (xy 303.639738 -303.318525) (xy 303.593722 -303.301073)
			(xy 303.551101 -303.276466) (xy 303.51298 -303.245341) (xy 303.480345 -303.208504) (xy 303.454042 -303.166908)
			(xy 303.434751 -303.121632) (xy 303.422974 -303.073848) (xy 303.419014 -303.024794) (xy 303.080166 -303.024794)
			(xy 303.079671 -303.049401) (xy 303.071776 -303.097978) (xy 303.056192 -303.144659) (xy 303.033321 -303.188236)
			(xy 303.003756 -303.22758) (xy 302.968263 -303.261672) (xy 302.92776 -303.289628) (xy 302.883298 -303.310726)
			(xy 302.836027 -303.324418) (xy 302.787172 -303.33035) (xy 302.737997 -303.328369) (xy 302.689778 -303.318525)
			(xy 302.643762 -303.301073) (xy 302.601141 -303.276466) (xy 302.56302 -303.245341) (xy 302.530385 -303.208504)
			(xy 302.504082 -303.166908) (xy 302.484791 -303.121632) (xy 302.473014 -303.073848) (xy 302.469054 -303.024794)
			(xy 302.130206 -303.024794) (xy 302.129711 -303.049401) (xy 302.121816 -303.097978) (xy 302.106232 -303.144659)
			(xy 302.083361 -303.188236) (xy 302.053796 -303.22758) (xy 302.018303 -303.261672) (xy 301.9778 -303.289628)
			(xy 301.933338 -303.310726) (xy 301.886067 -303.324418) (xy 301.837212 -303.33035) (xy 301.788037 -303.328369)
			(xy 301.739818 -303.318525) (xy 301.693802 -303.301073) (xy 301.651181 -303.276466) (xy 301.61306 -303.245341)
			(xy 301.580425 -303.208504) (xy 301.554122 -303.166908) (xy 301.534831 -303.121632) (xy 301.523054 -303.073848)
			(xy 301.519094 -303.024794) (xy 301.179992 -303.024794) (xy 301.179497 -303.049401) (xy 301.171602 -303.097978)
			(xy 301.156018 -303.144659) (xy 301.133147 -303.188236) (xy 301.103582 -303.22758) (xy 301.068089 -303.261672)
			(xy 301.027586 -303.289628) (xy 300.983124 -303.310726) (xy 300.935853 -303.324418) (xy 300.886998 -303.33035)
			(xy 300.837823 -303.328369) (xy 300.789604 -303.318525) (xy 300.743588 -303.301073) (xy 300.700967 -303.276466)
			(xy 300.662846 -303.245341) (xy 300.630211 -303.208504) (xy 300.603908 -303.166908) (xy 300.584617 -303.121632)
			(xy 300.57284 -303.073848) (xy 300.56888 -303.024794) (xy 300.230032 -303.024794) (xy 300.229537 -303.049401)
			(xy 300.221642 -303.097978) (xy 300.206058 -303.144659) (xy 300.183187 -303.188236) (xy 300.153622 -303.22758)
			(xy 300.118129 -303.261672) (xy 300.077626 -303.289628) (xy 300.033164 -303.310726) (xy 299.985893 -303.324418)
			(xy 299.937038 -303.33035) (xy 299.887863 -303.328369) (xy 299.839644 -303.318525) (xy 299.793628 -303.301073)
			(xy 299.751007 -303.276466) (xy 299.712886 -303.245341) (xy 299.680251 -303.208504) (xy 299.653948 -303.166908)
			(xy 299.634657 -303.121632) (xy 299.62288 -303.073848) (xy 299.61892 -303.024794) (xy 299.280072 -303.024794)
			(xy 299.279577 -303.049401) (xy 299.271682 -303.097978) (xy 299.256098 -303.144659) (xy 299.233227 -303.188236)
			(xy 299.203662 -303.22758) (xy 299.168169 -303.261672) (xy 299.127666 -303.289628) (xy 299.083204 -303.310726)
			(xy 299.035933 -303.324418) (xy 298.987078 -303.33035) (xy 298.937903 -303.328369) (xy 298.889684 -303.318525)
			(xy 298.843668 -303.301073) (xy 298.801047 -303.276466) (xy 298.762926 -303.245341) (xy 298.730291 -303.208504)
			(xy 298.703988 -303.166908) (xy 298.684697 -303.121632) (xy 298.67292 -303.073848) (xy 298.66896 -303.024794)
			(xy 298.330112 -303.024794) (xy 298.329617 -303.049401) (xy 298.321722 -303.097978) (xy 298.306138 -303.144659)
			(xy 298.283267 -303.188236) (xy 298.253702 -303.22758) (xy 298.218209 -303.261672) (xy 298.177706 -303.289628)
			(xy 298.133244 -303.310726) (xy 298.085973 -303.324418) (xy 298.037118 -303.33035) (xy 297.987943 -303.328369)
			(xy 297.939724 -303.318525) (xy 297.893708 -303.301073) (xy 297.851087 -303.276466) (xy 297.812966 -303.245341)
			(xy 297.780331 -303.208504) (xy 297.754028 -303.166908) (xy 297.734737 -303.121632) (xy 297.72296 -303.073848)
			(xy 297.719 -303.024794) (xy 297.380152 -303.024794) (xy 297.379657 -303.049401) (xy 297.371762 -303.097978)
			(xy 297.356178 -303.144659) (xy 297.333307 -303.188236) (xy 297.303742 -303.22758) (xy 297.268249 -303.261672)
			(xy 297.227746 -303.289628) (xy 297.183284 -303.310726) (xy 297.136013 -303.324418) (xy 297.087158 -303.33035)
			(xy 297.037983 -303.328369) (xy 296.989764 -303.318525) (xy 296.943748 -303.301073) (xy 296.901127 -303.276466)
			(xy 296.863006 -303.245341) (xy 296.830371 -303.208504) (xy 296.804068 -303.166908) (xy 296.784777 -303.121632)
			(xy 296.773 -303.073848) (xy 296.76904 -303.024794) (xy 296.430192 -303.024794) (xy 296.429697 -303.049401)
			(xy 296.421802 -303.097978) (xy 296.406218 -303.144659) (xy 296.383347 -303.188236) (xy 296.353782 -303.22758)
			(xy 296.318289 -303.261672) (xy 296.277786 -303.289628) (xy 296.233324 -303.310726) (xy 296.186053 -303.324418)
			(xy 296.137198 -303.33035) (xy 296.088023 -303.328369) (xy 296.039804 -303.318525) (xy 295.993788 -303.301073)
			(xy 295.951167 -303.276466) (xy 295.913046 -303.245341) (xy 295.880411 -303.208504) (xy 295.854108 -303.166908)
			(xy 295.834817 -303.121632) (xy 295.82304 -303.073848) (xy 295.81908 -303.024794) (xy 295.480232 -303.024794)
			(xy 295.479737 -303.049401) (xy 295.471842 -303.097978) (xy 295.456258 -303.144659) (xy 295.433387 -303.188236)
			(xy 295.403822 -303.22758) (xy 295.368329 -303.261672) (xy 295.327826 -303.289628) (xy 295.283364 -303.310726)
			(xy 295.236093 -303.324418) (xy 295.187238 -303.33035) (xy 295.138063 -303.328369) (xy 295.089844 -303.318525)
			(xy 295.043828 -303.301073) (xy 295.001207 -303.276466) (xy 294.963086 -303.245341) (xy 294.930451 -303.208504)
			(xy 294.904148 -303.166908) (xy 294.884857 -303.121632) (xy 294.87308 -303.073848) (xy 294.86912 -303.024794)
			(xy 294.530018 -303.024794) (xy 294.529523 -303.049401) (xy 294.521628 -303.097978) (xy 294.506044 -303.144659)
			(xy 294.483173 -303.188236) (xy 294.453608 -303.22758) (xy 294.418115 -303.261672) (xy 294.377612 -303.289628)
			(xy 294.33315 -303.310726) (xy 294.285879 -303.324418) (xy 294.237024 -303.33035) (xy 294.187849 -303.328369)
			(xy 294.13963 -303.318525) (xy 294.093614 -303.301073) (xy 294.050993 -303.276466) (xy 294.012872 -303.245341)
			(xy 293.980237 -303.208504) (xy 293.953934 -303.166908) (xy 293.934643 -303.121632) (xy 293.922866 -303.073848)
			(xy 293.918906 -303.024794) (xy 293.580058 -303.024794) (xy 293.579563 -303.049401) (xy 293.571668 -303.097978)
			(xy 293.556084 -303.144659) (xy 293.533213 -303.188236) (xy 293.503648 -303.22758) (xy 293.468155 -303.261672)
			(xy 293.427652 -303.289628) (xy 293.38319 -303.310726) (xy 293.335919 -303.324418) (xy 293.287064 -303.33035)
			(xy 293.237889 -303.328369) (xy 293.18967 -303.318525) (xy 293.143654 -303.301073) (xy 293.101033 -303.276466)
			(xy 293.062912 -303.245341) (xy 293.030277 -303.208504) (xy 293.003974 -303.166908) (xy 292.984683 -303.121632)
			(xy 292.972906 -303.073848) (xy 292.968946 -303.024794) (xy 292.630083 -303.024794) (xy 292.629566 -303.051259)
			(xy 292.620057 -303.104874) (xy 292.601221 -303.155964) (xy 292.587934 -303.179734) (xy 292.582771 -303.1897)
			(xy 292.580711 -303.212024) (xy 292.588294 -303.233121) (xy 292.595808 -303.241456) (xy 292.847268 -303.492916)
			(xy 292.853615 -303.499774) (xy 306.744128 -303.499774) (xy 306.748088 -303.45072) (xy 306.759865 -303.402936)
			(xy 306.779156 -303.35766) (xy 306.805459 -303.316064) (xy 306.838094 -303.279227) (xy 306.876215 -303.248102)
			(xy 306.918836 -303.223495) (xy 306.964852 -303.206043) (xy 307.013071 -303.196199) (xy 307.062246 -303.194218)
			(xy 307.111101 -303.20015) (xy 307.158372 -303.213842) (xy 307.202834 -303.23494) (xy 307.243337 -303.262896)
			(xy 307.27883 -303.296988) (xy 307.308395 -303.336332) (xy 307.331266 -303.379909) (xy 307.34685 -303.42659)
			(xy 307.354745 -303.475167) (xy 307.355074 -303.491531) (xy 307.694155 -303.491531) (xy 307.69952 -303.442176)
			(xy 307.7128 -303.394338) (xy 307.733644 -303.349279) (xy 307.761504 -303.308186) (xy 307.795644 -303.272142)
			(xy 307.835167 -303.242096) (xy 307.879029 -303.21884) (xy 307.926076 -303.202986) (xy 307.975069 -303.194953)
			(xy 307.999892 -303.194466) (xy 308.014075 -303.194644) (xy 308.042315 -303.197315) (xy 308.05628 -303.1998)
			(xy 308.070247 -303.201963) (xy 308.09838 -303.199389) (xy 308.124731 -303.189201) (xy 308.14728 -303.172181)
			(xy 308.1643 -303.149632) (xy 308.174488 -303.123282) (xy 308.177063 -303.095148) (xy 308.174898 -303.081182)
			(xy 308.172423 -303.067216) (xy 308.16975 -303.038976) (xy 308.169564 -303.024794) (xy 308.170084 -302.999973)
			(xy 308.178117 -302.950986) (xy 308.193968 -302.903943) (xy 308.217222 -302.860085) (xy 308.247265 -302.820567)
			(xy 308.283306 -302.78643) (xy 308.324394 -302.758573) (xy 308.369448 -302.737731) (xy 308.417281 -302.724452)
			(xy 308.466632 -302.719087) (xy 308.5162 -302.721777) (xy 308.564681 -302.73245) (xy 308.610796 -302.750827)
			(xy 308.65333 -302.776422) (xy 308.691163 -302.808561) (xy 308.723298 -302.846398) (xy 308.748888 -302.888935)
			(xy 308.76726 -302.935052) (xy 308.777928 -302.983534) (xy 308.780162 -303.024794) (xy 309.119028 -303.024794)
			(xy 309.122988 -302.97574) (xy 309.134765 -302.927956) (xy 309.154056 -302.88268) (xy 309.180359 -302.841084)
			(xy 309.212994 -302.804247) (xy 309.251115 -302.773122) (xy 309.293736 -302.748515) (xy 309.339752 -302.731063)
			(xy 309.387971 -302.721219) (xy 309.437146 -302.719238) (xy 309.486001 -302.72517) (xy 309.533272 -302.738862)
			(xy 309.577734 -302.75996) (xy 309.618237 -302.787916) (xy 309.65373 -302.822008) (xy 309.683295 -302.861352)
			(xy 309.706166 -302.904929) (xy 309.72175 -302.95161) (xy 309.729645 -303.000187) (xy 309.73014 -303.024794)
			(xy 309.729973 -303.033078) (xy 310.069089 -303.033078) (xy 310.071777 -302.983511) (xy 310.082449 -302.935032)
			(xy 310.100823 -302.888917) (xy 310.126415 -302.846383) (xy 310.158551 -302.80855) (xy 310.196385 -302.776414)
			(xy 310.238919 -302.750822) (xy 310.285034 -302.732448) (xy 310.333513 -302.721777) (xy 310.38308 -302.719089)
			(xy 310.432429 -302.724456) (xy 310.48026 -302.737736) (xy 310.525312 -302.758578) (xy 310.566399 -302.786435)
			(xy 310.602437 -302.820572) (xy 310.632479 -302.86009) (xy 310.655731 -302.903947) (xy 310.671582 -302.950988)
			(xy 310.679614 -302.999974) (xy 310.6801 -303.024794) (xy 310.679923 -303.038977) (xy 310.677251 -303.067217)
			(xy 310.674766 -303.081182) (xy 310.67248 -303.093628) (xy 310.679846 -303.11725) (xy 310.757316 -303.19472)
			(xy 310.780938 -303.202086) (xy 310.793384 -303.1998) (xy 310.807349 -303.197316) (xy 310.835589 -303.194649)
			(xy 310.849772 -303.194466) (xy 310.863955 -303.194647) (xy 310.892195 -303.197316) (xy 310.90616 -303.1998)
			(xy 310.918606 -303.202086) (xy 310.942228 -303.19472) (xy 311.019698 -303.11725) (xy 311.027064 -303.093628)
			(xy 311.024778 -303.081182) (xy 311.022303 -303.067216) (xy 311.01963 -303.038976) (xy 311.019444 -303.024794)
			(xy 311.019984 -302.999973) (xy 311.028017 -302.950985) (xy 311.043869 -302.903942) (xy 311.067123 -302.860083)
			(xy 311.097167 -302.820564) (xy 311.133208 -302.786427) (xy 311.174298 -302.758571) (xy 311.219353 -302.737729)
			(xy 311.267187 -302.724451) (xy 311.316538 -302.719087) (xy 311.366107 -302.721778) (xy 311.414588 -302.732453)
			(xy 311.460703 -302.750831) (xy 311.503237 -302.776427) (xy 311.54107 -302.808568) (xy 311.573204 -302.846406)
			(xy 311.598793 -302.888945) (xy 311.617163 -302.935063) (xy 311.62783 -302.983546) (xy 311.630062 -303.024794)
			(xy 311.968908 -303.024794) (xy 311.972868 -302.97574) (xy 311.984645 -302.927956) (xy 312.003936 -302.88268)
			(xy 312.030239 -302.841084) (xy 312.062874 -302.804247) (xy 312.100995 -302.773122) (xy 312.143616 -302.748515)
			(xy 312.189632 -302.731063) (xy 312.237851 -302.721219) (xy 312.287026 -302.719238) (xy 312.335881 -302.72517)
			(xy 312.383152 -302.738862) (xy 312.427614 -302.75996) (xy 312.468117 -302.787916) (xy 312.50361 -302.822008)
			(xy 312.533175 -302.861352) (xy 312.556046 -302.904929) (xy 312.57163 -302.95161) (xy 312.579525 -303.000187)
			(xy 312.58002 -303.024794) (xy 312.919122 -303.024794) (xy 312.923082 -302.97574) (xy 312.934859 -302.927956)
			(xy 312.95415 -302.88268) (xy 312.980453 -302.841084) (xy 313.013088 -302.804247) (xy 313.051209 -302.773122)
			(xy 313.09383 -302.748515) (xy 313.139846 -302.731063) (xy 313.188065 -302.721219) (xy 313.23724 -302.719238)
			(xy 313.286095 -302.72517) (xy 313.333366 -302.738862) (xy 313.377828 -302.75996) (xy 313.418331 -302.787916)
			(xy 313.453824 -302.822008) (xy 313.483389 -302.861352) (xy 313.50626 -302.904929) (xy 313.521844 -302.95161)
			(xy 313.529739 -303.000187) (xy 313.530234 -303.024794) (xy 313.869082 -303.024794) (xy 313.873042 -302.97574)
			(xy 313.884819 -302.927956) (xy 313.90411 -302.88268) (xy 313.930413 -302.841084) (xy 313.963048 -302.804247)
			(xy 314.001169 -302.773122) (xy 314.04379 -302.748515) (xy 314.089806 -302.731063) (xy 314.138025 -302.721219)
			(xy 314.1872 -302.719238) (xy 314.236055 -302.72517) (xy 314.283326 -302.738862) (xy 314.327788 -302.75996)
			(xy 314.368291 -302.787916) (xy 314.403784 -302.822008) (xy 314.433349 -302.861352) (xy 314.45622 -302.904929)
			(xy 314.471804 -302.95161) (xy 314.479699 -303.000187) (xy 314.480194 -303.024794) (xy 314.803802 -303.024794)
			(xy 314.807762 -302.97574) (xy 314.819539 -302.927956) (xy 314.83883 -302.88268) (xy 314.865133 -302.841084)
			(xy 314.897768 -302.804247) (xy 314.935889 -302.773122) (xy 314.97851 -302.748515) (xy 315.024526 -302.731063)
			(xy 315.072745 -302.721219) (xy 315.12192 -302.719238) (xy 315.170775 -302.72517) (xy 315.218046 -302.738862)
			(xy 315.262508 -302.75996) (xy 315.303011 -302.787916) (xy 315.338504 -302.822008) (xy 315.368069 -302.861352)
			(xy 315.39094 -302.904929) (xy 315.406524 -302.95161) (xy 315.414419 -303.000187) (xy 315.414914 -303.024794)
			(xy 315.414419 -303.049401) (xy 315.406524 -303.097978) (xy 315.39094 -303.144659) (xy 315.368069 -303.188236)
			(xy 315.338504 -303.22758) (xy 315.303011 -303.261672) (xy 315.262508 -303.289628) (xy 315.218046 -303.310726)
			(xy 315.170775 -303.324418) (xy 315.12192 -303.33035) (xy 315.072745 -303.328369) (xy 315.024526 -303.318525)
			(xy 314.97851 -303.301073) (xy 314.935889 -303.276466) (xy 314.897768 -303.245341) (xy 314.865133 -303.208504)
			(xy 314.83883 -303.166908) (xy 314.819539 -303.121632) (xy 314.807762 -303.073848) (xy 314.803802 -303.024794)
			(xy 314.480194 -303.024794) (xy 314.479699 -303.049401) (xy 314.471804 -303.097978) (xy 314.45622 -303.144659)
			(xy 314.433349 -303.188236) (xy 314.403784 -303.22758) (xy 314.368291 -303.261672) (xy 314.327788 -303.289628)
			(xy 314.283326 -303.310726) (xy 314.236055 -303.324418) (xy 314.1872 -303.33035) (xy 314.138025 -303.328369)
			(xy 314.089806 -303.318525) (xy 314.04379 -303.301073) (xy 314.001169 -303.276466) (xy 313.963048 -303.245341)
			(xy 313.930413 -303.208504) (xy 313.90411 -303.166908) (xy 313.884819 -303.121632) (xy 313.873042 -303.073848)
			(xy 313.869082 -303.024794) (xy 313.530234 -303.024794) (xy 313.529739 -303.049401) (xy 313.521844 -303.097978)
			(xy 313.50626 -303.144659) (xy 313.483389 -303.188236) (xy 313.453824 -303.22758) (xy 313.418331 -303.261672)
			(xy 313.377828 -303.289628) (xy 313.333366 -303.310726) (xy 313.286095 -303.324418) (xy 313.23724 -303.33035)
			(xy 313.188065 -303.328369) (xy 313.139846 -303.318525) (xy 313.09383 -303.301073) (xy 313.051209 -303.276466)
			(xy 313.013088 -303.245341) (xy 312.980453 -303.208504) (xy 312.95415 -303.166908) (xy 312.934859 -303.121632)
			(xy 312.923082 -303.073848) (xy 312.919122 -303.024794) (xy 312.58002 -303.024794) (xy 312.579525 -303.049401)
			(xy 312.57163 -303.097978) (xy 312.556046 -303.144659) (xy 312.533175 -303.188236) (xy 312.50361 -303.22758)
			(xy 312.468117 -303.261672) (xy 312.427614 -303.289628) (xy 312.383152 -303.310726) (xy 312.335881 -303.324418)
			(xy 312.287026 -303.33035) (xy 312.237851 -303.328369) (xy 312.189632 -303.318525) (xy 312.143616 -303.301073)
			(xy 312.100995 -303.276466) (xy 312.062874 -303.245341) (xy 312.030239 -303.208504) (xy 312.003936 -303.166908)
			(xy 311.984645 -303.121632) (xy 311.972868 -303.073848) (xy 311.968908 -303.024794) (xy 311.630062 -303.024794)
			(xy 311.630512 -303.033116) (xy 311.625139 -303.082466) (xy 311.611853 -303.130298) (xy 311.591003 -303.175349)
			(xy 311.563139 -303.216434) (xy 311.528995 -303.252469) (xy 311.489471 -303.282506) (xy 311.445609 -303.305752)
			(xy 311.398563 -303.321596) (xy 311.349573 -303.32962) (xy 311.324752 -303.330102) (xy 311.310569 -303.329918)
			(xy 311.282329 -303.327251) (xy 311.268364 -303.324768) (xy 311.255918 -303.322482) (xy 311.232296 -303.329848)
			(xy 311.154826 -303.407318) (xy 311.14746 -303.43094) (xy 311.149746 -303.443386) (xy 311.152216 -303.457353)
			(xy 311.154892 -303.485592) (xy 311.15508 -303.499774) (xy 311.154558 -303.525029) (xy 311.146245 -303.574851)
			(xy 311.129844 -303.622625) (xy 311.105803 -303.667048) (xy 311.074779 -303.706908) (xy 311.037617 -303.741118)
			(xy 310.995331 -303.768744) (xy 310.949075 -303.789034) (xy 310.90011 -303.801434) (xy 310.849772 -303.805605)
			(xy 310.799434 -303.801434) (xy 310.750469 -303.789034) (xy 310.704213 -303.768744) (xy 310.661927 -303.741118)
			(xy 310.624765 -303.706908) (xy 310.593741 -303.667048) (xy 310.5697 -303.622625) (xy 310.553299 -303.574851)
			(xy 310.544986 -303.525029) (xy 310.544464 -303.499774) (xy 310.544637 -303.485591) (xy 310.547312 -303.457351)
			(xy 310.549798 -303.443386) (xy 310.552084 -303.43094) (xy 310.544718 -303.407318) (xy 310.467248 -303.329848)
			(xy 310.443626 -303.322482) (xy 310.43118 -303.324768) (xy 310.417214 -303.327243) (xy 310.388974 -303.329916)
			(xy 310.374792 -303.330102) (xy 310.349972 -303.329614) (xy 310.300986 -303.321581) (xy 310.253945 -303.30573)
			(xy 310.210088 -303.282478) (xy 310.170571 -303.252436) (xy 310.136434 -303.216397) (xy 310.108578 -303.17531)
			(xy 310.087735 -303.130258) (xy 310.074455 -303.082427) (xy 310.069089 -303.033078) (xy 309.729973 -303.033078)
			(xy 309.729645 -303.049401) (xy 309.72175 -303.097978) (xy 309.706166 -303.144659) (xy 309.683295 -303.188236)
			(xy 309.65373 -303.22758) (xy 309.618237 -303.261672) (xy 309.577734 -303.289628) (xy 309.533272 -303.310726)
			(xy 309.486001 -303.324418) (xy 309.437146 -303.33035) (xy 309.387971 -303.328369) (xy 309.339752 -303.318525)
			(xy 309.293736 -303.301073) (xy 309.251115 -303.276466) (xy 309.212994 -303.245341) (xy 309.180359 -303.208504)
			(xy 309.154056 -303.166908) (xy 309.134765 -303.121632) (xy 309.122988 -303.073848) (xy 309.119028 -303.024794)
			(xy 308.780162 -303.024794) (xy 308.780612 -303.033102) (xy 308.775242 -303.082452) (xy 308.761958 -303.130284)
			(xy 308.74111 -303.175335) (xy 308.713249 -303.216421) (xy 308.679108 -303.252458) (xy 308.639586 -303.282496)
			(xy 308.595725 -303.305745) (xy 308.548681 -303.321592) (xy 308.499693 -303.329618) (xy 308.474872 -303.330102)
			(xy 308.460689 -303.329929) (xy 308.432449 -303.327255) (xy 308.418484 -303.324768) (xy 308.404519 -303.322605)
			(xy 308.376389 -303.325188) (xy 308.350043 -303.335379) (xy 308.327498 -303.352399) (xy 308.310478 -303.374945)
			(xy 308.300288 -303.401291) (xy 308.297705 -303.429421) (xy 308.299866 -303.443386) (xy 308.302336 -303.457353)
			(xy 308.305012 -303.485592) (xy 308.3052 -303.499774) (xy 308.30475 -303.524597) (xy 308.296722 -303.573591)
			(xy 308.280874 -303.62064) (xy 308.257622 -303.664505) (xy 308.227581 -303.70403) (xy 308.19154 -303.738175)
			(xy 308.15045 -303.766039) (xy 308.105394 -303.786888) (xy 308.057558 -303.800173) (xy 308.008203 -303.805544)
			(xy 307.958629 -303.80286) (xy 307.910142 -303.79219) (xy 307.864021 -303.773817) (xy 307.821479 -303.748224)
			(xy 307.783638 -303.716086) (xy 307.751496 -303.678249) (xy 307.725898 -303.63571) (xy 307.70752 -303.58959)
			(xy 307.696845 -303.541105) (xy 307.694155 -303.491531) (xy 307.355074 -303.491531) (xy 307.35524 -303.499774)
			(xy 307.354745 -303.524381) (xy 307.34685 -303.572958) (xy 307.331266 -303.619639) (xy 307.308395 -303.663216)
			(xy 307.27883 -303.70256) (xy 307.243337 -303.736652) (xy 307.202834 -303.764608) (xy 307.158372 -303.785706)
			(xy 307.111101 -303.799398) (xy 307.062246 -303.80533) (xy 307.013071 -303.803349) (xy 306.964852 -303.793505)
			(xy 306.918836 -303.776053) (xy 306.876215 -303.751446) (xy 306.838094 -303.720321) (xy 306.805459 -303.683484)
			(xy 306.779156 -303.641888) (xy 306.759865 -303.596612) (xy 306.748088 -303.548828) (xy 306.744128 -303.499774)
			(xy 292.853615 -303.499774) (xy 292.854115 -303.500314) (xy 292.861849 -303.518912) (xy 292.862254 -303.528984)
			(xy 292.862254 -303.879504) (xy 292.861829 -303.889573) (xy 292.854108 -303.908172) (xy 292.847268 -303.915572)
			(xy 292.788086 -303.974754) (xy 292.968946 -303.974754) (xy 292.972906 -303.9257) (xy 292.984683 -303.877916)
			(xy 293.003974 -303.83264) (xy 293.030277 -303.791044) (xy 293.062912 -303.754207) (xy 293.101033 -303.723082)
			(xy 293.143654 -303.698475) (xy 293.18967 -303.681023) (xy 293.237889 -303.671179) (xy 293.287064 -303.669198)
			(xy 293.335919 -303.67513) (xy 293.38319 -303.688822) (xy 293.427652 -303.70992) (xy 293.468155 -303.737876)
			(xy 293.503648 -303.771968) (xy 293.533213 -303.811312) (xy 293.556084 -303.854889) (xy 293.571668 -303.90157)
			(xy 293.579563 -303.950147) (xy 293.580058 -303.974754) (xy 293.918906 -303.974754) (xy 293.922866 -303.9257)
			(xy 293.934643 -303.877916) (xy 293.953934 -303.83264) (xy 293.980237 -303.791044) (xy 294.012872 -303.754207)
			(xy 294.050993 -303.723082) (xy 294.093614 -303.698475) (xy 294.13963 -303.681023) (xy 294.187849 -303.671179)
			(xy 294.237024 -303.669198) (xy 294.285879 -303.67513) (xy 294.33315 -303.688822) (xy 294.377612 -303.70992)
			(xy 294.418115 -303.737876) (xy 294.453608 -303.771968) (xy 294.483173 -303.811312) (xy 294.506044 -303.854889)
			(xy 294.521628 -303.90157) (xy 294.529523 -303.950147) (xy 294.530018 -303.974754) (xy 294.86912 -303.974754)
			(xy 294.87308 -303.9257) (xy 294.884857 -303.877916) (xy 294.904148 -303.83264) (xy 294.930451 -303.791044)
			(xy 294.963086 -303.754207) (xy 295.001207 -303.723082) (xy 295.043828 -303.698475) (xy 295.089844 -303.681023)
			(xy 295.138063 -303.671179) (xy 295.187238 -303.669198) (xy 295.236093 -303.67513) (xy 295.283364 -303.688822)
			(xy 295.327826 -303.70992) (xy 295.368329 -303.737876) (xy 295.403822 -303.771968) (xy 295.433387 -303.811312)
			(xy 295.456258 -303.854889) (xy 295.471842 -303.90157) (xy 295.479737 -303.950147) (xy 295.480232 -303.974754)
			(xy 295.81908 -303.974754) (xy 295.82304 -303.9257) (xy 295.834817 -303.877916) (xy 295.854108 -303.83264)
			(xy 295.880411 -303.791044) (xy 295.913046 -303.754207) (xy 295.951167 -303.723082) (xy 295.993788 -303.698475)
			(xy 296.039804 -303.681023) (xy 296.088023 -303.671179) (xy 296.137198 -303.669198) (xy 296.186053 -303.67513)
			(xy 296.233324 -303.688822) (xy 296.277786 -303.70992) (xy 296.318289 -303.737876) (xy 296.353782 -303.771968)
			(xy 296.383347 -303.811312) (xy 296.406218 -303.854889) (xy 296.421802 -303.90157) (xy 296.429697 -303.950147)
			(xy 296.430192 -303.974754) (xy 296.76904 -303.974754) (xy 296.773 -303.9257) (xy 296.784777 -303.877916)
			(xy 296.804068 -303.83264) (xy 296.830371 -303.791044) (xy 296.863006 -303.754207) (xy 296.901127 -303.723082)
			(xy 296.943748 -303.698475) (xy 296.989764 -303.681023) (xy 297.037983 -303.671179) (xy 297.087158 -303.669198)
			(xy 297.136013 -303.67513) (xy 297.183284 -303.688822) (xy 297.227746 -303.70992) (xy 297.268249 -303.737876)
			(xy 297.303742 -303.771968) (xy 297.333307 -303.811312) (xy 297.356178 -303.854889) (xy 297.371762 -303.90157)
			(xy 297.379657 -303.950147) (xy 297.380152 -303.974754) (xy 297.719 -303.974754) (xy 297.72296 -303.9257)
			(xy 297.734737 -303.877916) (xy 297.754028 -303.83264) (xy 297.780331 -303.791044) (xy 297.812966 -303.754207)
			(xy 297.851087 -303.723082) (xy 297.893708 -303.698475) (xy 297.939724 -303.681023) (xy 297.987943 -303.671179)
			(xy 298.037118 -303.669198) (xy 298.085973 -303.67513) (xy 298.133244 -303.688822) (xy 298.177706 -303.70992)
			(xy 298.218209 -303.737876) (xy 298.253702 -303.771968) (xy 298.283267 -303.811312) (xy 298.306138 -303.854889)
			(xy 298.321722 -303.90157) (xy 298.329617 -303.950147) (xy 298.330112 -303.974754) (xy 298.66896 -303.974754)
			(xy 298.67292 -303.9257) (xy 298.684697 -303.877916) (xy 298.703988 -303.83264) (xy 298.730291 -303.791044)
			(xy 298.762926 -303.754207) (xy 298.801047 -303.723082) (xy 298.843668 -303.698475) (xy 298.889684 -303.681023)
			(xy 298.937903 -303.671179) (xy 298.987078 -303.669198) (xy 299.035933 -303.67513) (xy 299.083204 -303.688822)
			(xy 299.127666 -303.70992) (xy 299.168169 -303.737876) (xy 299.203662 -303.771968) (xy 299.233227 -303.811312)
			(xy 299.256098 -303.854889) (xy 299.271682 -303.90157) (xy 299.279577 -303.950147) (xy 299.280072 -303.974754)
			(xy 299.61892 -303.974754) (xy 299.62288 -303.9257) (xy 299.634657 -303.877916) (xy 299.653948 -303.83264)
			(xy 299.680251 -303.791044) (xy 299.712886 -303.754207) (xy 299.751007 -303.723082) (xy 299.793628 -303.698475)
			(xy 299.839644 -303.681023) (xy 299.887863 -303.671179) (xy 299.937038 -303.669198) (xy 299.985893 -303.67513)
			(xy 300.033164 -303.688822) (xy 300.077626 -303.70992) (xy 300.118129 -303.737876) (xy 300.153622 -303.771968)
			(xy 300.183187 -303.811312) (xy 300.206058 -303.854889) (xy 300.221642 -303.90157) (xy 300.229537 -303.950147)
			(xy 300.229935 -303.969928) (xy 300.57396 -303.969928) (xy 300.57792 -303.920874) (xy 300.589697 -303.87309)
			(xy 300.608988 -303.827814) (xy 300.635291 -303.786218) (xy 300.667926 -303.749381) (xy 300.706047 -303.718256)
			(xy 300.748668 -303.693649) (xy 300.794684 -303.676197) (xy 300.842903 -303.666353) (xy 300.892078 -303.664372)
			(xy 300.940933 -303.670304) (xy 300.988204 -303.683996) (xy 301.032666 -303.705094) (xy 301.073169 -303.73305)
			(xy 301.108662 -303.767142) (xy 301.138227 -303.806486) (xy 301.161098 -303.850063) (xy 301.176682 -303.896744)
			(xy 301.184577 -303.945321) (xy 301.185072 -303.969928) (xy 301.184975 -303.974754) (xy 301.519094 -303.974754)
			(xy 301.523054 -303.9257) (xy 301.534831 -303.877916) (xy 301.554122 -303.83264) (xy 301.580425 -303.791044)
			(xy 301.61306 -303.754207) (xy 301.651181 -303.723082) (xy 301.693802 -303.698475) (xy 301.739818 -303.681023)
			(xy 301.788037 -303.671179) (xy 301.837212 -303.669198) (xy 301.886067 -303.67513) (xy 301.933338 -303.688822)
			(xy 301.9778 -303.70992) (xy 302.018303 -303.737876) (xy 302.053796 -303.771968) (xy 302.083361 -303.811312)
			(xy 302.106232 -303.854889) (xy 302.121816 -303.90157) (xy 302.129711 -303.950147) (xy 302.130206 -303.974754)
			(xy 302.469054 -303.974754) (xy 302.473014 -303.9257) (xy 302.484791 -303.877916) (xy 302.504082 -303.83264)
			(xy 302.530385 -303.791044) (xy 302.56302 -303.754207) (xy 302.601141 -303.723082) (xy 302.643762 -303.698475)
			(xy 302.689778 -303.681023) (xy 302.737997 -303.671179) (xy 302.787172 -303.669198) (xy 302.836027 -303.67513)
			(xy 302.883298 -303.688822) (xy 302.92776 -303.70992) (xy 302.968263 -303.737876) (xy 303.003756 -303.771968)
			(xy 303.033321 -303.811312) (xy 303.056192 -303.854889) (xy 303.071776 -303.90157) (xy 303.079671 -303.950147)
			(xy 303.080166 -303.974754) (xy 303.419014 -303.974754) (xy 303.422974 -303.9257) (xy 303.434751 -303.877916)
			(xy 303.454042 -303.83264) (xy 303.480345 -303.791044) (xy 303.51298 -303.754207) (xy 303.551101 -303.723082)
			(xy 303.593722 -303.698475) (xy 303.639738 -303.681023) (xy 303.687957 -303.671179) (xy 303.737132 -303.669198)
			(xy 303.785987 -303.67513) (xy 303.833258 -303.688822) (xy 303.87772 -303.70992) (xy 303.918223 -303.737876)
			(xy 303.953716 -303.771968) (xy 303.983281 -303.811312) (xy 304.006152 -303.854889) (xy 304.021736 -303.90157)
			(xy 304.029631 -303.950147) (xy 304.030126 -303.974754) (xy 304.368974 -303.974754) (xy 304.372934 -303.9257)
			(xy 304.384711 -303.877916) (xy 304.404002 -303.83264) (xy 304.430305 -303.791044) (xy 304.46294 -303.754207)
			(xy 304.501061 -303.723082) (xy 304.543682 -303.698475) (xy 304.589698 -303.681023) (xy 304.637917 -303.671179)
			(xy 304.687092 -303.669198) (xy 304.735947 -303.67513) (xy 304.783218 -303.688822) (xy 304.82768 -303.70992)
			(xy 304.868183 -303.737876) (xy 304.903676 -303.771968) (xy 304.933241 -303.811312) (xy 304.956112 -303.854889)
			(xy 304.971696 -303.90157) (xy 304.979591 -303.950147) (xy 304.980086 -303.974754) (xy 304.979591 -303.999361)
			(xy 304.971696 -304.047938) (xy 304.956112 -304.094619) (xy 304.933241 -304.138196) (xy 304.903676 -304.17754)
			(xy 304.868183 -304.211632) (xy 304.82768 -304.239588) (xy 304.783218 -304.260686) (xy 304.735947 -304.274378)
			(xy 304.687092 -304.28031) (xy 304.637917 -304.278329) (xy 304.589698 -304.268485) (xy 304.543682 -304.251033)
			(xy 304.501061 -304.226426) (xy 304.46294 -304.195301) (xy 304.430305 -304.158464) (xy 304.404002 -304.116868)
			(xy 304.384711 -304.071592) (xy 304.372934 -304.023808) (xy 304.368974 -303.974754) (xy 304.030126 -303.974754)
			(xy 304.029631 -303.999361) (xy 304.021736 -304.047938) (xy 304.006152 -304.094619) (xy 303.983281 -304.138196)
			(xy 303.953716 -304.17754) (xy 303.918223 -304.211632) (xy 303.87772 -304.239588) (xy 303.833258 -304.260686)
			(xy 303.785987 -304.274378) (xy 303.737132 -304.28031) (xy 303.687957 -304.278329) (xy 303.639738 -304.268485)
			(xy 303.593722 -304.251033) (xy 303.551101 -304.226426) (xy 303.51298 -304.195301) (xy 303.480345 -304.158464)
			(xy 303.454042 -304.116868) (xy 303.434751 -304.071592) (xy 303.422974 -304.023808) (xy 303.419014 -303.974754)
			(xy 303.080166 -303.974754) (xy 303.079671 -303.999361) (xy 303.071776 -304.047938) (xy 303.056192 -304.094619)
			(xy 303.033321 -304.138196) (xy 303.003756 -304.17754) (xy 302.968263 -304.211632) (xy 302.92776 -304.239588)
			(xy 302.883298 -304.260686) (xy 302.836027 -304.274378) (xy 302.787172 -304.28031) (xy 302.737997 -304.278329)
			(xy 302.689778 -304.268485) (xy 302.643762 -304.251033) (xy 302.601141 -304.226426) (xy 302.56302 -304.195301)
			(xy 302.530385 -304.158464) (xy 302.504082 -304.116868) (xy 302.484791 -304.071592) (xy 302.473014 -304.023808)
			(xy 302.469054 -303.974754) (xy 302.130206 -303.974754) (xy 302.129711 -303.999361) (xy 302.121816 -304.047938)
			(xy 302.106232 -304.094619) (xy 302.083361 -304.138196) (xy 302.053796 -304.17754) (xy 302.018303 -304.211632)
			(xy 301.9778 -304.239588) (xy 301.933338 -304.260686) (xy 301.886067 -304.274378) (xy 301.837212 -304.28031)
			(xy 301.788037 -304.278329) (xy 301.739818 -304.268485) (xy 301.693802 -304.251033) (xy 301.651181 -304.226426)
			(xy 301.61306 -304.195301) (xy 301.580425 -304.158464) (xy 301.554122 -304.116868) (xy 301.534831 -304.071592)
			(xy 301.523054 -304.023808) (xy 301.519094 -303.974754) (xy 301.184975 -303.974754) (xy 301.184577 -303.994535)
			(xy 301.176682 -304.043112) (xy 301.161098 -304.089793) (xy 301.138227 -304.13337) (xy 301.108662 -304.172714)
			(xy 301.073169 -304.206806) (xy 301.032666 -304.234762) (xy 300.988204 -304.25586) (xy 300.940933 -304.269552)
			(xy 300.892078 -304.275484) (xy 300.842903 -304.273503) (xy 300.794684 -304.263659) (xy 300.748668 -304.246207)
			(xy 300.706047 -304.2216) (xy 300.667926 -304.190475) (xy 300.635291 -304.153638) (xy 300.608988 -304.112042)
			(xy 300.589697 -304.066766) (xy 300.57792 -304.018982) (xy 300.57396 -303.969928) (xy 300.229935 -303.969928)
			(xy 300.230032 -303.974754) (xy 300.229537 -303.999361) (xy 300.221642 -304.047938) (xy 300.206058 -304.094619)
			(xy 300.183187 -304.138196) (xy 300.153622 -304.17754) (xy 300.118129 -304.211632) (xy 300.077626 -304.239588)
			(xy 300.033164 -304.260686) (xy 299.985893 -304.274378) (xy 299.937038 -304.28031) (xy 299.887863 -304.278329)
			(xy 299.839644 -304.268485) (xy 299.793628 -304.251033) (xy 299.751007 -304.226426) (xy 299.712886 -304.195301)
			(xy 299.680251 -304.158464) (xy 299.653948 -304.116868) (xy 299.634657 -304.071592) (xy 299.62288 -304.023808)
			(xy 299.61892 -303.974754) (xy 299.280072 -303.974754) (xy 299.279577 -303.999361) (xy 299.271682 -304.047938)
			(xy 299.256098 -304.094619) (xy 299.233227 -304.138196) (xy 299.203662 -304.17754) (xy 299.168169 -304.211632)
			(xy 299.127666 -304.239588) (xy 299.083204 -304.260686) (xy 299.035933 -304.274378) (xy 298.987078 -304.28031)
			(xy 298.937903 -304.278329) (xy 298.889684 -304.268485) (xy 298.843668 -304.251033) (xy 298.801047 -304.226426)
			(xy 298.762926 -304.195301) (xy 298.730291 -304.158464) (xy 298.703988 -304.116868) (xy 298.684697 -304.071592)
			(xy 298.67292 -304.023808) (xy 298.66896 -303.974754) (xy 298.330112 -303.974754) (xy 298.329617 -303.999361)
			(xy 298.321722 -304.047938) (xy 298.306138 -304.094619) (xy 298.283267 -304.138196) (xy 298.253702 -304.17754)
			(xy 298.218209 -304.211632) (xy 298.177706 -304.239588) (xy 298.133244 -304.260686) (xy 298.085973 -304.274378)
			(xy 298.037118 -304.28031) (xy 297.987943 -304.278329) (xy 297.939724 -304.268485) (xy 297.893708 -304.251033)
			(xy 297.851087 -304.226426) (xy 297.812966 -304.195301) (xy 297.780331 -304.158464) (xy 297.754028 -304.116868)
			(xy 297.734737 -304.071592) (xy 297.72296 -304.023808) (xy 297.719 -303.974754) (xy 297.380152 -303.974754)
			(xy 297.379657 -303.999361) (xy 297.371762 -304.047938) (xy 297.356178 -304.094619) (xy 297.333307 -304.138196)
			(xy 297.303742 -304.17754) (xy 297.268249 -304.211632) (xy 297.227746 -304.239588) (xy 297.183284 -304.260686)
			(xy 297.136013 -304.274378) (xy 297.087158 -304.28031) (xy 297.037983 -304.278329) (xy 296.989764 -304.268485)
			(xy 296.943748 -304.251033) (xy 296.901127 -304.226426) (xy 296.863006 -304.195301) (xy 296.830371 -304.158464)
			(xy 296.804068 -304.116868) (xy 296.784777 -304.071592) (xy 296.773 -304.023808) (xy 296.76904 -303.974754)
			(xy 296.430192 -303.974754) (xy 296.429697 -303.999361) (xy 296.421802 -304.047938) (xy 296.406218 -304.094619)
			(xy 296.383347 -304.138196) (xy 296.353782 -304.17754) (xy 296.318289 -304.211632) (xy 296.277786 -304.239588)
			(xy 296.233324 -304.260686) (xy 296.186053 -304.274378) (xy 296.137198 -304.28031) (xy 296.088023 -304.278329)
			(xy 296.039804 -304.268485) (xy 295.993788 -304.251033) (xy 295.951167 -304.226426) (xy 295.913046 -304.195301)
			(xy 295.880411 -304.158464) (xy 295.854108 -304.116868) (xy 295.834817 -304.071592) (xy 295.82304 -304.023808)
			(xy 295.81908 -303.974754) (xy 295.480232 -303.974754) (xy 295.479737 -303.999361) (xy 295.471842 -304.047938)
			(xy 295.456258 -304.094619) (xy 295.433387 -304.138196) (xy 295.403822 -304.17754) (xy 295.368329 -304.211632)
			(xy 295.327826 -304.239588) (xy 295.283364 -304.260686) (xy 295.236093 -304.274378) (xy 295.187238 -304.28031)
			(xy 295.138063 -304.278329) (xy 295.089844 -304.268485) (xy 295.043828 -304.251033) (xy 295.001207 -304.226426)
			(xy 294.963086 -304.195301) (xy 294.930451 -304.158464) (xy 294.904148 -304.116868) (xy 294.884857 -304.071592)
			(xy 294.87308 -304.023808) (xy 294.86912 -303.974754) (xy 294.530018 -303.974754) (xy 294.529523 -303.999361)
			(xy 294.521628 -304.047938) (xy 294.506044 -304.094619) (xy 294.483173 -304.138196) (xy 294.453608 -304.17754)
			(xy 294.418115 -304.211632) (xy 294.377612 -304.239588) (xy 294.33315 -304.260686) (xy 294.285879 -304.274378)
			(xy 294.237024 -304.28031) (xy 294.187849 -304.278329) (xy 294.13963 -304.268485) (xy 294.093614 -304.251033)
			(xy 294.050993 -304.226426) (xy 294.012872 -304.195301) (xy 293.980237 -304.158464) (xy 293.953934 -304.116868)
			(xy 293.934643 -304.071592) (xy 293.922866 -304.023808) (xy 293.918906 -303.974754) (xy 293.580058 -303.974754)
			(xy 293.579563 -303.999361) (xy 293.571668 -304.047938) (xy 293.556084 -304.094619) (xy 293.533213 -304.138196)
			(xy 293.503648 -304.17754) (xy 293.468155 -304.211632) (xy 293.427652 -304.239588) (xy 293.38319 -304.260686)
			(xy 293.335919 -304.274378) (xy 293.287064 -304.28031) (xy 293.237889 -304.278329) (xy 293.18967 -304.268485)
			(xy 293.143654 -304.251033) (xy 293.101033 -304.226426) (xy 293.062912 -304.195301) (xy 293.030277 -304.158464)
			(xy 293.003974 -304.116868) (xy 292.984683 -304.071592) (xy 292.972906 -304.023808) (xy 292.968946 -303.974754)
			(xy 292.788086 -303.974754) (xy 292.69944 -304.0634) (xy 292.69309 -304.074322) (xy 292.691312 -304.080672)
			(xy 292.683222 -304.106947) (xy 292.660542 -304.157026) (xy 292.630909 -304.203332) (xy 292.594935 -304.244904)
			(xy 292.553367 -304.280882) (xy 292.507066 -304.310521) (xy 292.456989 -304.333207) (xy 292.430708 -304.341276)
			(xy 292.420294 -304.34407) (xy 292.415976 -304.345086) (xy 292.415214 -304.34534) (xy 292.381432 -304.351944)
			(xy 292.381178 -304.351944) (xy 292.367162 -304.353883) (xy 292.338939 -304.35592) (xy 292.32479 -304.356008)
			(xy 292.30268 -304.355705) (xy 292.258754 -304.350611) (xy 292.23716 -304.345848) (xy 292.231318 -304.344578)
			(xy 282.912058 -304.344578) (xy 282.901991 -304.345008) (xy 282.883395 -304.352731) (xy 282.87599 -304.359564)
			(xy 282.78582 -304.449734) (xy 305.793914 -304.449734) (xy 305.797874 -304.40068) (xy 305.809651 -304.352896)
			(xy 305.828942 -304.30762) (xy 305.855245 -304.266024) (xy 305.88788 -304.229187) (xy 305.926001 -304.198062)
			(xy 305.968622 -304.173455) (xy 306.014638 -304.156003) (xy 306.062857 -304.146159) (xy 306.112032 -304.144178)
			(xy 306.160887 -304.15011) (xy 306.208158 -304.163802) (xy 306.25262 -304.1849) (xy 306.293123 -304.212856)
			(xy 306.328616 -304.246948) (xy 306.358181 -304.286292) (xy 306.381052 -304.329869) (xy 306.396636 -304.37655)
			(xy 306.404531 -304.425127) (xy 306.405026 -304.449734) (xy 306.744128 -304.449734) (xy 306.748088 -304.40068)
			(xy 306.759865 -304.352896) (xy 306.779156 -304.30762) (xy 306.805459 -304.266024) (xy 306.838094 -304.229187)
			(xy 306.876215 -304.198062) (xy 306.918836 -304.173455) (xy 306.964852 -304.156003) (xy 307.013071 -304.146159)
			(xy 307.062246 -304.144178) (xy 307.111101 -304.15011) (xy 307.158372 -304.163802) (xy 307.202834 -304.1849)
			(xy 307.243337 -304.212856) (xy 307.27883 -304.246948) (xy 307.308395 -304.286292) (xy 307.331266 -304.329869)
			(xy 307.34685 -304.37655) (xy 307.354745 -304.425127) (xy 307.35524 -304.449734) (xy 307.694088 -304.449734)
			(xy 307.698048 -304.40068) (xy 307.709825 -304.352896) (xy 307.729116 -304.30762) (xy 307.755419 -304.266024)
			(xy 307.788054 -304.229187) (xy 307.826175 -304.198062) (xy 307.868796 -304.173455) (xy 307.914812 -304.156003)
			(xy 307.963031 -304.146159) (xy 308.012206 -304.144178) (xy 308.061061 -304.15011) (xy 308.108332 -304.163802)
			(xy 308.152794 -304.1849) (xy 308.193297 -304.212856) (xy 308.22879 -304.246948) (xy 308.258355 -304.286292)
			(xy 308.281226 -304.329869) (xy 308.29681 -304.37655) (xy 308.304705 -304.425127) (xy 308.3052 -304.449734)
			(xy 308.644048 -304.449734) (xy 308.648008 -304.40068) (xy 308.659785 -304.352896) (xy 308.679076 -304.30762)
			(xy 308.705379 -304.266024) (xy 308.738014 -304.229187) (xy 308.776135 -304.198062) (xy 308.818756 -304.173455)
			(xy 308.864772 -304.156003) (xy 308.912991 -304.146159) (xy 308.962166 -304.144178) (xy 309.011021 -304.15011)
			(xy 309.058292 -304.163802) (xy 309.102754 -304.1849) (xy 309.143257 -304.212856) (xy 309.17875 -304.246948)
			(xy 309.208315 -304.286292) (xy 309.231186 -304.329869) (xy 309.24677 -304.37655) (xy 309.254665 -304.425127)
			(xy 309.25516 -304.449734) (xy 309.594008 -304.449734) (xy 309.597968 -304.40068) (xy 309.609745 -304.352896)
			(xy 309.629036 -304.30762) (xy 309.655339 -304.266024) (xy 309.687974 -304.229187) (xy 309.726095 -304.198062)
			(xy 309.768716 -304.173455) (xy 309.814732 -304.156003) (xy 309.862951 -304.146159) (xy 309.912126 -304.144178)
			(xy 309.960981 -304.15011) (xy 310.008252 -304.163802) (xy 310.052714 -304.1849) (xy 310.093217 -304.212856)
			(xy 310.12871 -304.246948) (xy 310.158275 -304.286292) (xy 310.181146 -304.329869) (xy 310.19673 -304.37655)
			(xy 310.204625 -304.425127) (xy 310.20512 -304.449734) (xy 310.543968 -304.449734) (xy 310.547928 -304.40068)
			(xy 310.559705 -304.352896) (xy 310.578996 -304.30762) (xy 310.605299 -304.266024) (xy 310.637934 -304.229187)
			(xy 310.676055 -304.198062) (xy 310.718676 -304.173455) (xy 310.764692 -304.156003) (xy 310.812911 -304.146159)
			(xy 310.862086 -304.144178) (xy 310.910941 -304.15011) (xy 310.958212 -304.163802) (xy 311.002674 -304.1849)
			(xy 311.043177 -304.212856) (xy 311.07867 -304.246948) (xy 311.108235 -304.286292) (xy 311.131106 -304.329869)
			(xy 311.14669 -304.37655) (xy 311.154585 -304.425127) (xy 311.154912 -304.441387) (xy 311.494016 -304.441387)
			(xy 311.499388 -304.392042) (xy 311.512672 -304.344216) (xy 311.533519 -304.29917) (xy 311.561378 -304.25809)
			(xy 311.595517 -304.222058) (xy 311.635035 -304.192024) (xy 311.678891 -304.168778) (xy 311.725931 -304.152934)
			(xy 311.774914 -304.144909) (xy 311.799732 -304.144426) (xy 311.813915 -304.144598) (xy 311.842155 -304.147273)
			(xy 311.85612 -304.14976) (xy 311.868566 -304.152046) (xy 311.892188 -304.14468) (xy 311.969658 -304.06721)
			(xy 311.977024 -304.043588) (xy 311.974738 -304.031142) (xy 311.972258 -304.017177) (xy 311.969588 -303.988937)
			(xy 311.969404 -303.974754) (xy 311.969926 -303.949499) (xy 311.978239 -303.899677) (xy 311.99464 -303.851903)
			(xy 312.018681 -303.80748) (xy 312.049705 -303.76762) (xy 312.086867 -303.73341) (xy 312.129153 -303.705784)
			(xy 312.175409 -303.685494) (xy 312.224374 -303.673094) (xy 312.274712 -303.668923) (xy 312.32505 -303.673094)
			(xy 312.374015 -303.685494) (xy 312.420271 -303.705784) (xy 312.462557 -303.73341) (xy 312.499719 -303.76762)
			(xy 312.530743 -303.80748) (xy 312.554784 -303.851903) (xy 312.571185 -303.899677) (xy 312.579498 -303.949499)
			(xy 312.58002 -303.974754) (xy 312.579837 -303.988937) (xy 312.577169 -304.017177) (xy 312.574686 -304.031142)
			(xy 312.5724 -304.043588) (xy 312.579766 -304.06721) (xy 312.657236 -304.14468) (xy 312.680858 -304.152046)
			(xy 312.693304 -304.14976) (xy 312.707271 -304.147287) (xy 312.73551 -304.144613) (xy 312.749692 -304.144426)
			(xy 312.763939 -304.144596) (xy 312.792307 -304.147263) (xy 312.806334 -304.14976) (xy 312.818526 -304.152046)
			(xy 312.842656 -304.14468) (xy 312.919872 -304.067464) (xy 312.927238 -304.043588) (xy 312.924952 -304.031142)
			(xy 312.922472 -304.017177) (xy 312.919802 -303.988937) (xy 312.919618 -303.974754) (xy 312.92014 -303.949499)
			(xy 312.928453 -303.899677) (xy 312.944854 -303.851903) (xy 312.968895 -303.80748) (xy 312.999919 -303.76762)
			(xy 313.037081 -303.73341) (xy 313.079367 -303.705784) (xy 313.125623 -303.685494) (xy 313.174588 -303.673094)
			(xy 313.224926 -303.668923) (xy 313.275264 -303.673094) (xy 313.324229 -303.685494) (xy 313.370485 -303.705784)
			(xy 313.412771 -303.73341) (xy 313.449933 -303.76762) (xy 313.480957 -303.80748) (xy 313.504998 -303.851903)
			(xy 313.521399 -303.899677) (xy 313.529712 -303.949499) (xy 313.530234 -303.974754) (xy 313.530051 -303.988937)
			(xy 313.527383 -304.017177) (xy 313.5249 -304.031142) (xy 313.522614 -304.043588) (xy 313.52998 -304.06721)
			(xy 313.60745 -304.14468) (xy 313.631072 -304.152046) (xy 313.643518 -304.14976) (xy 313.657484 -304.147286)
			(xy 313.685724 -304.144612) (xy 313.699906 -304.144426) (xy 313.724726 -304.144884) (xy 313.773711 -304.152916)
			(xy 313.820752 -304.168766) (xy 313.864609 -304.192018) (xy 313.904126 -304.222058) (xy 313.938263 -304.258096)
			(xy 313.96612 -304.299182) (xy 313.986964 -304.344233) (xy 314.000245 -304.392063) (xy 314.005613 -304.441411)
			(xy 314.005162 -304.449734) (xy 314.344062 -304.449734) (xy 314.348022 -304.40068) (xy 314.359799 -304.352896)
			(xy 314.37909 -304.30762) (xy 314.405393 -304.266024) (xy 314.438028 -304.229187) (xy 314.476149 -304.198062)
			(xy 314.51877 -304.173455) (xy 314.564786 -304.156003) (xy 314.613005 -304.146159) (xy 314.66218 -304.144178)
			(xy 314.711035 -304.15011) (xy 314.758306 -304.163802) (xy 314.802768 -304.1849) (xy 314.843271 -304.212856)
			(xy 314.878764 -304.246948) (xy 314.908329 -304.286292) (xy 314.9312 -304.329869) (xy 314.946784 -304.37655)
			(xy 314.954679 -304.425127) (xy 314.955174 -304.449734) (xy 315.294276 -304.449734) (xy 315.298236 -304.40068)
			(xy 315.310013 -304.352896) (xy 315.329304 -304.30762) (xy 315.355607 -304.266024) (xy 315.388242 -304.229187)
			(xy 315.426363 -304.198062) (xy 315.468984 -304.173455) (xy 315.515 -304.156003) (xy 315.563219 -304.146159)
			(xy 315.612394 -304.144178) (xy 315.661249 -304.15011) (xy 315.70852 -304.163802) (xy 315.752982 -304.1849)
			(xy 315.793485 -304.212856) (xy 315.828978 -304.246948) (xy 315.858543 -304.286292) (xy 315.881414 -304.329869)
			(xy 315.896998 -304.37655) (xy 315.904893 -304.425127) (xy 315.905388 -304.449734) (xy 315.904893 -304.474341)
			(xy 315.896998 -304.522918) (xy 315.881414 -304.569599) (xy 315.858543 -304.613176) (xy 315.828978 -304.65252)
			(xy 315.793485 -304.686612) (xy 315.752982 -304.714568) (xy 315.70852 -304.735666) (xy 315.661249 -304.749358)
			(xy 315.612394 -304.75529) (xy 315.563219 -304.753309) (xy 315.515 -304.743465) (xy 315.468984 -304.726013)
			(xy 315.426363 -304.701406) (xy 315.388242 -304.670281) (xy 315.355607 -304.633444) (xy 315.329304 -304.591848)
			(xy 315.310013 -304.546572) (xy 315.298236 -304.498788) (xy 315.294276 -304.449734) (xy 314.955174 -304.449734)
			(xy 314.954679 -304.474341) (xy 314.946784 -304.522918) (xy 314.9312 -304.569599) (xy 314.908329 -304.613176)
			(xy 314.878764 -304.65252) (xy 314.843271 -304.686612) (xy 314.802768 -304.714568) (xy 314.758306 -304.735666)
			(xy 314.711035 -304.749358) (xy 314.66218 -304.75529) (xy 314.613005 -304.753309) (xy 314.564786 -304.743465)
			(xy 314.51877 -304.726013) (xy 314.476149 -304.701406) (xy 314.438028 -304.670281) (xy 314.405393 -304.633444)
			(xy 314.37909 -304.591848) (xy 314.359799 -304.546572) (xy 314.348022 -304.498788) (xy 314.344062 -304.449734)
			(xy 314.005162 -304.449734) (xy 314.002927 -304.490978) (xy 313.992257 -304.539457) (xy 313.973885 -304.585572)
			(xy 313.948295 -304.628106) (xy 313.916161 -304.665941) (xy 313.878329 -304.698079) (xy 313.835797 -304.723673)
			(xy 313.789684 -304.742049) (xy 313.741206 -304.752723) (xy 313.691639 -304.755413) (xy 313.642291 -304.75005)
			(xy 313.59446 -304.736774) (xy 313.549406 -304.715934) (xy 313.508318 -304.688081) (xy 313.472277 -304.653947)
			(xy 313.442233 -304.614432) (xy 313.418977 -304.570577) (xy 313.403123 -304.523538) (xy 313.395087 -304.474554)
			(xy 313.394598 -304.449734) (xy 313.394779 -304.435551) (xy 313.397448 -304.407311) (xy 313.399932 -304.393346)
			(xy 313.402218 -304.3809) (xy 313.394852 -304.357278) (xy 313.317382 -304.279808) (xy 313.29376 -304.272442)
			(xy 313.281314 -304.274728) (xy 313.267347 -304.277199) (xy 313.239108 -304.279874) (xy 313.224926 -304.280062)
			(xy 313.210679 -304.279904) (xy 313.182311 -304.277229) (xy 313.168284 -304.274728) (xy 313.156092 -304.272442)
			(xy 313.131962 -304.279808) (xy 313.054746 -304.357024) (xy 313.04738 -304.3809) (xy 313.049666 -304.393346)
			(xy 313.052145 -304.407312) (xy 313.054815 -304.435551) (xy 313.055 -304.449734) (xy 313.054478 -304.474989)
			(xy 313.046165 -304.524811) (xy 313.029764 -304.572585) (xy 313.005723 -304.617008) (xy 312.974699 -304.656868)
			(xy 312.937537 -304.691078) (xy 312.895251 -304.718704) (xy 312.848995 -304.738994) (xy 312.80003 -304.751394)
			(xy 312.749692 -304.755565) (xy 312.699354 -304.751394) (xy 312.650389 -304.738994) (xy 312.604133 -304.718704)
			(xy 312.561847 -304.691078) (xy 312.524685 -304.656868) (xy 312.493661 -304.617008) (xy 312.46962 -304.572585)
			(xy 312.453219 -304.524811) (xy 312.444906 -304.474989) (xy 312.444384 -304.449734) (xy 312.444565 -304.435551)
			(xy 312.447234 -304.407311) (xy 312.449718 -304.393346) (xy 312.452004 -304.3809) (xy 312.444638 -304.357278)
			(xy 312.367168 -304.279808) (xy 312.343546 -304.272442) (xy 312.3311 -304.274728) (xy 312.317134 -304.277201)
			(xy 312.288894 -304.279875) (xy 312.274712 -304.280062) (xy 312.260529 -304.279884) (xy 312.232289 -304.277213)
			(xy 312.218324 -304.274728) (xy 312.205878 -304.272442) (xy 312.182256 -304.279808) (xy 312.104786 -304.357278)
			(xy 312.09742 -304.3809) (xy 312.099706 -304.393346) (xy 312.102185 -304.407311) (xy 312.104855 -304.435551)
			(xy 312.10504 -304.449734) (xy 312.104485 -304.474552) (xy 312.09645 -304.523533) (xy 312.080596 -304.570569)
			(xy 312.057341 -304.614421) (xy 312.027298 -304.653933) (xy 311.991259 -304.688063) (xy 311.950172 -304.715914)
			(xy 311.905121 -304.736751) (xy 311.857293 -304.750025) (xy 311.807947 -304.755386) (xy 311.758384 -304.752693)
			(xy 311.70991 -304.742018) (xy 311.663801 -304.72364) (xy 311.621273 -304.698046) (xy 311.583445 -304.665908)
			(xy 311.551316 -304.628074) (xy 311.52573 -304.58554) (xy 311.507363 -304.539427) (xy 311.496698 -304.49095)
			(xy 311.494016 -304.441387) (xy 311.154912 -304.441387) (xy 311.15508 -304.449734) (xy 311.154585 -304.474341)
			(xy 311.14669 -304.522918) (xy 311.131106 -304.569599) (xy 311.108235 -304.613176) (xy 311.07867 -304.65252)
			(xy 311.043177 -304.686612) (xy 311.002674 -304.714568) (xy 310.958212 -304.735666) (xy 310.910941 -304.749358)
			(xy 310.862086 -304.75529) (xy 310.812911 -304.753309) (xy 310.764692 -304.743465) (xy 310.718676 -304.726013)
			(xy 310.676055 -304.701406) (xy 310.637934 -304.670281) (xy 310.605299 -304.633444) (xy 310.578996 -304.591848)
			(xy 310.559705 -304.546572) (xy 310.547928 -304.498788) (xy 310.543968 -304.449734) (xy 310.20512 -304.449734)
			(xy 310.204625 -304.474341) (xy 310.19673 -304.522918) (xy 310.181146 -304.569599) (xy 310.158275 -304.613176)
			(xy 310.12871 -304.65252) (xy 310.093217 -304.686612) (xy 310.052714 -304.714568) (xy 310.008252 -304.735666)
			(xy 309.960981 -304.749358) (xy 309.912126 -304.75529) (xy 309.862951 -304.753309) (xy 309.814732 -304.743465)
			(xy 309.768716 -304.726013) (xy 309.726095 -304.701406) (xy 309.687974 -304.670281) (xy 309.655339 -304.633444)
			(xy 309.629036 -304.591848) (xy 309.609745 -304.546572) (xy 309.597968 -304.498788) (xy 309.594008 -304.449734)
			(xy 309.25516 -304.449734) (xy 309.254665 -304.474341) (xy 309.24677 -304.522918) (xy 309.231186 -304.569599)
			(xy 309.208315 -304.613176) (xy 309.17875 -304.65252) (xy 309.143257 -304.686612) (xy 309.102754 -304.714568)
			(xy 309.058292 -304.735666) (xy 309.011021 -304.749358) (xy 308.962166 -304.75529) (xy 308.912991 -304.753309)
			(xy 308.864772 -304.743465) (xy 308.818756 -304.726013) (xy 308.776135 -304.701406) (xy 308.738014 -304.670281)
			(xy 308.705379 -304.633444) (xy 308.679076 -304.591848) (xy 308.659785 -304.546572) (xy 308.648008 -304.498788)
			(xy 308.644048 -304.449734) (xy 308.3052 -304.449734) (xy 308.304705 -304.474341) (xy 308.29681 -304.522918)
			(xy 308.281226 -304.569599) (xy 308.258355 -304.613176) (xy 308.22879 -304.65252) (xy 308.193297 -304.686612)
			(xy 308.152794 -304.714568) (xy 308.108332 -304.735666) (xy 308.061061 -304.749358) (xy 308.012206 -304.75529)
			(xy 307.963031 -304.753309) (xy 307.914812 -304.743465) (xy 307.868796 -304.726013) (xy 307.826175 -304.701406)
			(xy 307.788054 -304.670281) (xy 307.755419 -304.633444) (xy 307.729116 -304.591848) (xy 307.709825 -304.546572)
			(xy 307.698048 -304.498788) (xy 307.694088 -304.449734) (xy 307.35524 -304.449734) (xy 307.354745 -304.474341)
			(xy 307.34685 -304.522918) (xy 307.331266 -304.569599) (xy 307.308395 -304.613176) (xy 307.27883 -304.65252)
			(xy 307.243337 -304.686612) (xy 307.202834 -304.714568) (xy 307.158372 -304.735666) (xy 307.111101 -304.749358)
			(xy 307.062246 -304.75529) (xy 307.013071 -304.753309) (xy 306.964852 -304.743465) (xy 306.918836 -304.726013)
			(xy 306.876215 -304.701406) (xy 306.838094 -304.670281) (xy 306.805459 -304.633444) (xy 306.779156 -304.591848)
			(xy 306.759865 -304.546572) (xy 306.748088 -304.498788) (xy 306.744128 -304.449734) (xy 306.405026 -304.449734)
			(xy 306.404531 -304.474341) (xy 306.396636 -304.522918) (xy 306.381052 -304.569599) (xy 306.358181 -304.613176)
			(xy 306.328616 -304.65252) (xy 306.293123 -304.686612) (xy 306.25262 -304.714568) (xy 306.208158 -304.735666)
			(xy 306.160887 -304.749358) (xy 306.112032 -304.75529) (xy 306.062857 -304.753309) (xy 306.014638 -304.743465)
			(xy 305.968622 -304.726013) (xy 305.926001 -304.701406) (xy 305.88788 -304.670281) (xy 305.855245 -304.633444)
			(xy 305.828942 -304.591848) (xy 305.809651 -304.546572) (xy 305.797874 -304.498788) (xy 305.793914 -304.449734)
			(xy 282.78582 -304.449734) (xy 282.31084 -304.924714) (xy 300.56888 -304.924714) (xy 300.57284 -304.87566)
			(xy 300.584617 -304.827876) (xy 300.603908 -304.7826) (xy 300.630211 -304.741004) (xy 300.662846 -304.704167)
			(xy 300.700967 -304.673042) (xy 300.743588 -304.648435) (xy 300.789604 -304.630983) (xy 300.837823 -304.621139)
			(xy 300.886998 -304.619158) (xy 300.935853 -304.62509) (xy 300.983124 -304.638782) (xy 301.027586 -304.65988)
			(xy 301.068089 -304.687836) (xy 301.103582 -304.721928) (xy 301.133147 -304.761272) (xy 301.156018 -304.804849)
			(xy 301.171602 -304.85153) (xy 301.179497 -304.900107) (xy 301.179992 -304.924714) (xy 301.519094 -304.924714)
			(xy 301.523054 -304.87566) (xy 301.534831 -304.827876) (xy 301.554122 -304.7826) (xy 301.580425 -304.741004)
			(xy 301.61306 -304.704167) (xy 301.651181 -304.673042) (xy 301.693802 -304.648435) (xy 301.739818 -304.630983)
			(xy 301.788037 -304.621139) (xy 301.837212 -304.619158) (xy 301.886067 -304.62509) (xy 301.933338 -304.638782)
			(xy 301.9778 -304.65988) (xy 302.018303 -304.687836) (xy 302.053796 -304.721928) (xy 302.083361 -304.761272)
			(xy 302.106232 -304.804849) (xy 302.121816 -304.85153) (xy 302.129711 -304.900107) (xy 302.130206 -304.924714)
			(xy 302.469054 -304.924714) (xy 302.473014 -304.87566) (xy 302.484791 -304.827876) (xy 302.504082 -304.7826)
			(xy 302.530385 -304.741004) (xy 302.56302 -304.704167) (xy 302.601141 -304.673042) (xy 302.643762 -304.648435)
			(xy 302.689778 -304.630983) (xy 302.737997 -304.621139) (xy 302.787172 -304.619158) (xy 302.836027 -304.62509)
			(xy 302.883298 -304.638782) (xy 302.92776 -304.65988) (xy 302.968263 -304.687836) (xy 303.003756 -304.721928)
			(xy 303.033321 -304.761272) (xy 303.056192 -304.804849) (xy 303.071776 -304.85153) (xy 303.079671 -304.900107)
			(xy 303.080166 -304.924714) (xy 303.419014 -304.924714) (xy 303.422974 -304.87566) (xy 303.434751 -304.827876)
			(xy 303.454042 -304.7826) (xy 303.480345 -304.741004) (xy 303.51298 -304.704167) (xy 303.551101 -304.673042)
			(xy 303.593722 -304.648435) (xy 303.639738 -304.630983) (xy 303.687957 -304.621139) (xy 303.737132 -304.619158)
			(xy 303.785987 -304.62509) (xy 303.833258 -304.638782) (xy 303.87772 -304.65988) (xy 303.918223 -304.687836)
			(xy 303.953716 -304.721928) (xy 303.983281 -304.761272) (xy 304.006152 -304.804849) (xy 304.021736 -304.85153)
			(xy 304.029631 -304.900107) (xy 304.030126 -304.924714) (xy 304.368974 -304.924714) (xy 304.372934 -304.87566)
			(xy 304.384711 -304.827876) (xy 304.404002 -304.7826) (xy 304.430305 -304.741004) (xy 304.46294 -304.704167)
			(xy 304.501061 -304.673042) (xy 304.543682 -304.648435) (xy 304.589698 -304.630983) (xy 304.637917 -304.621139)
			(xy 304.687092 -304.619158) (xy 304.735947 -304.62509) (xy 304.783218 -304.638782) (xy 304.82768 -304.65988)
			(xy 304.868183 -304.687836) (xy 304.903676 -304.721928) (xy 304.933241 -304.761272) (xy 304.956112 -304.804849)
			(xy 304.971696 -304.85153) (xy 304.979591 -304.900107) (xy 304.980086 -304.924714) (xy 304.979591 -304.949321)
			(xy 304.971696 -304.997898) (xy 304.956112 -305.044579) (xy 304.933241 -305.088156) (xy 304.903676 -305.1275)
			(xy 304.868183 -305.161592) (xy 304.82768 -305.189548) (xy 304.783218 -305.210646) (xy 304.735947 -305.224338)
			(xy 304.687092 -305.23027) (xy 304.637917 -305.228289) (xy 304.589698 -305.218445) (xy 304.543682 -305.200993)
			(xy 304.501061 -305.176386) (xy 304.46294 -305.145261) (xy 304.430305 -305.108424) (xy 304.404002 -305.066828)
			(xy 304.384711 -305.021552) (xy 304.372934 -304.973768) (xy 304.368974 -304.924714) (xy 304.030126 -304.924714)
			(xy 304.029631 -304.949321) (xy 304.021736 -304.997898) (xy 304.006152 -305.044579) (xy 303.983281 -305.088156)
			(xy 303.953716 -305.1275) (xy 303.918223 -305.161592) (xy 303.87772 -305.189548) (xy 303.833258 -305.210646)
			(xy 303.785987 -305.224338) (xy 303.737132 -305.23027) (xy 303.687957 -305.228289) (xy 303.639738 -305.218445)
			(xy 303.593722 -305.200993) (xy 303.551101 -305.176386) (xy 303.51298 -305.145261) (xy 303.480345 -305.108424)
			(xy 303.454042 -305.066828) (xy 303.434751 -305.021552) (xy 303.422974 -304.973768) (xy 303.419014 -304.924714)
			(xy 303.080166 -304.924714) (xy 303.079671 -304.949321) (xy 303.071776 -304.997898) (xy 303.056192 -305.044579)
			(xy 303.033321 -305.088156) (xy 303.003756 -305.1275) (xy 302.968263 -305.161592) (xy 302.92776 -305.189548)
			(xy 302.883298 -305.210646) (xy 302.836027 -305.224338) (xy 302.787172 -305.23027) (xy 302.737997 -305.228289)
			(xy 302.689778 -305.218445) (xy 302.643762 -305.200993) (xy 302.601141 -305.176386) (xy 302.56302 -305.145261)
			(xy 302.530385 -305.108424) (xy 302.504082 -305.066828) (xy 302.484791 -305.021552) (xy 302.473014 -304.973768)
			(xy 302.469054 -304.924714) (xy 302.130206 -304.924714) (xy 302.129711 -304.949321) (xy 302.121816 -304.997898)
			(xy 302.106232 -305.044579) (xy 302.083361 -305.088156) (xy 302.053796 -305.1275) (xy 302.018303 -305.161592)
			(xy 301.9778 -305.189548) (xy 301.933338 -305.210646) (xy 301.886067 -305.224338) (xy 301.837212 -305.23027)
			(xy 301.788037 -305.228289) (xy 301.739818 -305.218445) (xy 301.693802 -305.200993) (xy 301.651181 -305.176386)
			(xy 301.61306 -305.145261) (xy 301.580425 -305.108424) (xy 301.554122 -305.066828) (xy 301.534831 -305.021552)
			(xy 301.523054 -304.973768) (xy 301.519094 -304.924714) (xy 301.179992 -304.924714) (xy 301.179497 -304.949321)
			(xy 301.171602 -304.997898) (xy 301.156018 -305.044579) (xy 301.133147 -305.088156) (xy 301.103582 -305.1275)
			(xy 301.068089 -305.161592) (xy 301.027586 -305.189548) (xy 300.983124 -305.210646) (xy 300.935853 -305.224338)
			(xy 300.886998 -305.23027) (xy 300.837823 -305.228289) (xy 300.789604 -305.218445) (xy 300.743588 -305.200993)
			(xy 300.700967 -305.176386) (xy 300.662846 -305.145261) (xy 300.630211 -305.108424) (xy 300.603908 -305.066828)
			(xy 300.584617 -305.021552) (xy 300.57284 -304.973768) (xy 300.56888 -304.924714) (xy 282.31084 -304.924714)
			(xy 282.234132 -305.001422) (xy 282.226766 -305.008534) (xy 282.219146 -305.02733) (xy 282.219146 -305.399948)
			(xy 305.793914 -305.399948) (xy 305.797874 -305.350894) (xy 305.809651 -305.30311) (xy 305.828942 -305.257834)
			(xy 305.855245 -305.216238) (xy 305.88788 -305.179401) (xy 305.926001 -305.148276) (xy 305.968622 -305.123669)
			(xy 306.014638 -305.106217) (xy 306.062857 -305.096373) (xy 306.112032 -305.094392) (xy 306.160887 -305.100324)
			(xy 306.208158 -305.114016) (xy 306.25262 -305.135114) (xy 306.293123 -305.16307) (xy 306.328616 -305.197162)
			(xy 306.358181 -305.236506) (xy 306.381052 -305.280083) (xy 306.396636 -305.326764) (xy 306.404531 -305.375341)
			(xy 306.405026 -305.399948) (xy 306.744128 -305.399948) (xy 306.748088 -305.350894) (xy 306.759865 -305.30311)
			(xy 306.779156 -305.257834) (xy 306.805459 -305.216238) (xy 306.838094 -305.179401) (xy 306.876215 -305.148276)
			(xy 306.918836 -305.123669) (xy 306.964852 -305.106217) (xy 307.013071 -305.096373) (xy 307.062246 -305.094392)
			(xy 307.111101 -305.100324) (xy 307.158372 -305.114016) (xy 307.202834 -305.135114) (xy 307.243337 -305.16307)
			(xy 307.27883 -305.197162) (xy 307.308395 -305.236506) (xy 307.331266 -305.280083) (xy 307.34685 -305.326764)
			(xy 307.354745 -305.375341) (xy 307.35524 -305.399948) (xy 307.694088 -305.399948) (xy 307.698048 -305.350894)
			(xy 307.709825 -305.30311) (xy 307.729116 -305.257834) (xy 307.755419 -305.216238) (xy 307.788054 -305.179401)
			(xy 307.826175 -305.148276) (xy 307.868796 -305.123669) (xy 307.914812 -305.106217) (xy 307.963031 -305.096373)
			(xy 308.012206 -305.094392) (xy 308.061061 -305.100324) (xy 308.108332 -305.114016) (xy 308.152794 -305.135114)
			(xy 308.193297 -305.16307) (xy 308.22879 -305.197162) (xy 308.258355 -305.236506) (xy 308.281226 -305.280083)
			(xy 308.29681 -305.326764) (xy 308.304705 -305.375341) (xy 308.3052 -305.399948) (xy 308.644048 -305.399948)
			(xy 308.648008 -305.350894) (xy 308.659785 -305.30311) (xy 308.679076 -305.257834) (xy 308.705379 -305.216238)
			(xy 308.738014 -305.179401) (xy 308.776135 -305.148276) (xy 308.818756 -305.123669) (xy 308.864772 -305.106217)
			(xy 308.912991 -305.096373) (xy 308.962166 -305.094392) (xy 309.011021 -305.100324) (xy 309.058292 -305.114016)
			(xy 309.102754 -305.135114) (xy 309.143257 -305.16307) (xy 309.17875 -305.197162) (xy 309.208315 -305.236506)
			(xy 309.231186 -305.280083) (xy 309.24677 -305.326764) (xy 309.254665 -305.375341) (xy 309.25516 -305.399948)
			(xy 309.594008 -305.399948) (xy 309.597968 -305.350894) (xy 309.609745 -305.30311) (xy 309.629036 -305.257834)
			(xy 309.655339 -305.216238) (xy 309.687974 -305.179401) (xy 309.726095 -305.148276) (xy 309.768716 -305.123669)
			(xy 309.814732 -305.106217) (xy 309.862951 -305.096373) (xy 309.912126 -305.094392) (xy 309.960981 -305.100324)
			(xy 310.008252 -305.114016) (xy 310.052714 -305.135114) (xy 310.093217 -305.16307) (xy 310.12871 -305.197162)
			(xy 310.158275 -305.236506) (xy 310.181146 -305.280083) (xy 310.19673 -305.326764) (xy 310.204625 -305.375341)
			(xy 310.20512 -305.399948) (xy 310.543968 -305.399948) (xy 310.547928 -305.350894) (xy 310.559705 -305.30311)
			(xy 310.578996 -305.257834) (xy 310.605299 -305.216238) (xy 310.637934 -305.179401) (xy 310.676055 -305.148276)
			(xy 310.718676 -305.123669) (xy 310.764692 -305.106217) (xy 310.812911 -305.096373) (xy 310.862086 -305.094392)
			(xy 310.910941 -305.100324) (xy 310.958212 -305.114016) (xy 311.002674 -305.135114) (xy 311.043177 -305.16307)
			(xy 311.07867 -305.197162) (xy 311.108235 -305.236506) (xy 311.131106 -305.280083) (xy 311.14669 -305.326764)
			(xy 311.154585 -305.375341) (xy 311.15508 -305.399948) (xy 311.493928 -305.399948) (xy 311.497888 -305.350894)
			(xy 311.509665 -305.30311) (xy 311.528956 -305.257834) (xy 311.555259 -305.216238) (xy 311.587894 -305.179401)
			(xy 311.626015 -305.148276) (xy 311.668636 -305.123669) (xy 311.714652 -305.106217) (xy 311.762871 -305.096373)
			(xy 311.812046 -305.094392) (xy 311.860901 -305.100324) (xy 311.908172 -305.114016) (xy 311.952634 -305.135114)
			(xy 311.993137 -305.16307) (xy 312.02863 -305.197162) (xy 312.058195 -305.236506) (xy 312.081066 -305.280083)
			(xy 312.09665 -305.326764) (xy 312.104545 -305.375341) (xy 312.10504 -305.399948) (xy 312.443888 -305.399948)
			(xy 312.447848 -305.350894) (xy 312.459625 -305.30311) (xy 312.478916 -305.257834) (xy 312.505219 -305.216238)
			(xy 312.537854 -305.179401) (xy 312.575975 -305.148276) (xy 312.618596 -305.123669) (xy 312.664612 -305.106217)
			(xy 312.712831 -305.096373) (xy 312.762006 -305.094392) (xy 312.810861 -305.100324) (xy 312.858132 -305.114016)
			(xy 312.902594 -305.135114) (xy 312.943097 -305.16307) (xy 312.97859 -305.197162) (xy 313.008155 -305.236506)
			(xy 313.031026 -305.280083) (xy 313.04661 -305.326764) (xy 313.054505 -305.375341) (xy 313.055 -305.399948)
			(xy 313.394102 -305.399948) (xy 313.398062 -305.350894) (xy 313.409839 -305.30311) (xy 313.42913 -305.257834)
			(xy 313.455433 -305.216238) (xy 313.488068 -305.179401) (xy 313.526189 -305.148276) (xy 313.56881 -305.123669)
			(xy 313.614826 -305.106217) (xy 313.663045 -305.096373) (xy 313.71222 -305.094392) (xy 313.761075 -305.100324)
			(xy 313.808346 -305.114016) (xy 313.852808 -305.135114) (xy 313.893311 -305.16307) (xy 313.928804 -305.197162)
			(xy 313.958369 -305.236506) (xy 313.98124 -305.280083) (xy 313.996824 -305.326764) (xy 314.004719 -305.375341)
			(xy 314.005214 -305.399948) (xy 314.344062 -305.399948) (xy 314.348022 -305.350894) (xy 314.359799 -305.30311)
			(xy 314.37909 -305.257834) (xy 314.405393 -305.216238) (xy 314.438028 -305.179401) (xy 314.476149 -305.148276)
			(xy 314.51877 -305.123669) (xy 314.564786 -305.106217) (xy 314.613005 -305.096373) (xy 314.66218 -305.094392)
			(xy 314.711035 -305.100324) (xy 314.758306 -305.114016) (xy 314.802768 -305.135114) (xy 314.843271 -305.16307)
			(xy 314.878764 -305.197162) (xy 314.908329 -305.236506) (xy 314.9312 -305.280083) (xy 314.946784 -305.326764)
			(xy 314.954679 -305.375341) (xy 314.955174 -305.399948) (xy 314.954679 -305.424555) (xy 314.946784 -305.473132)
			(xy 314.9312 -305.519813) (xy 314.908329 -305.56339) (xy 314.878764 -305.602734) (xy 314.843271 -305.636826)
			(xy 314.802768 -305.664782) (xy 314.758306 -305.68588) (xy 314.711035 -305.699572) (xy 314.66218 -305.705504)
			(xy 314.613005 -305.703523) (xy 314.564786 -305.693679) (xy 314.51877 -305.676227) (xy 314.476149 -305.65162)
			(xy 314.438028 -305.620495) (xy 314.405393 -305.583658) (xy 314.37909 -305.542062) (xy 314.359799 -305.496786)
			(xy 314.348022 -305.449002) (xy 314.344062 -305.399948) (xy 314.005214 -305.399948) (xy 314.004719 -305.424555)
			(xy 313.996824 -305.473132) (xy 313.98124 -305.519813) (xy 313.958369 -305.56339) (xy 313.928804 -305.602734)
			(xy 313.893311 -305.636826) (xy 313.852808 -305.664782) (xy 313.808346 -305.68588) (xy 313.761075 -305.699572)
			(xy 313.71222 -305.705504) (xy 313.663045 -305.703523) (xy 313.614826 -305.693679) (xy 313.56881 -305.676227)
			(xy 313.526189 -305.65162) (xy 313.488068 -305.620495) (xy 313.455433 -305.583658) (xy 313.42913 -305.542062)
			(xy 313.409839 -305.496786) (xy 313.398062 -305.449002) (xy 313.394102 -305.399948) (xy 313.055 -305.399948)
			(xy 313.054505 -305.424555) (xy 313.04661 -305.473132) (xy 313.031026 -305.519813) (xy 313.008155 -305.56339)
			(xy 312.97859 -305.602734) (xy 312.943097 -305.636826) (xy 312.902594 -305.664782) (xy 312.858132 -305.68588)
			(xy 312.810861 -305.699572) (xy 312.762006 -305.705504) (xy 312.712831 -305.703523) (xy 312.664612 -305.693679)
			(xy 312.618596 -305.676227) (xy 312.575975 -305.65162) (xy 312.537854 -305.620495) (xy 312.505219 -305.583658)
			(xy 312.478916 -305.542062) (xy 312.459625 -305.496786) (xy 312.447848 -305.449002) (xy 312.443888 -305.399948)
			(xy 312.10504 -305.399948) (xy 312.104545 -305.424555) (xy 312.09665 -305.473132) (xy 312.081066 -305.519813)
			(xy 312.058195 -305.56339) (xy 312.02863 -305.602734) (xy 311.993137 -305.636826) (xy 311.952634 -305.664782)
			(xy 311.908172 -305.68588) (xy 311.860901 -305.699572) (xy 311.812046 -305.705504) (xy 311.762871 -305.703523)
			(xy 311.714652 -305.693679) (xy 311.668636 -305.676227) (xy 311.626015 -305.65162) (xy 311.587894 -305.620495)
			(xy 311.555259 -305.583658) (xy 311.528956 -305.542062) (xy 311.509665 -305.496786) (xy 311.497888 -305.449002)
			(xy 311.493928 -305.399948) (xy 311.15508 -305.399948) (xy 311.154585 -305.424555) (xy 311.14669 -305.473132)
			(xy 311.131106 -305.519813) (xy 311.108235 -305.56339) (xy 311.07867 -305.602734) (xy 311.043177 -305.636826)
			(xy 311.002674 -305.664782) (xy 310.958212 -305.68588) (xy 310.910941 -305.699572) (xy 310.862086 -305.705504)
			(xy 310.812911 -305.703523) (xy 310.764692 -305.693679) (xy 310.718676 -305.676227) (xy 310.676055 -305.65162)
			(xy 310.637934 -305.620495) (xy 310.605299 -305.583658) (xy 310.578996 -305.542062) (xy 310.559705 -305.496786)
			(xy 310.547928 -305.449002) (xy 310.543968 -305.399948) (xy 310.20512 -305.399948) (xy 310.204625 -305.424555)
			(xy 310.19673 -305.473132) (xy 310.181146 -305.519813) (xy 310.158275 -305.56339) (xy 310.12871 -305.602734)
			(xy 310.093217 -305.636826) (xy 310.052714 -305.664782) (xy 310.008252 -305.68588) (xy 309.960981 -305.699572)
			(xy 309.912126 -305.705504) (xy 309.862951 -305.703523) (xy 309.814732 -305.693679) (xy 309.768716 -305.676227)
			(xy 309.726095 -305.65162) (xy 309.687974 -305.620495) (xy 309.655339 -305.583658) (xy 309.629036 -305.542062)
			(xy 309.609745 -305.496786) (xy 309.597968 -305.449002) (xy 309.594008 -305.399948) (xy 309.25516 -305.399948)
			(xy 309.254665 -305.424555) (xy 309.24677 -305.473132) (xy 309.231186 -305.519813) (xy 309.208315 -305.56339)
			(xy 309.17875 -305.602734) (xy 309.143257 -305.636826) (xy 309.102754 -305.664782) (xy 309.058292 -305.68588)
			(xy 309.011021 -305.699572) (xy 308.962166 -305.705504) (xy 308.912991 -305.703523) (xy 308.864772 -305.693679)
			(xy 308.818756 -305.676227) (xy 308.776135 -305.65162) (xy 308.738014 -305.620495) (xy 308.705379 -305.583658)
			(xy 308.679076 -305.542062) (xy 308.659785 -305.496786) (xy 308.648008 -305.449002) (xy 308.644048 -305.399948)
			(xy 308.3052 -305.399948) (xy 308.304705 -305.424555) (xy 308.29681 -305.473132) (xy 308.281226 -305.519813)
			(xy 308.258355 -305.56339) (xy 308.22879 -305.602734) (xy 308.193297 -305.636826) (xy 308.152794 -305.664782)
			(xy 308.108332 -305.68588) (xy 308.061061 -305.699572) (xy 308.012206 -305.705504) (xy 307.963031 -305.703523)
			(xy 307.914812 -305.693679) (xy 307.868796 -305.676227) (xy 307.826175 -305.65162) (xy 307.788054 -305.620495)
			(xy 307.755419 -305.583658) (xy 307.729116 -305.542062) (xy 307.709825 -305.496786) (xy 307.698048 -305.449002)
			(xy 307.694088 -305.399948) (xy 307.35524 -305.399948) (xy 307.354745 -305.424555) (xy 307.34685 -305.473132)
			(xy 307.331266 -305.519813) (xy 307.308395 -305.56339) (xy 307.27883 -305.602734) (xy 307.243337 -305.636826)
			(xy 307.202834 -305.664782) (xy 307.158372 -305.68588) (xy 307.111101 -305.699572) (xy 307.062246 -305.705504)
			(xy 307.013071 -305.703523) (xy 306.964852 -305.693679) (xy 306.918836 -305.676227) (xy 306.876215 -305.65162)
			(xy 306.838094 -305.620495) (xy 306.805459 -305.583658) (xy 306.779156 -305.542062) (xy 306.759865 -305.496786)
			(xy 306.748088 -305.449002) (xy 306.744128 -305.399948) (xy 306.405026 -305.399948) (xy 306.404531 -305.424555)
			(xy 306.396636 -305.473132) (xy 306.381052 -305.519813) (xy 306.358181 -305.56339) (xy 306.328616 -305.602734)
			(xy 306.293123 -305.636826) (xy 306.25262 -305.664782) (xy 306.208158 -305.68588) (xy 306.160887 -305.699572)
			(xy 306.112032 -305.705504) (xy 306.062857 -305.703523) (xy 306.014638 -305.693679) (xy 305.968622 -305.676227)
			(xy 305.926001 -305.65162) (xy 305.88788 -305.620495) (xy 305.855245 -305.583658) (xy 305.828942 -305.542062)
			(xy 305.809651 -305.496786) (xy 305.797874 -305.449002) (xy 305.793914 -305.399948) (xy 282.219146 -305.399948)
			(xy 282.219146 -305.874928) (xy 282.519132 -305.874928) (xy 282.523092 -305.825874) (xy 282.534869 -305.77809)
			(xy 282.55416 -305.732814) (xy 282.580463 -305.691218) (xy 282.613098 -305.654381) (xy 282.651219 -305.623256)
			(xy 282.69384 -305.598649) (xy 282.739856 -305.581197) (xy 282.788075 -305.571353) (xy 282.83725 -305.569372)
			(xy 282.886105 -305.575304) (xy 282.933376 -305.588996) (xy 282.977838 -305.610094) (xy 283.018341 -305.63805)
			(xy 283.053834 -305.672142) (xy 283.083399 -305.711486) (xy 283.10627 -305.755063) (xy 283.121854 -305.801744)
			(xy 283.129749 -305.850321) (xy 283.130244 -305.874928) (xy 283.469092 -305.874928) (xy 283.473052 -305.825874)
			(xy 283.484829 -305.77809) (xy 283.50412 -305.732814) (xy 283.530423 -305.691218) (xy 283.563058 -305.654381)
			(xy 283.601179 -305.623256) (xy 283.6438 -305.598649) (xy 283.689816 -305.581197) (xy 283.738035 -305.571353)
			(xy 283.78721 -305.569372) (xy 283.836065 -305.575304) (xy 283.883336 -305.588996) (xy 283.927798 -305.610094)
			(xy 283.968301 -305.63805) (xy 284.003794 -305.672142) (xy 284.033359 -305.711486) (xy 284.05623 -305.755063)
			(xy 284.071814 -305.801744) (xy 284.079709 -305.850321) (xy 284.080204 -305.874928) (xy 284.419052 -305.874928)
			(xy 284.423012 -305.825874) (xy 284.434789 -305.77809) (xy 284.45408 -305.732814) (xy 284.480383 -305.691218)
			(xy 284.513018 -305.654381) (xy 284.551139 -305.623256) (xy 284.59376 -305.598649) (xy 284.639776 -305.581197)
			(xy 284.687995 -305.571353) (xy 284.73717 -305.569372) (xy 284.786025 -305.575304) (xy 284.833296 -305.588996)
			(xy 284.877758 -305.610094) (xy 284.918261 -305.63805) (xy 284.953754 -305.672142) (xy 284.983319 -305.711486)
			(xy 285.00619 -305.755063) (xy 285.021774 -305.801744) (xy 285.029669 -305.850321) (xy 285.030164 -305.874928)
			(xy 285.369012 -305.874928) (xy 285.372972 -305.825874) (xy 285.384749 -305.77809) (xy 285.40404 -305.732814)
			(xy 285.430343 -305.691218) (xy 285.462978 -305.654381) (xy 285.501099 -305.623256) (xy 285.54372 -305.598649)
			(xy 285.589736 -305.581197) (xy 285.637955 -305.571353) (xy 285.68713 -305.569372) (xy 285.735985 -305.575304)
			(xy 285.783256 -305.588996) (xy 285.827718 -305.610094) (xy 285.868221 -305.63805) (xy 285.903714 -305.672142)
			(xy 285.933279 -305.711486) (xy 285.95615 -305.755063) (xy 285.971734 -305.801744) (xy 285.979629 -305.850321)
			(xy 285.980124 -305.874928) (xy 286.318972 -305.874928) (xy 286.322932 -305.825874) (xy 286.334709 -305.77809)
			(xy 286.354 -305.732814) (xy 286.380303 -305.691218) (xy 286.412938 -305.654381) (xy 286.451059 -305.623256)
			(xy 286.49368 -305.598649) (xy 286.539696 -305.581197) (xy 286.587915 -305.571353) (xy 286.63709 -305.569372)
			(xy 286.685945 -305.575304) (xy 286.733216 -305.588996) (xy 286.777678 -305.610094) (xy 286.818181 -305.63805)
			(xy 286.853674 -305.672142) (xy 286.883239 -305.711486) (xy 286.90611 -305.755063) (xy 286.921694 -305.801744)
			(xy 286.929589 -305.850321) (xy 286.930084 -305.874928) (xy 287.268932 -305.874928) (xy 287.272892 -305.825874)
			(xy 287.284669 -305.77809) (xy 287.30396 -305.732814) (xy 287.330263 -305.691218) (xy 287.362898 -305.654381)
			(xy 287.401019 -305.623256) (xy 287.44364 -305.598649) (xy 287.489656 -305.581197) (xy 287.537875 -305.571353)
			(xy 287.58705 -305.569372) (xy 287.635905 -305.575304) (xy 287.683176 -305.588996) (xy 287.727638 -305.610094)
			(xy 287.768141 -305.63805) (xy 287.803634 -305.672142) (xy 287.833199 -305.711486) (xy 287.85607 -305.755063)
			(xy 287.871654 -305.801744) (xy 287.879549 -305.850321) (xy 287.880044 -305.874928) (xy 288.218892 -305.874928)
			(xy 288.222852 -305.825874) (xy 288.234629 -305.77809) (xy 288.25392 -305.732814) (xy 288.280223 -305.691218)
			(xy 288.312858 -305.654381) (xy 288.350979 -305.623256) (xy 288.3936 -305.598649) (xy 288.439616 -305.581197)
			(xy 288.487835 -305.571353) (xy 288.53701 -305.569372) (xy 288.585865 -305.575304) (xy 288.633136 -305.588996)
			(xy 288.677598 -305.610094) (xy 288.718101 -305.63805) (xy 288.753594 -305.672142) (xy 288.783159 -305.711486)
			(xy 288.80603 -305.755063) (xy 288.821614 -305.801744) (xy 288.829509 -305.850321) (xy 288.830004 -305.874928)
			(xy 289.169106 -305.874928) (xy 289.173066 -305.825874) (xy 289.184843 -305.77809) (xy 289.204134 -305.732814)
			(xy 289.230437 -305.691218) (xy 289.263072 -305.654381) (xy 289.301193 -305.623256) (xy 289.343814 -305.598649)
			(xy 289.38983 -305.581197) (xy 289.438049 -305.571353) (xy 289.487224 -305.569372) (xy 289.536079 -305.575304)
			(xy 289.58335 -305.588996) (xy 289.627812 -305.610094) (xy 289.668315 -305.63805) (xy 289.703808 -305.672142)
			(xy 289.733373 -305.711486) (xy 289.756244 -305.755063) (xy 289.771828 -305.801744) (xy 289.779723 -305.850321)
			(xy 289.780218 -305.874928) (xy 290.119066 -305.874928) (xy 290.123026 -305.825874) (xy 290.134803 -305.77809)
			(xy 290.154094 -305.732814) (xy 290.180397 -305.691218) (xy 290.213032 -305.654381) (xy 290.251153 -305.623256)
			(xy 290.293774 -305.598649) (xy 290.33979 -305.581197) (xy 290.388009 -305.571353) (xy 290.437184 -305.569372)
			(xy 290.486039 -305.575304) (xy 290.53331 -305.588996) (xy 290.577772 -305.610094) (xy 290.618275 -305.63805)
			(xy 290.653768 -305.672142) (xy 290.683333 -305.711486) (xy 290.706204 -305.755063) (xy 290.721788 -305.801744)
			(xy 290.729683 -305.850321) (xy 290.730178 -305.874928) (xy 292.018986 -305.874928) (xy 292.022946 -305.825874)
			(xy 292.034723 -305.77809) (xy 292.054014 -305.732814) (xy 292.080317 -305.691218) (xy 292.112952 -305.654381)
			(xy 292.151073 -305.623256) (xy 292.193694 -305.598649) (xy 292.23971 -305.581197) (xy 292.287929 -305.571353)
			(xy 292.337104 -305.569372) (xy 292.385959 -305.575304) (xy 292.43323 -305.588996) (xy 292.477692 -305.610094)
			(xy 292.518195 -305.63805) (xy 292.553688 -305.672142) (xy 292.583253 -305.711486) (xy 292.606124 -305.755063)
			(xy 292.621708 -305.801744) (xy 292.629603 -305.850321) (xy 292.630098 -305.874928) (xy 292.968946 -305.874928)
			(xy 292.972906 -305.825874) (xy 292.984683 -305.77809) (xy 293.003974 -305.732814) (xy 293.030277 -305.691218)
			(xy 293.062912 -305.654381) (xy 293.101033 -305.623256) (xy 293.143654 -305.598649) (xy 293.18967 -305.581197)
			(xy 293.237889 -305.571353) (xy 293.287064 -305.569372) (xy 293.335919 -305.575304) (xy 293.38319 -305.588996)
			(xy 293.427652 -305.610094) (xy 293.468155 -305.63805) (xy 293.503648 -305.672142) (xy 293.533213 -305.711486)
			(xy 293.556084 -305.755063) (xy 293.571668 -305.801744) (xy 293.579563 -305.850321) (xy 293.580058 -305.874928)
			(xy 293.918906 -305.874928) (xy 293.922866 -305.825874) (xy 293.934643 -305.77809) (xy 293.953934 -305.732814)
			(xy 293.980237 -305.691218) (xy 294.012872 -305.654381) (xy 294.050993 -305.623256) (xy 294.093614 -305.598649)
			(xy 294.13963 -305.581197) (xy 294.187849 -305.571353) (xy 294.237024 -305.569372) (xy 294.285879 -305.575304)
			(xy 294.33315 -305.588996) (xy 294.377612 -305.610094) (xy 294.418115 -305.63805) (xy 294.453608 -305.672142)
			(xy 294.483173 -305.711486) (xy 294.506044 -305.755063) (xy 294.521628 -305.801744) (xy 294.529523 -305.850321)
			(xy 294.530018 -305.874928) (xy 294.86912 -305.874928) (xy 294.87308 -305.825874) (xy 294.884857 -305.77809)
			(xy 294.904148 -305.732814) (xy 294.930451 -305.691218) (xy 294.963086 -305.654381) (xy 295.001207 -305.623256)
			(xy 295.043828 -305.598649) (xy 295.089844 -305.581197) (xy 295.138063 -305.571353) (xy 295.187238 -305.569372)
			(xy 295.236093 -305.575304) (xy 295.283364 -305.588996) (xy 295.327826 -305.610094) (xy 295.368329 -305.63805)
			(xy 295.403822 -305.672142) (xy 295.433387 -305.711486) (xy 295.456258 -305.755063) (xy 295.471842 -305.801744)
			(xy 295.479737 -305.850321) (xy 295.480232 -305.874928) (xy 295.81908 -305.874928) (xy 295.82304 -305.825874)
			(xy 295.834817 -305.77809) (xy 295.854108 -305.732814) (xy 295.880411 -305.691218) (xy 295.913046 -305.654381)
			(xy 295.951167 -305.623256) (xy 295.993788 -305.598649) (xy 296.039804 -305.581197) (xy 296.088023 -305.571353)
			(xy 296.137198 -305.569372) (xy 296.186053 -305.575304) (xy 296.233324 -305.588996) (xy 296.277786 -305.610094)
			(xy 296.318289 -305.63805) (xy 296.353782 -305.672142) (xy 296.383347 -305.711486) (xy 296.406218 -305.755063)
			(xy 296.421802 -305.801744) (xy 296.429697 -305.850321) (xy 296.430192 -305.874928) (xy 296.76904 -305.874928)
			(xy 296.773 -305.825874) (xy 296.784777 -305.77809) (xy 296.804068 -305.732814) (xy 296.830371 -305.691218)
			(xy 296.863006 -305.654381) (xy 296.901127 -305.623256) (xy 296.943748 -305.598649) (xy 296.989764 -305.581197)
			(xy 297.037983 -305.571353) (xy 297.087158 -305.569372) (xy 297.136013 -305.575304) (xy 297.183284 -305.588996)
			(xy 297.227746 -305.610094) (xy 297.268249 -305.63805) (xy 297.303742 -305.672142) (xy 297.333307 -305.711486)
			(xy 297.356178 -305.755063) (xy 297.371762 -305.801744) (xy 297.379657 -305.850321) (xy 297.380152 -305.874928)
			(xy 297.719 -305.874928) (xy 297.72296 -305.825874) (xy 297.734737 -305.77809) (xy 297.754028 -305.732814)
			(xy 297.780331 -305.691218) (xy 297.812966 -305.654381) (xy 297.851087 -305.623256) (xy 297.893708 -305.598649)
			(xy 297.939724 -305.581197) (xy 297.987943 -305.571353) (xy 298.037118 -305.569372) (xy 298.085973 -305.575304)
			(xy 298.133244 -305.588996) (xy 298.177706 -305.610094) (xy 298.218209 -305.63805) (xy 298.253702 -305.672142)
			(xy 298.283267 -305.711486) (xy 298.306138 -305.755063) (xy 298.321722 -305.801744) (xy 298.329617 -305.850321)
			(xy 298.330112 -305.874928) (xy 298.66896 -305.874928) (xy 298.67292 -305.825874) (xy 298.684697 -305.77809)
			(xy 298.703988 -305.732814) (xy 298.730291 -305.691218) (xy 298.762926 -305.654381) (xy 298.801047 -305.623256)
			(xy 298.843668 -305.598649) (xy 298.889684 -305.581197) (xy 298.937903 -305.571353) (xy 298.987078 -305.569372)
			(xy 299.035933 -305.575304) (xy 299.083204 -305.588996) (xy 299.127666 -305.610094) (xy 299.168169 -305.63805)
			(xy 299.203662 -305.672142) (xy 299.233227 -305.711486) (xy 299.256098 -305.755063) (xy 299.271682 -305.801744)
			(xy 299.279577 -305.850321) (xy 299.280072 -305.874928) (xy 299.61892 -305.874928) (xy 299.62288 -305.825874)
			(xy 299.634657 -305.77809) (xy 299.653948 -305.732814) (xy 299.680251 -305.691218) (xy 299.712886 -305.654381)
			(xy 299.751007 -305.623256) (xy 299.793628 -305.598649) (xy 299.839644 -305.581197) (xy 299.887863 -305.571353)
			(xy 299.937038 -305.569372) (xy 299.985893 -305.575304) (xy 300.033164 -305.588996) (xy 300.077626 -305.610094)
			(xy 300.118129 -305.63805) (xy 300.153622 -305.672142) (xy 300.183187 -305.711486) (xy 300.206058 -305.755063)
			(xy 300.221642 -305.801744) (xy 300.229537 -305.850321) (xy 300.230032 -305.874928) (xy 300.56888 -305.874928)
			(xy 300.57284 -305.825874) (xy 300.584617 -305.77809) (xy 300.603908 -305.732814) (xy 300.630211 -305.691218)
			(xy 300.662846 -305.654381) (xy 300.700967 -305.623256) (xy 300.743588 -305.598649) (xy 300.789604 -305.581197)
			(xy 300.837823 -305.571353) (xy 300.886998 -305.569372) (xy 300.935853 -305.575304) (xy 300.983124 -305.588996)
			(xy 301.027586 -305.610094) (xy 301.068089 -305.63805) (xy 301.103582 -305.672142) (xy 301.133147 -305.711486)
			(xy 301.156018 -305.755063) (xy 301.171602 -305.801744) (xy 301.179497 -305.850321) (xy 301.179992 -305.874928)
			(xy 301.519094 -305.874928) (xy 301.523054 -305.825874) (xy 301.534831 -305.77809) (xy 301.554122 -305.732814)
			(xy 301.580425 -305.691218) (xy 301.61306 -305.654381) (xy 301.651181 -305.623256) (xy 301.693802 -305.598649)
			(xy 301.739818 -305.581197) (xy 301.788037 -305.571353) (xy 301.837212 -305.569372) (xy 301.886067 -305.575304)
			(xy 301.933338 -305.588996) (xy 301.9778 -305.610094) (xy 302.018303 -305.63805) (xy 302.053796 -305.672142)
			(xy 302.083361 -305.711486) (xy 302.106232 -305.755063) (xy 302.121816 -305.801744) (xy 302.129711 -305.850321)
			(xy 302.130206 -305.874928) (xy 302.469054 -305.874928) (xy 302.473014 -305.825874) (xy 302.484791 -305.77809)
			(xy 302.504082 -305.732814) (xy 302.530385 -305.691218) (xy 302.56302 -305.654381) (xy 302.601141 -305.623256)
			(xy 302.643762 -305.598649) (xy 302.689778 -305.581197) (xy 302.737997 -305.571353) (xy 302.787172 -305.569372)
			(xy 302.836027 -305.575304) (xy 302.883298 -305.588996) (xy 302.92776 -305.610094) (xy 302.968263 -305.63805)
			(xy 303.003756 -305.672142) (xy 303.033321 -305.711486) (xy 303.056192 -305.755063) (xy 303.071776 -305.801744)
			(xy 303.079671 -305.850321) (xy 303.080166 -305.874928) (xy 303.419014 -305.874928) (xy 303.422974 -305.825874)
			(xy 303.434751 -305.77809) (xy 303.454042 -305.732814) (xy 303.480345 -305.691218) (xy 303.51298 -305.654381)
			(xy 303.551101 -305.623256) (xy 303.593722 -305.598649) (xy 303.639738 -305.581197) (xy 303.687957 -305.571353)
			(xy 303.737132 -305.569372) (xy 303.785987 -305.575304) (xy 303.833258 -305.588996) (xy 303.87772 -305.610094)
			(xy 303.918223 -305.63805) (xy 303.953716 -305.672142) (xy 303.983281 -305.711486) (xy 304.006152 -305.755063)
			(xy 304.021736 -305.801744) (xy 304.029631 -305.850321) (xy 304.030126 -305.874928) (xy 304.368974 -305.874928)
			(xy 304.372934 -305.825874) (xy 304.384711 -305.77809) (xy 304.404002 -305.732814) (xy 304.430305 -305.691218)
			(xy 304.46294 -305.654381) (xy 304.501061 -305.623256) (xy 304.543682 -305.598649) (xy 304.589698 -305.581197)
			(xy 304.637917 -305.571353) (xy 304.687092 -305.569372) (xy 304.735947 -305.575304) (xy 304.783218 -305.588996)
			(xy 304.82768 -305.610094) (xy 304.868183 -305.63805) (xy 304.903676 -305.672142) (xy 304.933241 -305.711486)
			(xy 304.956112 -305.755063) (xy 304.971696 -305.801744) (xy 304.979591 -305.850321) (xy 304.980086 -305.874928)
			(xy 304.979591 -305.899535) (xy 304.971696 -305.948112) (xy 304.956112 -305.994793) (xy 304.933241 -306.03837)
			(xy 304.903676 -306.077714) (xy 304.868183 -306.111806) (xy 304.82768 -306.139762) (xy 304.783218 -306.16086)
			(xy 304.735947 -306.174552) (xy 304.687092 -306.180484) (xy 304.637917 -306.178503) (xy 304.589698 -306.168659)
			(xy 304.543682 -306.151207) (xy 304.501061 -306.1266) (xy 304.46294 -306.095475) (xy 304.430305 -306.058638)
			(xy 304.404002 -306.017042) (xy 304.384711 -305.971766) (xy 304.372934 -305.923982) (xy 304.368974 -305.874928)
			(xy 304.030126 -305.874928) (xy 304.029631 -305.899535) (xy 304.021736 -305.948112) (xy 304.006152 -305.994793)
			(xy 303.983281 -306.03837) (xy 303.953716 -306.077714) (xy 303.918223 -306.111806) (xy 303.87772 -306.139762)
			(xy 303.833258 -306.16086) (xy 303.785987 -306.174552) (xy 303.737132 -306.180484) (xy 303.687957 -306.178503)
			(xy 303.639738 -306.168659) (xy 303.593722 -306.151207) (xy 303.551101 -306.1266) (xy 303.51298 -306.095475)
			(xy 303.480345 -306.058638) (xy 303.454042 -306.017042) (xy 303.434751 -305.971766) (xy 303.422974 -305.923982)
			(xy 303.419014 -305.874928) (xy 303.080166 -305.874928) (xy 303.079671 -305.899535) (xy 303.071776 -305.948112)
			(xy 303.056192 -305.994793) (xy 303.033321 -306.03837) (xy 303.003756 -306.077714) (xy 302.968263 -306.111806)
			(xy 302.92776 -306.139762) (xy 302.883298 -306.16086) (xy 302.836027 -306.174552) (xy 302.787172 -306.180484)
			(xy 302.737997 -306.178503) (xy 302.689778 -306.168659) (xy 302.643762 -306.151207) (xy 302.601141 -306.1266)
			(xy 302.56302 -306.095475) (xy 302.530385 -306.058638) (xy 302.504082 -306.017042) (xy 302.484791 -305.971766)
			(xy 302.473014 -305.923982) (xy 302.469054 -305.874928) (xy 302.130206 -305.874928) (xy 302.129711 -305.899535)
			(xy 302.121816 -305.948112) (xy 302.106232 -305.994793) (xy 302.083361 -306.03837) (xy 302.053796 -306.077714)
			(xy 302.018303 -306.111806) (xy 301.9778 -306.139762) (xy 301.933338 -306.16086) (xy 301.886067 -306.174552)
			(xy 301.837212 -306.180484) (xy 301.788037 -306.178503) (xy 301.739818 -306.168659) (xy 301.693802 -306.151207)
			(xy 301.651181 -306.1266) (xy 301.61306 -306.095475) (xy 301.580425 -306.058638) (xy 301.554122 -306.017042)
			(xy 301.534831 -305.971766) (xy 301.523054 -305.923982) (xy 301.519094 -305.874928) (xy 301.179992 -305.874928)
			(xy 301.179497 -305.899535) (xy 301.171602 -305.948112) (xy 301.156018 -305.994793) (xy 301.133147 -306.03837)
			(xy 301.103582 -306.077714) (xy 301.068089 -306.111806) (xy 301.027586 -306.139762) (xy 300.983124 -306.16086)
			(xy 300.935853 -306.174552) (xy 300.886998 -306.180484) (xy 300.837823 -306.178503) (xy 300.789604 -306.168659)
			(xy 300.743588 -306.151207) (xy 300.700967 -306.1266) (xy 300.662846 -306.095475) (xy 300.630211 -306.058638)
			(xy 300.603908 -306.017042) (xy 300.584617 -305.971766) (xy 300.57284 -305.923982) (xy 300.56888 -305.874928)
			(xy 300.230032 -305.874928) (xy 300.229537 -305.899535) (xy 300.221642 -305.948112) (xy 300.206058 -305.994793)
			(xy 300.183187 -306.03837) (xy 300.153622 -306.077714) (xy 300.118129 -306.111806) (xy 300.077626 -306.139762)
			(xy 300.033164 -306.16086) (xy 299.985893 -306.174552) (xy 299.937038 -306.180484) (xy 299.887863 -306.178503)
			(xy 299.839644 -306.168659) (xy 299.793628 -306.151207) (xy 299.751007 -306.1266) (xy 299.712886 -306.095475)
			(xy 299.680251 -306.058638) (xy 299.653948 -306.017042) (xy 299.634657 -305.971766) (xy 299.62288 -305.923982)
			(xy 299.61892 -305.874928) (xy 299.280072 -305.874928) (xy 299.279577 -305.899535) (xy 299.271682 -305.948112)
			(xy 299.256098 -305.994793) (xy 299.233227 -306.03837) (xy 299.203662 -306.077714) (xy 299.168169 -306.111806)
			(xy 299.127666 -306.139762) (xy 299.083204 -306.16086) (xy 299.035933 -306.174552) (xy 298.987078 -306.180484)
			(xy 298.937903 -306.178503) (xy 298.889684 -306.168659) (xy 298.843668 -306.151207) (xy 298.801047 -306.1266)
			(xy 298.762926 -306.095475) (xy 298.730291 -306.058638) (xy 298.703988 -306.017042) (xy 298.684697 -305.971766)
			(xy 298.67292 -305.923982) (xy 298.66896 -305.874928) (xy 298.330112 -305.874928) (xy 298.329617 -305.899535)
			(xy 298.321722 -305.948112) (xy 298.306138 -305.994793) (xy 298.283267 -306.03837) (xy 298.253702 -306.077714)
			(xy 298.218209 -306.111806) (xy 298.177706 -306.139762) (xy 298.133244 -306.16086) (xy 298.085973 -306.174552)
			(xy 298.037118 -306.180484) (xy 297.987943 -306.178503) (xy 297.939724 -306.168659) (xy 297.893708 -306.151207)
			(xy 297.851087 -306.1266) (xy 297.812966 -306.095475) (xy 297.780331 -306.058638) (xy 297.754028 -306.017042)
			(xy 297.734737 -305.971766) (xy 297.72296 -305.923982) (xy 297.719 -305.874928) (xy 297.380152 -305.874928)
			(xy 297.379657 -305.899535) (xy 297.371762 -305.948112) (xy 297.356178 -305.994793) (xy 297.333307 -306.03837)
			(xy 297.303742 -306.077714) (xy 297.268249 -306.111806) (xy 297.227746 -306.139762) (xy 297.183284 -306.16086)
			(xy 297.136013 -306.174552) (xy 297.087158 -306.180484) (xy 297.037983 -306.178503) (xy 296.989764 -306.168659)
			(xy 296.943748 -306.151207) (xy 296.901127 -306.1266) (xy 296.863006 -306.095475) (xy 296.830371 -306.058638)
			(xy 296.804068 -306.017042) (xy 296.784777 -305.971766) (xy 296.773 -305.923982) (xy 296.76904 -305.874928)
			(xy 296.430192 -305.874928) (xy 296.429697 -305.899535) (xy 296.421802 -305.948112) (xy 296.406218 -305.994793)
			(xy 296.383347 -306.03837) (xy 296.353782 -306.077714) (xy 296.318289 -306.111806) (xy 296.277786 -306.139762)
			(xy 296.233324 -306.16086) (xy 296.186053 -306.174552) (xy 296.137198 -306.180484) (xy 296.088023 -306.178503)
			(xy 296.039804 -306.168659) (xy 295.993788 -306.151207) (xy 295.951167 -306.1266) (xy 295.913046 -306.095475)
			(xy 295.880411 -306.058638) (xy 295.854108 -306.017042) (xy 295.834817 -305.971766) (xy 295.82304 -305.923982)
			(xy 295.81908 -305.874928) (xy 295.480232 -305.874928) (xy 295.479737 -305.899535) (xy 295.471842 -305.948112)
			(xy 295.456258 -305.994793) (xy 295.433387 -306.03837) (xy 295.403822 -306.077714) (xy 295.368329 -306.111806)
			(xy 295.327826 -306.139762) (xy 295.283364 -306.16086) (xy 295.236093 -306.174552) (xy 295.187238 -306.180484)
			(xy 295.138063 -306.178503) (xy 295.089844 -306.168659) (xy 295.043828 -306.151207) (xy 295.001207 -306.1266)
			(xy 294.963086 -306.095475) (xy 294.930451 -306.058638) (xy 294.904148 -306.017042) (xy 294.884857 -305.971766)
			(xy 294.87308 -305.923982) (xy 294.86912 -305.874928) (xy 294.530018 -305.874928) (xy 294.529523 -305.899535)
			(xy 294.521628 -305.948112) (xy 294.506044 -305.994793) (xy 294.483173 -306.03837) (xy 294.453608 -306.077714)
			(xy 294.418115 -306.111806) (xy 294.377612 -306.139762) (xy 294.33315 -306.16086) (xy 294.285879 -306.174552)
			(xy 294.237024 -306.180484) (xy 294.187849 -306.178503) (xy 294.13963 -306.168659) (xy 294.093614 -306.151207)
			(xy 294.050993 -306.1266) (xy 294.012872 -306.095475) (xy 293.980237 -306.058638) (xy 293.953934 -306.017042)
			(xy 293.934643 -305.971766) (xy 293.922866 -305.923982) (xy 293.918906 -305.874928) (xy 293.580058 -305.874928)
			(xy 293.579563 -305.899535) (xy 293.571668 -305.948112) (xy 293.556084 -305.994793) (xy 293.533213 -306.03837)
			(xy 293.503648 -306.077714) (xy 293.468155 -306.111806) (xy 293.427652 -306.139762) (xy 293.38319 -306.16086)
			(xy 293.335919 -306.174552) (xy 293.287064 -306.180484) (xy 293.237889 -306.178503) (xy 293.18967 -306.168659)
			(xy 293.143654 -306.151207) (xy 293.101033 -306.1266) (xy 293.062912 -306.095475) (xy 293.030277 -306.058638)
			(xy 293.003974 -306.017042) (xy 292.984683 -305.971766) (xy 292.972906 -305.923982) (xy 292.968946 -305.874928)
			(xy 292.630098 -305.874928) (xy 292.629603 -305.899535) (xy 292.621708 -305.948112) (xy 292.606124 -305.994793)
			(xy 292.583253 -306.03837) (xy 292.553688 -306.077714) (xy 292.518195 -306.111806) (xy 292.477692 -306.139762)
			(xy 292.43323 -306.16086) (xy 292.385959 -306.174552) (xy 292.337104 -306.180484) (xy 292.287929 -306.178503)
			(xy 292.23971 -306.168659) (xy 292.193694 -306.151207) (xy 292.151073 -306.1266) (xy 292.112952 -306.095475)
			(xy 292.080317 -306.058638) (xy 292.054014 -306.017042) (xy 292.034723 -305.971766) (xy 292.022946 -305.923982)
			(xy 292.018986 -305.874928) (xy 290.730178 -305.874928) (xy 290.729683 -305.899535) (xy 290.721788 -305.948112)
			(xy 290.706204 -305.994793) (xy 290.683333 -306.03837) (xy 290.653768 -306.077714) (xy 290.618275 -306.111806)
			(xy 290.577772 -306.139762) (xy 290.53331 -306.16086) (xy 290.486039 -306.174552) (xy 290.437184 -306.180484)
			(xy 290.388009 -306.178503) (xy 290.33979 -306.168659) (xy 290.293774 -306.151207) (xy 290.251153 -306.1266)
			(xy 290.213032 -306.095475) (xy 290.180397 -306.058638) (xy 290.154094 -306.017042) (xy 290.134803 -305.971766)
			(xy 290.123026 -305.923982) (xy 290.119066 -305.874928) (xy 289.780218 -305.874928) (xy 289.779723 -305.899535)
			(xy 289.771828 -305.948112) (xy 289.756244 -305.994793) (xy 289.733373 -306.03837) (xy 289.703808 -306.077714)
			(xy 289.668315 -306.111806) (xy 289.627812 -306.139762) (xy 289.58335 -306.16086) (xy 289.536079 -306.174552)
			(xy 289.487224 -306.180484) (xy 289.438049 -306.178503) (xy 289.38983 -306.168659) (xy 289.343814 -306.151207)
			(xy 289.301193 -306.1266) (xy 289.263072 -306.095475) (xy 289.230437 -306.058638) (xy 289.204134 -306.017042)
			(xy 289.184843 -305.971766) (xy 289.173066 -305.923982) (xy 289.169106 -305.874928) (xy 288.830004 -305.874928)
			(xy 288.829509 -305.899535) (xy 288.821614 -305.948112) (xy 288.80603 -305.994793) (xy 288.783159 -306.03837)
			(xy 288.753594 -306.077714) (xy 288.718101 -306.111806) (xy 288.677598 -306.139762) (xy 288.633136 -306.16086)
			(xy 288.585865 -306.174552) (xy 288.53701 -306.180484) (xy 288.487835 -306.178503) (xy 288.439616 -306.168659)
			(xy 288.3936 -306.151207) (xy 288.350979 -306.1266) (xy 288.312858 -306.095475) (xy 288.280223 -306.058638)
			(xy 288.25392 -306.017042) (xy 288.234629 -305.971766) (xy 288.222852 -305.923982) (xy 288.218892 -305.874928)
			(xy 287.880044 -305.874928) (xy 287.879549 -305.899535) (xy 287.871654 -305.948112) (xy 287.85607 -305.994793)
			(xy 287.833199 -306.03837) (xy 287.803634 -306.077714) (xy 287.768141 -306.111806) (xy 287.727638 -306.139762)
			(xy 287.683176 -306.16086) (xy 287.635905 -306.174552) (xy 287.58705 -306.180484) (xy 287.537875 -306.178503)
			(xy 287.489656 -306.168659) (xy 287.44364 -306.151207) (xy 287.401019 -306.1266) (xy 287.362898 -306.095475)
			(xy 287.330263 -306.058638) (xy 287.30396 -306.017042) (xy 287.284669 -305.971766) (xy 287.272892 -305.923982)
			(xy 287.268932 -305.874928) (xy 286.930084 -305.874928) (xy 286.929589 -305.899535) (xy 286.921694 -305.948112)
			(xy 286.90611 -305.994793) (xy 286.883239 -306.03837) (xy 286.853674 -306.077714) (xy 286.818181 -306.111806)
			(xy 286.777678 -306.139762) (xy 286.733216 -306.16086) (xy 286.685945 -306.174552) (xy 286.63709 -306.180484)
			(xy 286.587915 -306.178503) (xy 286.539696 -306.168659) (xy 286.49368 -306.151207) (xy 286.451059 -306.1266)
			(xy 286.412938 -306.095475) (xy 286.380303 -306.058638) (xy 286.354 -306.017042) (xy 286.334709 -305.971766)
			(xy 286.322932 -305.923982) (xy 286.318972 -305.874928) (xy 285.980124 -305.874928) (xy 285.979629 -305.899535)
			(xy 285.971734 -305.948112) (xy 285.95615 -305.994793) (xy 285.933279 -306.03837) (xy 285.903714 -306.077714)
			(xy 285.868221 -306.111806) (xy 285.827718 -306.139762) (xy 285.783256 -306.16086) (xy 285.735985 -306.174552)
			(xy 285.68713 -306.180484) (xy 285.637955 -306.178503) (xy 285.589736 -306.168659) (xy 285.54372 -306.151207)
			(xy 285.501099 -306.1266) (xy 285.462978 -306.095475) (xy 285.430343 -306.058638) (xy 285.40404 -306.017042)
			(xy 285.384749 -305.971766) (xy 285.372972 -305.923982) (xy 285.369012 -305.874928) (xy 285.030164 -305.874928)
			(xy 285.029669 -305.899535) (xy 285.021774 -305.948112) (xy 285.00619 -305.994793) (xy 284.983319 -306.03837)
			(xy 284.953754 -306.077714) (xy 284.918261 -306.111806) (xy 284.877758 -306.139762) (xy 284.833296 -306.16086)
			(xy 284.786025 -306.174552) (xy 284.73717 -306.180484) (xy 284.687995 -306.178503) (xy 284.639776 -306.168659)
			(xy 284.59376 -306.151207) (xy 284.551139 -306.1266) (xy 284.513018 -306.095475) (xy 284.480383 -306.058638)
			(xy 284.45408 -306.017042) (xy 284.434789 -305.971766) (xy 284.423012 -305.923982) (xy 284.419052 -305.874928)
			(xy 284.080204 -305.874928) (xy 284.079709 -305.899535) (xy 284.071814 -305.948112) (xy 284.05623 -305.994793)
			(xy 284.033359 -306.03837) (xy 284.003794 -306.077714) (xy 283.968301 -306.111806) (xy 283.927798 -306.139762)
			(xy 283.883336 -306.16086) (xy 283.836065 -306.174552) (xy 283.78721 -306.180484) (xy 283.738035 -306.178503)
			(xy 283.689816 -306.168659) (xy 283.6438 -306.151207) (xy 283.601179 -306.1266) (xy 283.563058 -306.095475)
			(xy 283.530423 -306.058638) (xy 283.50412 -306.017042) (xy 283.484829 -305.971766) (xy 283.473052 -305.923982)
			(xy 283.469092 -305.874928) (xy 283.130244 -305.874928) (xy 283.129749 -305.899535) (xy 283.121854 -305.948112)
			(xy 283.10627 -305.994793) (xy 283.083399 -306.03837) (xy 283.053834 -306.077714) (xy 283.018341 -306.111806)
			(xy 282.977838 -306.139762) (xy 282.933376 -306.16086) (xy 282.886105 -306.174552) (xy 282.83725 -306.180484)
			(xy 282.788075 -306.178503) (xy 282.739856 -306.168659) (xy 282.69384 -306.151207) (xy 282.651219 -306.1266)
			(xy 282.613098 -306.095475) (xy 282.580463 -306.058638) (xy 282.55416 -306.017042) (xy 282.534869 -305.971766)
			(xy 282.523092 -305.923982) (xy 282.519132 -305.874928) (xy 282.219146 -305.874928) (xy 282.219146 -306.349908)
			(xy 305.793914 -306.349908) (xy 305.797874 -306.300854) (xy 305.809651 -306.25307) (xy 305.828942 -306.207794)
			(xy 305.855245 -306.166198) (xy 305.88788 -306.129361) (xy 305.926001 -306.098236) (xy 305.968622 -306.073629)
			(xy 306.014638 -306.056177) (xy 306.062857 -306.046333) (xy 306.112032 -306.044352) (xy 306.160887 -306.050284)
			(xy 306.208158 -306.063976) (xy 306.25262 -306.085074) (xy 306.293123 -306.11303) (xy 306.328616 -306.147122)
			(xy 306.358181 -306.186466) (xy 306.381052 -306.230043) (xy 306.396636 -306.276724) (xy 306.404531 -306.325301)
			(xy 306.405026 -306.349908) (xy 306.744128 -306.349908) (xy 306.748088 -306.300854) (xy 306.759865 -306.25307)
			(xy 306.779156 -306.207794) (xy 306.805459 -306.166198) (xy 306.838094 -306.129361) (xy 306.876215 -306.098236)
			(xy 306.918836 -306.073629) (xy 306.964852 -306.056177) (xy 307.013071 -306.046333) (xy 307.062246 -306.044352)
			(xy 307.111101 -306.050284) (xy 307.158372 -306.063976) (xy 307.202834 -306.085074) (xy 307.243337 -306.11303)
			(xy 307.27883 -306.147122) (xy 307.308395 -306.186466) (xy 307.331266 -306.230043) (xy 307.34685 -306.276724)
			(xy 307.354745 -306.325301) (xy 307.35524 -306.349908) (xy 307.694088 -306.349908) (xy 307.698048 -306.300854)
			(xy 307.709825 -306.25307) (xy 307.729116 -306.207794) (xy 307.755419 -306.166198) (xy 307.788054 -306.129361)
			(xy 307.826175 -306.098236) (xy 307.868796 -306.073629) (xy 307.914812 -306.056177) (xy 307.963031 -306.046333)
			(xy 308.012206 -306.044352) (xy 308.061061 -306.050284) (xy 308.108332 -306.063976) (xy 308.152794 -306.085074)
			(xy 308.193297 -306.11303) (xy 308.22879 -306.147122) (xy 308.258355 -306.186466) (xy 308.281226 -306.230043)
			(xy 308.29681 -306.276724) (xy 308.304705 -306.325301) (xy 308.3052 -306.349908) (xy 308.644048 -306.349908)
			(xy 308.648008 -306.300854) (xy 308.659785 -306.25307) (xy 308.679076 -306.207794) (xy 308.705379 -306.166198)
			(xy 308.738014 -306.129361) (xy 308.776135 -306.098236) (xy 308.818756 -306.073629) (xy 308.864772 -306.056177)
			(xy 308.912991 -306.046333) (xy 308.962166 -306.044352) (xy 309.011021 -306.050284) (xy 309.058292 -306.063976)
			(xy 309.102754 -306.085074) (xy 309.143257 -306.11303) (xy 309.17875 -306.147122) (xy 309.208315 -306.186466)
			(xy 309.231186 -306.230043) (xy 309.24677 -306.276724) (xy 309.254665 -306.325301) (xy 309.25516 -306.349908)
			(xy 309.594008 -306.349908) (xy 309.597968 -306.300854) (xy 309.609745 -306.25307) (xy 309.629036 -306.207794)
			(xy 309.655339 -306.166198) (xy 309.687974 -306.129361) (xy 309.726095 -306.098236) (xy 309.768716 -306.073629)
			(xy 309.814732 -306.056177) (xy 309.862951 -306.046333) (xy 309.912126 -306.044352) (xy 309.960981 -306.050284)
			(xy 310.008252 -306.063976) (xy 310.052714 -306.085074) (xy 310.093217 -306.11303) (xy 310.12871 -306.147122)
			(xy 310.158275 -306.186466) (xy 310.181146 -306.230043) (xy 310.19673 -306.276724) (xy 310.204625 -306.325301)
			(xy 310.20512 -306.349908) (xy 310.543968 -306.349908) (xy 310.547928 -306.300854) (xy 310.559705 -306.25307)
			(xy 310.578996 -306.207794) (xy 310.605299 -306.166198) (xy 310.637934 -306.129361) (xy 310.676055 -306.098236)
			(xy 310.718676 -306.073629) (xy 310.764692 -306.056177) (xy 310.812911 -306.046333) (xy 310.862086 -306.044352)
			(xy 310.910941 -306.050284) (xy 310.958212 -306.063976) (xy 311.002674 -306.085074) (xy 311.043177 -306.11303)
			(xy 311.07867 -306.147122) (xy 311.108235 -306.186466) (xy 311.131106 -306.230043) (xy 311.14669 -306.276724)
			(xy 311.154585 -306.325301) (xy 311.15508 -306.349908) (xy 311.493928 -306.349908) (xy 311.497888 -306.300854)
			(xy 311.509665 -306.25307) (xy 311.528956 -306.207794) (xy 311.555259 -306.166198) (xy 311.587894 -306.129361)
			(xy 311.626015 -306.098236) (xy 311.668636 -306.073629) (xy 311.714652 -306.056177) (xy 311.762871 -306.046333)
			(xy 311.812046 -306.044352) (xy 311.860901 -306.050284) (xy 311.908172 -306.063976) (xy 311.952634 -306.085074)
			(xy 311.993137 -306.11303) (xy 312.02863 -306.147122) (xy 312.058195 -306.186466) (xy 312.081066 -306.230043)
			(xy 312.09665 -306.276724) (xy 312.104545 -306.325301) (xy 312.10504 -306.349908) (xy 312.443888 -306.349908)
			(xy 312.447848 -306.300854) (xy 312.459625 -306.25307) (xy 312.478916 -306.207794) (xy 312.505219 -306.166198)
			(xy 312.537854 -306.129361) (xy 312.575975 -306.098236) (xy 312.618596 -306.073629) (xy 312.664612 -306.056177)
			(xy 312.712831 -306.046333) (xy 312.762006 -306.044352) (xy 312.810861 -306.050284) (xy 312.858132 -306.063976)
			(xy 312.902594 -306.085074) (xy 312.943097 -306.11303) (xy 312.97859 -306.147122) (xy 313.008155 -306.186466)
			(xy 313.031026 -306.230043) (xy 313.04661 -306.276724) (xy 313.054505 -306.325301) (xy 313.055 -306.349908)
			(xy 313.394102 -306.349908) (xy 313.398062 -306.300854) (xy 313.409839 -306.25307) (xy 313.42913 -306.207794)
			(xy 313.455433 -306.166198) (xy 313.488068 -306.129361) (xy 313.526189 -306.098236) (xy 313.56881 -306.073629)
			(xy 313.614826 -306.056177) (xy 313.663045 -306.046333) (xy 313.71222 -306.044352) (xy 313.761075 -306.050284)
			(xy 313.808346 -306.063976) (xy 313.852808 -306.085074) (xy 313.893311 -306.11303) (xy 313.928804 -306.147122)
			(xy 313.958369 -306.186466) (xy 313.98124 -306.230043) (xy 313.996824 -306.276724) (xy 314.004719 -306.325301)
			(xy 314.005214 -306.349908) (xy 314.344062 -306.349908) (xy 314.348022 -306.300854) (xy 314.359799 -306.25307)
			(xy 314.37909 -306.207794) (xy 314.405393 -306.166198) (xy 314.438028 -306.129361) (xy 314.476149 -306.098236)
			(xy 314.51877 -306.073629) (xy 314.564786 -306.056177) (xy 314.613005 -306.046333) (xy 314.66218 -306.044352)
			(xy 314.711035 -306.050284) (xy 314.758306 -306.063976) (xy 314.802768 -306.085074) (xy 314.843271 -306.11303)
			(xy 314.878764 -306.147122) (xy 314.908329 -306.186466) (xy 314.9312 -306.230043) (xy 314.946784 -306.276724)
			(xy 314.954679 -306.325301) (xy 314.955174 -306.349908) (xy 315.294276 -306.349908) (xy 315.298236 -306.300854)
			(xy 315.310013 -306.25307) (xy 315.329304 -306.207794) (xy 315.355607 -306.166198) (xy 315.388242 -306.129361)
			(xy 315.426363 -306.098236) (xy 315.468984 -306.073629) (xy 315.515 -306.056177) (xy 315.563219 -306.046333)
			(xy 315.612394 -306.044352) (xy 315.661249 -306.050284) (xy 315.70852 -306.063976) (xy 315.752982 -306.085074)
			(xy 315.793485 -306.11303) (xy 315.828978 -306.147122) (xy 315.858543 -306.186466) (xy 315.881414 -306.230043)
			(xy 315.896998 -306.276724) (xy 315.904893 -306.325301) (xy 315.905388 -306.349908) (xy 315.904893 -306.374515)
			(xy 315.896998 -306.423092) (xy 315.881414 -306.469773) (xy 315.858543 -306.51335) (xy 315.828978 -306.552694)
			(xy 315.793485 -306.586786) (xy 315.752982 -306.614742) (xy 315.70852 -306.63584) (xy 315.661249 -306.649532)
			(xy 315.612394 -306.655464) (xy 315.563219 -306.653483) (xy 315.515 -306.643639) (xy 315.468984 -306.626187)
			(xy 315.426363 -306.60158) (xy 315.388242 -306.570455) (xy 315.355607 -306.533618) (xy 315.329304 -306.492022)
			(xy 315.310013 -306.446746) (xy 315.298236 -306.398962) (xy 315.294276 -306.349908) (xy 314.955174 -306.349908)
			(xy 314.954679 -306.374515) (xy 314.946784 -306.423092) (xy 314.9312 -306.469773) (xy 314.908329 -306.51335)
			(xy 314.878764 -306.552694) (xy 314.843271 -306.586786) (xy 314.802768 -306.614742) (xy 314.758306 -306.63584)
			(xy 314.711035 -306.649532) (xy 314.66218 -306.655464) (xy 314.613005 -306.653483) (xy 314.564786 -306.643639)
			(xy 314.51877 -306.626187) (xy 314.476149 -306.60158) (xy 314.438028 -306.570455) (xy 314.405393 -306.533618)
			(xy 314.37909 -306.492022) (xy 314.359799 -306.446746) (xy 314.348022 -306.398962) (xy 314.344062 -306.349908)
			(xy 314.005214 -306.349908) (xy 314.004719 -306.374515) (xy 313.996824 -306.423092) (xy 313.98124 -306.469773)
			(xy 313.958369 -306.51335) (xy 313.928804 -306.552694) (xy 313.893311 -306.586786) (xy 313.852808 -306.614742)
			(xy 313.808346 -306.63584) (xy 313.761075 -306.649532) (xy 313.71222 -306.655464) (xy 313.663045 -306.653483)
			(xy 313.614826 -306.643639) (xy 313.56881 -306.626187) (xy 313.526189 -306.60158) (xy 313.488068 -306.570455)
			(xy 313.455433 -306.533618) (xy 313.42913 -306.492022) (xy 313.409839 -306.446746) (xy 313.398062 -306.398962)
			(xy 313.394102 -306.349908) (xy 313.055 -306.349908) (xy 313.054505 -306.374515) (xy 313.04661 -306.423092)
			(xy 313.031026 -306.469773) (xy 313.008155 -306.51335) (xy 312.97859 -306.552694) (xy 312.943097 -306.586786)
			(xy 312.902594 -306.614742) (xy 312.858132 -306.63584) (xy 312.810861 -306.649532) (xy 312.762006 -306.655464)
			(xy 312.712831 -306.653483) (xy 312.664612 -306.643639) (xy 312.618596 -306.626187) (xy 312.575975 -306.60158)
			(xy 312.537854 -306.570455) (xy 312.505219 -306.533618) (xy 312.478916 -306.492022) (xy 312.459625 -306.446746)
			(xy 312.447848 -306.398962) (xy 312.443888 -306.349908) (xy 312.10504 -306.349908) (xy 312.104545 -306.374515)
			(xy 312.09665 -306.423092) (xy 312.081066 -306.469773) (xy 312.058195 -306.51335) (xy 312.02863 -306.552694)
			(xy 311.993137 -306.586786) (xy 311.952634 -306.614742) (xy 311.908172 -306.63584) (xy 311.860901 -306.649532)
			(xy 311.812046 -306.655464) (xy 311.762871 -306.653483) (xy 311.714652 -306.643639) (xy 311.668636 -306.626187)
			(xy 311.626015 -306.60158) (xy 311.587894 -306.570455) (xy 311.555259 -306.533618) (xy 311.528956 -306.492022)
			(xy 311.509665 -306.446746) (xy 311.497888 -306.398962) (xy 311.493928 -306.349908) (xy 311.15508 -306.349908)
			(xy 311.154585 -306.374515) (xy 311.14669 -306.423092) (xy 311.131106 -306.469773) (xy 311.108235 -306.51335)
			(xy 311.07867 -306.552694) (xy 311.043177 -306.586786) (xy 311.002674 -306.614742) (xy 310.958212 -306.63584)
			(xy 310.910941 -306.649532) (xy 310.862086 -306.655464) (xy 310.812911 -306.653483) (xy 310.764692 -306.643639)
			(xy 310.718676 -306.626187) (xy 310.676055 -306.60158) (xy 310.637934 -306.570455) (xy 310.605299 -306.533618)
			(xy 310.578996 -306.492022) (xy 310.559705 -306.446746) (xy 310.547928 -306.398962) (xy 310.543968 -306.349908)
			(xy 310.20512 -306.349908) (xy 310.204625 -306.374515) (xy 310.19673 -306.423092) (xy 310.181146 -306.469773)
			(xy 310.158275 -306.51335) (xy 310.12871 -306.552694) (xy 310.093217 -306.586786) (xy 310.052714 -306.614742)
			(xy 310.008252 -306.63584) (xy 309.960981 -306.649532) (xy 309.912126 -306.655464) (xy 309.862951 -306.653483)
			(xy 309.814732 -306.643639) (xy 309.768716 -306.626187) (xy 309.726095 -306.60158) (xy 309.687974 -306.570455)
			(xy 309.655339 -306.533618) (xy 309.629036 -306.492022) (xy 309.609745 -306.446746) (xy 309.597968 -306.398962)
			(xy 309.594008 -306.349908) (xy 309.25516 -306.349908) (xy 309.254665 -306.374515) (xy 309.24677 -306.423092)
			(xy 309.231186 -306.469773) (xy 309.208315 -306.51335) (xy 309.17875 -306.552694) (xy 309.143257 -306.586786)
			(xy 309.102754 -306.614742) (xy 309.058292 -306.63584) (xy 309.011021 -306.649532) (xy 308.962166 -306.655464)
			(xy 308.912991 -306.653483) (xy 308.864772 -306.643639) (xy 308.818756 -306.626187) (xy 308.776135 -306.60158)
			(xy 308.738014 -306.570455) (xy 308.705379 -306.533618) (xy 308.679076 -306.492022) (xy 308.659785 -306.446746)
			(xy 308.648008 -306.398962) (xy 308.644048 -306.349908) (xy 308.3052 -306.349908) (xy 308.304705 -306.374515)
			(xy 308.29681 -306.423092) (xy 308.281226 -306.469773) (xy 308.258355 -306.51335) (xy 308.22879 -306.552694)
			(xy 308.193297 -306.586786) (xy 308.152794 -306.614742) (xy 308.108332 -306.63584) (xy 308.061061 -306.649532)
			(xy 308.012206 -306.655464) (xy 307.963031 -306.653483) (xy 307.914812 -306.643639) (xy 307.868796 -306.626187)
			(xy 307.826175 -306.60158) (xy 307.788054 -306.570455) (xy 307.755419 -306.533618) (xy 307.729116 -306.492022)
			(xy 307.709825 -306.446746) (xy 307.698048 -306.398962) (xy 307.694088 -306.349908) (xy 307.35524 -306.349908)
			(xy 307.354745 -306.374515) (xy 307.34685 -306.423092) (xy 307.331266 -306.469773) (xy 307.308395 -306.51335)
			(xy 307.27883 -306.552694) (xy 307.243337 -306.586786) (xy 307.202834 -306.614742) (xy 307.158372 -306.63584)
			(xy 307.111101 -306.649532) (xy 307.062246 -306.655464) (xy 307.013071 -306.653483) (xy 306.964852 -306.643639)
			(xy 306.918836 -306.626187) (xy 306.876215 -306.60158) (xy 306.838094 -306.570455) (xy 306.805459 -306.533618)
			(xy 306.779156 -306.492022) (xy 306.759865 -306.446746) (xy 306.748088 -306.398962) (xy 306.744128 -306.349908)
			(xy 306.405026 -306.349908) (xy 306.404531 -306.374515) (xy 306.396636 -306.423092) (xy 306.381052 -306.469773)
			(xy 306.358181 -306.51335) (xy 306.328616 -306.552694) (xy 306.293123 -306.586786) (xy 306.25262 -306.614742)
			(xy 306.208158 -306.63584) (xy 306.160887 -306.649532) (xy 306.112032 -306.655464) (xy 306.062857 -306.653483)
			(xy 306.014638 -306.643639) (xy 305.968622 -306.626187) (xy 305.926001 -306.60158) (xy 305.88788 -306.570455)
			(xy 305.855245 -306.533618) (xy 305.828942 -306.492022) (xy 305.809651 -306.446746) (xy 305.797874 -306.398962)
			(xy 305.793914 -306.349908) (xy 282.219146 -306.349908) (xy 282.219146 -306.824888) (xy 282.519132 -306.824888)
			(xy 282.523092 -306.775834) (xy 282.534869 -306.72805) (xy 282.55416 -306.682774) (xy 282.580463 -306.641178)
			(xy 282.613098 -306.604341) (xy 282.651219 -306.573216) (xy 282.69384 -306.548609) (xy 282.739856 -306.531157)
			(xy 282.788075 -306.521313) (xy 282.83725 -306.519332) (xy 282.886105 -306.525264) (xy 282.933376 -306.538956)
			(xy 282.977838 -306.560054) (xy 283.018341 -306.58801) (xy 283.053834 -306.622102) (xy 283.083399 -306.661446)
			(xy 283.10627 -306.705023) (xy 283.121854 -306.751704) (xy 283.129749 -306.800281) (xy 283.130244 -306.824888)
			(xy 283.469092 -306.824888) (xy 283.473052 -306.775834) (xy 283.484829 -306.72805) (xy 283.50412 -306.682774)
			(xy 283.530423 -306.641178) (xy 283.563058 -306.604341) (xy 283.601179 -306.573216) (xy 283.6438 -306.548609)
			(xy 283.689816 -306.531157) (xy 283.738035 -306.521313) (xy 283.78721 -306.519332) (xy 283.836065 -306.525264)
			(xy 283.883336 -306.538956) (xy 283.927798 -306.560054) (xy 283.968301 -306.58801) (xy 284.003794 -306.622102)
			(xy 284.033359 -306.661446) (xy 284.05623 -306.705023) (xy 284.071814 -306.751704) (xy 284.079709 -306.800281)
			(xy 284.080204 -306.824888) (xy 284.419052 -306.824888) (xy 284.423012 -306.775834) (xy 284.434789 -306.72805)
			(xy 284.45408 -306.682774) (xy 284.480383 -306.641178) (xy 284.513018 -306.604341) (xy 284.551139 -306.573216)
			(xy 284.59376 -306.548609) (xy 284.639776 -306.531157) (xy 284.687995 -306.521313) (xy 284.73717 -306.519332)
			(xy 284.786025 -306.525264) (xy 284.833296 -306.538956) (xy 284.877758 -306.560054) (xy 284.918261 -306.58801)
			(xy 284.953754 -306.622102) (xy 284.983319 -306.661446) (xy 285.00619 -306.705023) (xy 285.021774 -306.751704)
			(xy 285.029669 -306.800281) (xy 285.030164 -306.824888) (xy 285.369012 -306.824888) (xy 285.372972 -306.775834)
			(xy 285.384749 -306.72805) (xy 285.40404 -306.682774) (xy 285.430343 -306.641178) (xy 285.462978 -306.604341)
			(xy 285.501099 -306.573216) (xy 285.54372 -306.548609) (xy 285.589736 -306.531157) (xy 285.637955 -306.521313)
			(xy 285.68713 -306.519332) (xy 285.735985 -306.525264) (xy 285.783256 -306.538956) (xy 285.827718 -306.560054)
			(xy 285.868221 -306.58801) (xy 285.903714 -306.622102) (xy 285.933279 -306.661446) (xy 285.95615 -306.705023)
			(xy 285.971734 -306.751704) (xy 285.979629 -306.800281) (xy 285.980124 -306.824888) (xy 286.318972 -306.824888)
			(xy 286.322932 -306.775834) (xy 286.334709 -306.72805) (xy 286.354 -306.682774) (xy 286.380303 -306.641178)
			(xy 286.412938 -306.604341) (xy 286.451059 -306.573216) (xy 286.49368 -306.548609) (xy 286.539696 -306.531157)
			(xy 286.587915 -306.521313) (xy 286.63709 -306.519332) (xy 286.685945 -306.525264) (xy 286.733216 -306.538956)
			(xy 286.777678 -306.560054) (xy 286.818181 -306.58801) (xy 286.853674 -306.622102) (xy 286.883239 -306.661446)
			(xy 286.90611 -306.705023) (xy 286.921694 -306.751704) (xy 286.929589 -306.800281) (xy 286.930084 -306.824888)
			(xy 287.268932 -306.824888) (xy 287.272892 -306.775834) (xy 287.284669 -306.72805) (xy 287.30396 -306.682774)
			(xy 287.330263 -306.641178) (xy 287.362898 -306.604341) (xy 287.401019 -306.573216) (xy 287.44364 -306.548609)
			(xy 287.489656 -306.531157) (xy 287.537875 -306.521313) (xy 287.58705 -306.519332) (xy 287.635905 -306.525264)
			(xy 287.683176 -306.538956) (xy 287.727638 -306.560054) (xy 287.768141 -306.58801) (xy 287.803634 -306.622102)
			(xy 287.833199 -306.661446) (xy 287.85607 -306.705023) (xy 287.871654 -306.751704) (xy 287.879549 -306.800281)
			(xy 287.880044 -306.824888) (xy 288.218892 -306.824888) (xy 288.222852 -306.775834) (xy 288.234629 -306.72805)
			(xy 288.25392 -306.682774) (xy 288.280223 -306.641178) (xy 288.312858 -306.604341) (xy 288.350979 -306.573216)
			(xy 288.3936 -306.548609) (xy 288.439616 -306.531157) (xy 288.487835 -306.521313) (xy 288.53701 -306.519332)
			(xy 288.585865 -306.525264) (xy 288.633136 -306.538956) (xy 288.677598 -306.560054) (xy 288.718101 -306.58801)
			(xy 288.753594 -306.622102) (xy 288.783159 -306.661446) (xy 288.80603 -306.705023) (xy 288.821614 -306.751704)
			(xy 288.829509 -306.800281) (xy 288.830004 -306.824888) (xy 289.169106 -306.824888) (xy 289.173066 -306.775834)
			(xy 289.184843 -306.72805) (xy 289.204134 -306.682774) (xy 289.230437 -306.641178) (xy 289.263072 -306.604341)
			(xy 289.301193 -306.573216) (xy 289.343814 -306.548609) (xy 289.38983 -306.531157) (xy 289.438049 -306.521313)
			(xy 289.487224 -306.519332) (xy 289.536079 -306.525264) (xy 289.58335 -306.538956) (xy 289.627812 -306.560054)
			(xy 289.668315 -306.58801) (xy 289.703808 -306.622102) (xy 289.733373 -306.661446) (xy 289.756244 -306.705023)
			(xy 289.771828 -306.751704) (xy 289.779723 -306.800281) (xy 289.780218 -306.824888) (xy 290.119066 -306.824888)
			(xy 290.123026 -306.775834) (xy 290.134803 -306.72805) (xy 290.154094 -306.682774) (xy 290.180397 -306.641178)
			(xy 290.213032 -306.604341) (xy 290.251153 -306.573216) (xy 290.293774 -306.548609) (xy 290.33979 -306.531157)
			(xy 290.388009 -306.521313) (xy 290.437184 -306.519332) (xy 290.486039 -306.525264) (xy 290.53331 -306.538956)
			(xy 290.577772 -306.560054) (xy 290.618275 -306.58801) (xy 290.653768 -306.622102) (xy 290.683333 -306.661446)
			(xy 290.706204 -306.705023) (xy 290.721788 -306.751704) (xy 290.729683 -306.800281) (xy 290.730178 -306.824888)
			(xy 292.018986 -306.824888) (xy 292.022946 -306.775834) (xy 292.034723 -306.72805) (xy 292.054014 -306.682774)
			(xy 292.080317 -306.641178) (xy 292.112952 -306.604341) (xy 292.151073 -306.573216) (xy 292.193694 -306.548609)
			(xy 292.23971 -306.531157) (xy 292.287929 -306.521313) (xy 292.337104 -306.519332) (xy 292.385959 -306.525264)
			(xy 292.43323 -306.538956) (xy 292.477692 -306.560054) (xy 292.518195 -306.58801) (xy 292.553688 -306.622102)
			(xy 292.583253 -306.661446) (xy 292.606124 -306.705023) (xy 292.621708 -306.751704) (xy 292.629603 -306.800281)
			(xy 292.630098 -306.824888) (xy 292.968946 -306.824888) (xy 292.972906 -306.775834) (xy 292.984683 -306.72805)
			(xy 293.003974 -306.682774) (xy 293.030277 -306.641178) (xy 293.062912 -306.604341) (xy 293.101033 -306.573216)
			(xy 293.143654 -306.548609) (xy 293.18967 -306.531157) (xy 293.237889 -306.521313) (xy 293.287064 -306.519332)
			(xy 293.335919 -306.525264) (xy 293.38319 -306.538956) (xy 293.427652 -306.560054) (xy 293.468155 -306.58801)
			(xy 293.503648 -306.622102) (xy 293.533213 -306.661446) (xy 293.556084 -306.705023) (xy 293.571668 -306.751704)
			(xy 293.579563 -306.800281) (xy 293.580058 -306.824888) (xy 293.918906 -306.824888) (xy 293.922866 -306.775834)
			(xy 293.934643 -306.72805) (xy 293.953934 -306.682774) (xy 293.980237 -306.641178) (xy 294.012872 -306.604341)
			(xy 294.050993 -306.573216) (xy 294.093614 -306.548609) (xy 294.13963 -306.531157) (xy 294.187849 -306.521313)
			(xy 294.237024 -306.519332) (xy 294.285879 -306.525264) (xy 294.33315 -306.538956) (xy 294.377612 -306.560054)
			(xy 294.418115 -306.58801) (xy 294.453608 -306.622102) (xy 294.483173 -306.661446) (xy 294.506044 -306.705023)
			(xy 294.521628 -306.751704) (xy 294.529523 -306.800281) (xy 294.530018 -306.824888) (xy 294.86912 -306.824888)
			(xy 294.87308 -306.775834) (xy 294.884857 -306.72805) (xy 294.904148 -306.682774) (xy 294.930451 -306.641178)
			(xy 294.963086 -306.604341) (xy 295.001207 -306.573216) (xy 295.043828 -306.548609) (xy 295.089844 -306.531157)
			(xy 295.138063 -306.521313) (xy 295.187238 -306.519332) (xy 295.236093 -306.525264) (xy 295.283364 -306.538956)
			(xy 295.327826 -306.560054) (xy 295.368329 -306.58801) (xy 295.403822 -306.622102) (xy 295.433387 -306.661446)
			(xy 295.456258 -306.705023) (xy 295.471842 -306.751704) (xy 295.479737 -306.800281) (xy 295.480232 -306.824888)
			(xy 295.81908 -306.824888) (xy 295.82304 -306.775834) (xy 295.834817 -306.72805) (xy 295.854108 -306.682774)
			(xy 295.880411 -306.641178) (xy 295.913046 -306.604341) (xy 295.951167 -306.573216) (xy 295.993788 -306.548609)
			(xy 296.039804 -306.531157) (xy 296.088023 -306.521313) (xy 296.137198 -306.519332) (xy 296.186053 -306.525264)
			(xy 296.233324 -306.538956) (xy 296.277786 -306.560054) (xy 296.318289 -306.58801) (xy 296.353782 -306.622102)
			(xy 296.383347 -306.661446) (xy 296.406218 -306.705023) (xy 296.421802 -306.751704) (xy 296.429697 -306.800281)
			(xy 296.430192 -306.824888) (xy 296.76904 -306.824888) (xy 296.773 -306.775834) (xy 296.784777 -306.72805)
			(xy 296.804068 -306.682774) (xy 296.830371 -306.641178) (xy 296.863006 -306.604341) (xy 296.901127 -306.573216)
			(xy 296.943748 -306.548609) (xy 296.989764 -306.531157) (xy 297.037983 -306.521313) (xy 297.087158 -306.519332)
			(xy 297.136013 -306.525264) (xy 297.183284 -306.538956) (xy 297.227746 -306.560054) (xy 297.268249 -306.58801)
			(xy 297.303742 -306.622102) (xy 297.333307 -306.661446) (xy 297.356178 -306.705023) (xy 297.371762 -306.751704)
			(xy 297.379657 -306.800281) (xy 297.380152 -306.824888) (xy 297.719 -306.824888) (xy 297.72296 -306.775834)
			(xy 297.734737 -306.72805) (xy 297.754028 -306.682774) (xy 297.780331 -306.641178) (xy 297.812966 -306.604341)
			(xy 297.851087 -306.573216) (xy 297.893708 -306.548609) (xy 297.939724 -306.531157) (xy 297.987943 -306.521313)
			(xy 298.037118 -306.519332) (xy 298.085973 -306.525264) (xy 298.133244 -306.538956) (xy 298.177706 -306.560054)
			(xy 298.218209 -306.58801) (xy 298.253702 -306.622102) (xy 298.283267 -306.661446) (xy 298.306138 -306.705023)
			(xy 298.321722 -306.751704) (xy 298.329617 -306.800281) (xy 298.330112 -306.824888) (xy 298.66896 -306.824888)
			(xy 298.67292 -306.775834) (xy 298.684697 -306.72805) (xy 298.703988 -306.682774) (xy 298.730291 -306.641178)
			(xy 298.762926 -306.604341) (xy 298.801047 -306.573216) (xy 298.843668 -306.548609) (xy 298.889684 -306.531157)
			(xy 298.937903 -306.521313) (xy 298.987078 -306.519332) (xy 299.035933 -306.525264) (xy 299.083204 -306.538956)
			(xy 299.127666 -306.560054) (xy 299.168169 -306.58801) (xy 299.203662 -306.622102) (xy 299.233227 -306.661446)
			(xy 299.256098 -306.705023) (xy 299.271682 -306.751704) (xy 299.279577 -306.800281) (xy 299.280072 -306.824888)
			(xy 299.61892 -306.824888) (xy 299.62288 -306.775834) (xy 299.634657 -306.72805) (xy 299.653948 -306.682774)
			(xy 299.680251 -306.641178) (xy 299.712886 -306.604341) (xy 299.751007 -306.573216) (xy 299.793628 -306.548609)
			(xy 299.839644 -306.531157) (xy 299.887863 -306.521313) (xy 299.937038 -306.519332) (xy 299.985893 -306.525264)
			(xy 300.033164 -306.538956) (xy 300.077626 -306.560054) (xy 300.118129 -306.58801) (xy 300.153622 -306.622102)
			(xy 300.183187 -306.661446) (xy 300.206058 -306.705023) (xy 300.221642 -306.751704) (xy 300.229537 -306.800281)
			(xy 300.230032 -306.824888) (xy 300.56888 -306.824888) (xy 300.57284 -306.775834) (xy 300.584617 -306.72805)
			(xy 300.603908 -306.682774) (xy 300.630211 -306.641178) (xy 300.662846 -306.604341) (xy 300.700967 -306.573216)
			(xy 300.743588 -306.548609) (xy 300.789604 -306.531157) (xy 300.837823 -306.521313) (xy 300.886998 -306.519332)
			(xy 300.935853 -306.525264) (xy 300.983124 -306.538956) (xy 301.027586 -306.560054) (xy 301.068089 -306.58801)
			(xy 301.103582 -306.622102) (xy 301.133147 -306.661446) (xy 301.156018 -306.705023) (xy 301.171602 -306.751704)
			(xy 301.179497 -306.800281) (xy 301.179992 -306.824888) (xy 301.519094 -306.824888) (xy 301.523054 -306.775834)
			(xy 301.534831 -306.72805) (xy 301.554122 -306.682774) (xy 301.580425 -306.641178) (xy 301.61306 -306.604341)
			(xy 301.651181 -306.573216) (xy 301.693802 -306.548609) (xy 301.739818 -306.531157) (xy 301.788037 -306.521313)
			(xy 301.837212 -306.519332) (xy 301.886067 -306.525264) (xy 301.933338 -306.538956) (xy 301.9778 -306.560054)
			(xy 302.018303 -306.58801) (xy 302.053796 -306.622102) (xy 302.083361 -306.661446) (xy 302.106232 -306.705023)
			(xy 302.121816 -306.751704) (xy 302.129711 -306.800281) (xy 302.130206 -306.824888) (xy 302.469054 -306.824888)
			(xy 302.473014 -306.775834) (xy 302.484791 -306.72805) (xy 302.504082 -306.682774) (xy 302.530385 -306.641178)
			(xy 302.56302 -306.604341) (xy 302.601141 -306.573216) (xy 302.643762 -306.548609) (xy 302.689778 -306.531157)
			(xy 302.737997 -306.521313) (xy 302.787172 -306.519332) (xy 302.836027 -306.525264) (xy 302.883298 -306.538956)
			(xy 302.92776 -306.560054) (xy 302.968263 -306.58801) (xy 303.003756 -306.622102) (xy 303.033321 -306.661446)
			(xy 303.056192 -306.705023) (xy 303.071776 -306.751704) (xy 303.079671 -306.800281) (xy 303.080166 -306.824888)
			(xy 303.419014 -306.824888) (xy 303.422974 -306.775834) (xy 303.434751 -306.72805) (xy 303.454042 -306.682774)
			(xy 303.480345 -306.641178) (xy 303.51298 -306.604341) (xy 303.551101 -306.573216) (xy 303.593722 -306.548609)
			(xy 303.639738 -306.531157) (xy 303.687957 -306.521313) (xy 303.737132 -306.519332) (xy 303.785987 -306.525264)
			(xy 303.833258 -306.538956) (xy 303.87772 -306.560054) (xy 303.918223 -306.58801) (xy 303.953716 -306.622102)
			(xy 303.983281 -306.661446) (xy 304.006152 -306.705023) (xy 304.021736 -306.751704) (xy 304.029631 -306.800281)
			(xy 304.030126 -306.824888) (xy 304.368974 -306.824888) (xy 304.372934 -306.775834) (xy 304.384711 -306.72805)
			(xy 304.404002 -306.682774) (xy 304.430305 -306.641178) (xy 304.46294 -306.604341) (xy 304.501061 -306.573216)
			(xy 304.543682 -306.548609) (xy 304.589698 -306.531157) (xy 304.637917 -306.521313) (xy 304.687092 -306.519332)
			(xy 304.735947 -306.525264) (xy 304.783218 -306.538956) (xy 304.82768 -306.560054) (xy 304.868183 -306.58801)
			(xy 304.903676 -306.622102) (xy 304.933241 -306.661446) (xy 304.956112 -306.705023) (xy 304.971696 -306.751704)
			(xy 304.979591 -306.800281) (xy 304.980086 -306.824888) (xy 304.979591 -306.849495) (xy 304.971696 -306.898072)
			(xy 304.956112 -306.944753) (xy 304.933241 -306.98833) (xy 304.903676 -307.027674) (xy 304.868183 -307.061766)
			(xy 304.82768 -307.089722) (xy 304.783218 -307.11082) (xy 304.735947 -307.124512) (xy 304.687092 -307.130444)
			(xy 304.637917 -307.128463) (xy 304.589698 -307.118619) (xy 304.543682 -307.101167) (xy 304.501061 -307.07656)
			(xy 304.46294 -307.045435) (xy 304.430305 -307.008598) (xy 304.404002 -306.967002) (xy 304.384711 -306.921726)
			(xy 304.372934 -306.873942) (xy 304.368974 -306.824888) (xy 304.030126 -306.824888) (xy 304.029631 -306.849495)
			(xy 304.021736 -306.898072) (xy 304.006152 -306.944753) (xy 303.983281 -306.98833) (xy 303.953716 -307.027674)
			(xy 303.918223 -307.061766) (xy 303.87772 -307.089722) (xy 303.833258 -307.11082) (xy 303.785987 -307.124512)
			(xy 303.737132 -307.130444) (xy 303.687957 -307.128463) (xy 303.639738 -307.118619) (xy 303.593722 -307.101167)
			(xy 303.551101 -307.07656) (xy 303.51298 -307.045435) (xy 303.480345 -307.008598) (xy 303.454042 -306.967002)
			(xy 303.434751 -306.921726) (xy 303.422974 -306.873942) (xy 303.419014 -306.824888) (xy 303.080166 -306.824888)
			(xy 303.079671 -306.849495) (xy 303.071776 -306.898072) (xy 303.056192 -306.944753) (xy 303.033321 -306.98833)
			(xy 303.003756 -307.027674) (xy 302.968263 -307.061766) (xy 302.92776 -307.089722) (xy 302.883298 -307.11082)
			(xy 302.836027 -307.124512) (xy 302.787172 -307.130444) (xy 302.737997 -307.128463) (xy 302.689778 -307.118619)
			(xy 302.643762 -307.101167) (xy 302.601141 -307.07656) (xy 302.56302 -307.045435) (xy 302.530385 -307.008598)
			(xy 302.504082 -306.967002) (xy 302.484791 -306.921726) (xy 302.473014 -306.873942) (xy 302.469054 -306.824888)
			(xy 302.130206 -306.824888) (xy 302.129711 -306.849495) (xy 302.121816 -306.898072) (xy 302.106232 -306.944753)
			(xy 302.083361 -306.98833) (xy 302.053796 -307.027674) (xy 302.018303 -307.061766) (xy 301.9778 -307.089722)
			(xy 301.933338 -307.11082) (xy 301.886067 -307.124512) (xy 301.837212 -307.130444) (xy 301.788037 -307.128463)
			(xy 301.739818 -307.118619) (xy 301.693802 -307.101167) (xy 301.651181 -307.07656) (xy 301.61306 -307.045435)
			(xy 301.580425 -307.008598) (xy 301.554122 -306.967002) (xy 301.534831 -306.921726) (xy 301.523054 -306.873942)
			(xy 301.519094 -306.824888) (xy 301.179992 -306.824888) (xy 301.179497 -306.849495) (xy 301.171602 -306.898072)
			(xy 301.156018 -306.944753) (xy 301.133147 -306.98833) (xy 301.103582 -307.027674) (xy 301.068089 -307.061766)
			(xy 301.027586 -307.089722) (xy 300.983124 -307.11082) (xy 300.935853 -307.124512) (xy 300.886998 -307.130444)
			(xy 300.837823 -307.128463) (xy 300.789604 -307.118619) (xy 300.743588 -307.101167) (xy 300.700967 -307.07656)
			(xy 300.662846 -307.045435) (xy 300.630211 -307.008598) (xy 300.603908 -306.967002) (xy 300.584617 -306.921726)
			(xy 300.57284 -306.873942) (xy 300.56888 -306.824888) (xy 300.230032 -306.824888) (xy 300.229537 -306.849495)
			(xy 300.221642 -306.898072) (xy 300.206058 -306.944753) (xy 300.183187 -306.98833) (xy 300.153622 -307.027674)
			(xy 300.118129 -307.061766) (xy 300.077626 -307.089722) (xy 300.033164 -307.11082) (xy 299.985893 -307.124512)
			(xy 299.937038 -307.130444) (xy 299.887863 -307.128463) (xy 299.839644 -307.118619) (xy 299.793628 -307.101167)
			(xy 299.751007 -307.07656) (xy 299.712886 -307.045435) (xy 299.680251 -307.008598) (xy 299.653948 -306.967002)
			(xy 299.634657 -306.921726) (xy 299.62288 -306.873942) (xy 299.61892 -306.824888) (xy 299.280072 -306.824888)
			(xy 299.279577 -306.849495) (xy 299.271682 -306.898072) (xy 299.256098 -306.944753) (xy 299.233227 -306.98833)
			(xy 299.203662 -307.027674) (xy 299.168169 -307.061766) (xy 299.127666 -307.089722) (xy 299.083204 -307.11082)
			(xy 299.035933 -307.124512) (xy 298.987078 -307.130444) (xy 298.937903 -307.128463) (xy 298.889684 -307.118619)
			(xy 298.843668 -307.101167) (xy 298.801047 -307.07656) (xy 298.762926 -307.045435) (xy 298.730291 -307.008598)
			(xy 298.703988 -306.967002) (xy 298.684697 -306.921726) (xy 298.67292 -306.873942) (xy 298.66896 -306.824888)
			(xy 298.330112 -306.824888) (xy 298.329617 -306.849495) (xy 298.321722 -306.898072) (xy 298.306138 -306.944753)
			(xy 298.283267 -306.98833) (xy 298.253702 -307.027674) (xy 298.218209 -307.061766) (xy 298.177706 -307.089722)
			(xy 298.133244 -307.11082) (xy 298.085973 -307.124512) (xy 298.037118 -307.130444) (xy 297.987943 -307.128463)
			(xy 297.939724 -307.118619) (xy 297.893708 -307.101167) (xy 297.851087 -307.07656) (xy 297.812966 -307.045435)
			(xy 297.780331 -307.008598) (xy 297.754028 -306.967002) (xy 297.734737 -306.921726) (xy 297.72296 -306.873942)
			(xy 297.719 -306.824888) (xy 297.380152 -306.824888) (xy 297.379657 -306.849495) (xy 297.371762 -306.898072)
			(xy 297.356178 -306.944753) (xy 297.333307 -306.98833) (xy 297.303742 -307.027674) (xy 297.268249 -307.061766)
			(xy 297.227746 -307.089722) (xy 297.183284 -307.11082) (xy 297.136013 -307.124512) (xy 297.087158 -307.130444)
			(xy 297.037983 -307.128463) (xy 296.989764 -307.118619) (xy 296.943748 -307.101167) (xy 296.901127 -307.07656)
			(xy 296.863006 -307.045435) (xy 296.830371 -307.008598) (xy 296.804068 -306.967002) (xy 296.784777 -306.921726)
			(xy 296.773 -306.873942) (xy 296.76904 -306.824888) (xy 296.430192 -306.824888) (xy 296.429697 -306.849495)
			(xy 296.421802 -306.898072) (xy 296.406218 -306.944753) (xy 296.383347 -306.98833) (xy 296.353782 -307.027674)
			(xy 296.318289 -307.061766) (xy 296.277786 -307.089722) (xy 296.233324 -307.11082) (xy 296.186053 -307.124512)
			(xy 296.137198 -307.130444) (xy 296.088023 -307.128463) (xy 296.039804 -307.118619) (xy 295.993788 -307.101167)
			(xy 295.951167 -307.07656) (xy 295.913046 -307.045435) (xy 295.880411 -307.008598) (xy 295.854108 -306.967002)
			(xy 295.834817 -306.921726) (xy 295.82304 -306.873942) (xy 295.81908 -306.824888) (xy 295.480232 -306.824888)
			(xy 295.479737 -306.849495) (xy 295.471842 -306.898072) (xy 295.456258 -306.944753) (xy 295.433387 -306.98833)
			(xy 295.403822 -307.027674) (xy 295.368329 -307.061766) (xy 295.327826 -307.089722) (xy 295.283364 -307.11082)
			(xy 295.236093 -307.124512) (xy 295.187238 -307.130444) (xy 295.138063 -307.128463) (xy 295.089844 -307.118619)
			(xy 295.043828 -307.101167) (xy 295.001207 -307.07656) (xy 294.963086 -307.045435) (xy 294.930451 -307.008598)
			(xy 294.904148 -306.967002) (xy 294.884857 -306.921726) (xy 294.87308 -306.873942) (xy 294.86912 -306.824888)
			(xy 294.530018 -306.824888) (xy 294.529523 -306.849495) (xy 294.521628 -306.898072) (xy 294.506044 -306.944753)
			(xy 294.483173 -306.98833) (xy 294.453608 -307.027674) (xy 294.418115 -307.061766) (xy 294.377612 -307.089722)
			(xy 294.33315 -307.11082) (xy 294.285879 -307.124512) (xy 294.237024 -307.130444) (xy 294.187849 -307.128463)
			(xy 294.13963 -307.118619) (xy 294.093614 -307.101167) (xy 294.050993 -307.07656) (xy 294.012872 -307.045435)
			(xy 293.980237 -307.008598) (xy 293.953934 -306.967002) (xy 293.934643 -306.921726) (xy 293.922866 -306.873942)
			(xy 293.918906 -306.824888) (xy 293.580058 -306.824888) (xy 293.579563 -306.849495) (xy 293.571668 -306.898072)
			(xy 293.556084 -306.944753) (xy 293.533213 -306.98833) (xy 293.503648 -307.027674) (xy 293.468155 -307.061766)
			(xy 293.427652 -307.089722) (xy 293.38319 -307.11082) (xy 293.335919 -307.124512) (xy 293.287064 -307.130444)
			(xy 293.237889 -307.128463) (xy 293.18967 -307.118619) (xy 293.143654 -307.101167) (xy 293.101033 -307.07656)
			(xy 293.062912 -307.045435) (xy 293.030277 -307.008598) (xy 293.003974 -306.967002) (xy 292.984683 -306.921726)
			(xy 292.972906 -306.873942) (xy 292.968946 -306.824888) (xy 292.630098 -306.824888) (xy 292.629603 -306.849495)
			(xy 292.621708 -306.898072) (xy 292.606124 -306.944753) (xy 292.583253 -306.98833) (xy 292.553688 -307.027674)
			(xy 292.518195 -307.061766) (xy 292.477692 -307.089722) (xy 292.43323 -307.11082) (xy 292.385959 -307.124512)
			(xy 292.337104 -307.130444) (xy 292.287929 -307.128463) (xy 292.23971 -307.118619) (xy 292.193694 -307.101167)
			(xy 292.151073 -307.07656) (xy 292.112952 -307.045435) (xy 292.080317 -307.008598) (xy 292.054014 -306.967002)
			(xy 292.034723 -306.921726) (xy 292.022946 -306.873942) (xy 292.018986 -306.824888) (xy 290.730178 -306.824888)
			(xy 290.729683 -306.849495) (xy 290.721788 -306.898072) (xy 290.706204 -306.944753) (xy 290.683333 -306.98833)
			(xy 290.653768 -307.027674) (xy 290.618275 -307.061766) (xy 290.577772 -307.089722) (xy 290.53331 -307.11082)
			(xy 290.486039 -307.124512) (xy 290.437184 -307.130444) (xy 290.388009 -307.128463) (xy 290.33979 -307.118619)
			(xy 290.293774 -307.101167) (xy 290.251153 -307.07656) (xy 290.213032 -307.045435) (xy 290.180397 -307.008598)
			(xy 290.154094 -306.967002) (xy 290.134803 -306.921726) (xy 290.123026 -306.873942) (xy 290.119066 -306.824888)
			(xy 289.780218 -306.824888) (xy 289.779723 -306.849495) (xy 289.771828 -306.898072) (xy 289.756244 -306.944753)
			(xy 289.733373 -306.98833) (xy 289.703808 -307.027674) (xy 289.668315 -307.061766) (xy 289.627812 -307.089722)
			(xy 289.58335 -307.11082) (xy 289.536079 -307.124512) (xy 289.487224 -307.130444) (xy 289.438049 -307.128463)
			(xy 289.38983 -307.118619) (xy 289.343814 -307.101167) (xy 289.301193 -307.07656) (xy 289.263072 -307.045435)
			(xy 289.230437 -307.008598) (xy 289.204134 -306.967002) (xy 289.184843 -306.921726) (xy 289.173066 -306.873942)
			(xy 289.169106 -306.824888) (xy 288.830004 -306.824888) (xy 288.829509 -306.849495) (xy 288.821614 -306.898072)
			(xy 288.80603 -306.944753) (xy 288.783159 -306.98833) (xy 288.753594 -307.027674) (xy 288.718101 -307.061766)
			(xy 288.677598 -307.089722) (xy 288.633136 -307.11082) (xy 288.585865 -307.124512) (xy 288.53701 -307.130444)
			(xy 288.487835 -307.128463) (xy 288.439616 -307.118619) (xy 288.3936 -307.101167) (xy 288.350979 -307.07656)
			(xy 288.312858 -307.045435) (xy 288.280223 -307.008598) (xy 288.25392 -306.967002) (xy 288.234629 -306.921726)
			(xy 288.222852 -306.873942) (xy 288.218892 -306.824888) (xy 287.880044 -306.824888) (xy 287.879549 -306.849495)
			(xy 287.871654 -306.898072) (xy 287.85607 -306.944753) (xy 287.833199 -306.98833) (xy 287.803634 -307.027674)
			(xy 287.768141 -307.061766) (xy 287.727638 -307.089722) (xy 287.683176 -307.11082) (xy 287.635905 -307.124512)
			(xy 287.58705 -307.130444) (xy 287.537875 -307.128463) (xy 287.489656 -307.118619) (xy 287.44364 -307.101167)
			(xy 287.401019 -307.07656) (xy 287.362898 -307.045435) (xy 287.330263 -307.008598) (xy 287.30396 -306.967002)
			(xy 287.284669 -306.921726) (xy 287.272892 -306.873942) (xy 287.268932 -306.824888) (xy 286.930084 -306.824888)
			(xy 286.929589 -306.849495) (xy 286.921694 -306.898072) (xy 286.90611 -306.944753) (xy 286.883239 -306.98833)
			(xy 286.853674 -307.027674) (xy 286.818181 -307.061766) (xy 286.777678 -307.089722) (xy 286.733216 -307.11082)
			(xy 286.685945 -307.124512) (xy 286.63709 -307.130444) (xy 286.587915 -307.128463) (xy 286.539696 -307.118619)
			(xy 286.49368 -307.101167) (xy 286.451059 -307.07656) (xy 286.412938 -307.045435) (xy 286.380303 -307.008598)
			(xy 286.354 -306.967002) (xy 286.334709 -306.921726) (xy 286.322932 -306.873942) (xy 286.318972 -306.824888)
			(xy 285.980124 -306.824888) (xy 285.979629 -306.849495) (xy 285.971734 -306.898072) (xy 285.95615 -306.944753)
			(xy 285.933279 -306.98833) (xy 285.903714 -307.027674) (xy 285.868221 -307.061766) (xy 285.827718 -307.089722)
			(xy 285.783256 -307.11082) (xy 285.735985 -307.124512) (xy 285.68713 -307.130444) (xy 285.637955 -307.128463)
			(xy 285.589736 -307.118619) (xy 285.54372 -307.101167) (xy 285.501099 -307.07656) (xy 285.462978 -307.045435)
			(xy 285.430343 -307.008598) (xy 285.40404 -306.967002) (xy 285.384749 -306.921726) (xy 285.372972 -306.873942)
			(xy 285.369012 -306.824888) (xy 285.030164 -306.824888) (xy 285.029669 -306.849495) (xy 285.021774 -306.898072)
			(xy 285.00619 -306.944753) (xy 284.983319 -306.98833) (xy 284.953754 -307.027674) (xy 284.918261 -307.061766)
			(xy 284.877758 -307.089722) (xy 284.833296 -307.11082) (xy 284.786025 -307.124512) (xy 284.73717 -307.130444)
			(xy 284.687995 -307.128463) (xy 284.639776 -307.118619) (xy 284.59376 -307.101167) (xy 284.551139 -307.07656)
			(xy 284.513018 -307.045435) (xy 284.480383 -307.008598) (xy 284.45408 -306.967002) (xy 284.434789 -306.921726)
			(xy 284.423012 -306.873942) (xy 284.419052 -306.824888) (xy 284.080204 -306.824888) (xy 284.079709 -306.849495)
			(xy 284.071814 -306.898072) (xy 284.05623 -306.944753) (xy 284.033359 -306.98833) (xy 284.003794 -307.027674)
			(xy 283.968301 -307.061766) (xy 283.927798 -307.089722) (xy 283.883336 -307.11082) (xy 283.836065 -307.124512)
			(xy 283.78721 -307.130444) (xy 283.738035 -307.128463) (xy 283.689816 -307.118619) (xy 283.6438 -307.101167)
			(xy 283.601179 -307.07656) (xy 283.563058 -307.045435) (xy 283.530423 -307.008598) (xy 283.50412 -306.967002)
			(xy 283.484829 -306.921726) (xy 283.473052 -306.873942) (xy 283.469092 -306.824888) (xy 283.130244 -306.824888)
			(xy 283.129749 -306.849495) (xy 283.121854 -306.898072) (xy 283.10627 -306.944753) (xy 283.083399 -306.98833)
			(xy 283.053834 -307.027674) (xy 283.018341 -307.061766) (xy 282.977838 -307.089722) (xy 282.933376 -307.11082)
			(xy 282.886105 -307.124512) (xy 282.83725 -307.130444) (xy 282.788075 -307.128463) (xy 282.739856 -307.118619)
			(xy 282.69384 -307.101167) (xy 282.651219 -307.07656) (xy 282.613098 -307.045435) (xy 282.580463 -307.008598)
			(xy 282.55416 -306.967002) (xy 282.534869 -306.921726) (xy 282.523092 -306.873942) (xy 282.519132 -306.824888)
			(xy 282.219146 -306.824888) (xy 282.219146 -307.299868) (xy 305.793914 -307.299868) (xy 305.797874 -307.250814)
			(xy 305.809651 -307.20303) (xy 305.828942 -307.157754) (xy 305.855245 -307.116158) (xy 305.88788 -307.079321)
			(xy 305.926001 -307.048196) (xy 305.968622 -307.023589) (xy 306.014638 -307.006137) (xy 306.062857 -306.996293)
			(xy 306.112032 -306.994312) (xy 306.160887 -307.000244) (xy 306.208158 -307.013936) (xy 306.25262 -307.035034)
			(xy 306.293123 -307.06299) (xy 306.328616 -307.097082) (xy 306.358181 -307.136426) (xy 306.381052 -307.180003)
			(xy 306.396636 -307.226684) (xy 306.404531 -307.275261) (xy 306.405026 -307.299868) (xy 306.744128 -307.299868)
			(xy 306.748088 -307.250814) (xy 306.759865 -307.20303) (xy 306.779156 -307.157754) (xy 306.805459 -307.116158)
			(xy 306.838094 -307.079321) (xy 306.876215 -307.048196) (xy 306.918836 -307.023589) (xy 306.964852 -307.006137)
			(xy 307.013071 -306.996293) (xy 307.062246 -306.994312) (xy 307.111101 -307.000244) (xy 307.158372 -307.013936)
			(xy 307.202834 -307.035034) (xy 307.243337 -307.06299) (xy 307.27883 -307.097082) (xy 307.308395 -307.136426)
			(xy 307.331266 -307.180003) (xy 307.34685 -307.226684) (xy 307.354745 -307.275261) (xy 307.35524 -307.299868)
			(xy 307.694088 -307.299868) (xy 307.698048 -307.250814) (xy 307.709825 -307.20303) (xy 307.729116 -307.157754)
			(xy 307.755419 -307.116158) (xy 307.788054 -307.079321) (xy 307.826175 -307.048196) (xy 307.868796 -307.023589)
			(xy 307.914812 -307.006137) (xy 307.963031 -306.996293) (xy 308.012206 -306.994312) (xy 308.061061 -307.000244)
			(xy 308.108332 -307.013936) (xy 308.152794 -307.035034) (xy 308.193297 -307.06299) (xy 308.22879 -307.097082)
			(xy 308.258355 -307.136426) (xy 308.281226 -307.180003) (xy 308.29681 -307.226684) (xy 308.304705 -307.275261)
			(xy 308.3052 -307.299868) (xy 308.644048 -307.299868) (xy 308.648008 -307.250814) (xy 308.659785 -307.20303)
			(xy 308.679076 -307.157754) (xy 308.705379 -307.116158) (xy 308.738014 -307.079321) (xy 308.776135 -307.048196)
			(xy 308.818756 -307.023589) (xy 308.864772 -307.006137) (xy 308.912991 -306.996293) (xy 308.962166 -306.994312)
			(xy 309.011021 -307.000244) (xy 309.058292 -307.013936) (xy 309.102754 -307.035034) (xy 309.143257 -307.06299)
			(xy 309.17875 -307.097082) (xy 309.208315 -307.136426) (xy 309.231186 -307.180003) (xy 309.24677 -307.226684)
			(xy 309.254665 -307.275261) (xy 309.25516 -307.299868) (xy 309.594008 -307.299868) (xy 309.597968 -307.250814)
			(xy 309.609745 -307.20303) (xy 309.629036 -307.157754) (xy 309.655339 -307.116158) (xy 309.687974 -307.079321)
			(xy 309.726095 -307.048196) (xy 309.768716 -307.023589) (xy 309.814732 -307.006137) (xy 309.862951 -306.996293)
			(xy 309.912126 -306.994312) (xy 309.960981 -307.000244) (xy 310.008252 -307.013936) (xy 310.052714 -307.035034)
			(xy 310.093217 -307.06299) (xy 310.12871 -307.097082) (xy 310.158275 -307.136426) (xy 310.181146 -307.180003)
			(xy 310.19673 -307.226684) (xy 310.204625 -307.275261) (xy 310.20512 -307.299868) (xy 310.543968 -307.299868)
			(xy 310.547928 -307.250814) (xy 310.559705 -307.20303) (xy 310.578996 -307.157754) (xy 310.605299 -307.116158)
			(xy 310.637934 -307.079321) (xy 310.676055 -307.048196) (xy 310.718676 -307.023589) (xy 310.764692 -307.006137)
			(xy 310.812911 -306.996293) (xy 310.862086 -306.994312) (xy 310.910941 -307.000244) (xy 310.958212 -307.013936)
			(xy 311.002674 -307.035034) (xy 311.043177 -307.06299) (xy 311.07867 -307.097082) (xy 311.108235 -307.136426)
			(xy 311.131106 -307.180003) (xy 311.14669 -307.226684) (xy 311.154585 -307.275261) (xy 311.15508 -307.299868)
			(xy 311.493928 -307.299868) (xy 311.497888 -307.250814) (xy 311.509665 -307.20303) (xy 311.528956 -307.157754)
			(xy 311.555259 -307.116158) (xy 311.587894 -307.079321) (xy 311.626015 -307.048196) (xy 311.668636 -307.023589)
			(xy 311.714652 -307.006137) (xy 311.762871 -306.996293) (xy 311.812046 -306.994312) (xy 311.860901 -307.000244)
			(xy 311.908172 -307.013936) (xy 311.952634 -307.035034) (xy 311.993137 -307.06299) (xy 312.02863 -307.097082)
			(xy 312.058195 -307.136426) (xy 312.081066 -307.180003) (xy 312.09665 -307.226684) (xy 312.104545 -307.275261)
			(xy 312.10504 -307.299868) (xy 312.443888 -307.299868) (xy 312.447848 -307.250814) (xy 312.459625 -307.20303)
			(xy 312.478916 -307.157754) (xy 312.505219 -307.116158) (xy 312.537854 -307.079321) (xy 312.575975 -307.048196)
			(xy 312.618596 -307.023589) (xy 312.664612 -307.006137) (xy 312.712831 -306.996293) (xy 312.762006 -306.994312)
			(xy 312.810861 -307.000244) (xy 312.858132 -307.013936) (xy 312.902594 -307.035034) (xy 312.943097 -307.06299)
			(xy 312.97859 -307.097082) (xy 313.008155 -307.136426) (xy 313.031026 -307.180003) (xy 313.04661 -307.226684)
			(xy 313.054505 -307.275261) (xy 313.055 -307.299868) (xy 313.394102 -307.299868) (xy 313.398062 -307.250814)
			(xy 313.409839 -307.20303) (xy 313.42913 -307.157754) (xy 313.455433 -307.116158) (xy 313.488068 -307.079321)
			(xy 313.526189 -307.048196) (xy 313.56881 -307.023589) (xy 313.614826 -307.006137) (xy 313.663045 -306.996293)
			(xy 313.71222 -306.994312) (xy 313.761075 -307.000244) (xy 313.808346 -307.013936) (xy 313.852808 -307.035034)
			(xy 313.893311 -307.06299) (xy 313.928804 -307.097082) (xy 313.958369 -307.136426) (xy 313.98124 -307.180003)
			(xy 313.996824 -307.226684) (xy 314.004719 -307.275261) (xy 314.005214 -307.299868) (xy 314.344062 -307.299868)
			(xy 314.348022 -307.250814) (xy 314.359799 -307.20303) (xy 314.37909 -307.157754) (xy 314.405393 -307.116158)
			(xy 314.438028 -307.079321) (xy 314.476149 -307.048196) (xy 314.51877 -307.023589) (xy 314.564786 -307.006137)
			(xy 314.613005 -306.996293) (xy 314.66218 -306.994312) (xy 314.711035 -307.000244) (xy 314.758306 -307.013936)
			(xy 314.802768 -307.035034) (xy 314.843271 -307.06299) (xy 314.878764 -307.097082) (xy 314.908329 -307.136426)
			(xy 314.9312 -307.180003) (xy 314.946784 -307.226684) (xy 314.954679 -307.275261) (xy 314.955174 -307.299868)
			(xy 314.954679 -307.324475) (xy 314.946784 -307.373052) (xy 314.9312 -307.419733) (xy 314.908329 -307.46331)
			(xy 314.878764 -307.502654) (xy 314.843271 -307.536746) (xy 314.802768 -307.564702) (xy 314.758306 -307.5858)
			(xy 314.711035 -307.599492) (xy 314.66218 -307.605424) (xy 314.613005 -307.603443) (xy 314.564786 -307.593599)
			(xy 314.51877 -307.576147) (xy 314.476149 -307.55154) (xy 314.438028 -307.520415) (xy 314.405393 -307.483578)
			(xy 314.37909 -307.441982) (xy 314.359799 -307.396706) (xy 314.348022 -307.348922) (xy 314.344062 -307.299868)
			(xy 314.005214 -307.299868) (xy 314.004719 -307.324475) (xy 313.996824 -307.373052) (xy 313.98124 -307.419733)
			(xy 313.958369 -307.46331) (xy 313.928804 -307.502654) (xy 313.893311 -307.536746) (xy 313.852808 -307.564702)
			(xy 313.808346 -307.5858) (xy 313.761075 -307.599492) (xy 313.71222 -307.605424) (xy 313.663045 -307.603443)
			(xy 313.614826 -307.593599) (xy 313.56881 -307.576147) (xy 313.526189 -307.55154) (xy 313.488068 -307.520415)
			(xy 313.455433 -307.483578) (xy 313.42913 -307.441982) (xy 313.409839 -307.396706) (xy 313.398062 -307.348922)
			(xy 313.394102 -307.299868) (xy 313.055 -307.299868) (xy 313.054505 -307.324475) (xy 313.04661 -307.373052)
			(xy 313.031026 -307.419733) (xy 313.008155 -307.46331) (xy 312.97859 -307.502654) (xy 312.943097 -307.536746)
			(xy 312.902594 -307.564702) (xy 312.858132 -307.5858) (xy 312.810861 -307.599492) (xy 312.762006 -307.605424)
			(xy 312.712831 -307.603443) (xy 312.664612 -307.593599) (xy 312.618596 -307.576147) (xy 312.575975 -307.55154)
			(xy 312.537854 -307.520415) (xy 312.505219 -307.483578) (xy 312.478916 -307.441982) (xy 312.459625 -307.396706)
			(xy 312.447848 -307.348922) (xy 312.443888 -307.299868) (xy 312.10504 -307.299868) (xy 312.104545 -307.324475)
			(xy 312.09665 -307.373052) (xy 312.081066 -307.419733) (xy 312.058195 -307.46331) (xy 312.02863 -307.502654)
			(xy 311.993137 -307.536746) (xy 311.952634 -307.564702) (xy 311.908172 -307.5858) (xy 311.860901 -307.599492)
			(xy 311.812046 -307.605424) (xy 311.762871 -307.603443) (xy 311.714652 -307.593599) (xy 311.668636 -307.576147)
			(xy 311.626015 -307.55154) (xy 311.587894 -307.520415) (xy 311.555259 -307.483578) (xy 311.528956 -307.441982)
			(xy 311.509665 -307.396706) (xy 311.497888 -307.348922) (xy 311.493928 -307.299868) (xy 311.15508 -307.299868)
			(xy 311.154585 -307.324475) (xy 311.14669 -307.373052) (xy 311.131106 -307.419733) (xy 311.108235 -307.46331)
			(xy 311.07867 -307.502654) (xy 311.043177 -307.536746) (xy 311.002674 -307.564702) (xy 310.958212 -307.5858)
			(xy 310.910941 -307.599492) (xy 310.862086 -307.605424) (xy 310.812911 -307.603443) (xy 310.764692 -307.593599)
			(xy 310.718676 -307.576147) (xy 310.676055 -307.55154) (xy 310.637934 -307.520415) (xy 310.605299 -307.483578)
			(xy 310.578996 -307.441982) (xy 310.559705 -307.396706) (xy 310.547928 -307.348922) (xy 310.543968 -307.299868)
			(xy 310.20512 -307.299868) (xy 310.204625 -307.324475) (xy 310.19673 -307.373052) (xy 310.181146 -307.419733)
			(xy 310.158275 -307.46331) (xy 310.12871 -307.502654) (xy 310.093217 -307.536746) (xy 310.052714 -307.564702)
			(xy 310.008252 -307.5858) (xy 309.960981 -307.599492) (xy 309.912126 -307.605424) (xy 309.862951 -307.603443)
			(xy 309.814732 -307.593599) (xy 309.768716 -307.576147) (xy 309.726095 -307.55154) (xy 309.687974 -307.520415)
			(xy 309.655339 -307.483578) (xy 309.629036 -307.441982) (xy 309.609745 -307.396706) (xy 309.597968 -307.348922)
			(xy 309.594008 -307.299868) (xy 309.25516 -307.299868) (xy 309.254665 -307.324475) (xy 309.24677 -307.373052)
			(xy 309.231186 -307.419733) (xy 309.208315 -307.46331) (xy 309.17875 -307.502654) (xy 309.143257 -307.536746)
			(xy 309.102754 -307.564702) (xy 309.058292 -307.5858) (xy 309.011021 -307.599492) (xy 308.962166 -307.605424)
			(xy 308.912991 -307.603443) (xy 308.864772 -307.593599) (xy 308.818756 -307.576147) (xy 308.776135 -307.55154)
			(xy 308.738014 -307.520415) (xy 308.705379 -307.483578) (xy 308.679076 -307.441982) (xy 308.659785 -307.396706)
			(xy 308.648008 -307.348922) (xy 308.644048 -307.299868) (xy 308.3052 -307.299868) (xy 308.304705 -307.324475)
			(xy 308.29681 -307.373052) (xy 308.281226 -307.419733) (xy 308.258355 -307.46331) (xy 308.22879 -307.502654)
			(xy 308.193297 -307.536746) (xy 308.152794 -307.564702) (xy 308.108332 -307.5858) (xy 308.061061 -307.599492)
			(xy 308.012206 -307.605424) (xy 307.963031 -307.603443) (xy 307.914812 -307.593599) (xy 307.868796 -307.576147)
			(xy 307.826175 -307.55154) (xy 307.788054 -307.520415) (xy 307.755419 -307.483578) (xy 307.729116 -307.441982)
			(xy 307.709825 -307.396706) (xy 307.698048 -307.348922) (xy 307.694088 -307.299868) (xy 307.35524 -307.299868)
			(xy 307.354745 -307.324475) (xy 307.34685 -307.373052) (xy 307.331266 -307.419733) (xy 307.308395 -307.46331)
			(xy 307.27883 -307.502654) (xy 307.243337 -307.536746) (xy 307.202834 -307.564702) (xy 307.158372 -307.5858)
			(xy 307.111101 -307.599492) (xy 307.062246 -307.605424) (xy 307.013071 -307.603443) (xy 306.964852 -307.593599)
			(xy 306.918836 -307.576147) (xy 306.876215 -307.55154) (xy 306.838094 -307.520415) (xy 306.805459 -307.483578)
			(xy 306.779156 -307.441982) (xy 306.759865 -307.396706) (xy 306.748088 -307.348922) (xy 306.744128 -307.299868)
			(xy 306.405026 -307.299868) (xy 306.404531 -307.324475) (xy 306.396636 -307.373052) (xy 306.381052 -307.419733)
			(xy 306.358181 -307.46331) (xy 306.328616 -307.502654) (xy 306.293123 -307.536746) (xy 306.25262 -307.564702)
			(xy 306.208158 -307.5858) (xy 306.160887 -307.599492) (xy 306.112032 -307.605424) (xy 306.062857 -307.603443)
			(xy 306.014638 -307.593599) (xy 305.968622 -307.576147) (xy 305.926001 -307.55154) (xy 305.88788 -307.520415)
			(xy 305.855245 -307.483578) (xy 305.828942 -307.441982) (xy 305.809651 -307.396706) (xy 305.797874 -307.348922)
			(xy 305.793914 -307.299868) (xy 282.219146 -307.299868) (xy 282.219146 -307.774848) (xy 282.519132 -307.774848)
			(xy 282.523092 -307.725794) (xy 282.534869 -307.67801) (xy 282.55416 -307.632734) (xy 282.580463 -307.591138)
			(xy 282.613098 -307.554301) (xy 282.651219 -307.523176) (xy 282.69384 -307.498569) (xy 282.739856 -307.481117)
			(xy 282.788075 -307.471273) (xy 282.83725 -307.469292) (xy 282.886105 -307.475224) (xy 282.933376 -307.488916)
			(xy 282.977838 -307.510014) (xy 283.018341 -307.53797) (xy 283.053834 -307.572062) (xy 283.083399 -307.611406)
			(xy 283.10627 -307.654983) (xy 283.121854 -307.701664) (xy 283.129749 -307.750241) (xy 283.130244 -307.774848)
			(xy 283.469092 -307.774848) (xy 283.473052 -307.725794) (xy 283.484829 -307.67801) (xy 283.50412 -307.632734)
			(xy 283.530423 -307.591138) (xy 283.563058 -307.554301) (xy 283.601179 -307.523176) (xy 283.6438 -307.498569)
			(xy 283.689816 -307.481117) (xy 283.738035 -307.471273) (xy 283.78721 -307.469292) (xy 283.836065 -307.475224)
			(xy 283.883336 -307.488916) (xy 283.927798 -307.510014) (xy 283.968301 -307.53797) (xy 284.003794 -307.572062)
			(xy 284.033359 -307.611406) (xy 284.05623 -307.654983) (xy 284.071814 -307.701664) (xy 284.079709 -307.750241)
			(xy 284.080204 -307.774848) (xy 284.419052 -307.774848) (xy 284.423012 -307.725794) (xy 284.434789 -307.67801)
			(xy 284.45408 -307.632734) (xy 284.480383 -307.591138) (xy 284.513018 -307.554301) (xy 284.551139 -307.523176)
			(xy 284.59376 -307.498569) (xy 284.639776 -307.481117) (xy 284.687995 -307.471273) (xy 284.73717 -307.469292)
			(xy 284.786025 -307.475224) (xy 284.833296 -307.488916) (xy 284.877758 -307.510014) (xy 284.918261 -307.53797)
			(xy 284.953754 -307.572062) (xy 284.983319 -307.611406) (xy 285.00619 -307.654983) (xy 285.021774 -307.701664)
			(xy 285.029669 -307.750241) (xy 285.030164 -307.774848) (xy 285.369012 -307.774848) (xy 285.372972 -307.725794)
			(xy 285.384749 -307.67801) (xy 285.40404 -307.632734) (xy 285.430343 -307.591138) (xy 285.462978 -307.554301)
			(xy 285.501099 -307.523176) (xy 285.54372 -307.498569) (xy 285.589736 -307.481117) (xy 285.637955 -307.471273)
			(xy 285.68713 -307.469292) (xy 285.735985 -307.475224) (xy 285.783256 -307.488916) (xy 285.827718 -307.510014)
			(xy 285.868221 -307.53797) (xy 285.903714 -307.572062) (xy 285.933279 -307.611406) (xy 285.95615 -307.654983)
			(xy 285.971734 -307.701664) (xy 285.979629 -307.750241) (xy 285.980124 -307.774848) (xy 286.318972 -307.774848)
			(xy 286.322932 -307.725794) (xy 286.334709 -307.67801) (xy 286.354 -307.632734) (xy 286.380303 -307.591138)
			(xy 286.412938 -307.554301) (xy 286.451059 -307.523176) (xy 286.49368 -307.498569) (xy 286.539696 -307.481117)
			(xy 286.587915 -307.471273) (xy 286.63709 -307.469292) (xy 286.685945 -307.475224) (xy 286.733216 -307.488916)
			(xy 286.777678 -307.510014) (xy 286.818181 -307.53797) (xy 286.853674 -307.572062) (xy 286.883239 -307.611406)
			(xy 286.90611 -307.654983) (xy 286.921694 -307.701664) (xy 286.929589 -307.750241) (xy 286.930084 -307.774848)
			(xy 287.268932 -307.774848) (xy 287.272892 -307.725794) (xy 287.284669 -307.67801) (xy 287.30396 -307.632734)
			(xy 287.330263 -307.591138) (xy 287.362898 -307.554301) (xy 287.401019 -307.523176) (xy 287.44364 -307.498569)
			(xy 287.489656 -307.481117) (xy 287.537875 -307.471273) (xy 287.58705 -307.469292) (xy 287.635905 -307.475224)
			(xy 287.683176 -307.488916) (xy 287.727638 -307.510014) (xy 287.768141 -307.53797) (xy 287.803634 -307.572062)
			(xy 287.833199 -307.611406) (xy 287.85607 -307.654983) (xy 287.871654 -307.701664) (xy 287.879549 -307.750241)
			(xy 287.880044 -307.774848) (xy 288.219146 -307.774848) (xy 288.223106 -307.725794) (xy 288.234883 -307.67801)
			(xy 288.254174 -307.632734) (xy 288.280477 -307.591138) (xy 288.313112 -307.554301) (xy 288.351233 -307.523176)
			(xy 288.393854 -307.498569) (xy 288.43987 -307.481117) (xy 288.488089 -307.471273) (xy 288.537264 -307.469292)
			(xy 288.586119 -307.475224) (xy 288.63339 -307.488916) (xy 288.677852 -307.510014) (xy 288.718355 -307.53797)
			(xy 288.753848 -307.572062) (xy 288.783413 -307.611406) (xy 288.806284 -307.654983) (xy 288.821868 -307.701664)
			(xy 288.829763 -307.750241) (xy 288.830258 -307.774848) (xy 289.169106 -307.774848) (xy 289.173066 -307.725794)
			(xy 289.184843 -307.67801) (xy 289.204134 -307.632734) (xy 289.230437 -307.591138) (xy 289.263072 -307.554301)
			(xy 289.301193 -307.523176) (xy 289.343814 -307.498569) (xy 289.38983 -307.481117) (xy 289.438049 -307.471273)
			(xy 289.487224 -307.469292) (xy 289.536079 -307.475224) (xy 289.58335 -307.488916) (xy 289.627812 -307.510014)
			(xy 289.668315 -307.53797) (xy 289.703808 -307.572062) (xy 289.733373 -307.611406) (xy 289.756244 -307.654983)
			(xy 289.771828 -307.701664) (xy 289.779723 -307.750241) (xy 289.780218 -307.774848) (xy 290.119066 -307.774848)
			(xy 290.123026 -307.725794) (xy 290.134803 -307.67801) (xy 290.154094 -307.632734) (xy 290.180397 -307.591138)
			(xy 290.213032 -307.554301) (xy 290.251153 -307.523176) (xy 290.293774 -307.498569) (xy 290.33979 -307.481117)
			(xy 290.388009 -307.471273) (xy 290.437184 -307.469292) (xy 290.486039 -307.475224) (xy 290.53331 -307.488916)
			(xy 290.577772 -307.510014) (xy 290.618275 -307.53797) (xy 290.653768 -307.572062) (xy 290.683333 -307.611406)
			(xy 290.706204 -307.654983) (xy 290.721788 -307.701664) (xy 290.729683 -307.750241) (xy 290.730178 -307.774848)
			(xy 292.018986 -307.774848) (xy 292.022946 -307.725794) (xy 292.034723 -307.67801) (xy 292.054014 -307.632734)
			(xy 292.080317 -307.591138) (xy 292.112952 -307.554301) (xy 292.151073 -307.523176) (xy 292.193694 -307.498569)
			(xy 292.23971 -307.481117) (xy 292.287929 -307.471273) (xy 292.337104 -307.469292) (xy 292.385959 -307.475224)
			(xy 292.43323 -307.488916) (xy 292.477692 -307.510014) (xy 292.518195 -307.53797) (xy 292.553688 -307.572062)
			(xy 292.583253 -307.611406) (xy 292.606124 -307.654983) (xy 292.621708 -307.701664) (xy 292.629603 -307.750241)
			(xy 292.630098 -307.774848) (xy 292.968946 -307.774848) (xy 292.972906 -307.725794) (xy 292.984683 -307.67801)
			(xy 293.003974 -307.632734) (xy 293.030277 -307.591138) (xy 293.062912 -307.554301) (xy 293.101033 -307.523176)
			(xy 293.143654 -307.498569) (xy 293.18967 -307.481117) (xy 293.237889 -307.471273) (xy 293.287064 -307.469292)
			(xy 293.335919 -307.475224) (xy 293.38319 -307.488916) (xy 293.427652 -307.510014) (xy 293.468155 -307.53797)
			(xy 293.503648 -307.572062) (xy 293.533213 -307.611406) (xy 293.556084 -307.654983) (xy 293.571668 -307.701664)
			(xy 293.579563 -307.750241) (xy 293.580058 -307.774848) (xy 293.918906 -307.774848) (xy 293.922866 -307.725794)
			(xy 293.934643 -307.67801) (xy 293.953934 -307.632734) (xy 293.980237 -307.591138) (xy 294.012872 -307.554301)
			(xy 294.050993 -307.523176) (xy 294.093614 -307.498569) (xy 294.13963 -307.481117) (xy 294.187849 -307.471273)
			(xy 294.237024 -307.469292) (xy 294.285879 -307.475224) (xy 294.33315 -307.488916) (xy 294.377612 -307.510014)
			(xy 294.418115 -307.53797) (xy 294.453608 -307.572062) (xy 294.483173 -307.611406) (xy 294.506044 -307.654983)
			(xy 294.521628 -307.701664) (xy 294.529523 -307.750241) (xy 294.530013 -307.774594) (xy 294.868866 -307.774594)
			(xy 294.872826 -307.72554) (xy 294.884603 -307.677756) (xy 294.903894 -307.63248) (xy 294.930197 -307.590884)
			(xy 294.962832 -307.554047) (xy 295.000953 -307.522922) (xy 295.043574 -307.498315) (xy 295.08959 -307.480863)
			(xy 295.137809 -307.471019) (xy 295.186984 -307.469038) (xy 295.235839 -307.47497) (xy 295.28311 -307.488662)
			(xy 295.327572 -307.50976) (xy 295.368075 -307.537716) (xy 295.403568 -307.571808) (xy 295.433133 -307.611152)
			(xy 295.456004 -307.654729) (xy 295.471588 -307.70141) (xy 295.479483 -307.749987) (xy 295.479978 -307.774594)
			(xy 295.81908 -307.774594) (xy 295.82304 -307.72554) (xy 295.834817 -307.677756) (xy 295.854108 -307.63248)
			(xy 295.880411 -307.590884) (xy 295.913046 -307.554047) (xy 295.951167 -307.522922) (xy 295.993788 -307.498315)
			(xy 296.039804 -307.480863) (xy 296.088023 -307.471019) (xy 296.137198 -307.469038) (xy 296.186053 -307.47497)
			(xy 296.233324 -307.488662) (xy 296.277786 -307.50976) (xy 296.318289 -307.537716) (xy 296.353782 -307.571808)
			(xy 296.383347 -307.611152) (xy 296.406218 -307.654729) (xy 296.421802 -307.70141) (xy 296.429697 -307.749987)
			(xy 296.430192 -307.774594) (xy 296.430187 -307.774848) (xy 296.76904 -307.774848) (xy 296.773 -307.725794)
			(xy 296.784777 -307.67801) (xy 296.804068 -307.632734) (xy 296.830371 -307.591138) (xy 296.863006 -307.554301)
			(xy 296.901127 -307.523176) (xy 296.943748 -307.498569) (xy 296.989764 -307.481117) (xy 297.037983 -307.471273)
			(xy 297.087158 -307.469292) (xy 297.136013 -307.475224) (xy 297.183284 -307.488916) (xy 297.227746 -307.510014)
			(xy 297.268249 -307.53797) (xy 297.303742 -307.572062) (xy 297.333307 -307.611406) (xy 297.356178 -307.654983)
			(xy 297.371762 -307.701664) (xy 297.379657 -307.750241) (xy 297.380152 -307.774848) (xy 297.719 -307.774848)
			(xy 297.72296 -307.725794) (xy 297.734737 -307.67801) (xy 297.754028 -307.632734) (xy 297.780331 -307.591138)
			(xy 297.812966 -307.554301) (xy 297.851087 -307.523176) (xy 297.893708 -307.498569) (xy 297.939724 -307.481117)
			(xy 297.987943 -307.471273) (xy 298.037118 -307.469292) (xy 298.085973 -307.475224) (xy 298.133244 -307.488916)
			(xy 298.177706 -307.510014) (xy 298.218209 -307.53797) (xy 298.253702 -307.572062) (xy 298.283267 -307.611406)
			(xy 298.306138 -307.654983) (xy 298.321722 -307.701664) (xy 298.329617 -307.750241) (xy 298.330112 -307.774848)
			(xy 298.66896 -307.774848) (xy 298.67292 -307.725794) (xy 298.684697 -307.67801) (xy 298.703988 -307.632734)
			(xy 298.730291 -307.591138) (xy 298.762926 -307.554301) (xy 298.801047 -307.523176) (xy 298.843668 -307.498569)
			(xy 298.889684 -307.481117) (xy 298.937903 -307.471273) (xy 298.987078 -307.469292) (xy 299.035933 -307.475224)
			(xy 299.083204 -307.488916) (xy 299.127666 -307.510014) (xy 299.168169 -307.53797) (xy 299.203662 -307.572062)
			(xy 299.233227 -307.611406) (xy 299.256098 -307.654983) (xy 299.271682 -307.701664) (xy 299.279577 -307.750241)
			(xy 299.280072 -307.774848) (xy 299.61892 -307.774848) (xy 299.62288 -307.725794) (xy 299.634657 -307.67801)
			(xy 299.653948 -307.632734) (xy 299.680251 -307.591138) (xy 299.712886 -307.554301) (xy 299.751007 -307.523176)
			(xy 299.793628 -307.498569) (xy 299.839644 -307.481117) (xy 299.887863 -307.471273) (xy 299.937038 -307.469292)
			(xy 299.985893 -307.475224) (xy 300.033164 -307.488916) (xy 300.077626 -307.510014) (xy 300.118129 -307.53797)
			(xy 300.153622 -307.572062) (xy 300.183187 -307.611406) (xy 300.206058 -307.654983) (xy 300.221642 -307.701664)
			(xy 300.229537 -307.750241) (xy 300.230032 -307.774848) (xy 300.56888 -307.774848) (xy 300.57284 -307.725794)
			(xy 300.584617 -307.67801) (xy 300.603908 -307.632734) (xy 300.630211 -307.591138) (xy 300.662846 -307.554301)
			(xy 300.700967 -307.523176) (xy 300.743588 -307.498569) (xy 300.789604 -307.481117) (xy 300.837823 -307.471273)
			(xy 300.886998 -307.469292) (xy 300.935853 -307.475224) (xy 300.983124 -307.488916) (xy 301.027586 -307.510014)
			(xy 301.068089 -307.53797) (xy 301.103582 -307.572062) (xy 301.133147 -307.611406) (xy 301.156018 -307.654983)
			(xy 301.171602 -307.701664) (xy 301.179497 -307.750241) (xy 301.179992 -307.774848) (xy 301.519094 -307.774848)
			(xy 301.523054 -307.725794) (xy 301.534831 -307.67801) (xy 301.554122 -307.632734) (xy 301.580425 -307.591138)
			(xy 301.61306 -307.554301) (xy 301.651181 -307.523176) (xy 301.693802 -307.498569) (xy 301.739818 -307.481117)
			(xy 301.788037 -307.471273) (xy 301.837212 -307.469292) (xy 301.886067 -307.475224) (xy 301.933338 -307.488916)
			(xy 301.9778 -307.510014) (xy 302.018303 -307.53797) (xy 302.053796 -307.572062) (xy 302.083361 -307.611406)
			(xy 302.106232 -307.654983) (xy 302.121816 -307.701664) (xy 302.129711 -307.750241) (xy 302.130206 -307.774848)
			(xy 302.469054 -307.774848) (xy 302.473014 -307.725794) (xy 302.484791 -307.67801) (xy 302.504082 -307.632734)
			(xy 302.530385 -307.591138) (xy 302.56302 -307.554301) (xy 302.601141 -307.523176) (xy 302.643762 -307.498569)
			(xy 302.689778 -307.481117) (xy 302.737997 -307.471273) (xy 302.787172 -307.469292) (xy 302.836027 -307.475224)
			(xy 302.883298 -307.488916) (xy 302.92776 -307.510014) (xy 302.968263 -307.53797) (xy 303.003756 -307.572062)
			(xy 303.033321 -307.611406) (xy 303.056192 -307.654983) (xy 303.071776 -307.701664) (xy 303.079671 -307.750241)
			(xy 303.080166 -307.774848) (xy 303.419014 -307.774848) (xy 303.422974 -307.725794) (xy 303.434751 -307.67801)
			(xy 303.454042 -307.632734) (xy 303.480345 -307.591138) (xy 303.51298 -307.554301) (xy 303.551101 -307.523176)
			(xy 303.593722 -307.498569) (xy 303.639738 -307.481117) (xy 303.687957 -307.471273) (xy 303.737132 -307.469292)
			(xy 303.785987 -307.475224) (xy 303.833258 -307.488916) (xy 303.87772 -307.510014) (xy 303.918223 -307.53797)
			(xy 303.953716 -307.572062) (xy 303.983281 -307.611406) (xy 304.006152 -307.654983) (xy 304.021736 -307.701664)
			(xy 304.029631 -307.750241) (xy 304.030126 -307.774848) (xy 304.368974 -307.774848) (xy 304.372934 -307.725794)
			(xy 304.384711 -307.67801) (xy 304.404002 -307.632734) (xy 304.430305 -307.591138) (xy 304.46294 -307.554301)
			(xy 304.501061 -307.523176) (xy 304.543682 -307.498569) (xy 304.589698 -307.481117) (xy 304.637917 -307.471273)
			(xy 304.687092 -307.469292) (xy 304.735947 -307.475224) (xy 304.783218 -307.488916) (xy 304.82768 -307.510014)
			(xy 304.868183 -307.53797) (xy 304.903676 -307.572062) (xy 304.933241 -307.611406) (xy 304.956112 -307.654983)
			(xy 304.971696 -307.701664) (xy 304.979591 -307.750241) (xy 304.980086 -307.774848) (xy 304.979591 -307.799455)
			(xy 304.971696 -307.848032) (xy 304.956112 -307.894713) (xy 304.933241 -307.93829) (xy 304.903676 -307.977634)
			(xy 304.868183 -308.011726) (xy 304.82768 -308.039682) (xy 304.783218 -308.06078) (xy 304.735947 -308.074472)
			(xy 304.687092 -308.080404) (xy 304.637917 -308.078423) (xy 304.589698 -308.068579) (xy 304.543682 -308.051127)
			(xy 304.501061 -308.02652) (xy 304.46294 -307.995395) (xy 304.430305 -307.958558) (xy 304.404002 -307.916962)
			(xy 304.384711 -307.871686) (xy 304.372934 -307.823902) (xy 304.368974 -307.774848) (xy 304.030126 -307.774848)
			(xy 304.029631 -307.799455) (xy 304.021736 -307.848032) (xy 304.006152 -307.894713) (xy 303.983281 -307.93829)
			(xy 303.953716 -307.977634) (xy 303.918223 -308.011726) (xy 303.87772 -308.039682) (xy 303.833258 -308.06078)
			(xy 303.785987 -308.074472) (xy 303.737132 -308.080404) (xy 303.687957 -308.078423) (xy 303.639738 -308.068579)
			(xy 303.593722 -308.051127) (xy 303.551101 -308.02652) (xy 303.51298 -307.995395) (xy 303.480345 -307.958558)
			(xy 303.454042 -307.916962) (xy 303.434751 -307.871686) (xy 303.422974 -307.823902) (xy 303.419014 -307.774848)
			(xy 303.080166 -307.774848) (xy 303.079671 -307.799455) (xy 303.071776 -307.848032) (xy 303.056192 -307.894713)
			(xy 303.033321 -307.93829) (xy 303.003756 -307.977634) (xy 302.968263 -308.011726) (xy 302.92776 -308.039682)
			(xy 302.883298 -308.06078) (xy 302.836027 -308.074472) (xy 302.787172 -308.080404) (xy 302.737997 -308.078423)
			(xy 302.689778 -308.068579) (xy 302.643762 -308.051127) (xy 302.601141 -308.02652) (xy 302.56302 -307.995395)
			(xy 302.530385 -307.958558) (xy 302.504082 -307.916962) (xy 302.484791 -307.871686) (xy 302.473014 -307.823902)
			(xy 302.469054 -307.774848) (xy 302.130206 -307.774848) (xy 302.129711 -307.799455) (xy 302.121816 -307.848032)
			(xy 302.106232 -307.894713) (xy 302.083361 -307.93829) (xy 302.053796 -307.977634) (xy 302.018303 -308.011726)
			(xy 301.9778 -308.039682) (xy 301.933338 -308.06078) (xy 301.886067 -308.074472) (xy 301.837212 -308.080404)
			(xy 301.788037 -308.078423) (xy 301.739818 -308.068579) (xy 301.693802 -308.051127) (xy 301.651181 -308.02652)
			(xy 301.61306 -307.995395) (xy 301.580425 -307.958558) (xy 301.554122 -307.916962) (xy 301.534831 -307.871686)
			(xy 301.523054 -307.823902) (xy 301.519094 -307.774848) (xy 301.179992 -307.774848) (xy 301.179497 -307.799455)
			(xy 301.171602 -307.848032) (xy 301.156018 -307.894713) (xy 301.133147 -307.93829) (xy 301.103582 -307.977634)
			(xy 301.068089 -308.011726) (xy 301.027586 -308.039682) (xy 300.983124 -308.06078) (xy 300.935853 -308.074472)
			(xy 300.886998 -308.080404) (xy 300.837823 -308.078423) (xy 300.789604 -308.068579) (xy 300.743588 -308.051127)
			(xy 300.700967 -308.02652) (xy 300.662846 -307.995395) (xy 300.630211 -307.958558) (xy 300.603908 -307.916962)
			(xy 300.584617 -307.871686) (xy 300.57284 -307.823902) (xy 300.56888 -307.774848) (xy 300.230032 -307.774848)
			(xy 300.229537 -307.799455) (xy 300.221642 -307.848032) (xy 300.206058 -307.894713) (xy 300.183187 -307.93829)
			(xy 300.153622 -307.977634) (xy 300.118129 -308.011726) (xy 300.077626 -308.039682) (xy 300.033164 -308.06078)
			(xy 299.985893 -308.074472) (xy 299.937038 -308.080404) (xy 299.887863 -308.078423) (xy 299.839644 -308.068579)
			(xy 299.793628 -308.051127) (xy 299.751007 -308.02652) (xy 299.712886 -307.995395) (xy 299.680251 -307.958558)
			(xy 299.653948 -307.916962) (xy 299.634657 -307.871686) (xy 299.62288 -307.823902) (xy 299.61892 -307.774848)
			(xy 299.280072 -307.774848) (xy 299.279577 -307.799455) (xy 299.271682 -307.848032) (xy 299.256098 -307.894713)
			(xy 299.233227 -307.93829) (xy 299.203662 -307.977634) (xy 299.168169 -308.011726) (xy 299.127666 -308.039682)
			(xy 299.083204 -308.06078) (xy 299.035933 -308.074472) (xy 298.987078 -308.080404) (xy 298.937903 -308.078423)
			(xy 298.889684 -308.068579) (xy 298.843668 -308.051127) (xy 298.801047 -308.02652) (xy 298.762926 -307.995395)
			(xy 298.730291 -307.958558) (xy 298.703988 -307.916962) (xy 298.684697 -307.871686) (xy 298.67292 -307.823902)
			(xy 298.66896 -307.774848) (xy 298.330112 -307.774848) (xy 298.329617 -307.799455) (xy 298.321722 -307.848032)
			(xy 298.306138 -307.894713) (xy 298.283267 -307.93829) (xy 298.253702 -307.977634) (xy 298.218209 -308.011726)
			(xy 298.177706 -308.039682) (xy 298.133244 -308.06078) (xy 298.085973 -308.074472) (xy 298.037118 -308.080404)
			(xy 297.987943 -308.078423) (xy 297.939724 -308.068579) (xy 297.893708 -308.051127) (xy 297.851087 -308.02652)
			(xy 297.812966 -307.995395) (xy 297.780331 -307.958558) (xy 297.754028 -307.916962) (xy 297.734737 -307.871686)
			(xy 297.72296 -307.823902) (xy 297.719 -307.774848) (xy 297.380152 -307.774848) (xy 297.379657 -307.799455)
			(xy 297.371762 -307.848032) (xy 297.356178 -307.894713) (xy 297.333307 -307.93829) (xy 297.303742 -307.977634)
			(xy 297.268249 -308.011726) (xy 297.227746 -308.039682) (xy 297.183284 -308.06078) (xy 297.136013 -308.074472)
			(xy 297.087158 -308.080404) (xy 297.037983 -308.078423) (xy 296.989764 -308.068579) (xy 296.943748 -308.051127)
			(xy 296.901127 -308.02652) (xy 296.863006 -307.995395) (xy 296.830371 -307.958558) (xy 296.804068 -307.916962)
			(xy 296.784777 -307.871686) (xy 296.773 -307.823902) (xy 296.76904 -307.774848) (xy 296.430187 -307.774848)
			(xy 296.429697 -307.799201) (xy 296.421802 -307.847778) (xy 296.406218 -307.894459) (xy 296.383347 -307.938036)
			(xy 296.353782 -307.97738) (xy 296.318289 -308.011472) (xy 296.277786 -308.039428) (xy 296.233324 -308.060526)
			(xy 296.186053 -308.074218) (xy 296.137198 -308.08015) (xy 296.088023 -308.078169) (xy 296.039804 -308.068325)
			(xy 295.993788 -308.050873) (xy 295.951167 -308.026266) (xy 295.913046 -307.995141) (xy 295.880411 -307.958304)
			(xy 295.854108 -307.916708) (xy 295.834817 -307.871432) (xy 295.82304 -307.823648) (xy 295.81908 -307.774594)
			(xy 295.479978 -307.774594) (xy 295.479483 -307.799201) (xy 295.471588 -307.847778) (xy 295.456004 -307.894459)
			(xy 295.433133 -307.938036) (xy 295.403568 -307.97738) (xy 295.368075 -308.011472) (xy 295.327572 -308.039428)
			(xy 295.28311 -308.060526) (xy 295.235839 -308.074218) (xy 295.186984 -308.08015) (xy 295.137809 -308.078169)
			(xy 295.08959 -308.068325) (xy 295.043574 -308.050873) (xy 295.000953 -308.026266) (xy 294.962832 -307.995141)
			(xy 294.930197 -307.958304) (xy 294.903894 -307.916708) (xy 294.884603 -307.871432) (xy 294.872826 -307.823648)
			(xy 294.868866 -307.774594) (xy 294.530013 -307.774594) (xy 294.530018 -307.774848) (xy 294.529523 -307.799455)
			(xy 294.521628 -307.848032) (xy 294.506044 -307.894713) (xy 294.483173 -307.93829) (xy 294.453608 -307.977634)
			(xy 294.418115 -308.011726) (xy 294.377612 -308.039682) (xy 294.33315 -308.06078) (xy 294.285879 -308.074472)
			(xy 294.237024 -308.080404) (xy 294.187849 -308.078423) (xy 294.13963 -308.068579) (xy 294.093614 -308.051127)
			(xy 294.050993 -308.02652) (xy 294.012872 -307.995395) (xy 293.980237 -307.958558) (xy 293.953934 -307.916962)
			(xy 293.934643 -307.871686) (xy 293.922866 -307.823902) (xy 293.918906 -307.774848) (xy 293.580058 -307.774848)
			(xy 293.579563 -307.799455) (xy 293.571668 -307.848032) (xy 293.556084 -307.894713) (xy 293.533213 -307.93829)
			(xy 293.503648 -307.977634) (xy 293.468155 -308.011726) (xy 293.427652 -308.039682) (xy 293.38319 -308.06078)
			(xy 293.335919 -308.074472) (xy 293.287064 -308.080404) (xy 293.237889 -308.078423) (xy 293.18967 -308.068579)
			(xy 293.143654 -308.051127) (xy 293.101033 -308.02652) (xy 293.062912 -307.995395) (xy 293.030277 -307.958558)
			(xy 293.003974 -307.916962) (xy 292.984683 -307.871686) (xy 292.972906 -307.823902) (xy 292.968946 -307.774848)
			(xy 292.630098 -307.774848) (xy 292.629603 -307.799455) (xy 292.621708 -307.848032) (xy 292.606124 -307.894713)
			(xy 292.583253 -307.93829) (xy 292.553688 -307.977634) (xy 292.518195 -308.011726) (xy 292.477692 -308.039682)
			(xy 292.43323 -308.06078) (xy 292.385959 -308.074472) (xy 292.337104 -308.080404) (xy 292.287929 -308.078423)
			(xy 292.23971 -308.068579) (xy 292.193694 -308.051127) (xy 292.151073 -308.02652) (xy 292.112952 -307.995395)
			(xy 292.080317 -307.958558) (xy 292.054014 -307.916962) (xy 292.034723 -307.871686) (xy 292.022946 -307.823902)
			(xy 292.018986 -307.774848) (xy 290.730178 -307.774848) (xy 290.729683 -307.799455) (xy 290.721788 -307.848032)
			(xy 290.706204 -307.894713) (xy 290.683333 -307.93829) (xy 290.653768 -307.977634) (xy 290.618275 -308.011726)
			(xy 290.577772 -308.039682) (xy 290.53331 -308.06078) (xy 290.486039 -308.074472) (xy 290.437184 -308.080404)
			(xy 290.388009 -308.078423) (xy 290.33979 -308.068579) (xy 290.293774 -308.051127) (xy 290.251153 -308.02652)
			(xy 290.213032 -307.995395) (xy 290.180397 -307.958558) (xy 290.154094 -307.916962) (xy 290.134803 -307.871686)
			(xy 290.123026 -307.823902) (xy 290.119066 -307.774848) (xy 289.780218 -307.774848) (xy 289.779723 -307.799455)
			(xy 289.771828 -307.848032) (xy 289.756244 -307.894713) (xy 289.733373 -307.93829) (xy 289.703808 -307.977634)
			(xy 289.668315 -308.011726) (xy 289.627812 -308.039682) (xy 289.58335 -308.06078) (xy 289.536079 -308.074472)
			(xy 289.487224 -308.080404) (xy 289.438049 -308.078423) (xy 289.38983 -308.068579) (xy 289.343814 -308.051127)
			(xy 289.301193 -308.02652) (xy 289.263072 -307.995395) (xy 289.230437 -307.958558) (xy 289.204134 -307.916962)
			(xy 289.184843 -307.871686) (xy 289.173066 -307.823902) (xy 289.169106 -307.774848) (xy 288.830258 -307.774848)
			(xy 288.829763 -307.799455) (xy 288.821868 -307.848032) (xy 288.806284 -307.894713) (xy 288.783413 -307.93829)
			(xy 288.753848 -307.977634) (xy 288.718355 -308.011726) (xy 288.677852 -308.039682) (xy 288.63339 -308.06078)
			(xy 288.586119 -308.074472) (xy 288.537264 -308.080404) (xy 288.488089 -308.078423) (xy 288.43987 -308.068579)
			(xy 288.393854 -308.051127) (xy 288.351233 -308.02652) (xy 288.313112 -307.995395) (xy 288.280477 -307.958558)
			(xy 288.254174 -307.916962) (xy 288.234883 -307.871686) (xy 288.223106 -307.823902) (xy 288.219146 -307.774848)
			(xy 287.880044 -307.774848) (xy 287.879549 -307.799455) (xy 287.871654 -307.848032) (xy 287.85607 -307.894713)
			(xy 287.833199 -307.93829) (xy 287.803634 -307.977634) (xy 287.768141 -308.011726) (xy 287.727638 -308.039682)
			(xy 287.683176 -308.06078) (xy 287.635905 -308.074472) (xy 287.58705 -308.080404) (xy 287.537875 -308.078423)
			(xy 287.489656 -308.068579) (xy 287.44364 -308.051127) (xy 287.401019 -308.02652) (xy 287.362898 -307.995395)
			(xy 287.330263 -307.958558) (xy 287.30396 -307.916962) (xy 287.284669 -307.871686) (xy 287.272892 -307.823902)
			(xy 287.268932 -307.774848) (xy 286.930084 -307.774848) (xy 286.929589 -307.799455) (xy 286.921694 -307.848032)
			(xy 286.90611 -307.894713) (xy 286.883239 -307.93829) (xy 286.853674 -307.977634) (xy 286.818181 -308.011726)
			(xy 286.777678 -308.039682) (xy 286.733216 -308.06078) (xy 286.685945 -308.074472) (xy 286.63709 -308.080404)
			(xy 286.587915 -308.078423) (xy 286.539696 -308.068579) (xy 286.49368 -308.051127) (xy 286.451059 -308.02652)
			(xy 286.412938 -307.995395) (xy 286.380303 -307.958558) (xy 286.354 -307.916962) (xy 286.334709 -307.871686)
			(xy 286.322932 -307.823902) (xy 286.318972 -307.774848) (xy 285.980124 -307.774848) (xy 285.979629 -307.799455)
			(xy 285.971734 -307.848032) (xy 285.95615 -307.894713) (xy 285.933279 -307.93829) (xy 285.903714 -307.977634)
			(xy 285.868221 -308.011726) (xy 285.827718 -308.039682) (xy 285.783256 -308.06078) (xy 285.735985 -308.074472)
			(xy 285.68713 -308.080404) (xy 285.637955 -308.078423) (xy 285.589736 -308.068579) (xy 285.54372 -308.051127)
			(xy 285.501099 -308.02652) (xy 285.462978 -307.995395) (xy 285.430343 -307.958558) (xy 285.40404 -307.916962)
			(xy 285.384749 -307.871686) (xy 285.372972 -307.823902) (xy 285.369012 -307.774848) (xy 285.030164 -307.774848)
			(xy 285.029669 -307.799455) (xy 285.021774 -307.848032) (xy 285.00619 -307.894713) (xy 284.983319 -307.93829)
			(xy 284.953754 -307.977634) (xy 284.918261 -308.011726) (xy 284.877758 -308.039682) (xy 284.833296 -308.06078)
			(xy 284.786025 -308.074472) (xy 284.73717 -308.080404) (xy 284.687995 -308.078423) (xy 284.639776 -308.068579)
			(xy 284.59376 -308.051127) (xy 284.551139 -308.02652) (xy 284.513018 -307.995395) (xy 284.480383 -307.958558)
			(xy 284.45408 -307.916962) (xy 284.434789 -307.871686) (xy 284.423012 -307.823902) (xy 284.419052 -307.774848)
			(xy 284.080204 -307.774848) (xy 284.079709 -307.799455) (xy 284.071814 -307.848032) (xy 284.05623 -307.894713)
			(xy 284.033359 -307.93829) (xy 284.003794 -307.977634) (xy 283.968301 -308.011726) (xy 283.927798 -308.039682)
			(xy 283.883336 -308.06078) (xy 283.836065 -308.074472) (xy 283.78721 -308.080404) (xy 283.738035 -308.078423)
			(xy 283.689816 -308.068579) (xy 283.6438 -308.051127) (xy 283.601179 -308.02652) (xy 283.563058 -307.995395)
			(xy 283.530423 -307.958558) (xy 283.50412 -307.916962) (xy 283.484829 -307.871686) (xy 283.473052 -307.823902)
			(xy 283.469092 -307.774848) (xy 283.130244 -307.774848) (xy 283.129749 -307.799455) (xy 283.121854 -307.848032)
			(xy 283.10627 -307.894713) (xy 283.083399 -307.93829) (xy 283.053834 -307.977634) (xy 283.018341 -308.011726)
			(xy 282.977838 -308.039682) (xy 282.933376 -308.06078) (xy 282.886105 -308.074472) (xy 282.83725 -308.080404)
			(xy 282.788075 -308.078423) (xy 282.739856 -308.068579) (xy 282.69384 -308.051127) (xy 282.651219 -308.02652)
			(xy 282.613098 -307.995395) (xy 282.580463 -307.958558) (xy 282.55416 -307.916962) (xy 282.534869 -307.871686)
			(xy 282.523092 -307.823902) (xy 282.519132 -307.774848) (xy 282.219146 -307.774848) (xy 282.219146 -308.249828)
			(xy 305.793914 -308.249828) (xy 305.797874 -308.200774) (xy 305.809651 -308.15299) (xy 305.828942 -308.107714)
			(xy 305.855245 -308.066118) (xy 305.88788 -308.029281) (xy 305.926001 -307.998156) (xy 305.968622 -307.973549)
			(xy 306.014638 -307.956097) (xy 306.062857 -307.946253) (xy 306.112032 -307.944272) (xy 306.160887 -307.950204)
			(xy 306.208158 -307.963896) (xy 306.25262 -307.984994) (xy 306.293123 -308.01295) (xy 306.328616 -308.047042)
			(xy 306.358181 -308.086386) (xy 306.381052 -308.129963) (xy 306.396636 -308.176644) (xy 306.404531 -308.225221)
			(xy 306.405026 -308.249828) (xy 306.744128 -308.249828) (xy 306.748088 -308.200774) (xy 306.759865 -308.15299)
			(xy 306.779156 -308.107714) (xy 306.805459 -308.066118) (xy 306.838094 -308.029281) (xy 306.876215 -307.998156)
			(xy 306.918836 -307.973549) (xy 306.964852 -307.956097) (xy 307.013071 -307.946253) (xy 307.062246 -307.944272)
			(xy 307.111101 -307.950204) (xy 307.158372 -307.963896) (xy 307.202834 -307.984994) (xy 307.243337 -308.01295)
			(xy 307.27883 -308.047042) (xy 307.308395 -308.086386) (xy 307.331266 -308.129963) (xy 307.34685 -308.176644)
			(xy 307.354745 -308.225221) (xy 307.35524 -308.249828) (xy 307.694088 -308.249828) (xy 307.698048 -308.200774)
			(xy 307.709825 -308.15299) (xy 307.729116 -308.107714) (xy 307.755419 -308.066118) (xy 307.788054 -308.029281)
			(xy 307.826175 -307.998156) (xy 307.868796 -307.973549) (xy 307.914812 -307.956097) (xy 307.963031 -307.946253)
			(xy 308.012206 -307.944272) (xy 308.061061 -307.950204) (xy 308.108332 -307.963896) (xy 308.152794 -307.984994)
			(xy 308.193297 -308.01295) (xy 308.22879 -308.047042) (xy 308.258355 -308.086386) (xy 308.281226 -308.129963)
			(xy 308.29681 -308.176644) (xy 308.304705 -308.225221) (xy 308.3052 -308.249828) (xy 308.644048 -308.249828)
			(xy 308.648008 -308.200774) (xy 308.659785 -308.15299) (xy 308.679076 -308.107714) (xy 308.705379 -308.066118)
			(xy 308.738014 -308.029281) (xy 308.776135 -307.998156) (xy 308.818756 -307.973549) (xy 308.864772 -307.956097)
			(xy 308.912991 -307.946253) (xy 308.962166 -307.944272) (xy 309.011021 -307.950204) (xy 309.058292 -307.963896)
			(xy 309.102754 -307.984994) (xy 309.143257 -308.01295) (xy 309.17875 -308.047042) (xy 309.208315 -308.086386)
			(xy 309.231186 -308.129963) (xy 309.24677 -308.176644) (xy 309.254665 -308.225221) (xy 309.25516 -308.249828)
			(xy 309.594008 -308.249828) (xy 309.597968 -308.200774) (xy 309.609745 -308.15299) (xy 309.629036 -308.107714)
			(xy 309.655339 -308.066118) (xy 309.687974 -308.029281) (xy 309.726095 -307.998156) (xy 309.768716 -307.973549)
			(xy 309.814732 -307.956097) (xy 309.862951 -307.946253) (xy 309.912126 -307.944272) (xy 309.960981 -307.950204)
			(xy 310.008252 -307.963896) (xy 310.052714 -307.984994) (xy 310.093217 -308.01295) (xy 310.12871 -308.047042)
			(xy 310.158275 -308.086386) (xy 310.181146 -308.129963) (xy 310.19673 -308.176644) (xy 310.204625 -308.225221)
			(xy 310.20512 -308.249828) (xy 310.543968 -308.249828) (xy 310.547928 -308.200774) (xy 310.559705 -308.15299)
			(xy 310.578996 -308.107714) (xy 310.605299 -308.066118) (xy 310.637934 -308.029281) (xy 310.676055 -307.998156)
			(xy 310.718676 -307.973549) (xy 310.764692 -307.956097) (xy 310.812911 -307.946253) (xy 310.862086 -307.944272)
			(xy 310.910941 -307.950204) (xy 310.958212 -307.963896) (xy 311.002674 -307.984994) (xy 311.043177 -308.01295)
			(xy 311.07867 -308.047042) (xy 311.108235 -308.086386) (xy 311.131106 -308.129963) (xy 311.14669 -308.176644)
			(xy 311.154585 -308.225221) (xy 311.15508 -308.249828) (xy 311.493928 -308.249828) (xy 311.497888 -308.200774)
			(xy 311.509665 -308.15299) (xy 311.528956 -308.107714) (xy 311.555259 -308.066118) (xy 311.587894 -308.029281)
			(xy 311.626015 -307.998156) (xy 311.668636 -307.973549) (xy 311.714652 -307.956097) (xy 311.762871 -307.946253)
			(xy 311.812046 -307.944272) (xy 311.860901 -307.950204) (xy 311.908172 -307.963896) (xy 311.952634 -307.984994)
			(xy 311.993137 -308.01295) (xy 312.02863 -308.047042) (xy 312.058195 -308.086386) (xy 312.081066 -308.129963)
			(xy 312.09665 -308.176644) (xy 312.104545 -308.225221) (xy 312.10504 -308.249828) (xy 312.443888 -308.249828)
			(xy 312.447848 -308.200774) (xy 312.459625 -308.15299) (xy 312.478916 -308.107714) (xy 312.505219 -308.066118)
			(xy 312.537854 -308.029281) (xy 312.575975 -307.998156) (xy 312.618596 -307.973549) (xy 312.664612 -307.956097)
			(xy 312.712831 -307.946253) (xy 312.762006 -307.944272) (xy 312.810861 -307.950204) (xy 312.858132 -307.963896)
			(xy 312.902594 -307.984994) (xy 312.943097 -308.01295) (xy 312.97859 -308.047042) (xy 313.008155 -308.086386)
			(xy 313.031026 -308.129963) (xy 313.04661 -308.176644) (xy 313.054505 -308.225221) (xy 313.055 -308.249828)
			(xy 313.394102 -308.249828) (xy 313.398062 -308.200774) (xy 313.409839 -308.15299) (xy 313.42913 -308.107714)
			(xy 313.455433 -308.066118) (xy 313.488068 -308.029281) (xy 313.526189 -307.998156) (xy 313.56881 -307.973549)
			(xy 313.614826 -307.956097) (xy 313.663045 -307.946253) (xy 313.71222 -307.944272) (xy 313.761075 -307.950204)
			(xy 313.808346 -307.963896) (xy 313.852808 -307.984994) (xy 313.893311 -308.01295) (xy 313.928804 -308.047042)
			(xy 313.958369 -308.086386) (xy 313.98124 -308.129963) (xy 313.996824 -308.176644) (xy 314.004719 -308.225221)
			(xy 314.005214 -308.249828) (xy 314.344062 -308.249828) (xy 314.348022 -308.200774) (xy 314.359799 -308.15299)
			(xy 314.37909 -308.107714) (xy 314.405393 -308.066118) (xy 314.438028 -308.029281) (xy 314.476149 -307.998156)
			(xy 314.51877 -307.973549) (xy 314.564786 -307.956097) (xy 314.613005 -307.946253) (xy 314.66218 -307.944272)
			(xy 314.711035 -307.950204) (xy 314.758306 -307.963896) (xy 314.802768 -307.984994) (xy 314.843271 -308.01295)
			(xy 314.878764 -308.047042) (xy 314.908329 -308.086386) (xy 314.9312 -308.129963) (xy 314.946784 -308.176644)
			(xy 314.954679 -308.225221) (xy 314.955174 -308.249828) (xy 315.294276 -308.249828) (xy 315.298236 -308.200774)
			(xy 315.310013 -308.15299) (xy 315.329304 -308.107714) (xy 315.355607 -308.066118) (xy 315.388242 -308.029281)
			(xy 315.426363 -307.998156) (xy 315.468984 -307.973549) (xy 315.515 -307.956097) (xy 315.563219 -307.946253)
			(xy 315.612394 -307.944272) (xy 315.661249 -307.950204) (xy 315.70852 -307.963896) (xy 315.752982 -307.984994)
			(xy 315.793485 -308.01295) (xy 315.828978 -308.047042) (xy 315.858543 -308.086386) (xy 315.881414 -308.129963)
			(xy 315.896998 -308.176644) (xy 315.904893 -308.225221) (xy 315.905388 -308.249828) (xy 315.904893 -308.274435)
			(xy 315.896998 -308.323012) (xy 315.881414 -308.369693) (xy 315.858543 -308.41327) (xy 315.828978 -308.452614)
			(xy 315.793485 -308.486706) (xy 315.752982 -308.514662) (xy 315.70852 -308.53576) (xy 315.661249 -308.549452)
			(xy 315.612394 -308.555384) (xy 315.563219 -308.553403) (xy 315.515 -308.543559) (xy 315.468984 -308.526107)
			(xy 315.426363 -308.5015) (xy 315.388242 -308.470375) (xy 315.355607 -308.433538) (xy 315.329304 -308.391942)
			(xy 315.310013 -308.346666) (xy 315.298236 -308.298882) (xy 315.294276 -308.249828) (xy 314.955174 -308.249828)
			(xy 314.954679 -308.274435) (xy 314.946784 -308.323012) (xy 314.9312 -308.369693) (xy 314.908329 -308.41327)
			(xy 314.878764 -308.452614) (xy 314.843271 -308.486706) (xy 314.802768 -308.514662) (xy 314.758306 -308.53576)
			(xy 314.711035 -308.549452) (xy 314.66218 -308.555384) (xy 314.613005 -308.553403) (xy 314.564786 -308.543559)
			(xy 314.51877 -308.526107) (xy 314.476149 -308.5015) (xy 314.438028 -308.470375) (xy 314.405393 -308.433538)
			(xy 314.37909 -308.391942) (xy 314.359799 -308.346666) (xy 314.348022 -308.298882) (xy 314.344062 -308.249828)
			(xy 314.005214 -308.249828) (xy 314.004719 -308.274435) (xy 313.996824 -308.323012) (xy 313.98124 -308.369693)
			(xy 313.958369 -308.41327) (xy 313.928804 -308.452614) (xy 313.893311 -308.486706) (xy 313.852808 -308.514662)
			(xy 313.808346 -308.53576) (xy 313.761075 -308.549452) (xy 313.71222 -308.555384) (xy 313.663045 -308.553403)
			(xy 313.614826 -308.543559) (xy 313.56881 -308.526107) (xy 313.526189 -308.5015) (xy 313.488068 -308.470375)
			(xy 313.455433 -308.433538) (xy 313.42913 -308.391942) (xy 313.409839 -308.346666) (xy 313.398062 -308.298882)
			(xy 313.394102 -308.249828) (xy 313.055 -308.249828) (xy 313.054505 -308.274435) (xy 313.04661 -308.323012)
			(xy 313.031026 -308.369693) (xy 313.008155 -308.41327) (xy 312.97859 -308.452614) (xy 312.943097 -308.486706)
			(xy 312.902594 -308.514662) (xy 312.858132 -308.53576) (xy 312.810861 -308.549452) (xy 312.762006 -308.555384)
			(xy 312.712831 -308.553403) (xy 312.664612 -308.543559) (xy 312.618596 -308.526107) (xy 312.575975 -308.5015)
			(xy 312.537854 -308.470375) (xy 312.505219 -308.433538) (xy 312.478916 -308.391942) (xy 312.459625 -308.346666)
			(xy 312.447848 -308.298882) (xy 312.443888 -308.249828) (xy 312.10504 -308.249828) (xy 312.104545 -308.274435)
			(xy 312.09665 -308.323012) (xy 312.081066 -308.369693) (xy 312.058195 -308.41327) (xy 312.02863 -308.452614)
			(xy 311.993137 -308.486706) (xy 311.952634 -308.514662) (xy 311.908172 -308.53576) (xy 311.860901 -308.549452)
			(xy 311.812046 -308.555384) (xy 311.762871 -308.553403) (xy 311.714652 -308.543559) (xy 311.668636 -308.526107)
			(xy 311.626015 -308.5015) (xy 311.587894 -308.470375) (xy 311.555259 -308.433538) (xy 311.528956 -308.391942)
			(xy 311.509665 -308.346666) (xy 311.497888 -308.298882) (xy 311.493928 -308.249828) (xy 311.15508 -308.249828)
			(xy 311.154585 -308.274435) (xy 311.14669 -308.323012) (xy 311.131106 -308.369693) (xy 311.108235 -308.41327)
			(xy 311.07867 -308.452614) (xy 311.043177 -308.486706) (xy 311.002674 -308.514662) (xy 310.958212 -308.53576)
			(xy 310.910941 -308.549452) (xy 310.862086 -308.555384) (xy 310.812911 -308.553403) (xy 310.764692 -308.543559)
			(xy 310.718676 -308.526107) (xy 310.676055 -308.5015) (xy 310.637934 -308.470375) (xy 310.605299 -308.433538)
			(xy 310.578996 -308.391942) (xy 310.559705 -308.346666) (xy 310.547928 -308.298882) (xy 310.543968 -308.249828)
			(xy 310.20512 -308.249828) (xy 310.204625 -308.274435) (xy 310.19673 -308.323012) (xy 310.181146 -308.369693)
			(xy 310.158275 -308.41327) (xy 310.12871 -308.452614) (xy 310.093217 -308.486706) (xy 310.052714 -308.514662)
			(xy 310.008252 -308.53576) (xy 309.960981 -308.549452) (xy 309.912126 -308.555384) (xy 309.862951 -308.553403)
			(xy 309.814732 -308.543559) (xy 309.768716 -308.526107) (xy 309.726095 -308.5015) (xy 309.687974 -308.470375)
			(xy 309.655339 -308.433538) (xy 309.629036 -308.391942) (xy 309.609745 -308.346666) (xy 309.597968 -308.298882)
			(xy 309.594008 -308.249828) (xy 309.25516 -308.249828) (xy 309.254665 -308.274435) (xy 309.24677 -308.323012)
			(xy 309.231186 -308.369693) (xy 309.208315 -308.41327) (xy 309.17875 -308.452614) (xy 309.143257 -308.486706)
			(xy 309.102754 -308.514662) (xy 309.058292 -308.53576) (xy 309.011021 -308.549452) (xy 308.962166 -308.555384)
			(xy 308.912991 -308.553403) (xy 308.864772 -308.543559) (xy 308.818756 -308.526107) (xy 308.776135 -308.5015)
			(xy 308.738014 -308.470375) (xy 308.705379 -308.433538) (xy 308.679076 -308.391942) (xy 308.659785 -308.346666)
			(xy 308.648008 -308.298882) (xy 308.644048 -308.249828) (xy 308.3052 -308.249828) (xy 308.304705 -308.274435)
			(xy 308.29681 -308.323012) (xy 308.281226 -308.369693) (xy 308.258355 -308.41327) (xy 308.22879 -308.452614)
			(xy 308.193297 -308.486706) (xy 308.152794 -308.514662) (xy 308.108332 -308.53576) (xy 308.061061 -308.549452)
			(xy 308.012206 -308.555384) (xy 307.963031 -308.553403) (xy 307.914812 -308.543559) (xy 307.868796 -308.526107)
			(xy 307.826175 -308.5015) (xy 307.788054 -308.470375) (xy 307.755419 -308.433538) (xy 307.729116 -308.391942)
			(xy 307.709825 -308.346666) (xy 307.698048 -308.298882) (xy 307.694088 -308.249828) (xy 307.35524 -308.249828)
			(xy 307.354745 -308.274435) (xy 307.34685 -308.323012) (xy 307.331266 -308.369693) (xy 307.308395 -308.41327)
			(xy 307.27883 -308.452614) (xy 307.243337 -308.486706) (xy 307.202834 -308.514662) (xy 307.158372 -308.53576)
			(xy 307.111101 -308.549452) (xy 307.062246 -308.555384) (xy 307.013071 -308.553403) (xy 306.964852 -308.543559)
			(xy 306.918836 -308.526107) (xy 306.876215 -308.5015) (xy 306.838094 -308.470375) (xy 306.805459 -308.433538)
			(xy 306.779156 -308.391942) (xy 306.759865 -308.346666) (xy 306.748088 -308.298882) (xy 306.744128 -308.249828)
			(xy 306.405026 -308.249828) (xy 306.404531 -308.274435) (xy 306.396636 -308.323012) (xy 306.381052 -308.369693)
			(xy 306.358181 -308.41327) (xy 306.328616 -308.452614) (xy 306.293123 -308.486706) (xy 306.25262 -308.514662)
			(xy 306.208158 -308.53576) (xy 306.160887 -308.549452) (xy 306.112032 -308.555384) (xy 306.062857 -308.553403)
			(xy 306.014638 -308.543559) (xy 305.968622 -308.526107) (xy 305.926001 -308.5015) (xy 305.88788 -308.470375)
			(xy 305.855245 -308.433538) (xy 305.828942 -308.391942) (xy 305.809651 -308.346666) (xy 305.797874 -308.298882)
			(xy 305.793914 -308.249828) (xy 282.219146 -308.249828) (xy 282.219146 -308.793896) (xy 282.219702 -308.804346)
			(xy 282.228088 -308.823496) (xy 282.235402 -308.83098) (xy 282.297632 -308.889146) (xy 282.317444 -308.896004)
			(xy 282.327858 -308.895242) (xy 282.349702 -308.89448) (xy 282.374958 -308.895002) (xy 282.424782 -308.903316)
			(xy 282.472557 -308.919718) (xy 282.516981 -308.943759) (xy 282.556843 -308.974785) (xy 282.591054 -309.011948)
			(xy 282.618681 -309.054235) (xy 282.638972 -309.100493) (xy 282.651372 -309.14946) (xy 282.654856 -309.191511)
			(xy 282.994169 -309.191511) (xy 282.999538 -309.142158) (xy 283.012821 -309.094323) (xy 283.033667 -309.049267)
			(xy 283.061529 -309.008178) (xy 283.09567 -308.972137) (xy 283.135193 -308.942095) (xy 283.179056 -308.918843)
			(xy 283.226103 -308.902994) (xy 283.275094 -308.894965) (xy 283.299916 -308.89448) (xy 283.314099 -308.894655)
			(xy 283.342339 -308.897328) (xy 283.356304 -308.899814) (xy 283.370269 -308.901986) (xy 283.398402 -308.899406)
			(xy 283.42475 -308.889215) (xy 283.447298 -308.872193) (xy 283.464318 -308.849645) (xy 283.474507 -308.823295)
			(xy 283.477085 -308.795162) (xy 283.474922 -308.781196) (xy 283.472449 -308.76723) (xy 283.469775 -308.73899)
			(xy 283.469588 -308.724808) (xy 283.470069 -308.699986) (xy 283.478099 -308.650997) (xy 283.49395 -308.603952)
			(xy 283.517202 -308.56009) (xy 283.547244 -308.520569) (xy 283.583284 -308.486429) (xy 283.624373 -308.458569)
			(xy 283.669428 -308.437723) (xy 283.717262 -308.424441) (xy 283.766614 -308.419073) (xy 283.816185 -308.42176)
			(xy 283.864668 -308.432432) (xy 283.910785 -308.450806) (xy 283.953323 -308.4764) (xy 283.991159 -308.508538)
			(xy 284.023298 -308.546374) (xy 284.048892 -308.588911) (xy 284.067267 -308.635029) (xy 284.077939 -308.683511)
			(xy 284.080178 -308.724808) (xy 284.419052 -308.724808) (xy 284.423012 -308.675754) (xy 284.434789 -308.62797)
			(xy 284.45408 -308.582694) (xy 284.480383 -308.541098) (xy 284.513018 -308.504261) (xy 284.551139 -308.473136)
			(xy 284.59376 -308.448529) (xy 284.639776 -308.431077) (xy 284.687995 -308.421233) (xy 284.73717 -308.419252)
			(xy 284.786025 -308.425184) (xy 284.833296 -308.438876) (xy 284.877758 -308.459974) (xy 284.918261 -308.48793)
			(xy 284.953754 -308.522022) (xy 284.983319 -308.561366) (xy 285.00619 -308.604943) (xy 285.021774 -308.651624)
			(xy 285.029669 -308.700201) (xy 285.030164 -308.724808) (xy 285.369012 -308.724808) (xy 285.372972 -308.675754)
			(xy 285.384749 -308.62797) (xy 285.40404 -308.582694) (xy 285.430343 -308.541098) (xy 285.462978 -308.504261)
			(xy 285.501099 -308.473136) (xy 285.54372 -308.448529) (xy 285.589736 -308.431077) (xy 285.637955 -308.421233)
			(xy 285.68713 -308.419252) (xy 285.735985 -308.425184) (xy 285.783256 -308.438876) (xy 285.827718 -308.459974)
			(xy 285.868221 -308.48793) (xy 285.903714 -308.522022) (xy 285.933279 -308.561366) (xy 285.95615 -308.604943)
			(xy 285.971734 -308.651624) (xy 285.979629 -308.700201) (xy 285.980124 -308.724808) (xy 286.318972 -308.724808)
			(xy 286.322932 -308.675754) (xy 286.334709 -308.62797) (xy 286.354 -308.582694) (xy 286.380303 -308.541098)
			(xy 286.412938 -308.504261) (xy 286.451059 -308.473136) (xy 286.49368 -308.448529) (xy 286.539696 -308.431077)
			(xy 286.587915 -308.421233) (xy 286.63709 -308.419252) (xy 286.685945 -308.425184) (xy 286.733216 -308.438876)
			(xy 286.777678 -308.459974) (xy 286.818181 -308.48793) (xy 286.853674 -308.522022) (xy 286.883239 -308.561366)
			(xy 286.90611 -308.604943) (xy 286.921694 -308.651624) (xy 286.929589 -308.700201) (xy 286.930084 -308.724808)
			(xy 286.929917 -308.733104) (xy 287.268946 -308.733104) (xy 287.27163 -308.683528) (xy 287.2823 -308.635039)
			(xy 287.300675 -308.588915) (xy 287.326269 -308.546371) (xy 287.358409 -308.508529) (xy 287.396249 -308.476386)
			(xy 287.43879 -308.450787) (xy 287.484912 -308.432409) (xy 287.5334 -308.421734) (xy 287.582976 -308.419045)
			(xy 287.632334 -308.424412) (xy 287.680174 -308.437694) (xy 287.725234 -308.458541) (xy 287.766328 -308.486403)
			(xy 287.802373 -308.520547) (xy 287.83242 -308.560072) (xy 287.855675 -308.603938) (xy 287.871527 -308.650988)
			(xy 287.879559 -308.699983) (xy 287.880044 -308.724808) (xy 287.879868 -308.738991) (xy 287.877195 -308.767231)
			(xy 287.87471 -308.781196) (xy 287.872424 -308.793642) (xy 287.87979 -308.817264) (xy 287.95726 -308.894734)
			(xy 287.980882 -308.9021) (xy 287.993328 -308.899814) (xy 288.007294 -308.897338) (xy 288.035533 -308.894666)
			(xy 288.049716 -308.89448) (xy 288.063963 -308.894645) (xy 288.092331 -308.897316) (xy 288.106358 -308.899814)
			(xy 288.11855 -308.9021) (xy 288.14268 -308.894734) (xy 288.219896 -308.817518) (xy 288.227262 -308.793642)
			(xy 288.224976 -308.781196) (xy 288.222503 -308.76723) (xy 288.219829 -308.73899) (xy 288.219642 -308.724808)
			(xy 288.220069 -308.699987) (xy 288.228099 -308.650999) (xy 288.243948 -308.603956) (xy 288.267198 -308.560096)
			(xy 288.297238 -308.520575) (xy 288.333276 -308.486435) (xy 288.374363 -308.458575) (xy 288.419415 -308.437728)
			(xy 288.467246 -308.424444) (xy 288.516596 -308.419074) (xy 288.566165 -308.421758) (xy 288.614647 -308.432425)
			(xy 288.660764 -308.450796) (xy 288.703302 -308.476385) (xy 288.74114 -308.508519) (xy 288.773281 -308.54635)
			(xy 288.798878 -308.588884) (xy 288.817258 -308.634997) (xy 288.827935 -308.683477) (xy 288.83018 -308.724808)
			(xy 290.119066 -308.724808) (xy 290.123026 -308.675754) (xy 290.134803 -308.62797) (xy 290.154094 -308.582694)
			(xy 290.180397 -308.541098) (xy 290.213032 -308.504261) (xy 290.251153 -308.473136) (xy 290.293774 -308.448529)
			(xy 290.33979 -308.431077) (xy 290.388009 -308.421233) (xy 290.437184 -308.419252) (xy 290.486039 -308.425184)
			(xy 290.53331 -308.438876) (xy 290.577772 -308.459974) (xy 290.618275 -308.48793) (xy 290.653768 -308.522022)
			(xy 290.683333 -308.561366) (xy 290.706204 -308.604943) (xy 290.721788 -308.651624) (xy 290.729683 -308.700201)
			(xy 290.730178 -308.724808) (xy 290.730012 -308.733072) (xy 292.019091 -308.733072) (xy 292.02178 -308.683505)
			(xy 292.032452 -308.635026) (xy 292.050828 -308.588912) (xy 292.076421 -308.546378) (xy 292.108558 -308.508546)
			(xy 292.146393 -308.47641) (xy 292.188928 -308.45082) (xy 292.235043 -308.432447) (xy 292.283523 -308.421777)
			(xy 292.33309 -308.419091) (xy 292.382439 -308.42446) (xy 292.430269 -308.437741) (xy 292.475321 -308.458586)
			(xy 292.516406 -308.486444) (xy 292.552444 -308.520583) (xy 292.582484 -308.560102) (xy 292.605734 -308.60396)
			(xy 292.621583 -308.651002) (xy 292.629613 -308.699988) (xy 292.630098 -308.724808) (xy 292.629923 -308.738991)
			(xy 292.62725 -308.767231) (xy 292.624764 -308.781196) (xy 292.622478 -308.793642) (xy 292.629844 -308.817264)
			(xy 292.707314 -308.894734) (xy 292.730936 -308.9021) (xy 292.743382 -308.899814) (xy 292.757347 -308.89733)
			(xy 292.785587 -308.894663) (xy 292.79977 -308.89448) (xy 292.813953 -308.894661) (xy 292.842193 -308.89733)
			(xy 292.856158 -308.899814) (xy 292.868604 -308.9021) (xy 292.892226 -308.894734) (xy 292.969696 -308.817264)
			(xy 292.977062 -308.793642) (xy 292.974776 -308.781196) (xy 292.972303 -308.76723) (xy 292.969629 -308.73899)
			(xy 292.969442 -308.724808) (xy 292.969964 -308.699553) (xy 292.978277 -308.649731) (xy 292.994678 -308.601957)
			(xy 293.018719 -308.557534) (xy 293.049743 -308.517674) (xy 293.086905 -308.483464) (xy 293.129191 -308.455838)
			(xy 293.175447 -308.435548) (xy 293.224412 -308.423148) (xy 293.27475 -308.418977) (xy 293.325088 -308.423148)
			(xy 293.374053 -308.435548) (xy 293.420309 -308.455838) (xy 293.462595 -308.483464) (xy 293.499757 -308.517674)
			(xy 293.530781 -308.557534) (xy 293.554822 -308.601957) (xy 293.571223 -308.649731) (xy 293.579536 -308.699553)
			(xy 293.580058 -308.724808) (xy 293.579883 -308.738991) (xy 293.57721 -308.767231) (xy 293.574724 -308.781196)
			(xy 293.572438 -308.793642) (xy 293.579804 -308.817264) (xy 293.657274 -308.894734) (xy 293.680896 -308.9021)
			(xy 293.693342 -308.899814) (xy 293.707308 -308.897336) (xy 293.735547 -308.894665) (xy 293.74973 -308.89448)
			(xy 293.763913 -308.894653) (xy 293.792153 -308.897327) (xy 293.806118 -308.899814) (xy 293.818564 -308.9021)
			(xy 293.842186 -308.894734) (xy 293.919656 -308.817264) (xy 293.927022 -308.793642) (xy 293.924736 -308.781196)
			(xy 293.922263 -308.76723) (xy 293.919589 -308.73899) (xy 293.919402 -308.724808) (xy 293.919869 -308.699987)
			(xy 293.927899 -308.650997) (xy 293.943749 -308.603953) (xy 293.967001 -308.560092) (xy 293.997043 -308.520571)
			(xy 294.033082 -308.48643) (xy 294.07417 -308.45857) (xy 294.119225 -308.437724) (xy 294.167058 -308.424442)
			(xy 294.216409 -308.419073) (xy 294.26598 -308.42176) (xy 294.314462 -308.43243) (xy 294.36058 -308.450803)
			(xy 294.403118 -308.476396) (xy 294.440954 -308.508533) (xy 294.473094 -308.546368) (xy 294.498689 -308.588904)
			(xy 294.517065 -308.635021) (xy 294.527738 -308.683503) (xy 294.529965 -308.724554) (xy 294.868866 -308.724554)
			(xy 294.872826 -308.6755) (xy 294.884603 -308.627716) (xy 294.903894 -308.58244) (xy 294.930197 -308.540844)
			(xy 294.962832 -308.504007) (xy 295.000953 -308.472882) (xy 295.043574 -308.448275) (xy 295.08959 -308.430823)
			(xy 295.137809 -308.420979) (xy 295.186984 -308.418998) (xy 295.235839 -308.42493) (xy 295.28311 -308.438622)
			(xy 295.327572 -308.45972) (xy 295.368075 -308.487676) (xy 295.403568 -308.521768) (xy 295.433133 -308.561112)
			(xy 295.456004 -308.604689) (xy 295.471588 -308.65137) (xy 295.479483 -308.699947) (xy 295.479978 -308.724554)
			(xy 295.479973 -308.724808) (xy 295.81908 -308.724808) (xy 295.82304 -308.675754) (xy 295.834817 -308.62797)
			(xy 295.854108 -308.582694) (xy 295.880411 -308.541098) (xy 295.913046 -308.504261) (xy 295.951167 -308.473136)
			(xy 295.993788 -308.448529) (xy 296.039804 -308.431077) (xy 296.088023 -308.421233) (xy 296.137198 -308.419252)
			(xy 296.186053 -308.425184) (xy 296.233324 -308.438876) (xy 296.277786 -308.459974) (xy 296.318289 -308.48793)
			(xy 296.353782 -308.522022) (xy 296.383347 -308.561366) (xy 296.406218 -308.604943) (xy 296.421802 -308.651624)
			(xy 296.429697 -308.700201) (xy 296.430192 -308.724808) (xy 296.76904 -308.724808) (xy 296.773 -308.675754)
			(xy 296.784777 -308.62797) (xy 296.804068 -308.582694) (xy 296.830371 -308.541098) (xy 296.863006 -308.504261)
			(xy 296.901127 -308.473136) (xy 296.943748 -308.448529) (xy 296.989764 -308.431077) (xy 297.037983 -308.421233)
			(xy 297.087158 -308.419252) (xy 297.136013 -308.425184) (xy 297.183284 -308.438876) (xy 297.227746 -308.459974)
			(xy 297.268249 -308.48793) (xy 297.303742 -308.522022) (xy 297.333307 -308.561366) (xy 297.356178 -308.604943)
			(xy 297.371762 -308.651624) (xy 297.379657 -308.700201) (xy 297.380152 -308.724808) (xy 297.719 -308.724808)
			(xy 297.72296 -308.675754) (xy 297.734737 -308.62797) (xy 297.754028 -308.582694) (xy 297.780331 -308.541098)
			(xy 297.812966 -308.504261) (xy 297.851087 -308.473136) (xy 297.893708 -308.448529) (xy 297.939724 -308.431077)
			(xy 297.987943 -308.421233) (xy 298.037118 -308.419252) (xy 298.085973 -308.425184) (xy 298.133244 -308.438876)
			(xy 298.177706 -308.459974) (xy 298.218209 -308.48793) (xy 298.253702 -308.522022) (xy 298.283267 -308.561366)
			(xy 298.306138 -308.604943) (xy 298.321722 -308.651624) (xy 298.329617 -308.700201) (xy 298.330112 -308.724808)
			(xy 298.66896 -308.724808) (xy 298.67292 -308.675754) (xy 298.684697 -308.62797) (xy 298.703988 -308.582694)
			(xy 298.730291 -308.541098) (xy 298.762926 -308.504261) (xy 298.801047 -308.473136) (xy 298.843668 -308.448529)
			(xy 298.889684 -308.431077) (xy 298.937903 -308.421233) (xy 298.987078 -308.419252) (xy 299.035933 -308.425184)
			(xy 299.083204 -308.438876) (xy 299.127666 -308.459974) (xy 299.168169 -308.48793) (xy 299.203662 -308.522022)
			(xy 299.233227 -308.561366) (xy 299.256098 -308.604943) (xy 299.271682 -308.651624) (xy 299.279577 -308.700201)
			(xy 299.280072 -308.724808) (xy 299.61892 -308.724808) (xy 299.62288 -308.675754) (xy 299.634657 -308.62797)
			(xy 299.653948 -308.582694) (xy 299.680251 -308.541098) (xy 299.712886 -308.504261) (xy 299.751007 -308.473136)
			(xy 299.793628 -308.448529) (xy 299.839644 -308.431077) (xy 299.887863 -308.421233) (xy 299.937038 -308.419252)
			(xy 299.985893 -308.425184) (xy 300.033164 -308.438876) (xy 300.077626 -308.459974) (xy 300.118129 -308.48793)
			(xy 300.153622 -308.522022) (xy 300.183187 -308.561366) (xy 300.206058 -308.604943) (xy 300.221642 -308.651624)
			(xy 300.229537 -308.700201) (xy 300.230032 -308.724808) (xy 300.569134 -308.724808) (xy 300.573094 -308.675754)
			(xy 300.584871 -308.62797) (xy 300.604162 -308.582694) (xy 300.630465 -308.541098) (xy 300.6631 -308.504261)
			(xy 300.701221 -308.473136) (xy 300.743842 -308.448529) (xy 300.789858 -308.431077) (xy 300.838077 -308.421233)
			(xy 300.887252 -308.419252) (xy 300.936107 -308.425184) (xy 300.983378 -308.438876) (xy 301.02784 -308.459974)
			(xy 301.068343 -308.48793) (xy 301.103836 -308.522022) (xy 301.133401 -308.561366) (xy 301.156272 -308.604943)
			(xy 301.171856 -308.651624) (xy 301.179751 -308.700201) (xy 301.180246 -308.724808) (xy 301.519094 -308.724808)
			(xy 301.523054 -308.675754) (xy 301.534831 -308.62797) (xy 301.554122 -308.582694) (xy 301.580425 -308.541098)
			(xy 301.61306 -308.504261) (xy 301.651181 -308.473136) (xy 301.693802 -308.448529) (xy 301.739818 -308.431077)
			(xy 301.788037 -308.421233) (xy 301.837212 -308.419252) (xy 301.886067 -308.425184) (xy 301.933338 -308.438876)
			(xy 301.9778 -308.459974) (xy 302.018303 -308.48793) (xy 302.053796 -308.522022) (xy 302.083361 -308.561366)
			(xy 302.106232 -308.604943) (xy 302.121816 -308.651624) (xy 302.129711 -308.700201) (xy 302.130206 -308.724808)
			(xy 302.469054 -308.724808) (xy 302.473014 -308.675754) (xy 302.484791 -308.62797) (xy 302.504082 -308.582694)
			(xy 302.530385 -308.541098) (xy 302.56302 -308.504261) (xy 302.601141 -308.473136) (xy 302.643762 -308.448529)
			(xy 302.689778 -308.431077) (xy 302.737997 -308.421233) (xy 302.787172 -308.419252) (xy 302.836027 -308.425184)
			(xy 302.883298 -308.438876) (xy 302.92776 -308.459974) (xy 302.968263 -308.48793) (xy 303.003756 -308.522022)
			(xy 303.033321 -308.561366) (xy 303.056192 -308.604943) (xy 303.071776 -308.651624) (xy 303.079671 -308.700201)
			(xy 303.080166 -308.724808) (xy 303.419014 -308.724808) (xy 303.422974 -308.675754) (xy 303.434751 -308.62797)
			(xy 303.454042 -308.582694) (xy 303.480345 -308.541098) (xy 303.51298 -308.504261) (xy 303.551101 -308.473136)
			(xy 303.593722 -308.448529) (xy 303.639738 -308.431077) (xy 303.687957 -308.421233) (xy 303.737132 -308.419252)
			(xy 303.785987 -308.425184) (xy 303.833258 -308.438876) (xy 303.87772 -308.459974) (xy 303.918223 -308.48793)
			(xy 303.953716 -308.522022) (xy 303.983281 -308.561366) (xy 304.006152 -308.604943) (xy 304.021736 -308.651624)
			(xy 304.029631 -308.700201) (xy 304.030126 -308.724808) (xy 304.368974 -308.724808) (xy 304.372934 -308.675754)
			(xy 304.384711 -308.62797) (xy 304.404002 -308.582694) (xy 304.430305 -308.541098) (xy 304.46294 -308.504261)
			(xy 304.501061 -308.473136) (xy 304.543682 -308.448529) (xy 304.589698 -308.431077) (xy 304.637917 -308.421233)
			(xy 304.687092 -308.419252) (xy 304.735947 -308.425184) (xy 304.783218 -308.438876) (xy 304.82768 -308.459974)
			(xy 304.868183 -308.48793) (xy 304.903676 -308.522022) (xy 304.933241 -308.561366) (xy 304.956112 -308.604943)
			(xy 304.971696 -308.651624) (xy 304.979591 -308.700201) (xy 304.980086 -308.724808) (xy 304.979591 -308.749415)
			(xy 304.971696 -308.797992) (xy 304.956112 -308.844673) (xy 304.933241 -308.88825) (xy 304.903676 -308.927594)
			(xy 304.868183 -308.961686) (xy 304.82768 -308.989642) (xy 304.783218 -309.01074) (xy 304.735947 -309.024432)
			(xy 304.687092 -309.030364) (xy 304.637917 -309.028383) (xy 304.589698 -309.018539) (xy 304.543682 -309.001087)
			(xy 304.501061 -308.97648) (xy 304.46294 -308.945355) (xy 304.430305 -308.908518) (xy 304.404002 -308.866922)
			(xy 304.384711 -308.821646) (xy 304.372934 -308.773862) (xy 304.368974 -308.724808) (xy 304.030126 -308.724808)
			(xy 304.029631 -308.749415) (xy 304.021736 -308.797992) (xy 304.006152 -308.844673) (xy 303.983281 -308.88825)
			(xy 303.953716 -308.927594) (xy 303.918223 -308.961686) (xy 303.87772 -308.989642) (xy 303.833258 -309.01074)
			(xy 303.785987 -309.024432) (xy 303.737132 -309.030364) (xy 303.687957 -309.028383) (xy 303.639738 -309.018539)
			(xy 303.593722 -309.001087) (xy 303.551101 -308.97648) (xy 303.51298 -308.945355) (xy 303.480345 -308.908518)
			(xy 303.454042 -308.866922) (xy 303.434751 -308.821646) (xy 303.422974 -308.773862) (xy 303.419014 -308.724808)
			(xy 303.080166 -308.724808) (xy 303.079671 -308.749415) (xy 303.071776 -308.797992) (xy 303.056192 -308.844673)
			(xy 303.033321 -308.88825) (xy 303.003756 -308.927594) (xy 302.968263 -308.961686) (xy 302.92776 -308.989642)
			(xy 302.883298 -309.01074) (xy 302.836027 -309.024432) (xy 302.787172 -309.030364) (xy 302.737997 -309.028383)
			(xy 302.689778 -309.018539) (xy 302.643762 -309.001087) (xy 302.601141 -308.97648) (xy 302.56302 -308.945355)
			(xy 302.530385 -308.908518) (xy 302.504082 -308.866922) (xy 302.484791 -308.821646) (xy 302.473014 -308.773862)
			(xy 302.469054 -308.724808) (xy 302.130206 -308.724808) (xy 302.129711 -308.749415) (xy 302.121816 -308.797992)
			(xy 302.106232 -308.844673) (xy 302.083361 -308.88825) (xy 302.053796 -308.927594) (xy 302.018303 -308.961686)
			(xy 301.9778 -308.989642) (xy 301.933338 -309.01074) (xy 301.886067 -309.024432) (xy 301.837212 -309.030364)
			(xy 301.788037 -309.028383) (xy 301.739818 -309.018539) (xy 301.693802 -309.001087) (xy 301.651181 -308.97648)
			(xy 301.61306 -308.945355) (xy 301.580425 -308.908518) (xy 301.554122 -308.866922) (xy 301.534831 -308.821646)
			(xy 301.523054 -308.773862) (xy 301.519094 -308.724808) (xy 301.180246 -308.724808) (xy 301.179751 -308.749415)
			(xy 301.171856 -308.797992) (xy 301.156272 -308.844673) (xy 301.133401 -308.88825) (xy 301.103836 -308.927594)
			(xy 301.068343 -308.961686) (xy 301.02784 -308.989642) (xy 300.983378 -309.01074) (xy 300.936107 -309.024432)
			(xy 300.887252 -309.030364) (xy 300.838077 -309.028383) (xy 300.789858 -309.018539) (xy 300.743842 -309.001087)
			(xy 300.701221 -308.97648) (xy 300.6631 -308.945355) (xy 300.630465 -308.908518) (xy 300.604162 -308.866922)
			(xy 300.584871 -308.821646) (xy 300.573094 -308.773862) (xy 300.569134 -308.724808) (xy 300.230032 -308.724808)
			(xy 300.229537 -308.749415) (xy 300.221642 -308.797992) (xy 300.206058 -308.844673) (xy 300.183187 -308.88825)
			(xy 300.153622 -308.927594) (xy 300.118129 -308.961686) (xy 300.077626 -308.989642) (xy 300.033164 -309.01074)
			(xy 299.985893 -309.024432) (xy 299.937038 -309.030364) (xy 299.887863 -309.028383) (xy 299.839644 -309.018539)
			(xy 299.793628 -309.001087) (xy 299.751007 -308.97648) (xy 299.712886 -308.945355) (xy 299.680251 -308.908518)
			(xy 299.653948 -308.866922) (xy 299.634657 -308.821646) (xy 299.62288 -308.773862) (xy 299.61892 -308.724808)
			(xy 299.280072 -308.724808) (xy 299.279577 -308.749415) (xy 299.271682 -308.797992) (xy 299.256098 -308.844673)
			(xy 299.233227 -308.88825) (xy 299.203662 -308.927594) (xy 299.168169 -308.961686) (xy 299.127666 -308.989642)
			(xy 299.083204 -309.01074) (xy 299.035933 -309.024432) (xy 298.987078 -309.030364) (xy 298.937903 -309.028383)
			(xy 298.889684 -309.018539) (xy 298.843668 -309.001087) (xy 298.801047 -308.97648) (xy 298.762926 -308.945355)
			(xy 298.730291 -308.908518) (xy 298.703988 -308.866922) (xy 298.684697 -308.821646) (xy 298.67292 -308.773862)
			(xy 298.66896 -308.724808) (xy 298.330112 -308.724808) (xy 298.329617 -308.749415) (xy 298.321722 -308.797992)
			(xy 298.306138 -308.844673) (xy 298.283267 -308.88825) (xy 298.253702 -308.927594) (xy 298.218209 -308.961686)
			(xy 298.177706 -308.989642) (xy 298.133244 -309.01074) (xy 298.085973 -309.024432) (xy 298.037118 -309.030364)
			(xy 297.987943 -309.028383) (xy 297.939724 -309.018539) (xy 297.893708 -309.001087) (xy 297.851087 -308.97648)
			(xy 297.812966 -308.945355) (xy 297.780331 -308.908518) (xy 297.754028 -308.866922) (xy 297.734737 -308.821646)
			(xy 297.72296 -308.773862) (xy 297.719 -308.724808) (xy 297.380152 -308.724808) (xy 297.379657 -308.749415)
			(xy 297.371762 -308.797992) (xy 297.356178 -308.844673) (xy 297.333307 -308.88825) (xy 297.303742 -308.927594)
			(xy 297.268249 -308.961686) (xy 297.227746 -308.989642) (xy 297.183284 -309.01074) (xy 297.136013 -309.024432)
			(xy 297.087158 -309.030364) (xy 297.037983 -309.028383) (xy 296.989764 -309.018539) (xy 296.943748 -309.001087)
			(xy 296.901127 -308.97648) (xy 296.863006 -308.945355) (xy 296.830371 -308.908518) (xy 296.804068 -308.866922)
			(xy 296.784777 -308.821646) (xy 296.773 -308.773862) (xy 296.76904 -308.724808) (xy 296.430192 -308.724808)
			(xy 296.429697 -308.749415) (xy 296.421802 -308.797992) (xy 296.406218 -308.844673) (xy 296.383347 -308.88825)
			(xy 296.353782 -308.927594) (xy 296.318289 -308.961686) (xy 296.277786 -308.989642) (xy 296.233324 -309.01074)
			(xy 296.186053 -309.024432) (xy 296.137198 -309.030364) (xy 296.088023 -309.028383) (xy 296.039804 -309.018539)
			(xy 295.993788 -309.001087) (xy 295.951167 -308.97648) (xy 295.913046 -308.945355) (xy 295.880411 -308.908518)
			(xy 295.854108 -308.866922) (xy 295.834817 -308.821646) (xy 295.82304 -308.773862) (xy 295.81908 -308.724808)
			(xy 295.479973 -308.724808) (xy 295.479483 -308.749161) (xy 295.471588 -308.797738) (xy 295.456004 -308.844419)
			(xy 295.433133 -308.887996) (xy 295.403568 -308.92734) (xy 295.368075 -308.961432) (xy 295.327572 -308.989388)
			(xy 295.28311 -309.010486) (xy 295.235839 -309.024178) (xy 295.186984 -309.03011) (xy 295.137809 -309.028129)
			(xy 295.08959 -309.018285) (xy 295.043574 -309.000833) (xy 295.000953 -308.976226) (xy 294.962832 -308.945101)
			(xy 294.930197 -308.908264) (xy 294.903894 -308.866668) (xy 294.884603 -308.821392) (xy 294.872826 -308.773608)
			(xy 294.868866 -308.724554) (xy 294.529965 -308.724554) (xy 294.530427 -308.733073) (xy 294.525061 -308.782425)
			(xy 294.511782 -308.830259) (xy 294.490939 -308.875314) (xy 294.463081 -308.916404) (xy 294.428943 -308.952445)
			(xy 294.389423 -308.982489) (xy 294.345564 -309.005744) (xy 294.29852 -309.021596) (xy 294.249531 -309.029629)
			(xy 294.22471 -309.030116) (xy 294.210527 -309.029938) (xy 294.182287 -309.027267) (xy 294.168322 -309.024782)
			(xy 294.155876 -309.022496) (xy 294.132254 -309.029862) (xy 294.054784 -309.107332) (xy 294.047418 -309.130954)
			(xy 294.049704 -309.1434) (xy 294.052177 -309.157367) (xy 294.054851 -309.185606) (xy 294.055038 -309.199788)
			(xy 305.793914 -309.199788) (xy 305.797874 -309.150734) (xy 305.809651 -309.10295) (xy 305.828942 -309.057674)
			(xy 305.855245 -309.016078) (xy 305.88788 -308.979241) (xy 305.926001 -308.948116) (xy 305.968622 -308.923509)
			(xy 306.014638 -308.906057) (xy 306.062857 -308.896213) (xy 306.112032 -308.894232) (xy 306.160887 -308.900164)
			(xy 306.208158 -308.913856) (xy 306.25262 -308.934954) (xy 306.293123 -308.96291) (xy 306.328616 -308.997002)
			(xy 306.358181 -309.036346) (xy 306.381052 -309.079923) (xy 306.396636 -309.126604) (xy 306.404531 -309.175181)
			(xy 306.405026 -309.199788) (xy 306.744128 -309.199788) (xy 306.748088 -309.150734) (xy 306.759865 -309.10295)
			(xy 306.779156 -309.057674) (xy 306.805459 -309.016078) (xy 306.838094 -308.979241) (xy 306.876215 -308.948116)
			(xy 306.918836 -308.923509) (xy 306.964852 -308.906057) (xy 307.013071 -308.896213) (xy 307.062246 -308.894232)
			(xy 307.111101 -308.900164) (xy 307.158372 -308.913856) (xy 307.202834 -308.934954) (xy 307.243337 -308.96291)
			(xy 307.27883 -308.997002) (xy 307.308395 -309.036346) (xy 307.331266 -309.079923) (xy 307.34685 -309.126604)
			(xy 307.354745 -309.175181) (xy 307.35524 -309.199788) (xy 307.694088 -309.199788) (xy 307.698048 -309.150734)
			(xy 307.709825 -309.10295) (xy 307.729116 -309.057674) (xy 307.755419 -309.016078) (xy 307.788054 -308.979241)
			(xy 307.826175 -308.948116) (xy 307.868796 -308.923509) (xy 307.914812 -308.906057) (xy 307.963031 -308.896213)
			(xy 308.012206 -308.894232) (xy 308.061061 -308.900164) (xy 308.108332 -308.913856) (xy 308.152794 -308.934954)
			(xy 308.193297 -308.96291) (xy 308.22879 -308.997002) (xy 308.258355 -309.036346) (xy 308.281226 -309.079923)
			(xy 308.29681 -309.126604) (xy 308.304705 -309.175181) (xy 308.3052 -309.199788) (xy 308.644048 -309.199788)
			(xy 308.648008 -309.150734) (xy 308.659785 -309.10295) (xy 308.679076 -309.057674) (xy 308.705379 -309.016078)
			(xy 308.738014 -308.979241) (xy 308.776135 -308.948116) (xy 308.818756 -308.923509) (xy 308.864772 -308.906057)
			(xy 308.912991 -308.896213) (xy 308.962166 -308.894232) (xy 309.011021 -308.900164) (xy 309.058292 -308.913856)
			(xy 309.102754 -308.934954) (xy 309.143257 -308.96291) (xy 309.17875 -308.997002) (xy 309.208315 -309.036346)
			(xy 309.231186 -309.079923) (xy 309.24677 -309.126604) (xy 309.254665 -309.175181) (xy 309.25516 -309.199788)
			(xy 309.594008 -309.199788) (xy 309.597968 -309.150734) (xy 309.609745 -309.10295) (xy 309.629036 -309.057674)
			(xy 309.655339 -309.016078) (xy 309.687974 -308.979241) (xy 309.726095 -308.948116) (xy 309.768716 -308.923509)
			(xy 309.814732 -308.906057) (xy 309.862951 -308.896213) (xy 309.912126 -308.894232) (xy 309.960981 -308.900164)
			(xy 310.008252 -308.913856) (xy 310.052714 -308.934954) (xy 310.093217 -308.96291) (xy 310.12871 -308.997002)
			(xy 310.158275 -309.036346) (xy 310.181146 -309.079923) (xy 310.19673 -309.126604) (xy 310.204625 -309.175181)
			(xy 310.20512 -309.199788) (xy 310.543968 -309.199788) (xy 310.547928 -309.150734) (xy 310.559705 -309.10295)
			(xy 310.578996 -309.057674) (xy 310.605299 -309.016078) (xy 310.637934 -308.979241) (xy 310.676055 -308.948116)
			(xy 310.718676 -308.923509) (xy 310.764692 -308.906057) (xy 310.812911 -308.896213) (xy 310.862086 -308.894232)
			(xy 310.910941 -308.900164) (xy 310.958212 -308.913856) (xy 311.002674 -308.934954) (xy 311.043177 -308.96291)
			(xy 311.07867 -308.997002) (xy 311.108235 -309.036346) (xy 311.131106 -309.079923) (xy 311.14669 -309.126604)
			(xy 311.154585 -309.175181) (xy 311.15508 -309.199788) (xy 311.493928 -309.199788) (xy 311.497888 -309.150734)
			(xy 311.509665 -309.10295) (xy 311.528956 -309.057674) (xy 311.555259 -309.016078) (xy 311.587894 -308.979241)
			(xy 311.626015 -308.948116) (xy 311.668636 -308.923509) (xy 311.714652 -308.906057) (xy 311.762871 -308.896213)
			(xy 311.812046 -308.894232) (xy 311.860901 -308.900164) (xy 311.908172 -308.913856) (xy 311.952634 -308.934954)
			(xy 311.993137 -308.96291) (xy 312.02863 -308.997002) (xy 312.058195 -309.036346) (xy 312.081066 -309.079923)
			(xy 312.09665 -309.126604) (xy 312.104545 -309.175181) (xy 312.10504 -309.199788) (xy 312.443888 -309.199788)
			(xy 312.447848 -309.150734) (xy 312.459625 -309.10295) (xy 312.478916 -309.057674) (xy 312.505219 -309.016078)
			(xy 312.537854 -308.979241) (xy 312.575975 -308.948116) (xy 312.618596 -308.923509) (xy 312.664612 -308.906057)
			(xy 312.712831 -308.896213) (xy 312.762006 -308.894232) (xy 312.810861 -308.900164) (xy 312.858132 -308.913856)
			(xy 312.902594 -308.934954) (xy 312.943097 -308.96291) (xy 312.97859 -308.997002) (xy 313.008155 -309.036346)
			(xy 313.031026 -309.079923) (xy 313.04661 -309.126604) (xy 313.054505 -309.175181) (xy 313.055 -309.199788)
			(xy 313.394102 -309.199788) (xy 313.398062 -309.150734) (xy 313.409839 -309.10295) (xy 313.42913 -309.057674)
			(xy 313.455433 -309.016078) (xy 313.488068 -308.979241) (xy 313.526189 -308.948116) (xy 313.56881 -308.923509)
			(xy 313.614826 -308.906057) (xy 313.663045 -308.896213) (xy 313.71222 -308.894232) (xy 313.761075 -308.900164)
			(xy 313.808346 -308.913856) (xy 313.852808 -308.934954) (xy 313.893311 -308.96291) (xy 313.928804 -308.997002)
			(xy 313.958369 -309.036346) (xy 313.98124 -309.079923) (xy 313.996824 -309.126604) (xy 314.004719 -309.175181)
			(xy 314.005214 -309.199788) (xy 314.344062 -309.199788) (xy 314.348022 -309.150734) (xy 314.359799 -309.10295)
			(xy 314.37909 -309.057674) (xy 314.405393 -309.016078) (xy 314.438028 -308.979241) (xy 314.476149 -308.948116)
			(xy 314.51877 -308.923509) (xy 314.564786 -308.906057) (xy 314.613005 -308.896213) (xy 314.66218 -308.894232)
			(xy 314.711035 -308.900164) (xy 314.758306 -308.913856) (xy 314.802768 -308.934954) (xy 314.843271 -308.96291)
			(xy 314.878764 -308.997002) (xy 314.908329 -309.036346) (xy 314.9312 -309.079923) (xy 314.946784 -309.126604)
			(xy 314.954679 -309.175181) (xy 314.955174 -309.199788) (xy 314.954679 -309.224395) (xy 314.946784 -309.272972)
			(xy 314.9312 -309.319653) (xy 314.908329 -309.36323) (xy 314.878764 -309.402574) (xy 314.843271 -309.436666)
			(xy 314.802768 -309.464622) (xy 314.758306 -309.48572) (xy 314.711035 -309.499412) (xy 314.66218 -309.505344)
			(xy 314.613005 -309.503363) (xy 314.564786 -309.493519) (xy 314.51877 -309.476067) (xy 314.476149 -309.45146)
			(xy 314.438028 -309.420335) (xy 314.405393 -309.383498) (xy 314.37909 -309.341902) (xy 314.359799 -309.296626)
			(xy 314.348022 -309.248842) (xy 314.344062 -309.199788) (xy 314.005214 -309.199788) (xy 314.004719 -309.224395)
			(xy 313.996824 -309.272972) (xy 313.98124 -309.319653) (xy 313.958369 -309.36323) (xy 313.928804 -309.402574)
			(xy 313.893311 -309.436666) (xy 313.852808 -309.464622) (xy 313.808346 -309.48572) (xy 313.761075 -309.499412)
			(xy 313.71222 -309.505344) (xy 313.663045 -309.503363) (xy 313.614826 -309.493519) (xy 313.56881 -309.476067)
			(xy 313.526189 -309.45146) (xy 313.488068 -309.420335) (xy 313.455433 -309.383498) (xy 313.42913 -309.341902)
			(xy 313.409839 -309.296626) (xy 313.398062 -309.248842) (xy 313.394102 -309.199788) (xy 313.055 -309.199788)
			(xy 313.054505 -309.224395) (xy 313.04661 -309.272972) (xy 313.031026 -309.319653) (xy 313.008155 -309.36323)
			(xy 312.97859 -309.402574) (xy 312.943097 -309.436666) (xy 312.902594 -309.464622) (xy 312.858132 -309.48572)
			(xy 312.810861 -309.499412) (xy 312.762006 -309.505344) (xy 312.712831 -309.503363) (xy 312.664612 -309.493519)
			(xy 312.618596 -309.476067) (xy 312.575975 -309.45146) (xy 312.537854 -309.420335) (xy 312.505219 -309.383498)
			(xy 312.478916 -309.341902) (xy 312.459625 -309.296626) (xy 312.447848 -309.248842) (xy 312.443888 -309.199788)
			(xy 312.10504 -309.199788) (xy 312.104545 -309.224395) (xy 312.09665 -309.272972) (xy 312.081066 -309.319653)
			(xy 312.058195 -309.36323) (xy 312.02863 -309.402574) (xy 311.993137 -309.436666) (xy 311.952634 -309.464622)
			(xy 311.908172 -309.48572) (xy 311.860901 -309.499412) (xy 311.812046 -309.505344) (xy 311.762871 -309.503363)
			(xy 311.714652 -309.493519) (xy 311.668636 -309.476067) (xy 311.626015 -309.45146) (xy 311.587894 -309.420335)
			(xy 311.555259 -309.383498) (xy 311.528956 -309.341902) (xy 311.509665 -309.296626) (xy 311.497888 -309.248842)
			(xy 311.493928 -309.199788) (xy 311.15508 -309.199788) (xy 311.154585 -309.224395) (xy 311.14669 -309.272972)
			(xy 311.131106 -309.319653) (xy 311.108235 -309.36323) (xy 311.07867 -309.402574) (xy 311.043177 -309.436666)
			(xy 311.002674 -309.464622) (xy 310.958212 -309.48572) (xy 310.910941 -309.499412) (xy 310.862086 -309.505344)
			(xy 310.812911 -309.503363) (xy 310.764692 -309.493519) (xy 310.718676 -309.476067) (xy 310.676055 -309.45146)
			(xy 310.637934 -309.420335) (xy 310.605299 -309.383498) (xy 310.578996 -309.341902) (xy 310.559705 -309.296626)
			(xy 310.547928 -309.248842) (xy 310.543968 -309.199788) (xy 310.20512 -309.199788) (xy 310.204625 -309.224395)
			(xy 310.19673 -309.272972) (xy 310.181146 -309.319653) (xy 310.158275 -309.36323) (xy 310.12871 -309.402574)
			(xy 310.093217 -309.436666) (xy 310.052714 -309.464622) (xy 310.008252 -309.48572) (xy 309.960981 -309.499412)
			(xy 309.912126 -309.505344) (xy 309.862951 -309.503363) (xy 309.814732 -309.493519) (xy 309.768716 -309.476067)
			(xy 309.726095 -309.45146) (xy 309.687974 -309.420335) (xy 309.655339 -309.383498) (xy 309.629036 -309.341902)
			(xy 309.609745 -309.296626) (xy 309.597968 -309.248842) (xy 309.594008 -309.199788) (xy 309.25516 -309.199788)
			(xy 309.254665 -309.224395) (xy 309.24677 -309.272972) (xy 309.231186 -309.319653) (xy 309.208315 -309.36323)
			(xy 309.17875 -309.402574) (xy 309.143257 -309.436666) (xy 309.102754 -309.464622) (xy 309.058292 -309.48572)
			(xy 309.011021 -309.499412) (xy 308.962166 -309.505344) (xy 308.912991 -309.503363) (xy 308.864772 -309.493519)
			(xy 308.818756 -309.476067) (xy 308.776135 -309.45146) (xy 308.738014 -309.420335) (xy 308.705379 -309.383498)
			(xy 308.679076 -309.341902) (xy 308.659785 -309.296626) (xy 308.648008 -309.248842) (xy 308.644048 -309.199788)
			(xy 308.3052 -309.199788) (xy 308.304705 -309.224395) (xy 308.29681 -309.272972) (xy 308.281226 -309.319653)
			(xy 308.258355 -309.36323) (xy 308.22879 -309.402574) (xy 308.193297 -309.436666) (xy 308.152794 -309.464622)
			(xy 308.108332 -309.48572) (xy 308.061061 -309.499412) (xy 308.012206 -309.505344) (xy 307.963031 -309.503363)
			(xy 307.914812 -309.493519) (xy 307.868796 -309.476067) (xy 307.826175 -309.45146) (xy 307.788054 -309.420335)
			(xy 307.755419 -309.383498) (xy 307.729116 -309.341902) (xy 307.709825 -309.296626) (xy 307.698048 -309.248842)
			(xy 307.694088 -309.199788) (xy 307.35524 -309.199788) (xy 307.354745 -309.224395) (xy 307.34685 -309.272972)
			(xy 307.331266 -309.319653) (xy 307.308395 -309.36323) (xy 307.27883 -309.402574) (xy 307.243337 -309.436666)
			(xy 307.202834 -309.464622) (xy 307.158372 -309.48572) (xy 307.111101 -309.499412) (xy 307.062246 -309.505344)
			(xy 307.013071 -309.503363) (xy 306.964852 -309.493519) (xy 306.918836 -309.476067) (xy 306.876215 -309.45146)
			(xy 306.838094 -309.420335) (xy 306.805459 -309.383498) (xy 306.779156 -309.341902) (xy 306.759865 -309.296626)
			(xy 306.748088 -309.248842) (xy 306.744128 -309.199788) (xy 306.405026 -309.199788) (xy 306.404531 -309.224395)
			(xy 306.396636 -309.272972) (xy 306.381052 -309.319653) (xy 306.358181 -309.36323) (xy 306.328616 -309.402574)
			(xy 306.293123 -309.436666) (xy 306.25262 -309.464622) (xy 306.208158 -309.48572) (xy 306.160887 -309.499412)
			(xy 306.112032 -309.505344) (xy 306.062857 -309.503363) (xy 306.014638 -309.493519) (xy 305.968622 -309.476067)
			(xy 305.926001 -309.45146) (xy 305.88788 -309.420335) (xy 305.855245 -309.383498) (xy 305.828942 -309.341902)
			(xy 305.809651 -309.296626) (xy 305.797874 -309.248842) (xy 305.793914 -309.199788) (xy 294.055038 -309.199788)
			(xy 294.054516 -309.225043) (xy 294.046203 -309.274865) (xy 294.029802 -309.322639) (xy 294.005761 -309.367062)
			(xy 293.974737 -309.406922) (xy 293.937575 -309.441132) (xy 293.895289 -309.468758) (xy 293.849033 -309.489048)
			(xy 293.800068 -309.501448) (xy 293.74973 -309.505619) (xy 293.699392 -309.501448) (xy 293.650427 -309.489048)
			(xy 293.604171 -309.468758) (xy 293.561885 -309.441132) (xy 293.524723 -309.406922) (xy 293.493699 -309.367062)
			(xy 293.469658 -309.322639) (xy 293.453257 -309.274865) (xy 293.444944 -309.225043) (xy 293.444422 -309.199788)
			(xy 293.444596 -309.185605) (xy 293.44727 -309.157365) (xy 293.449756 -309.1434) (xy 293.452042 -309.130954)
			(xy 293.444676 -309.107332) (xy 293.367206 -309.029862) (xy 293.343584 -309.022496) (xy 293.331138 -309.024782)
			(xy 293.317173 -309.027263) (xy 293.288933 -309.029932) (xy 293.27475 -309.030116) (xy 293.260567 -309.029932)
			(xy 293.232327 -309.027265) (xy 293.218362 -309.024782) (xy 293.205916 -309.022496) (xy 293.182294 -309.029862)
			(xy 293.104824 -309.107332) (xy 293.097458 -309.130954) (xy 293.099744 -309.1434) (xy 293.102216 -309.157367)
			(xy 293.104891 -309.185606) (xy 293.105078 -309.199788) (xy 293.104556 -309.225043) (xy 293.096243 -309.274865)
			(xy 293.079842 -309.322639) (xy 293.055801 -309.367062) (xy 293.024777 -309.406922) (xy 292.987615 -309.441132)
			(xy 292.945329 -309.468758) (xy 292.899073 -309.489048) (xy 292.850108 -309.501448) (xy 292.79977 -309.505619)
			(xy 292.749432 -309.501448) (xy 292.700467 -309.489048) (xy 292.654211 -309.468758) (xy 292.611925 -309.441132)
			(xy 292.574763 -309.406922) (xy 292.543739 -309.367062) (xy 292.519698 -309.322639) (xy 292.503297 -309.274865)
			(xy 292.494984 -309.225043) (xy 292.494462 -309.199788) (xy 292.494637 -309.185605) (xy 292.49731 -309.157365)
			(xy 292.499796 -309.1434) (xy 292.502082 -309.130954) (xy 292.494716 -309.107332) (xy 292.417246 -309.029862)
			(xy 292.393624 -309.022496) (xy 292.381178 -309.024782) (xy 292.367212 -309.027257) (xy 292.338972 -309.02993)
			(xy 292.32479 -309.030116) (xy 292.29997 -309.029611) (xy 292.250984 -309.021579) (xy 292.203943 -309.005727)
			(xy 292.160086 -308.982474) (xy 292.120569 -308.952432) (xy 292.086433 -308.916392) (xy 292.058577 -308.875305)
			(xy 292.037735 -308.830252) (xy 292.024456 -308.782421) (xy 292.019091 -308.733072) (xy 290.730012 -308.733072)
			(xy 290.729683 -308.749415) (xy 290.721788 -308.797992) (xy 290.706204 -308.844673) (xy 290.683333 -308.88825)
			(xy 290.653768 -308.927594) (xy 290.618275 -308.961686) (xy 290.577772 -308.989642) (xy 290.53331 -309.01074)
			(xy 290.486039 -309.024432) (xy 290.437184 -309.030364) (xy 290.388009 -309.028383) (xy 290.33979 -309.018539)
			(xy 290.293774 -309.001087) (xy 290.251153 -308.97648) (xy 290.213032 -308.945355) (xy 290.180397 -308.908518)
			(xy 290.154094 -308.866922) (xy 290.134803 -308.821646) (xy 290.123026 -308.773862) (xy 290.119066 -308.724808)
			(xy 288.83018 -308.724808) (xy 288.830628 -308.733046) (xy 288.825267 -308.782397) (xy 288.811992 -308.830231)
			(xy 288.791154 -308.875287) (xy 288.763301 -308.916378) (xy 288.729168 -308.952423) (xy 288.689653 -308.98247)
			(xy 288.645798 -309.005729) (xy 288.598757 -309.021587) (xy 288.549771 -309.029626) (xy 288.52495 -309.030116)
			(xy 288.510703 -309.029949) (xy 288.482336 -309.027276) (xy 288.468308 -309.024782) (xy 288.456116 -309.022496)
			(xy 288.431986 -309.029862) (xy 288.35477 -309.107078) (xy 288.347404 -309.130954) (xy 288.34969 -309.1434)
			(xy 288.352162 -309.157367) (xy 288.354837 -309.185606) (xy 288.355024 -309.199788) (xy 288.354502 -309.225043)
			(xy 288.346189 -309.274865) (xy 288.329788 -309.322639) (xy 288.305747 -309.367062) (xy 288.274723 -309.406922)
			(xy 288.237561 -309.441132) (xy 288.195275 -309.468758) (xy 288.149019 -309.489048) (xy 288.100054 -309.501448)
			(xy 288.049716 -309.505619) (xy 287.999378 -309.501448) (xy 287.950413 -309.489048) (xy 287.904157 -309.468758)
			(xy 287.861871 -309.441132) (xy 287.824709 -309.406922) (xy 287.793685 -309.367062) (xy 287.769644 -309.322639)
			(xy 287.753243 -309.274865) (xy 287.74493 -309.225043) (xy 287.744408 -309.199788) (xy 287.744583 -309.185605)
			(xy 287.747256 -309.157365) (xy 287.749742 -309.1434) (xy 287.752028 -309.130954) (xy 287.744662 -309.107332)
			(xy 287.667192 -309.029862) (xy 287.64357 -309.022496) (xy 287.631124 -309.024782) (xy 287.617159 -309.027265)
			(xy 287.588919 -309.029932) (xy 287.574736 -309.030116) (xy 287.549911 -309.029661) (xy 287.500915 -309.021634)
			(xy 287.453864 -309.005786) (xy 287.409996 -308.982535) (xy 287.370468 -308.952492) (xy 287.336321 -308.91645)
			(xy 287.308454 -308.875359) (xy 287.287604 -308.8303) (xy 287.274317 -308.782462) (xy 287.268946 -308.733104)
			(xy 286.929917 -308.733104) (xy 286.929589 -308.749415) (xy 286.921694 -308.797992) (xy 286.90611 -308.844673)
			(xy 286.883239 -308.88825) (xy 286.853674 -308.927594) (xy 286.818181 -308.961686) (xy 286.777678 -308.989642)
			(xy 286.733216 -309.01074) (xy 286.685945 -309.024432) (xy 286.63709 -309.030364) (xy 286.587915 -309.028383)
			(xy 286.539696 -309.018539) (xy 286.49368 -309.001087) (xy 286.451059 -308.97648) (xy 286.412938 -308.945355)
			(xy 286.380303 -308.908518) (xy 286.354 -308.866922) (xy 286.334709 -308.821646) (xy 286.322932 -308.773862)
			(xy 286.318972 -308.724808) (xy 285.980124 -308.724808) (xy 285.979629 -308.749415) (xy 285.971734 -308.797992)
			(xy 285.95615 -308.844673) (xy 285.933279 -308.88825) (xy 285.903714 -308.927594) (xy 285.868221 -308.961686)
			(xy 285.827718 -308.989642) (xy 285.783256 -309.01074) (xy 285.735985 -309.024432) (xy 285.68713 -309.030364)
			(xy 285.637955 -309.028383) (xy 285.589736 -309.018539) (xy 285.54372 -309.001087) (xy 285.501099 -308.97648)
			(xy 285.462978 -308.945355) (xy 285.430343 -308.908518) (xy 285.40404 -308.866922) (xy 285.384749 -308.821646)
			(xy 285.372972 -308.773862) (xy 285.369012 -308.724808) (xy 285.030164 -308.724808) (xy 285.029669 -308.749415)
			(xy 285.021774 -308.797992) (xy 285.00619 -308.844673) (xy 284.983319 -308.88825) (xy 284.953754 -308.927594)
			(xy 284.918261 -308.961686) (xy 284.877758 -308.989642) (xy 284.833296 -309.01074) (xy 284.786025 -309.024432)
			(xy 284.73717 -309.030364) (xy 284.687995 -309.028383) (xy 284.639776 -309.018539) (xy 284.59376 -309.001087)
			(xy 284.551139 -308.97648) (xy 284.513018 -308.945355) (xy 284.480383 -308.908518) (xy 284.45408 -308.866922)
			(xy 284.434789 -308.821646) (xy 284.423012 -308.773862) (xy 284.419052 -308.724808) (xy 284.080178 -308.724808)
			(xy 284.080627 -308.733082) (xy 284.075259 -308.782434) (xy 284.061978 -308.830268) (xy 284.041133 -308.875323)
			(xy 284.013274 -308.916413) (xy 283.979134 -308.952453) (xy 283.939613 -308.982496) (xy 283.895752 -309.005749)
			(xy 283.848707 -309.0216) (xy 283.799718 -309.02963) (xy 283.774896 -309.030116) (xy 283.760713 -309.02994)
			(xy 283.732473 -309.027267) (xy 283.718508 -309.024782) (xy 283.704541 -309.022628) (xy 283.67641 -309.025205)
			(xy 283.650063 -309.035393) (xy 283.627516 -309.052411) (xy 283.610496 -309.074957) (xy 283.600306 -309.101304)
			(xy 283.597727 -309.129435) (xy 283.59989 -309.1434) (xy 283.602362 -309.157367) (xy 283.605037 -309.185606)
			(xy 283.605224 -309.199788) (xy 283.604735 -309.22461) (xy 283.596705 -309.273601) (xy 283.580855 -309.320648)
			(xy 283.557602 -309.36451) (xy 283.52756 -309.404033) (xy 283.491519 -309.438174) (xy 283.450429 -309.466035)
			(xy 283.405373 -309.486881) (xy 283.357538 -309.500163) (xy 283.308185 -309.505531) (xy 283.258613 -309.502843)
			(xy 283.210129 -309.492172) (xy 283.16401 -309.473796) (xy 283.121472 -309.448202) (xy 283.083635 -309.416062)
			(xy 283.051496 -309.378225) (xy 283.025902 -309.335686) (xy 283.007527 -309.289567) (xy 282.996856 -309.241083)
			(xy 282.994169 -309.191511) (xy 282.654856 -309.191511) (xy 282.655543 -309.1998) (xy 282.651372 -309.25014)
			(xy 282.638972 -309.299107) (xy 282.618681 -309.345365) (xy 282.591054 -309.387652) (xy 282.556843 -309.424815)
			(xy 282.516981 -309.455841) (xy 282.472557 -309.479882) (xy 282.424782 -309.496284) (xy 282.374958 -309.504598)
			(xy 282.349702 -309.505096) (xy 282.327858 -309.504334) (xy 282.317444 -309.503572) (xy 282.297632 -309.51043)
			(xy 282.235402 -309.568596) (xy 282.228064 -309.576066) (xy 282.219664 -309.595222) (xy 282.219146 -309.60568)
			(xy 282.219146 -309.743856) (xy 282.219713 -309.754301) (xy 282.228115 -309.773434) (xy 282.235402 -309.78094)
			(xy 282.297632 -309.839106) (xy 282.317444 -309.845964) (xy 282.327858 -309.845202) (xy 282.349702 -309.84444)
			(xy 282.374953 -309.844962) (xy 282.424767 -309.853274) (xy 282.472533 -309.869673) (xy 282.516949 -309.893709)
			(xy 282.556802 -309.924729) (xy 282.591006 -309.961885) (xy 282.618628 -310.004164) (xy 282.638915 -310.050413)
			(xy 282.651313 -310.09937) (xy 282.655483 -310.1497) (xy 282.655479 -310.149748) (xy 282.994112 -310.149748)
			(xy 282.998072 -310.100694) (xy 283.009849 -310.05291) (xy 283.02914 -310.007634) (xy 283.055443 -309.966038)
			(xy 283.088078 -309.929201) (xy 283.126199 -309.898076) (xy 283.16882 -309.873469) (xy 283.214836 -309.856017)
			(xy 283.263055 -309.846173) (xy 283.31223 -309.844192) (xy 283.361085 -309.850124) (xy 283.408356 -309.863816)
			(xy 283.452818 -309.884914) (xy 283.493321 -309.91287) (xy 283.528814 -309.946962) (xy 283.558379 -309.986306)
			(xy 283.58125 -310.029883) (xy 283.596834 -310.076564) (xy 283.604729 -310.125141) (xy 283.605224 -310.149748)
			(xy 283.944072 -310.149748) (xy 283.948032 -310.100694) (xy 283.959809 -310.05291) (xy 283.9791 -310.007634)
			(xy 284.005403 -309.966038) (xy 284.038038 -309.929201) (xy 284.076159 -309.898076) (xy 284.11878 -309.873469)
			(xy 284.164796 -309.856017) (xy 284.213015 -309.846173) (xy 284.26219 -309.844192) (xy 284.311045 -309.850124)
			(xy 284.358316 -309.863816) (xy 284.402778 -309.884914) (xy 284.443281 -309.91287) (xy 284.478774 -309.946962)
			(xy 284.508339 -309.986306) (xy 284.53121 -310.029883) (xy 284.546794 -310.076564) (xy 284.554689 -310.125141)
			(xy 284.555184 -310.149748) (xy 284.894032 -310.149748) (xy 284.897992 -310.100694) (xy 284.909769 -310.05291)
			(xy 284.92906 -310.007634) (xy 284.955363 -309.966038) (xy 284.987998 -309.929201) (xy 285.026119 -309.898076)
			(xy 285.06874 -309.873469) (xy 285.114756 -309.856017) (xy 285.162975 -309.846173) (xy 285.21215 -309.844192)
			(xy 285.261005 -309.850124) (xy 285.308276 -309.863816) (xy 285.352738 -309.884914) (xy 285.393241 -309.91287)
			(xy 285.428734 -309.946962) (xy 285.458299 -309.986306) (xy 285.48117 -310.029883) (xy 285.496754 -310.076564)
			(xy 285.504649 -310.125141) (xy 285.505144 -310.149748) (xy 285.843992 -310.149748) (xy 285.847952 -310.100694)
			(xy 285.859729 -310.05291) (xy 285.87902 -310.007634) (xy 285.905323 -309.966038) (xy 285.937958 -309.929201)
			(xy 285.976079 -309.898076) (xy 286.0187 -309.873469) (xy 286.064716 -309.856017) (xy 286.112935 -309.846173)
			(xy 286.16211 -309.844192) (xy 286.210965 -309.850124) (xy 286.258236 -309.863816) (xy 286.302698 -309.884914)
			(xy 286.343201 -309.91287) (xy 286.378694 -309.946962) (xy 286.408259 -309.986306) (xy 286.43113 -310.029883)
			(xy 286.446714 -310.076564) (xy 286.454609 -310.125141) (xy 286.455104 -310.149748) (xy 286.793952 -310.149748)
			(xy 286.797912 -310.100694) (xy 286.809689 -310.05291) (xy 286.82898 -310.007634) (xy 286.855283 -309.966038)
			(xy 286.887918 -309.929201) (xy 286.926039 -309.898076) (xy 286.96866 -309.873469) (xy 287.014676 -309.856017)
			(xy 287.062895 -309.846173) (xy 287.11207 -309.844192) (xy 287.160925 -309.850124) (xy 287.208196 -309.863816)
			(xy 287.252658 -309.884914) (xy 287.293161 -309.91287) (xy 287.328654 -309.946962) (xy 287.358219 -309.986306)
			(xy 287.38109 -310.029883) (xy 287.396674 -310.076564) (xy 287.404569 -310.125141) (xy 287.405064 -310.149748)
			(xy 287.743912 -310.149748) (xy 287.747872 -310.100694) (xy 287.759649 -310.05291) (xy 287.77894 -310.007634)
			(xy 287.805243 -309.966038) (xy 287.837878 -309.929201) (xy 287.875999 -309.898076) (xy 287.91862 -309.873469)
			(xy 287.964636 -309.856017) (xy 288.012855 -309.846173) (xy 288.06203 -309.844192) (xy 288.110885 -309.850124)
			(xy 288.158156 -309.863816) (xy 288.202618 -309.884914) (xy 288.243121 -309.91287) (xy 288.278614 -309.946962)
			(xy 288.308179 -309.986306) (xy 288.33105 -310.029883) (xy 288.346634 -310.076564) (xy 288.354529 -310.125141)
			(xy 288.355024 -310.149748) (xy 288.694126 -310.149748) (xy 288.698086 -310.100694) (xy 288.709863 -310.05291)
			(xy 288.729154 -310.007634) (xy 288.755457 -309.966038) (xy 288.788092 -309.929201) (xy 288.826213 -309.898076)
			(xy 288.868834 -309.873469) (xy 288.91485 -309.856017) (xy 288.963069 -309.846173) (xy 289.012244 -309.844192)
			(xy 289.061099 -309.850124) (xy 289.10837 -309.863816) (xy 289.152832 -309.884914) (xy 289.193335 -309.91287)
			(xy 289.228828 -309.946962) (xy 289.258393 -309.986306) (xy 289.281264 -310.029883) (xy 289.296848 -310.076564)
			(xy 289.304743 -310.125141) (xy 289.305238 -310.149748) (xy 289.644086 -310.149748) (xy 289.648046 -310.100694)
			(xy 289.659823 -310.05291) (xy 289.679114 -310.007634) (xy 289.705417 -309.966038) (xy 289.738052 -309.929201)
			(xy 289.776173 -309.898076) (xy 289.818794 -309.873469) (xy 289.86481 -309.856017) (xy 289.913029 -309.846173)
			(xy 289.962204 -309.844192) (xy 290.011059 -309.850124) (xy 290.05833 -309.863816) (xy 290.102792 -309.884914)
			(xy 290.143295 -309.91287) (xy 290.178788 -309.946962) (xy 290.208353 -309.986306) (xy 290.231224 -310.029883)
			(xy 290.246808 -310.076564) (xy 290.254703 -310.125141) (xy 290.255198 -310.149748) (xy 290.594046 -310.149748)
			(xy 290.598006 -310.100694) (xy 290.609783 -310.05291) (xy 290.629074 -310.007634) (xy 290.655377 -309.966038)
			(xy 290.688012 -309.929201) (xy 290.726133 -309.898076) (xy 290.768754 -309.873469) (xy 290.81477 -309.856017)
			(xy 290.862989 -309.846173) (xy 290.912164 -309.844192) (xy 290.961019 -309.850124) (xy 291.00829 -309.863816)
			(xy 291.052752 -309.884914) (xy 291.093255 -309.91287) (xy 291.128748 -309.946962) (xy 291.158313 -309.986306)
			(xy 291.181184 -310.029883) (xy 291.196768 -310.076564) (xy 291.204663 -310.125141) (xy 291.205158 -310.149748)
			(xy 291.544006 -310.149748) (xy 291.547966 -310.100694) (xy 291.559743 -310.05291) (xy 291.579034 -310.007634)
			(xy 291.605337 -309.966038) (xy 291.637972 -309.929201) (xy 291.676093 -309.898076) (xy 291.718714 -309.873469)
			(xy 291.76473 -309.856017) (xy 291.812949 -309.846173) (xy 291.862124 -309.844192) (xy 291.910979 -309.850124)
			(xy 291.95825 -309.863816) (xy 292.002712 -309.884914) (xy 292.043215 -309.91287) (xy 292.078708 -309.946962)
			(xy 292.108273 -309.986306) (xy 292.131144 -310.029883) (xy 292.146728 -310.076564) (xy 292.154623 -310.125141)
			(xy 292.155118 -310.149748) (xy 292.493966 -310.149748) (xy 292.497926 -310.100694) (xy 292.509703 -310.05291)
			(xy 292.528994 -310.007634) (xy 292.555297 -309.966038) (xy 292.587932 -309.929201) (xy 292.626053 -309.898076)
			(xy 292.668674 -309.873469) (xy 292.71469 -309.856017) (xy 292.762909 -309.846173) (xy 292.812084 -309.844192)
			(xy 292.860939 -309.850124) (xy 292.90821 -309.863816) (xy 292.952672 -309.884914) (xy 292.993175 -309.91287)
			(xy 293.028668 -309.946962) (xy 293.058233 -309.986306) (xy 293.081104 -310.029883) (xy 293.096688 -310.076564)
			(xy 293.104583 -310.125141) (xy 293.105078 -310.149748) (xy 293.443926 -310.149748) (xy 293.447886 -310.100694)
			(xy 293.459663 -310.05291) (xy 293.478954 -310.007634) (xy 293.505257 -309.966038) (xy 293.537892 -309.929201)
			(xy 293.576013 -309.898076) (xy 293.618634 -309.873469) (xy 293.66465 -309.856017) (xy 293.712869 -309.846173)
			(xy 293.762044 -309.844192) (xy 293.810899 -309.850124) (xy 293.85817 -309.863816) (xy 293.902632 -309.884914)
			(xy 293.943135 -309.91287) (xy 293.978628 -309.946962) (xy 294.008193 -309.986306) (xy 294.031064 -310.029883)
			(xy 294.046648 -310.076564) (xy 294.054543 -310.125141) (xy 294.055038 -310.149748) (xy 294.393886 -310.149748)
			(xy 294.397846 -310.100694) (xy 294.409623 -310.05291) (xy 294.428914 -310.007634) (xy 294.455217 -309.966038)
			(xy 294.487852 -309.929201) (xy 294.525973 -309.898076) (xy 294.568594 -309.873469) (xy 294.61461 -309.856017)
			(xy 294.662829 -309.846173) (xy 294.712004 -309.844192) (xy 294.760859 -309.850124) (xy 294.80813 -309.863816)
			(xy 294.852592 -309.884914) (xy 294.893095 -309.91287) (xy 294.928588 -309.946962) (xy 294.958153 -309.986306)
			(xy 294.981024 -310.029883) (xy 294.996608 -310.076564) (xy 295.004503 -310.125141) (xy 295.004998 -310.149748)
			(xy 295.3441 -310.149748) (xy 295.34806 -310.100694) (xy 295.359837 -310.05291) (xy 295.379128 -310.007634)
			(xy 295.405431 -309.966038) (xy 295.438066 -309.929201) (xy 295.476187 -309.898076) (xy 295.518808 -309.873469)
			(xy 295.564824 -309.856017) (xy 295.613043 -309.846173) (xy 295.662218 -309.844192) (xy 295.711073 -309.850124)
			(xy 295.758344 -309.863816) (xy 295.802806 -309.884914) (xy 295.843309 -309.91287) (xy 295.878802 -309.946962)
			(xy 295.908367 -309.986306) (xy 295.931238 -310.029883) (xy 295.946822 -310.076564) (xy 295.954717 -310.125141)
			(xy 295.955212 -310.149748) (xy 296.29406 -310.149748) (xy 296.29802 -310.100694) (xy 296.309797 -310.05291)
			(xy 296.329088 -310.007634) (xy 296.355391 -309.966038) (xy 296.388026 -309.929201) (xy 296.426147 -309.898076)
			(xy 296.468768 -309.873469) (xy 296.514784 -309.856017) (xy 296.563003 -309.846173) (xy 296.612178 -309.844192)
			(xy 296.661033 -309.850124) (xy 296.708304 -309.863816) (xy 296.752766 -309.884914) (xy 296.793269 -309.91287)
			(xy 296.828762 -309.946962) (xy 296.858327 -309.986306) (xy 296.881198 -310.029883) (xy 296.896782 -310.076564)
			(xy 296.904677 -310.125141) (xy 296.905172 -310.149748) (xy 297.24402 -310.149748) (xy 297.24798 -310.100694)
			(xy 297.259757 -310.05291) (xy 297.279048 -310.007634) (xy 297.305351 -309.966038) (xy 297.337986 -309.929201)
			(xy 297.376107 -309.898076) (xy 297.418728 -309.873469) (xy 297.464744 -309.856017) (xy 297.512963 -309.846173)
			(xy 297.562138 -309.844192) (xy 297.610993 -309.850124) (xy 297.658264 -309.863816) (xy 297.702726 -309.884914)
			(xy 297.743229 -309.91287) (xy 297.778722 -309.946962) (xy 297.808287 -309.986306) (xy 297.831158 -310.029883)
			(xy 297.846742 -310.076564) (xy 297.854637 -310.125141) (xy 297.855132 -310.149748) (xy 298.19398 -310.149748)
			(xy 298.19794 -310.100694) (xy 298.209717 -310.05291) (xy 298.229008 -310.007634) (xy 298.255311 -309.966038)
			(xy 298.287946 -309.929201) (xy 298.326067 -309.898076) (xy 298.368688 -309.873469) (xy 298.414704 -309.856017)
			(xy 298.462923 -309.846173) (xy 298.512098 -309.844192) (xy 298.560953 -309.850124) (xy 298.608224 -309.863816)
			(xy 298.652686 -309.884914) (xy 298.693189 -309.91287) (xy 298.728682 -309.946962) (xy 298.758247 -309.986306)
			(xy 298.781118 -310.029883) (xy 298.796702 -310.076564) (xy 298.804597 -310.125141) (xy 298.805092 -310.149748)
			(xy 299.14394 -310.149748) (xy 299.1479 -310.100694) (xy 299.159677 -310.05291) (xy 299.178968 -310.007634)
			(xy 299.205271 -309.966038) (xy 299.237906 -309.929201) (xy 299.276027 -309.898076) (xy 299.318648 -309.873469)
			(xy 299.364664 -309.856017) (xy 299.412883 -309.846173) (xy 299.462058 -309.844192) (xy 299.510913 -309.850124)
			(xy 299.558184 -309.863816) (xy 299.602646 -309.884914) (xy 299.643149 -309.91287) (xy 299.678642 -309.946962)
			(xy 299.708207 -309.986306) (xy 299.731078 -310.029883) (xy 299.746662 -310.076564) (xy 299.754557 -310.125141)
			(xy 299.755052 -310.149748) (xy 300.0939 -310.149748) (xy 300.09786 -310.100694) (xy 300.109637 -310.05291)
			(xy 300.128928 -310.007634) (xy 300.155231 -309.966038) (xy 300.187866 -309.929201) (xy 300.225987 -309.898076)
			(xy 300.268608 -309.873469) (xy 300.314624 -309.856017) (xy 300.362843 -309.846173) (xy 300.412018 -309.844192)
			(xy 300.460873 -309.850124) (xy 300.508144 -309.863816) (xy 300.552606 -309.884914) (xy 300.593109 -309.91287)
			(xy 300.628602 -309.946962) (xy 300.658167 -309.986306) (xy 300.681038 -310.029883) (xy 300.696622 -310.076564)
			(xy 300.704517 -310.125141) (xy 300.705012 -310.149748) (xy 301.044114 -310.149748) (xy 301.048074 -310.100694)
			(xy 301.059851 -310.05291) (xy 301.079142 -310.007634) (xy 301.105445 -309.966038) (xy 301.13808 -309.929201)
			(xy 301.176201 -309.898076) (xy 301.218822 -309.873469) (xy 301.264838 -309.856017) (xy 301.313057 -309.846173)
			(xy 301.362232 -309.844192) (xy 301.411087 -309.850124) (xy 301.458358 -309.863816) (xy 301.50282 -309.884914)
			(xy 301.543323 -309.91287) (xy 301.578816 -309.946962) (xy 301.608381 -309.986306) (xy 301.631252 -310.029883)
			(xy 301.646836 -310.076564) (xy 301.654731 -310.125141) (xy 301.655226 -310.149748) (xy 301.994074 -310.149748)
			(xy 301.998034 -310.100694) (xy 302.009811 -310.05291) (xy 302.029102 -310.007634) (xy 302.055405 -309.966038)
			(xy 302.08804 -309.929201) (xy 302.126161 -309.898076) (xy 302.168782 -309.873469) (xy 302.214798 -309.856017)
			(xy 302.263017 -309.846173) (xy 302.312192 -309.844192) (xy 302.361047 -309.850124) (xy 302.408318 -309.863816)
			(xy 302.45278 -309.884914) (xy 302.493283 -309.91287) (xy 302.528776 -309.946962) (xy 302.558341 -309.986306)
			(xy 302.581212 -310.029883) (xy 302.596796 -310.076564) (xy 302.604691 -310.125141) (xy 302.605186 -310.149748)
			(xy 302.944034 -310.149748) (xy 302.947994 -310.100694) (xy 302.959771 -310.05291) (xy 302.979062 -310.007634)
			(xy 303.005365 -309.966038) (xy 303.038 -309.929201) (xy 303.076121 -309.898076) (xy 303.118742 -309.873469)
			(xy 303.164758 -309.856017) (xy 303.212977 -309.846173) (xy 303.262152 -309.844192) (xy 303.311007 -309.850124)
			(xy 303.358278 -309.863816) (xy 303.40274 -309.884914) (xy 303.443243 -309.91287) (xy 303.478736 -309.946962)
			(xy 303.508301 -309.986306) (xy 303.531172 -310.029883) (xy 303.546756 -310.076564) (xy 303.554651 -310.125141)
			(xy 303.555146 -310.149748) (xy 303.893994 -310.149748) (xy 303.897954 -310.100694) (xy 303.909731 -310.05291)
			(xy 303.929022 -310.007634) (xy 303.955325 -309.966038) (xy 303.98796 -309.929201) (xy 304.026081 -309.898076)
			(xy 304.068702 -309.873469) (xy 304.114718 -309.856017) (xy 304.162937 -309.846173) (xy 304.212112 -309.844192)
			(xy 304.260967 -309.850124) (xy 304.308238 -309.863816) (xy 304.3527 -309.884914) (xy 304.393203 -309.91287)
			(xy 304.428696 -309.946962) (xy 304.458261 -309.986306) (xy 304.481132 -310.029883) (xy 304.496716 -310.076564)
			(xy 304.504611 -310.125141) (xy 304.505106 -310.149748) (xy 304.843954 -310.149748) (xy 304.847914 -310.100694)
			(xy 304.859691 -310.05291) (xy 304.878982 -310.007634) (xy 304.905285 -309.966038) (xy 304.93792 -309.929201)
			(xy 304.976041 -309.898076) (xy 305.018662 -309.873469) (xy 305.064678 -309.856017) (xy 305.112897 -309.846173)
			(xy 305.162072 -309.844192) (xy 305.210927 -309.850124) (xy 305.258198 -309.863816) (xy 305.30266 -309.884914)
			(xy 305.343163 -309.91287) (xy 305.378656 -309.946962) (xy 305.408221 -309.986306) (xy 305.431092 -310.029883)
			(xy 305.446676 -310.076564) (xy 305.454571 -310.125141) (xy 305.455066 -310.149748) (xy 305.793914 -310.149748)
			(xy 305.797874 -310.100694) (xy 305.809651 -310.05291) (xy 305.828942 -310.007634) (xy 305.855245 -309.966038)
			(xy 305.88788 -309.929201) (xy 305.926001 -309.898076) (xy 305.968622 -309.873469) (xy 306.014638 -309.856017)
			(xy 306.062857 -309.846173) (xy 306.112032 -309.844192) (xy 306.160887 -309.850124) (xy 306.208158 -309.863816)
			(xy 306.25262 -309.884914) (xy 306.293123 -309.91287) (xy 306.328616 -309.946962) (xy 306.358181 -309.986306)
			(xy 306.381052 -310.029883) (xy 306.396636 -310.076564) (xy 306.404531 -310.125141) (xy 306.405026 -310.149748)
			(xy 306.744128 -310.149748) (xy 306.748088 -310.100694) (xy 306.759865 -310.05291) (xy 306.779156 -310.007634)
			(xy 306.805459 -309.966038) (xy 306.838094 -309.929201) (xy 306.876215 -309.898076) (xy 306.918836 -309.873469)
			(xy 306.964852 -309.856017) (xy 307.013071 -309.846173) (xy 307.062246 -309.844192) (xy 307.111101 -309.850124)
			(xy 307.158372 -309.863816) (xy 307.202834 -309.884914) (xy 307.243337 -309.91287) (xy 307.27883 -309.946962)
			(xy 307.308395 -309.986306) (xy 307.331266 -310.029883) (xy 307.34685 -310.076564) (xy 307.354745 -310.125141)
			(xy 307.35524 -310.149748) (xy 307.694088 -310.149748) (xy 307.698048 -310.100694) (xy 307.709825 -310.05291)
			(xy 307.729116 -310.007634) (xy 307.755419 -309.966038) (xy 307.788054 -309.929201) (xy 307.826175 -309.898076)
			(xy 307.868796 -309.873469) (xy 307.914812 -309.856017) (xy 307.963031 -309.846173) (xy 308.012206 -309.844192)
			(xy 308.061061 -309.850124) (xy 308.108332 -309.863816) (xy 308.152794 -309.884914) (xy 308.193297 -309.91287)
			(xy 308.22879 -309.946962) (xy 308.258355 -309.986306) (xy 308.281226 -310.029883) (xy 308.29681 -310.076564)
			(xy 308.304705 -310.125141) (xy 308.3052 -310.149748) (xy 308.644048 -310.149748) (xy 308.648008 -310.100694)
			(xy 308.659785 -310.05291) (xy 308.679076 -310.007634) (xy 308.705379 -309.966038) (xy 308.738014 -309.929201)
			(xy 308.776135 -309.898076) (xy 308.818756 -309.873469) (xy 308.864772 -309.856017) (xy 308.912991 -309.846173)
			(xy 308.962166 -309.844192) (xy 309.011021 -309.850124) (xy 309.058292 -309.863816) (xy 309.102754 -309.884914)
			(xy 309.143257 -309.91287) (xy 309.17875 -309.946962) (xy 309.208315 -309.986306) (xy 309.231186 -310.029883)
			(xy 309.24677 -310.076564) (xy 309.254665 -310.125141) (xy 309.25516 -310.149748) (xy 309.594008 -310.149748)
			(xy 309.597968 -310.100694) (xy 309.609745 -310.05291) (xy 309.629036 -310.007634) (xy 309.655339 -309.966038)
			(xy 309.687974 -309.929201) (xy 309.726095 -309.898076) (xy 309.768716 -309.873469) (xy 309.814732 -309.856017)
			(xy 309.862951 -309.846173) (xy 309.912126 -309.844192) (xy 309.960981 -309.850124) (xy 310.008252 -309.863816)
			(xy 310.052714 -309.884914) (xy 310.093217 -309.91287) (xy 310.12871 -309.946962) (xy 310.158275 -309.986306)
			(xy 310.181146 -310.029883) (xy 310.19673 -310.076564) (xy 310.204625 -310.125141) (xy 310.20512 -310.149748)
			(xy 310.204625 -310.174355) (xy 310.19673 -310.222932) (xy 310.181146 -310.269613) (xy 310.158275 -310.31319)
			(xy 310.12871 -310.352534) (xy 310.093217 -310.386626) (xy 310.052714 -310.414582) (xy 310.008252 -310.43568)
			(xy 309.960981 -310.449372) (xy 309.912126 -310.455304) (xy 309.862951 -310.453323) (xy 309.814732 -310.443479)
			(xy 309.768716 -310.426027) (xy 309.726095 -310.40142) (xy 309.687974 -310.370295) (xy 309.655339 -310.333458)
			(xy 309.629036 -310.291862) (xy 309.609745 -310.246586) (xy 309.597968 -310.198802) (xy 309.594008 -310.149748)
			(xy 309.25516 -310.149748) (xy 309.254665 -310.174355) (xy 309.24677 -310.222932) (xy 309.231186 -310.269613)
			(xy 309.208315 -310.31319) (xy 309.17875 -310.352534) (xy 309.143257 -310.386626) (xy 309.102754 -310.414582)
			(xy 309.058292 -310.43568) (xy 309.011021 -310.449372) (xy 308.962166 -310.455304) (xy 308.912991 -310.453323)
			(xy 308.864772 -310.443479) (xy 308.818756 -310.426027) (xy 308.776135 -310.40142) (xy 308.738014 -310.370295)
			(xy 308.705379 -310.333458) (xy 308.679076 -310.291862) (xy 308.659785 -310.246586) (xy 308.648008 -310.198802)
			(xy 308.644048 -310.149748) (xy 308.3052 -310.149748) (xy 308.304705 -310.174355) (xy 308.29681 -310.222932)
			(xy 308.281226 -310.269613) (xy 308.258355 -310.31319) (xy 308.22879 -310.352534) (xy 308.193297 -310.386626)
			(xy 308.152794 -310.414582) (xy 308.108332 -310.43568) (xy 308.061061 -310.449372) (xy 308.012206 -310.455304)
			(xy 307.963031 -310.453323) (xy 307.914812 -310.443479) (xy 307.868796 -310.426027) (xy 307.826175 -310.40142)
			(xy 307.788054 -310.370295) (xy 307.755419 -310.333458) (xy 307.729116 -310.291862) (xy 307.709825 -310.246586)
			(xy 307.698048 -310.198802) (xy 307.694088 -310.149748) (xy 307.35524 -310.149748) (xy 307.354745 -310.174355)
			(xy 307.34685 -310.222932) (xy 307.331266 -310.269613) (xy 307.308395 -310.31319) (xy 307.27883 -310.352534)
			(xy 307.243337 -310.386626) (xy 307.202834 -310.414582) (xy 307.158372 -310.43568) (xy 307.111101 -310.449372)
			(xy 307.062246 -310.455304) (xy 307.013071 -310.453323) (xy 306.964852 -310.443479) (xy 306.918836 -310.426027)
			(xy 306.876215 -310.40142) (xy 306.838094 -310.370295) (xy 306.805459 -310.333458) (xy 306.779156 -310.291862)
			(xy 306.759865 -310.246586) (xy 306.748088 -310.198802) (xy 306.744128 -310.149748) (xy 306.405026 -310.149748)
			(xy 306.404531 -310.174355) (xy 306.396636 -310.222932) (xy 306.381052 -310.269613) (xy 306.358181 -310.31319)
			(xy 306.328616 -310.352534) (xy 306.293123 -310.386626) (xy 306.25262 -310.414582) (xy 306.208158 -310.43568)
			(xy 306.160887 -310.449372) (xy 306.112032 -310.455304) (xy 306.062857 -310.453323) (xy 306.014638 -310.443479)
			(xy 305.968622 -310.426027) (xy 305.926001 -310.40142) (xy 305.88788 -310.370295) (xy 305.855245 -310.333458)
			(xy 305.828942 -310.291862) (xy 305.809651 -310.246586) (xy 305.797874 -310.198802) (xy 305.793914 -310.149748)
			(xy 305.455066 -310.149748) (xy 305.454571 -310.174355) (xy 305.446676 -310.222932) (xy 305.431092 -310.269613)
			(xy 305.408221 -310.31319) (xy 305.378656 -310.352534) (xy 305.343163 -310.386626) (xy 305.30266 -310.414582)
			(xy 305.258198 -310.43568) (xy 305.210927 -310.449372) (xy 305.162072 -310.455304) (xy 305.112897 -310.453323)
			(xy 305.064678 -310.443479) (xy 305.018662 -310.426027) (xy 304.976041 -310.40142) (xy 304.93792 -310.370295)
			(xy 304.905285 -310.333458) (xy 304.878982 -310.291862) (xy 304.859691 -310.246586) (xy 304.847914 -310.198802)
			(xy 304.843954 -310.149748) (xy 304.505106 -310.149748) (xy 304.504611 -310.174355) (xy 304.496716 -310.222932)
			(xy 304.481132 -310.269613) (xy 304.458261 -310.31319) (xy 304.428696 -310.352534) (xy 304.393203 -310.386626)
			(xy 304.3527 -310.414582) (xy 304.308238 -310.43568) (xy 304.260967 -310.449372) (xy 304.212112 -310.455304)
			(xy 304.162937 -310.453323) (xy 304.114718 -310.443479) (xy 304.068702 -310.426027) (xy 304.026081 -310.40142)
			(xy 303.98796 -310.370295) (xy 303.955325 -310.333458) (xy 303.929022 -310.291862) (xy 303.909731 -310.246586)
			(xy 303.897954 -310.198802) (xy 303.893994 -310.149748) (xy 303.555146 -310.149748) (xy 303.554651 -310.174355)
			(xy 303.546756 -310.222932) (xy 303.531172 -310.269613) (xy 303.508301 -310.31319) (xy 303.478736 -310.352534)
			(xy 303.443243 -310.386626) (xy 303.40274 -310.414582) (xy 303.358278 -310.43568) (xy 303.311007 -310.449372)
			(xy 303.262152 -310.455304) (xy 303.212977 -310.453323) (xy 303.164758 -310.443479) (xy 303.118742 -310.426027)
			(xy 303.076121 -310.40142) (xy 303.038 -310.370295) (xy 303.005365 -310.333458) (xy 302.979062 -310.291862)
			(xy 302.959771 -310.246586) (xy 302.947994 -310.198802) (xy 302.944034 -310.149748) (xy 302.605186 -310.149748)
			(xy 302.604691 -310.174355) (xy 302.596796 -310.222932) (xy 302.581212 -310.269613) (xy 302.558341 -310.31319)
			(xy 302.528776 -310.352534) (xy 302.493283 -310.386626) (xy 302.45278 -310.414582) (xy 302.408318 -310.43568)
			(xy 302.361047 -310.449372) (xy 302.312192 -310.455304) (xy 302.263017 -310.453323) (xy 302.214798 -310.443479)
			(xy 302.168782 -310.426027) (xy 302.126161 -310.40142) (xy 302.08804 -310.370295) (xy 302.055405 -310.333458)
			(xy 302.029102 -310.291862) (xy 302.009811 -310.246586) (xy 301.998034 -310.198802) (xy 301.994074 -310.149748)
			(xy 301.655226 -310.149748) (xy 301.654731 -310.174355) (xy 301.646836 -310.222932) (xy 301.631252 -310.269613)
			(xy 301.608381 -310.31319) (xy 301.578816 -310.352534) (xy 301.543323 -310.386626) (xy 301.50282 -310.414582)
			(xy 301.458358 -310.43568) (xy 301.411087 -310.449372) (xy 301.362232 -310.455304) (xy 301.313057 -310.453323)
			(xy 301.264838 -310.443479) (xy 301.218822 -310.426027) (xy 301.176201 -310.40142) (xy 301.13808 -310.370295)
			(xy 301.105445 -310.333458) (xy 301.079142 -310.291862) (xy 301.059851 -310.246586) (xy 301.048074 -310.198802)
			(xy 301.044114 -310.149748) (xy 300.705012 -310.149748) (xy 300.704517 -310.174355) (xy 300.696622 -310.222932)
			(xy 300.681038 -310.269613) (xy 300.658167 -310.31319) (xy 300.628602 -310.352534) (xy 300.593109 -310.386626)
			(xy 300.552606 -310.414582) (xy 300.508144 -310.43568) (xy 300.460873 -310.449372) (xy 300.412018 -310.455304)
			(xy 300.362843 -310.453323) (xy 300.314624 -310.443479) (xy 300.268608 -310.426027) (xy 300.225987 -310.40142)
			(xy 300.187866 -310.370295) (xy 300.155231 -310.333458) (xy 300.128928 -310.291862) (xy 300.109637 -310.246586)
			(xy 300.09786 -310.198802) (xy 300.0939 -310.149748) (xy 299.755052 -310.149748) (xy 299.754557 -310.174355)
			(xy 299.746662 -310.222932) (xy 299.731078 -310.269613) (xy 299.708207 -310.31319) (xy 299.678642 -310.352534)
			(xy 299.643149 -310.386626) (xy 299.602646 -310.414582) (xy 299.558184 -310.43568) (xy 299.510913 -310.449372)
			(xy 299.462058 -310.455304) (xy 299.412883 -310.453323) (xy 299.364664 -310.443479) (xy 299.318648 -310.426027)
			(xy 299.276027 -310.40142) (xy 299.237906 -310.370295) (xy 299.205271 -310.333458) (xy 299.178968 -310.291862)
			(xy 299.159677 -310.246586) (xy 299.1479 -310.198802) (xy 299.14394 -310.149748) (xy 298.805092 -310.149748)
			(xy 298.804597 -310.174355) (xy 298.796702 -310.222932) (xy 298.781118 -310.269613) (xy 298.758247 -310.31319)
			(xy 298.728682 -310.352534) (xy 298.693189 -310.386626) (xy 298.652686 -310.414582) (xy 298.608224 -310.43568)
			(xy 298.560953 -310.449372) (xy 298.512098 -310.455304) (xy 298.462923 -310.453323) (xy 298.414704 -310.443479)
			(xy 298.368688 -310.426027) (xy 298.326067 -310.40142) (xy 298.287946 -310.370295) (xy 298.255311 -310.333458)
			(xy 298.229008 -310.291862) (xy 298.209717 -310.246586) (xy 298.19794 -310.198802) (xy 298.19398 -310.149748)
			(xy 297.855132 -310.149748) (xy 297.854637 -310.174355) (xy 297.846742 -310.222932) (xy 297.831158 -310.269613)
			(xy 297.808287 -310.31319) (xy 297.778722 -310.352534) (xy 297.743229 -310.386626) (xy 297.702726 -310.414582)
			(xy 297.658264 -310.43568) (xy 297.610993 -310.449372) (xy 297.562138 -310.455304) (xy 297.512963 -310.453323)
			(xy 297.464744 -310.443479) (xy 297.418728 -310.426027) (xy 297.376107 -310.40142) (xy 297.337986 -310.370295)
			(xy 297.305351 -310.333458) (xy 297.279048 -310.291862) (xy 297.259757 -310.246586) (xy 297.24798 -310.198802)
			(xy 297.24402 -310.149748) (xy 296.905172 -310.149748) (xy 296.904677 -310.174355) (xy 296.896782 -310.222932)
			(xy 296.881198 -310.269613) (xy 296.858327 -310.31319) (xy 296.828762 -310.352534) (xy 296.793269 -310.386626)
			(xy 296.752766 -310.414582) (xy 296.708304 -310.43568) (xy 296.661033 -310.449372) (xy 296.612178 -310.455304)
			(xy 296.563003 -310.453323) (xy 296.514784 -310.443479) (xy 296.468768 -310.426027) (xy 296.426147 -310.40142)
			(xy 296.388026 -310.370295) (xy 296.355391 -310.333458) (xy 296.329088 -310.291862) (xy 296.309797 -310.246586)
			(xy 296.29802 -310.198802) (xy 296.29406 -310.149748) (xy 295.955212 -310.149748) (xy 295.954717 -310.174355)
			(xy 295.946822 -310.222932) (xy 295.931238 -310.269613) (xy 295.908367 -310.31319) (xy 295.878802 -310.352534)
			(xy 295.843309 -310.386626) (xy 295.802806 -310.414582) (xy 295.758344 -310.43568) (xy 295.711073 -310.449372)
			(xy 295.662218 -310.455304) (xy 295.613043 -310.453323) (xy 295.564824 -310.443479) (xy 295.518808 -310.426027)
			(xy 295.476187 -310.40142) (xy 295.438066 -310.370295) (xy 295.405431 -310.333458) (xy 295.379128 -310.291862)
			(xy 295.359837 -310.246586) (xy 295.34806 -310.198802) (xy 295.3441 -310.149748) (xy 295.004998 -310.149748)
			(xy 295.004503 -310.174355) (xy 294.996608 -310.222932) (xy 294.981024 -310.269613) (xy 294.958153 -310.31319)
			(xy 294.928588 -310.352534) (xy 294.893095 -310.386626) (xy 294.852592 -310.414582) (xy 294.80813 -310.43568)
			(xy 294.760859 -310.449372) (xy 294.712004 -310.455304) (xy 294.662829 -310.453323) (xy 294.61461 -310.443479)
			(xy 294.568594 -310.426027) (xy 294.525973 -310.40142) (xy 294.487852 -310.370295) (xy 294.455217 -310.333458)
			(xy 294.428914 -310.291862) (xy 294.409623 -310.246586) (xy 294.397846 -310.198802) (xy 294.393886 -310.149748)
			(xy 294.055038 -310.149748) (xy 294.054543 -310.174355) (xy 294.046648 -310.222932) (xy 294.031064 -310.269613)
			(xy 294.008193 -310.31319) (xy 293.978628 -310.352534) (xy 293.943135 -310.386626) (xy 293.902632 -310.414582)
			(xy 293.85817 -310.43568) (xy 293.810899 -310.449372) (xy 293.762044 -310.455304) (xy 293.712869 -310.453323)
			(xy 293.66465 -310.443479) (xy 293.618634 -310.426027) (xy 293.576013 -310.40142) (xy 293.537892 -310.370295)
			(xy 293.505257 -310.333458) (xy 293.478954 -310.291862) (xy 293.459663 -310.246586) (xy 293.447886 -310.198802)
			(xy 293.443926 -310.149748) (xy 293.105078 -310.149748) (xy 293.104583 -310.174355) (xy 293.096688 -310.222932)
			(xy 293.081104 -310.269613) (xy 293.058233 -310.31319) (xy 293.028668 -310.352534) (xy 292.993175 -310.386626)
			(xy 292.952672 -310.414582) (xy 292.90821 -310.43568) (xy 292.860939 -310.449372) (xy 292.812084 -310.455304)
			(xy 292.762909 -310.453323) (xy 292.71469 -310.443479) (xy 292.668674 -310.426027) (xy 292.626053 -310.40142)
			(xy 292.587932 -310.370295) (xy 292.555297 -310.333458) (xy 292.528994 -310.291862) (xy 292.509703 -310.246586)
			(xy 292.497926 -310.198802) (xy 292.493966 -310.149748) (xy 292.155118 -310.149748) (xy 292.154623 -310.174355)
			(xy 292.146728 -310.222932) (xy 292.131144 -310.269613) (xy 292.108273 -310.31319) (xy 292.078708 -310.352534)
			(xy 292.043215 -310.386626) (xy 292.002712 -310.414582) (xy 291.95825 -310.43568) (xy 291.910979 -310.449372)
			(xy 291.862124 -310.455304) (xy 291.812949 -310.453323) (xy 291.76473 -310.443479) (xy 291.718714 -310.426027)
			(xy 291.676093 -310.40142) (xy 291.637972 -310.370295) (xy 291.605337 -310.333458) (xy 291.579034 -310.291862)
			(xy 291.559743 -310.246586) (xy 291.547966 -310.198802) (xy 291.544006 -310.149748) (xy 291.205158 -310.149748)
			(xy 291.204663 -310.174355) (xy 291.196768 -310.222932) (xy 291.181184 -310.269613) (xy 291.158313 -310.31319)
			(xy 291.128748 -310.352534) (xy 291.093255 -310.386626) (xy 291.052752 -310.414582) (xy 291.00829 -310.43568)
			(xy 290.961019 -310.449372) (xy 290.912164 -310.455304) (xy 290.862989 -310.453323) (xy 290.81477 -310.443479)
			(xy 290.768754 -310.426027) (xy 290.726133 -310.40142) (xy 290.688012 -310.370295) (xy 290.655377 -310.333458)
			(xy 290.629074 -310.291862) (xy 290.609783 -310.246586) (xy 290.598006 -310.198802) (xy 290.594046 -310.149748)
			(xy 290.255198 -310.149748) (xy 290.254703 -310.174355) (xy 290.246808 -310.222932) (xy 290.231224 -310.269613)
			(xy 290.208353 -310.31319) (xy 290.178788 -310.352534) (xy 290.143295 -310.386626) (xy 290.102792 -310.414582)
			(xy 290.05833 -310.43568) (xy 290.011059 -310.449372) (xy 289.962204 -310.455304) (xy 289.913029 -310.453323)
			(xy 289.86481 -310.443479) (xy 289.818794 -310.426027) (xy 289.776173 -310.40142) (xy 289.738052 -310.370295)
			(xy 289.705417 -310.333458) (xy 289.679114 -310.291862) (xy 289.659823 -310.246586) (xy 289.648046 -310.198802)
			(xy 289.644086 -310.149748) (xy 289.305238 -310.149748) (xy 289.304743 -310.174355) (xy 289.296848 -310.222932)
			(xy 289.281264 -310.269613) (xy 289.258393 -310.31319) (xy 289.228828 -310.352534) (xy 289.193335 -310.386626)
			(xy 289.152832 -310.414582) (xy 289.10837 -310.43568) (xy 289.061099 -310.449372) (xy 289.012244 -310.455304)
			(xy 288.963069 -310.453323) (xy 288.91485 -310.443479) (xy 288.868834 -310.426027) (xy 288.826213 -310.40142)
			(xy 288.788092 -310.370295) (xy 288.755457 -310.333458) (xy 288.729154 -310.291862) (xy 288.709863 -310.246586)
			(xy 288.698086 -310.198802) (xy 288.694126 -310.149748) (xy 288.355024 -310.149748) (xy 288.354529 -310.174355)
			(xy 288.346634 -310.222932) (xy 288.33105 -310.269613) (xy 288.308179 -310.31319) (xy 288.278614 -310.352534)
			(xy 288.243121 -310.386626) (xy 288.202618 -310.414582) (xy 288.158156 -310.43568) (xy 288.110885 -310.449372)
			(xy 288.06203 -310.455304) (xy 288.012855 -310.453323) (xy 287.964636 -310.443479) (xy 287.91862 -310.426027)
			(xy 287.875999 -310.40142) (xy 287.837878 -310.370295) (xy 287.805243 -310.333458) (xy 287.77894 -310.291862)
			(xy 287.759649 -310.246586) (xy 287.747872 -310.198802) (xy 287.743912 -310.149748) (xy 287.405064 -310.149748)
			(xy 287.404569 -310.174355) (xy 287.396674 -310.222932) (xy 287.38109 -310.269613) (xy 287.358219 -310.31319)
			(xy 287.328654 -310.352534) (xy 287.293161 -310.386626) (xy 287.252658 -310.414582) (xy 287.208196 -310.43568)
			(xy 287.160925 -310.449372) (xy 287.11207 -310.455304) (xy 287.062895 -310.453323) (xy 287.014676 -310.443479)
			(xy 286.96866 -310.426027) (xy 286.926039 -310.40142) (xy 286.887918 -310.370295) (xy 286.855283 -310.333458)
			(xy 286.82898 -310.291862) (xy 286.809689 -310.246586) (xy 286.797912 -310.198802) (xy 286.793952 -310.149748)
			(xy 286.455104 -310.149748) (xy 286.454609 -310.174355) (xy 286.446714 -310.222932) (xy 286.43113 -310.269613)
			(xy 286.408259 -310.31319) (xy 286.378694 -310.352534) (xy 286.343201 -310.386626) (xy 286.302698 -310.414582)
			(xy 286.258236 -310.43568) (xy 286.210965 -310.449372) (xy 286.16211 -310.455304) (xy 286.112935 -310.453323)
			(xy 286.064716 -310.443479) (xy 286.0187 -310.426027) (xy 285.976079 -310.40142) (xy 285.937958 -310.370295)
			(xy 285.905323 -310.333458) (xy 285.87902 -310.291862) (xy 285.859729 -310.246586) (xy 285.847952 -310.198802)
			(xy 285.843992 -310.149748) (xy 285.505144 -310.149748) (xy 285.504649 -310.174355) (xy 285.496754 -310.222932)
			(xy 285.48117 -310.269613) (xy 285.458299 -310.31319) (xy 285.428734 -310.352534) (xy 285.393241 -310.386626)
			(xy 285.352738 -310.414582) (xy 285.308276 -310.43568) (xy 285.261005 -310.449372) (xy 285.21215 -310.455304)
			(xy 285.162975 -310.453323) (xy 285.114756 -310.443479) (xy 285.06874 -310.426027) (xy 285.026119 -310.40142)
			(xy 284.987998 -310.370295) (xy 284.955363 -310.333458) (xy 284.92906 -310.291862) (xy 284.909769 -310.246586)
			(xy 284.897992 -310.198802) (xy 284.894032 -310.149748) (xy 284.555184 -310.149748) (xy 284.554689 -310.174355)
			(xy 284.546794 -310.222932) (xy 284.53121 -310.269613) (xy 284.508339 -310.31319) (xy 284.478774 -310.352534)
			(xy 284.443281 -310.386626) (xy 284.402778 -310.414582) (xy 284.358316 -310.43568) (xy 284.311045 -310.449372)
			(xy 284.26219 -310.455304) (xy 284.213015 -310.453323) (xy 284.164796 -310.443479) (xy 284.11878 -310.426027)
			(xy 284.076159 -310.40142) (xy 284.038038 -310.370295) (xy 284.005403 -310.333458) (xy 283.9791 -310.291862)
			(xy 283.959809 -310.246586) (xy 283.948032 -310.198802) (xy 283.944072 -310.149748) (xy 283.605224 -310.149748)
			(xy 283.604729 -310.174355) (xy 283.596834 -310.222932) (xy 283.58125 -310.269613) (xy 283.558379 -310.31319)
			(xy 283.528814 -310.352534) (xy 283.493321 -310.386626) (xy 283.452818 -310.414582) (xy 283.408356 -310.43568)
			(xy 283.361085 -310.449372) (xy 283.31223 -310.455304) (xy 283.263055 -310.453323) (xy 283.214836 -310.443479)
			(xy 283.16882 -310.426027) (xy 283.126199 -310.40142) (xy 283.088078 -310.370295) (xy 283.055443 -310.333458)
			(xy 283.02914 -310.291862) (xy 283.009849 -310.246586) (xy 282.998072 -310.198802) (xy 282.994112 -310.149748)
			(xy 282.655479 -310.149748) (xy 282.651313 -310.20003) (xy 282.638915 -310.248987) (xy 282.618628 -310.295236)
			(xy 282.591006 -310.337515) (xy 282.556802 -310.374671) (xy 282.516949 -310.405691) (xy 282.472533 -310.429727)
			(xy 282.424767 -310.446126) (xy 282.374953 -310.454438) (xy 282.349702 -310.455056) (xy 282.327858 -310.454294)
			(xy 282.317444 -310.453532) (xy 282.297632 -310.46039) (xy 282.235402 -310.518556) (xy 282.228058 -310.526024)
			(xy 282.219642 -310.545179) (xy 282.219146 -310.55564) (xy 282.219146 -310.69407) (xy 282.219716 -310.704513)
			(xy 282.228121 -310.723643) (xy 282.235402 -310.731154) (xy 282.297632 -310.78932) (xy 282.317444 -310.796178)
			(xy 282.327858 -310.795416) (xy 282.349702 -310.794654) (xy 282.37496 -310.795176) (xy 282.424788 -310.803491)
			(xy 282.472568 -310.819894) (xy 282.516996 -310.843937) (xy 282.55686 -310.874966) (xy 282.591074 -310.912132)
			(xy 282.618704 -310.954423) (xy 282.638996 -311.000685) (xy 282.651397 -311.049656) (xy 282.655566 -311.099962)
			(xy 282.994112 -311.099962) (xy 282.998072 -311.050908) (xy 283.009849 -311.003124) (xy 283.02914 -310.957848)
			(xy 283.055443 -310.916252) (xy 283.088078 -310.879415) (xy 283.126199 -310.84829) (xy 283.16882 -310.823683)
			(xy 283.214836 -310.806231) (xy 283.263055 -310.796387) (xy 283.31223 -310.794406) (xy 283.361085 -310.800338)
			(xy 283.408356 -310.81403) (xy 283.452818 -310.835128) (xy 283.493321 -310.863084) (xy 283.528814 -310.897176)
			(xy 283.558379 -310.93652) (xy 283.58125 -310.980097) (xy 283.596834 -311.026778) (xy 283.604729 -311.075355)
			(xy 283.605224 -311.099962) (xy 283.944072 -311.099962) (xy 283.948032 -311.050908) (xy 283.959809 -311.003124)
			(xy 283.9791 -310.957848) (xy 284.005403 -310.916252) (xy 284.038038 -310.879415) (xy 284.076159 -310.84829)
			(xy 284.11878 -310.823683) (xy 284.164796 -310.806231) (xy 284.213015 -310.796387) (xy 284.26219 -310.794406)
			(xy 284.311045 -310.800338) (xy 284.358316 -310.81403) (xy 284.402778 -310.835128) (xy 284.443281 -310.863084)
			(xy 284.478774 -310.897176) (xy 284.508339 -310.93652) (xy 284.53121 -310.980097) (xy 284.546794 -311.026778)
			(xy 284.554689 -311.075355) (xy 284.555184 -311.099962) (xy 284.894032 -311.099962) (xy 284.897992 -311.050908)
			(xy 284.909769 -311.003124) (xy 284.92906 -310.957848) (xy 284.955363 -310.916252) (xy 284.987998 -310.879415)
			(xy 285.026119 -310.84829) (xy 285.06874 -310.823683) (xy 285.114756 -310.806231) (xy 285.162975 -310.796387)
			(xy 285.21215 -310.794406) (xy 285.261005 -310.800338) (xy 285.308276 -310.81403) (xy 285.352738 -310.835128)
			(xy 285.393241 -310.863084) (xy 285.428734 -310.897176) (xy 285.458299 -310.93652) (xy 285.48117 -310.980097)
			(xy 285.496754 -311.026778) (xy 285.504649 -311.075355) (xy 285.505144 -311.099962) (xy 285.843992 -311.099962)
			(xy 285.847952 -311.050908) (xy 285.859729 -311.003124) (xy 285.87902 -310.957848) (xy 285.905323 -310.916252)
			(xy 285.937958 -310.879415) (xy 285.976079 -310.84829) (xy 286.0187 -310.823683) (xy 286.064716 -310.806231)
			(xy 286.112935 -310.796387) (xy 286.16211 -310.794406) (xy 286.210965 -310.800338) (xy 286.258236 -310.81403)
			(xy 286.302698 -310.835128) (xy 286.343201 -310.863084) (xy 286.378694 -310.897176) (xy 286.408259 -310.93652)
			(xy 286.43113 -310.980097) (xy 286.446714 -311.026778) (xy 286.454609 -311.075355) (xy 286.455104 -311.099962)
			(xy 286.793952 -311.099962) (xy 286.797912 -311.050908) (xy 286.809689 -311.003124) (xy 286.82898 -310.957848)
			(xy 286.855283 -310.916252) (xy 286.887918 -310.879415) (xy 286.926039 -310.84829) (xy 286.96866 -310.823683)
			(xy 287.014676 -310.806231) (xy 287.062895 -310.796387) (xy 287.11207 -310.794406) (xy 287.160925 -310.800338)
			(xy 287.208196 -310.81403) (xy 287.252658 -310.835128) (xy 287.293161 -310.863084) (xy 287.328654 -310.897176)
			(xy 287.358219 -310.93652) (xy 287.38109 -310.980097) (xy 287.396674 -311.026778) (xy 287.404569 -311.075355)
			(xy 287.405064 -311.099962) (xy 287.743912 -311.099962) (xy 287.747872 -311.050908) (xy 287.759649 -311.003124)
			(xy 287.77894 -310.957848) (xy 287.805243 -310.916252) (xy 287.837878 -310.879415) (xy 287.875999 -310.84829)
			(xy 287.91862 -310.823683) (xy 287.964636 -310.806231) (xy 288.012855 -310.796387) (xy 288.06203 -310.794406)
			(xy 288.110885 -310.800338) (xy 288.158156 -310.81403) (xy 288.202618 -310.835128) (xy 288.243121 -310.863084)
			(xy 288.278614 -310.897176) (xy 288.308179 -310.93652) (xy 288.33105 -310.980097) (xy 288.346634 -311.026778)
			(xy 288.354529 -311.075355) (xy 288.355024 -311.099962) (xy 288.694126 -311.099962) (xy 288.698086 -311.050908)
			(xy 288.709863 -311.003124) (xy 288.729154 -310.957848) (xy 288.755457 -310.916252) (xy 288.788092 -310.879415)
			(xy 288.826213 -310.84829) (xy 288.868834 -310.823683) (xy 288.91485 -310.806231) (xy 288.963069 -310.796387)
			(xy 289.012244 -310.794406) (xy 289.061099 -310.800338) (xy 289.10837 -310.81403) (xy 289.152832 -310.835128)
			(xy 289.193335 -310.863084) (xy 289.228828 -310.897176) (xy 289.258393 -310.93652) (xy 289.281264 -310.980097)
			(xy 289.296848 -311.026778) (xy 289.304743 -311.075355) (xy 289.305238 -311.099962) (xy 289.644086 -311.099962)
			(xy 289.648046 -311.050908) (xy 289.659823 -311.003124) (xy 289.679114 -310.957848) (xy 289.705417 -310.916252)
			(xy 289.738052 -310.879415) (xy 289.776173 -310.84829) (xy 289.818794 -310.823683) (xy 289.86481 -310.806231)
			(xy 289.913029 -310.796387) (xy 289.962204 -310.794406) (xy 290.011059 -310.800338) (xy 290.05833 -310.81403)
			(xy 290.102792 -310.835128) (xy 290.143295 -310.863084) (xy 290.178788 -310.897176) (xy 290.208353 -310.93652)
			(xy 290.231224 -310.980097) (xy 290.246808 -311.026778) (xy 290.254703 -311.075355) (xy 290.255198 -311.099962)
			(xy 290.254703 -311.124569) (xy 290.254524 -311.12567) (xy 290.573202 -311.12567) (xy 290.573202 -311.074254)
			(xy 290.581245 -311.023472) (xy 290.597133 -310.974573) (xy 290.620476 -310.928761) (xy 290.650697 -310.887165)
			(xy 290.687053 -310.850809) (xy 290.728649 -310.820588) (xy 290.774461 -310.797245) (xy 290.82336 -310.781357)
			(xy 290.874142 -310.773314) (xy 290.925558 -310.773314) (xy 290.97634 -310.781357) (xy 291.025239 -310.797245)
			(xy 291.071051 -310.820588) (xy 291.112647 -310.850809) (xy 291.149003 -310.887165) (xy 291.179224 -310.928761)
			(xy 291.202567 -310.974573) (xy 291.218455 -311.023472) (xy 291.226498 -311.074254) (xy 291.227002 -311.099962)
			(xy 291.544006 -311.099962) (xy 291.547966 -311.050908) (xy 291.559743 -311.003124) (xy 291.579034 -310.957848)
			(xy 291.605337 -310.916252) (xy 291.637972 -310.879415) (xy 291.676093 -310.84829) (xy 291.718714 -310.823683)
			(xy 291.76473 -310.806231) (xy 291.812949 -310.796387) (xy 291.862124 -310.794406) (xy 291.910979 -310.800338)
			(xy 291.95825 -310.81403) (xy 292.002712 -310.835128) (xy 292.043215 -310.863084) (xy 292.078708 -310.897176)
			(xy 292.108273 -310.93652) (xy 292.131144 -310.980097) (xy 292.146728 -311.026778) (xy 292.154623 -311.075355)
			(xy 292.155118 -311.099962) (xy 292.154623 -311.124569) (xy 292.154444 -311.12567) (xy 292.473122 -311.12567)
			(xy 292.473122 -311.074254) (xy 292.481165 -311.023472) (xy 292.497053 -310.974573) (xy 292.520396 -310.928761)
			(xy 292.550617 -310.887165) (xy 292.586973 -310.850809) (xy 292.628569 -310.820588) (xy 292.674381 -310.797245)
			(xy 292.72328 -310.781357) (xy 292.774062 -310.773314) (xy 292.825478 -310.773314) (xy 292.87626 -310.781357)
			(xy 292.925159 -310.797245) (xy 292.970971 -310.820588) (xy 293.012567 -310.850809) (xy 293.048923 -310.887165)
			(xy 293.079144 -310.928761) (xy 293.102487 -310.974573) (xy 293.118375 -311.023472) (xy 293.126418 -311.074254)
			(xy 293.126922 -311.099962) (xy 293.443926 -311.099962) (xy 293.447886 -311.050908) (xy 293.459663 -311.003124)
			(xy 293.478954 -310.957848) (xy 293.505257 -310.916252) (xy 293.537892 -310.879415) (xy 293.576013 -310.84829)
			(xy 293.618634 -310.823683) (xy 293.66465 -310.806231) (xy 293.712869 -310.796387) (xy 293.762044 -310.794406)
			(xy 293.810899 -310.800338) (xy 293.85817 -310.81403) (xy 293.902632 -310.835128) (xy 293.943135 -310.863084)
			(xy 293.978628 -310.897176) (xy 294.008193 -310.93652) (xy 294.031064 -310.980097) (xy 294.046648 -311.026778)
			(xy 294.054543 -311.075355) (xy 294.055038 -311.099962) (xy 294.054543 -311.124569) (xy 294.054364 -311.12567)
			(xy 294.373042 -311.12567) (xy 294.373042 -311.074254) (xy 294.381085 -311.023472) (xy 294.396973 -310.974573)
			(xy 294.420316 -310.928761) (xy 294.450537 -310.887165) (xy 294.486893 -310.850809) (xy 294.528489 -310.820588)
			(xy 294.574301 -310.797245) (xy 294.6232 -310.781357) (xy 294.673982 -310.773314) (xy 294.725398 -310.773314)
			(xy 294.77618 -310.781357) (xy 294.825079 -310.797245) (xy 294.870891 -310.820588) (xy 294.912487 -310.850809)
			(xy 294.948843 -310.887165) (xy 294.979064 -310.928761) (xy 295.002407 -310.974573) (xy 295.018295 -311.023472)
			(xy 295.026338 -311.074254) (xy 295.026842 -311.099962) (xy 295.3441 -311.099962) (xy 295.34806 -311.050908)
			(xy 295.359837 -311.003124) (xy 295.379128 -310.957848) (xy 295.405431 -310.916252) (xy 295.438066 -310.879415)
			(xy 295.476187 -310.84829) (xy 295.518808 -310.823683) (xy 295.564824 -310.806231) (xy 295.613043 -310.796387)
			(xy 295.662218 -310.794406) (xy 295.711073 -310.800338) (xy 295.758344 -310.81403) (xy 295.802806 -310.835128)
			(xy 295.843309 -310.863084) (xy 295.878802 -310.897176) (xy 295.908367 -310.93652) (xy 295.931238 -310.980097)
			(xy 295.946822 -311.026778) (xy 295.954717 -311.075355) (xy 295.955212 -311.099962) (xy 295.954717 -311.124569)
			(xy 295.954538 -311.12567) (xy 296.273216 -311.12567) (xy 296.273216 -311.074254) (xy 296.281259 -311.023472)
			(xy 296.297147 -310.974573) (xy 296.32049 -310.928761) (xy 296.350711 -310.887165) (xy 296.387067 -310.850809)
			(xy 296.428663 -310.820588) (xy 296.474475 -310.797245) (xy 296.523374 -310.781357) (xy 296.574156 -310.773314)
			(xy 296.625572 -310.773314) (xy 296.676354 -310.781357) (xy 296.725253 -310.797245) (xy 296.771065 -310.820588)
			(xy 296.812661 -310.850809) (xy 296.849017 -310.887165) (xy 296.879238 -310.928761) (xy 296.902581 -310.974573)
			(xy 296.918469 -311.023472) (xy 296.926512 -311.074254) (xy 296.927016 -311.099962) (xy 297.24402 -311.099962)
			(xy 297.24798 -311.050908) (xy 297.259757 -311.003124) (xy 297.279048 -310.957848) (xy 297.305351 -310.916252)
			(xy 297.337986 -310.879415) (xy 297.376107 -310.84829) (xy 297.418728 -310.823683) (xy 297.464744 -310.806231)
			(xy 297.512963 -310.796387) (xy 297.562138 -310.794406) (xy 297.610993 -310.800338) (xy 297.658264 -310.81403)
			(xy 297.702726 -310.835128) (xy 297.743229 -310.863084) (xy 297.778722 -310.897176) (xy 297.808287 -310.93652)
			(xy 297.831158 -310.980097) (xy 297.846742 -311.026778) (xy 297.854637 -311.075355) (xy 297.855132 -311.099962)
			(xy 297.854637 -311.124569) (xy 297.854458 -311.12567) (xy 298.173136 -311.12567) (xy 298.173136 -311.074254)
			(xy 298.181179 -311.023472) (xy 298.197067 -310.974573) (xy 298.22041 -310.928761) (xy 298.250631 -310.887165)
			(xy 298.286987 -310.850809) (xy 298.328583 -310.820588) (xy 298.374395 -310.797245) (xy 298.423294 -310.781357)
			(xy 298.474076 -310.773314) (xy 298.525492 -310.773314) (xy 298.576274 -310.781357) (xy 298.625173 -310.797245)
			(xy 298.670985 -310.820588) (xy 298.712581 -310.850809) (xy 298.748937 -310.887165) (xy 298.779158 -310.928761)
			(xy 298.802501 -310.974573) (xy 298.818389 -311.023472) (xy 298.826432 -311.074254) (xy 298.826936 -311.099962)
			(xy 299.14394 -311.099962) (xy 299.1479 -311.050908) (xy 299.159677 -311.003124) (xy 299.178968 -310.957848)
			(xy 299.205271 -310.916252) (xy 299.237906 -310.879415) (xy 299.276027 -310.84829) (xy 299.318648 -310.823683)
			(xy 299.364664 -310.806231) (xy 299.412883 -310.796387) (xy 299.462058 -310.794406) (xy 299.510913 -310.800338)
			(xy 299.558184 -310.81403) (xy 299.602646 -310.835128) (xy 299.643149 -310.863084) (xy 299.678642 -310.897176)
			(xy 299.708207 -310.93652) (xy 299.731078 -310.980097) (xy 299.746662 -311.026778) (xy 299.754557 -311.075355)
			(xy 299.755052 -311.099962) (xy 299.754557 -311.124569) (xy 299.754378 -311.12567) (xy 300.073056 -311.12567)
			(xy 300.073056 -311.074254) (xy 300.081099 -311.023472) (xy 300.096987 -310.974573) (xy 300.12033 -310.928761)
			(xy 300.150551 -310.887165) (xy 300.186907 -310.850809) (xy 300.228503 -310.820588) (xy 300.274315 -310.797245)
			(xy 300.323214 -310.781357) (xy 300.373996 -310.773314) (xy 300.425412 -310.773314) (xy 300.476194 -310.781357)
			(xy 300.525093 -310.797245) (xy 300.570905 -310.820588) (xy 300.612501 -310.850809) (xy 300.648857 -310.887165)
			(xy 300.679078 -310.928761) (xy 300.702421 -310.974573) (xy 300.718309 -311.023472) (xy 300.726352 -311.074254)
			(xy 300.726856 -311.099962) (xy 301.044114 -311.099962) (xy 301.048074 -311.050908) (xy 301.059851 -311.003124)
			(xy 301.079142 -310.957848) (xy 301.105445 -310.916252) (xy 301.13808 -310.879415) (xy 301.176201 -310.84829)
			(xy 301.218822 -310.823683) (xy 301.264838 -310.806231) (xy 301.313057 -310.796387) (xy 301.362232 -310.794406)
			(xy 301.411087 -310.800338) (xy 301.458358 -310.81403) (xy 301.50282 -310.835128) (xy 301.543323 -310.863084)
			(xy 301.578816 -310.897176) (xy 301.608381 -310.93652) (xy 301.631252 -310.980097) (xy 301.646836 -311.026778)
			(xy 301.654731 -311.075355) (xy 301.655226 -311.099962) (xy 301.654731 -311.124569) (xy 301.654552 -311.12567)
			(xy 301.97323 -311.12567) (xy 301.97323 -311.074254) (xy 301.981273 -311.023472) (xy 301.997161 -310.974573)
			(xy 302.020504 -310.928761) (xy 302.050725 -310.887165) (xy 302.087081 -310.850809) (xy 302.128677 -310.820588)
			(xy 302.174489 -310.797245) (xy 302.223388 -310.781357) (xy 302.27417 -310.773314) (xy 302.325586 -310.773314)
			(xy 302.376368 -310.781357) (xy 302.425267 -310.797245) (xy 302.471079 -310.820588) (xy 302.512675 -310.850809)
			(xy 302.549031 -310.887165) (xy 302.579252 -310.928761) (xy 302.602595 -310.974573) (xy 302.618483 -311.023472)
			(xy 302.626526 -311.074254) (xy 302.62703 -311.099962) (xy 302.944034 -311.099962) (xy 302.947994 -311.050908)
			(xy 302.959771 -311.003124) (xy 302.979062 -310.957848) (xy 303.005365 -310.916252) (xy 303.038 -310.879415)
			(xy 303.076121 -310.84829) (xy 303.118742 -310.823683) (xy 303.164758 -310.806231) (xy 303.212977 -310.796387)
			(xy 303.262152 -310.794406) (xy 303.311007 -310.800338) (xy 303.358278 -310.81403) (xy 303.40274 -310.835128)
			(xy 303.443243 -310.863084) (xy 303.478736 -310.897176) (xy 303.508301 -310.93652) (xy 303.531172 -310.980097)
			(xy 303.546756 -311.026778) (xy 303.554651 -311.075355) (xy 303.555146 -311.099962) (xy 303.554651 -311.124569)
			(xy 303.554472 -311.12567) (xy 303.87315 -311.12567) (xy 303.87315 -311.074254) (xy 303.881193 -311.023472)
			(xy 303.897081 -310.974573) (xy 303.920424 -310.928761) (xy 303.950645 -310.887165) (xy 303.987001 -310.850809)
			(xy 304.028597 -310.820588) (xy 304.074409 -310.797245) (xy 304.123308 -310.781357) (xy 304.17409 -310.773314)
			(xy 304.225506 -310.773314) (xy 304.276288 -310.781357) (xy 304.325187 -310.797245) (xy 304.370999 -310.820588)
			(xy 304.412595 -310.850809) (xy 304.448951 -310.887165) (xy 304.479172 -310.928761) (xy 304.502515 -310.974573)
			(xy 304.518403 -311.023472) (xy 304.526446 -311.074254) (xy 304.52695 -311.099962) (xy 304.843954 -311.099962)
			(xy 304.847914 -311.050908) (xy 304.859691 -311.003124) (xy 304.878982 -310.957848) (xy 304.905285 -310.916252)
			(xy 304.93792 -310.879415) (xy 304.976041 -310.84829) (xy 305.018662 -310.823683) (xy 305.064678 -310.806231)
			(xy 305.112897 -310.796387) (xy 305.162072 -310.794406) (xy 305.210927 -310.800338) (xy 305.258198 -310.81403)
			(xy 305.30266 -310.835128) (xy 305.343163 -310.863084) (xy 305.378656 -310.897176) (xy 305.408221 -310.93652)
			(xy 305.431092 -310.980097) (xy 305.446676 -311.026778) (xy 305.454571 -311.075355) (xy 305.455066 -311.099962)
			(xy 305.793914 -311.099962) (xy 305.797874 -311.050908) (xy 305.809651 -311.003124) (xy 305.828942 -310.957848)
			(xy 305.855245 -310.916252) (xy 305.88788 -310.879415) (xy 305.926001 -310.84829) (xy 305.968622 -310.823683)
			(xy 306.014638 -310.806231) (xy 306.062857 -310.796387) (xy 306.112032 -310.794406) (xy 306.160887 -310.800338)
			(xy 306.208158 -310.81403) (xy 306.25262 -310.835128) (xy 306.293123 -310.863084) (xy 306.328616 -310.897176)
			(xy 306.358181 -310.93652) (xy 306.381052 -310.980097) (xy 306.396636 -311.026778) (xy 306.404531 -311.075355)
			(xy 306.405026 -311.099962) (xy 306.744128 -311.099962) (xy 306.748088 -311.050908) (xy 306.759865 -311.003124)
			(xy 306.779156 -310.957848) (xy 306.805459 -310.916252) (xy 306.838094 -310.879415) (xy 306.876215 -310.84829)
			(xy 306.918836 -310.823683) (xy 306.964852 -310.806231) (xy 307.013071 -310.796387) (xy 307.062246 -310.794406)
			(xy 307.111101 -310.800338) (xy 307.158372 -310.81403) (xy 307.202834 -310.835128) (xy 307.243337 -310.863084)
			(xy 307.27883 -310.897176) (xy 307.308395 -310.93652) (xy 307.331266 -310.980097) (xy 307.34685 -311.026778)
			(xy 307.354745 -311.075355) (xy 307.35524 -311.099962) (xy 307.694088 -311.099962) (xy 307.698048 -311.050908)
			(xy 307.709825 -311.003124) (xy 307.729116 -310.957848) (xy 307.755419 -310.916252) (xy 307.788054 -310.879415)
			(xy 307.826175 -310.84829) (xy 307.868796 -310.823683) (xy 307.914812 -310.806231) (xy 307.963031 -310.796387)
			(xy 308.012206 -310.794406) (xy 308.061061 -310.800338) (xy 308.108332 -310.81403) (xy 308.152794 -310.835128)
			(xy 308.193297 -310.863084) (xy 308.22879 -310.897176) (xy 308.258355 -310.93652) (xy 308.281226 -310.980097)
			(xy 308.29681 -311.026778) (xy 308.304705 -311.075355) (xy 308.3052 -311.099962) (xy 308.644048 -311.099962)
			(xy 308.648008 -311.050908) (xy 308.659785 -311.003124) (xy 308.679076 -310.957848) (xy 308.705379 -310.916252)
			(xy 308.738014 -310.879415) (xy 308.776135 -310.84829) (xy 308.818756 -310.823683) (xy 308.864772 -310.806231)
			(xy 308.912991 -310.796387) (xy 308.962166 -310.794406) (xy 309.011021 -310.800338) (xy 309.058292 -310.81403)
			(xy 309.102754 -310.835128) (xy 309.143257 -310.863084) (xy 309.17875 -310.897176) (xy 309.208315 -310.93652)
			(xy 309.231186 -310.980097) (xy 309.24677 -311.026778) (xy 309.254665 -311.075355) (xy 309.25516 -311.099962)
			(xy 309.594008 -311.099962) (xy 309.597968 -311.050908) (xy 309.609745 -311.003124) (xy 309.629036 -310.957848)
			(xy 309.655339 -310.916252) (xy 309.687974 -310.879415) (xy 309.726095 -310.84829) (xy 309.768716 -310.823683)
			(xy 309.814732 -310.806231) (xy 309.862951 -310.796387) (xy 309.912126 -310.794406) (xy 309.960981 -310.800338)
			(xy 310.008252 -310.81403) (xy 310.052714 -310.835128) (xy 310.093217 -310.863084) (xy 310.12871 -310.897176)
			(xy 310.158275 -310.93652) (xy 310.181146 -310.980097) (xy 310.19673 -311.026778) (xy 310.204625 -311.075355)
			(xy 310.204955 -311.091749) (xy 310.544042 -311.091749) (xy 310.549405 -311.042391) (xy 310.562683 -310.994551)
			(xy 310.583525 -310.949489) (xy 310.611383 -310.908393) (xy 310.645522 -310.872346) (xy 310.685044 -310.842296)
			(xy 310.728907 -310.819036) (xy 310.775954 -310.803179) (xy 310.824948 -310.795142) (xy 310.849772 -310.794654)
			(xy 310.863955 -310.794835) (xy 310.892195 -310.797504) (xy 310.90616 -310.799988) (xy 310.918606 -310.802274)
			(xy 310.942482 -310.794908) (xy 311.019698 -310.717692) (xy 311.027064 -310.693562) (xy 311.024778 -310.68137)
			(xy 311.022292 -310.667341) (xy 311.019621 -310.638974) (xy 311.019444 -310.624728) (xy 311.019624 -310.610545)
			(xy 311.022294 -310.582305) (xy 311.024778 -310.56834) (xy 311.027064 -310.555894) (xy 311.019698 -310.532272)
			(xy 310.942228 -310.454802) (xy 310.918606 -310.447436) (xy 310.90616 -310.449722) (xy 310.892194 -310.4522)
			(xy 310.863955 -310.454871) (xy 310.849772 -310.455056) (xy 310.824953 -310.454492) (xy 310.77597 -310.446457)
			(xy 310.728932 -310.430603) (xy 310.685079 -310.407348) (xy 310.645565 -310.377304) (xy 310.611433 -310.341264)
			(xy 310.583581 -310.300176) (xy 310.562744 -310.255124) (xy 310.549469 -310.207294) (xy 310.544108 -310.157946)
			(xy 310.546801 -310.108382) (xy 310.557478 -310.059906) (xy 310.575856 -310.013795) (xy 310.601452 -309.971266)
			(xy 310.633592 -309.933438) (xy 310.671428 -309.901308) (xy 310.713963 -309.875722) (xy 310.760078 -309.857355)
			(xy 310.808557 -309.846691) (xy 310.858122 -309.84401) (xy 310.907469 -309.849384) (xy 310.955295 -309.86267)
			(xy 311.000342 -309.883519) (xy 311.041423 -309.911381) (xy 311.077455 -309.945522) (xy 311.107489 -309.985043)
			(xy 311.130733 -310.028902) (xy 311.146575 -310.075944) (xy 311.154598 -310.124929) (xy 311.15508 -310.149748)
			(xy 311.154897 -310.163931) (xy 311.152229 -310.192171) (xy 311.149746 -310.206136) (xy 311.14746 -310.218582)
			(xy 311.154826 -310.242204) (xy 311.232296 -310.319674) (xy 311.255918 -310.32704) (xy 311.268364 -310.324754)
			(xy 311.282329 -310.322273) (xy 311.310569 -310.319604) (xy 311.324752 -310.31942) (xy 311.338935 -310.319603)
			(xy 311.367175 -310.322271) (xy 311.38114 -310.324754) (xy 311.393586 -310.32704) (xy 311.417208 -310.319674)
			(xy 311.494678 -310.242204) (xy 311.502044 -310.218582) (xy 311.499758 -310.206136) (xy 311.497277 -310.192171)
			(xy 311.494608 -310.163931) (xy 311.494424 -310.149748) (xy 311.494826 -310.124923) (xy 311.502851 -310.075926)
			(xy 311.518697 -310.028872) (xy 311.541947 -309.985002) (xy 311.571988 -309.945471) (xy 311.608028 -309.911322)
			(xy 311.649119 -309.883453) (xy 311.694177 -309.862599) (xy 311.742016 -309.849309) (xy 311.791374 -309.843934)
			(xy 311.840952 -309.846615) (xy 311.889443 -309.857282) (xy 311.935569 -309.875653) (xy 311.978115 -309.901244)
			(xy 312.015961 -309.933382) (xy 312.048109 -309.971219) (xy 312.073712 -310.013759) (xy 312.092095 -310.059881)
			(xy 312.102774 -310.108369) (xy 312.105023 -310.149748) (xy 312.443888 -310.149748) (xy 312.447848 -310.100694)
			(xy 312.459625 -310.05291) (xy 312.478916 -310.007634) (xy 312.505219 -309.966038) (xy 312.537854 -309.929201)
			(xy 312.575975 -309.898076) (xy 312.618596 -309.873469) (xy 312.664612 -309.856017) (xy 312.712831 -309.846173)
			(xy 312.762006 -309.844192) (xy 312.810861 -309.850124) (xy 312.858132 -309.863816) (xy 312.902594 -309.884914)
			(xy 312.943097 -309.91287) (xy 312.97859 -309.946962) (xy 313.008155 -309.986306) (xy 313.031026 -310.029883)
			(xy 313.04661 -310.076564) (xy 313.054505 -310.125141) (xy 313.055 -310.149748) (xy 313.394102 -310.149748)
			(xy 313.398062 -310.100694) (xy 313.409839 -310.05291) (xy 313.42913 -310.007634) (xy 313.455433 -309.966038)
			(xy 313.488068 -309.929201) (xy 313.526189 -309.898076) (xy 313.56881 -309.873469) (xy 313.614826 -309.856017)
			(xy 313.663045 -309.846173) (xy 313.71222 -309.844192) (xy 313.761075 -309.850124) (xy 313.808346 -309.863816)
			(xy 313.852808 -309.884914) (xy 313.893311 -309.91287) (xy 313.928804 -309.946962) (xy 313.958369 -309.986306)
			(xy 313.98124 -310.029883) (xy 313.996824 -310.076564) (xy 314.004719 -310.125141) (xy 314.005214 -310.149748)
			(xy 314.344062 -310.149748) (xy 314.348022 -310.100694) (xy 314.359799 -310.05291) (xy 314.37909 -310.007634)
			(xy 314.405393 -309.966038) (xy 314.438028 -309.929201) (xy 314.476149 -309.898076) (xy 314.51877 -309.873469)
			(xy 314.564786 -309.856017) (xy 314.613005 -309.846173) (xy 314.66218 -309.844192) (xy 314.711035 -309.850124)
			(xy 314.758306 -309.863816) (xy 314.802768 -309.884914) (xy 314.843271 -309.91287) (xy 314.878764 -309.946962)
			(xy 314.908329 -309.986306) (xy 314.9312 -310.029883) (xy 314.946784 -310.076564) (xy 314.954679 -310.125141)
			(xy 314.955174 -310.149748) (xy 315.294276 -310.149748) (xy 315.298236 -310.100694) (xy 315.310013 -310.05291)
			(xy 315.329304 -310.007634) (xy 315.355607 -309.966038) (xy 315.388242 -309.929201) (xy 315.426363 -309.898076)
			(xy 315.468984 -309.873469) (xy 315.515 -309.856017) (xy 315.563219 -309.846173) (xy 315.612394 -309.844192)
			(xy 315.661249 -309.850124) (xy 315.70852 -309.863816) (xy 315.752982 -309.884914) (xy 315.793485 -309.91287)
			(xy 315.828978 -309.946962) (xy 315.858543 -309.986306) (xy 315.881414 -310.029883) (xy 315.896998 -310.076564)
			(xy 315.904893 -310.125141) (xy 315.905388 -310.149748) (xy 315.904893 -310.174355) (xy 315.896998 -310.222932)
			(xy 315.881414 -310.269613) (xy 315.858543 -310.31319) (xy 315.828978 -310.352534) (xy 315.793485 -310.386626)
			(xy 315.752982 -310.414582) (xy 315.70852 -310.43568) (xy 315.661249 -310.449372) (xy 315.612394 -310.455304)
			(xy 315.563219 -310.453323) (xy 315.515 -310.443479) (xy 315.468984 -310.426027) (xy 315.426363 -310.40142)
			(xy 315.388242 -310.370295) (xy 315.355607 -310.333458) (xy 315.329304 -310.291862) (xy 315.310013 -310.246586)
			(xy 315.298236 -310.198802) (xy 315.294276 -310.149748) (xy 314.955174 -310.149748) (xy 314.954679 -310.174355)
			(xy 314.946784 -310.222932) (xy 314.9312 -310.269613) (xy 314.908329 -310.31319) (xy 314.878764 -310.352534)
			(xy 314.843271 -310.386626) (xy 314.802768 -310.414582) (xy 314.758306 -310.43568) (xy 314.711035 -310.449372)
			(xy 314.66218 -310.455304) (xy 314.613005 -310.453323) (xy 314.564786 -310.443479) (xy 314.51877 -310.426027)
			(xy 314.476149 -310.40142) (xy 314.438028 -310.370295) (xy 314.405393 -310.333458) (xy 314.37909 -310.291862)
			(xy 314.359799 -310.246586) (xy 314.348022 -310.198802) (xy 314.344062 -310.149748) (xy 314.005214 -310.149748)
			(xy 314.004719 -310.174355) (xy 313.996824 -310.222932) (xy 313.98124 -310.269613) (xy 313.958369 -310.31319)
			(xy 313.928804 -310.352534) (xy 313.893311 -310.386626) (xy 313.852808 -310.414582) (xy 313.808346 -310.43568)
			(xy 313.761075 -310.449372) (xy 313.71222 -310.455304) (xy 313.663045 -310.453323) (xy 313.614826 -310.443479)
			(xy 313.56881 -310.426027) (xy 313.526189 -310.40142) (xy 313.488068 -310.370295) (xy 313.455433 -310.333458)
			(xy 313.42913 -310.291862) (xy 313.409839 -310.246586) (xy 313.398062 -310.198802) (xy 313.394102 -310.149748)
			(xy 313.055 -310.149748) (xy 313.054505 -310.174355) (xy 313.04661 -310.222932) (xy 313.031026 -310.269613)
			(xy 313.008155 -310.31319) (xy 312.97859 -310.352534) (xy 312.943097 -310.386626) (xy 312.902594 -310.414582)
			(xy 312.858132 -310.43568) (xy 312.810861 -310.449372) (xy 312.762006 -310.455304) (xy 312.712831 -310.453323)
			(xy 312.664612 -310.443479) (xy 312.618596 -310.426027) (xy 312.575975 -310.40142) (xy 312.537854 -310.370295)
			(xy 312.505219 -310.333458) (xy 312.478916 -310.291862) (xy 312.459625 -310.246586) (xy 312.447848 -310.198802)
			(xy 312.443888 -310.149748) (xy 312.105023 -310.149748) (xy 312.105468 -310.157946) (xy 312.100106 -310.207305)
			(xy 312.086829 -310.255147) (xy 312.065987 -310.300211) (xy 312.038129 -310.341309) (xy 312.003988 -310.377359)
			(xy 311.964466 -310.40741) (xy 311.920602 -310.430672) (xy 311.873552 -310.44653) (xy 311.824557 -310.454568)
			(xy 311.799732 -310.455056) (xy 311.785549 -310.454876) (xy 311.757309 -310.452206) (xy 311.743344 -310.449722)
			(xy 311.730898 -310.447436) (xy 311.707276 -310.454802) (xy 311.629806 -310.532272) (xy 311.62244 -310.555894)
			(xy 311.624726 -310.56834) (xy 311.627204 -310.582306) (xy 311.629875 -310.610545) (xy 311.63006 -310.624728)
			(xy 311.629896 -310.638975) (xy 311.627225 -310.667343) (xy 311.624726 -310.68137) (xy 311.62244 -310.693562)
			(xy 311.629806 -310.717692) (xy 311.707022 -310.794908) (xy 311.730898 -310.802274) (xy 311.743344 -310.799988)
			(xy 311.75731 -310.797509) (xy 311.785549 -310.794839) (xy 311.799732 -310.794654) (xy 311.82455 -310.795212)
			(xy 311.873532 -310.803248) (xy 311.920569 -310.819102) (xy 311.964421 -310.842357) (xy 312.003933 -310.8724)
			(xy 312.038065 -310.90844) (xy 312.065916 -310.949527) (xy 312.086753 -310.994578) (xy 312.100027 -311.042407)
			(xy 312.105388 -311.091753) (xy 312.104942 -311.099962) (xy 312.443888 -311.099962) (xy 312.447848 -311.050908)
			(xy 312.459625 -311.003124) (xy 312.478916 -310.957848) (xy 312.505219 -310.916252) (xy 312.537854 -310.879415)
			(xy 312.575975 -310.84829) (xy 312.618596 -310.823683) (xy 312.664612 -310.806231) (xy 312.712831 -310.796387)
			(xy 312.762006 -310.794406) (xy 312.810861 -310.800338) (xy 312.858132 -310.81403) (xy 312.902594 -310.835128)
			(xy 312.943097 -310.863084) (xy 312.97859 -310.897176) (xy 313.008155 -310.93652) (xy 313.031026 -310.980097)
			(xy 313.04661 -311.026778) (xy 313.054505 -311.075355) (xy 313.055 -311.099962) (xy 313.394102 -311.099962)
			(xy 313.398062 -311.050908) (xy 313.409839 -311.003124) (xy 313.42913 -310.957848) (xy 313.455433 -310.916252)
			(xy 313.488068 -310.879415) (xy 313.526189 -310.84829) (xy 313.56881 -310.823683) (xy 313.614826 -310.806231)
			(xy 313.663045 -310.796387) (xy 313.71222 -310.794406) (xy 313.761075 -310.800338) (xy 313.808346 -310.81403)
			(xy 313.852808 -310.835128) (xy 313.893311 -310.863084) (xy 313.928804 -310.897176) (xy 313.958369 -310.93652)
			(xy 313.98124 -310.980097) (xy 313.996824 -311.026778) (xy 314.004719 -311.075355) (xy 314.005214 -311.099962)
			(xy 314.344062 -311.099962) (xy 314.348022 -311.050908) (xy 314.359799 -311.003124) (xy 314.37909 -310.957848)
			(xy 314.405393 -310.916252) (xy 314.438028 -310.879415) (xy 314.476149 -310.84829) (xy 314.51877 -310.823683)
			(xy 314.564786 -310.806231) (xy 314.613005 -310.796387) (xy 314.66218 -310.794406) (xy 314.711035 -310.800338)
			(xy 314.758306 -310.81403) (xy 314.802768 -310.835128) (xy 314.843271 -310.863084) (xy 314.878764 -310.897176)
			(xy 314.908329 -310.93652) (xy 314.9312 -310.980097) (xy 314.946784 -311.026778) (xy 314.954679 -311.075355)
			(xy 314.955174 -311.099962) (xy 314.954679 -311.124569) (xy 314.946784 -311.173146) (xy 314.9312 -311.219827)
			(xy 314.908329 -311.263404) (xy 314.878764 -311.302748) (xy 314.843271 -311.33684) (xy 314.802768 -311.364796)
			(xy 314.758306 -311.385894) (xy 314.711035 -311.399586) (xy 314.66218 -311.405518) (xy 314.613005 -311.403537)
			(xy 314.564786 -311.393693) (xy 314.51877 -311.376241) (xy 314.476149 -311.351634) (xy 314.438028 -311.320509)
			(xy 314.405393 -311.283672) (xy 314.37909 -311.242076) (xy 314.359799 -311.1968) (xy 314.348022 -311.149016)
			(xy 314.344062 -311.099962) (xy 314.005214 -311.099962) (xy 314.004719 -311.124569) (xy 313.996824 -311.173146)
			(xy 313.98124 -311.219827) (xy 313.958369 -311.263404) (xy 313.928804 -311.302748) (xy 313.893311 -311.33684)
			(xy 313.852808 -311.364796) (xy 313.808346 -311.385894) (xy 313.761075 -311.399586) (xy 313.71222 -311.405518)
			(xy 313.663045 -311.403537) (xy 313.614826 -311.393693) (xy 313.56881 -311.376241) (xy 313.526189 -311.351634)
			(xy 313.488068 -311.320509) (xy 313.455433 -311.283672) (xy 313.42913 -311.242076) (xy 313.409839 -311.1968)
			(xy 313.398062 -311.149016) (xy 313.394102 -311.099962) (xy 313.055 -311.099962) (xy 313.054505 -311.124569)
			(xy 313.04661 -311.173146) (xy 313.031026 -311.219827) (xy 313.008155 -311.263404) (xy 312.97859 -311.302748)
			(xy 312.943097 -311.33684) (xy 312.902594 -311.364796) (xy 312.858132 -311.385894) (xy 312.810861 -311.399586)
			(xy 312.762006 -311.405518) (xy 312.712831 -311.403537) (xy 312.664612 -311.393693) (xy 312.618596 -311.376241)
			(xy 312.575975 -311.351634) (xy 312.537854 -311.320509) (xy 312.505219 -311.283672) (xy 312.478916 -311.242076)
			(xy 312.459625 -311.1968) (xy 312.447848 -311.149016) (xy 312.443888 -311.099962) (xy 312.104942 -311.099962)
			(xy 312.102695 -311.141317) (xy 312.092019 -311.189792) (xy 312.073641 -311.235901) (xy 312.048046 -311.27843)
			(xy 312.015908 -311.316257) (xy 311.978073 -311.348387) (xy 311.935538 -311.373973) (xy 311.889425 -311.39234)
			(xy 311.840947 -311.403004) (xy 311.791383 -311.405686) (xy 311.742038 -311.400313) (xy 311.694212 -311.387028)
			(xy 311.649166 -311.366181) (xy 311.608085 -311.338321) (xy 311.572053 -311.304181) (xy 311.542019 -311.264662)
			(xy 311.518774 -311.220805) (xy 311.502931 -311.173764) (xy 311.494907 -311.12478) (xy 311.494424 -311.099962)
			(xy 311.494587 -311.085715) (xy 311.497259 -311.057347) (xy 311.499758 -311.04332) (xy 311.502044 -311.031128)
			(xy 311.494678 -311.006998) (xy 311.417462 -310.929782) (xy 311.393586 -310.922416) (xy 311.38114 -310.924702)
			(xy 311.367175 -310.927183) (xy 311.338935 -310.929852) (xy 311.324752 -310.930036) (xy 311.310569 -310.929852)
			(xy 311.282329 -310.927185) (xy 311.268364 -310.924702) (xy 311.255918 -310.922416) (xy 311.232042 -310.929782)
			(xy 311.154826 -311.006998) (xy 311.14746 -311.031128) (xy 311.149746 -311.04332) (xy 311.152231 -311.057349)
			(xy 311.154903 -311.085716) (xy 311.15508 -311.099962) (xy 311.154663 -311.124786) (xy 311.146637 -311.173781)
			(xy 311.13079 -311.220833) (xy 311.10754 -311.2647) (xy 311.077499 -311.304228) (xy 311.041458 -311.338376)
			(xy 311.000368 -311.366243) (xy 310.955311 -311.387095) (xy 310.907474 -311.400382) (xy 310.858118 -311.405756)
			(xy 310.808542 -311.403074) (xy 310.760053 -311.392406) (xy 310.713929 -311.374035) (xy 310.671385 -311.348443)
			(xy 310.633541 -311.316305) (xy 310.601396 -311.278469) (xy 310.575795 -311.23593) (xy 310.557413 -311.18981)
			(xy 310.546735 -311.141324) (xy 310.544042 -311.091749) (xy 310.204955 -311.091749) (xy 310.20512 -311.099962)
			(xy 310.204625 -311.124569) (xy 310.19673 -311.173146) (xy 310.181146 -311.219827) (xy 310.158275 -311.263404)
			(xy 310.12871 -311.302748) (xy 310.093217 -311.33684) (xy 310.052714 -311.364796) (xy 310.008252 -311.385894)
			(xy 309.960981 -311.399586) (xy 309.912126 -311.405518) (xy 309.862951 -311.403537) (xy 309.814732 -311.393693)
			(xy 309.768716 -311.376241) (xy 309.726095 -311.351634) (xy 309.687974 -311.320509) (xy 309.655339 -311.283672)
			(xy 309.629036 -311.242076) (xy 309.609745 -311.1968) (xy 309.597968 -311.149016) (xy 309.594008 -311.099962)
			(xy 309.25516 -311.099962) (xy 309.254665 -311.124569) (xy 309.24677 -311.173146) (xy 309.231186 -311.219827)
			(xy 309.208315 -311.263404) (xy 309.17875 -311.302748) (xy 309.143257 -311.33684) (xy 309.102754 -311.364796)
			(xy 309.058292 -311.385894) (xy 309.011021 -311.399586) (xy 308.962166 -311.405518) (xy 308.912991 -311.403537)
			(xy 308.864772 -311.393693) (xy 308.818756 -311.376241) (xy 308.776135 -311.351634) (xy 308.738014 -311.320509)
			(xy 308.705379 -311.283672) (xy 308.679076 -311.242076) (xy 308.659785 -311.1968) (xy 308.648008 -311.149016)
			(xy 308.644048 -311.099962) (xy 308.3052 -311.099962) (xy 308.304705 -311.124569) (xy 308.29681 -311.173146)
			(xy 308.281226 -311.219827) (xy 308.258355 -311.263404) (xy 308.22879 -311.302748) (xy 308.193297 -311.33684)
			(xy 308.152794 -311.364796) (xy 308.108332 -311.385894) (xy 308.061061 -311.399586) (xy 308.012206 -311.405518)
			(xy 307.963031 -311.403537) (xy 307.914812 -311.393693) (xy 307.868796 -311.376241) (xy 307.826175 -311.351634)
			(xy 307.788054 -311.320509) (xy 307.755419 -311.283672) (xy 307.729116 -311.242076) (xy 307.709825 -311.1968)
			(xy 307.698048 -311.149016) (xy 307.694088 -311.099962) (xy 307.35524 -311.099962) (xy 307.354745 -311.124569)
			(xy 307.34685 -311.173146) (xy 307.331266 -311.219827) (xy 307.308395 -311.263404) (xy 307.27883 -311.302748)
			(xy 307.243337 -311.33684) (xy 307.202834 -311.364796) (xy 307.158372 -311.385894) (xy 307.111101 -311.399586)
			(xy 307.062246 -311.405518) (xy 307.013071 -311.403537) (xy 306.964852 -311.393693) (xy 306.918836 -311.376241)
			(xy 306.876215 -311.351634) (xy 306.838094 -311.320509) (xy 306.805459 -311.283672) (xy 306.779156 -311.242076)
			(xy 306.759865 -311.1968) (xy 306.748088 -311.149016) (xy 306.744128 -311.099962) (xy 306.405026 -311.099962)
			(xy 306.404531 -311.124569) (xy 306.396636 -311.173146) (xy 306.381052 -311.219827) (xy 306.358181 -311.263404)
			(xy 306.328616 -311.302748) (xy 306.293123 -311.33684) (xy 306.25262 -311.364796) (xy 306.208158 -311.385894)
			(xy 306.160887 -311.399586) (xy 306.112032 -311.405518) (xy 306.062857 -311.403537) (xy 306.014638 -311.393693)
			(xy 305.968622 -311.376241) (xy 305.926001 -311.351634) (xy 305.88788 -311.320509) (xy 305.855245 -311.283672)
			(xy 305.828942 -311.242076) (xy 305.809651 -311.1968) (xy 305.797874 -311.149016) (xy 305.793914 -311.099962)
			(xy 305.455066 -311.099962) (xy 305.454571 -311.124569) (xy 305.446676 -311.173146) (xy 305.431092 -311.219827)
			(xy 305.408221 -311.263404) (xy 305.378656 -311.302748) (xy 305.343163 -311.33684) (xy 305.30266 -311.364796)
			(xy 305.258198 -311.385894) (xy 305.210927 -311.399586) (xy 305.162072 -311.405518) (xy 305.112897 -311.403537)
			(xy 305.064678 -311.393693) (xy 305.018662 -311.376241) (xy 304.976041 -311.351634) (xy 304.93792 -311.320509)
			(xy 304.905285 -311.283672) (xy 304.878982 -311.242076) (xy 304.859691 -311.1968) (xy 304.847914 -311.149016)
			(xy 304.843954 -311.099962) (xy 304.52695 -311.099962) (xy 304.526446 -311.12567) (xy 304.518403 -311.176452)
			(xy 304.502515 -311.225351) (xy 304.479172 -311.271163) (xy 304.448951 -311.312759) (xy 304.412595 -311.349115)
			(xy 304.370999 -311.379336) (xy 304.325187 -311.402679) (xy 304.276288 -311.418567) (xy 304.225506 -311.42661)
			(xy 304.17409 -311.42661) (xy 304.123308 -311.418567) (xy 304.074409 -311.402679) (xy 304.028597 -311.379336)
			(xy 303.987001 -311.349115) (xy 303.950645 -311.312759) (xy 303.920424 -311.271163) (xy 303.897081 -311.225351)
			(xy 303.881193 -311.176452) (xy 303.87315 -311.12567) (xy 303.554472 -311.12567) (xy 303.546756 -311.173146)
			(xy 303.531172 -311.219827) (xy 303.508301 -311.263404) (xy 303.478736 -311.302748) (xy 303.443243 -311.33684)
			(xy 303.40274 -311.364796) (xy 303.358278 -311.385894) (xy 303.311007 -311.399586) (xy 303.262152 -311.405518)
			(xy 303.212977 -311.403537) (xy 303.164758 -311.393693) (xy 303.118742 -311.376241) (xy 303.076121 -311.351634)
			(xy 303.038 -311.320509) (xy 303.005365 -311.283672) (xy 302.979062 -311.242076) (xy 302.959771 -311.1968)
			(xy 302.947994 -311.149016) (xy 302.944034 -311.099962) (xy 302.62703 -311.099962) (xy 302.626526 -311.12567)
			(xy 302.618483 -311.176452) (xy 302.602595 -311.225351) (xy 302.579252 -311.271163) (xy 302.549031 -311.312759)
			(xy 302.512675 -311.349115) (xy 302.471079 -311.379336) (xy 302.425267 -311.402679) (xy 302.376368 -311.418567)
			(xy 302.325586 -311.42661) (xy 302.27417 -311.42661) (xy 302.223388 -311.418567) (xy 302.174489 -311.402679)
			(xy 302.128677 -311.379336) (xy 302.087081 -311.349115) (xy 302.050725 -311.312759) (xy 302.020504 -311.271163)
			(xy 301.997161 -311.225351) (xy 301.981273 -311.176452) (xy 301.97323 -311.12567) (xy 301.654552 -311.12567)
			(xy 301.646836 -311.173146) (xy 301.631252 -311.219827) (xy 301.608381 -311.263404) (xy 301.578816 -311.302748)
			(xy 301.543323 -311.33684) (xy 301.50282 -311.364796) (xy 301.458358 -311.385894) (xy 301.411087 -311.399586)
			(xy 301.362232 -311.405518) (xy 301.313057 -311.403537) (xy 301.264838 -311.393693) (xy 301.218822 -311.376241)
			(xy 301.176201 -311.351634) (xy 301.13808 -311.320509) (xy 301.105445 -311.283672) (xy 301.079142 -311.242076)
			(xy 301.059851 -311.1968) (xy 301.048074 -311.149016) (xy 301.044114 -311.099962) (xy 300.726856 -311.099962)
			(xy 300.726352 -311.12567) (xy 300.718309 -311.176452) (xy 300.702421 -311.225351) (xy 300.679078 -311.271163)
			(xy 300.648857 -311.312759) (xy 300.612501 -311.349115) (xy 300.570905 -311.379336) (xy 300.525093 -311.402679)
			(xy 300.476194 -311.418567) (xy 300.425412 -311.42661) (xy 300.373996 -311.42661) (xy 300.323214 -311.418567)
			(xy 300.274315 -311.402679) (xy 300.228503 -311.379336) (xy 300.186907 -311.349115) (xy 300.150551 -311.312759)
			(xy 300.12033 -311.271163) (xy 300.096987 -311.225351) (xy 300.081099 -311.176452) (xy 300.073056 -311.12567)
			(xy 299.754378 -311.12567) (xy 299.746662 -311.173146) (xy 299.731078 -311.219827) (xy 299.708207 -311.263404)
			(xy 299.678642 -311.302748) (xy 299.643149 -311.33684) (xy 299.602646 -311.364796) (xy 299.558184 -311.385894)
			(xy 299.510913 -311.399586) (xy 299.462058 -311.405518) (xy 299.412883 -311.403537) (xy 299.364664 -311.393693)
			(xy 299.318648 -311.376241) (xy 299.276027 -311.351634) (xy 299.237906 -311.320509) (xy 299.205271 -311.283672)
			(xy 299.178968 -311.242076) (xy 299.159677 -311.1968) (xy 299.1479 -311.149016) (xy 299.14394 -311.099962)
			(xy 298.826936 -311.099962) (xy 298.826432 -311.12567) (xy 298.818389 -311.176452) (xy 298.802501 -311.225351)
			(xy 298.779158 -311.271163) (xy 298.748937 -311.312759) (xy 298.712581 -311.349115) (xy 298.670985 -311.379336)
			(xy 298.625173 -311.402679) (xy 298.576274 -311.418567) (xy 298.525492 -311.42661) (xy 298.474076 -311.42661)
			(xy 298.423294 -311.418567) (xy 298.374395 -311.402679) (xy 298.328583 -311.379336) (xy 298.286987 -311.349115)
			(xy 298.250631 -311.312759) (xy 298.22041 -311.271163) (xy 298.197067 -311.225351) (xy 298.181179 -311.176452)
			(xy 298.173136 -311.12567) (xy 297.854458 -311.12567) (xy 297.846742 -311.173146) (xy 297.831158 -311.219827)
			(xy 297.808287 -311.263404) (xy 297.778722 -311.302748) (xy 297.743229 -311.33684) (xy 297.702726 -311.364796)
			(xy 297.658264 -311.385894) (xy 297.610993 -311.399586) (xy 297.562138 -311.405518) (xy 297.512963 -311.403537)
			(xy 297.464744 -311.393693) (xy 297.418728 -311.376241) (xy 297.376107 -311.351634) (xy 297.337986 -311.320509)
			(xy 297.305351 -311.283672) (xy 297.279048 -311.242076) (xy 297.259757 -311.1968) (xy 297.24798 -311.149016)
			(xy 297.24402 -311.099962) (xy 296.927016 -311.099962) (xy 296.926512 -311.12567) (xy 296.918469 -311.176452)
			(xy 296.902581 -311.225351) (xy 296.879238 -311.271163) (xy 296.849017 -311.312759) (xy 296.812661 -311.349115)
			(xy 296.771065 -311.379336) (xy 296.725253 -311.402679) (xy 296.676354 -311.418567) (xy 296.625572 -311.42661)
			(xy 296.574156 -311.42661) (xy 296.523374 -311.418567) (xy 296.474475 -311.402679) (xy 296.428663 -311.379336)
			(xy 296.387067 -311.349115) (xy 296.350711 -311.312759) (xy 296.32049 -311.271163) (xy 296.297147 -311.225351)
			(xy 296.281259 -311.176452) (xy 296.273216 -311.12567) (xy 295.954538 -311.12567) (xy 295.946822 -311.173146)
			(xy 295.931238 -311.219827) (xy 295.908367 -311.263404) (xy 295.878802 -311.302748) (xy 295.843309 -311.33684)
			(xy 295.802806 -311.364796) (xy 295.758344 -311.385894) (xy 295.711073 -311.399586) (xy 295.662218 -311.405518)
			(xy 295.613043 -311.403537) (xy 295.564824 -311.393693) (xy 295.518808 -311.376241) (xy 295.476187 -311.351634)
			(xy 295.438066 -311.320509) (xy 295.405431 -311.283672) (xy 295.379128 -311.242076) (xy 295.359837 -311.1968)
			(xy 295.34806 -311.149016) (xy 295.3441 -311.099962) (xy 295.026842 -311.099962) (xy 295.026338 -311.12567)
			(xy 295.018295 -311.176452) (xy 295.002407 -311.225351) (xy 294.979064 -311.271163) (xy 294.948843 -311.312759)
			(xy 294.912487 -311.349115) (xy 294.870891 -311.379336) (xy 294.825079 -311.402679) (xy 294.77618 -311.418567)
			(xy 294.725398 -311.42661) (xy 294.673982 -311.42661) (xy 294.6232 -311.418567) (xy 294.574301 -311.402679)
			(xy 294.528489 -311.379336) (xy 294.486893 -311.349115) (xy 294.450537 -311.312759) (xy 294.420316 -311.271163)
			(xy 294.396973 -311.225351) (xy 294.381085 -311.176452) (xy 294.373042 -311.12567) (xy 294.054364 -311.12567)
			(xy 294.046648 -311.173146) (xy 294.031064 -311.219827) (xy 294.008193 -311.263404) (xy 293.978628 -311.302748)
			(xy 293.943135 -311.33684) (xy 293.902632 -311.364796) (xy 293.85817 -311.385894) (xy 293.810899 -311.399586)
			(xy 293.762044 -311.405518) (xy 293.712869 -311.403537) (xy 293.66465 -311.393693) (xy 293.618634 -311.376241)
			(xy 293.576013 -311.351634) (xy 293.537892 -311.320509) (xy 293.505257 -311.283672) (xy 293.478954 -311.242076)
			(xy 293.459663 -311.1968) (xy 293.447886 -311.149016) (xy 293.443926 -311.099962) (xy 293.126922 -311.099962)
			(xy 293.126418 -311.12567) (xy 293.118375 -311.176452) (xy 293.102487 -311.225351) (xy 293.079144 -311.271163)
			(xy 293.048923 -311.312759) (xy 293.012567 -311.349115) (xy 292.970971 -311.379336) (xy 292.925159 -311.402679)
			(xy 292.87626 -311.418567) (xy 292.825478 -311.42661) (xy 292.774062 -311.42661) (xy 292.72328 -311.418567)
			(xy 292.674381 -311.402679) (xy 292.628569 -311.379336) (xy 292.586973 -311.349115) (xy 292.550617 -311.312759)
			(xy 292.520396 -311.271163) (xy 292.497053 -311.225351) (xy 292.481165 -311.176452) (xy 292.473122 -311.12567)
			(xy 292.154444 -311.12567) (xy 292.146728 -311.173146) (xy 292.131144 -311.219827) (xy 292.108273 -311.263404)
			(xy 292.078708 -311.302748) (xy 292.043215 -311.33684) (xy 292.002712 -311.364796) (xy 291.95825 -311.385894)
			(xy 291.910979 -311.399586) (xy 291.862124 -311.405518) (xy 291.812949 -311.403537) (xy 291.76473 -311.393693)
			(xy 291.718714 -311.376241) (xy 291.676093 -311.351634) (xy 291.637972 -311.320509) (xy 291.605337 -311.283672)
			(xy 291.579034 -311.242076) (xy 291.559743 -311.1968) (xy 291.547966 -311.149016) (xy 291.544006 -311.099962)
			(xy 291.227002 -311.099962) (xy 291.226498 -311.12567) (xy 291.218455 -311.176452) (xy 291.202567 -311.225351)
			(xy 291.179224 -311.271163) (xy 291.149003 -311.312759) (xy 291.112647 -311.349115) (xy 291.071051 -311.379336)
			(xy 291.025239 -311.402679) (xy 290.97634 -311.418567) (xy 290.925558 -311.42661) (xy 290.874142 -311.42661)
			(xy 290.82336 -311.418567) (xy 290.774461 -311.402679) (xy 290.728649 -311.379336) (xy 290.687053 -311.349115)
			(xy 290.650697 -311.312759) (xy 290.620476 -311.271163) (xy 290.597133 -311.225351) (xy 290.581245 -311.176452)
			(xy 290.573202 -311.12567) (xy 290.254524 -311.12567) (xy 290.246808 -311.173146) (xy 290.231224 -311.219827)
			(xy 290.208353 -311.263404) (xy 290.178788 -311.302748) (xy 290.143295 -311.33684) (xy 290.102792 -311.364796)
			(xy 290.05833 -311.385894) (xy 290.011059 -311.399586) (xy 289.962204 -311.405518) (xy 289.913029 -311.403537)
			(xy 289.86481 -311.393693) (xy 289.818794 -311.376241) (xy 289.776173 -311.351634) (xy 289.738052 -311.320509)
			(xy 289.705417 -311.283672) (xy 289.679114 -311.242076) (xy 289.659823 -311.1968) (xy 289.648046 -311.149016)
			(xy 289.644086 -311.099962) (xy 289.305238 -311.099962) (xy 289.304743 -311.124569) (xy 289.296848 -311.173146)
			(xy 289.281264 -311.219827) (xy 289.258393 -311.263404) (xy 289.228828 -311.302748) (xy 289.193335 -311.33684)
			(xy 289.152832 -311.364796) (xy 289.10837 -311.385894) (xy 289.061099 -311.399586) (xy 289.012244 -311.405518)
			(xy 288.963069 -311.403537) (xy 288.91485 -311.393693) (xy 288.868834 -311.376241) (xy 288.826213 -311.351634)
			(xy 288.788092 -311.320509) (xy 288.755457 -311.283672) (xy 288.729154 -311.242076) (xy 288.709863 -311.1968)
			(xy 288.698086 -311.149016) (xy 288.694126 -311.099962) (xy 288.355024 -311.099962) (xy 288.354529 -311.124569)
			(xy 288.346634 -311.173146) (xy 288.33105 -311.219827) (xy 288.308179 -311.263404) (xy 288.278614 -311.302748)
			(xy 288.243121 -311.33684) (xy 288.202618 -311.364796) (xy 288.158156 -311.385894) (xy 288.110885 -311.399586)
			(xy 288.06203 -311.405518) (xy 288.012855 -311.403537) (xy 287.964636 -311.393693) (xy 287.91862 -311.376241)
			(xy 287.875999 -311.351634) (xy 287.837878 -311.320509) (xy 287.805243 -311.283672) (xy 287.77894 -311.242076)
			(xy 287.759649 -311.1968) (xy 287.747872 -311.149016) (xy 287.743912 -311.099962) (xy 287.405064 -311.099962)
			(xy 287.404569 -311.124569) (xy 287.396674 -311.173146) (xy 287.38109 -311.219827) (xy 287.358219 -311.263404)
			(xy 287.328654 -311.302748) (xy 287.293161 -311.33684) (xy 287.252658 -311.364796) (xy 287.208196 -311.385894)
			(xy 287.160925 -311.399586) (xy 287.11207 -311.405518) (xy 287.062895 -311.403537) (xy 287.014676 -311.393693)
			(xy 286.96866 -311.376241) (xy 286.926039 -311.351634) (xy 286.887918 -311.320509) (xy 286.855283 -311.283672)
			(xy 286.82898 -311.242076) (xy 286.809689 -311.1968) (xy 286.797912 -311.149016) (xy 286.793952 -311.099962)
			(xy 286.455104 -311.099962) (xy 286.454609 -311.124569) (xy 286.446714 -311.173146) (xy 286.43113 -311.219827)
			(xy 286.408259 -311.263404) (xy 286.378694 -311.302748) (xy 286.343201 -311.33684) (xy 286.302698 -311.364796)
			(xy 286.258236 -311.385894) (xy 286.210965 -311.399586) (xy 286.16211 -311.405518) (xy 286.112935 -311.403537)
			(xy 286.064716 -311.393693) (xy 286.0187 -311.376241) (xy 285.976079 -311.351634) (xy 285.937958 -311.320509)
			(xy 285.905323 -311.283672) (xy 285.87902 -311.242076) (xy 285.859729 -311.1968) (xy 285.847952 -311.149016)
			(xy 285.843992 -311.099962) (xy 285.505144 -311.099962) (xy 285.504649 -311.124569) (xy 285.496754 -311.173146)
			(xy 285.48117 -311.219827) (xy 285.458299 -311.263404) (xy 285.428734 -311.302748) (xy 285.393241 -311.33684)
			(xy 285.352738 -311.364796) (xy 285.308276 -311.385894) (xy 285.261005 -311.399586) (xy 285.21215 -311.405518)
			(xy 285.162975 -311.403537) (xy 285.114756 -311.393693) (xy 285.06874 -311.376241) (xy 285.026119 -311.351634)
			(xy 284.987998 -311.320509) (xy 284.955363 -311.283672) (xy 284.92906 -311.242076) (xy 284.909769 -311.1968)
			(xy 284.897992 -311.149016) (xy 284.894032 -311.099962) (xy 284.555184 -311.099962) (xy 284.554689 -311.124569)
			(xy 284.546794 -311.173146) (xy 284.53121 -311.219827) (xy 284.508339 -311.263404) (xy 284.478774 -311.302748)
			(xy 284.443281 -311.33684) (xy 284.402778 -311.364796) (xy 284.358316 -311.385894) (xy 284.311045 -311.399586)
			(xy 284.26219 -311.405518) (xy 284.213015 -311.403537) (xy 284.164796 -311.393693) (xy 284.11878 -311.376241)
			(xy 284.076159 -311.351634) (xy 284.038038 -311.320509) (xy 284.005403 -311.283672) (xy 283.9791 -311.242076)
			(xy 283.959809 -311.1968) (xy 283.948032 -311.149016) (xy 283.944072 -311.099962) (xy 283.605224 -311.099962)
			(xy 283.604729 -311.124569) (xy 283.596834 -311.173146) (xy 283.58125 -311.219827) (xy 283.558379 -311.263404)
			(xy 283.528814 -311.302748) (xy 283.493321 -311.33684) (xy 283.452818 -311.364796) (xy 283.408356 -311.385894)
			(xy 283.361085 -311.399586) (xy 283.31223 -311.405518) (xy 283.263055 -311.403537) (xy 283.214836 -311.393693)
			(xy 283.16882 -311.376241) (xy 283.126199 -311.351634) (xy 283.088078 -311.320509) (xy 283.055443 -311.283672)
			(xy 283.02914 -311.242076) (xy 283.009849 -311.1968) (xy 282.998072 -311.149016) (xy 282.994112 -311.099962)
			(xy 282.655566 -311.099962) (xy 282.655569 -311.1) (xy 282.651397 -311.150344) (xy 282.638996 -311.199315)
			(xy 282.618704 -311.245577) (xy 282.591074 -311.287868) (xy 282.55686 -311.325034) (xy 282.516996 -311.356063)
			(xy 282.472568 -311.380106) (xy 282.424788 -311.396509) (xy 282.37496 -311.404824) (xy 282.349702 -311.40527)
			(xy 282.327858 -311.404508) (xy 282.317444 -311.403746) (xy 282.297632 -311.410604) (xy 282.235402 -311.46877)
			(xy 282.22806 -311.476238) (xy 282.21965 -311.495394) (xy 282.219146 -311.505854) (xy 282.219146 -311.64403)
			(xy 282.219709 -311.654477) (xy 282.228103 -311.673618) (xy 282.235402 -311.681114) (xy 282.297632 -311.73928)
			(xy 282.317444 -311.746138) (xy 282.327858 -311.745376) (xy 282.349702 -311.744614) (xy 282.374955 -311.745136)
			(xy 282.424773 -311.753449) (xy 282.472543 -311.769849) (xy 282.516963 -311.793888) (xy 282.55682 -311.82491)
			(xy 282.591027 -311.862069) (xy 282.618651 -311.904352) (xy 282.63894 -311.950604) (xy 282.651338 -311.999566)
			(xy 282.655509 -312.0499) (xy 282.655507 -312.049922) (xy 282.994112 -312.049922) (xy 282.998072 -312.000868)
			(xy 283.009849 -311.953084) (xy 283.02914 -311.907808) (xy 283.055443 -311.866212) (xy 283.088078 -311.829375)
			(xy 283.126199 -311.79825) (xy 283.16882 -311.773643) (xy 283.214836 -311.756191) (xy 283.263055 -311.746347)
			(xy 283.31223 -311.744366) (xy 283.361085 -311.750298) (xy 283.408356 -311.76399) (xy 283.452818 -311.785088)
			(xy 283.493321 -311.813044) (xy 283.528814 -311.847136) (xy 283.558379 -311.88648) (xy 283.58125 -311.930057)
			(xy 283.596834 -311.976738) (xy 283.604729 -312.025315) (xy 283.605224 -312.049922) (xy 283.944072 -312.049922)
			(xy 283.948032 -312.000868) (xy 283.959809 -311.953084) (xy 283.9791 -311.907808) (xy 284.005403 -311.866212)
			(xy 284.038038 -311.829375) (xy 284.076159 -311.79825) (xy 284.11878 -311.773643) (xy 284.164796 -311.756191)
			(xy 284.213015 -311.746347) (xy 284.26219 -311.744366) (xy 284.311045 -311.750298) (xy 284.358316 -311.76399)
			(xy 284.402778 -311.785088) (xy 284.443281 -311.813044) (xy 284.478774 -311.847136) (xy 284.508339 -311.88648)
			(xy 284.53121 -311.930057) (xy 284.546794 -311.976738) (xy 284.554689 -312.025315) (xy 284.555184 -312.049922)
			(xy 284.894032 -312.049922) (xy 284.897992 -312.000868) (xy 284.909769 -311.953084) (xy 284.92906 -311.907808)
			(xy 284.955363 -311.866212) (xy 284.987998 -311.829375) (xy 285.026119 -311.79825) (xy 285.06874 -311.773643)
			(xy 285.114756 -311.756191) (xy 285.162975 -311.746347) (xy 285.21215 -311.744366) (xy 285.261005 -311.750298)
			(xy 285.308276 -311.76399) (xy 285.352738 -311.785088) (xy 285.393241 -311.813044) (xy 285.428734 -311.847136)
			(xy 285.458299 -311.88648) (xy 285.48117 -311.930057) (xy 285.496754 -311.976738) (xy 285.504649 -312.025315)
			(xy 285.505144 -312.049922) (xy 285.843992 -312.049922) (xy 285.847952 -312.000868) (xy 285.859729 -311.953084)
			(xy 285.87902 -311.907808) (xy 285.905323 -311.866212) (xy 285.937958 -311.829375) (xy 285.976079 -311.79825)
			(xy 286.0187 -311.773643) (xy 286.064716 -311.756191) (xy 286.112935 -311.746347) (xy 286.16211 -311.744366)
			(xy 286.210965 -311.750298) (xy 286.258236 -311.76399) (xy 286.302698 -311.785088) (xy 286.343201 -311.813044)
			(xy 286.378694 -311.847136) (xy 286.408259 -311.88648) (xy 286.43113 -311.930057) (xy 286.446714 -311.976738)
			(xy 286.454609 -312.025315) (xy 286.455104 -312.049922) (xy 286.793952 -312.049922) (xy 286.797912 -312.000868)
			(xy 286.809689 -311.953084) (xy 286.82898 -311.907808) (xy 286.855283 -311.866212) (xy 286.887918 -311.829375)
			(xy 286.926039 -311.79825) (xy 286.96866 -311.773643) (xy 287.014676 -311.756191) (xy 287.062895 -311.746347)
			(xy 287.11207 -311.744366) (xy 287.160925 -311.750298) (xy 287.208196 -311.76399) (xy 287.252658 -311.785088)
			(xy 287.293161 -311.813044) (xy 287.328654 -311.847136) (xy 287.358219 -311.88648) (xy 287.38109 -311.930057)
			(xy 287.396674 -311.976738) (xy 287.404569 -312.025315) (xy 287.405064 -312.049922) (xy 287.743912 -312.049922)
			(xy 287.747872 -312.000868) (xy 287.759649 -311.953084) (xy 287.77894 -311.907808) (xy 287.805243 -311.866212)
			(xy 287.837878 -311.829375) (xy 287.875999 -311.79825) (xy 287.91862 -311.773643) (xy 287.964636 -311.756191)
			(xy 288.012855 -311.746347) (xy 288.06203 -311.744366) (xy 288.110885 -311.750298) (xy 288.158156 -311.76399)
			(xy 288.202618 -311.785088) (xy 288.243121 -311.813044) (xy 288.278614 -311.847136) (xy 288.308179 -311.88648)
			(xy 288.33105 -311.930057) (xy 288.346634 -311.976738) (xy 288.354529 -312.025315) (xy 288.355024 -312.049922)
			(xy 288.694126 -312.049922) (xy 288.698086 -312.000868) (xy 288.709863 -311.953084) (xy 288.729154 -311.907808)
			(xy 288.755457 -311.866212) (xy 288.788092 -311.829375) (xy 288.826213 -311.79825) (xy 288.868834 -311.773643)
			(xy 288.91485 -311.756191) (xy 288.963069 -311.746347) (xy 289.012244 -311.744366) (xy 289.061099 -311.750298)
			(xy 289.10837 -311.76399) (xy 289.152832 -311.785088) (xy 289.193335 -311.813044) (xy 289.228828 -311.847136)
			(xy 289.258393 -311.88648) (xy 289.281264 -311.930057) (xy 289.296848 -311.976738) (xy 289.304743 -312.025315)
			(xy 289.305238 -312.049922) (xy 289.644086 -312.049922) (xy 289.648046 -312.000868) (xy 289.659823 -311.953084)
			(xy 289.679114 -311.907808) (xy 289.705417 -311.866212) (xy 289.738052 -311.829375) (xy 289.776173 -311.79825)
			(xy 289.818794 -311.773643) (xy 289.86481 -311.756191) (xy 289.913029 -311.746347) (xy 289.962204 -311.744366)
			(xy 290.011059 -311.750298) (xy 290.05833 -311.76399) (xy 290.102792 -311.785088) (xy 290.143295 -311.813044)
			(xy 290.178788 -311.847136) (xy 290.208353 -311.88648) (xy 290.231224 -311.930057) (xy 290.246808 -311.976738)
			(xy 290.254703 -312.025315) (xy 290.255198 -312.049922) (xy 290.254703 -312.074529) (xy 290.254524 -312.07563)
			(xy 290.573202 -312.07563) (xy 290.573202 -312.024214) (xy 290.581245 -311.973432) (xy 290.597133 -311.924533)
			(xy 290.620476 -311.878721) (xy 290.650697 -311.837125) (xy 290.687053 -311.800769) (xy 290.728649 -311.770548)
			(xy 290.774461 -311.747205) (xy 290.82336 -311.731317) (xy 290.874142 -311.723274) (xy 290.925558 -311.723274)
			(xy 290.97634 -311.731317) (xy 291.025239 -311.747205) (xy 291.071051 -311.770548) (xy 291.112647 -311.800769)
			(xy 291.149003 -311.837125) (xy 291.179224 -311.878721) (xy 291.202567 -311.924533) (xy 291.218455 -311.973432)
			(xy 291.226498 -312.024214) (xy 291.227002 -312.049922) (xy 291.544006 -312.049922) (xy 291.547966 -312.000868)
			(xy 291.559743 -311.953084) (xy 291.579034 -311.907808) (xy 291.605337 -311.866212) (xy 291.637972 -311.829375)
			(xy 291.676093 -311.79825) (xy 291.718714 -311.773643) (xy 291.76473 -311.756191) (xy 291.812949 -311.746347)
			(xy 291.862124 -311.744366) (xy 291.910979 -311.750298) (xy 291.95825 -311.76399) (xy 292.002712 -311.785088)
			(xy 292.043215 -311.813044) (xy 292.078708 -311.847136) (xy 292.108273 -311.88648) (xy 292.131144 -311.930057)
			(xy 292.146728 -311.976738) (xy 292.154623 -312.025315) (xy 292.155118 -312.049922) (xy 292.154623 -312.074529)
			(xy 292.154444 -312.07563) (xy 292.473122 -312.07563) (xy 292.473122 -312.024214) (xy 292.481165 -311.973432)
			(xy 292.497053 -311.924533) (xy 292.520396 -311.878721) (xy 292.550617 -311.837125) (xy 292.586973 -311.800769)
			(xy 292.628569 -311.770548) (xy 292.674381 -311.747205) (xy 292.72328 -311.731317) (xy 292.774062 -311.723274)
			(xy 292.825478 -311.723274) (xy 292.87626 -311.731317) (xy 292.925159 -311.747205) (xy 292.970971 -311.770548)
			(xy 293.012567 -311.800769) (xy 293.048923 -311.837125) (xy 293.079144 -311.878721) (xy 293.102487 -311.924533)
			(xy 293.118375 -311.973432) (xy 293.126418 -312.024214) (xy 293.126922 -312.049922) (xy 293.443926 -312.049922)
			(xy 293.447886 -312.000868) (xy 293.459663 -311.953084) (xy 293.478954 -311.907808) (xy 293.505257 -311.866212)
			(xy 293.537892 -311.829375) (xy 293.576013 -311.79825) (xy 293.618634 -311.773643) (xy 293.66465 -311.756191)
			(xy 293.712869 -311.746347) (xy 293.762044 -311.744366) (xy 293.810899 -311.750298) (xy 293.85817 -311.76399)
			(xy 293.902632 -311.785088) (xy 293.943135 -311.813044) (xy 293.978628 -311.847136) (xy 294.008193 -311.88648)
			(xy 294.031064 -311.930057) (xy 294.046648 -311.976738) (xy 294.054543 -312.025315) (xy 294.055038 -312.049922)
			(xy 294.054543 -312.074529) (xy 294.054364 -312.07563) (xy 294.373042 -312.07563) (xy 294.373042 -312.024214)
			(xy 294.381085 -311.973432) (xy 294.396973 -311.924533) (xy 294.420316 -311.878721) (xy 294.450537 -311.837125)
			(xy 294.486893 -311.800769) (xy 294.528489 -311.770548) (xy 294.574301 -311.747205) (xy 294.6232 -311.731317)
			(xy 294.673982 -311.723274) (xy 294.725398 -311.723274) (xy 294.77618 -311.731317) (xy 294.825079 -311.747205)
			(xy 294.870891 -311.770548) (xy 294.912487 -311.800769) (xy 294.948843 -311.837125) (xy 294.979064 -311.878721)
			(xy 295.002407 -311.924533) (xy 295.018295 -311.973432) (xy 295.026338 -312.024214) (xy 295.026842 -312.049922)
			(xy 295.3441 -312.049922) (xy 295.34806 -312.000868) (xy 295.359837 -311.953084) (xy 295.379128 -311.907808)
			(xy 295.405431 -311.866212) (xy 295.438066 -311.829375) (xy 295.476187 -311.79825) (xy 295.518808 -311.773643)
			(xy 295.564824 -311.756191) (xy 295.613043 -311.746347) (xy 295.662218 -311.744366) (xy 295.711073 -311.750298)
			(xy 295.758344 -311.76399) (xy 295.802806 -311.785088) (xy 295.843309 -311.813044) (xy 295.878802 -311.847136)
			(xy 295.908367 -311.88648) (xy 295.931238 -311.930057) (xy 295.946822 -311.976738) (xy 295.954717 -312.025315)
			(xy 295.955212 -312.049922) (xy 295.954717 -312.074529) (xy 295.954538 -312.07563) (xy 296.273216 -312.07563)
			(xy 296.273216 -312.024214) (xy 296.281259 -311.973432) (xy 296.297147 -311.924533) (xy 296.32049 -311.878721)
			(xy 296.350711 -311.837125) (xy 296.387067 -311.800769) (xy 296.428663 -311.770548) (xy 296.474475 -311.747205)
			(xy 296.523374 -311.731317) (xy 296.574156 -311.723274) (xy 296.625572 -311.723274) (xy 296.676354 -311.731317)
			(xy 296.725253 -311.747205) (xy 296.771065 -311.770548) (xy 296.812661 -311.800769) (xy 296.849017 -311.837125)
			(xy 296.879238 -311.878721) (xy 296.902581 -311.924533) (xy 296.918469 -311.973432) (xy 296.926512 -312.024214)
			(xy 296.927016 -312.049922) (xy 297.24402 -312.049922) (xy 297.24798 -312.000868) (xy 297.259757 -311.953084)
			(xy 297.279048 -311.907808) (xy 297.305351 -311.866212) (xy 297.337986 -311.829375) (xy 297.376107 -311.79825)
			(xy 297.418728 -311.773643) (xy 297.464744 -311.756191) (xy 297.512963 -311.746347) (xy 297.562138 -311.744366)
			(xy 297.610993 -311.750298) (xy 297.658264 -311.76399) (xy 297.702726 -311.785088) (xy 297.743229 -311.813044)
			(xy 297.778722 -311.847136) (xy 297.808287 -311.88648) (xy 297.831158 -311.930057) (xy 297.846742 -311.976738)
			(xy 297.854637 -312.025315) (xy 297.855132 -312.049922) (xy 297.854637 -312.074529) (xy 297.854458 -312.07563)
			(xy 298.173136 -312.07563) (xy 298.173136 -312.024214) (xy 298.181179 -311.973432) (xy 298.197067 -311.924533)
			(xy 298.22041 -311.878721) (xy 298.250631 -311.837125) (xy 298.286987 -311.800769) (xy 298.328583 -311.770548)
			(xy 298.374395 -311.747205) (xy 298.423294 -311.731317) (xy 298.474076 -311.723274) (xy 298.525492 -311.723274)
			(xy 298.576274 -311.731317) (xy 298.625173 -311.747205) (xy 298.670985 -311.770548) (xy 298.712581 -311.800769)
			(xy 298.748937 -311.837125) (xy 298.779158 -311.878721) (xy 298.802501 -311.924533) (xy 298.818389 -311.973432)
			(xy 298.826432 -312.024214) (xy 298.826936 -312.049922) (xy 299.14394 -312.049922) (xy 299.1479 -312.000868)
			(xy 299.159677 -311.953084) (xy 299.178968 -311.907808) (xy 299.205271 -311.866212) (xy 299.237906 -311.829375)
			(xy 299.276027 -311.79825) (xy 299.318648 -311.773643) (xy 299.364664 -311.756191) (xy 299.412883 -311.746347)
			(xy 299.462058 -311.744366) (xy 299.510913 -311.750298) (xy 299.558184 -311.76399) (xy 299.602646 -311.785088)
			(xy 299.643149 -311.813044) (xy 299.678642 -311.847136) (xy 299.708207 -311.88648) (xy 299.731078 -311.930057)
			(xy 299.746662 -311.976738) (xy 299.754557 -312.025315) (xy 299.755052 -312.049922) (xy 299.754557 -312.074529)
			(xy 299.754378 -312.07563) (xy 300.073056 -312.07563) (xy 300.073056 -312.024214) (xy 300.081099 -311.973432)
			(xy 300.096987 -311.924533) (xy 300.12033 -311.878721) (xy 300.150551 -311.837125) (xy 300.186907 -311.800769)
			(xy 300.228503 -311.770548) (xy 300.274315 -311.747205) (xy 300.323214 -311.731317) (xy 300.373996 -311.723274)
			(xy 300.425412 -311.723274) (xy 300.476194 -311.731317) (xy 300.525093 -311.747205) (xy 300.570905 -311.770548)
			(xy 300.612501 -311.800769) (xy 300.648857 -311.837125) (xy 300.679078 -311.878721) (xy 300.702421 -311.924533)
			(xy 300.718309 -311.973432) (xy 300.726352 -312.024214) (xy 300.726856 -312.049922) (xy 301.044114 -312.049922)
			(xy 301.048074 -312.000868) (xy 301.059851 -311.953084) (xy 301.079142 -311.907808) (xy 301.105445 -311.866212)
			(xy 301.13808 -311.829375) (xy 301.176201 -311.79825) (xy 301.218822 -311.773643) (xy 301.264838 -311.756191)
			(xy 301.313057 -311.746347) (xy 301.362232 -311.744366) (xy 301.411087 -311.750298) (xy 301.458358 -311.76399)
			(xy 301.50282 -311.785088) (xy 301.543323 -311.813044) (xy 301.578816 -311.847136) (xy 301.608381 -311.88648)
			(xy 301.631252 -311.930057) (xy 301.646836 -311.976738) (xy 301.654731 -312.025315) (xy 301.655226 -312.049922)
			(xy 301.654731 -312.074529) (xy 301.654552 -312.07563) (xy 301.97323 -312.07563) (xy 301.97323 -312.024214)
			(xy 301.981273 -311.973432) (xy 301.997161 -311.924533) (xy 302.020504 -311.878721) (xy 302.050725 -311.837125)
			(xy 302.087081 -311.800769) (xy 302.128677 -311.770548) (xy 302.174489 -311.747205) (xy 302.223388 -311.731317)
			(xy 302.27417 -311.723274) (xy 302.325586 -311.723274) (xy 302.376368 -311.731317) (xy 302.425267 -311.747205)
			(xy 302.471079 -311.770548) (xy 302.512675 -311.800769) (xy 302.549031 -311.837125) (xy 302.579252 -311.878721)
			(xy 302.602595 -311.924533) (xy 302.618483 -311.973432) (xy 302.626526 -312.024214) (xy 302.62703 -312.049922)
			(xy 302.944034 -312.049922) (xy 302.947994 -312.000868) (xy 302.959771 -311.953084) (xy 302.979062 -311.907808)
			(xy 303.005365 -311.866212) (xy 303.038 -311.829375) (xy 303.076121 -311.79825) (xy 303.118742 -311.773643)
			(xy 303.164758 -311.756191) (xy 303.212977 -311.746347) (xy 303.262152 -311.744366) (xy 303.311007 -311.750298)
			(xy 303.358278 -311.76399) (xy 303.40274 -311.785088) (xy 303.443243 -311.813044) (xy 303.478736 -311.847136)
			(xy 303.508301 -311.88648) (xy 303.531172 -311.930057) (xy 303.546756 -311.976738) (xy 303.554651 -312.025315)
			(xy 303.555146 -312.049922) (xy 303.554651 -312.074529) (xy 303.554472 -312.07563) (xy 303.87315 -312.07563)
			(xy 303.87315 -312.024214) (xy 303.881193 -311.973432) (xy 303.897081 -311.924533) (xy 303.920424 -311.878721)
			(xy 303.950645 -311.837125) (xy 303.987001 -311.800769) (xy 304.028597 -311.770548) (xy 304.074409 -311.747205)
			(xy 304.123308 -311.731317) (xy 304.17409 -311.723274) (xy 304.225506 -311.723274) (xy 304.276288 -311.731317)
			(xy 304.325187 -311.747205) (xy 304.370999 -311.770548) (xy 304.412595 -311.800769) (xy 304.448951 -311.837125)
			(xy 304.479172 -311.878721) (xy 304.502515 -311.924533) (xy 304.518403 -311.973432) (xy 304.526446 -312.024214)
			(xy 304.52695 -312.049922) (xy 304.843954 -312.049922) (xy 304.847914 -312.000868) (xy 304.859691 -311.953084)
			(xy 304.878982 -311.907808) (xy 304.905285 -311.866212) (xy 304.93792 -311.829375) (xy 304.976041 -311.79825)
			(xy 305.018662 -311.773643) (xy 305.064678 -311.756191) (xy 305.112897 -311.746347) (xy 305.162072 -311.744366)
			(xy 305.210927 -311.750298) (xy 305.258198 -311.76399) (xy 305.30266 -311.785088) (xy 305.343163 -311.813044)
			(xy 305.378656 -311.847136) (xy 305.408221 -311.88648) (xy 305.431092 -311.930057) (xy 305.446676 -311.976738)
			(xy 305.454571 -312.025315) (xy 305.455066 -312.049922) (xy 305.793914 -312.049922) (xy 305.797874 -312.000868)
			(xy 305.809651 -311.953084) (xy 305.828942 -311.907808) (xy 305.855245 -311.866212) (xy 305.88788 -311.829375)
			(xy 305.926001 -311.79825) (xy 305.968622 -311.773643) (xy 306.014638 -311.756191) (xy 306.062857 -311.746347)
			(xy 306.112032 -311.744366) (xy 306.160887 -311.750298) (xy 306.208158 -311.76399) (xy 306.25262 -311.785088)
			(xy 306.293123 -311.813044) (xy 306.328616 -311.847136) (xy 306.358181 -311.88648) (xy 306.381052 -311.930057)
			(xy 306.396636 -311.976738) (xy 306.404531 -312.025315) (xy 306.405026 -312.049922) (xy 306.744128 -312.049922)
			(xy 306.748088 -312.000868) (xy 306.759865 -311.953084) (xy 306.779156 -311.907808) (xy 306.805459 -311.866212)
			(xy 306.838094 -311.829375) (xy 306.876215 -311.79825) (xy 306.918836 -311.773643) (xy 306.964852 -311.756191)
			(xy 307.013071 -311.746347) (xy 307.062246 -311.744366) (xy 307.111101 -311.750298) (xy 307.158372 -311.76399)
			(xy 307.202834 -311.785088) (xy 307.243337 -311.813044) (xy 307.27883 -311.847136) (xy 307.308395 -311.88648)
			(xy 307.331266 -311.930057) (xy 307.34685 -311.976738) (xy 307.354745 -312.025315) (xy 307.35524 -312.049922)
			(xy 307.694088 -312.049922) (xy 307.698048 -312.000868) (xy 307.709825 -311.953084) (xy 307.729116 -311.907808)
			(xy 307.755419 -311.866212) (xy 307.788054 -311.829375) (xy 307.826175 -311.79825) (xy 307.868796 -311.773643)
			(xy 307.914812 -311.756191) (xy 307.963031 -311.746347) (xy 308.012206 -311.744366) (xy 308.061061 -311.750298)
			(xy 308.108332 -311.76399) (xy 308.152794 -311.785088) (xy 308.193297 -311.813044) (xy 308.22879 -311.847136)
			(xy 308.258355 -311.88648) (xy 308.281226 -311.930057) (xy 308.29681 -311.976738) (xy 308.304705 -312.025315)
			(xy 308.3052 -312.049922) (xy 308.644048 -312.049922) (xy 308.648008 -312.000868) (xy 308.659785 -311.953084)
			(xy 308.679076 -311.907808) (xy 308.705379 -311.866212) (xy 308.738014 -311.829375) (xy 308.776135 -311.79825)
			(xy 308.818756 -311.773643) (xy 308.864772 -311.756191) (xy 308.912991 -311.746347) (xy 308.962166 -311.744366)
			(xy 309.011021 -311.750298) (xy 309.058292 -311.76399) (xy 309.102754 -311.785088) (xy 309.143257 -311.813044)
			(xy 309.17875 -311.847136) (xy 309.208315 -311.88648) (xy 309.231186 -311.930057) (xy 309.24677 -311.976738)
			(xy 309.254665 -312.025315) (xy 309.25516 -312.049922) (xy 309.594008 -312.049922) (xy 309.597968 -312.000868)
			(xy 309.609745 -311.953084) (xy 309.629036 -311.907808) (xy 309.655339 -311.866212) (xy 309.687974 -311.829375)
			(xy 309.726095 -311.79825) (xy 309.768716 -311.773643) (xy 309.814732 -311.756191) (xy 309.862951 -311.746347)
			(xy 309.912126 -311.744366) (xy 309.960981 -311.750298) (xy 310.008252 -311.76399) (xy 310.052714 -311.785088)
			(xy 310.093217 -311.813044) (xy 310.12871 -311.847136) (xy 310.158275 -311.88648) (xy 310.181146 -311.930057)
			(xy 310.19673 -311.976738) (xy 310.204625 -312.025315) (xy 310.20512 -312.049922) (xy 310.543968 -312.049922)
			(xy 310.547928 -312.000868) (xy 310.559705 -311.953084) (xy 310.578996 -311.907808) (xy 310.605299 -311.866212)
			(xy 310.637934 -311.829375) (xy 310.676055 -311.79825) (xy 310.718676 -311.773643) (xy 310.764692 -311.756191)
			(xy 310.812911 -311.746347) (xy 310.862086 -311.744366) (xy 310.910941 -311.750298) (xy 310.958212 -311.76399)
			(xy 311.002674 -311.785088) (xy 311.043177 -311.813044) (xy 311.07867 -311.847136) (xy 311.108235 -311.88648)
			(xy 311.131106 -311.930057) (xy 311.14669 -311.976738) (xy 311.154585 -312.025315) (xy 311.15508 -312.049922)
			(xy 311.493928 -312.049922) (xy 311.497888 -312.000868) (xy 311.509665 -311.953084) (xy 311.528956 -311.907808)
			(xy 311.555259 -311.866212) (xy 311.587894 -311.829375) (xy 311.626015 -311.79825) (xy 311.668636 -311.773643)
			(xy 311.714652 -311.756191) (xy 311.762871 -311.746347) (xy 311.812046 -311.744366) (xy 311.860901 -311.750298)
			(xy 311.908172 -311.76399) (xy 311.952634 -311.785088) (xy 311.993137 -311.813044) (xy 312.02863 -311.847136)
			(xy 312.058195 -311.88648) (xy 312.081066 -311.930057) (xy 312.09665 -311.976738) (xy 312.104545 -312.025315)
			(xy 312.10504 -312.049922) (xy 312.443888 -312.049922) (xy 312.447848 -312.000868) (xy 312.459625 -311.953084)
			(xy 312.478916 -311.907808) (xy 312.505219 -311.866212) (xy 312.537854 -311.829375) (xy 312.575975 -311.79825)
			(xy 312.618596 -311.773643) (xy 312.664612 -311.756191) (xy 312.712831 -311.746347) (xy 312.762006 -311.744366)
			(xy 312.810861 -311.750298) (xy 312.858132 -311.76399) (xy 312.902594 -311.785088) (xy 312.943097 -311.813044)
			(xy 312.97859 -311.847136) (xy 313.008155 -311.88648) (xy 313.031026 -311.930057) (xy 313.04661 -311.976738)
			(xy 313.054505 -312.025315) (xy 313.055 -312.049922) (xy 313.394102 -312.049922) (xy 313.398062 -312.000868)
			(xy 313.409839 -311.953084) (xy 313.42913 -311.907808) (xy 313.455433 -311.866212) (xy 313.488068 -311.829375)
			(xy 313.526189 -311.79825) (xy 313.56881 -311.773643) (xy 313.614826 -311.756191) (xy 313.663045 -311.746347)
			(xy 313.71222 -311.744366) (xy 313.761075 -311.750298) (xy 313.808346 -311.76399) (xy 313.852808 -311.785088)
			(xy 313.893311 -311.813044) (xy 313.928804 -311.847136) (xy 313.958369 -311.88648) (xy 313.98124 -311.930057)
			(xy 313.996824 -311.976738) (xy 314.004719 -312.025315) (xy 314.005214 -312.049922) (xy 314.344062 -312.049922)
			(xy 314.348022 -312.000868) (xy 314.359799 -311.953084) (xy 314.37909 -311.907808) (xy 314.405393 -311.866212)
			(xy 314.438028 -311.829375) (xy 314.476149 -311.79825) (xy 314.51877 -311.773643) (xy 314.564786 -311.756191)
			(xy 314.613005 -311.746347) (xy 314.66218 -311.744366) (xy 314.711035 -311.750298) (xy 314.758306 -311.76399)
			(xy 314.802768 -311.785088) (xy 314.843271 -311.813044) (xy 314.878764 -311.847136) (xy 314.908329 -311.88648)
			(xy 314.9312 -311.930057) (xy 314.946784 -311.976738) (xy 314.954679 -312.025315) (xy 314.955174 -312.049922)
			(xy 315.294276 -312.049922) (xy 315.298236 -312.000868) (xy 315.310013 -311.953084) (xy 315.329304 -311.907808)
			(xy 315.355607 -311.866212) (xy 315.388242 -311.829375) (xy 315.426363 -311.79825) (xy 315.468984 -311.773643)
			(xy 315.515 -311.756191) (xy 315.563219 -311.746347) (xy 315.612394 -311.744366) (xy 315.661249 -311.750298)
			(xy 315.70852 -311.76399) (xy 315.752982 -311.785088) (xy 315.793485 -311.813044) (xy 315.828978 -311.847136)
			(xy 315.858543 -311.88648) (xy 315.881414 -311.930057) (xy 315.896998 -311.976738) (xy 315.904893 -312.025315)
			(xy 315.905388 -312.049922) (xy 315.904893 -312.074529) (xy 315.896998 -312.123106) (xy 315.881414 -312.169787)
			(xy 315.858543 -312.213364) (xy 315.828978 -312.252708) (xy 315.793485 -312.2868) (xy 315.752982 -312.314756)
			(xy 315.70852 -312.335854) (xy 315.661249 -312.349546) (xy 315.612394 -312.355478) (xy 315.563219 -312.353497)
			(xy 315.515 -312.343653) (xy 315.468984 -312.326201) (xy 315.426363 -312.301594) (xy 315.388242 -312.270469)
			(xy 315.355607 -312.233632) (xy 315.329304 -312.192036) (xy 315.310013 -312.14676) (xy 315.298236 -312.098976)
			(xy 315.294276 -312.049922) (xy 314.955174 -312.049922) (xy 314.954679 -312.074529) (xy 314.946784 -312.123106)
			(xy 314.9312 -312.169787) (xy 314.908329 -312.213364) (xy 314.878764 -312.252708) (xy 314.843271 -312.2868)
			(xy 314.802768 -312.314756) (xy 314.758306 -312.335854) (xy 314.711035 -312.349546) (xy 314.66218 -312.355478)
			(xy 314.613005 -312.353497) (xy 314.564786 -312.343653) (xy 314.51877 -312.326201) (xy 314.476149 -312.301594)
			(xy 314.438028 -312.270469) (xy 314.405393 -312.233632) (xy 314.37909 -312.192036) (xy 314.359799 -312.14676)
			(xy 314.348022 -312.098976) (xy 314.344062 -312.049922) (xy 314.005214 -312.049922) (xy 314.004719 -312.074529)
			(xy 313.996824 -312.123106) (xy 313.98124 -312.169787) (xy 313.958369 -312.213364) (xy 313.928804 -312.252708)
			(xy 313.893311 -312.2868) (xy 313.852808 -312.314756) (xy 313.808346 -312.335854) (xy 313.761075 -312.349546)
			(xy 313.71222 -312.355478) (xy 313.663045 -312.353497) (xy 313.614826 -312.343653) (xy 313.56881 -312.326201)
			(xy 313.526189 -312.301594) (xy 313.488068 -312.270469) (xy 313.455433 -312.233632) (xy 313.42913 -312.192036)
			(xy 313.409839 -312.14676) (xy 313.398062 -312.098976) (xy 313.394102 -312.049922) (xy 313.055 -312.049922)
			(xy 313.054505 -312.074529) (xy 313.04661 -312.123106) (xy 313.031026 -312.169787) (xy 313.008155 -312.213364)
			(xy 312.97859 -312.252708) (xy 312.943097 -312.2868) (xy 312.902594 -312.314756) (xy 312.858132 -312.335854)
			(xy 312.810861 -312.349546) (xy 312.762006 -312.355478) (xy 312.712831 -312.353497) (xy 312.664612 -312.343653)
			(xy 312.618596 -312.326201) (xy 312.575975 -312.301594) (xy 312.537854 -312.270469) (xy 312.505219 -312.233632)
			(xy 312.478916 -312.192036) (xy 312.459625 -312.14676) (xy 312.447848 -312.098976) (xy 312.443888 -312.049922)
			(xy 312.10504 -312.049922) (xy 312.104545 -312.074529) (xy 312.09665 -312.123106) (xy 312.081066 -312.169787)
			(xy 312.058195 -312.213364) (xy 312.02863 -312.252708) (xy 311.993137 -312.2868) (xy 311.952634 -312.314756)
			(xy 311.908172 -312.335854) (xy 311.860901 -312.349546) (xy 311.812046 -312.355478) (xy 311.762871 -312.353497)
			(xy 311.714652 -312.343653) (xy 311.668636 -312.326201) (xy 311.626015 -312.301594) (xy 311.587894 -312.270469)
			(xy 311.555259 -312.233632) (xy 311.528956 -312.192036) (xy 311.509665 -312.14676) (xy 311.497888 -312.098976)
			(xy 311.493928 -312.049922) (xy 311.15508 -312.049922) (xy 311.154585 -312.074529) (xy 311.14669 -312.123106)
			(xy 311.131106 -312.169787) (xy 311.108235 -312.213364) (xy 311.07867 -312.252708) (xy 311.043177 -312.2868)
			(xy 311.002674 -312.314756) (xy 310.958212 -312.335854) (xy 310.910941 -312.349546) (xy 310.862086 -312.355478)
			(xy 310.812911 -312.353497) (xy 310.764692 -312.343653) (xy 310.718676 -312.326201) (xy 310.676055 -312.301594)
			(xy 310.637934 -312.270469) (xy 310.605299 -312.233632) (xy 310.578996 -312.192036) (xy 310.559705 -312.14676)
			(xy 310.547928 -312.098976) (xy 310.543968 -312.049922) (xy 310.20512 -312.049922) (xy 310.204625 -312.074529)
			(xy 310.19673 -312.123106) (xy 310.181146 -312.169787) (xy 310.158275 -312.213364) (xy 310.12871 -312.252708)
			(xy 310.093217 -312.2868) (xy 310.052714 -312.314756) (xy 310.008252 -312.335854) (xy 309.960981 -312.349546)
			(xy 309.912126 -312.355478) (xy 309.862951 -312.353497) (xy 309.814732 -312.343653) (xy 309.768716 -312.326201)
			(xy 309.726095 -312.301594) (xy 309.687974 -312.270469) (xy 309.655339 -312.233632) (xy 309.629036 -312.192036)
			(xy 309.609745 -312.14676) (xy 309.597968 -312.098976) (xy 309.594008 -312.049922) (xy 309.25516 -312.049922)
			(xy 309.254665 -312.074529) (xy 309.24677 -312.123106) (xy 309.231186 -312.169787) (xy 309.208315 -312.213364)
			(xy 309.17875 -312.252708) (xy 309.143257 -312.2868) (xy 309.102754 -312.314756) (xy 309.058292 -312.335854)
			(xy 309.011021 -312.349546) (xy 308.962166 -312.355478) (xy 308.912991 -312.353497) (xy 308.864772 -312.343653)
			(xy 308.818756 -312.326201) (xy 308.776135 -312.301594) (xy 308.738014 -312.270469) (xy 308.705379 -312.233632)
			(xy 308.679076 -312.192036) (xy 308.659785 -312.14676) (xy 308.648008 -312.098976) (xy 308.644048 -312.049922)
			(xy 308.3052 -312.049922) (xy 308.304705 -312.074529) (xy 308.29681 -312.123106) (xy 308.281226 -312.169787)
			(xy 308.258355 -312.213364) (xy 308.22879 -312.252708) (xy 308.193297 -312.2868) (xy 308.152794 -312.314756)
			(xy 308.108332 -312.335854) (xy 308.061061 -312.349546) (xy 308.012206 -312.355478) (xy 307.963031 -312.353497)
			(xy 307.914812 -312.343653) (xy 307.868796 -312.326201) (xy 307.826175 -312.301594) (xy 307.788054 -312.270469)
			(xy 307.755419 -312.233632) (xy 307.729116 -312.192036) (xy 307.709825 -312.14676) (xy 307.698048 -312.098976)
			(xy 307.694088 -312.049922) (xy 307.35524 -312.049922) (xy 307.354745 -312.074529) (xy 307.34685 -312.123106)
			(xy 307.331266 -312.169787) (xy 307.308395 -312.213364) (xy 307.27883 -312.252708) (xy 307.243337 -312.2868)
			(xy 307.202834 -312.314756) (xy 307.158372 -312.335854) (xy 307.111101 -312.349546) (xy 307.062246 -312.355478)
			(xy 307.013071 -312.353497) (xy 306.964852 -312.343653) (xy 306.918836 -312.326201) (xy 306.876215 -312.301594)
			(xy 306.838094 -312.270469) (xy 306.805459 -312.233632) (xy 306.779156 -312.192036) (xy 306.759865 -312.14676)
			(xy 306.748088 -312.098976) (xy 306.744128 -312.049922) (xy 306.405026 -312.049922) (xy 306.404531 -312.074529)
			(xy 306.396636 -312.123106) (xy 306.381052 -312.169787) (xy 306.358181 -312.213364) (xy 306.328616 -312.252708)
			(xy 306.293123 -312.2868) (xy 306.25262 -312.314756) (xy 306.208158 -312.335854) (xy 306.160887 -312.349546)
			(xy 306.112032 -312.355478) (xy 306.062857 -312.353497) (xy 306.014638 -312.343653) (xy 305.968622 -312.326201)
			(xy 305.926001 -312.301594) (xy 305.88788 -312.270469) (xy 305.855245 -312.233632) (xy 305.828942 -312.192036)
			(xy 305.809651 -312.14676) (xy 305.797874 -312.098976) (xy 305.793914 -312.049922) (xy 305.455066 -312.049922)
			(xy 305.454571 -312.074529) (xy 305.446676 -312.123106) (xy 305.431092 -312.169787) (xy 305.408221 -312.213364)
			(xy 305.378656 -312.252708) (xy 305.343163 -312.2868) (xy 305.30266 -312.314756) (xy 305.258198 -312.335854)
			(xy 305.210927 -312.349546) (xy 305.162072 -312.355478) (xy 305.112897 -312.353497) (xy 305.064678 -312.343653)
			(xy 305.018662 -312.326201) (xy 304.976041 -312.301594) (xy 304.93792 -312.270469) (xy 304.905285 -312.233632)
			(xy 304.878982 -312.192036) (xy 304.859691 -312.14676) (xy 304.847914 -312.098976) (xy 304.843954 -312.049922)
			(xy 304.52695 -312.049922) (xy 304.526446 -312.07563) (xy 304.518403 -312.126412) (xy 304.502515 -312.175311)
			(xy 304.479172 -312.221123) (xy 304.448951 -312.262719) (xy 304.412595 -312.299075) (xy 304.370999 -312.329296)
			(xy 304.325187 -312.352639) (xy 304.276288 -312.368527) (xy 304.225506 -312.37657) (xy 304.17409 -312.37657)
			(xy 304.123308 -312.368527) (xy 304.074409 -312.352639) (xy 304.028597 -312.329296) (xy 303.987001 -312.299075)
			(xy 303.950645 -312.262719) (xy 303.920424 -312.221123) (xy 303.897081 -312.175311) (xy 303.881193 -312.126412)
			(xy 303.87315 -312.07563) (xy 303.554472 -312.07563) (xy 303.546756 -312.123106) (xy 303.531172 -312.169787)
			(xy 303.508301 -312.213364) (xy 303.478736 -312.252708) (xy 303.443243 -312.2868) (xy 303.40274 -312.314756)
			(xy 303.358278 -312.335854) (xy 303.311007 -312.349546) (xy 303.262152 -312.355478) (xy 303.212977 -312.353497)
			(xy 303.164758 -312.343653) (xy 303.118742 -312.326201) (xy 303.076121 -312.301594) (xy 303.038 -312.270469)
			(xy 303.005365 -312.233632) (xy 302.979062 -312.192036) (xy 302.959771 -312.14676) (xy 302.947994 -312.098976)
			(xy 302.944034 -312.049922) (xy 302.62703 -312.049922) (xy 302.626526 -312.07563) (xy 302.618483 -312.126412)
			(xy 302.602595 -312.175311) (xy 302.579252 -312.221123) (xy 302.549031 -312.262719) (xy 302.512675 -312.299075)
			(xy 302.471079 -312.329296) (xy 302.425267 -312.352639) (xy 302.376368 -312.368527) (xy 302.325586 -312.37657)
			(xy 302.27417 -312.37657) (xy 302.223388 -312.368527) (xy 302.174489 -312.352639) (xy 302.128677 -312.329296)
			(xy 302.087081 -312.299075) (xy 302.050725 -312.262719) (xy 302.020504 -312.221123) (xy 301.997161 -312.175311)
			(xy 301.981273 -312.126412) (xy 301.97323 -312.07563) (xy 301.654552 -312.07563) (xy 301.646836 -312.123106)
			(xy 301.631252 -312.169787) (xy 301.608381 -312.213364) (xy 301.578816 -312.252708) (xy 301.543323 -312.2868)
			(xy 301.50282 -312.314756) (xy 301.458358 -312.335854) (xy 301.411087 -312.349546) (xy 301.362232 -312.355478)
			(xy 301.313057 -312.353497) (xy 301.264838 -312.343653) (xy 301.218822 -312.326201) (xy 301.176201 -312.301594)
			(xy 301.13808 -312.270469) (xy 301.105445 -312.233632) (xy 301.079142 -312.192036) (xy 301.059851 -312.14676)
			(xy 301.048074 -312.098976) (xy 301.044114 -312.049922) (xy 300.726856 -312.049922) (xy 300.726352 -312.07563)
			(xy 300.718309 -312.126412) (xy 300.702421 -312.175311) (xy 300.679078 -312.221123) (xy 300.648857 -312.262719)
			(xy 300.612501 -312.299075) (xy 300.570905 -312.329296) (xy 300.525093 -312.352639) (xy 300.476194 -312.368527)
			(xy 300.425412 -312.37657) (xy 300.373996 -312.37657) (xy 300.323214 -312.368527) (xy 300.274315 -312.352639)
			(xy 300.228503 -312.329296) (xy 300.186907 -312.299075) (xy 300.150551 -312.262719) (xy 300.12033 -312.221123)
			(xy 300.096987 -312.175311) (xy 300.081099 -312.126412) (xy 300.073056 -312.07563) (xy 299.754378 -312.07563)
			(xy 299.746662 -312.123106) (xy 299.731078 -312.169787) (xy 299.708207 -312.213364) (xy 299.678642 -312.252708)
			(xy 299.643149 -312.2868) (xy 299.602646 -312.314756) (xy 299.558184 -312.335854) (xy 299.510913 -312.349546)
			(xy 299.462058 -312.355478) (xy 299.412883 -312.353497) (xy 299.364664 -312.343653) (xy 299.318648 -312.326201)
			(xy 299.276027 -312.301594) (xy 299.237906 -312.270469) (xy 299.205271 -312.233632) (xy 299.178968 -312.192036)
			(xy 299.159677 -312.14676) (xy 299.1479 -312.098976) (xy 299.14394 -312.049922) (xy 298.826936 -312.049922)
			(xy 298.826432 -312.07563) (xy 298.818389 -312.126412) (xy 298.802501 -312.175311) (xy 298.779158 -312.221123)
			(xy 298.748937 -312.262719) (xy 298.712581 -312.299075) (xy 298.670985 -312.329296) (xy 298.625173 -312.352639)
			(xy 298.576274 -312.368527) (xy 298.525492 -312.37657) (xy 298.474076 -312.37657) (xy 298.423294 -312.368527)
			(xy 298.374395 -312.352639) (xy 298.328583 -312.329296) (xy 298.286987 -312.299075) (xy 298.250631 -312.262719)
			(xy 298.22041 -312.221123) (xy 298.197067 -312.175311) (xy 298.181179 -312.126412) (xy 298.173136 -312.07563)
			(xy 297.854458 -312.07563) (xy 297.846742 -312.123106) (xy 297.831158 -312.169787) (xy 297.808287 -312.213364)
			(xy 297.778722 -312.252708) (xy 297.743229 -312.2868) (xy 297.702726 -312.314756) (xy 297.658264 -312.335854)
			(xy 297.610993 -312.349546) (xy 297.562138 -312.355478) (xy 297.512963 -312.353497) (xy 297.464744 -312.343653)
			(xy 297.418728 -312.326201) (xy 297.376107 -312.301594) (xy 297.337986 -312.270469) (xy 297.305351 -312.233632)
			(xy 297.279048 -312.192036) (xy 297.259757 -312.14676) (xy 297.24798 -312.098976) (xy 297.24402 -312.049922)
			(xy 296.927016 -312.049922) (xy 296.926512 -312.07563) (xy 296.918469 -312.126412) (xy 296.902581 -312.175311)
			(xy 296.879238 -312.221123) (xy 296.849017 -312.262719) (xy 296.812661 -312.299075) (xy 296.771065 -312.329296)
			(xy 296.725253 -312.352639) (xy 296.676354 -312.368527) (xy 296.625572 -312.37657) (xy 296.574156 -312.37657)
			(xy 296.523374 -312.368527) (xy 296.474475 -312.352639) (xy 296.428663 -312.329296) (xy 296.387067 -312.299075)
			(xy 296.350711 -312.262719) (xy 296.32049 -312.221123) (xy 296.297147 -312.175311) (xy 296.281259 -312.126412)
			(xy 296.273216 -312.07563) (xy 295.954538 -312.07563) (xy 295.946822 -312.123106) (xy 295.931238 -312.169787)
			(xy 295.908367 -312.213364) (xy 295.878802 -312.252708) (xy 295.843309 -312.2868) (xy 295.802806 -312.314756)
			(xy 295.758344 -312.335854) (xy 295.711073 -312.349546) (xy 295.662218 -312.355478) (xy 295.613043 -312.353497)
			(xy 295.564824 -312.343653) (xy 295.518808 -312.326201) (xy 295.476187 -312.301594) (xy 295.438066 -312.270469)
			(xy 295.405431 -312.233632) (xy 295.379128 -312.192036) (xy 295.359837 -312.14676) (xy 295.34806 -312.098976)
			(xy 295.3441 -312.049922) (xy 295.026842 -312.049922) (xy 295.026338 -312.07563) (xy 295.018295 -312.126412)
			(xy 295.002407 -312.175311) (xy 294.979064 -312.221123) (xy 294.948843 -312.262719) (xy 294.912487 -312.299075)
			(xy 294.870891 -312.329296) (xy 294.825079 -312.352639) (xy 294.77618 -312.368527) (xy 294.725398 -312.37657)
			(xy 294.673982 -312.37657) (xy 294.6232 -312.368527) (xy 294.574301 -312.352639) (xy 294.528489 -312.329296)
			(xy 294.486893 -312.299075) (xy 294.450537 -312.262719) (xy 294.420316 -312.221123) (xy 294.396973 -312.175311)
			(xy 294.381085 -312.126412) (xy 294.373042 -312.07563) (xy 294.054364 -312.07563) (xy 294.046648 -312.123106)
			(xy 294.031064 -312.169787) (xy 294.008193 -312.213364) (xy 293.978628 -312.252708) (xy 293.943135 -312.2868)
			(xy 293.902632 -312.314756) (xy 293.85817 -312.335854) (xy 293.810899 -312.349546) (xy 293.762044 -312.355478)
			(xy 293.712869 -312.353497) (xy 293.66465 -312.343653) (xy 293.618634 -312.326201) (xy 293.576013 -312.301594)
			(xy 293.537892 -312.270469) (xy 293.505257 -312.233632) (xy 293.478954 -312.192036) (xy 293.459663 -312.14676)
			(xy 293.447886 -312.098976) (xy 293.443926 -312.049922) (xy 293.126922 -312.049922) (xy 293.126418 -312.07563)
			(xy 293.118375 -312.126412) (xy 293.102487 -312.175311) (xy 293.079144 -312.221123) (xy 293.048923 -312.262719)
			(xy 293.012567 -312.299075) (xy 292.970971 -312.329296) (xy 292.925159 -312.352639) (xy 292.87626 -312.368527)
			(xy 292.825478 -312.37657) (xy 292.774062 -312.37657) (xy 292.72328 -312.368527) (xy 292.674381 -312.352639)
			(xy 292.628569 -312.329296) (xy 292.586973 -312.299075) (xy 292.550617 -312.262719) (xy 292.520396 -312.221123)
			(xy 292.497053 -312.175311) (xy 292.481165 -312.126412) (xy 292.473122 -312.07563) (xy 292.154444 -312.07563)
			(xy 292.146728 -312.123106) (xy 292.131144 -312.169787) (xy 292.108273 -312.213364) (xy 292.078708 -312.252708)
			(xy 292.043215 -312.2868) (xy 292.002712 -312.314756) (xy 291.95825 -312.335854) (xy 291.910979 -312.349546)
			(xy 291.862124 -312.355478) (xy 291.812949 -312.353497) (xy 291.76473 -312.343653) (xy 291.718714 -312.326201)
			(xy 291.676093 -312.301594) (xy 291.637972 -312.270469) (xy 291.605337 -312.233632) (xy 291.579034 -312.192036)
			(xy 291.559743 -312.14676) (xy 291.547966 -312.098976) (xy 291.544006 -312.049922) (xy 291.227002 -312.049922)
			(xy 291.226498 -312.07563) (xy 291.218455 -312.126412) (xy 291.202567 -312.175311) (xy 291.179224 -312.221123)
			(xy 291.149003 -312.262719) (xy 291.112647 -312.299075) (xy 291.071051 -312.329296) (xy 291.025239 -312.352639)
			(xy 290.97634 -312.368527) (xy 290.925558 -312.37657) (xy 290.874142 -312.37657) (xy 290.82336 -312.368527)
			(xy 290.774461 -312.352639) (xy 290.728649 -312.329296) (xy 290.687053 -312.299075) (xy 290.650697 -312.262719)
			(xy 290.620476 -312.221123) (xy 290.597133 -312.175311) (xy 290.581245 -312.126412) (xy 290.573202 -312.07563)
			(xy 290.254524 -312.07563) (xy 290.246808 -312.123106) (xy 290.231224 -312.169787) (xy 290.208353 -312.213364)
			(xy 290.178788 -312.252708) (xy 290.143295 -312.2868) (xy 290.102792 -312.314756) (xy 290.05833 -312.335854)
			(xy 290.011059 -312.349546) (xy 289.962204 -312.355478) (xy 289.913029 -312.353497) (xy 289.86481 -312.343653)
			(xy 289.818794 -312.326201) (xy 289.776173 -312.301594) (xy 289.738052 -312.270469) (xy 289.705417 -312.233632)
			(xy 289.679114 -312.192036) (xy 289.659823 -312.14676) (xy 289.648046 -312.098976) (xy 289.644086 -312.049922)
			(xy 289.305238 -312.049922) (xy 289.304743 -312.074529) (xy 289.296848 -312.123106) (xy 289.281264 -312.169787)
			(xy 289.258393 -312.213364) (xy 289.228828 -312.252708) (xy 289.193335 -312.2868) (xy 289.152832 -312.314756)
			(xy 289.10837 -312.335854) (xy 289.061099 -312.349546) (xy 289.012244 -312.355478) (xy 288.963069 -312.353497)
			(xy 288.91485 -312.343653) (xy 288.868834 -312.326201) (xy 288.826213 -312.301594) (xy 288.788092 -312.270469)
			(xy 288.755457 -312.233632) (xy 288.729154 -312.192036) (xy 288.709863 -312.14676) (xy 288.698086 -312.098976)
			(xy 288.694126 -312.049922) (xy 288.355024 -312.049922) (xy 288.354529 -312.074529) (xy 288.346634 -312.123106)
			(xy 288.33105 -312.169787) (xy 288.308179 -312.213364) (xy 288.278614 -312.252708) (xy 288.243121 -312.2868)
			(xy 288.202618 -312.314756) (xy 288.158156 -312.335854) (xy 288.110885 -312.349546) (xy 288.06203 -312.355478)
			(xy 288.012855 -312.353497) (xy 287.964636 -312.343653) (xy 287.91862 -312.326201) (xy 287.875999 -312.301594)
			(xy 287.837878 -312.270469) (xy 287.805243 -312.233632) (xy 287.77894 -312.192036) (xy 287.759649 -312.14676)
			(xy 287.747872 -312.098976) (xy 287.743912 -312.049922) (xy 287.405064 -312.049922) (xy 287.404569 -312.074529)
			(xy 287.396674 -312.123106) (xy 287.38109 -312.169787) (xy 287.358219 -312.213364) (xy 287.328654 -312.252708)
			(xy 287.293161 -312.2868) (xy 287.252658 -312.314756) (xy 287.208196 -312.335854) (xy 287.160925 -312.349546)
			(xy 287.11207 -312.355478) (xy 287.062895 -312.353497) (xy 287.014676 -312.343653) (xy 286.96866 -312.326201)
			(xy 286.926039 -312.301594) (xy 286.887918 -312.270469) (xy 286.855283 -312.233632) (xy 286.82898 -312.192036)
			(xy 286.809689 -312.14676) (xy 286.797912 -312.098976) (xy 286.793952 -312.049922) (xy 286.455104 -312.049922)
			(xy 286.454609 -312.074529) (xy 286.446714 -312.123106) (xy 286.43113 -312.169787) (xy 286.408259 -312.213364)
			(xy 286.378694 -312.252708) (xy 286.343201 -312.2868) (xy 286.302698 -312.314756) (xy 286.258236 -312.335854)
			(xy 286.210965 -312.349546) (xy 286.16211 -312.355478) (xy 286.112935 -312.353497) (xy 286.064716 -312.343653)
			(xy 286.0187 -312.326201) (xy 285.976079 -312.301594) (xy 285.937958 -312.270469) (xy 285.905323 -312.233632)
			(xy 285.87902 -312.192036) (xy 285.859729 -312.14676) (xy 285.847952 -312.098976) (xy 285.843992 -312.049922)
			(xy 285.505144 -312.049922) (xy 285.504649 -312.074529) (xy 285.496754 -312.123106) (xy 285.48117 -312.169787)
			(xy 285.458299 -312.213364) (xy 285.428734 -312.252708) (xy 285.393241 -312.2868) (xy 285.352738 -312.314756)
			(xy 285.308276 -312.335854) (xy 285.261005 -312.349546) (xy 285.21215 -312.355478) (xy 285.162975 -312.353497)
			(xy 285.114756 -312.343653) (xy 285.06874 -312.326201) (xy 285.026119 -312.301594) (xy 284.987998 -312.270469)
			(xy 284.955363 -312.233632) (xy 284.92906 -312.192036) (xy 284.909769 -312.14676) (xy 284.897992 -312.098976)
			(xy 284.894032 -312.049922) (xy 284.555184 -312.049922) (xy 284.554689 -312.074529) (xy 284.546794 -312.123106)
			(xy 284.53121 -312.169787) (xy 284.508339 -312.213364) (xy 284.478774 -312.252708) (xy 284.443281 -312.2868)
			(xy 284.402778 -312.314756) (xy 284.358316 -312.335854) (xy 284.311045 -312.349546) (xy 284.26219 -312.355478)
			(xy 284.213015 -312.353497) (xy 284.164796 -312.343653) (xy 284.11878 -312.326201) (xy 284.076159 -312.301594)
			(xy 284.038038 -312.270469) (xy 284.005403 -312.233632) (xy 283.9791 -312.192036) (xy 283.959809 -312.14676)
			(xy 283.948032 -312.098976) (xy 283.944072 -312.049922) (xy 283.605224 -312.049922) (xy 283.604729 -312.074529)
			(xy 283.596834 -312.123106) (xy 283.58125 -312.169787) (xy 283.558379 -312.213364) (xy 283.528814 -312.252708)
			(xy 283.493321 -312.2868) (xy 283.452818 -312.314756) (xy 283.408356 -312.335854) (xy 283.361085 -312.349546)
			(xy 283.31223 -312.355478) (xy 283.263055 -312.353497) (xy 283.214836 -312.343653) (xy 283.16882 -312.326201)
			(xy 283.126199 -312.301594) (xy 283.088078 -312.270469) (xy 283.055443 -312.233632) (xy 283.02914 -312.192036)
			(xy 283.009849 -312.14676) (xy 282.998072 -312.098976) (xy 282.994112 -312.049922) (xy 282.655507 -312.049922)
			(xy 282.651338 -312.100234) (xy 282.63894 -312.149196) (xy 282.618651 -312.195448) (xy 282.591027 -312.237731)
			(xy 282.55682 -312.27489) (xy 282.516963 -312.305912) (xy 282.472543 -312.329951) (xy 282.424773 -312.346351)
			(xy 282.374955 -312.354664) (xy 282.349702 -312.35523) (xy 282.327858 -312.354468) (xy 282.317444 -312.353706)
			(xy 282.297632 -312.360564) (xy 282.235402 -312.41873) (xy 282.228069 -312.426202) (xy 282.219682 -312.445358)
			(xy 282.219146 -312.455814) (xy 282.219146 -312.59399) (xy 282.219701 -312.604441) (xy 282.228086 -312.623593)
			(xy 282.235402 -312.631074) (xy 282.297632 -312.68924) (xy 282.317444 -312.696098) (xy 282.327858 -312.695336)
			(xy 282.349702 -312.694574) (xy 282.374959 -312.695096) (xy 282.424783 -312.70341) (xy 282.472559 -312.719812)
			(xy 282.516985 -312.743854) (xy 282.556847 -312.77488) (xy 282.591058 -312.812044) (xy 282.618686 -312.854333)
			(xy 282.638977 -312.900591) (xy 282.651378 -312.949559) (xy 282.655548 -312.999882) (xy 282.994112 -312.999882)
			(xy 282.998072 -312.950828) (xy 283.009849 -312.903044) (xy 283.02914 -312.857768) (xy 283.055443 -312.816172)
			(xy 283.088078 -312.779335) (xy 283.126199 -312.74821) (xy 283.16882 -312.723603) (xy 283.214836 -312.706151)
			(xy 283.263055 -312.696307) (xy 283.31223 -312.694326) (xy 283.361085 -312.700258) (xy 283.408356 -312.71395)
			(xy 283.452818 -312.735048) (xy 283.493321 -312.763004) (xy 283.528814 -312.797096) (xy 283.558379 -312.83644)
			(xy 283.58125 -312.880017) (xy 283.596834 -312.926698) (xy 283.604729 -312.975275) (xy 283.605224 -312.999882)
			(xy 283.944072 -312.999882) (xy 283.948032 -312.950828) (xy 283.959809 -312.903044) (xy 283.9791 -312.857768)
			(xy 284.005403 -312.816172) (xy 284.038038 -312.779335) (xy 284.076159 -312.74821) (xy 284.11878 -312.723603)
			(xy 284.164796 -312.706151) (xy 284.213015 -312.696307) (xy 284.26219 -312.694326) (xy 284.311045 -312.700258)
			(xy 284.358316 -312.71395) (xy 284.402778 -312.735048) (xy 284.443281 -312.763004) (xy 284.478774 -312.797096)
			(xy 284.508339 -312.83644) (xy 284.53121 -312.880017) (xy 284.546794 -312.926698) (xy 284.554689 -312.975275)
			(xy 284.555184 -312.999882) (xy 284.894032 -312.999882) (xy 284.897992 -312.950828) (xy 284.909769 -312.903044)
			(xy 284.92906 -312.857768) (xy 284.955363 -312.816172) (xy 284.987998 -312.779335) (xy 285.026119 -312.74821)
			(xy 285.06874 -312.723603) (xy 285.114756 -312.706151) (xy 285.162975 -312.696307) (xy 285.21215 -312.694326)
			(xy 285.261005 -312.700258) (xy 285.308276 -312.71395) (xy 285.352738 -312.735048) (xy 285.393241 -312.763004)
			(xy 285.428734 -312.797096) (xy 285.458299 -312.83644) (xy 285.48117 -312.880017) (xy 285.496754 -312.926698)
			(xy 285.504649 -312.975275) (xy 285.505144 -312.999882) (xy 285.843992 -312.999882) (xy 285.847952 -312.950828)
			(xy 285.859729 -312.903044) (xy 285.87902 -312.857768) (xy 285.905323 -312.816172) (xy 285.937958 -312.779335)
			(xy 285.976079 -312.74821) (xy 286.0187 -312.723603) (xy 286.064716 -312.706151) (xy 286.112935 -312.696307)
			(xy 286.16211 -312.694326) (xy 286.210965 -312.700258) (xy 286.258236 -312.71395) (xy 286.302698 -312.735048)
			(xy 286.343201 -312.763004) (xy 286.378694 -312.797096) (xy 286.408259 -312.83644) (xy 286.43113 -312.880017)
			(xy 286.446714 -312.926698) (xy 286.454609 -312.975275) (xy 286.455104 -312.999882) (xy 286.793952 -312.999882)
			(xy 286.797912 -312.950828) (xy 286.809689 -312.903044) (xy 286.82898 -312.857768) (xy 286.855283 -312.816172)
			(xy 286.887918 -312.779335) (xy 286.926039 -312.74821) (xy 286.96866 -312.723603) (xy 287.014676 -312.706151)
			(xy 287.062895 -312.696307) (xy 287.11207 -312.694326) (xy 287.160925 -312.700258) (xy 287.208196 -312.71395)
			(xy 287.252658 -312.735048) (xy 287.293161 -312.763004) (xy 287.328654 -312.797096) (xy 287.358219 -312.83644)
			(xy 287.38109 -312.880017) (xy 287.396674 -312.926698) (xy 287.404569 -312.975275) (xy 287.405064 -312.999882)
			(xy 287.743912 -312.999882) (xy 287.747872 -312.950828) (xy 287.759649 -312.903044) (xy 287.77894 -312.857768)
			(xy 287.805243 -312.816172) (xy 287.837878 -312.779335) (xy 287.875999 -312.74821) (xy 287.91862 -312.723603)
			(xy 287.964636 -312.706151) (xy 288.012855 -312.696307) (xy 288.06203 -312.694326) (xy 288.110885 -312.700258)
			(xy 288.158156 -312.71395) (xy 288.202618 -312.735048) (xy 288.243121 -312.763004) (xy 288.278614 -312.797096)
			(xy 288.308179 -312.83644) (xy 288.33105 -312.880017) (xy 288.346634 -312.926698) (xy 288.354529 -312.975275)
			(xy 288.355024 -312.999882) (xy 288.694126 -312.999882) (xy 288.698086 -312.950828) (xy 288.709863 -312.903044)
			(xy 288.729154 -312.857768) (xy 288.755457 -312.816172) (xy 288.788092 -312.779335) (xy 288.826213 -312.74821)
			(xy 288.868834 -312.723603) (xy 288.91485 -312.706151) (xy 288.963069 -312.696307) (xy 289.012244 -312.694326)
			(xy 289.061099 -312.700258) (xy 289.10837 -312.71395) (xy 289.152832 -312.735048) (xy 289.193335 -312.763004)
			(xy 289.228828 -312.797096) (xy 289.258393 -312.83644) (xy 289.281264 -312.880017) (xy 289.296848 -312.926698)
			(xy 289.304743 -312.975275) (xy 289.305238 -312.999882) (xy 289.644086 -312.999882) (xy 289.648046 -312.950828)
			(xy 289.659823 -312.903044) (xy 289.679114 -312.857768) (xy 289.705417 -312.816172) (xy 289.738052 -312.779335)
			(xy 289.776173 -312.74821) (xy 289.818794 -312.723603) (xy 289.86481 -312.706151) (xy 289.913029 -312.696307)
			(xy 289.962204 -312.694326) (xy 290.011059 -312.700258) (xy 290.05833 -312.71395) (xy 290.102792 -312.735048)
			(xy 290.143295 -312.763004) (xy 290.178788 -312.797096) (xy 290.208353 -312.83644) (xy 290.231224 -312.880017)
			(xy 290.246808 -312.926698) (xy 290.254703 -312.975275) (xy 290.255198 -312.999882) (xy 290.594046 -312.999882)
			(xy 290.598006 -312.950828) (xy 290.609783 -312.903044) (xy 290.629074 -312.857768) (xy 290.655377 -312.816172)
			(xy 290.688012 -312.779335) (xy 290.726133 -312.74821) (xy 290.768754 -312.723603) (xy 290.81477 -312.706151)
			(xy 290.862989 -312.696307) (xy 290.912164 -312.694326) (xy 290.961019 -312.700258) (xy 291.00829 -312.71395)
			(xy 291.052752 -312.735048) (xy 291.093255 -312.763004) (xy 291.128748 -312.797096) (xy 291.158313 -312.83644)
			(xy 291.181184 -312.880017) (xy 291.196768 -312.926698) (xy 291.204663 -312.975275) (xy 291.205158 -312.999882)
			(xy 291.204663 -313.024489) (xy 291.204484 -313.02559) (xy 291.523162 -313.02559) (xy 291.523162 -312.974174)
			(xy 291.531205 -312.923392) (xy 291.547093 -312.874493) (xy 291.570436 -312.828681) (xy 291.600657 -312.787085)
			(xy 291.637013 -312.750729) (xy 291.678609 -312.720508) (xy 291.724421 -312.697165) (xy 291.77332 -312.681277)
			(xy 291.824102 -312.673234) (xy 291.875518 -312.673234) (xy 291.9263 -312.681277) (xy 291.975199 -312.697165)
			(xy 292.021011 -312.720508) (xy 292.062607 -312.750729) (xy 292.098963 -312.787085) (xy 292.129184 -312.828681)
			(xy 292.152527 -312.874493) (xy 292.168415 -312.923392) (xy 292.176458 -312.974174) (xy 292.176962 -312.999882)
			(xy 292.493966 -312.999882) (xy 292.497926 -312.950828) (xy 292.509703 -312.903044) (xy 292.528994 -312.857768)
			(xy 292.555297 -312.816172) (xy 292.587932 -312.779335) (xy 292.626053 -312.74821) (xy 292.668674 -312.723603)
			(xy 292.71469 -312.706151) (xy 292.762909 -312.696307) (xy 292.812084 -312.694326) (xy 292.860939 -312.700258)
			(xy 292.90821 -312.71395) (xy 292.952672 -312.735048) (xy 292.993175 -312.763004) (xy 293.028668 -312.797096)
			(xy 293.058233 -312.83644) (xy 293.081104 -312.880017) (xy 293.096688 -312.926698) (xy 293.104583 -312.975275)
			(xy 293.105078 -312.999882) (xy 293.104583 -313.024489) (xy 293.104404 -313.02559) (xy 293.423082 -313.02559)
			(xy 293.423082 -312.974174) (xy 293.431125 -312.923392) (xy 293.447013 -312.874493) (xy 293.470356 -312.828681)
			(xy 293.500577 -312.787085) (xy 293.536933 -312.750729) (xy 293.578529 -312.720508) (xy 293.624341 -312.697165)
			(xy 293.67324 -312.681277) (xy 293.724022 -312.673234) (xy 293.775438 -312.673234) (xy 293.82622 -312.681277)
			(xy 293.875119 -312.697165) (xy 293.920931 -312.720508) (xy 293.962527 -312.750729) (xy 293.998883 -312.787085)
			(xy 294.029104 -312.828681) (xy 294.052447 -312.874493) (xy 294.068335 -312.923392) (xy 294.076378 -312.974174)
			(xy 294.076882 -312.999882) (xy 294.393886 -312.999882) (xy 294.397846 -312.950828) (xy 294.409623 -312.903044)
			(xy 294.428914 -312.857768) (xy 294.455217 -312.816172) (xy 294.487852 -312.779335) (xy 294.525973 -312.74821)
			(xy 294.568594 -312.723603) (xy 294.61461 -312.706151) (xy 294.662829 -312.696307) (xy 294.712004 -312.694326)
			(xy 294.760859 -312.700258) (xy 294.80813 -312.71395) (xy 294.852592 -312.735048) (xy 294.893095 -312.763004)
			(xy 294.928588 -312.797096) (xy 294.958153 -312.83644) (xy 294.981024 -312.880017) (xy 294.996608 -312.926698)
			(xy 295.004503 -312.975275) (xy 295.004998 -312.999882) (xy 295.004503 -313.024489) (xy 295.004324 -313.02559)
			(xy 295.323256 -313.02559) (xy 295.323256 -312.974174) (xy 295.331299 -312.923392) (xy 295.347187 -312.874493)
			(xy 295.37053 -312.828681) (xy 295.400751 -312.787085) (xy 295.437107 -312.750729) (xy 295.478703 -312.720508)
			(xy 295.524515 -312.697165) (xy 295.573414 -312.681277) (xy 295.624196 -312.673234) (xy 295.675612 -312.673234)
			(xy 295.726394 -312.681277) (xy 295.775293 -312.697165) (xy 295.821105 -312.720508) (xy 295.862701 -312.750729)
			(xy 295.899057 -312.787085) (xy 295.929278 -312.828681) (xy 295.952621 -312.874493) (xy 295.968509 -312.923392)
			(xy 295.976552 -312.974174) (xy 295.977056 -312.999882) (xy 296.29406 -312.999882) (xy 296.29802 -312.950828)
			(xy 296.309797 -312.903044) (xy 296.329088 -312.857768) (xy 296.355391 -312.816172) (xy 296.388026 -312.779335)
			(xy 296.426147 -312.74821) (xy 296.468768 -312.723603) (xy 296.514784 -312.706151) (xy 296.563003 -312.696307)
			(xy 296.612178 -312.694326) (xy 296.661033 -312.700258) (xy 296.708304 -312.71395) (xy 296.752766 -312.735048)
			(xy 296.793269 -312.763004) (xy 296.828762 -312.797096) (xy 296.858327 -312.83644) (xy 296.881198 -312.880017)
			(xy 296.896782 -312.926698) (xy 296.904677 -312.975275) (xy 296.905172 -312.999882) (xy 296.904677 -313.024489)
			(xy 296.904498 -313.02559) (xy 297.223176 -313.02559) (xy 297.223176 -312.974174) (xy 297.231219 -312.923392)
			(xy 297.247107 -312.874493) (xy 297.27045 -312.828681) (xy 297.300671 -312.787085) (xy 297.337027 -312.750729)
			(xy 297.378623 -312.720508) (xy 297.424435 -312.697165) (xy 297.473334 -312.681277) (xy 297.524116 -312.673234)
			(xy 297.575532 -312.673234) (xy 297.626314 -312.681277) (xy 297.675213 -312.697165) (xy 297.721025 -312.720508)
			(xy 297.762621 -312.750729) (xy 297.798977 -312.787085) (xy 297.829198 -312.828681) (xy 297.852541 -312.874493)
			(xy 297.868429 -312.923392) (xy 297.876472 -312.974174) (xy 297.876976 -312.999882) (xy 298.19398 -312.999882)
			(xy 298.19794 -312.950828) (xy 298.209717 -312.903044) (xy 298.229008 -312.857768) (xy 298.255311 -312.816172)
			(xy 298.287946 -312.779335) (xy 298.326067 -312.74821) (xy 298.368688 -312.723603) (xy 298.414704 -312.706151)
			(xy 298.462923 -312.696307) (xy 298.512098 -312.694326) (xy 298.560953 -312.700258) (xy 298.608224 -312.71395)
			(xy 298.652686 -312.735048) (xy 298.693189 -312.763004) (xy 298.728682 -312.797096) (xy 298.758247 -312.83644)
			(xy 298.781118 -312.880017) (xy 298.796702 -312.926698) (xy 298.804597 -312.975275) (xy 298.805092 -312.999882)
			(xy 298.804597 -313.024489) (xy 298.804418 -313.02559) (xy 299.123096 -313.02559) (xy 299.123096 -312.974174)
			(xy 299.131139 -312.923392) (xy 299.147027 -312.874493) (xy 299.17037 -312.828681) (xy 299.200591 -312.787085)
			(xy 299.236947 -312.750729) (xy 299.278543 -312.720508) (xy 299.324355 -312.697165) (xy 299.373254 -312.681277)
			(xy 299.424036 -312.673234) (xy 299.475452 -312.673234) (xy 299.526234 -312.681277) (xy 299.575133 -312.697165)
			(xy 299.620945 -312.720508) (xy 299.662541 -312.750729) (xy 299.698897 -312.787085) (xy 299.729118 -312.828681)
			(xy 299.752461 -312.874493) (xy 299.768349 -312.923392) (xy 299.776392 -312.974174) (xy 299.776896 -312.999882)
			(xy 300.0939 -312.999882) (xy 300.09786 -312.950828) (xy 300.109637 -312.903044) (xy 300.128928 -312.857768)
			(xy 300.155231 -312.816172) (xy 300.187866 -312.779335) (xy 300.225987 -312.74821) (xy 300.268608 -312.723603)
			(xy 300.314624 -312.706151) (xy 300.362843 -312.696307) (xy 300.412018 -312.694326) (xy 300.460873 -312.700258)
			(xy 300.508144 -312.71395) (xy 300.552606 -312.735048) (xy 300.593109 -312.763004) (xy 300.628602 -312.797096)
			(xy 300.658167 -312.83644) (xy 300.681038 -312.880017) (xy 300.696622 -312.926698) (xy 300.704517 -312.975275)
			(xy 300.705012 -312.999882) (xy 300.704517 -313.024489) (xy 300.704338 -313.02559) (xy 301.02327 -313.02559)
			(xy 301.02327 -312.974174) (xy 301.031313 -312.923392) (xy 301.047201 -312.874493) (xy 301.070544 -312.828681)
			(xy 301.100765 -312.787085) (xy 301.137121 -312.750729) (xy 301.178717 -312.720508) (xy 301.224529 -312.697165)
			(xy 301.273428 -312.681277) (xy 301.32421 -312.673234) (xy 301.375626 -312.673234) (xy 301.426408 -312.681277)
			(xy 301.475307 -312.697165) (xy 301.521119 -312.720508) (xy 301.562715 -312.750729) (xy 301.599071 -312.787085)
			(xy 301.629292 -312.828681) (xy 301.652635 -312.874493) (xy 301.668523 -312.923392) (xy 301.676566 -312.974174)
			(xy 301.67707 -312.999882) (xy 301.994074 -312.999882) (xy 301.998034 -312.950828) (xy 302.009811 -312.903044)
			(xy 302.029102 -312.857768) (xy 302.055405 -312.816172) (xy 302.08804 -312.779335) (xy 302.126161 -312.74821)
			(xy 302.168782 -312.723603) (xy 302.214798 -312.706151) (xy 302.263017 -312.696307) (xy 302.312192 -312.694326)
			(xy 302.361047 -312.700258) (xy 302.408318 -312.71395) (xy 302.45278 -312.735048) (xy 302.493283 -312.763004)
			(xy 302.528776 -312.797096) (xy 302.558341 -312.83644) (xy 302.581212 -312.880017) (xy 302.596796 -312.926698)
			(xy 302.604691 -312.975275) (xy 302.605186 -312.999882) (xy 302.604691 -313.024489) (xy 302.604512 -313.02559)
			(xy 302.92319 -313.02559) (xy 302.92319 -312.974174) (xy 302.931233 -312.923392) (xy 302.947121 -312.874493)
			(xy 302.970464 -312.828681) (xy 303.000685 -312.787085) (xy 303.037041 -312.750729) (xy 303.078637 -312.720508)
			(xy 303.124449 -312.697165) (xy 303.173348 -312.681277) (xy 303.22413 -312.673234) (xy 303.275546 -312.673234)
			(xy 303.326328 -312.681277) (xy 303.375227 -312.697165) (xy 303.421039 -312.720508) (xy 303.462635 -312.750729)
			(xy 303.498991 -312.787085) (xy 303.529212 -312.828681) (xy 303.552555 -312.874493) (xy 303.568443 -312.923392)
			(xy 303.576486 -312.974174) (xy 303.57699 -312.999882) (xy 303.893994 -312.999882) (xy 303.897954 -312.950828)
			(xy 303.909731 -312.903044) (xy 303.929022 -312.857768) (xy 303.955325 -312.816172) (xy 303.98796 -312.779335)
			(xy 304.026081 -312.74821) (xy 304.068702 -312.723603) (xy 304.114718 -312.706151) (xy 304.162937 -312.696307)
			(xy 304.212112 -312.694326) (xy 304.260967 -312.700258) (xy 304.308238 -312.71395) (xy 304.3527 -312.735048)
			(xy 304.393203 -312.763004) (xy 304.428696 -312.797096) (xy 304.458261 -312.83644) (xy 304.481132 -312.880017)
			(xy 304.496716 -312.926698) (xy 304.504611 -312.975275) (xy 304.505106 -312.999882) (xy 304.504611 -313.024489)
			(xy 304.504432 -313.02559) (xy 304.82311 -313.02559) (xy 304.82311 -312.974174) (xy 304.831153 -312.923392)
			(xy 304.847041 -312.874493) (xy 304.870384 -312.828681) (xy 304.900605 -312.787085) (xy 304.936961 -312.750729)
			(xy 304.978557 -312.720508) (xy 305.024369 -312.697165) (xy 305.073268 -312.681277) (xy 305.12405 -312.673234)
			(xy 305.175466 -312.673234) (xy 305.226248 -312.681277) (xy 305.275147 -312.697165) (xy 305.320959 -312.720508)
			(xy 305.362555 -312.750729) (xy 305.398911 -312.787085) (xy 305.429132 -312.828681) (xy 305.452475 -312.874493)
			(xy 305.468363 -312.923392) (xy 305.476406 -312.974174) (xy 305.47691 -312.999882) (xy 305.793914 -312.999882)
			(xy 305.797874 -312.950828) (xy 305.809651 -312.903044) (xy 305.828942 -312.857768) (xy 305.855245 -312.816172)
			(xy 305.88788 -312.779335) (xy 305.926001 -312.74821) (xy 305.968622 -312.723603) (xy 306.014638 -312.706151)
			(xy 306.062857 -312.696307) (xy 306.112032 -312.694326) (xy 306.160887 -312.700258) (xy 306.208158 -312.71395)
			(xy 306.25262 -312.735048) (xy 306.293123 -312.763004) (xy 306.328616 -312.797096) (xy 306.358181 -312.83644)
			(xy 306.381052 -312.880017) (xy 306.396636 -312.926698) (xy 306.404531 -312.975275) (xy 306.405026 -312.999882)
			(xy 306.744128 -312.999882) (xy 306.748088 -312.950828) (xy 306.759865 -312.903044) (xy 306.779156 -312.857768)
			(xy 306.805459 -312.816172) (xy 306.838094 -312.779335) (xy 306.876215 -312.74821) (xy 306.918836 -312.723603)
			(xy 306.964852 -312.706151) (xy 307.013071 -312.696307) (xy 307.062246 -312.694326) (xy 307.111101 -312.700258)
			(xy 307.158372 -312.71395) (xy 307.202834 -312.735048) (xy 307.243337 -312.763004) (xy 307.27883 -312.797096)
			(xy 307.308395 -312.83644) (xy 307.331266 -312.880017) (xy 307.34685 -312.926698) (xy 307.354745 -312.975275)
			(xy 307.35524 -312.999882) (xy 307.694088 -312.999882) (xy 307.698048 -312.950828) (xy 307.709825 -312.903044)
			(xy 307.729116 -312.857768) (xy 307.755419 -312.816172) (xy 307.788054 -312.779335) (xy 307.826175 -312.74821)
			(xy 307.868796 -312.723603) (xy 307.914812 -312.706151) (xy 307.963031 -312.696307) (xy 308.012206 -312.694326)
			(xy 308.061061 -312.700258) (xy 308.108332 -312.71395) (xy 308.152794 -312.735048) (xy 308.193297 -312.763004)
			(xy 308.22879 -312.797096) (xy 308.258355 -312.83644) (xy 308.281226 -312.880017) (xy 308.29681 -312.926698)
			(xy 308.304705 -312.975275) (xy 308.3052 -312.999882) (xy 308.644048 -312.999882) (xy 308.648008 -312.950828)
			(xy 308.659785 -312.903044) (xy 308.679076 -312.857768) (xy 308.705379 -312.816172) (xy 308.738014 -312.779335)
			(xy 308.776135 -312.74821) (xy 308.818756 -312.723603) (xy 308.864772 -312.706151) (xy 308.912991 -312.696307)
			(xy 308.962166 -312.694326) (xy 309.011021 -312.700258) (xy 309.058292 -312.71395) (xy 309.102754 -312.735048)
			(xy 309.143257 -312.763004) (xy 309.17875 -312.797096) (xy 309.208315 -312.83644) (xy 309.231186 -312.880017)
			(xy 309.24677 -312.926698) (xy 309.254665 -312.975275) (xy 309.25516 -312.999882) (xy 309.594008 -312.999882)
			(xy 309.597968 -312.950828) (xy 309.609745 -312.903044) (xy 309.629036 -312.857768) (xy 309.655339 -312.816172)
			(xy 309.687974 -312.779335) (xy 309.726095 -312.74821) (xy 309.768716 -312.723603) (xy 309.814732 -312.706151)
			(xy 309.862951 -312.696307) (xy 309.912126 -312.694326) (xy 309.960981 -312.700258) (xy 310.008252 -312.71395)
			(xy 310.052714 -312.735048) (xy 310.093217 -312.763004) (xy 310.12871 -312.797096) (xy 310.158275 -312.83644)
			(xy 310.181146 -312.880017) (xy 310.19673 -312.926698) (xy 310.204625 -312.975275) (xy 310.20512 -312.999882)
			(xy 310.543968 -312.999882) (xy 310.547928 -312.950828) (xy 310.559705 -312.903044) (xy 310.578996 -312.857768)
			(xy 310.605299 -312.816172) (xy 310.637934 -312.779335) (xy 310.676055 -312.74821) (xy 310.718676 -312.723603)
			(xy 310.764692 -312.706151) (xy 310.812911 -312.696307) (xy 310.862086 -312.694326) (xy 310.910941 -312.700258)
			(xy 310.958212 -312.71395) (xy 311.002674 -312.735048) (xy 311.043177 -312.763004) (xy 311.07867 -312.797096)
			(xy 311.108235 -312.83644) (xy 311.131106 -312.880017) (xy 311.14669 -312.926698) (xy 311.154585 -312.975275)
			(xy 311.15508 -312.999882) (xy 311.493928 -312.999882) (xy 311.497888 -312.950828) (xy 311.509665 -312.903044)
			(xy 311.528956 -312.857768) (xy 311.555259 -312.816172) (xy 311.587894 -312.779335) (xy 311.626015 -312.74821)
			(xy 311.668636 -312.723603) (xy 311.714652 -312.706151) (xy 311.762871 -312.696307) (xy 311.812046 -312.694326)
			(xy 311.860901 -312.700258) (xy 311.908172 -312.71395) (xy 311.952634 -312.735048) (xy 311.993137 -312.763004)
			(xy 312.02863 -312.797096) (xy 312.058195 -312.83644) (xy 312.081066 -312.880017) (xy 312.09665 -312.926698)
			(xy 312.104545 -312.975275) (xy 312.10504 -312.999882) (xy 312.443888 -312.999882) (xy 312.447848 -312.950828)
			(xy 312.459625 -312.903044) (xy 312.478916 -312.857768) (xy 312.505219 -312.816172) (xy 312.537854 -312.779335)
			(xy 312.575975 -312.74821) (xy 312.618596 -312.723603) (xy 312.664612 -312.706151) (xy 312.712831 -312.696307)
			(xy 312.762006 -312.694326) (xy 312.810861 -312.700258) (xy 312.858132 -312.71395) (xy 312.902594 -312.735048)
			(xy 312.943097 -312.763004) (xy 312.97859 -312.797096) (xy 313.008155 -312.83644) (xy 313.031026 -312.880017)
			(xy 313.04661 -312.926698) (xy 313.054505 -312.975275) (xy 313.055 -312.999882) (xy 313.394102 -312.999882)
			(xy 313.398062 -312.950828) (xy 313.409839 -312.903044) (xy 313.42913 -312.857768) (xy 313.455433 -312.816172)
			(xy 313.488068 -312.779335) (xy 313.526189 -312.74821) (xy 313.56881 -312.723603) (xy 313.614826 -312.706151)
			(xy 313.663045 -312.696307) (xy 313.71222 -312.694326) (xy 313.761075 -312.700258) (xy 313.808346 -312.71395)
			(xy 313.852808 -312.735048) (xy 313.893311 -312.763004) (xy 313.928804 -312.797096) (xy 313.958369 -312.83644)
			(xy 313.98124 -312.880017) (xy 313.996824 -312.926698) (xy 314.004719 -312.975275) (xy 314.005214 -312.999882)
			(xy 314.344062 -312.999882) (xy 314.348022 -312.950828) (xy 314.359799 -312.903044) (xy 314.37909 -312.857768)
			(xy 314.405393 -312.816172) (xy 314.438028 -312.779335) (xy 314.476149 -312.74821) (xy 314.51877 -312.723603)
			(xy 314.564786 -312.706151) (xy 314.613005 -312.696307) (xy 314.66218 -312.694326) (xy 314.711035 -312.700258)
			(xy 314.758306 -312.71395) (xy 314.802768 -312.735048) (xy 314.843271 -312.763004) (xy 314.878764 -312.797096)
			(xy 314.908329 -312.83644) (xy 314.9312 -312.880017) (xy 314.946784 -312.926698) (xy 314.954679 -312.975275)
			(xy 314.955174 -312.999882) (xy 314.954679 -313.024489) (xy 314.946784 -313.073066) (xy 314.9312 -313.119747)
			(xy 314.908329 -313.163324) (xy 314.878764 -313.202668) (xy 314.843271 -313.23676) (xy 314.802768 -313.264716)
			(xy 314.758306 -313.285814) (xy 314.711035 -313.299506) (xy 314.66218 -313.305438) (xy 314.613005 -313.303457)
			(xy 314.564786 -313.293613) (xy 314.51877 -313.276161) (xy 314.476149 -313.251554) (xy 314.438028 -313.220429)
			(xy 314.405393 -313.183592) (xy 314.37909 -313.141996) (xy 314.359799 -313.09672) (xy 314.348022 -313.048936)
			(xy 314.344062 -312.999882) (xy 314.005214 -312.999882) (xy 314.004719 -313.024489) (xy 313.996824 -313.073066)
			(xy 313.98124 -313.119747) (xy 313.958369 -313.163324) (xy 313.928804 -313.202668) (xy 313.893311 -313.23676)
			(xy 313.852808 -313.264716) (xy 313.808346 -313.285814) (xy 313.761075 -313.299506) (xy 313.71222 -313.305438)
			(xy 313.663045 -313.303457) (xy 313.614826 -313.293613) (xy 313.56881 -313.276161) (xy 313.526189 -313.251554)
			(xy 313.488068 -313.220429) (xy 313.455433 -313.183592) (xy 313.42913 -313.141996) (xy 313.409839 -313.09672)
			(xy 313.398062 -313.048936) (xy 313.394102 -312.999882) (xy 313.055 -312.999882) (xy 313.054505 -313.024489)
			(xy 313.04661 -313.073066) (xy 313.031026 -313.119747) (xy 313.008155 -313.163324) (xy 312.97859 -313.202668)
			(xy 312.943097 -313.23676) (xy 312.902594 -313.264716) (xy 312.858132 -313.285814) (xy 312.810861 -313.299506)
			(xy 312.762006 -313.305438) (xy 312.712831 -313.303457) (xy 312.664612 -313.293613) (xy 312.618596 -313.276161)
			(xy 312.575975 -313.251554) (xy 312.537854 -313.220429) (xy 312.505219 -313.183592) (xy 312.478916 -313.141996)
			(xy 312.459625 -313.09672) (xy 312.447848 -313.048936) (xy 312.443888 -312.999882) (xy 312.10504 -312.999882)
			(xy 312.104545 -313.024489) (xy 312.09665 -313.073066) (xy 312.081066 -313.119747) (xy 312.058195 -313.163324)
			(xy 312.02863 -313.202668) (xy 311.993137 -313.23676) (xy 311.952634 -313.264716) (xy 311.908172 -313.285814)
			(xy 311.860901 -313.299506) (xy 311.812046 -313.305438) (xy 311.762871 -313.303457) (xy 311.714652 -313.293613)
			(xy 311.668636 -313.276161) (xy 311.626015 -313.251554) (xy 311.587894 -313.220429) (xy 311.555259 -313.183592)
			(xy 311.528956 -313.141996) (xy 311.509665 -313.09672) (xy 311.497888 -313.048936) (xy 311.493928 -312.999882)
			(xy 311.15508 -312.999882) (xy 311.154585 -313.024489) (xy 311.14669 -313.073066) (xy 311.131106 -313.119747)
			(xy 311.108235 -313.163324) (xy 311.07867 -313.202668) (xy 311.043177 -313.23676) (xy 311.002674 -313.264716)
			(xy 310.958212 -313.285814) (xy 310.910941 -313.299506) (xy 310.862086 -313.305438) (xy 310.812911 -313.303457)
			(xy 310.764692 -313.293613) (xy 310.718676 -313.276161) (xy 310.676055 -313.251554) (xy 310.637934 -313.220429)
			(xy 310.605299 -313.183592) (xy 310.578996 -313.141996) (xy 310.559705 -313.09672) (xy 310.547928 -313.048936)
			(xy 310.543968 -312.999882) (xy 310.20512 -312.999882) (xy 310.204625 -313.024489) (xy 310.19673 -313.073066)
			(xy 310.181146 -313.119747) (xy 310.158275 -313.163324) (xy 310.12871 -313.202668) (xy 310.093217 -313.23676)
			(xy 310.052714 -313.264716) (xy 310.008252 -313.285814) (xy 309.960981 -313.299506) (xy 309.912126 -313.305438)
			(xy 309.862951 -313.303457) (xy 309.814732 -313.293613) (xy 309.768716 -313.276161) (xy 309.726095 -313.251554)
			(xy 309.687974 -313.220429) (xy 309.655339 -313.183592) (xy 309.629036 -313.141996) (xy 309.609745 -313.09672)
			(xy 309.597968 -313.048936) (xy 309.594008 -312.999882) (xy 309.25516 -312.999882) (xy 309.254665 -313.024489)
			(xy 309.24677 -313.073066) (xy 309.231186 -313.119747) (xy 309.208315 -313.163324) (xy 309.17875 -313.202668)
			(xy 309.143257 -313.23676) (xy 309.102754 -313.264716) (xy 309.058292 -313.285814) (xy 309.011021 -313.299506)
			(xy 308.962166 -313.305438) (xy 308.912991 -313.303457) (xy 308.864772 -313.293613) (xy 308.818756 -313.276161)
			(xy 308.776135 -313.251554) (xy 308.738014 -313.220429) (xy 308.705379 -313.183592) (xy 308.679076 -313.141996)
			(xy 308.659785 -313.09672) (xy 308.648008 -313.048936) (xy 308.644048 -312.999882) (xy 308.3052 -312.999882)
			(xy 308.304705 -313.024489) (xy 308.29681 -313.073066) (xy 308.281226 -313.119747) (xy 308.258355 -313.163324)
			(xy 308.22879 -313.202668) (xy 308.193297 -313.23676) (xy 308.152794 -313.264716) (xy 308.108332 -313.285814)
			(xy 308.061061 -313.299506) (xy 308.012206 -313.305438) (xy 307.963031 -313.303457) (xy 307.914812 -313.293613)
			(xy 307.868796 -313.276161) (xy 307.826175 -313.251554) (xy 307.788054 -313.220429) (xy 307.755419 -313.183592)
			(xy 307.729116 -313.141996) (xy 307.709825 -313.09672) (xy 307.698048 -313.048936) (xy 307.694088 -312.999882)
			(xy 307.35524 -312.999882) (xy 307.354745 -313.024489) (xy 307.34685 -313.073066) (xy 307.331266 -313.119747)
			(xy 307.308395 -313.163324) (xy 307.27883 -313.202668) (xy 307.243337 -313.23676) (xy 307.202834 -313.264716)
			(xy 307.158372 -313.285814) (xy 307.111101 -313.299506) (xy 307.062246 -313.305438) (xy 307.013071 -313.303457)
			(xy 306.964852 -313.293613) (xy 306.918836 -313.276161) (xy 306.876215 -313.251554) (xy 306.838094 -313.220429)
			(xy 306.805459 -313.183592) (xy 306.779156 -313.141996) (xy 306.759865 -313.09672) (xy 306.748088 -313.048936)
			(xy 306.744128 -312.999882) (xy 306.405026 -312.999882) (xy 306.404531 -313.024489) (xy 306.396636 -313.073066)
			(xy 306.381052 -313.119747) (xy 306.358181 -313.163324) (xy 306.328616 -313.202668) (xy 306.293123 -313.23676)
			(xy 306.25262 -313.264716) (xy 306.208158 -313.285814) (xy 306.160887 -313.299506) (xy 306.112032 -313.305438)
			(xy 306.062857 -313.303457) (xy 306.014638 -313.293613) (xy 305.968622 -313.276161) (xy 305.926001 -313.251554)
			(xy 305.88788 -313.220429) (xy 305.855245 -313.183592) (xy 305.828942 -313.141996) (xy 305.809651 -313.09672)
			(xy 305.797874 -313.048936) (xy 305.793914 -312.999882) (xy 305.47691 -312.999882) (xy 305.476406 -313.02559)
			(xy 305.468363 -313.076372) (xy 305.452475 -313.125271) (xy 305.429132 -313.171083) (xy 305.398911 -313.212679)
			(xy 305.362555 -313.249035) (xy 305.320959 -313.279256) (xy 305.275147 -313.302599) (xy 305.226248 -313.318487)
			(xy 305.175466 -313.32653) (xy 305.12405 -313.32653) (xy 305.073268 -313.318487) (xy 305.024369 -313.302599)
			(xy 304.978557 -313.279256) (xy 304.936961 -313.249035) (xy 304.900605 -313.212679) (xy 304.870384 -313.171083)
			(xy 304.847041 -313.125271) (xy 304.831153 -313.076372) (xy 304.82311 -313.02559) (xy 304.504432 -313.02559)
			(xy 304.496716 -313.073066) (xy 304.481132 -313.119747) (xy 304.458261 -313.163324) (xy 304.428696 -313.202668)
			(xy 304.393203 -313.23676) (xy 304.3527 -313.264716) (xy 304.308238 -313.285814) (xy 304.260967 -313.299506)
			(xy 304.212112 -313.305438) (xy 304.162937 -313.303457) (xy 304.114718 -313.293613) (xy 304.068702 -313.276161)
			(xy 304.026081 -313.251554) (xy 303.98796 -313.220429) (xy 303.955325 -313.183592) (xy 303.929022 -313.141996)
			(xy 303.909731 -313.09672) (xy 303.897954 -313.048936) (xy 303.893994 -312.999882) (xy 303.57699 -312.999882)
			(xy 303.576486 -313.02559) (xy 303.568443 -313.076372) (xy 303.552555 -313.125271) (xy 303.529212 -313.171083)
			(xy 303.498991 -313.212679) (xy 303.462635 -313.249035) (xy 303.421039 -313.279256) (xy 303.375227 -313.302599)
			(xy 303.326328 -313.318487) (xy 303.275546 -313.32653) (xy 303.22413 -313.32653) (xy 303.173348 -313.318487)
			(xy 303.124449 -313.302599) (xy 303.078637 -313.279256) (xy 303.037041 -313.249035) (xy 303.000685 -313.212679)
			(xy 302.970464 -313.171083) (xy 302.947121 -313.125271) (xy 302.931233 -313.076372) (xy 302.92319 -313.02559)
			(xy 302.604512 -313.02559) (xy 302.596796 -313.073066) (xy 302.581212 -313.119747) (xy 302.558341 -313.163324)
			(xy 302.528776 -313.202668) (xy 302.493283 -313.23676) (xy 302.45278 -313.264716) (xy 302.408318 -313.285814)
			(xy 302.361047 -313.299506) (xy 302.312192 -313.305438) (xy 302.263017 -313.303457) (xy 302.214798 -313.293613)
			(xy 302.168782 -313.276161) (xy 302.126161 -313.251554) (xy 302.08804 -313.220429) (xy 302.055405 -313.183592)
			(xy 302.029102 -313.141996) (xy 302.009811 -313.09672) (xy 301.998034 -313.048936) (xy 301.994074 -312.999882)
			(xy 301.67707 -312.999882) (xy 301.676566 -313.02559) (xy 301.668523 -313.076372) (xy 301.652635 -313.125271)
			(xy 301.629292 -313.171083) (xy 301.599071 -313.212679) (xy 301.562715 -313.249035) (xy 301.521119 -313.279256)
			(xy 301.475307 -313.302599) (xy 301.426408 -313.318487) (xy 301.375626 -313.32653) (xy 301.32421 -313.32653)
			(xy 301.273428 -313.318487) (xy 301.224529 -313.302599) (xy 301.178717 -313.279256) (xy 301.137121 -313.249035)
			(xy 301.100765 -313.212679) (xy 301.070544 -313.171083) (xy 301.047201 -313.125271) (xy 301.031313 -313.076372)
			(xy 301.02327 -313.02559) (xy 300.704338 -313.02559) (xy 300.696622 -313.073066) (xy 300.681038 -313.119747)
			(xy 300.658167 -313.163324) (xy 300.628602 -313.202668) (xy 300.593109 -313.23676) (xy 300.552606 -313.264716)
			(xy 300.508144 -313.285814) (xy 300.460873 -313.299506) (xy 300.412018 -313.305438) (xy 300.362843 -313.303457)
			(xy 300.314624 -313.293613) (xy 300.268608 -313.276161) (xy 300.225987 -313.251554) (xy 300.187866 -313.220429)
			(xy 300.155231 -313.183592) (xy 300.128928 -313.141996) (xy 300.109637 -313.09672) (xy 300.09786 -313.048936)
			(xy 300.0939 -312.999882) (xy 299.776896 -312.999882) (xy 299.776392 -313.02559) (xy 299.768349 -313.076372)
			(xy 299.752461 -313.125271) (xy 299.729118 -313.171083) (xy 299.698897 -313.212679) (xy 299.662541 -313.249035)
			(xy 299.620945 -313.279256) (xy 299.575133 -313.302599) (xy 299.526234 -313.318487) (xy 299.475452 -313.32653)
			(xy 299.424036 -313.32653) (xy 299.373254 -313.318487) (xy 299.324355 -313.302599) (xy 299.278543 -313.279256)
			(xy 299.236947 -313.249035) (xy 299.200591 -313.212679) (xy 299.17037 -313.171083) (xy 299.147027 -313.125271)
			(xy 299.131139 -313.076372) (xy 299.123096 -313.02559) (xy 298.804418 -313.02559) (xy 298.796702 -313.073066)
			(xy 298.781118 -313.119747) (xy 298.758247 -313.163324) (xy 298.728682 -313.202668) (xy 298.693189 -313.23676)
			(xy 298.652686 -313.264716) (xy 298.608224 -313.285814) (xy 298.560953 -313.299506) (xy 298.512098 -313.305438)
			(xy 298.462923 -313.303457) (xy 298.414704 -313.293613) (xy 298.368688 -313.276161) (xy 298.326067 -313.251554)
			(xy 298.287946 -313.220429) (xy 298.255311 -313.183592) (xy 298.229008 -313.141996) (xy 298.209717 -313.09672)
			(xy 298.19794 -313.048936) (xy 298.19398 -312.999882) (xy 297.876976 -312.999882) (xy 297.876472 -313.02559)
			(xy 297.868429 -313.076372) (xy 297.852541 -313.125271) (xy 297.829198 -313.171083) (xy 297.798977 -313.212679)
			(xy 297.762621 -313.249035) (xy 297.721025 -313.279256) (xy 297.675213 -313.302599) (xy 297.626314 -313.318487)
			(xy 297.575532 -313.32653) (xy 297.524116 -313.32653) (xy 297.473334 -313.318487) (xy 297.424435 -313.302599)
			(xy 297.378623 -313.279256) (xy 297.337027 -313.249035) (xy 297.300671 -313.212679) (xy 297.27045 -313.171083)
			(xy 297.247107 -313.125271) (xy 297.231219 -313.076372) (xy 297.223176 -313.02559) (xy 296.904498 -313.02559)
			(xy 296.896782 -313.073066) (xy 296.881198 -313.119747) (xy 296.858327 -313.163324) (xy 296.828762 -313.202668)
			(xy 296.793269 -313.23676) (xy 296.752766 -313.264716) (xy 296.708304 -313.285814) (xy 296.661033 -313.299506)
			(xy 296.612178 -313.305438) (xy 296.563003 -313.303457) (xy 296.514784 -313.293613) (xy 296.468768 -313.276161)
			(xy 296.426147 -313.251554) (xy 296.388026 -313.220429) (xy 296.355391 -313.183592) (xy 296.329088 -313.141996)
			(xy 296.309797 -313.09672) (xy 296.29802 -313.048936) (xy 296.29406 -312.999882) (xy 295.977056 -312.999882)
			(xy 295.976552 -313.02559) (xy 295.968509 -313.076372) (xy 295.952621 -313.125271) (xy 295.929278 -313.171083)
			(xy 295.899057 -313.212679) (xy 295.862701 -313.249035) (xy 295.821105 -313.279256) (xy 295.775293 -313.302599)
			(xy 295.726394 -313.318487) (xy 295.675612 -313.32653) (xy 295.624196 -313.32653) (xy 295.573414 -313.318487)
			(xy 295.524515 -313.302599) (xy 295.478703 -313.279256) (xy 295.437107 -313.249035) (xy 295.400751 -313.212679)
			(xy 295.37053 -313.171083) (xy 295.347187 -313.125271) (xy 295.331299 -313.076372) (xy 295.323256 -313.02559)
			(xy 295.004324 -313.02559) (xy 294.996608 -313.073066) (xy 294.981024 -313.119747) (xy 294.958153 -313.163324)
			(xy 294.928588 -313.202668) (xy 294.893095 -313.23676) (xy 294.852592 -313.264716) (xy 294.80813 -313.285814)
			(xy 294.760859 -313.299506) (xy 294.712004 -313.305438) (xy 294.662829 -313.303457) (xy 294.61461 -313.293613)
			(xy 294.568594 -313.276161) (xy 294.525973 -313.251554) (xy 294.487852 -313.220429) (xy 294.455217 -313.183592)
			(xy 294.428914 -313.141996) (xy 294.409623 -313.09672) (xy 294.397846 -313.048936) (xy 294.393886 -312.999882)
			(xy 294.076882 -312.999882) (xy 294.076378 -313.02559) (xy 294.068335 -313.076372) (xy 294.052447 -313.125271)
			(xy 294.029104 -313.171083) (xy 293.998883 -313.212679) (xy 293.962527 -313.249035) (xy 293.920931 -313.279256)
			(xy 293.875119 -313.302599) (xy 293.82622 -313.318487) (xy 293.775438 -313.32653) (xy 293.724022 -313.32653)
			(xy 293.67324 -313.318487) (xy 293.624341 -313.302599) (xy 293.578529 -313.279256) (xy 293.536933 -313.249035)
			(xy 293.500577 -313.212679) (xy 293.470356 -313.171083) (xy 293.447013 -313.125271) (xy 293.431125 -313.076372)
			(xy 293.423082 -313.02559) (xy 293.104404 -313.02559) (xy 293.096688 -313.073066) (xy 293.081104 -313.119747)
			(xy 293.058233 -313.163324) (xy 293.028668 -313.202668) (xy 292.993175 -313.23676) (xy 292.952672 -313.264716)
			(xy 292.90821 -313.285814) (xy 292.860939 -313.299506) (xy 292.812084 -313.305438) (xy 292.762909 -313.303457)
			(xy 292.71469 -313.293613) (xy 292.668674 -313.276161) (xy 292.626053 -313.251554) (xy 292.587932 -313.220429)
			(xy 292.555297 -313.183592) (xy 292.528994 -313.141996) (xy 292.509703 -313.09672) (xy 292.497926 -313.048936)
			(xy 292.493966 -312.999882) (xy 292.176962 -312.999882) (xy 292.176458 -313.02559) (xy 292.168415 -313.076372)
			(xy 292.152527 -313.125271) (xy 292.129184 -313.171083) (xy 292.098963 -313.212679) (xy 292.062607 -313.249035)
			(xy 292.021011 -313.279256) (xy 291.975199 -313.302599) (xy 291.9263 -313.318487) (xy 291.875518 -313.32653)
			(xy 291.824102 -313.32653) (xy 291.77332 -313.318487) (xy 291.724421 -313.302599) (xy 291.678609 -313.279256)
			(xy 291.637013 -313.249035) (xy 291.600657 -313.212679) (xy 291.570436 -313.171083) (xy 291.547093 -313.125271)
			(xy 291.531205 -313.076372) (xy 291.523162 -313.02559) (xy 291.204484 -313.02559) (xy 291.196768 -313.073066)
			(xy 291.181184 -313.119747) (xy 291.158313 -313.163324) (xy 291.128748 -313.202668) (xy 291.093255 -313.23676)
			(xy 291.052752 -313.264716) (xy 291.00829 -313.285814) (xy 290.961019 -313.299506) (xy 290.912164 -313.305438)
			(xy 290.862989 -313.303457) (xy 290.81477 -313.293613) (xy 290.768754 -313.276161) (xy 290.726133 -313.251554)
			(xy 290.688012 -313.220429) (xy 290.655377 -313.183592) (xy 290.629074 -313.141996) (xy 290.609783 -313.09672)
			(xy 290.598006 -313.048936) (xy 290.594046 -312.999882) (xy 290.255198 -312.999882) (xy 290.254703 -313.024489)
			(xy 290.246808 -313.073066) (xy 290.231224 -313.119747) (xy 290.208353 -313.163324) (xy 290.178788 -313.202668)
			(xy 290.143295 -313.23676) (xy 290.102792 -313.264716) (xy 290.05833 -313.285814) (xy 290.011059 -313.299506)
			(xy 289.962204 -313.305438) (xy 289.913029 -313.303457) (xy 289.86481 -313.293613) (xy 289.818794 -313.276161)
			(xy 289.776173 -313.251554) (xy 289.738052 -313.220429) (xy 289.705417 -313.183592) (xy 289.679114 -313.141996)
			(xy 289.659823 -313.09672) (xy 289.648046 -313.048936) (xy 289.644086 -312.999882) (xy 289.305238 -312.999882)
			(xy 289.304743 -313.024489) (xy 289.296848 -313.073066) (xy 289.281264 -313.119747) (xy 289.258393 -313.163324)
			(xy 289.228828 -313.202668) (xy 289.193335 -313.23676) (xy 289.152832 -313.264716) (xy 289.10837 -313.285814)
			(xy 289.061099 -313.299506) (xy 289.012244 -313.305438) (xy 288.963069 -313.303457) (xy 288.91485 -313.293613)
			(xy 288.868834 -313.276161) (xy 288.826213 -313.251554) (xy 288.788092 -313.220429) (xy 288.755457 -313.183592)
			(xy 288.729154 -313.141996) (xy 288.709863 -313.09672) (xy 288.698086 -313.048936) (xy 288.694126 -312.999882)
			(xy 288.355024 -312.999882) (xy 288.354529 -313.024489) (xy 288.346634 -313.073066) (xy 288.33105 -313.119747)
			(xy 288.308179 -313.163324) (xy 288.278614 -313.202668) (xy 288.243121 -313.23676) (xy 288.202618 -313.264716)
			(xy 288.158156 -313.285814) (xy 288.110885 -313.299506) (xy 288.06203 -313.305438) (xy 288.012855 -313.303457)
			(xy 287.964636 -313.293613) (xy 287.91862 -313.276161) (xy 287.875999 -313.251554) (xy 287.837878 -313.220429)
			(xy 287.805243 -313.183592) (xy 287.77894 -313.141996) (xy 287.759649 -313.09672) (xy 287.747872 -313.048936)
			(xy 287.743912 -312.999882) (xy 287.405064 -312.999882) (xy 287.404569 -313.024489) (xy 287.396674 -313.073066)
			(xy 287.38109 -313.119747) (xy 287.358219 -313.163324) (xy 287.328654 -313.202668) (xy 287.293161 -313.23676)
			(xy 287.252658 -313.264716) (xy 287.208196 -313.285814) (xy 287.160925 -313.299506) (xy 287.11207 -313.305438)
			(xy 287.062895 -313.303457) (xy 287.014676 -313.293613) (xy 286.96866 -313.276161) (xy 286.926039 -313.251554)
			(xy 286.887918 -313.220429) (xy 286.855283 -313.183592) (xy 286.82898 -313.141996) (xy 286.809689 -313.09672)
			(xy 286.797912 -313.048936) (xy 286.793952 -312.999882) (xy 286.455104 -312.999882) (xy 286.454609 -313.024489)
			(xy 286.446714 -313.073066) (xy 286.43113 -313.119747) (xy 286.408259 -313.163324) (xy 286.378694 -313.202668)
			(xy 286.343201 -313.23676) (xy 286.302698 -313.264716) (xy 286.258236 -313.285814) (xy 286.210965 -313.299506)
			(xy 286.16211 -313.305438) (xy 286.112935 -313.303457) (xy 286.064716 -313.293613) (xy 286.0187 -313.276161)
			(xy 285.976079 -313.251554) (xy 285.937958 -313.220429) (xy 285.905323 -313.183592) (xy 285.87902 -313.141996)
			(xy 285.859729 -313.09672) (xy 285.847952 -313.048936) (xy 285.843992 -312.999882) (xy 285.505144 -312.999882)
			(xy 285.504649 -313.024489) (xy 285.496754 -313.073066) (xy 285.48117 -313.119747) (xy 285.458299 -313.163324)
			(xy 285.428734 -313.202668) (xy 285.393241 -313.23676) (xy 285.352738 -313.264716) (xy 285.308276 -313.285814)
			(xy 285.261005 -313.299506) (xy 285.21215 -313.305438) (xy 285.162975 -313.303457) (xy 285.114756 -313.293613)
			(xy 285.06874 -313.276161) (xy 285.026119 -313.251554) (xy 284.987998 -313.220429) (xy 284.955363 -313.183592)
			(xy 284.92906 -313.141996) (xy 284.909769 -313.09672) (xy 284.897992 -313.048936) (xy 284.894032 -312.999882)
			(xy 284.555184 -312.999882) (xy 284.554689 -313.024489) (xy 284.546794 -313.073066) (xy 284.53121 -313.119747)
			(xy 284.508339 -313.163324) (xy 284.478774 -313.202668) (xy 284.443281 -313.23676) (xy 284.402778 -313.264716)
			(xy 284.358316 -313.285814) (xy 284.311045 -313.299506) (xy 284.26219 -313.305438) (xy 284.213015 -313.303457)
			(xy 284.164796 -313.293613) (xy 284.11878 -313.276161) (xy 284.076159 -313.251554) (xy 284.038038 -313.220429)
			(xy 284.005403 -313.183592) (xy 283.9791 -313.141996) (xy 283.959809 -313.09672) (xy 283.948032 -313.048936)
			(xy 283.944072 -312.999882) (xy 283.605224 -312.999882) (xy 283.604729 -313.024489) (xy 283.596834 -313.073066)
			(xy 283.58125 -313.119747) (xy 283.558379 -313.163324) (xy 283.528814 -313.202668) (xy 283.493321 -313.23676)
			(xy 283.452818 -313.264716) (xy 283.408356 -313.285814) (xy 283.361085 -313.299506) (xy 283.31223 -313.305438)
			(xy 283.263055 -313.303457) (xy 283.214836 -313.293613) (xy 283.16882 -313.276161) (xy 283.126199 -313.251554)
			(xy 283.088078 -313.220429) (xy 283.055443 -313.183592) (xy 283.02914 -313.141996) (xy 283.009849 -313.09672)
			(xy 282.998072 -313.048936) (xy 282.994112 -312.999882) (xy 282.655548 -312.999882) (xy 282.655549 -312.9999)
			(xy 282.651378 -313.050241) (xy 282.638977 -313.099209) (xy 282.618686 -313.145467) (xy 282.591058 -313.187756)
			(xy 282.556847 -313.22492) (xy 282.516985 -313.255946) (xy 282.472559 -313.279988) (xy 282.424783 -313.29639)
			(xy 282.374959 -313.304704) (xy 282.349702 -313.30519) (xy 282.327858 -313.304428) (xy 282.317444 -313.303666)
			(xy 282.297632 -313.310524) (xy 282.235402 -313.36869) (xy 282.228063 -313.37616) (xy 282.219661 -313.395316)
			(xy 282.219146 -313.405774) (xy 282.219146 -313.54395) (xy 282.219712 -313.554395) (xy 282.228112 -313.57353)
			(xy 282.235402 -313.581034) (xy 282.297632 -313.6392) (xy 282.317444 -313.646058) (xy 282.327858 -313.645296)
			(xy 282.349702 -313.644534) (xy 282.374954 -313.645056) (xy 282.424768 -313.653368) (xy 282.472535 -313.669767)
			(xy 282.516952 -313.693804) (xy 282.556806 -313.724824) (xy 282.591011 -313.761981) (xy 282.618634 -313.804261)
			(xy 282.638921 -313.850511) (xy 282.651318 -313.899469) (xy 282.655489 -313.9498) (xy 282.655486 -313.949842)
			(xy 282.994112 -313.949842) (xy 282.998072 -313.900788) (xy 283.009849 -313.853004) (xy 283.02914 -313.807728)
			(xy 283.055443 -313.766132) (xy 283.088078 -313.729295) (xy 283.126199 -313.69817) (xy 283.16882 -313.673563)
			(xy 283.214836 -313.656111) (xy 283.263055 -313.646267) (xy 283.31223 -313.644286) (xy 283.361085 -313.650218)
			(xy 283.408356 -313.66391) (xy 283.452818 -313.685008) (xy 283.493321 -313.712964) (xy 283.528814 -313.747056)
			(xy 283.558379 -313.7864) (xy 283.58125 -313.829977) (xy 283.596834 -313.876658) (xy 283.604729 -313.925235)
			(xy 283.605224 -313.949842) (xy 283.944072 -313.949842) (xy 283.948032 -313.900788) (xy 283.959809 -313.853004)
			(xy 283.9791 -313.807728) (xy 284.005403 -313.766132) (xy 284.038038 -313.729295) (xy 284.076159 -313.69817)
			(xy 284.11878 -313.673563) (xy 284.164796 -313.656111) (xy 284.213015 -313.646267) (xy 284.26219 -313.644286)
			(xy 284.311045 -313.650218) (xy 284.358316 -313.66391) (xy 284.402778 -313.685008) (xy 284.443281 -313.712964)
			(xy 284.478774 -313.747056) (xy 284.508339 -313.7864) (xy 284.53121 -313.829977) (xy 284.546794 -313.876658)
			(xy 284.554689 -313.925235) (xy 284.555184 -313.949842) (xy 284.894032 -313.949842) (xy 284.897992 -313.900788)
			(xy 284.909769 -313.853004) (xy 284.92906 -313.807728) (xy 284.955363 -313.766132) (xy 284.987998 -313.729295)
			(xy 285.026119 -313.69817) (xy 285.06874 -313.673563) (xy 285.114756 -313.656111) (xy 285.162975 -313.646267)
			(xy 285.21215 -313.644286) (xy 285.261005 -313.650218) (xy 285.308276 -313.66391) (xy 285.352738 -313.685008)
			(xy 285.393241 -313.712964) (xy 285.428734 -313.747056) (xy 285.458299 -313.7864) (xy 285.48117 -313.829977)
			(xy 285.496754 -313.876658) (xy 285.504649 -313.925235) (xy 285.505144 -313.949842) (xy 285.843992 -313.949842)
			(xy 285.847952 -313.900788) (xy 285.859729 -313.853004) (xy 285.87902 -313.807728) (xy 285.905323 -313.766132)
			(xy 285.937958 -313.729295) (xy 285.976079 -313.69817) (xy 286.0187 -313.673563) (xy 286.064716 -313.656111)
			(xy 286.112935 -313.646267) (xy 286.16211 -313.644286) (xy 286.210965 -313.650218) (xy 286.258236 -313.66391)
			(xy 286.302698 -313.685008) (xy 286.343201 -313.712964) (xy 286.378694 -313.747056) (xy 286.408259 -313.7864)
			(xy 286.43113 -313.829977) (xy 286.446714 -313.876658) (xy 286.454609 -313.925235) (xy 286.455104 -313.949842)
			(xy 286.793952 -313.949842) (xy 286.797912 -313.900788) (xy 286.809689 -313.853004) (xy 286.82898 -313.807728)
			(xy 286.855283 -313.766132) (xy 286.887918 -313.729295) (xy 286.926039 -313.69817) (xy 286.96866 -313.673563)
			(xy 287.014676 -313.656111) (xy 287.062895 -313.646267) (xy 287.11207 -313.644286) (xy 287.160925 -313.650218)
			(xy 287.208196 -313.66391) (xy 287.252658 -313.685008) (xy 287.293161 -313.712964) (xy 287.328654 -313.747056)
			(xy 287.358219 -313.7864) (xy 287.38109 -313.829977) (xy 287.396674 -313.876658) (xy 287.404569 -313.925235)
			(xy 287.405064 -313.949842) (xy 287.743912 -313.949842) (xy 287.747872 -313.900788) (xy 287.759649 -313.853004)
			(xy 287.77894 -313.807728) (xy 287.805243 -313.766132) (xy 287.837878 -313.729295) (xy 287.875999 -313.69817)
			(xy 287.91862 -313.673563) (xy 287.964636 -313.656111) (xy 288.012855 -313.646267) (xy 288.06203 -313.644286)
			(xy 288.110885 -313.650218) (xy 288.158156 -313.66391) (xy 288.202618 -313.685008) (xy 288.243121 -313.712964)
			(xy 288.278614 -313.747056) (xy 288.308179 -313.7864) (xy 288.33105 -313.829977) (xy 288.346634 -313.876658)
			(xy 288.354529 -313.925235) (xy 288.355024 -313.949842) (xy 288.694126 -313.949842) (xy 288.698086 -313.900788)
			(xy 288.709863 -313.853004) (xy 288.729154 -313.807728) (xy 288.755457 -313.766132) (xy 288.788092 -313.729295)
			(xy 288.826213 -313.69817) (xy 288.868834 -313.673563) (xy 288.91485 -313.656111) (xy 288.963069 -313.646267)
			(xy 289.012244 -313.644286) (xy 289.061099 -313.650218) (xy 289.10837 -313.66391) (xy 289.152832 -313.685008)
			(xy 289.193335 -313.712964) (xy 289.228828 -313.747056) (xy 289.258393 -313.7864) (xy 289.281264 -313.829977)
			(xy 289.296848 -313.876658) (xy 289.304743 -313.925235) (xy 289.305238 -313.949842) (xy 289.644086 -313.949842)
			(xy 289.648046 -313.900788) (xy 289.659823 -313.853004) (xy 289.679114 -313.807728) (xy 289.705417 -313.766132)
			(xy 289.738052 -313.729295) (xy 289.776173 -313.69817) (xy 289.818794 -313.673563) (xy 289.86481 -313.656111)
			(xy 289.913029 -313.646267) (xy 289.962204 -313.644286) (xy 290.011059 -313.650218) (xy 290.05833 -313.66391)
			(xy 290.102792 -313.685008) (xy 290.143295 -313.712964) (xy 290.178788 -313.747056) (xy 290.208353 -313.7864)
			(xy 290.231224 -313.829977) (xy 290.246808 -313.876658) (xy 290.254703 -313.925235) (xy 290.255198 -313.949842)
			(xy 290.594046 -313.949842) (xy 290.598006 -313.900788) (xy 290.609783 -313.853004) (xy 290.629074 -313.807728)
			(xy 290.655377 -313.766132) (xy 290.688012 -313.729295) (xy 290.726133 -313.69817) (xy 290.768754 -313.673563)
			(xy 290.81477 -313.656111) (xy 290.862989 -313.646267) (xy 290.912164 -313.644286) (xy 290.961019 -313.650218)
			(xy 291.00829 -313.66391) (xy 291.052752 -313.685008) (xy 291.093255 -313.712964) (xy 291.128748 -313.747056)
			(xy 291.158313 -313.7864) (xy 291.181184 -313.829977) (xy 291.196768 -313.876658) (xy 291.204663 -313.925235)
			(xy 291.205158 -313.949842) (xy 291.204663 -313.974449) (xy 291.204484 -313.97555) (xy 291.523162 -313.97555)
			(xy 291.523162 -313.924134) (xy 291.531205 -313.873352) (xy 291.547093 -313.824453) (xy 291.570436 -313.778641)
			(xy 291.600657 -313.737045) (xy 291.637013 -313.700689) (xy 291.678609 -313.670468) (xy 291.724421 -313.647125)
			(xy 291.77332 -313.631237) (xy 291.824102 -313.623194) (xy 291.875518 -313.623194) (xy 291.9263 -313.631237)
			(xy 291.975199 -313.647125) (xy 292.021011 -313.670468) (xy 292.062607 -313.700689) (xy 292.098963 -313.737045)
			(xy 292.129184 -313.778641) (xy 292.152527 -313.824453) (xy 292.168415 -313.873352) (xy 292.176458 -313.924134)
			(xy 292.176962 -313.949842) (xy 292.493966 -313.949842) (xy 292.497926 -313.900788) (xy 292.509703 -313.853004)
			(xy 292.528994 -313.807728) (xy 292.555297 -313.766132) (xy 292.587932 -313.729295) (xy 292.626053 -313.69817)
			(xy 292.668674 -313.673563) (xy 292.71469 -313.656111) (xy 292.762909 -313.646267) (xy 292.812084 -313.644286)
			(xy 292.860939 -313.650218) (xy 292.90821 -313.66391) (xy 292.952672 -313.685008) (xy 292.993175 -313.712964)
			(xy 293.028668 -313.747056) (xy 293.058233 -313.7864) (xy 293.081104 -313.829977) (xy 293.096688 -313.876658)
			(xy 293.104583 -313.925235) (xy 293.105078 -313.949842) (xy 293.104583 -313.974449) (xy 293.104404 -313.97555)
			(xy 293.423082 -313.97555) (xy 293.423082 -313.924134) (xy 293.431125 -313.873352) (xy 293.447013 -313.824453)
			(xy 293.470356 -313.778641) (xy 293.500577 -313.737045) (xy 293.536933 -313.700689) (xy 293.578529 -313.670468)
			(xy 293.624341 -313.647125) (xy 293.67324 -313.631237) (xy 293.724022 -313.623194) (xy 293.775438 -313.623194)
			(xy 293.82622 -313.631237) (xy 293.875119 -313.647125) (xy 293.920931 -313.670468) (xy 293.962527 -313.700689)
			(xy 293.998883 -313.737045) (xy 294.029104 -313.778641) (xy 294.052447 -313.824453) (xy 294.068335 -313.873352)
			(xy 294.076378 -313.924134) (xy 294.076882 -313.949842) (xy 294.393886 -313.949842) (xy 294.397846 -313.900788)
			(xy 294.409623 -313.853004) (xy 294.428914 -313.807728) (xy 294.455217 -313.766132) (xy 294.487852 -313.729295)
			(xy 294.525973 -313.69817) (xy 294.568594 -313.673563) (xy 294.61461 -313.656111) (xy 294.662829 -313.646267)
			(xy 294.712004 -313.644286) (xy 294.760859 -313.650218) (xy 294.80813 -313.66391) (xy 294.852592 -313.685008)
			(xy 294.893095 -313.712964) (xy 294.928588 -313.747056) (xy 294.958153 -313.7864) (xy 294.981024 -313.829977)
			(xy 294.996608 -313.876658) (xy 295.004503 -313.925235) (xy 295.004998 -313.949842) (xy 295.004503 -313.974449)
			(xy 295.004324 -313.97555) (xy 295.323256 -313.97555) (xy 295.323256 -313.924134) (xy 295.331299 -313.873352)
			(xy 295.347187 -313.824453) (xy 295.37053 -313.778641) (xy 295.400751 -313.737045) (xy 295.437107 -313.700689)
			(xy 295.478703 -313.670468) (xy 295.524515 -313.647125) (xy 295.573414 -313.631237) (xy 295.624196 -313.623194)
			(xy 295.675612 -313.623194) (xy 295.726394 -313.631237) (xy 295.775293 -313.647125) (xy 295.821105 -313.670468)
			(xy 295.862701 -313.700689) (xy 295.899057 -313.737045) (xy 295.929278 -313.778641) (xy 295.952621 -313.824453)
			(xy 295.968509 -313.873352) (xy 295.976552 -313.924134) (xy 295.977056 -313.949842) (xy 296.29406 -313.949842)
			(xy 296.29802 -313.900788) (xy 296.309797 -313.853004) (xy 296.329088 -313.807728) (xy 296.355391 -313.766132)
			(xy 296.388026 -313.729295) (xy 296.426147 -313.69817) (xy 296.468768 -313.673563) (xy 296.514784 -313.656111)
			(xy 296.563003 -313.646267) (xy 296.612178 -313.644286) (xy 296.661033 -313.650218) (xy 296.708304 -313.66391)
			(xy 296.752766 -313.685008) (xy 296.793269 -313.712964) (xy 296.828762 -313.747056) (xy 296.858327 -313.7864)
			(xy 296.881198 -313.829977) (xy 296.896782 -313.876658) (xy 296.904677 -313.925235) (xy 296.905172 -313.949842)
			(xy 296.904677 -313.974449) (xy 296.904498 -313.97555) (xy 297.223176 -313.97555) (xy 297.223176 -313.924134)
			(xy 297.231219 -313.873352) (xy 297.247107 -313.824453) (xy 297.27045 -313.778641) (xy 297.300671 -313.737045)
			(xy 297.337027 -313.700689) (xy 297.378623 -313.670468) (xy 297.424435 -313.647125) (xy 297.473334 -313.631237)
			(xy 297.524116 -313.623194) (xy 297.575532 -313.623194) (xy 297.626314 -313.631237) (xy 297.675213 -313.647125)
			(xy 297.721025 -313.670468) (xy 297.762621 -313.700689) (xy 297.798977 -313.737045) (xy 297.829198 -313.778641)
			(xy 297.852541 -313.824453) (xy 297.868429 -313.873352) (xy 297.876472 -313.924134) (xy 297.876976 -313.949842)
			(xy 298.19398 -313.949842) (xy 298.19794 -313.900788) (xy 298.209717 -313.853004) (xy 298.229008 -313.807728)
			(xy 298.255311 -313.766132) (xy 298.287946 -313.729295) (xy 298.326067 -313.69817) (xy 298.368688 -313.673563)
			(xy 298.414704 -313.656111) (xy 298.462923 -313.646267) (xy 298.512098 -313.644286) (xy 298.560953 -313.650218)
			(xy 298.608224 -313.66391) (xy 298.652686 -313.685008) (xy 298.693189 -313.712964) (xy 298.728682 -313.747056)
			(xy 298.758247 -313.7864) (xy 298.781118 -313.829977) (xy 298.796702 -313.876658) (xy 298.804597 -313.925235)
			(xy 298.805092 -313.949842) (xy 298.804597 -313.974449) (xy 298.804418 -313.97555) (xy 299.123096 -313.97555)
			(xy 299.123096 -313.924134) (xy 299.131139 -313.873352) (xy 299.147027 -313.824453) (xy 299.17037 -313.778641)
			(xy 299.200591 -313.737045) (xy 299.236947 -313.700689) (xy 299.278543 -313.670468) (xy 299.324355 -313.647125)
			(xy 299.373254 -313.631237) (xy 299.424036 -313.623194) (xy 299.475452 -313.623194) (xy 299.526234 -313.631237)
			(xy 299.575133 -313.647125) (xy 299.620945 -313.670468) (xy 299.662541 -313.700689) (xy 299.698897 -313.737045)
			(xy 299.729118 -313.778641) (xy 299.752461 -313.824453) (xy 299.768349 -313.873352) (xy 299.776392 -313.924134)
			(xy 299.776896 -313.949842) (xy 300.0939 -313.949842) (xy 300.09786 -313.900788) (xy 300.109637 -313.853004)
			(xy 300.128928 -313.807728) (xy 300.155231 -313.766132) (xy 300.187866 -313.729295) (xy 300.225987 -313.69817)
			(xy 300.268608 -313.673563) (xy 300.314624 -313.656111) (xy 300.362843 -313.646267) (xy 300.412018 -313.644286)
			(xy 300.460873 -313.650218) (xy 300.508144 -313.66391) (xy 300.552606 -313.685008) (xy 300.593109 -313.712964)
			(xy 300.628602 -313.747056) (xy 300.658167 -313.7864) (xy 300.681038 -313.829977) (xy 300.696622 -313.876658)
			(xy 300.704517 -313.925235) (xy 300.705012 -313.949842) (xy 300.704517 -313.974449) (xy 300.704338 -313.97555)
			(xy 301.02327 -313.97555) (xy 301.02327 -313.924134) (xy 301.031313 -313.873352) (xy 301.047201 -313.824453)
			(xy 301.070544 -313.778641) (xy 301.100765 -313.737045) (xy 301.137121 -313.700689) (xy 301.178717 -313.670468)
			(xy 301.224529 -313.647125) (xy 301.273428 -313.631237) (xy 301.32421 -313.623194) (xy 301.375626 -313.623194)
			(xy 301.426408 -313.631237) (xy 301.475307 -313.647125) (xy 301.521119 -313.670468) (xy 301.562715 -313.700689)
			(xy 301.599071 -313.737045) (xy 301.629292 -313.778641) (xy 301.652635 -313.824453) (xy 301.668523 -313.873352)
			(xy 301.676566 -313.924134) (xy 301.67707 -313.949842) (xy 301.994074 -313.949842) (xy 301.998034 -313.900788)
			(xy 302.009811 -313.853004) (xy 302.029102 -313.807728) (xy 302.055405 -313.766132) (xy 302.08804 -313.729295)
			(xy 302.126161 -313.69817) (xy 302.168782 -313.673563) (xy 302.214798 -313.656111) (xy 302.263017 -313.646267)
			(xy 302.312192 -313.644286) (xy 302.361047 -313.650218) (xy 302.408318 -313.66391) (xy 302.45278 -313.685008)
			(xy 302.493283 -313.712964) (xy 302.528776 -313.747056) (xy 302.558341 -313.7864) (xy 302.581212 -313.829977)
			(xy 302.596796 -313.876658) (xy 302.604691 -313.925235) (xy 302.605186 -313.949842) (xy 302.604691 -313.974449)
			(xy 302.604512 -313.97555) (xy 302.92319 -313.97555) (xy 302.92319 -313.924134) (xy 302.931233 -313.873352)
			(xy 302.947121 -313.824453) (xy 302.970464 -313.778641) (xy 303.000685 -313.737045) (xy 303.037041 -313.700689)
			(xy 303.078637 -313.670468) (xy 303.124449 -313.647125) (xy 303.173348 -313.631237) (xy 303.22413 -313.623194)
			(xy 303.275546 -313.623194) (xy 303.326328 -313.631237) (xy 303.375227 -313.647125) (xy 303.421039 -313.670468)
			(xy 303.462635 -313.700689) (xy 303.498991 -313.737045) (xy 303.529212 -313.778641) (xy 303.552555 -313.824453)
			(xy 303.568443 -313.873352) (xy 303.576486 -313.924134) (xy 303.57699 -313.949842) (xy 303.893994 -313.949842)
			(xy 303.897954 -313.900788) (xy 303.909731 -313.853004) (xy 303.929022 -313.807728) (xy 303.955325 -313.766132)
			(xy 303.98796 -313.729295) (xy 304.026081 -313.69817) (xy 304.068702 -313.673563) (xy 304.114718 -313.656111)
			(xy 304.162937 -313.646267) (xy 304.212112 -313.644286) (xy 304.260967 -313.650218) (xy 304.308238 -313.66391)
			(xy 304.3527 -313.685008) (xy 304.393203 -313.712964) (xy 304.428696 -313.747056) (xy 304.458261 -313.7864)
			(xy 304.481132 -313.829977) (xy 304.496716 -313.876658) (xy 304.504611 -313.925235) (xy 304.505106 -313.949842)
			(xy 304.504611 -313.974449) (xy 304.504432 -313.97555) (xy 304.82311 -313.97555) (xy 304.82311 -313.924134)
			(xy 304.831153 -313.873352) (xy 304.847041 -313.824453) (xy 304.870384 -313.778641) (xy 304.900605 -313.737045)
			(xy 304.936961 -313.700689) (xy 304.978557 -313.670468) (xy 305.024369 -313.647125) (xy 305.073268 -313.631237)
			(xy 305.12405 -313.623194) (xy 305.175466 -313.623194) (xy 305.226248 -313.631237) (xy 305.275147 -313.647125)
			(xy 305.320959 -313.670468) (xy 305.362555 -313.700689) (xy 305.398911 -313.737045) (xy 305.429132 -313.778641)
			(xy 305.452475 -313.824453) (xy 305.468363 -313.873352) (xy 305.476406 -313.924134) (xy 305.47691 -313.949842)
			(xy 305.793914 -313.949842) (xy 305.797874 -313.900788) (xy 305.809651 -313.853004) (xy 305.828942 -313.807728)
			(xy 305.855245 -313.766132) (xy 305.88788 -313.729295) (xy 305.926001 -313.69817) (xy 305.968622 -313.673563)
			(xy 306.014638 -313.656111) (xy 306.062857 -313.646267) (xy 306.112032 -313.644286) (xy 306.160887 -313.650218)
			(xy 306.208158 -313.66391) (xy 306.25262 -313.685008) (xy 306.293123 -313.712964) (xy 306.328616 -313.747056)
			(xy 306.358181 -313.7864) (xy 306.381052 -313.829977) (xy 306.396636 -313.876658) (xy 306.404531 -313.925235)
			(xy 306.405026 -313.949842) (xy 306.744128 -313.949842) (xy 306.748088 -313.900788) (xy 306.759865 -313.853004)
			(xy 306.779156 -313.807728) (xy 306.805459 -313.766132) (xy 306.838094 -313.729295) (xy 306.876215 -313.69817)
			(xy 306.918836 -313.673563) (xy 306.964852 -313.656111) (xy 307.013071 -313.646267) (xy 307.062246 -313.644286)
			(xy 307.111101 -313.650218) (xy 307.158372 -313.66391) (xy 307.202834 -313.685008) (xy 307.243337 -313.712964)
			(xy 307.27883 -313.747056) (xy 307.308395 -313.7864) (xy 307.331266 -313.829977) (xy 307.34685 -313.876658)
			(xy 307.354745 -313.925235) (xy 307.35524 -313.949842) (xy 307.694088 -313.949842) (xy 307.698048 -313.900788)
			(xy 307.709825 -313.853004) (xy 307.729116 -313.807728) (xy 307.755419 -313.766132) (xy 307.788054 -313.729295)
			(xy 307.826175 -313.69817) (xy 307.868796 -313.673563) (xy 307.914812 -313.656111) (xy 307.963031 -313.646267)
			(xy 308.012206 -313.644286) (xy 308.061061 -313.650218) (xy 308.108332 -313.66391) (xy 308.152794 -313.685008)
			(xy 308.193297 -313.712964) (xy 308.22879 -313.747056) (xy 308.258355 -313.7864) (xy 308.281226 -313.829977)
			(xy 308.29681 -313.876658) (xy 308.304705 -313.925235) (xy 308.3052 -313.949842) (xy 308.644048 -313.949842)
			(xy 308.648008 -313.900788) (xy 308.659785 -313.853004) (xy 308.679076 -313.807728) (xy 308.705379 -313.766132)
			(xy 308.738014 -313.729295) (xy 308.776135 -313.69817) (xy 308.818756 -313.673563) (xy 308.864772 -313.656111)
			(xy 308.912991 -313.646267) (xy 308.962166 -313.644286) (xy 309.011021 -313.650218) (xy 309.058292 -313.66391)
			(xy 309.102754 -313.685008) (xy 309.143257 -313.712964) (xy 309.17875 -313.747056) (xy 309.208315 -313.7864)
			(xy 309.231186 -313.829977) (xy 309.24677 -313.876658) (xy 309.254665 -313.925235) (xy 309.25516 -313.949842)
			(xy 309.594008 -313.949842) (xy 309.597968 -313.900788) (xy 309.609745 -313.853004) (xy 309.629036 -313.807728)
			(xy 309.655339 -313.766132) (xy 309.687974 -313.729295) (xy 309.726095 -313.69817) (xy 309.768716 -313.673563)
			(xy 309.814732 -313.656111) (xy 309.862951 -313.646267) (xy 309.912126 -313.644286) (xy 309.960981 -313.650218)
			(xy 310.008252 -313.66391) (xy 310.052714 -313.685008) (xy 310.093217 -313.712964) (xy 310.12871 -313.747056)
			(xy 310.158275 -313.7864) (xy 310.181146 -313.829977) (xy 310.19673 -313.876658) (xy 310.204625 -313.925235)
			(xy 310.20512 -313.949842) (xy 310.543968 -313.949842) (xy 310.547928 -313.900788) (xy 310.559705 -313.853004)
			(xy 310.578996 -313.807728) (xy 310.605299 -313.766132) (xy 310.637934 -313.729295) (xy 310.676055 -313.69817)
			(xy 310.718676 -313.673563) (xy 310.764692 -313.656111) (xy 310.812911 -313.646267) (xy 310.862086 -313.644286)
			(xy 310.910941 -313.650218) (xy 310.958212 -313.66391) (xy 311.002674 -313.685008) (xy 311.043177 -313.712964)
			(xy 311.07867 -313.747056) (xy 311.108235 -313.7864) (xy 311.131106 -313.829977) (xy 311.14669 -313.876658)
			(xy 311.154585 -313.925235) (xy 311.15508 -313.949842) (xy 311.493928 -313.949842) (xy 311.497888 -313.900788)
			(xy 311.509665 -313.853004) (xy 311.528956 -313.807728) (xy 311.555259 -313.766132) (xy 311.587894 -313.729295)
			(xy 311.626015 -313.69817) (xy 311.668636 -313.673563) (xy 311.714652 -313.656111) (xy 311.762871 -313.646267)
			(xy 311.812046 -313.644286) (xy 311.860901 -313.650218) (xy 311.908172 -313.66391) (xy 311.952634 -313.685008)
			(xy 311.993137 -313.712964) (xy 312.02863 -313.747056) (xy 312.058195 -313.7864) (xy 312.081066 -313.829977)
			(xy 312.09665 -313.876658) (xy 312.104545 -313.925235) (xy 312.10504 -313.949842) (xy 312.443888 -313.949842)
			(xy 312.447848 -313.900788) (xy 312.459625 -313.853004) (xy 312.478916 -313.807728) (xy 312.505219 -313.766132)
			(xy 312.537854 -313.729295) (xy 312.575975 -313.69817) (xy 312.618596 -313.673563) (xy 312.664612 -313.656111)
			(xy 312.712831 -313.646267) (xy 312.762006 -313.644286) (xy 312.810861 -313.650218) (xy 312.858132 -313.66391)
			(xy 312.902594 -313.685008) (xy 312.943097 -313.712964) (xy 312.97859 -313.747056) (xy 313.008155 -313.7864)
			(xy 313.031026 -313.829977) (xy 313.04661 -313.876658) (xy 313.054505 -313.925235) (xy 313.055 -313.949842)
			(xy 313.394102 -313.949842) (xy 313.398062 -313.900788) (xy 313.409839 -313.853004) (xy 313.42913 -313.807728)
			(xy 313.455433 -313.766132) (xy 313.488068 -313.729295) (xy 313.526189 -313.69817) (xy 313.56881 -313.673563)
			(xy 313.614826 -313.656111) (xy 313.663045 -313.646267) (xy 313.71222 -313.644286) (xy 313.761075 -313.650218)
			(xy 313.808346 -313.66391) (xy 313.852808 -313.685008) (xy 313.893311 -313.712964) (xy 313.928804 -313.747056)
			(xy 313.958369 -313.7864) (xy 313.98124 -313.829977) (xy 313.996824 -313.876658) (xy 314.004719 -313.925235)
			(xy 314.005214 -313.949842) (xy 314.344062 -313.949842) (xy 314.348022 -313.900788) (xy 314.359799 -313.853004)
			(xy 314.37909 -313.807728) (xy 314.405393 -313.766132) (xy 314.438028 -313.729295) (xy 314.476149 -313.69817)
			(xy 314.51877 -313.673563) (xy 314.564786 -313.656111) (xy 314.613005 -313.646267) (xy 314.66218 -313.644286)
			(xy 314.711035 -313.650218) (xy 314.758306 -313.66391) (xy 314.802768 -313.685008) (xy 314.843271 -313.712964)
			(xy 314.878764 -313.747056) (xy 314.908329 -313.7864) (xy 314.9312 -313.829977) (xy 314.946784 -313.876658)
			(xy 314.954679 -313.925235) (xy 314.955174 -313.949842) (xy 314.954679 -313.974449) (xy 314.946784 -314.023026)
			(xy 314.9312 -314.069707) (xy 314.908329 -314.113284) (xy 314.878764 -314.152628) (xy 314.843271 -314.18672)
			(xy 314.802768 -314.214676) (xy 314.758306 -314.235774) (xy 314.711035 -314.249466) (xy 314.66218 -314.255398)
			(xy 314.613005 -314.253417) (xy 314.564786 -314.243573) (xy 314.51877 -314.226121) (xy 314.476149 -314.201514)
			(xy 314.438028 -314.170389) (xy 314.405393 -314.133552) (xy 314.37909 -314.091956) (xy 314.359799 -314.04668)
			(xy 314.348022 -313.998896) (xy 314.344062 -313.949842) (xy 314.005214 -313.949842) (xy 314.004719 -313.974449)
			(xy 313.996824 -314.023026) (xy 313.98124 -314.069707) (xy 313.958369 -314.113284) (xy 313.928804 -314.152628)
			(xy 313.893311 -314.18672) (xy 313.852808 -314.214676) (xy 313.808346 -314.235774) (xy 313.761075 -314.249466)
			(xy 313.71222 -314.255398) (xy 313.663045 -314.253417) (xy 313.614826 -314.243573) (xy 313.56881 -314.226121)
			(xy 313.526189 -314.201514) (xy 313.488068 -314.170389) (xy 313.455433 -314.133552) (xy 313.42913 -314.091956)
			(xy 313.409839 -314.04668) (xy 313.398062 -313.998896) (xy 313.394102 -313.949842) (xy 313.055 -313.949842)
			(xy 313.054505 -313.974449) (xy 313.04661 -314.023026) (xy 313.031026 -314.069707) (xy 313.008155 -314.113284)
			(xy 312.97859 -314.152628) (xy 312.943097 -314.18672) (xy 312.902594 -314.214676) (xy 312.858132 -314.235774)
			(xy 312.810861 -314.249466) (xy 312.762006 -314.255398) (xy 312.712831 -314.253417) (xy 312.664612 -314.243573)
			(xy 312.618596 -314.226121) (xy 312.575975 -314.201514) (xy 312.537854 -314.170389) (xy 312.505219 -314.133552)
			(xy 312.478916 -314.091956) (xy 312.459625 -314.04668) (xy 312.447848 -313.998896) (xy 312.443888 -313.949842)
			(xy 312.10504 -313.949842) (xy 312.104545 -313.974449) (xy 312.09665 -314.023026) (xy 312.081066 -314.069707)
			(xy 312.058195 -314.113284) (xy 312.02863 -314.152628) (xy 311.993137 -314.18672) (xy 311.952634 -314.214676)
			(xy 311.908172 -314.235774) (xy 311.860901 -314.249466) (xy 311.812046 -314.255398) (xy 311.762871 -314.253417)
			(xy 311.714652 -314.243573) (xy 311.668636 -314.226121) (xy 311.626015 -314.201514) (xy 311.587894 -314.170389)
			(xy 311.555259 -314.133552) (xy 311.528956 -314.091956) (xy 311.509665 -314.04668) (xy 311.497888 -313.998896)
			(xy 311.493928 -313.949842) (xy 311.15508 -313.949842) (xy 311.154585 -313.974449) (xy 311.14669 -314.023026)
			(xy 311.131106 -314.069707) (xy 311.108235 -314.113284) (xy 311.07867 -314.152628) (xy 311.043177 -314.18672)
			(xy 311.002674 -314.214676) (xy 310.958212 -314.235774) (xy 310.910941 -314.249466) (xy 310.862086 -314.255398)
			(xy 310.812911 -314.253417) (xy 310.764692 -314.243573) (xy 310.718676 -314.226121) (xy 310.676055 -314.201514)
			(xy 310.637934 -314.170389) (xy 310.605299 -314.133552) (xy 310.578996 -314.091956) (xy 310.559705 -314.04668)
			(xy 310.547928 -313.998896) (xy 310.543968 -313.949842) (xy 310.20512 -313.949842) (xy 310.204625 -313.974449)
			(xy 310.19673 -314.023026) (xy 310.181146 -314.069707) (xy 310.158275 -314.113284) (xy 310.12871 -314.152628)
			(xy 310.093217 -314.18672) (xy 310.052714 -314.214676) (xy 310.008252 -314.235774) (xy 309.960981 -314.249466)
			(xy 309.912126 -314.255398) (xy 309.862951 -314.253417) (xy 309.814732 -314.243573) (xy 309.768716 -314.226121)
			(xy 309.726095 -314.201514) (xy 309.687974 -314.170389) (xy 309.655339 -314.133552) (xy 309.629036 -314.091956)
			(xy 309.609745 -314.04668) (xy 309.597968 -313.998896) (xy 309.594008 -313.949842) (xy 309.25516 -313.949842)
			(xy 309.254665 -313.974449) (xy 309.24677 -314.023026) (xy 309.231186 -314.069707) (xy 309.208315 -314.113284)
			(xy 309.17875 -314.152628) (xy 309.143257 -314.18672) (xy 309.102754 -314.214676) (xy 309.058292 -314.235774)
			(xy 309.011021 -314.249466) (xy 308.962166 -314.255398) (xy 308.912991 -314.253417) (xy 308.864772 -314.243573)
			(xy 308.818756 -314.226121) (xy 308.776135 -314.201514) (xy 308.738014 -314.170389) (xy 308.705379 -314.133552)
			(xy 308.679076 -314.091956) (xy 308.659785 -314.04668) (xy 308.648008 -313.998896) (xy 308.644048 -313.949842)
			(xy 308.3052 -313.949842) (xy 308.304705 -313.974449) (xy 308.29681 -314.023026) (xy 308.281226 -314.069707)
			(xy 308.258355 -314.113284) (xy 308.22879 -314.152628) (xy 308.193297 -314.18672) (xy 308.152794 -314.214676)
			(xy 308.108332 -314.235774) (xy 308.061061 -314.249466) (xy 308.012206 -314.255398) (xy 307.963031 -314.253417)
			(xy 307.914812 -314.243573) (xy 307.868796 -314.226121) (xy 307.826175 -314.201514) (xy 307.788054 -314.170389)
			(xy 307.755419 -314.133552) (xy 307.729116 -314.091956) (xy 307.709825 -314.04668) (xy 307.698048 -313.998896)
			(xy 307.694088 -313.949842) (xy 307.35524 -313.949842) (xy 307.354745 -313.974449) (xy 307.34685 -314.023026)
			(xy 307.331266 -314.069707) (xy 307.308395 -314.113284) (xy 307.27883 -314.152628) (xy 307.243337 -314.18672)
			(xy 307.202834 -314.214676) (xy 307.158372 -314.235774) (xy 307.111101 -314.249466) (xy 307.062246 -314.255398)
			(xy 307.013071 -314.253417) (xy 306.964852 -314.243573) (xy 306.918836 -314.226121) (xy 306.876215 -314.201514)
			(xy 306.838094 -314.170389) (xy 306.805459 -314.133552) (xy 306.779156 -314.091956) (xy 306.759865 -314.04668)
			(xy 306.748088 -313.998896) (xy 306.744128 -313.949842) (xy 306.405026 -313.949842) (xy 306.404531 -313.974449)
			(xy 306.396636 -314.023026) (xy 306.381052 -314.069707) (xy 306.358181 -314.113284) (xy 306.328616 -314.152628)
			(xy 306.293123 -314.18672) (xy 306.25262 -314.214676) (xy 306.208158 -314.235774) (xy 306.160887 -314.249466)
			(xy 306.112032 -314.255398) (xy 306.062857 -314.253417) (xy 306.014638 -314.243573) (xy 305.968622 -314.226121)
			(xy 305.926001 -314.201514) (xy 305.88788 -314.170389) (xy 305.855245 -314.133552) (xy 305.828942 -314.091956)
			(xy 305.809651 -314.04668) (xy 305.797874 -313.998896) (xy 305.793914 -313.949842) (xy 305.47691 -313.949842)
			(xy 305.476406 -313.97555) (xy 305.468363 -314.026332) (xy 305.452475 -314.075231) (xy 305.429132 -314.121043)
			(xy 305.398911 -314.162639) (xy 305.362555 -314.198995) (xy 305.320959 -314.229216) (xy 305.275147 -314.252559)
			(xy 305.226248 -314.268447) (xy 305.175466 -314.27649) (xy 305.12405 -314.27649) (xy 305.073268 -314.268447)
			(xy 305.024369 -314.252559) (xy 304.978557 -314.229216) (xy 304.936961 -314.198995) (xy 304.900605 -314.162639)
			(xy 304.870384 -314.121043) (xy 304.847041 -314.075231) (xy 304.831153 -314.026332) (xy 304.82311 -313.97555)
			(xy 304.504432 -313.97555) (xy 304.496716 -314.023026) (xy 304.481132 -314.069707) (xy 304.458261 -314.113284)
			(xy 304.428696 -314.152628) (xy 304.393203 -314.18672) (xy 304.3527 -314.214676) (xy 304.308238 -314.235774)
			(xy 304.260967 -314.249466) (xy 304.212112 -314.255398) (xy 304.162937 -314.253417) (xy 304.114718 -314.243573)
			(xy 304.068702 -314.226121) (xy 304.026081 -314.201514) (xy 303.98796 -314.170389) (xy 303.955325 -314.133552)
			(xy 303.929022 -314.091956) (xy 303.909731 -314.04668) (xy 303.897954 -313.998896) (xy 303.893994 -313.949842)
			(xy 303.57699 -313.949842) (xy 303.576486 -313.97555) (xy 303.568443 -314.026332) (xy 303.552555 -314.075231)
			(xy 303.529212 -314.121043) (xy 303.498991 -314.162639) (xy 303.462635 -314.198995) (xy 303.421039 -314.229216)
			(xy 303.375227 -314.252559) (xy 303.326328 -314.268447) (xy 303.275546 -314.27649) (xy 303.22413 -314.27649)
			(xy 303.173348 -314.268447) (xy 303.124449 -314.252559) (xy 303.078637 -314.229216) (xy 303.037041 -314.198995)
			(xy 303.000685 -314.162639) (xy 302.970464 -314.121043) (xy 302.947121 -314.075231) (xy 302.931233 -314.026332)
			(xy 302.92319 -313.97555) (xy 302.604512 -313.97555) (xy 302.596796 -314.023026) (xy 302.581212 -314.069707)
			(xy 302.558341 -314.113284) (xy 302.528776 -314.152628) (xy 302.493283 -314.18672) (xy 302.45278 -314.214676)
			(xy 302.408318 -314.235774) (xy 302.361047 -314.249466) (xy 302.312192 -314.255398) (xy 302.263017 -314.253417)
			(xy 302.214798 -314.243573) (xy 302.168782 -314.226121) (xy 302.126161 -314.201514) (xy 302.08804 -314.170389)
			(xy 302.055405 -314.133552) (xy 302.029102 -314.091956) (xy 302.009811 -314.04668) (xy 301.998034 -313.998896)
			(xy 301.994074 -313.949842) (xy 301.67707 -313.949842) (xy 301.676566 -313.97555) (xy 301.668523 -314.026332)
			(xy 301.652635 -314.075231) (xy 301.629292 -314.121043) (xy 301.599071 -314.162639) (xy 301.562715 -314.198995)
			(xy 301.521119 -314.229216) (xy 301.475307 -314.252559) (xy 301.426408 -314.268447) (xy 301.375626 -314.27649)
			(xy 301.32421 -314.27649) (xy 301.273428 -314.268447) (xy 301.224529 -314.252559) (xy 301.178717 -314.229216)
			(xy 301.137121 -314.198995) (xy 301.100765 -314.162639) (xy 301.070544 -314.121043) (xy 301.047201 -314.075231)
			(xy 301.031313 -314.026332) (xy 301.02327 -313.97555) (xy 300.704338 -313.97555) (xy 300.696622 -314.023026)
			(xy 300.681038 -314.069707) (xy 300.658167 -314.113284) (xy 300.628602 -314.152628) (xy 300.593109 -314.18672)
			(xy 300.552606 -314.214676) (xy 300.508144 -314.235774) (xy 300.460873 -314.249466) (xy 300.412018 -314.255398)
			(xy 300.362843 -314.253417) (xy 300.314624 -314.243573) (xy 300.268608 -314.226121) (xy 300.225987 -314.201514)
			(xy 300.187866 -314.170389) (xy 300.155231 -314.133552) (xy 300.128928 -314.091956) (xy 300.109637 -314.04668)
			(xy 300.09786 -313.998896) (xy 300.0939 -313.949842) (xy 299.776896 -313.949842) (xy 299.776392 -313.97555)
			(xy 299.768349 -314.026332) (xy 299.752461 -314.075231) (xy 299.729118 -314.121043) (xy 299.698897 -314.162639)
			(xy 299.662541 -314.198995) (xy 299.620945 -314.229216) (xy 299.575133 -314.252559) (xy 299.526234 -314.268447)
			(xy 299.475452 -314.27649) (xy 299.424036 -314.27649) (xy 299.373254 -314.268447) (xy 299.324355 -314.252559)
			(xy 299.278543 -314.229216) (xy 299.236947 -314.198995) (xy 299.200591 -314.162639) (xy 299.17037 -314.121043)
			(xy 299.147027 -314.075231) (xy 299.131139 -314.026332) (xy 299.123096 -313.97555) (xy 298.804418 -313.97555)
			(xy 298.796702 -314.023026) (xy 298.781118 -314.069707) (xy 298.758247 -314.113284) (xy 298.728682 -314.152628)
			(xy 298.693189 -314.18672) (xy 298.652686 -314.214676) (xy 298.608224 -314.235774) (xy 298.560953 -314.249466)
			(xy 298.512098 -314.255398) (xy 298.462923 -314.253417) (xy 298.414704 -314.243573) (xy 298.368688 -314.226121)
			(xy 298.326067 -314.201514) (xy 298.287946 -314.170389) (xy 298.255311 -314.133552) (xy 298.229008 -314.091956)
			(xy 298.209717 -314.04668) (xy 298.19794 -313.998896) (xy 298.19398 -313.949842) (xy 297.876976 -313.949842)
			(xy 297.876472 -313.97555) (xy 297.868429 -314.026332) (xy 297.852541 -314.075231) (xy 297.829198 -314.121043)
			(xy 297.798977 -314.162639) (xy 297.762621 -314.198995) (xy 297.721025 -314.229216) (xy 297.675213 -314.252559)
			(xy 297.626314 -314.268447) (xy 297.575532 -314.27649) (xy 297.524116 -314.27649) (xy 297.473334 -314.268447)
			(xy 297.424435 -314.252559) (xy 297.378623 -314.229216) (xy 297.337027 -314.198995) (xy 297.300671 -314.162639)
			(xy 297.27045 -314.121043) (xy 297.247107 -314.075231) (xy 297.231219 -314.026332) (xy 297.223176 -313.97555)
			(xy 296.904498 -313.97555) (xy 296.896782 -314.023026) (xy 296.881198 -314.069707) (xy 296.858327 -314.113284)
			(xy 296.828762 -314.152628) (xy 296.793269 -314.18672) (xy 296.752766 -314.214676) (xy 296.708304 -314.235774)
			(xy 296.661033 -314.249466) (xy 296.612178 -314.255398) (xy 296.563003 -314.253417) (xy 296.514784 -314.243573)
			(xy 296.468768 -314.226121) (xy 296.426147 -314.201514) (xy 296.388026 -314.170389) (xy 296.355391 -314.133552)
			(xy 296.329088 -314.091956) (xy 296.309797 -314.04668) (xy 296.29802 -313.998896) (xy 296.29406 -313.949842)
			(xy 295.977056 -313.949842) (xy 295.976552 -313.97555) (xy 295.968509 -314.026332) (xy 295.952621 -314.075231)
			(xy 295.929278 -314.121043) (xy 295.899057 -314.162639) (xy 295.862701 -314.198995) (xy 295.821105 -314.229216)
			(xy 295.775293 -314.252559) (xy 295.726394 -314.268447) (xy 295.675612 -314.27649) (xy 295.624196 -314.27649)
			(xy 295.573414 -314.268447) (xy 295.524515 -314.252559) (xy 295.478703 -314.229216) (xy 295.437107 -314.198995)
			(xy 295.400751 -314.162639) (xy 295.37053 -314.121043) (xy 295.347187 -314.075231) (xy 295.331299 -314.026332)
			(xy 295.323256 -313.97555) (xy 295.004324 -313.97555) (xy 294.996608 -314.023026) (xy 294.981024 -314.069707)
			(xy 294.958153 -314.113284) (xy 294.928588 -314.152628) (xy 294.893095 -314.18672) (xy 294.852592 -314.214676)
			(xy 294.80813 -314.235774) (xy 294.760859 -314.249466) (xy 294.712004 -314.255398) (xy 294.662829 -314.253417)
			(xy 294.61461 -314.243573) (xy 294.568594 -314.226121) (xy 294.525973 -314.201514) (xy 294.487852 -314.170389)
			(xy 294.455217 -314.133552) (xy 294.428914 -314.091956) (xy 294.409623 -314.04668) (xy 294.397846 -313.998896)
			(xy 294.393886 -313.949842) (xy 294.076882 -313.949842) (xy 294.076378 -313.97555) (xy 294.068335 -314.026332)
			(xy 294.052447 -314.075231) (xy 294.029104 -314.121043) (xy 293.998883 -314.162639) (xy 293.962527 -314.198995)
			(xy 293.920931 -314.229216) (xy 293.875119 -314.252559) (xy 293.82622 -314.268447) (xy 293.775438 -314.27649)
			(xy 293.724022 -314.27649) (xy 293.67324 -314.268447) (xy 293.624341 -314.252559) (xy 293.578529 -314.229216)
			(xy 293.536933 -314.198995) (xy 293.500577 -314.162639) (xy 293.470356 -314.121043) (xy 293.447013 -314.075231)
			(xy 293.431125 -314.026332) (xy 293.423082 -313.97555) (xy 293.104404 -313.97555) (xy 293.096688 -314.023026)
			(xy 293.081104 -314.069707) (xy 293.058233 -314.113284) (xy 293.028668 -314.152628) (xy 292.993175 -314.18672)
			(xy 292.952672 -314.214676) (xy 292.90821 -314.235774) (xy 292.860939 -314.249466) (xy 292.812084 -314.255398)
			(xy 292.762909 -314.253417) (xy 292.71469 -314.243573) (xy 292.668674 -314.226121) (xy 292.626053 -314.201514)
			(xy 292.587932 -314.170389) (xy 292.555297 -314.133552) (xy 292.528994 -314.091956) (xy 292.509703 -314.04668)
			(xy 292.497926 -313.998896) (xy 292.493966 -313.949842) (xy 292.176962 -313.949842) (xy 292.176458 -313.97555)
			(xy 292.168415 -314.026332) (xy 292.152527 -314.075231) (xy 292.129184 -314.121043) (xy 292.098963 -314.162639)
			(xy 292.062607 -314.198995) (xy 292.021011 -314.229216) (xy 291.975199 -314.252559) (xy 291.9263 -314.268447)
			(xy 291.875518 -314.27649) (xy 291.824102 -314.27649) (xy 291.77332 -314.268447) (xy 291.724421 -314.252559)
			(xy 291.678609 -314.229216) (xy 291.637013 -314.198995) (xy 291.600657 -314.162639) (xy 291.570436 -314.121043)
			(xy 291.547093 -314.075231) (xy 291.531205 -314.026332) (xy 291.523162 -313.97555) (xy 291.204484 -313.97555)
			(xy 291.196768 -314.023026) (xy 291.181184 -314.069707) (xy 291.158313 -314.113284) (xy 291.128748 -314.152628)
			(xy 291.093255 -314.18672) (xy 291.052752 -314.214676) (xy 291.00829 -314.235774) (xy 290.961019 -314.249466)
			(xy 290.912164 -314.255398) (xy 290.862989 -314.253417) (xy 290.81477 -314.243573) (xy 290.768754 -314.226121)
			(xy 290.726133 -314.201514) (xy 290.688012 -314.170389) (xy 290.655377 -314.133552) (xy 290.629074 -314.091956)
			(xy 290.609783 -314.04668) (xy 290.598006 -313.998896) (xy 290.594046 -313.949842) (xy 290.255198 -313.949842)
			(xy 290.254703 -313.974449) (xy 290.246808 -314.023026) (xy 290.231224 -314.069707) (xy 290.208353 -314.113284)
			(xy 290.178788 -314.152628) (xy 290.143295 -314.18672) (xy 290.102792 -314.214676) (xy 290.05833 -314.235774)
			(xy 290.011059 -314.249466) (xy 289.962204 -314.255398) (xy 289.913029 -314.253417) (xy 289.86481 -314.243573)
			(xy 289.818794 -314.226121) (xy 289.776173 -314.201514) (xy 289.738052 -314.170389) (xy 289.705417 -314.133552)
			(xy 289.679114 -314.091956) (xy 289.659823 -314.04668) (xy 289.648046 -313.998896) (xy 289.644086 -313.949842)
			(xy 289.305238 -313.949842) (xy 289.304743 -313.974449) (xy 289.296848 -314.023026) (xy 289.281264 -314.069707)
			(xy 289.258393 -314.113284) (xy 289.228828 -314.152628) (xy 289.193335 -314.18672) (xy 289.152832 -314.214676)
			(xy 289.10837 -314.235774) (xy 289.061099 -314.249466) (xy 289.012244 -314.255398) (xy 288.963069 -314.253417)
			(xy 288.91485 -314.243573) (xy 288.868834 -314.226121) (xy 288.826213 -314.201514) (xy 288.788092 -314.170389)
			(xy 288.755457 -314.133552) (xy 288.729154 -314.091956) (xy 288.709863 -314.04668) (xy 288.698086 -313.998896)
			(xy 288.694126 -313.949842) (xy 288.355024 -313.949842) (xy 288.354529 -313.974449) (xy 288.346634 -314.023026)
			(xy 288.33105 -314.069707) (xy 288.308179 -314.113284) (xy 288.278614 -314.152628) (xy 288.243121 -314.18672)
			(xy 288.202618 -314.214676) (xy 288.158156 -314.235774) (xy 288.110885 -314.249466) (xy 288.06203 -314.255398)
			(xy 288.012855 -314.253417) (xy 287.964636 -314.243573) (xy 287.91862 -314.226121) (xy 287.875999 -314.201514)
			(xy 287.837878 -314.170389) (xy 287.805243 -314.133552) (xy 287.77894 -314.091956) (xy 287.759649 -314.04668)
			(xy 287.747872 -313.998896) (xy 287.743912 -313.949842) (xy 287.405064 -313.949842) (xy 287.404569 -313.974449)
			(xy 287.396674 -314.023026) (xy 287.38109 -314.069707) (xy 287.358219 -314.113284) (xy 287.328654 -314.152628)
			(xy 287.293161 -314.18672) (xy 287.252658 -314.214676) (xy 287.208196 -314.235774) (xy 287.160925 -314.249466)
			(xy 287.11207 -314.255398) (xy 287.062895 -314.253417) (xy 287.014676 -314.243573) (xy 286.96866 -314.226121)
			(xy 286.926039 -314.201514) (xy 286.887918 -314.170389) (xy 286.855283 -314.133552) (xy 286.82898 -314.091956)
			(xy 286.809689 -314.04668) (xy 286.797912 -313.998896) (xy 286.793952 -313.949842) (xy 286.455104 -313.949842)
			(xy 286.454609 -313.974449) (xy 286.446714 -314.023026) (xy 286.43113 -314.069707) (xy 286.408259 -314.113284)
			(xy 286.378694 -314.152628) (xy 286.343201 -314.18672) (xy 286.302698 -314.214676) (xy 286.258236 -314.235774)
			(xy 286.210965 -314.249466) (xy 286.16211 -314.255398) (xy 286.112935 -314.253417) (xy 286.064716 -314.243573)
			(xy 286.0187 -314.226121) (xy 285.976079 -314.201514) (xy 285.937958 -314.170389) (xy 285.905323 -314.133552)
			(xy 285.87902 -314.091956) (xy 285.859729 -314.04668) (xy 285.847952 -313.998896) (xy 285.843992 -313.949842)
			(xy 285.505144 -313.949842) (xy 285.504649 -313.974449) (xy 285.496754 -314.023026) (xy 285.48117 -314.069707)
			(xy 285.458299 -314.113284) (xy 285.428734 -314.152628) (xy 285.393241 -314.18672) (xy 285.352738 -314.214676)
			(xy 285.308276 -314.235774) (xy 285.261005 -314.249466) (xy 285.21215 -314.255398) (xy 285.162975 -314.253417)
			(xy 285.114756 -314.243573) (xy 285.06874 -314.226121) (xy 285.026119 -314.201514) (xy 284.987998 -314.170389)
			(xy 284.955363 -314.133552) (xy 284.92906 -314.091956) (xy 284.909769 -314.04668) (xy 284.897992 -313.998896)
			(xy 284.894032 -313.949842) (xy 284.555184 -313.949842) (xy 284.554689 -313.974449) (xy 284.546794 -314.023026)
			(xy 284.53121 -314.069707) (xy 284.508339 -314.113284) (xy 284.478774 -314.152628) (xy 284.443281 -314.18672)
			(xy 284.402778 -314.214676) (xy 284.358316 -314.235774) (xy 284.311045 -314.249466) (xy 284.26219 -314.255398)
			(xy 284.213015 -314.253417) (xy 284.164796 -314.243573) (xy 284.11878 -314.226121) (xy 284.076159 -314.201514)
			(xy 284.038038 -314.170389) (xy 284.005403 -314.133552) (xy 283.9791 -314.091956) (xy 283.959809 -314.04668)
			(xy 283.948032 -313.998896) (xy 283.944072 -313.949842) (xy 283.605224 -313.949842) (xy 283.604729 -313.974449)
			(xy 283.596834 -314.023026) (xy 283.58125 -314.069707) (xy 283.558379 -314.113284) (xy 283.528814 -314.152628)
			(xy 283.493321 -314.18672) (xy 283.452818 -314.214676) (xy 283.408356 -314.235774) (xy 283.361085 -314.249466)
			(xy 283.31223 -314.255398) (xy 283.263055 -314.253417) (xy 283.214836 -314.243573) (xy 283.16882 -314.226121)
			(xy 283.126199 -314.201514) (xy 283.088078 -314.170389) (xy 283.055443 -314.133552) (xy 283.02914 -314.091956)
			(xy 283.009849 -314.04668) (xy 282.998072 -313.998896) (xy 282.994112 -313.949842) (xy 282.655486 -313.949842)
			(xy 282.651318 -314.000131) (xy 282.638921 -314.049089) (xy 282.618634 -314.095339) (xy 282.591011 -314.137619)
			(xy 282.556806 -314.174776) (xy 282.516952 -314.205796) (xy 282.472535 -314.229833) (xy 282.424768 -314.246232)
			(xy 282.374954 -314.254544) (xy 282.349702 -314.25515) (xy 282.327858 -314.254388) (xy 282.317444 -314.253626)
			(xy 282.297632 -314.260484) (xy 282.235402 -314.31865) (xy 282.228057 -314.326117) (xy 282.219639 -314.345273)
			(xy 282.219146 -314.355734) (xy 282.219146 -314.477654) (xy 282.219611 -314.487529) (xy 282.227058 -314.505823)
			(xy 282.233624 -314.513214) (xy 282.233878 -314.513468) (xy 282.307792 -314.587382) (xy 282.32735 -314.595002)
			(xy 282.338018 -314.594748) (xy 282.349702 -314.594494) (xy 282.373693 -314.594965) (xy 282.421084 -314.602471)
			(xy 282.466718 -314.617299) (xy 282.50947 -314.639082) (xy 282.548288 -314.667286) (xy 282.582217 -314.701215)
			(xy 282.61042 -314.740033) (xy 282.632203 -314.782786) (xy 282.64703 -314.828419) (xy 282.654536 -314.875811)
			(xy 282.65501 -314.899802) (xy 282.654756 -314.911486) (xy 282.654502 -314.922154) (xy 282.662122 -314.941712)
			(xy 282.744926 -315.024516) (xy 282.77947 -315.028834) (xy 282.79471 -315.019436) (xy 282.834664 -314.995779)
			(xy 282.918247 -314.955323) (xy 282.961588 -314.938664) (xy 282.970916 -314.934687) (xy 282.985667 -314.920797)
			(xy 282.993934 -314.902299) (xy 282.994608 -314.892182) (xy 282.995717 -314.867339) (xy 283.004994 -314.818487)
			(xy 283.022063 -314.771783) (xy 283.046473 -314.728461) (xy 283.077579 -314.689666) (xy 283.114559 -314.656422)
			(xy 283.156436 -314.629609) (xy 283.202103 -314.609934) (xy 283.250355 -314.597917) (xy 283.299916 -314.593875)
			(xy 283.349477 -314.597917) (xy 283.397729 -314.609934) (xy 283.443396 -314.629609) (xy 283.485273 -314.656422)
			(xy 283.522253 -314.689666) (xy 283.553359 -314.728461) (xy 283.577769 -314.771783) (xy 283.594838 -314.818487)
			(xy 283.604115 -314.867339) (xy 283.605224 -314.892182) (xy 283.605853 -314.902321) (xy 283.614071 -314.920879)
			(xy 283.628861 -314.93478) (xy 283.638244 -314.938664) (xy 283.678079 -314.953959) (xy 283.755151 -314.990591)
			(xy 283.792168 -315.011816) (xy 283.804614 -315.018928) (xy 283.8323 -315.018674) (xy 283.933138 -314.956952)
			(xy 283.946092 -314.932314) (xy 283.945076 -314.91809) (xy 283.944568 -314.899802) (xy 283.94509 -314.874547)
			(xy 283.953403 -314.824725) (xy 283.969804 -314.776951) (xy 283.993845 -314.732528) (xy 284.024869 -314.692668)
			(xy 284.062031 -314.658458) (xy 284.104317 -314.630832) (xy 284.150573 -314.610542) (xy 284.199538 -314.598142)
			(xy 284.249876 -314.593971) (xy 284.300214 -314.598142) (xy 284.349179 -314.610542) (xy 284.395435 -314.630832)
			(xy 284.437721 -314.658458) (xy 284.474883 -314.692668) (xy 284.505907 -314.732528) (xy 284.529948 -314.776951)
			(xy 284.546349 -314.824725) (xy 284.554662 -314.874547) (xy 284.555184 -314.899802) (xy 284.554676 -314.91809)
			(xy 284.55366 -314.932314) (xy 284.566614 -314.956952) (xy 284.667452 -315.018674) (xy 284.695138 -315.018928)
			(xy 284.707584 -315.011816) (xy 284.744602 -314.990593) (xy 284.821675 -314.953964) (xy 284.861508 -314.938664)
			(xy 284.870847 -314.934697) (xy 284.885622 -314.920813) (xy 284.893904 -314.902307) (xy 284.894528 -314.892182)
			(xy 284.895637 -314.867339) (xy 284.904914 -314.818487) (xy 284.921983 -314.771783) (xy 284.946393 -314.728461)
			(xy 284.977499 -314.689666) (xy 285.014479 -314.656422) (xy 285.056356 -314.629609) (xy 285.102023 -314.609934)
			(xy 285.150275 -314.597917) (xy 285.199836 -314.593875) (xy 285.249397 -314.597917) (xy 285.297649 -314.609934)
			(xy 285.343316 -314.629609) (xy 285.385193 -314.656422) (xy 285.422173 -314.689666) (xy 285.453279 -314.728461)
			(xy 285.477689 -314.771783) (xy 285.494758 -314.818487) (xy 285.504035 -314.867339) (xy 285.505144 -314.892182)
			(xy 285.505773 -314.90232) (xy 285.513993 -314.920875) (xy 285.528785 -314.934771) (xy 285.538164 -314.938664)
			(xy 285.577998 -314.95396) (xy 285.65507 -314.990593) (xy 285.692088 -315.011816) (xy 285.704534 -315.018928)
			(xy 285.73222 -315.018674) (xy 285.833058 -314.956952) (xy 285.846012 -314.932314) (xy 285.844996 -314.91809)
			(xy 285.844488 -314.899802) (xy 285.84501 -314.874547) (xy 285.853323 -314.824725) (xy 285.869724 -314.776951)
			(xy 285.893765 -314.732528) (xy 285.924789 -314.692668) (xy 285.961951 -314.658458) (xy 286.004237 -314.630832)
			(xy 286.050493 -314.610542) (xy 286.099458 -314.598142) (xy 286.149796 -314.593971) (xy 286.200134 -314.598142)
			(xy 286.249099 -314.610542) (xy 286.295355 -314.630832) (xy 286.337641 -314.658458) (xy 286.374803 -314.692668)
			(xy 286.405827 -314.732528) (xy 286.429868 -314.776951) (xy 286.446269 -314.824725) (xy 286.454582 -314.874547)
			(xy 286.455104 -314.899802) (xy 286.454596 -314.91809) (xy 286.45358 -314.932314) (xy 286.466534 -314.956952)
			(xy 286.567372 -315.018674) (xy 286.595058 -315.018928) (xy 286.607504 -315.011816) (xy 286.644522 -314.990594)
			(xy 286.721596 -314.953966) (xy 286.761428 -314.938664) (xy 286.770764 -314.934695) (xy 286.785533 -314.920809)
			(xy 286.793811 -314.902305) (xy 286.794448 -314.892182) (xy 286.795557 -314.867339) (xy 286.804834 -314.818487)
			(xy 286.821903 -314.771783) (xy 286.846313 -314.728461) (xy 286.877419 -314.689666) (xy 286.914399 -314.656422)
			(xy 286.956276 -314.629609) (xy 287.001943 -314.609934) (xy 287.050195 -314.597917) (xy 287.099756 -314.593875)
			(xy 287.149317 -314.597917) (xy 287.197569 -314.609934) (xy 287.243236 -314.629609) (xy 287.285113 -314.656422)
			(xy 287.322093 -314.689666) (xy 287.353199 -314.728461) (xy 287.377609 -314.771783) (xy 287.394678 -314.818487)
			(xy 287.403955 -314.867339) (xy 287.405064 -314.892182) (xy 287.405694 -314.902319) (xy 287.413916 -314.920871)
			(xy 287.428709 -314.934762) (xy 287.438084 -314.938664) (xy 287.47792 -314.953957) (xy 287.554995 -314.990585)
			(xy 287.592008 -315.011816) (xy 287.604454 -315.018928) (xy 287.63214 -315.018674) (xy 287.732978 -314.956952)
			(xy 287.745932 -314.932314) (xy 287.744916 -314.91809) (xy 287.744408 -314.899802) (xy 287.74493 -314.874547)
			(xy 287.753243 -314.824725) (xy 287.769644 -314.776951) (xy 287.793685 -314.732528) (xy 287.824709 -314.692668)
			(xy 287.861871 -314.658458) (xy 287.904157 -314.630832) (xy 287.950413 -314.610542) (xy 287.999378 -314.598142)
			(xy 288.049716 -314.593971) (xy 288.100054 -314.598142) (xy 288.149019 -314.610542) (xy 288.195275 -314.630832)
			(xy 288.237561 -314.658458) (xy 288.274723 -314.692668) (xy 288.305747 -314.732528) (xy 288.329788 -314.776951)
			(xy 288.346189 -314.824725) (xy 288.354502 -314.874547) (xy 288.355024 -314.899802) (xy 288.354516 -314.91809)
			(xy 288.3535 -314.932314) (xy 288.366454 -314.957206) (xy 288.467292 -315.018928) (xy 288.494978 -315.019182)
			(xy 288.507424 -315.011816) (xy 288.544505 -314.990588) (xy 288.621706 -314.953959) (xy 288.661602 -314.938664)
			(xy 288.670928 -314.934686) (xy 288.685675 -314.920795) (xy 288.69394 -314.902298) (xy 288.694622 -314.892182)
			(xy 288.695731 -314.867339) (xy 288.705008 -314.818487) (xy 288.722077 -314.771783) (xy 288.746487 -314.728461)
			(xy 288.777593 -314.689666) (xy 288.814573 -314.656422) (xy 288.85645 -314.629609) (xy 288.902117 -314.609934)
			(xy 288.950369 -314.597917) (xy 288.99993 -314.593875) (xy 289.049491 -314.597917) (xy 289.097743 -314.609934)
			(xy 289.14341 -314.629609) (xy 289.185287 -314.656422) (xy 289.222267 -314.689666) (xy 289.253373 -314.728461)
			(xy 289.277783 -314.771783) (xy 289.294852 -314.818487) (xy 289.304129 -314.867339) (xy 289.305238 -314.892182)
			(xy 289.305867 -314.90232) (xy 289.314087 -314.920876) (xy 289.328878 -314.934773) (xy 289.338258 -314.938664)
			(xy 289.378092 -314.95396) (xy 289.455164 -314.990593) (xy 289.492182 -315.011816) (xy 289.504628 -315.018928)
			(xy 289.532314 -315.018674) (xy 289.633152 -314.956952) (xy 289.646106 -314.932314) (xy 289.64509 -314.91809)
			(xy 289.644582 -314.899802) (xy 289.645104 -314.874547) (xy 289.653417 -314.824725) (xy 289.669818 -314.776951)
			(xy 289.693859 -314.732528) (xy 289.724883 -314.692668) (xy 289.762045 -314.658458) (xy 289.804331 -314.630832)
			(xy 289.850587 -314.610542) (xy 289.899552 -314.598142) (xy 289.94989 -314.593971) (xy 290.000228 -314.598142)
			(xy 290.049193 -314.610542) (xy 290.095449 -314.630832) (xy 290.137735 -314.658458) (xy 290.174897 -314.692668)
			(xy 290.205921 -314.732528) (xy 290.229962 -314.776951) (xy 290.246363 -314.824725) (xy 290.254676 -314.874547)
			(xy 290.255198 -314.899802) (xy 290.25469 -314.91809) (xy 290.253674 -314.932314) (xy 290.266628 -314.956952)
			(xy 290.367466 -315.018674) (xy 290.395152 -315.018928) (xy 290.407598 -315.011816) (xy 290.444616 -314.990594)
			(xy 290.52169 -314.953965) (xy 290.561522 -314.938664) (xy 290.570859 -314.934695) (xy 290.585629 -314.92081)
			(xy 290.593909 -314.902305) (xy 290.594542 -314.892182) (xy 290.595651 -314.867339) (xy 290.604928 -314.818487)
			(xy 290.621997 -314.771783) (xy 290.646407 -314.728461) (xy 290.677513 -314.689666) (xy 290.714493 -314.656422)
			(xy 290.75637 -314.629609) (xy 290.802037 -314.609934) (xy 290.850289 -314.597917) (xy 290.89985 -314.593875)
			(xy 290.949411 -314.597917) (xy 290.997663 -314.609934) (xy 291.04333 -314.629609) (xy 291.085207 -314.656422)
			(xy 291.122187 -314.689666) (xy 291.153293 -314.728461) (xy 291.177703 -314.771783) (xy 291.194772 -314.818487)
			(xy 291.204049 -314.867339) (xy 291.205158 -314.892182) (xy 291.205788 -314.902319) (xy 291.214009 -314.920872)
			(xy 291.228802 -314.934764) (xy 291.238178 -314.938664) (xy 291.278014 -314.953957) (xy 291.355089 -314.990584)
			(xy 291.392102 -315.011816) (xy 291.404548 -315.018928) (xy 291.432234 -315.018674) (xy 291.533072 -314.956952)
			(xy 291.546026 -314.932314) (xy 291.54501 -314.91809) (xy 291.544502 -314.899802) (xy 291.545024 -314.874547)
			(xy 291.553337 -314.824725) (xy 291.569738 -314.776951) (xy 291.593779 -314.732528) (xy 291.624803 -314.692668)
			(xy 291.661965 -314.658458) (xy 291.704251 -314.630832) (xy 291.750507 -314.610542) (xy 291.799472 -314.598142)
			(xy 291.84981 -314.593971) (xy 291.900148 -314.598142) (xy 291.949113 -314.610542) (xy 291.995369 -314.630832)
			(xy 292.037655 -314.658458) (xy 292.074817 -314.692668) (xy 292.105841 -314.732528) (xy 292.129882 -314.776951)
			(xy 292.146283 -314.824725) (xy 292.154596 -314.874547) (xy 292.155118 -314.899802) (xy 292.15461 -314.91809)
			(xy 292.153594 -314.932314) (xy 292.166548 -314.956952) (xy 292.267386 -315.018674) (xy 292.295072 -315.018928)
			(xy 292.307518 -315.011816) (xy 292.344536 -314.990594) (xy 292.421611 -314.953968) (xy 292.461442 -314.938664)
			(xy 292.470776 -314.934693) (xy 292.485541 -314.920806) (xy 292.493817 -314.902304) (xy 292.494462 -314.892182)
			(xy 292.495571 -314.867339) (xy 292.504848 -314.818487) (xy 292.521917 -314.771783) (xy 292.546327 -314.728461)
			(xy 292.577433 -314.689666) (xy 292.614413 -314.656422) (xy 292.65629 -314.629609) (xy 292.701957 -314.609934)
			(xy 292.750209 -314.597917) (xy 292.79977 -314.593875) (xy 292.849331 -314.597917) (xy 292.897583 -314.609934)
			(xy 292.94325 -314.629609) (xy 292.985127 -314.656422) (xy 293.022107 -314.689666) (xy 293.053213 -314.728461)
			(xy 293.077623 -314.771783) (xy 293.094692 -314.818487) (xy 293.103969 -314.867339) (xy 293.105078 -314.892182)
			(xy 293.105708 -314.902318) (xy 293.113931 -314.920869) (xy 293.128726 -314.934756) (xy 293.138098 -314.938664)
			(xy 293.177933 -314.953958) (xy 293.255008 -314.990586) (xy 293.292022 -315.011816) (xy 293.304468 -315.018928)
			(xy 293.332154 -315.018674) (xy 293.432992 -314.956952) (xy 293.445946 -314.932314) (xy 293.44493 -314.91809)
			(xy 293.444422 -314.899802) (xy 293.444944 -314.874547) (xy 293.453257 -314.824725) (xy 293.469658 -314.776951)
			(xy 293.493699 -314.732528) (xy 293.524723 -314.692668) (xy 293.561885 -314.658458) (xy 293.604171 -314.630832)
			(xy 293.650427 -314.610542) (xy 293.699392 -314.598142) (xy 293.74973 -314.593971) (xy 293.800068 -314.598142)
			(xy 293.849033 -314.610542) (xy 293.895289 -314.630832) (xy 293.937575 -314.658458) (xy 293.974737 -314.692668)
			(xy 294.005761 -314.732528) (xy 294.029802 -314.776951) (xy 294.046203 -314.824725) (xy 294.054516 -314.874547)
			(xy 294.055038 -314.899802) (xy 294.05453 -314.91809) (xy 294.053514 -314.932314) (xy 294.066468 -314.956952)
			(xy 294.167306 -315.018674) (xy 294.194992 -315.018928) (xy 294.207438 -315.011816) (xy 294.244457 -314.990595)
			(xy 294.321532 -314.95397) (xy 294.361362 -314.938664) (xy 294.370693 -314.93469) (xy 294.385452 -314.920802)
			(xy 294.393724 -314.902302) (xy 294.394382 -314.892182) (xy 294.395491 -314.867339) (xy 294.404768 -314.818487)
			(xy 294.421837 -314.771783) (xy 294.446247 -314.728461) (xy 294.477353 -314.689666) (xy 294.514333 -314.656422)
			(xy 294.55621 -314.629609) (xy 294.601877 -314.609934) (xy 294.650129 -314.597917) (xy 294.69969 -314.593875)
			(xy 294.749251 -314.597917) (xy 294.797503 -314.609934) (xy 294.84317 -314.629609) (xy 294.885047 -314.656422)
			(xy 294.922027 -314.689666) (xy 294.953133 -314.728461) (xy 294.977543 -314.771783) (xy 294.994612 -314.818487)
			(xy 295.003889 -314.867339) (xy 295.004998 -314.892182) (xy 295.005629 -314.902317) (xy 295.013853 -314.920865)
			(xy 295.02865 -314.934747) (xy 295.038018 -314.938664) (xy 295.077919 -314.953947) (xy 295.155121 -314.990576)
			(xy 295.192196 -315.011816) (xy 295.204642 -315.019182) (xy 295.232328 -315.018928) (xy 295.333166 -314.957206)
			(xy 295.34612 -314.932314) (xy 295.345104 -314.91809) (xy 295.344596 -314.899802) (xy 295.345118 -314.874547)
			(xy 295.353431 -314.824725) (xy 295.369832 -314.776951) (xy 295.393873 -314.732528) (xy 295.424897 -314.692668)
			(xy 295.462059 -314.658458) (xy 295.504345 -314.630832) (xy 295.550601 -314.610542) (xy 295.599566 -314.598142)
			(xy 295.649904 -314.593971) (xy 295.700242 -314.598142) (xy 295.749207 -314.610542) (xy 295.795463 -314.630832)
			(xy 295.837749 -314.658458) (xy 295.874911 -314.692668) (xy 295.905935 -314.732528) (xy 295.929976 -314.776951)
			(xy 295.946377 -314.824725) (xy 295.95469 -314.874547) (xy 295.955212 -314.899802) (xy 295.954704 -314.91809)
			(xy 295.953688 -314.932314) (xy 295.966642 -314.956952) (xy 296.06748 -315.018674) (xy 296.095166 -315.018928)
			(xy 296.107612 -315.011816) (xy 296.14463 -314.990594) (xy 296.221705 -314.953967) (xy 296.261536 -314.938664)
			(xy 296.270871 -314.934694) (xy 296.285637 -314.920807) (xy 296.293914 -314.902304) (xy 296.294556 -314.892182)
			(xy 296.295665 -314.867339) (xy 296.304942 -314.818487) (xy 296.322011 -314.771783) (xy 296.346421 -314.728461)
			(xy 296.377527 -314.689666) (xy 296.414507 -314.656422) (xy 296.456384 -314.629609) (xy 296.502051 -314.609934)
			(xy 296.550303 -314.597917) (xy 296.599864 -314.593875) (xy 296.649425 -314.597917) (xy 296.697677 -314.609934)
			(xy 296.743344 -314.629609) (xy 296.785221 -314.656422) (xy 296.822201 -314.689666) (xy 296.853307 -314.728461)
			(xy 296.877717 -314.771783) (xy 296.894786 -314.818487) (xy 296.904063 -314.867339) (xy 296.905172 -314.892182)
			(xy 296.905802 -314.902319) (xy 296.914024 -314.92087) (xy 296.928819 -314.934758) (xy 296.938192 -314.938664)
			(xy 296.978027 -314.953957) (xy 297.055102 -314.990586) (xy 297.092116 -315.011816) (xy 297.104562 -315.018928)
			(xy 297.132248 -315.018674) (xy 297.233086 -314.956952) (xy 297.24604 -314.932314) (xy 297.245024 -314.91809)
			(xy 297.244516 -314.899802) (xy 297.245038 -314.874547) (xy 297.253351 -314.824725) (xy 297.269752 -314.776951)
			(xy 297.293793 -314.732528) (xy 297.324817 -314.692668) (xy 297.361979 -314.658458) (xy 297.404265 -314.630832)
			(xy 297.450521 -314.610542) (xy 297.499486 -314.598142) (xy 297.549824 -314.593971) (xy 297.600162 -314.598142)
			(xy 297.649127 -314.610542) (xy 297.695383 -314.630832) (xy 297.737669 -314.658458) (xy 297.774831 -314.692668)
			(xy 297.805855 -314.732528) (xy 297.829896 -314.776951) (xy 297.846297 -314.824725) (xy 297.85461 -314.874547)
			(xy 297.855132 -314.899802) (xy 297.854945 -314.913984) (xy 297.852272 -314.942224) (xy 297.849798 -314.95619)
			(xy 297.847512 -314.968636) (xy 297.854878 -314.992512) (xy 297.932094 -315.069728) (xy 297.956224 -315.077094)
			(xy 297.968416 -315.074808) (xy 297.996423 -315.070179) (xy 298.053185 -315.070179) (xy 298.081192 -315.074808)
			(xy 298.093384 -315.077094) (xy 298.117514 -315.069728) (xy 298.19473 -314.992512) (xy 298.202096 -314.968636)
			(xy 298.19981 -314.95619) (xy 298.197325 -314.942225) (xy 298.194653 -314.913985) (xy 298.194476 -314.899802)
			(xy 298.194998 -314.874547) (xy 298.203311 -314.824725) (xy 298.219712 -314.776951) (xy 298.243753 -314.732528)
			(xy 298.274777 -314.692668) (xy 298.311939 -314.658458) (xy 298.354225 -314.630832) (xy 298.400481 -314.610542)
			(xy 298.449446 -314.598142) (xy 298.499784 -314.593971) (xy 298.550122 -314.598142) (xy 298.599087 -314.610542)
			(xy 298.645343 -314.630832) (xy 298.687629 -314.658458) (xy 298.724791 -314.692668) (xy 298.755815 -314.732528)
			(xy 298.779856 -314.776951) (xy 298.796257 -314.824725) (xy 298.80457 -314.874547) (xy 298.805092 -314.899802)
			(xy 298.804905 -314.913984) (xy 298.802232 -314.942224) (xy 298.799758 -314.95619) (xy 298.797472 -314.968636)
			(xy 298.804838 -314.992512) (xy 298.882054 -315.069728) (xy 298.906184 -315.077094) (xy 298.918376 -315.074808)
			(xy 298.946383 -315.070179) (xy 299.003145 -315.070179) (xy 299.031152 -315.074808) (xy 299.043344 -315.077094)
			(xy 299.067474 -315.069728) (xy 299.14469 -314.992512) (xy 299.152056 -314.968636) (xy 299.14977 -314.95619)
			(xy 299.147284 -314.942225) (xy 299.144612 -314.913985) (xy 299.144436 -314.899802) (xy 299.144958 -314.874547)
			(xy 299.153271 -314.824725) (xy 299.169672 -314.776951) (xy 299.193713 -314.732528) (xy 299.224737 -314.692668)
			(xy 299.261899 -314.658458) (xy 299.304185 -314.630832) (xy 299.350441 -314.610542) (xy 299.399406 -314.598142)
			(xy 299.449744 -314.593971) (xy 299.500082 -314.598142) (xy 299.549047 -314.610542) (xy 299.595303 -314.630832)
			(xy 299.637589 -314.658458) (xy 299.674751 -314.692668) (xy 299.705775 -314.732528) (xy 299.729816 -314.776951)
			(xy 299.746217 -314.824725) (xy 299.75453 -314.874547) (xy 299.755052 -314.899802) (xy 299.754865 -314.913984)
			(xy 299.752192 -314.942224) (xy 299.749718 -314.95619) (xy 299.747432 -314.968636) (xy 299.754798 -314.992512)
			(xy 299.832014 -315.069728) (xy 299.856144 -315.077094) (xy 299.868336 -315.074808) (xy 299.896343 -315.070179)
			(xy 299.953105 -315.070179) (xy 299.981112 -315.074808) (xy 299.993304 -315.077094) (xy 300.017434 -315.069728)
			(xy 300.09465 -314.992512) (xy 300.102016 -314.968636) (xy 300.09973 -314.95619) (xy 300.097245 -314.942225)
			(xy 300.094572 -314.913985) (xy 300.094396 -314.899802) (xy 300.094918 -314.874547) (xy 300.103231 -314.824725)
			(xy 300.119632 -314.776951) (xy 300.143673 -314.732528) (xy 300.174697 -314.692668) (xy 300.211859 -314.658458)
			(xy 300.254145 -314.630832) (xy 300.300401 -314.610542) (xy 300.349366 -314.598142) (xy 300.399704 -314.593971)
			(xy 300.450042 -314.598142) (xy 300.499007 -314.610542) (xy 300.545263 -314.630832) (xy 300.587549 -314.658458)
			(xy 300.624711 -314.692668) (xy 300.655735 -314.732528) (xy 300.679776 -314.776951) (xy 300.696177 -314.824725)
			(xy 300.70449 -314.874547) (xy 300.705012 -314.899802) (xy 300.704825 -314.913984) (xy 300.702152 -314.942224)
			(xy 300.699678 -314.95619) (xy 300.697392 -314.968636) (xy 300.704758 -314.992512) (xy 300.781974 -315.069728)
			(xy 300.806104 -315.077094) (xy 300.818296 -315.074808) (xy 300.846365 -315.070147) (xy 300.903257 -315.070147)
			(xy 300.931326 -315.074808) (xy 300.943518 -315.077094) (xy 300.967648 -315.069728) (xy 301.044864 -314.992512)
			(xy 301.05223 -314.968636) (xy 301.049944 -314.95619) (xy 301.047459 -314.942225) (xy 301.044786 -314.913985)
			(xy 301.04461 -314.899802) (xy 301.045132 -314.874547) (xy 301.053445 -314.824725) (xy 301.069846 -314.776951)
			(xy 301.093887 -314.732528) (xy 301.124911 -314.692668) (xy 301.162073 -314.658458) (xy 301.204359 -314.630832)
			(xy 301.250615 -314.610542) (xy 301.29958 -314.598142) (xy 301.349918 -314.593971) (xy 301.400256 -314.598142)
			(xy 301.449221 -314.610542) (xy 301.495477 -314.630832) (xy 301.537763 -314.658458) (xy 301.574925 -314.692668)
			(xy 301.605949 -314.732528) (xy 301.62999 -314.776951) (xy 301.646391 -314.824725) (xy 301.654704 -314.874547)
			(xy 301.655226 -314.899802) (xy 301.655039 -314.913984) (xy 301.652366 -314.942224) (xy 301.649892 -314.95619)
			(xy 301.647606 -314.968636) (xy 301.654972 -314.992512) (xy 301.732188 -315.069728) (xy 301.756318 -315.077094)
			(xy 301.76851 -315.074808) (xy 301.796517 -315.070179) (xy 301.853279 -315.070179) (xy 301.881286 -315.074808)
			(xy 301.893478 -315.077094) (xy 301.917608 -315.069728) (xy 301.994824 -314.992512) (xy 302.00219 -314.968636)
			(xy 301.999904 -314.95619) (xy 301.997419 -314.942225) (xy 301.994747 -314.913985) (xy 301.99457 -314.899802)
			(xy 301.995092 -314.874547) (xy 302.003405 -314.824725) (xy 302.019806 -314.776951) (xy 302.043847 -314.732528)
			(xy 302.074871 -314.692668) (xy 302.112033 -314.658458) (xy 302.154319 -314.630832) (xy 302.200575 -314.610542)
			(xy 302.24954 -314.598142) (xy 302.299878 -314.593971) (xy 302.350216 -314.598142) (xy 302.399181 -314.610542)
			(xy 302.445437 -314.630832) (xy 302.487723 -314.658458) (xy 302.524885 -314.692668) (xy 302.555909 -314.732528)
			(xy 302.57995 -314.776951) (xy 302.596351 -314.824725) (xy 302.604664 -314.874547) (xy 302.605186 -314.899802)
			(xy 302.604999 -314.913984) (xy 302.602325 -314.942224) (xy 302.599852 -314.95619) (xy 302.597566 -314.968636)
			(xy 302.604932 -314.992512) (xy 302.682148 -315.069728) (xy 302.706278 -315.077094) (xy 302.71847 -315.074808)
			(xy 302.746477 -315.070179) (xy 302.803239 -315.070179) (xy 302.831246 -315.074808) (xy 302.843438 -315.077094)
			(xy 302.867568 -315.069728) (xy 302.944784 -314.992512) (xy 302.95215 -314.968636) (xy 302.949864 -314.95619)
			(xy 302.947378 -314.942225) (xy 302.944706 -314.913985) (xy 302.94453 -314.899802) (xy 302.945052 -314.874547)
			(xy 302.953365 -314.824725) (xy 302.969766 -314.776951) (xy 302.993807 -314.732528) (xy 303.024831 -314.692668)
			(xy 303.061993 -314.658458) (xy 303.104279 -314.630832) (xy 303.150535 -314.610542) (xy 303.1995 -314.598142)
			(xy 303.249838 -314.593971) (xy 303.300176 -314.598142) (xy 303.349141 -314.610542) (xy 303.395397 -314.630832)
			(xy 303.437683 -314.658458) (xy 303.474845 -314.692668) (xy 303.505869 -314.732528) (xy 303.52991 -314.776951)
			(xy 303.546311 -314.824725) (xy 303.554624 -314.874547) (xy 303.555146 -314.899802) (xy 303.554959 -314.913984)
			(xy 303.552286 -314.942224) (xy 303.549812 -314.95619) (xy 303.547526 -314.968636) (xy 303.554892 -314.992512)
			(xy 303.632108 -315.069728) (xy 303.656238 -315.077094) (xy 303.66843 -315.074808) (xy 303.696437 -315.070179)
			(xy 303.753199 -315.070179) (xy 303.781206 -315.074808) (xy 303.793398 -315.077094) (xy 303.817528 -315.069728)
			(xy 303.894744 -314.992512) (xy 303.90211 -314.968636) (xy 303.899824 -314.95619) (xy 303.897339 -314.942225)
			(xy 303.894666 -314.913985) (xy 303.89449 -314.899802) (xy 303.895012 -314.874547) (xy 303.903325 -314.824725)
			(xy 303.919726 -314.776951) (xy 303.943767 -314.732528) (xy 303.974791 -314.692668) (xy 304.011953 -314.658458)
			(xy 304.054239 -314.630832) (xy 304.100495 -314.610542) (xy 304.14946 -314.598142) (xy 304.199798 -314.593971)
			(xy 304.250136 -314.598142) (xy 304.299101 -314.610542) (xy 304.345357 -314.630832) (xy 304.387643 -314.658458)
			(xy 304.424805 -314.692668) (xy 304.455829 -314.732528) (xy 304.47987 -314.776951) (xy 304.496271 -314.824725)
			(xy 304.504584 -314.874547) (xy 304.505106 -314.899802) (xy 304.504919 -314.913984) (xy 304.502246 -314.942224)
			(xy 304.499772 -314.95619) (xy 304.497486 -314.968636) (xy 304.504852 -314.992512) (xy 304.582068 -315.069728)
			(xy 304.606198 -315.077094) (xy 304.61839 -315.074808) (xy 304.646397 -315.070179) (xy 304.703159 -315.070179)
			(xy 304.731166 -315.074808) (xy 304.743358 -315.077094) (xy 304.767488 -315.069728) (xy 304.844704 -314.992512)
			(xy 304.85207 -314.968636) (xy 304.849784 -314.95619) (xy 304.847299 -314.942225) (xy 304.844627 -314.913985)
			(xy 304.84445 -314.899802) (xy 304.844972 -314.874547) (xy 304.853285 -314.824725) (xy 304.869686 -314.776951)
			(xy 304.893727 -314.732528) (xy 304.924751 -314.692668) (xy 304.961913 -314.658458) (xy 305.004199 -314.630832)
			(xy 305.050455 -314.610542) (xy 305.09942 -314.598142) (xy 305.149758 -314.593971) (xy 305.200096 -314.598142)
			(xy 305.249061 -314.610542) (xy 305.295317 -314.630832) (xy 305.337603 -314.658458) (xy 305.374765 -314.692668)
			(xy 305.405789 -314.732528) (xy 305.42983 -314.776951) (xy 305.446231 -314.824725) (xy 305.454544 -314.874547)
			(xy 305.455066 -314.899802) (xy 305.454879 -314.913984) (xy 305.452206 -314.942224) (xy 305.449732 -314.95619)
			(xy 305.447446 -314.968636) (xy 305.454812 -314.992512) (xy 305.532028 -315.069728) (xy 305.556158 -315.077094)
			(xy 305.56835 -315.074808) (xy 305.596357 -315.070179) (xy 305.653119 -315.070179) (xy 305.681126 -315.074808)
			(xy 305.693318 -315.077094) (xy 305.717448 -315.069728) (xy 305.794664 -314.992512) (xy 305.80203 -314.968636)
			(xy 305.799744 -314.95619) (xy 305.797259 -314.942225) (xy 305.794586 -314.913985) (xy 305.79441 -314.899802)
			(xy 305.794932 -314.874547) (xy 305.803245 -314.824725) (xy 305.819646 -314.776951) (xy 305.843687 -314.732528)
			(xy 305.874711 -314.692668) (xy 305.911873 -314.658458) (xy 305.954159 -314.630832) (xy 306.000415 -314.610542)
			(xy 306.04938 -314.598142) (xy 306.099718 -314.593971) (xy 306.150056 -314.598142) (xy 306.199021 -314.610542)
			(xy 306.245277 -314.630832) (xy 306.287563 -314.658458) (xy 306.324725 -314.692668) (xy 306.355749 -314.732528)
			(xy 306.37979 -314.776951) (xy 306.396191 -314.824725) (xy 306.404504 -314.874547) (xy 306.405026 -314.899802)
			(xy 306.404839 -314.913984) (xy 306.402166 -314.942224) (xy 306.399692 -314.95619) (xy 306.397406 -314.968636)
			(xy 306.404772 -314.992512) (xy 306.481988 -315.069728) (xy 306.506118 -315.077094) (xy 306.51831 -315.074808)
			(xy 306.546379 -315.070147) (xy 306.603271 -315.070147) (xy 306.63134 -315.074808) (xy 306.643532 -315.077094)
			(xy 306.667662 -315.069728) (xy 306.744878 -314.992512) (xy 306.752244 -314.968636) (xy 306.749958 -314.95619)
			(xy 306.747472 -314.942225) (xy 306.7448 -314.913985) (xy 306.744624 -314.899802) (xy 306.745146 -314.874547)
			(xy 306.753459 -314.824725) (xy 306.76986 -314.776951) (xy 306.793901 -314.732528) (xy 306.824925 -314.692668)
			(xy 306.862087 -314.658458) (xy 306.904373 -314.630832) (xy 306.950629 -314.610542) (xy 306.999594 -314.598142)
			(xy 307.049932 -314.593971) (xy 307.10027 -314.598142) (xy 307.149235 -314.610542) (xy 307.195491 -314.630832)
			(xy 307.237777 -314.658458) (xy 307.274939 -314.692668) (xy 307.305963 -314.732528) (xy 307.330004 -314.776951)
			(xy 307.346405 -314.824725) (xy 307.354718 -314.874547) (xy 307.35524 -314.899802) (xy 307.355053 -314.913984)
			(xy 307.35238 -314.942224) (xy 307.349906 -314.95619) (xy 307.34762 -314.968636) (xy 307.354986 -314.992512)
			(xy 307.432202 -315.069728) (xy 307.456332 -315.077094) (xy 307.468524 -315.074808) (xy 307.496531 -315.070179)
			(xy 307.553293 -315.070179) (xy 307.5813 -315.074808) (xy 307.593492 -315.077094) (xy 307.617622 -315.069728)
			(xy 307.694838 -314.992512) (xy 307.702204 -314.968636) (xy 307.699918 -314.95619) (xy 307.697433 -314.942225)
			(xy 307.69476 -314.913985) (xy 307.694584 -314.899802) (xy 307.695106 -314.874547) (xy 307.703419 -314.824725)
			(xy 307.71982 -314.776951) (xy 307.743861 -314.732528) (xy 307.774885 -314.692668) (xy 307.812047 -314.658458)
			(xy 307.854333 -314.630832) (xy 307.900589 -314.610542) (xy 307.949554 -314.598142) (xy 307.999892 -314.593971)
			(xy 308.05023 -314.598142) (xy 308.099195 -314.610542) (xy 308.145451 -314.630832) (xy 308.187737 -314.658458)
			(xy 308.224899 -314.692668) (xy 308.255923 -314.732528) (xy 308.279964 -314.776951) (xy 308.296365 -314.824725)
			(xy 308.304678 -314.874547) (xy 308.3052 -314.899802) (xy 308.305013 -314.913984) (xy 308.30234 -314.942224)
			(xy 308.299866 -314.95619) (xy 308.29758 -314.968636) (xy 308.304946 -314.992512) (xy 308.382162 -315.069728)
			(xy 308.406292 -315.077094) (xy 308.418484 -315.074808) (xy 308.446491 -315.070179) (xy 308.503253 -315.070179)
			(xy 308.53126 -315.074808) (xy 308.543452 -315.077094) (xy 308.567582 -315.069728) (xy 308.644798 -314.992512)
			(xy 308.652164 -314.968636) (xy 308.649878 -314.95619) (xy 308.647392 -314.942225) (xy 308.64472 -314.913985)
			(xy 308.644544 -314.899802) (xy 308.645066 -314.874547) (xy 308.653379 -314.824725) (xy 308.66978 -314.776951)
			(xy 308.693821 -314.732528) (xy 308.724845 -314.692668) (xy 308.762007 -314.658458) (xy 308.804293 -314.630832)
			(xy 308.850549 -314.610542) (xy 308.899514 -314.598142) (xy 308.949852 -314.593971) (xy 309.00019 -314.598142)
			(xy 309.049155 -314.610542) (xy 309.095411 -314.630832) (xy 309.137697 -314.658458) (xy 309.174859 -314.692668)
			(xy 309.205883 -314.732528) (xy 309.229924 -314.776951) (xy 309.246325 -314.824725) (xy 309.254638 -314.874547)
			(xy 309.25516 -314.899802) (xy 309.254973 -314.913984) (xy 309.2523 -314.942224) (xy 309.249826 -314.95619)
			(xy 309.24754 -314.968636) (xy 309.254906 -314.992512) (xy 309.332122 -315.069728) (xy 309.356252 -315.077094)
			(xy 309.368444 -315.074808) (xy 309.396451 -315.070179) (xy 309.453213 -315.070179) (xy 309.48122 -315.074808)
			(xy 309.493412 -315.077094) (xy 309.517542 -315.069728) (xy 309.594758 -314.992512) (xy 309.602124 -314.968636)
			(xy 309.599838 -314.95619) (xy 309.597353 -314.942225) (xy 309.59468 -314.913985) (xy 309.594504 -314.899802)
			(xy 309.595026 -314.874547) (xy 309.603339 -314.824725) (xy 309.61974 -314.776951) (xy 309.643781 -314.732528)
			(xy 309.674805 -314.692668) (xy 309.711967 -314.658458) (xy 309.754253 -314.630832) (xy 309.800509 -314.610542)
			(xy 309.849474 -314.598142) (xy 309.899812 -314.593971) (xy 309.95015 -314.598142) (xy 309.999115 -314.610542)
			(xy 310.045371 -314.630832) (xy 310.087657 -314.658458) (xy 310.124819 -314.692668) (xy 310.155843 -314.732528)
			(xy 310.179884 -314.776951) (xy 310.196285 -314.824725) (xy 310.204598 -314.874547) (xy 310.20512 -314.899802)
			(xy 310.204933 -314.913984) (xy 310.20226 -314.942224) (xy 310.199786 -314.95619) (xy 310.1975 -314.968636)
			(xy 310.204866 -314.992512) (xy 310.282082 -315.069728) (xy 310.306212 -315.077094) (xy 310.318404 -315.074808)
			(xy 310.346411 -315.070179) (xy 310.403173 -315.070179) (xy 310.43118 -315.074808) (xy 310.443372 -315.077094)
			(xy 310.467502 -315.069728) (xy 310.544718 -314.992512) (xy 310.552084 -314.968636) (xy 310.549798 -314.95619)
			(xy 310.547313 -314.942225) (xy 310.544641 -314.913985) (xy 310.544464 -314.899802) (xy 310.544986 -314.874547)
			(xy 310.553299 -314.824725) (xy 310.5697 -314.776951) (xy 310.593741 -314.732528) (xy 310.624765 -314.692668)
			(xy 310.661927 -314.658458) (xy 310.704213 -314.630832) (xy 310.750469 -314.610542) (xy 310.799434 -314.598142)
			(xy 310.849772 -314.593971) (xy 310.90011 -314.598142) (xy 310.949075 -314.610542) (xy 310.995331 -314.630832)
			(xy 311.037617 -314.658458) (xy 311.074779 -314.692668) (xy 311.105803 -314.732528) (xy 311.129844 -314.776951)
			(xy 311.146245 -314.824725) (xy 311.154558 -314.874547) (xy 311.15508 -314.899802) (xy 311.154893 -314.913984)
			(xy 311.152219 -314.942224) (xy 311.149746 -314.95619) (xy 311.14746 -314.968636) (xy 311.154826 -314.992512)
			(xy 311.232042 -315.069728) (xy 311.256172 -315.077094) (xy 311.268364 -315.074808) (xy 311.296371 -315.070179)
			(xy 311.353133 -315.070179) (xy 311.38114 -315.074808) (xy 311.393332 -315.077094) (xy 311.417462 -315.069728)
			(xy 311.494678 -314.992512) (xy 311.502044 -314.968636) (xy 311.499758 -314.95619) (xy 311.497272 -314.942225)
			(xy 311.4946 -314.913985) (xy 311.494424 -314.899802) (xy 311.494946 -314.874547) (xy 311.503259 -314.824725)
			(xy 311.51966 -314.776951) (xy 311.543701 -314.732528) (xy 311.574725 -314.692668) (xy 311.611887 -314.658458)
			(xy 311.654173 -314.630832) (xy 311.700429 -314.610542) (xy 311.749394 -314.598142) (xy 311.799732 -314.593971)
			(xy 311.85007 -314.598142) (xy 311.899035 -314.610542) (xy 311.945291 -314.630832) (xy 311.987577 -314.658458)
			(xy 312.024739 -314.692668) (xy 312.055763 -314.732528) (xy 312.079804 -314.776951) (xy 312.096205 -314.824725)
			(xy 312.104518 -314.874547) (xy 312.10504 -314.899802) (xy 312.104853 -314.913984) (xy 312.10218 -314.942224)
			(xy 312.099706 -314.95619) (xy 312.09742 -314.968636) (xy 312.104786 -314.992512) (xy 312.182002 -315.069728)
			(xy 312.206132 -315.077094) (xy 312.218324 -315.074808) (xy 312.246331 -315.070179) (xy 312.303093 -315.070179)
			(xy 312.3311 -315.074808) (xy 312.343292 -315.077094) (xy 312.367422 -315.069728) (xy 312.444638 -314.992512)
			(xy 312.452004 -314.968636) (xy 312.449718 -314.95619) (xy 312.447233 -314.942225) (xy 312.44456 -314.913985)
			(xy 312.444384 -314.899802) (xy 312.444906 -314.874547) (xy 312.453219 -314.824725) (xy 312.46962 -314.776951)
			(xy 312.493661 -314.732528) (xy 312.524685 -314.692668) (xy 312.561847 -314.658458) (xy 312.604133 -314.630832)
			(xy 312.650389 -314.610542) (xy 312.699354 -314.598142) (xy 312.749692 -314.593971) (xy 312.80003 -314.598142)
			(xy 312.848995 -314.610542) (xy 312.895251 -314.630832) (xy 312.937537 -314.658458) (xy 312.974699 -314.692668)
			(xy 313.005723 -314.732528) (xy 313.029764 -314.776951) (xy 313.046165 -314.824725) (xy 313.054478 -314.874547)
			(xy 313.055 -314.899802) (xy 313.054813 -314.913984) (xy 313.05214 -314.942224) (xy 313.049666 -314.95619)
			(xy 313.04738 -314.968636) (xy 313.054746 -314.992512) (xy 313.131962 -315.069728) (xy 313.156092 -315.077094)
			(xy 313.168284 -315.074808) (xy 313.196353 -315.070147) (xy 313.253245 -315.070147) (xy 313.281314 -315.074808)
			(xy 313.293506 -315.077094) (xy 313.317636 -315.069728) (xy 313.394852 -314.992512) (xy 313.402218 -314.968636)
			(xy 313.399932 -314.95619) (xy 313.397447 -314.942225) (xy 313.394774 -314.913985) (xy 313.394598 -314.899802)
			(xy 313.39512 -314.874547) (xy 313.403433 -314.824725) (xy 313.419834 -314.776951) (xy 313.443875 -314.732528)
			(xy 313.474899 -314.692668) (xy 313.512061 -314.658458) (xy 313.554347 -314.630832) (xy 313.600603 -314.610542)
			(xy 313.649568 -314.598142) (xy 313.699906 -314.593971) (xy 313.750244 -314.598142) (xy 313.799209 -314.610542)
			(xy 313.845465 -314.630832) (xy 313.887751 -314.658458) (xy 313.924913 -314.692668) (xy 313.955937 -314.732528)
			(xy 313.979978 -314.776951) (xy 313.996379 -314.824725) (xy 314.004692 -314.874547) (xy 314.005214 -314.899802)
			(xy 314.005175 -314.908903) (xy 314.004158 -314.927076) (xy 314.003182 -314.936124) (xy 314.001658 -314.948062)
			(xy 314.009532 -314.970414) (xy 314.085986 -315.043312) (xy 314.108592 -315.050424) (xy 314.12053 -315.048392)
			(xy 314.134018 -315.046261) (xy 314.161231 -315.043972) (xy 314.174886 -315.04382) (xy 314.245244 -315.04382)
			(xy 314.255909 -315.043372) (xy 314.275395 -315.034706) (xy 314.282836 -315.027056) (xy 314.340748 -314.962794)
			(xy 314.347352 -314.942474) (xy 314.346336 -314.931552) (xy 314.344558 -314.899802) (xy 314.34508 -314.874547)
			(xy 314.353393 -314.824725) (xy 314.369794 -314.776951) (xy 314.393835 -314.732528) (xy 314.424859 -314.692668)
			(xy 314.462021 -314.658458) (xy 314.504307 -314.630832) (xy 314.550563 -314.610542) (xy 314.599528 -314.598142)
			(xy 314.649866 -314.593971) (xy 314.700204 -314.598142) (xy 314.749169 -314.610542) (xy 314.795425 -314.630832)
			(xy 314.837711 -314.658458) (xy 314.874873 -314.692668) (xy 314.905897 -314.732528) (xy 314.929938 -314.776951)
			(xy 314.946339 -314.824725) (xy 314.954652 -314.874547) (xy 314.955174 -314.899802) (xy 314.953396 -314.931552)
			(xy 314.95238 -314.942474) (xy 314.958984 -314.962794) (xy 315.016896 -315.027056) (xy 315.02444 -315.034566)
			(xy 315.04386 -315.043228) (xy 315.054488 -315.04382) (xy 315.124846 -315.04382) (xy 315.138564 -315.043976)
			(xy 315.165903 -315.046267) (xy 315.179456 -315.048392) (xy 315.191394 -315.050424) (xy 315.214 -315.043312)
			(xy 315.290454 -314.970414) (xy 315.298328 -314.948062) (xy 315.297058 -314.936124) (xy 315.296003 -314.927016)
			(xy 315.294858 -314.908716) (xy 315.294772 -314.899548) (xy 315.295294 -314.874293) (xy 315.303607 -314.824471)
			(xy 315.320008 -314.776697) (xy 315.344049 -314.732274) (xy 315.375073 -314.692414) (xy 315.412235 -314.658204)
			(xy 315.454521 -314.630578) (xy 315.500777 -314.610288) (xy 315.549742 -314.597888) (xy 315.60008 -314.593717)
			(xy 315.650418 -314.597888) (xy 315.699383 -314.610288) (xy 315.745639 -314.630578) (xy 315.787925 -314.658204)
			(xy 315.825087 -314.692414) (xy 315.856111 -314.732274) (xy 315.880152 -314.776697) (xy 315.896553 -314.824471)
			(xy 315.904866 -314.874293) (xy 315.905388 -314.899548) (xy 315.904654 -314.929759) (xy 315.892755 -314.988999)
			(xy 315.881766 -315.01715) (xy 315.87859 -315.025778) (xy 315.877923 -315.044138) (xy 315.880496 -315.052964)
			(xy 315.890656 -315.082936) (xy 315.893963 -315.091486) (xy 315.905543 -315.105679) (xy 315.913262 -315.110622)
			(xy 315.924906 -315.117555) (xy 315.94704 -315.133196) (xy 315.957458 -315.141864) (xy 315.964062 -315.147452)
			(xy 315.989208 -315.157104) (xy 315.993435 -315.158606) (xy 316.00225 -315.160264) (xy 316.006734 -315.160406)
		)
		(stroke
			(width 0)
			(type solid)
		)
		(fill yes)
		(layer "In9.Cu")
		(net "P1V25_SERDES_VDDPLL_PEX2")
	)
	(gr_poly
		(pts
			(xy 148.815044 -299.793152) (xy 148.82368 -299.789596) (xy 148.829522 -299.786548) (xy 148.834348 -299.782484)
			(xy 148.850858 -299.768006) (xy 148.858224 -299.760132) (xy 148.861526 -299.75556) (xy 148.863812 -299.749718)
			(xy 148.875054 -299.72393) (xy 148.903999 -299.675694) (xy 148.939702 -299.632223) (xy 148.981392 -299.594454)
			(xy 149.028168 -299.563205) (xy 149.07902 -299.539151) (xy 149.132849 -299.522811) (xy 149.188491 -299.514538)
			(xy 149.216618 -299.514006) (xy 149.243917 -299.514473) (xy 149.297956 -299.522257) (xy 149.350335 -299.537663)
			(xy 149.399983 -299.560377) (xy 149.445887 -299.589935) (xy 149.466808 -299.607478) (xy 149.470364 -299.610526)
			(xy 149.47392 -299.612558) (xy 149.477266 -299.614486) (xy 149.48441 -299.617414) (xy 149.488144 -299.6184)
			(xy 149.494171 -299.619713) (xy 149.506501 -299.619713) (xy 149.512528 -299.6184) (xy 149.77237 -299.55363)
			(xy 149.81093 -299.544366) (xy 149.889155 -299.531292) (xy 149.968176 -299.524514) (xy 150.007828 -299.523912)
			(xy 150.01113 -299.523912) (xy 150.021036 -299.522642) (xy 150.023068 -299.522388) (xy 150.03421 -299.520083)
			(xy 150.056704 -299.516652) (xy 150.068026 -299.51553) (xy 150.069296 -299.51553) (xy 150.079456 -299.51426)
			(xy 150.084536 -299.514006) (xy 150.104094 -299.514006) (xy 150.124382 -299.514288) (xy 150.164727 -299.518612)
			(xy 150.184612 -299.522642) (xy 150.186898 -299.52315) (xy 150.19655 -299.52442) (xy 151.443436 -299.52442)
			(xy 151.488846 -299.524953) (xy 151.57928 -299.533313) (xy 151.668568 -299.549923) (xy 151.755959 -299.574643)
			(xy 151.798528 -299.59046) (xy 151.8031 -299.592238) (xy 151.817324 -299.594778) (xy 151.826214 -299.59554)
			(xy 151.899112 -299.59554) (xy 151.909121 -299.59505) (xy 151.927616 -299.58739) (xy 151.941774 -299.573239)
			(xy 151.949445 -299.554749) (xy 151.949912 -299.54474) (xy 151.949912 -297.085004) (xy 151.94915 -297.076876)
			(xy 151.945848 -297.06062) (xy 151.944324 -297.056556) (xy 151.943816 -297.05554) (xy 151.939769 -297.045664)
			(xy 151.932904 -297.025452) (xy 151.9301 -297.015154) (xy 151.929338 -297.012106) (xy 151.927148 -297.002554)
			(xy 151.923843 -296.983235) (xy 151.922734 -296.973498) (xy 151.920956 -296.939208) (xy 151.920956 -294.804846)
			(xy 151.921102 -294.799407) (xy 151.923416 -294.788779) (xy 151.925528 -294.783764) (xy 151.94534 -294.739568)
			(xy 151.947454 -294.734621) (xy 151.949769 -294.724117) (xy 151.949912 -294.71874) (xy 151.949912 -294.219122)
			(xy 151.94534 -294.208962) (xy 151.941276 -294.199564) (xy 151.941276 -294.198548) (xy 151.938482 -294.19042)
			(xy 151.930432 -294.166116) (xy 151.921629 -294.115684) (xy 151.920956 -294.09009) (xy 151.920956 -292.904926)
			(xy 151.921094 -292.899485) (xy 151.923392 -292.88885) (xy 151.925528 -292.883844) (xy 151.94534 -292.839648)
			(xy 151.947452 -292.834701) (xy 151.949763 -292.824197) (xy 151.949912 -292.81882) (xy 151.949912 -292.319202)
			(xy 151.94534 -292.309042) (xy 151.941276 -292.299644) (xy 151.941276 -292.298628) (xy 151.938482 -292.2905)
			(xy 151.930425 -292.266197) (xy 151.921609 -292.215765) (xy 151.920956 -292.19017) (xy 151.920956 -291.954712)
			(xy 151.921095 -291.949272) (xy 151.923397 -291.938637) (xy 151.925528 -291.93363) (xy 151.94534 -291.889434)
			(xy 151.94745 -291.884486) (xy 151.949758 -291.873983) (xy 151.949912 -291.868606) (xy 151.949912 -291.368988)
			(xy 151.94534 -291.358828) (xy 151.941276 -291.34943) (xy 151.941276 -291.348414) (xy 151.938482 -291.340286)
			(xy 151.930427 -291.315983) (xy 151.921613 -291.265551) (xy 151.920956 -291.239956) (xy 151.920956 -291.004752)
			(xy 151.921101 -290.999313) (xy 151.923414 -290.988684) (xy 151.925528 -290.98367) (xy 151.94534 -290.939474)
			(xy 151.947455 -290.934527) (xy 151.949771 -290.924023) (xy 151.949912 -290.918646) (xy 151.949912 -290.419028)
			(xy 151.94534 -290.408868) (xy 151.941276 -290.39947) (xy 151.941276 -290.398454) (xy 151.938482 -290.390326)
			(xy 151.930431 -290.366022) (xy 151.921627 -290.31559) (xy 151.920956 -290.289996) (xy 151.920956 -290.054792)
			(xy 151.921097 -290.049352) (xy 151.923402 -290.038719) (xy 151.925528 -290.03371) (xy 151.94534 -289.989514)
			(xy 151.947448 -289.984566) (xy 151.949752 -289.974062) (xy 151.949912 -289.968686) (xy 151.949912 -289.469068)
			(xy 151.94534 -289.458908) (xy 151.941276 -289.44951) (xy 151.941276 -289.448494) (xy 151.938482 -289.440366)
			(xy 151.930428 -289.416063) (xy 151.921618 -289.365631) (xy 151.920956 -289.340036) (xy 151.920956 -289.104832)
			(xy 151.921104 -289.099394) (xy 151.92342 -289.088766) (xy 151.925528 -289.08375) (xy 151.94534 -289.039554)
			(xy 151.947453 -289.034607) (xy 151.949765 -289.024103) (xy 151.949912 -289.018726) (xy 151.949912 -288.519108)
			(xy 151.94534 -288.508948) (xy 151.941276 -288.49955) (xy 151.941276 -288.498534) (xy 151.938482 -288.490406)
			(xy 151.930433 -288.466102) (xy 151.921632 -288.41567) (xy 151.920956 -288.390076) (xy 151.920956 -288.154872)
			(xy 151.921099 -288.149433) (xy 151.923408 -288.138802) (xy 151.925528 -288.13379) (xy 151.94534 -288.089594)
			(xy 151.947446 -288.084646) (xy 151.949746 -288.074142) (xy 151.949912 -288.068766) (xy 151.949912 -287.569148)
			(xy 151.94534 -287.558988) (xy 151.941276 -287.54959) (xy 151.941276 -287.548574) (xy 151.938482 -287.540446)
			(xy 151.93043 -287.516142) (xy 151.921622 -287.46571) (xy 151.920956 -287.440116) (xy 151.920956 -287.204912)
			(xy 151.921095 -287.199472) (xy 151.923397 -287.188837) (xy 151.925528 -287.18383) (xy 151.94534 -287.139634)
			(xy 151.94745 -287.134686) (xy 151.949758 -287.124183) (xy 151.949912 -287.118806) (xy 151.949912 -286.619188)
			(xy 151.94534 -286.609028) (xy 151.941276 -286.59963) (xy 151.941276 -286.598614) (xy 151.938482 -286.590486)
			(xy 151.930427 -286.566183) (xy 151.921613 -286.515751) (xy 151.920956 -286.490156) (xy 151.920956 -286.254698)
			(xy 151.921097 -286.249258) (xy 151.923401 -286.238625) (xy 151.925528 -286.233616) (xy 151.94534 -286.18942)
			(xy 151.947449 -286.184472) (xy 151.949754 -286.173968) (xy 151.949912 -286.168592) (xy 151.949912 -285.668974)
			(xy 151.94534 -285.658814) (xy 151.941276 -285.649416) (xy 151.941276 -285.6484) (xy 151.938482 -285.640272)
			(xy 151.930428 -285.615969) (xy 151.921616 -285.565537) (xy 151.920956 -285.539942) (xy 151.920956 -285.304738)
			(xy 151.921103 -285.299299) (xy 151.923418 -285.288671) (xy 151.925528 -285.283656) (xy 151.94534 -285.23946)
			(xy 151.947453 -285.234513) (xy 151.949767 -285.224009) (xy 151.949912 -285.218632) (xy 151.949912 -284.719014)
			(xy 151.94534 -284.708854) (xy 151.941276 -284.699456) (xy 151.941276 -284.69844) (xy 151.938482 -284.690312)
			(xy 151.930432 -284.666008) (xy 151.921631 -284.615576) (xy 151.920956 -284.589982) (xy 151.920956 -284.449012)
			(xy 151.923242 -284.443678) (xy 151.92375 -284.442154) (xy 151.924258 -284.440884) (xy 151.927814 -284.432756)
			(xy 151.943816 -284.393894) (xy 151.943816 -284.39364) (xy 151.945594 -284.389576) (xy 151.949912 -284.37967)
			(xy 151.949912 -284.306264) (xy 151.950342 -284.296197) (xy 151.958067 -284.277603) (xy 151.964898 -284.270196)
			(xy 152.131776 -284.103318) (xy 152.138906 -284.095489) (xy 152.146652 -284.075806) (xy 152.146762 -284.065218)
			(xy 152.146254 -284.061662) (xy 152.146 -284.05963) (xy 152.146 -284.058868) (xy 152.145492 -284.055566)
			(xy 152.144222 -284.02661) (xy 152.144222 -284.023816) (xy 152.144801 -283.997931) (xy 152.153022 -283.946815)
			(xy 152.169108 -283.897604) (xy 152.192668 -283.851502) (xy 152.223124 -283.809634) (xy 152.259733 -283.773025)
			(xy 152.3016 -283.742569) (xy 152.347702 -283.719009) (xy 152.396913 -283.702922) (xy 152.448029 -283.694701)
			(xy 152.473914 -283.694124) (xy 152.475438 -283.694124) (xy 152.484601 -283.694186) (xy 152.5029 -283.695199)
			(xy 152.512014 -283.696156) (xy 152.523402 -283.696788) (xy 152.544903 -283.689269) (xy 152.553416 -283.681678)
			(xy 153.105358 -283.129736) (xy 153.112427 -283.121882) (xy 153.120059 -283.102201) (xy 153.12009 -283.091636)
			(xy 153.12009 -283.091128) (xy 153.119582 -283.075126) (xy 153.119582 -283.074618) (xy 153.120073 -283.050654)
			(xy 153.127606 -283.00332) (xy 153.142443 -282.957745) (xy 153.164219 -282.915047) (xy 153.192399 -282.876278)
			(xy 153.226291 -282.842387) (xy 153.265063 -282.814209) (xy 153.307761 -282.792436) (xy 153.353337 -282.777602)
			(xy 153.400672 -282.770071) (xy 153.424636 -282.769564) (xy 153.425398 -282.769564) (xy 153.441654 -282.770072)
			(xy 153.447032 -282.77022) (xy 153.457659 -282.768551) (xy 153.462736 -282.76677) (xy 153.47188 -282.763214)
			(xy 154.055318 -282.179776) (xy 154.058216 -282.176714) (xy 154.063073 -282.169824) (xy 154.06497 -282.16606)
			(xy 154.070812 -282.154122) (xy 154.070304 -282.14447) (xy 154.069796 -282.124912) (xy 154.069796 -282.124658)
			(xy 154.070284 -282.100692) (xy 154.077812 -282.053354) (xy 154.092645 -282.007774) (xy 154.11442 -281.965073)
			(xy 154.142599 -281.926299) (xy 154.176493 -281.892405) (xy 154.215266 -281.864224) (xy 154.257967 -281.842448)
			(xy 154.303546 -281.827614) (xy 154.350884 -281.820084) (xy 154.37485 -281.819604) (xy 154.37739 -281.819604)
			(xy 154.390852 -281.820112) (xy 154.391614 -281.820112) (xy 154.402028 -281.82062) (xy 154.412696 -281.816302)
			(xy 154.417484 -281.814311) (xy 154.426186 -281.808674) (xy 154.429968 -281.805126) (xy 154.7622 -281.472894)
			(xy 154.769599 -281.466048) (xy 154.788197 -281.458315) (xy 154.798268 -281.457908) (xy 160.255712 -281.457908)
			(xy 160.266949 -281.45732) (xy 160.287253 -281.447689) (xy 160.294828 -281.439366) (xy 160.310617 -281.420916)
			(xy 160.34668 -281.388396) (xy 160.387111 -281.3615) (xy 160.431041 -281.340807) (xy 160.477525 -281.326762)
			(xy 160.525564 -281.319666) (xy 160.549844 -281.319224) (xy 160.58388 -281.321002) (xy 160.59531 -281.322272)
			(xy 160.6169 -281.314652) (xy 160.680908 -281.25039) (xy 160.688458 -281.241929) (xy 160.695975 -281.220566)
			(xy 160.695386 -281.209242) (xy 160.69437 -281.196796) (xy 160.693608 -281.174952) (xy 160.693608 -280.224992)
			(xy 160.694119 -280.198984) (xy 160.702257 -280.14761) (xy 160.71833 -280.09814) (xy 160.741944 -280.051794)
			(xy 160.772517 -280.009713) (xy 160.809296 -279.972931) (xy 160.851376 -279.942356) (xy 160.89772 -279.918739)
			(xy 160.947188 -279.902662) (xy 160.998562 -279.894521) (xy 161.02457 -279.89403) (xy 161.025332 -279.89403)
			(xy 161.040406 -279.89422) (xy 161.070425 -279.897023) (xy 161.085276 -279.899618) (xy 161.085784 -279.899618)
			(xy 161.091118 -279.900634) (xy 161.113978 -279.893522) (xy 161.181796 -279.829006) (xy 161.189872 -279.820369)
			(xy 161.19783 -279.798131) (xy 161.197036 -279.786334) (xy 161.197036 -279.78608) (xy 161.195982 -279.776972)
			(xy 161.19484 -279.758672) (xy 161.19475 -279.749504) (xy 161.195236 -279.724679) (xy 161.203268 -279.675683)
			(xy 161.219121 -279.628632) (xy 161.242378 -279.584765) (xy 161.272425 -279.545239) (xy 161.308471 -279.511096)
			(xy 161.349567 -279.483233) (xy 161.394628 -279.462387) (xy 161.442469 -279.449105) (xy 161.491828 -279.443739)
			(xy 161.541405 -279.446429) (xy 161.589894 -279.457104) (xy 161.636017 -279.475484) (xy 161.678559 -279.501084)
			(xy 161.716398 -279.533229) (xy 161.748539 -279.571072) (xy 161.774133 -279.613617) (xy 161.792507 -279.659742)
			(xy 161.803176 -279.708232) (xy 161.80586 -279.75781) (xy 161.800487 -279.807168) (xy 161.7872 -279.855007)
			(xy 161.766348 -279.900067) (xy 161.738481 -279.941158) (xy 161.704332 -279.9772) (xy 161.664803 -280.007243)
			(xy 161.620933 -280.030494) (xy 161.57388 -280.046341) (xy 161.524883 -280.054367) (xy 161.500058 -280.054812)
			(xy 161.49089 -280.054718) (xy 161.47259 -280.053572) (xy 161.463482 -280.052526) (xy 161.463228 -280.052526)
			(xy 161.451426 -280.051711) (xy 161.429176 -280.059662) (xy 161.420556 -280.067766) (xy 161.35604 -280.135584)
			(xy 161.348928 -280.158444) (xy 161.349944 -280.164032) (xy 161.352535 -280.178947) (xy 161.355331 -280.209093)
			(xy 161.355532 -280.22423) (xy 161.355532 -280.295096) (xy 161.356091 -280.30579) (xy 161.364747 -280.325349)
			(xy 161.372296 -280.332942) (xy 161.436812 -280.3906) (xy 161.457132 -280.397204) (xy 161.467546 -280.396188)
			(xy 161.468054 -280.396188) (xy 161.500058 -280.39441) (xy 161.525317 -280.394899) (xy 161.575145 -280.403208)
			(xy 161.622927 -280.419606) (xy 161.667357 -280.443645) (xy 161.707225 -280.47467) (xy 161.741441 -280.511834)
			(xy 161.769074 -280.554124) (xy 161.789368 -280.600385) (xy 161.80177 -280.649356) (xy 161.805942 -280.6997)
			(xy 161.80177 -280.750044) (xy 161.789368 -280.799015) (xy 161.769074 -280.845276) (xy 161.741441 -280.887566)
			(xy 161.707225 -280.92473) (xy 161.667357 -280.955755) (xy 161.622927 -280.979794) (xy 161.575145 -280.996192)
			(xy 161.525317 -281.004501) (xy 161.500058 -281.005026) (xy 161.468054 -281.003248) (xy 161.467546 -281.003248)
			(xy 161.457132 -281.002232) (xy 161.436812 -281.008836) (xy 161.372296 -281.066494) (xy 161.36464 -281.074013)
			(xy 161.355962 -281.093617) (xy 161.355532 -281.10434) (xy 161.355532 -281.174952) (xy 161.35477 -281.196796)
			(xy 161.353754 -281.209242) (xy 161.353164 -281.220568) (xy 161.360674 -281.241936) (xy 161.368232 -281.25039)
			(xy 161.432494 -281.314652) (xy 161.454084 -281.322272) (xy 161.46526 -281.321002) (xy 161.500058 -281.319224)
			(xy 161.52434 -281.319648) (xy 161.572383 -281.326743) (xy 161.618873 -281.340786) (xy 161.662809 -281.361477)
			(xy 161.703248 -281.388369) (xy 161.73932 -281.420885) (xy 161.755074 -281.439366) (xy 161.762676 -281.447646)
			(xy 161.782967 -281.45726) (xy 161.79419 -281.457908) (xy 162.155886 -281.457908) (xy 162.167126 -281.457326)
			(xy 162.187438 -281.4477) (xy 162.195002 -281.439366) (xy 162.210791 -281.420915) (xy 162.246853 -281.388392)
			(xy 162.287283 -281.361493) (xy 162.331213 -281.340796) (xy 162.377698 -281.326747) (xy 162.425737 -281.319648)
			(xy 162.450018 -281.319224) (xy 162.4838 -281.321002) (xy 162.49523 -281.322272) (xy 162.51682 -281.314652)
			(xy 162.580828 -281.25039) (xy 162.588376 -281.241928) (xy 162.595889 -281.220566) (xy 162.595306 -281.209242)
			(xy 162.59429 -281.196796) (xy 162.593528 -281.174952) (xy 162.593528 -280.224992) (xy 162.594039 -280.198985)
			(xy 162.602177 -280.147612) (xy 162.618251 -280.098144) (xy 162.641865 -280.051799) (xy 162.672438 -280.009719)
			(xy 162.709217 -279.972939) (xy 162.751297 -279.942366) (xy 162.797642 -279.918751) (xy 162.84711 -279.902677)
			(xy 162.898483 -279.894539) (xy 162.92449 -279.89403) (xy 162.925252 -279.89403) (xy 162.940327 -279.894217)
			(xy 162.970347 -279.897012) (xy 162.985196 -279.899618) (xy 162.985704 -279.899618) (xy 162.991038 -279.900634)
			(xy 163.013898 -279.893522) (xy 163.081716 -279.829006) (xy 163.08979 -279.820368) (xy 163.097744 -279.79813)
			(xy 163.096956 -279.786334) (xy 163.096956 -279.78608) (xy 163.095902 -279.776972) (xy 163.09476 -279.758672)
			(xy 163.09467 -279.749504) (xy 163.095156 -279.724681) (xy 163.103187 -279.675689) (xy 163.119039 -279.628641)
			(xy 163.142293 -279.584778) (xy 163.172338 -279.545255) (xy 163.208381 -279.511113) (xy 163.249472 -279.483253)
			(xy 163.29453 -279.462407) (xy 163.342367 -279.449126) (xy 163.391722 -279.443759) (xy 163.441296 -279.446448)
			(xy 163.489781 -279.457121) (xy 163.535901 -279.475498) (xy 163.57844 -279.501094) (xy 163.616277 -279.533236)
			(xy 163.648416 -279.571075) (xy 163.67401 -279.613616) (xy 163.692384 -279.659736) (xy 163.703055 -279.708222)
			(xy 163.70574 -279.757796) (xy 163.700371 -279.807151) (xy 163.687086 -279.854987) (xy 163.666238 -279.900043)
			(xy 163.638375 -279.941133) (xy 163.604231 -279.977174) (xy 163.564707 -280.007216) (xy 163.520842 -280.030468)
			(xy 163.473794 -280.046317) (xy 163.424801 -280.054346) (xy 163.399978 -280.054812) (xy 163.39081 -280.054719)
			(xy 163.37251 -280.053574) (xy 163.363402 -280.052526) (xy 163.363148 -280.052526) (xy 163.351344 -280.051707)
			(xy 163.329087 -280.059652) (xy 163.320476 -280.067766) (xy 163.25596 -280.135584) (xy 163.248848 -280.158444)
			(xy 163.249864 -280.164032) (xy 163.252455 -280.178947) (xy 163.255251 -280.209093) (xy 163.255452 -280.22423)
			(xy 163.255452 -280.295096) (xy 163.256012 -280.305789) (xy 163.26467 -280.325346) (xy 163.272216 -280.332942)
			(xy 163.336732 -280.3906) (xy 163.357052 -280.397204) (xy 163.36772 -280.396188) (xy 163.399978 -280.39441)
			(xy 163.425235 -280.394901) (xy 163.475062 -280.403212) (xy 163.52284 -280.419612) (xy 163.567268 -280.443652)
			(xy 163.607133 -280.474677) (xy 163.641347 -280.511841) (xy 163.668977 -280.554129) (xy 163.689269 -280.600389)
			(xy 163.70167 -280.649358) (xy 163.705842 -280.6997) (xy 163.70167 -280.750042) (xy 163.689269 -280.799011)
			(xy 163.668977 -280.845271) (xy 163.641347 -280.887559) (xy 163.607133 -280.924723) (xy 163.567268 -280.955748)
			(xy 163.52284 -280.979788) (xy 163.475062 -280.996188) (xy 163.425235 -281.004499) (xy 163.399978 -281.005026)
			(xy 163.367974 -281.003248) (xy 163.367466 -281.003248) (xy 163.357052 -281.002232) (xy 163.336732 -281.008836)
			(xy 163.272216 -281.066494) (xy 163.264558 -281.074012) (xy 163.255876 -281.093617) (xy 163.255452 -281.10434)
			(xy 163.255452 -281.174952) (xy 163.25469 -281.196796) (xy 163.253674 -281.209242) (xy 163.253084 -281.220567)
			(xy 163.260596 -281.241934) (xy 163.268152 -281.25039) (xy 163.332414 -281.314652) (xy 163.354004 -281.322272)
			(xy 163.36518 -281.321002) (xy 163.399978 -281.319224) (xy 163.42426 -281.31965) (xy 163.472301 -281.326747)
			(xy 163.518788 -281.340793) (xy 163.562723 -281.361484) (xy 163.603159 -281.388378) (xy 163.639229 -281.420894)
			(xy 163.654994 -281.439366) (xy 163.662598 -281.447643) (xy 163.682889 -281.457249) (xy 163.69411 -281.457908)
			(xy 164.055806 -281.457908) (xy 164.067044 -281.457322) (xy 164.08735 -281.447691) (xy 164.094922 -281.439366)
			(xy 164.110711 -281.420916) (xy 164.146774 -281.388395) (xy 164.187205 -281.361499) (xy 164.231135 -281.340805)
			(xy 164.277619 -281.326758) (xy 164.325658 -281.319662) (xy 164.349938 -281.319224) (xy 164.350446 -281.319224)
			(xy 164.374283 -281.319659) (xy 164.421458 -281.326545) (xy 164.444426 -281.33294) (xy 164.454792 -281.335447)
			(xy 164.475917 -281.332714) (xy 164.494121 -281.321651) (xy 164.506279 -281.30416) (xy 164.510303 -281.283242)
			(xy 164.508434 -281.272742) (xy 164.499798 -281.237944) (xy 164.499798 -281.236674) (xy 164.498782 -281.231594)
			(xy 164.497512 -281.22499) (xy 164.497512 -281.222704) (xy 164.49675 -281.21864) (xy 164.495734 -281.211528)
			(xy 164.49548 -281.209496) (xy 164.493956 -281.175968) (xy 164.493956 -280.224992) (xy 164.494466 -280.199004)
			(xy 164.502597 -280.147669) (xy 164.518659 -280.098237) (xy 164.542254 -280.051926) (xy 164.572804 -280.009876)
			(xy 164.609554 -279.973122) (xy 164.651602 -279.942569) (xy 164.697911 -279.918969) (xy 164.747341 -279.902904)
			(xy 164.798676 -279.894768) (xy 164.824664 -279.894284) (xy 164.839092 -279.894447) (xy 164.867836 -279.89699)
			(xy 164.882068 -279.899364) (xy 164.88283 -279.899364) (xy 164.891466 -279.900888) (xy 164.914072 -279.893776)
			(xy 164.981636 -279.82926) (xy 164.989699 -279.820619) (xy 164.99763 -279.798384) (xy 164.996876 -279.786588)
			(xy 164.996876 -279.786334) (xy 164.995813 -279.777163) (xy 164.994667 -279.758736) (xy 164.99459 -279.749504)
			(xy 164.995076 -279.724683) (xy 165.003106 -279.675694) (xy 165.018956 -279.628651) (xy 165.042209 -279.584791)
			(xy 165.072251 -279.545271) (xy 165.10829 -279.511131) (xy 165.149378 -279.483273) (xy 165.194432 -279.462428)
			(xy 165.242265 -279.449147) (xy 165.291616 -279.443779) (xy 165.341186 -279.446466) (xy 165.389667 -279.457138)
			(xy 165.435784 -279.475512) (xy 165.47832 -279.501105) (xy 165.516156 -279.533243) (xy 165.548294 -279.571078)
			(xy 165.573887 -279.613614) (xy 165.592262 -279.659731) (xy 165.602933 -279.708212) (xy 165.605621 -279.757782)
			(xy 165.600254 -279.807133) (xy 165.586973 -279.854966) (xy 165.566128 -279.90002) (xy 165.53827 -279.941108)
			(xy 165.504131 -279.977148) (xy 165.464611 -280.00719) (xy 165.420751 -280.030443) (xy 165.373707 -280.046293)
			(xy 165.324719 -280.054324) (xy 165.299898 -280.054812) (xy 165.29073 -280.054719) (xy 165.27243 -280.053576)
			(xy 165.263322 -280.052526) (xy 165.263068 -280.052526) (xy 165.251262 -280.051702) (xy 165.228999 -280.059641)
			(xy 165.220396 -280.067766) (xy 165.15588 -280.135584) (xy 165.148768 -280.158444) (xy 165.149784 -280.164286)
			(xy 165.152391 -280.179263) (xy 165.155189 -280.209537) (xy 165.155372 -280.224738) (xy 165.155372 -280.295096)
			(xy 165.155929 -280.305791) (xy 165.164578 -280.325357) (xy 165.172136 -280.332942) (xy 165.236652 -280.3906)
			(xy 165.256972 -280.397204) (xy 165.26764 -280.396188) (xy 165.299898 -280.39441) (xy 165.325154 -280.394902)
			(xy 165.374978 -280.403216) (xy 165.422754 -280.419617) (xy 165.467179 -280.443659) (xy 165.50704 -280.474684)
			(xy 165.541252 -280.511847) (xy 165.56888 -280.554135) (xy 165.58917 -280.600393) (xy 165.601571 -280.64936)
			(xy 165.605742 -280.6997) (xy 165.601571 -280.75004) (xy 165.58917 -280.799007) (xy 165.56888 -280.845265)
			(xy 165.541252 -280.887553) (xy 165.50704 -280.924716) (xy 165.467179 -280.955741) (xy 165.422754 -280.979783)
			(xy 165.374978 -280.996184) (xy 165.325154 -281.004498) (xy 165.299898 -281.005026) (xy 165.267894 -281.003248)
			(xy 165.267386 -281.003248) (xy 165.256972 -281.002232) (xy 165.236652 -281.008836) (xy 165.172136 -281.066494)
			(xy 165.164476 -281.074011) (xy 165.155791 -281.093616) (xy 165.155372 -281.10434) (xy 165.155372 -281.175206)
			(xy 165.15528 -281.185329) (xy 165.154009 -281.205537) (xy 165.152832 -281.215592) (xy 165.152832 -281.216608)
			(xy 165.152324 -281.22118) (xy 165.159944 -281.242516) (xy 165.224206 -281.306524) (xy 165.232667 -281.314073)
			(xy 165.25403 -281.321589) (xy 165.265354 -281.321002) (xy 165.29939 -281.319224) (xy 165.299898 -281.319224)
			(xy 165.324179 -281.319651) (xy 165.372219 -281.326751) (xy 165.418704 -281.340799) (xy 165.462636 -281.361492)
			(xy 165.503071 -281.388387) (xy 165.539138 -281.420904) (xy 165.554914 -281.439366) (xy 165.562513 -281.447656)
			(xy 165.582803 -281.457293) (xy 165.59403 -281.457908) (xy 165.955726 -281.457908) (xy 165.966962 -281.457317)
			(xy 165.987261 -281.447682) (xy 165.994842 -281.439366) (xy 166.010631 -281.420917) (xy 166.046695 -281.388398)
			(xy 166.087126 -281.361504) (xy 166.131056 -281.340813) (xy 166.17754 -281.326769) (xy 166.225578 -281.319676)
			(xy 166.249858 -281.319224) (xy 166.250366 -281.319224) (xy 166.274203 -281.319661) (xy 166.321377 -281.326549)
			(xy 166.344346 -281.33294) (xy 166.354709 -281.335443) (xy 166.375827 -281.332704) (xy 166.394023 -281.321642)
			(xy 166.406175 -281.304155) (xy 166.410197 -281.283244) (xy 166.408354 -281.272742) (xy 166.399718 -281.237944)
			(xy 166.399718 -281.236674) (xy 166.398702 -281.231594) (xy 166.397432 -281.22499) (xy 166.397432 -281.222704)
			(xy 166.39667 -281.21864) (xy 166.395654 -281.211528) (xy 166.3954 -281.209496) (xy 166.393876 -281.175968)
			(xy 166.393876 -280.224992) (xy 166.394386 -280.199005) (xy 166.402518 -280.14767) (xy 166.418579 -280.09824)
			(xy 166.442175 -280.05193) (xy 166.472725 -280.009882) (xy 166.509476 -279.97313) (xy 166.551523 -279.942579)
			(xy 166.597832 -279.918982) (xy 166.647263 -279.902919) (xy 166.698597 -279.894787) (xy 166.724584 -279.894284)
			(xy 166.738365 -279.894427) (xy 166.765833 -279.896717) (xy 166.779448 -279.898856) (xy 166.791132 -279.900888)
			(xy 166.813992 -279.893776) (xy 166.88181 -279.82926) (xy 166.889876 -279.82062) (xy 166.897811 -279.798384)
			(xy 166.89705 -279.786588) (xy 166.89705 -279.786334) (xy 166.895987 -279.777163) (xy 166.894841 -279.758736)
			(xy 166.894764 -279.749504) (xy 166.89525 -279.72468) (xy 166.903281 -279.675687) (xy 166.919133 -279.628638)
			(xy 166.942389 -279.584774) (xy 166.972434 -279.54525) (xy 167.008478 -279.511108) (xy 167.049571 -279.483247)
			(xy 167.09463 -279.462401) (xy 167.142468 -279.44912) (xy 167.191824 -279.443753) (xy 167.241398 -279.446442)
			(xy 167.289885 -279.457116) (xy 167.336006 -279.475494) (xy 167.378545 -279.501091) (xy 167.416383 -279.533234)
			(xy 167.448523 -279.571074) (xy 167.474117 -279.613616) (xy 167.492491 -279.659738) (xy 167.503161 -279.708225)
			(xy 167.505846 -279.7578) (xy 167.500476 -279.807156) (xy 167.487191 -279.854993) (xy 167.466341 -279.90005)
			(xy 167.438477 -279.941141) (xy 167.404332 -279.977182) (xy 167.364805 -280.007224) (xy 167.32094 -280.030476)
			(xy 167.27389 -280.046325) (xy 167.224896 -280.054352) (xy 167.200072 -280.054812) (xy 167.190841 -280.054727)
			(xy 167.172413 -280.053586) (xy 167.163242 -280.052526) (xy 167.162988 -280.052526) (xy 167.151189 -280.05172)
			(xy 167.128952 -280.059683) (xy 167.120316 -280.067766) (xy 167.0558 -280.135584) (xy 167.048688 -280.158444)
			(xy 167.05072 -280.170128) (xy 167.052867 -280.183742) (xy 167.055156 -280.21121) (xy 167.055292 -280.224992)
			(xy 167.055292 -280.295096) (xy 167.05585 -280.30579) (xy 167.064501 -280.325354) (xy 167.072056 -280.332942)
			(xy 167.136572 -280.3906) (xy 167.156892 -280.397204) (xy 167.16756 -280.396188) (xy 167.200072 -280.39441)
			(xy 167.22533 -280.3949) (xy 167.275157 -280.403211) (xy 167.322936 -280.41961) (xy 167.367365 -280.44365)
			(xy 167.40723 -280.474675) (xy 167.441445 -280.511839) (xy 167.469076 -280.554128) (xy 167.489369 -280.600388)
			(xy 167.50177 -280.649357) (xy 167.505942 -280.6997) (xy 167.50177 -280.750043) (xy 167.489369 -280.799012)
			(xy 167.469076 -280.845272) (xy 167.441445 -280.887561) (xy 167.40723 -280.924725) (xy 167.367365 -280.95575)
			(xy 167.322936 -280.97979) (xy 167.275157 -280.996189) (xy 167.22533 -281.0045) (xy 167.200072 -281.005026)
			(xy 167.167814 -281.003248) (xy 167.167306 -281.003248) (xy 167.156892 -281.002232) (xy 167.136572 -281.008836)
			(xy 167.072056 -281.066494) (xy 167.064393 -281.07401) (xy 167.055704 -281.093615) (xy 167.055292 -281.10434)
			(xy 167.055292 -281.175206) (xy 167.0552 -281.185329) (xy 167.053929 -281.205537) (xy 167.052752 -281.215592)
			(xy 167.052752 -281.216608) (xy 167.052244 -281.22118) (xy 167.059864 -281.242516) (xy 167.124126 -281.306524)
			(xy 167.132588 -281.314069) (xy 167.15395 -281.321577) (xy 167.165274 -281.321002) (xy 167.200072 -281.319224)
			(xy 167.224354 -281.319649) (xy 167.272396 -281.326746) (xy 167.318884 -281.340791) (xy 167.362819 -281.361482)
			(xy 167.403256 -281.388375) (xy 167.439326 -281.420891) (xy 167.455088 -281.439366) (xy 167.462692 -281.447644)
			(xy 167.482982 -281.457252) (xy 167.494204 -281.457908) (xy 167.8559 -281.457908) (xy 167.867139 -281.457323)
			(xy 167.887447 -281.447694) (xy 167.895016 -281.439366) (xy 167.910805 -281.420915) (xy 167.946867 -281.388394)
			(xy 167.987298 -281.361497) (xy 168.031228 -281.340802) (xy 168.077713 -281.326755) (xy 168.125752 -281.319657)
			(xy 168.150032 -281.319224) (xy 168.173933 -281.319648) (xy 168.221236 -281.326535) (xy 168.244266 -281.33294)
			(xy 168.254652 -281.335441) (xy 168.275807 -281.33267) (xy 168.294015 -281.321547) (xy 168.306138 -281.303989)
			(xy 168.310087 -281.283022) (xy 168.308274 -281.272488) (xy 168.299638 -281.237944) (xy 168.299638 -281.236674)
			(xy 168.298622 -281.231594) (xy 168.297352 -281.22499) (xy 168.297352 -281.222704) (xy 168.29659 -281.21864)
			(xy 168.295574 -281.211528) (xy 168.29532 -281.209496) (xy 168.293796 -281.175968) (xy 168.293796 -280.224992)
			(xy 168.294306 -280.199005) (xy 168.302438 -280.147672) (xy 168.318499 -280.098243) (xy 168.342096 -280.051935)
			(xy 168.372646 -280.009888) (xy 168.409397 -279.973138) (xy 168.451445 -279.94259) (xy 168.497754 -279.918995)
			(xy 168.547184 -279.902935) (xy 168.598517 -279.894805) (xy 168.624504 -279.894284) (xy 168.638285 -279.894428)
			(xy 168.665752 -279.89672) (xy 168.679368 -279.898856) (xy 168.691052 -279.900888) (xy 168.713912 -279.893776)
			(xy 168.78173 -279.82926) (xy 168.789794 -279.820619) (xy 168.797726 -279.798384) (xy 168.79697 -279.786588)
			(xy 168.79697 -279.786334) (xy 168.795907 -279.777163) (xy 168.794761 -279.758736) (xy 168.794684 -279.749504)
			(xy 168.79517 -279.724682) (xy 168.8032 -279.675693) (xy 168.819051 -279.628648) (xy 168.842304 -279.584787)
			(xy 168.872347 -279.545266) (xy 168.908387 -279.511126) (xy 168.949477 -279.483267) (xy 168.994532 -279.462422)
			(xy 169.042366 -279.449141) (xy 169.091718 -279.443773) (xy 169.141289 -279.446461) (xy 169.189771 -279.457133)
			(xy 169.235889 -279.475508) (xy 169.278426 -279.501102) (xy 169.316262 -279.533241) (xy 169.3484 -279.571077)
			(xy 169.373994 -279.613615) (xy 169.392368 -279.659732) (xy 169.40304 -279.708215) (xy 169.405727 -279.757786)
			(xy 169.400359 -279.807138) (xy 169.387077 -279.854972) (xy 169.366231 -279.900027) (xy 169.338371 -279.941116)
			(xy 169.304231 -279.977156) (xy 169.26471 -280.007198) (xy 169.220848 -280.03045) (xy 169.173803 -280.046301)
			(xy 169.124814 -280.054331) (xy 169.099992 -280.054812) (xy 169.090761 -280.054725) (xy 169.072334 -280.053578)
			(xy 169.063162 -280.052526) (xy 169.062908 -280.052526) (xy 169.051107 -280.051716) (xy 169.028864 -280.059673)
			(xy 169.020236 -280.067766) (xy 168.95572 -280.135584) (xy 168.948608 -280.158444) (xy 168.95064 -280.170128)
			(xy 168.952787 -280.183742) (xy 168.955075 -280.21121) (xy 168.955212 -280.224992) (xy 168.955212 -280.295096)
			(xy 168.955771 -280.30579) (xy 168.964424 -280.325352) (xy 168.971976 -280.332942) (xy 169.036492 -280.3906)
			(xy 169.056812 -280.397204) (xy 169.06748 -280.396188) (xy 169.099992 -280.39441) (xy 169.125249 -280.394902)
			(xy 169.175073 -280.403215) (xy 169.22285 -280.419616) (xy 169.267275 -280.443657) (xy 169.307138 -280.474682)
			(xy 169.34135 -280.511845) (xy 169.368979 -280.554133) (xy 169.38927 -280.600392) (xy 169.401671 -280.649359)
			(xy 169.405842 -280.6997) (xy 169.401671 -280.750041) (xy 169.38927 -280.799008) (xy 169.368979 -280.845267)
			(xy 169.34135 -280.887555) (xy 169.307138 -280.924718) (xy 169.267275 -280.955743) (xy 169.22285 -280.979784)
			(xy 169.175073 -280.996185) (xy 169.125249 -281.004498) (xy 169.099992 -281.005026) (xy 169.067734 -281.003248)
			(xy 169.067226 -281.003248) (xy 169.056812 -281.002232) (xy 169.036492 -281.008836) (xy 168.971976 -281.066494)
			(xy 168.96431 -281.074008) (xy 168.955618 -281.093614) (xy 168.955212 -281.10434) (xy 168.955212 -281.175206)
			(xy 168.95512 -281.185329) (xy 168.953849 -281.205537) (xy 168.952672 -281.215592) (xy 168.952672 -281.216608)
			(xy 168.952164 -281.22118) (xy 168.959784 -281.242516) (xy 169.024046 -281.306524) (xy 169.032504 -281.314084)
			(xy 169.053869 -281.321625) (xy 169.065194 -281.321002) (xy 169.099992 -281.319224) (xy 169.124273 -281.319651)
			(xy 169.172313 -281.32675) (xy 169.2188 -281.340797) (xy 169.262732 -281.36149) (xy 169.303167 -281.388384)
			(xy 169.339235 -281.420901) (xy 169.355008 -281.439366) (xy 169.362606 -281.447657) (xy 169.382896 -281.457297)
			(xy 169.394124 -281.457908) (xy 169.75582 -281.457908) (xy 169.767057 -281.457319) (xy 169.787358 -281.447685)
			(xy 169.794936 -281.439366) (xy 169.810725 -281.420917) (xy 169.846788 -281.388397) (xy 169.88722 -281.361503)
			(xy 169.93115 -281.340811) (xy 169.977634 -281.326766) (xy 170.025672 -281.319671) (xy 170.049952 -281.319224)
			(xy 170.083988 -281.321002) (xy 170.095418 -281.322272) (xy 170.117008 -281.314652) (xy 170.181016 -281.25039)
			(xy 170.188565 -281.241929) (xy 170.19608 -281.220566) (xy 170.195494 -281.209242) (xy 170.194478 -281.196796)
			(xy 170.193716 -281.174952) (xy 170.193716 -280.224992) (xy 170.194227 -280.198985) (xy 170.202365 -280.147611)
			(xy 170.218438 -280.098142) (xy 170.242052 -280.051796) (xy 170.272625 -280.009715) (xy 170.309404 -279.972934)
			(xy 170.351484 -279.94236) (xy 170.397829 -279.918744) (xy 170.447297 -279.902668) (xy 170.498671 -279.894528)
			(xy 170.524678 -279.89403) (xy 170.52544 -279.89403) (xy 170.539804 -279.894202) (xy 170.56842 -279.89675)
			(xy 170.58259 -279.89911) (xy 170.583098 -279.89911) (xy 170.591226 -279.90038) (xy 170.613832 -279.893522)
			(xy 170.681396 -279.829006) (xy 170.689606 -279.820365) (xy 170.697683 -279.797973) (xy 170.69689 -279.78608)
			(xy 170.695836 -279.776972) (xy 170.694694 -279.758672) (xy 170.694604 -279.749504) (xy 170.69509 -279.724684)
			(xy 170.70312 -279.675699) (xy 170.718969 -279.628657) (xy 170.74222 -279.5848) (xy 170.77226 -279.545282)
			(xy 170.808297 -279.511144) (xy 170.849383 -279.483286) (xy 170.894434 -279.462442) (xy 170.942264 -279.449161)
			(xy 170.991612 -279.443793) (xy 171.041179 -279.44648) (xy 171.089658 -279.45715) (xy 171.135772 -279.475522)
			(xy 171.178307 -279.501113) (xy 171.216141 -279.533248) (xy 171.248278 -279.57108) (xy 171.273871 -279.613613)
			(xy 171.292246 -279.659727) (xy 171.302918 -279.708205) (xy 171.305607 -279.757772) (xy 171.300242 -279.807121)
			(xy 171.286963 -279.854951) (xy 171.266122 -279.900003) (xy 171.238266 -279.94109) (xy 171.20413 -279.97713)
			(xy 171.164614 -280.007172) (xy 171.120757 -280.030425) (xy 171.073717 -280.046277) (xy 171.024732 -280.054309)
			(xy 170.999912 -280.054812) (xy 170.990744 -280.05472) (xy 170.972444 -280.053577) (xy 170.963336 -280.052526)
			(xy 170.951652 -280.051002) (xy 170.928792 -280.05913) (xy 170.856148 -280.135584) (xy 170.849036 -280.15819)
			(xy 170.85056 -280.16708) (xy 170.852924 -280.181377) (xy 170.855464 -280.210247) (xy 170.85564 -280.224738)
			(xy 170.85564 -280.295096) (xy 170.8562 -280.305789) (xy 170.864856 -280.325348) (xy 170.872404 -280.332942)
			(xy 170.928538 -280.383488) (xy 170.93676 -280.390271) (xy 170.957016 -280.396849) (xy 170.967654 -280.396188)
			(xy 170.967908 -280.396188) (xy 170.999912 -280.39441) (xy 171.025165 -280.394932) (xy 171.074982 -280.403247)
			(xy 171.122752 -280.419648) (xy 171.16717 -280.443688) (xy 171.207026 -280.47471) (xy 171.241233 -280.51187)
			(xy 171.268856 -280.554152) (xy 171.289144 -280.600405) (xy 171.301542 -280.649366) (xy 171.305713 -280.6997)
			(xy 171.301542 -280.750034) (xy 171.289144 -280.798995) (xy 171.268856 -280.845248) (xy 171.241233 -280.88753)
			(xy 171.207026 -280.92469) (xy 171.16717 -280.955712) (xy 171.122752 -280.979752) (xy 171.074982 -280.996153)
			(xy 171.025165 -281.004468) (xy 170.999912 -281.005026) (xy 170.968162 -281.003248) (xy 170.967654 -281.003248)
			(xy 170.95703 -281.002724) (xy 170.936816 -281.009271) (xy 170.928538 -281.015948) (xy 170.872404 -281.066494)
			(xy 170.864747 -281.074013) (xy 170.856068 -281.093617) (xy 170.85564 -281.10434) (xy 170.85564 -281.174952)
			(xy 170.854878 -281.196796) (xy 170.853862 -281.209242) (xy 170.853272 -281.220567) (xy 170.860783 -281.241935)
			(xy 170.86834 -281.25039) (xy 170.932348 -281.314652) (xy 170.953938 -281.322272) (xy 170.965368 -281.321002)
			(xy 170.999404 -281.319224) (xy 170.999912 -281.319224) (xy 171.024192 -281.319652) (xy 171.072231 -281.326754)
			(xy 171.118715 -281.340803) (xy 171.162646 -281.361498) (xy 171.203079 -281.388393) (xy 171.239145 -281.420911)
			(xy 171.254928 -281.439366) (xy 171.262528 -281.447654) (xy 171.282818 -281.457286) (xy 171.294044 -281.457908)
			(xy 171.65574 -281.457908) (xy 171.666985 -281.457335) (xy 171.687312 -281.447721) (xy 171.694856 -281.439366)
			(xy 171.710644 -281.420912) (xy 171.746704 -281.388385) (xy 171.787134 -281.36148) (xy 171.831064 -281.340777)
			(xy 171.877549 -281.326722) (xy 171.92559 -281.319616) (xy 171.949872 -281.319224) (xy 171.973909 -281.319673)
			(xy 172.021469 -281.326689) (xy 172.044614 -281.333194) (xy 172.045884 -281.333702) (xy 172.054742 -281.335642)
			(xy 172.072778 -281.333873) (xy 172.08909 -281.325977) (xy 172.095668 -281.319732) (xy 172.101671 -281.313036)
			(xy 172.108945 -281.296603) (xy 172.110067 -281.278667) (xy 172.10786 -281.269948) (xy 172.099986 -281.237944)
			(xy 172.099986 -281.236674) (xy 172.09897 -281.231594) (xy 172.0977 -281.22499) (xy 172.0977 -281.222704)
			(xy 172.096938 -281.21864) (xy 172.095922 -281.211528) (xy 172.095668 -281.209496) (xy 172.094144 -281.175968)
			(xy 172.094144 -280.224992) (xy 172.094654 -280.199004) (xy 172.102785 -280.147668) (xy 172.118846 -280.098235)
			(xy 172.142442 -280.051923) (xy 172.172991 -280.009872) (xy 172.209742 -279.973117) (xy 172.251789 -279.942563)
			(xy 172.298098 -279.918962) (xy 172.347529 -279.902895) (xy 172.398864 -279.894757) (xy 172.424852 -279.894284)
			(xy 172.439794 -279.894438) (xy 172.469558 -279.897107) (xy 172.484288 -279.899618) (xy 172.484796 -279.899618)
			(xy 172.4914 -279.900634) (xy 172.514006 -279.893776) (xy 172.590206 -279.820624) (xy 172.598334 -279.798272)
			(xy 172.59681 -279.786334) (xy 172.595747 -279.777163) (xy 172.594601 -279.758736) (xy 172.594524 -279.749504)
			(xy 172.595009 -279.724686) (xy 172.603039 -279.675704) (xy 172.618887 -279.628667) (xy 172.642135 -279.584813)
			(xy 172.672172 -279.545297) (xy 172.708207 -279.511162) (xy 172.749289 -279.483306) (xy 172.794336 -279.462463)
			(xy 172.842162 -279.449182) (xy 172.891506 -279.443813) (xy 172.941069 -279.446498) (xy 172.989544 -279.457166)
			(xy 173.035656 -279.475536) (xy 173.078188 -279.501124) (xy 173.11602 -279.533255) (xy 173.148155 -279.571083)
			(xy 173.173748 -279.613612) (xy 173.192123 -279.659721) (xy 173.202797 -279.708195) (xy 173.205487 -279.757758)
			(xy 173.200125 -279.807103) (xy 173.18685 -279.85493) (xy 173.166012 -279.89998) (xy 173.138161 -279.941065)
			(xy 173.104029 -279.977104) (xy 173.064518 -280.007145) (xy 173.020666 -280.030399) (xy 172.973631 -280.046253)
			(xy 172.92465 -280.054288) (xy 172.899832 -280.054812) (xy 172.890664 -280.05472) (xy 172.872364 -280.053579)
			(xy 172.863256 -280.052526) (xy 172.851572 -280.051002) (xy 172.828712 -280.05913) (xy 172.756068 -280.135584)
			(xy 172.748956 -280.15819) (xy 172.75048 -280.167334) (xy 172.752847 -280.181631) (xy 172.755388 -280.210501)
			(xy 172.75556 -280.224992) (xy 172.75556 -280.295096) (xy 172.75612 -280.305789) (xy 172.764779 -280.325345)
			(xy 172.772324 -280.332942) (xy 172.828458 -280.383488) (xy 172.836681 -280.390268) (xy 172.856936 -280.396838)
			(xy 172.867574 -280.396188) (xy 172.867828 -280.396188) (xy 172.899832 -280.39441) (xy 172.925084 -280.394934)
			(xy 172.974899 -280.403251) (xy 173.022665 -280.419654) (xy 173.067081 -280.443695) (xy 173.106934 -280.474717)
			(xy 173.141138 -280.511876) (xy 173.168759 -280.554158) (xy 173.189045 -280.600409) (xy 173.201443 -280.649368)
			(xy 173.205613 -280.6997) (xy 173.201443 -280.750032) (xy 173.189045 -280.798991) (xy 173.168759 -280.845242)
			(xy 173.141138 -280.887524) (xy 173.106934 -280.924683) (xy 173.067081 -280.955705) (xy 173.022665 -280.979746)
			(xy 172.974899 -280.996149) (xy 172.925084 -281.004466) (xy 172.899832 -281.005026) (xy 172.868082 -281.003248)
			(xy 172.867574 -281.003248) (xy 172.856956 -281.00274) (xy 172.836763 -281.009311) (xy 172.828458 -281.015948)
			(xy 172.772324 -281.066494) (xy 172.764665 -281.074011) (xy 172.755982 -281.093616) (xy 172.75556 -281.10434)
			(xy 172.75556 -281.175206) (xy 172.755468 -281.185329) (xy 172.754197 -281.205537) (xy 172.75302 -281.215592)
			(xy 172.75302 -281.216608) (xy 172.752512 -281.22118) (xy 172.760132 -281.242516) (xy 172.824394 -281.306524)
			(xy 172.832855 -281.314075) (xy 172.854218 -281.321596) (xy 172.865542 -281.321002) (xy 172.899578 -281.319224)
			(xy 172.900086 -281.319224) (xy 172.924367 -281.31965) (xy 172.972408 -281.326749) (xy 173.018895 -281.340795)
			(xy 173.062828 -281.361487) (xy 173.103264 -281.388381) (xy 173.139333 -281.420898) (xy 173.155102 -281.439366)
			(xy 173.162706 -281.447642) (xy 173.182997 -281.457244) (xy 173.194218 -281.457908) (xy 173.555914 -281.457908)
			(xy 173.567151 -281.45732) (xy 173.587455 -281.447688) (xy 173.59503 -281.439366) (xy 173.610819 -281.420916)
			(xy 173.646882 -281.388397) (xy 173.687313 -281.361501) (xy 173.731243 -281.340808) (xy 173.777727 -281.326763)
			(xy 173.825766 -281.319667) (xy 173.850046 -281.319224) (xy 173.881288 -281.320748) (xy 173.892464 -281.321764)
			(xy 173.9138 -281.314144) (xy 173.980602 -281.247342) (xy 173.988111 -281.239077) (xy 173.995735 -281.218118)
			(xy 173.995334 -281.206956) (xy 173.995334 -281.205686) (xy 173.994826 -281.201114) (xy 173.994826 -281.20086)
			(xy 173.994572 -281.198574) (xy 173.994064 -281.191462) (xy 173.994064 -281.18943) (xy 173.99381 -281.187144)
			(xy 173.99381 -281.178254) (xy 173.993556 -281.176476) (xy 173.993556 -280.224738) (xy 173.994037 -280.198727)
			(xy 174.002169 -280.147346) (xy 174.018241 -280.097869) (xy 174.041855 -280.051517) (xy 174.07243 -280.009429)
			(xy 174.109214 -279.972643) (xy 174.1513 -279.942066) (xy 174.197651 -279.918449) (xy 174.247126 -279.902374)
			(xy 174.298507 -279.894238) (xy 174.324518 -279.893776) (xy 174.324772 -279.893776) (xy 174.3392 -279.893939)
			(xy 174.367943 -279.896485) (xy 174.382176 -279.898856) (xy 174.382684 -279.898856) (xy 174.39132 -279.90038)
			(xy 174.413926 -279.893268) (xy 174.49038 -279.820624) (xy 174.498508 -279.797764) (xy 174.496984 -279.78608)
			(xy 174.49593 -279.776972) (xy 174.494788 -279.758672) (xy 174.494698 -279.749504) (xy 174.495144 -279.725511)
			(xy 174.50265 -279.678115) (xy 174.517478 -279.632477) (xy 174.539264 -279.589721) (xy 174.567469 -279.550899)
			(xy 174.601401 -279.516968) (xy 174.640223 -279.488763) (xy 174.682979 -279.466978) (xy 174.728617 -279.45215)
			(xy 174.776013 -279.444644) (xy 174.800006 -279.444196) (xy 174.81804 -279.444704) (xy 174.83201 -279.445466)
			(xy 174.856648 -279.432512) (xy 174.911004 -279.34412) (xy 174.915514 -279.336091) (xy 174.919026 -279.318028)
			(xy 174.91589 -279.299896) (xy 174.911512 -279.291796) (xy 174.894494 -279.261316) (xy 174.891182 -279.25566)
			(xy 174.882178 -279.24614) (xy 174.876714 -279.24252) (xy 174.837836 -279.217372) (xy 174.764561 -279.160758)
			(xy 174.73041 -279.12949) (xy 174.725862 -279.125524) (xy 174.715335 -279.11963) (xy 174.709582 -279.117806)
			(xy 174.686594 -279.110822) (xy 174.642771 -279.091133) (xy 174.60226 -279.065308) (xy 174.565912 -279.033891)
			(xy 174.534495 -278.997544) (xy 174.50867 -278.957033) (xy 174.48898 -278.913211) (xy 174.481998 -278.890222)
			(xy 174.480207 -278.884456) (xy 174.474299 -278.873931) (xy 174.470314 -278.869394) (xy 174.439473 -278.835689)
			(xy 174.383564 -278.763426) (xy 174.334686 -278.686235) (xy 174.293269 -278.604795) (xy 174.259681 -278.519827)
			(xy 174.234217 -278.432082) (xy 174.217103 -278.342333) (xy 174.208489 -278.251375) (xy 174.207932 -278.205692)
			(xy 174.207932 -278.165814) (xy 174.207472 -278.156278) (xy 174.200409 -278.138553) (xy 174.187393 -278.124604)
			(xy 174.178976 -278.120094) (xy 174.08271 -278.07412) (xy 174.053754 -278.077676) (xy 174.042324 -278.087074)
			(xy 174.021776 -278.103033) (xy 173.976379 -278.128445) (xy 173.927334 -278.145802) (xy 173.876059 -278.154603)
			(xy 173.850046 -278.155146) (xy 173.824783 -278.154657) (xy 173.774944 -278.146347) (xy 173.727153 -278.129947)
			(xy 173.682714 -278.105903) (xy 173.642839 -278.074873) (xy 173.608615 -278.037702) (xy 173.580978 -277.995404)
			(xy 173.56068 -277.949134) (xy 173.548275 -277.900154) (xy 173.544102 -277.8498) (xy 173.548275 -277.799446)
			(xy 173.56068 -277.750466) (xy 173.580978 -277.704196) (xy 173.608615 -277.661898) (xy 173.642839 -277.624727)
			(xy 173.682714 -277.593697) (xy 173.727153 -277.569653) (xy 173.774944 -277.553253) (xy 173.824783 -277.544943)
			(xy 173.850046 -277.54453) (xy 173.876059 -277.545057) (xy 173.927332 -277.55387) (xy 173.976374 -277.571236)
			(xy 174.021769 -277.596651) (xy 174.042324 -277.612602) (xy 174.053754 -277.622) (xy 174.08271 -277.625556)
			(xy 174.178976 -277.579582) (xy 174.187441 -277.575133) (xy 174.200504 -277.561189) (xy 174.207521 -277.543416)
			(xy 174.207932 -277.533862) (xy 174.207932 -275.817838) (xy 174.207541 -275.808344) (xy 174.200656 -275.790649)
			(xy 174.18784 -275.776639) (xy 174.179484 -275.772118) (xy 174.17923 -275.772118) (xy 174.155738 -275.760075)
			(xy 174.112583 -275.729677) (xy 174.074801 -275.692812) (xy 174.043352 -275.650416) (xy 174.019034 -275.603564)
			(xy 174.002463 -275.553445) (xy 173.99406 -275.501331) (xy 173.993556 -275.474938) (xy 173.993556 -274.524724)
			(xy 173.993598 -274.51537) (xy 173.994613 -274.496689) (xy 173.995588 -274.487386) (xy 173.996858 -274.475956)
			(xy 173.989492 -274.454112) (xy 173.925484 -274.389596) (xy 173.917054 -274.381976) (xy 173.895687 -274.374331)
			(xy 173.884336 -274.374864) (xy 173.884082 -274.374864) (xy 173.8503 -274.376896) (xy 173.849792 -274.376896)
			(xy 173.824094 -274.376376) (xy 173.773334 -274.368308) (xy 173.72446 -274.352402) (xy 173.678674 -274.329049)
			(xy 173.637103 -274.298825) (xy 173.600768 -274.262473) (xy 173.570565 -274.220886) (xy 173.547235 -274.175089)
			(xy 173.531354 -274.126207) (xy 173.523311 -274.075443) (xy 173.522894 -274.049744) (xy 173.523369 -274.024033)
			(xy 173.531408 -273.973244) (xy 173.547294 -273.924338) (xy 173.570636 -273.87852) (xy 173.60086 -273.836919)
			(xy 173.63722 -273.800559) (xy 173.678822 -273.770335) (xy 173.72464 -273.746993) (xy 173.773546 -273.731107)
			(xy 173.824335 -273.723069) (xy 173.850046 -273.722592) (xy 173.876242 -273.723117) (xy 173.927961 -273.731499)
			(xy 173.977674 -273.748039) (xy 174.024105 -273.772312) (xy 174.045372 -273.787616) (xy 174.057056 -273.796252)
			(xy 174.085504 -273.798538) (xy 174.179992 -273.751294) (xy 174.188224 -273.746739) (xy 174.200834 -273.732794)
			(xy 174.207544 -273.715231) (xy 174.207932 -273.705828) (xy 174.207932 -273.4437) (xy 174.207495 -273.434315)
			(xy 174.200743 -273.4168) (xy 174.188169 -273.402861) (xy 174.179992 -273.398234) (xy 174.098458 -273.35734)
			(xy 174.089891 -273.3535) (xy 174.071225 -273.351653) (xy 174.053145 -273.356649) (xy 174.045372 -273.361912)
			(xy 174.024068 -273.377155) (xy 173.977631 -273.401391) (xy 173.927932 -273.41794) (xy 173.876236 -273.426382)
			(xy 173.850046 -273.426936) (xy 173.824335 -273.426461) (xy 173.773546 -273.418424) (xy 173.724639 -273.402539)
			(xy 173.678819 -273.379199) (xy 173.637216 -273.348977) (xy 173.600853 -273.312619) (xy 173.570626 -273.27102)
			(xy 173.547279 -273.225204) (xy 173.531387 -273.176299) (xy 173.523342 -273.125511) (xy 173.523342 -273.074089)
			(xy 173.531387 -273.023301) (xy 173.547279 -272.974396) (xy 173.570626 -272.92858) (xy 173.600853 -272.886981)
			(xy 173.637216 -272.850623) (xy 173.678819 -272.820401) (xy 173.724639 -272.797061) (xy 173.773546 -272.781176)
			(xy 173.824335 -272.773139) (xy 173.850046 -272.772632) (xy 173.876242 -272.773157) (xy 173.92796 -272.78154)
			(xy 173.977672 -272.798081) (xy 174.024101 -272.822357) (xy 174.045372 -272.837656) (xy 174.057056 -272.846292)
			(xy 174.085504 -272.848578) (xy 174.179992 -272.801334) (xy 174.188228 -272.79678) (xy 174.200849 -272.782838)
			(xy 174.207572 -272.765273) (xy 174.207932 -272.755868) (xy 174.207932 -271.851374) (xy 174.20781 -271.846685)
			(xy 174.206019 -271.837479) (xy 174.204376 -271.833086) (xy 174.188152 -271.789821) (xy 174.162838 -271.700948)
			(xy 174.145843 -271.610116) (xy 174.137315 -271.518102) (xy 174.136812 -271.471898) (xy 174.136812 -266.15644)
			(xy 174.136715 -266.152295) (xy 174.135307 -266.144125) (xy 174.134018 -266.140184) (xy 146.778472 -185.32094)
			(xy 146.768312 -185.315098) (xy 146.70405 -185.291984) (xy 146.703542 -185.291984) (xy 146.69135 -185.287412)
			(xy 146.686342 -185.285623) (xy 146.675839 -185.283967) (xy 146.670522 -185.28411) (xy 146.663918 -185.284872)
			(xy 146.654774 -185.286396) (xy 146.646392 -185.29173) (xy 146.62364 -185.305325) (xy 146.575179 -185.326784)
			(xy 146.524213 -185.341325) (xy 146.471724 -185.348668) (xy 146.445224 -185.349134) (xy 146.417971 -185.34865)
			(xy 146.364019 -185.340896) (xy 146.31172 -185.325543) (xy 146.262138 -185.302904) (xy 146.216283 -185.273439)
			(xy 146.175088 -185.237748) (xy 146.139391 -185.196557) (xy 146.10992 -185.150706) (xy 146.087274 -185.101127)
			(xy 146.071914 -185.04883) (xy 146.064154 -184.994879) (xy 146.063716 -184.967626) (xy 146.064217 -184.93948)
			(xy 146.072486 -184.883797) (xy 146.088848 -184.829935) (xy 146.112947 -184.779062) (xy 146.144261 -184.732282)
			(xy 146.18211 -184.690613) (xy 146.225671 -184.654957) (xy 146.273999 -184.626091) (xy 146.326044 -184.604639)
			(xy 146.380677 -184.591069) (xy 146.408648 -184.587896) (xy 146.417792 -184.587134) (xy 146.42592 -184.58307)
			(xy 146.43188 -184.5799) (xy 146.442044 -184.571024) (xy 146.445986 -184.565544) (xy 146.461226 -184.542176)
			(xy 146.461226 -184.541668) (xy 146.48307 -184.507886) (xy 146.488918 -184.497927) (xy 146.491848 -184.475042)
			(xy 146.488658 -184.463944) (xy 139.23518 -163.034218) (xy 139.225019 -163.003416) (xy 139.208242 -162.940754)
			(xy 139.201652 -162.908996) (xy 138.63701 -160.070292) (xy 138.630159 -160.034234) (xy 138.62113 -159.961389)
			(xy 138.618976 -159.92475) (xy 138.453876 -156.558742) (xy 138.453114 -156.552646) (xy 138.195304 -155.07589)
			(xy 138.189141 -155.038458) (xy 138.181892 -154.962935) (xy 138.180826 -154.925014) (xy 138.165586 -154.1272)
			(xy 138.16506 -154.120961) (xy 138.161331 -154.109012) (xy 138.15822 -154.103578) (xy 138.154664 -154.097736)
			(xy 138.148822 -154.092148) (xy 138.145012 -154.089354) (xy 138.14044 -154.086052) (xy 138.139932 -154.085544)
			(xy 138.117064 -154.067378) (xy 138.076602 -154.025267) (xy 138.043036 -153.977477) (xy 138.017152 -153.925126)
			(xy 137.999557 -153.86944) (xy 137.990661 -153.811722) (xy 137.990072 -153.782522) (xy 137.990605 -153.754028)
			(xy 137.999082 -153.697675) (xy 138.015836 -153.643205) (xy 138.040496 -153.591829) (xy 138.072514 -153.544687)
			(xy 138.111179 -153.502823) (xy 138.133074 -153.48458) (xy 138.135106 -153.482802) (xy 138.14171 -153.476198)
			(xy 138.145012 -153.470864) (xy 138.148545 -153.464574) (xy 138.15228 -153.450646) (xy 138.152378 -153.443432)
			(xy 138.11758 -151.630126) (xy 138.057128 -148.482304) (xy 138.057128 -148.48078) (xy 138.02995 -147.927568)
			(xy 138.02487 -147.917916) (xy 138.011354 -147.890563) (xy 137.992221 -147.832632) (xy 137.982524 -147.772398)
			(xy 137.981944 -147.741894) (xy 137.981944 -147.741386) (xy 137.982345 -147.715943) (xy 137.989062 -147.665503)
			(xy 138.002415 -147.616401) (xy 138.011916 -147.592796) (xy 138.01344 -147.58924) (xy 137.918444 -145.65249)
			(xy 137.918125 -145.648118) (xy 137.916207 -145.639564) (xy 137.914634 -145.635472) (xy 136.443466 -142.084044)
			(xy 136.439548 -142.075726) (xy 136.426923 -142.062378) (xy 136.410409 -142.054325) (xy 136.401302 -142.053056)
			(xy 136.297924 -142.04315) (xy 136.27227 -142.055342) (xy 136.269476 -142.059914) (xy 136.259407 -142.075663)
			(xy 136.23663 -142.105306) (xy 136.22401 -142.119096) (xy 136.216898 -142.126716) (xy 136.213596 -142.135352)
			(xy 136.212055 -142.1397) (xy 136.210399 -142.148774) (xy 136.210294 -142.153386) (xy 136.210294 -142.222982)
			(xy 136.210356 -142.227255) (xy 136.211766 -142.235682) (xy 136.213088 -142.239746) (xy 136.214932 -142.244637)
			(xy 136.220307 -142.253599) (xy 136.223756 -142.257526) (xy 136.22401 -142.25778) (xy 136.243276 -142.279107)
			(xy 136.275833 -142.32647) (xy 136.300917 -142.37818) (xy 136.31796 -142.433068) (xy 136.326577 -142.489891)
			(xy 136.326573 -142.547364) (xy 136.317948 -142.604186) (xy 136.300897 -142.659072) (xy 136.275805 -142.710778)
			(xy 136.243242 -142.758136) (xy 136.22401 -142.779496) (xy 136.216898 -142.787116) (xy 136.213596 -142.795752)
			(xy 136.212055 -142.8001) (xy 136.210399 -142.809174) (xy 136.210294 -142.813786) (xy 136.210294 -142.883382)
			(xy 136.210356 -142.887655) (xy 136.211766 -142.896082) (xy 136.213088 -142.900146) (xy 136.214932 -142.905037)
			(xy 136.220307 -142.913999) (xy 136.223756 -142.917926) (xy 136.22401 -142.91818) (xy 136.243283 -142.939506)
			(xy 136.275853 -142.986868) (xy 136.300951 -143.038579) (xy 136.318008 -143.09347) (xy 136.326639 -143.150298)
			(xy 136.327134 -143.179038) (xy 136.326584 -143.208228) (xy 136.317702 -143.265928) (xy 136.300136 -143.321602)
			(xy 136.274296 -143.373951) (xy 136.240784 -143.421754) (xy 136.200383 -143.463895) (xy 136.177528 -143.48206)
			(xy 136.176004 -143.48333) (xy 136.169654 -143.48968) (xy 136.166873 -143.492582) (xy 136.162159 -143.499093)
			(xy 136.160256 -143.502634) (xy 136.150858 -143.521176) (xy 136.148064 -143.526764) (xy 136.14527 -143.538194)
			(xy 136.14527 -143.601186) (xy 136.145441 -143.607195) (xy 136.148271 -143.618874) (xy 136.150858 -143.6243)
			(xy 136.160256 -143.642842) (xy 136.162136 -143.646397) (xy 136.166855 -143.652908) (xy 136.169654 -143.655796)
			(xy 136.176004 -143.662146) (xy 136.177528 -143.663416) (xy 136.200359 -143.681607) (xy 136.240751 -143.72375)
			(xy 136.274258 -143.77155) (xy 136.300099 -143.823892) (xy 136.317671 -143.879559) (xy 136.326566 -143.937251)
			(xy 136.327134 -143.966438) (xy 136.326648 -143.993689) (xy 136.318892 -144.047637) (xy 136.303537 -144.099932)
			(xy 136.280895 -144.149509) (xy 136.251429 -144.195359) (xy 136.215738 -144.23655) (xy 136.174547 -144.272241)
			(xy 136.128697 -144.301707) (xy 136.07912 -144.324349) (xy 136.026825 -144.339704) (xy 135.972877 -144.34746)
			(xy 135.918375 -144.34746) (xy 135.864427 -144.339704) (xy 135.812132 -144.324349) (xy 135.762555 -144.301707)
			(xy 135.716705 -144.272241) (xy 135.675514 -144.23655) (xy 135.639823 -144.195359) (xy 135.610357 -144.149509)
			(xy 135.587715 -144.099932) (xy 135.57236 -144.047637) (xy 135.564604 -143.993689) (xy 135.564118 -143.966438)
			(xy 135.563864 -143.966438) (xy 135.564408 -143.937354) (xy 135.573227 -143.879858) (xy 135.590667 -143.824365)
			(xy 135.616324 -143.772161) (xy 135.649605 -143.724453) (xy 135.689738 -143.682347) (xy 135.712454 -143.664178)
			(xy 135.715248 -143.662146) (xy 135.721598 -143.655796) (xy 135.724385 -143.652898) (xy 135.729111 -143.646393)
			(xy 135.730996 -143.642842) (xy 135.740394 -143.6243) (xy 135.743188 -143.618712) (xy 135.745982 -143.607282)
			(xy 135.745982 -143.538194) (xy 135.743188 -143.526764) (xy 135.740394 -143.521176) (xy 135.730996 -143.502634)
			(xy 135.729116 -143.499079) (xy 135.724398 -143.492566) (xy 135.721598 -143.48968) (xy 135.715248 -143.48333)
			(xy 135.713724 -143.48206) (xy 135.690891 -143.463869) (xy 135.650495 -143.421726) (xy 135.616983 -143.373927)
			(xy 135.591136 -143.321585) (xy 135.573555 -143.265919) (xy 135.56465 -143.208226) (xy 135.564118 -143.179038)
			(xy 135.564636 -143.150298) (xy 135.573254 -143.093468) (xy 135.590301 -143.038573) (xy 135.61539 -142.986858)
			(xy 135.647954 -142.939492) (xy 135.667242 -142.91818) (xy 135.667496 -142.917926) (xy 135.670954 -142.914005)
			(xy 135.676338 -142.905045) (xy 135.678164 -142.900146) (xy 135.679464 -142.896077) (xy 135.680872 -142.887653)
			(xy 135.680958 -142.883382) (xy 135.680958 -142.813786) (xy 135.680857 -142.809174) (xy 135.679195 -142.800101)
			(xy 135.677656 -142.795752) (xy 135.674354 -142.787116) (xy 135.667242 -142.779496) (xy 135.647968 -142.75817)
			(xy 135.615395 -142.710807) (xy 135.590297 -142.659093) (xy 135.573241 -142.6042) (xy 135.564613 -142.547369)
			(xy 135.564609 -142.489887) (xy 135.573228 -142.433054) (xy 135.590276 -142.378158) (xy 135.615367 -142.326441)
			(xy 135.647933 -142.279074) (xy 135.667242 -142.25778) (xy 135.667496 -142.257526) (xy 135.670954 -142.253605)
			(xy 135.676338 -142.244645) (xy 135.678164 -142.239746) (xy 135.679464 -142.235677) (xy 135.680872 -142.227253)
			(xy 135.680958 -142.222982) (xy 135.680958 -142.153386) (xy 135.680857 -142.148774) (xy 135.679195 -142.139701)
			(xy 135.677656 -142.135352) (xy 135.674354 -142.126716) (xy 135.667242 -142.119096) (xy 135.647968 -142.09777)
			(xy 135.615395 -142.050407) (xy 135.590297 -141.998693) (xy 135.573241 -141.9438) (xy 135.564613 -141.886969)
			(xy 135.564609 -141.829487) (xy 135.573228 -141.772654) (xy 135.590276 -141.717758) (xy 135.615367 -141.666041)
			(xy 135.647933 -141.618674) (xy 135.667242 -141.59738) (xy 135.667496 -141.597126) (xy 135.670954 -141.593205)
			(xy 135.676338 -141.584245) (xy 135.678164 -141.579346) (xy 135.679464 -141.575277) (xy 135.680872 -141.566853)
			(xy 135.680958 -141.562582) (xy 135.680958 -141.492986) (xy 135.680857 -141.488374) (xy 135.679195 -141.479301)
			(xy 135.677656 -141.474952) (xy 135.674354 -141.466316) (xy 135.667242 -141.458696) (xy 135.647968 -141.43737)
			(xy 135.615395 -141.390007) (xy 135.590297 -141.338293) (xy 135.573241 -141.2834) (xy 135.564613 -141.226569)
			(xy 135.564609 -141.169087) (xy 135.573228 -141.112254) (xy 135.590276 -141.057358) (xy 135.615367 -141.005641)
			(xy 135.647933 -140.958274) (xy 135.667242 -140.93698) (xy 135.667496 -140.936726) (xy 135.670954 -140.932805)
			(xy 135.676338 -140.923845) (xy 135.678164 -140.918946) (xy 135.679464 -140.914877) (xy 135.680872 -140.906453)
			(xy 135.680958 -140.902182) (xy 135.680958 -140.832586) (xy 135.680857 -140.827974) (xy 135.679195 -140.818901)
			(xy 135.677656 -140.814552) (xy 135.674354 -140.805916) (xy 135.667242 -140.798296) (xy 135.647979 -140.776984)
			(xy 135.615422 -140.729653) (xy 135.59033 -140.677977) (xy 135.573269 -140.623122) (xy 135.564625 -140.56633)
			(xy 135.564594 -140.508884) (xy 135.573176 -140.452082) (xy 135.590177 -140.397209) (xy 135.615214 -140.345506)
			(xy 135.647719 -140.29814) (xy 135.666988 -140.276834) (xy 135.667496 -140.276326) (xy 135.674354 -140.268706)
			(xy 135.679688 -140.239496) (xy 135.442706 -139.667996) (xy 135.424672 -139.652248) (xy 135.412988 -139.649454)
			(xy 135.384117 -139.641557) (xy 135.329092 -139.618013) (xy 135.27842 -139.586162) (xy 135.255508 -139.566904)
			(xy 135.255 -139.566904) (xy 135.255 -139.56665) (xy 135.247915 -139.56106) (xy 135.230997 -139.554812)
			(xy 135.22198 -139.554458) (xy 135.154924 -139.554458) (xy 135.145905 -139.554812) (xy 135.128981 -139.56105)
			(xy 135.121904 -139.56665) (xy 135.12165 -139.566904) (xy 135.100717 -139.584545) (xy 135.054749 -139.614269)
			(xy 135.005003 -139.637115) (xy 134.952501 -139.652611) (xy 134.898323 -139.66044) (xy 134.843581 -139.66044)
			(xy 134.789403 -139.652611) (xy 134.736901 -139.637115) (xy 134.687155 -139.614269) (xy 134.641187 -139.584545)
			(xy 134.620254 -139.566904) (xy 134.62 -139.566904) (xy 134.62 -139.56665) (xy 134.612915 -139.56106)
			(xy 134.595997 -139.554812) (xy 134.58698 -139.554458) (xy 134.519924 -139.554458) (xy 134.510905 -139.554812)
			(xy 134.493981 -139.56105) (xy 134.486904 -139.56665) (xy 134.48665 -139.566904) (xy 134.465717 -139.584545)
			(xy 134.419749 -139.614269) (xy 134.370003 -139.637115) (xy 134.317501 -139.652611) (xy 134.263323 -139.66044)
			(xy 134.208581 -139.66044) (xy 134.154403 -139.652611) (xy 134.101901 -139.637115) (xy 134.052155 -139.614269)
			(xy 134.006187 -139.584545) (xy 133.985254 -139.566904) (xy 133.985 -139.566904) (xy 133.985 -139.56665)
			(xy 133.977915 -139.56106) (xy 133.960997 -139.554812) (xy 133.95198 -139.554458) (xy 133.884924 -139.554458)
			(xy 133.875905 -139.554812) (xy 133.858981 -139.56105) (xy 133.851904 -139.56665) (xy 133.85165 -139.566904)
			(xy 133.830718 -139.584543) (xy 133.78475 -139.614263) (xy 133.735003 -139.637099) (xy 133.6825 -139.652582)
			(xy 133.628321 -139.660394) (xy 133.600952 -139.660884) (xy 133.573704 -139.660394) (xy 133.519762 -139.652632)
			(xy 133.467475 -139.637273) (xy 133.417905 -139.614629) (xy 133.372063 -139.585161) (xy 133.33088 -139.549469)
			(xy 133.295196 -139.50828) (xy 133.265737 -139.462431) (xy 133.243102 -139.412858) (xy 133.227752 -139.360567)
			(xy 133.22 -139.306624) (xy 133.219444 -139.279376) (xy 133.219909 -139.252747) (xy 133.227319 -139.200006)
			(xy 133.241992 -139.148809) (xy 133.263642 -139.10015) (xy 133.29185 -139.054974) (xy 133.308598 -139.034266)
			(xy 133.316472 -139.024868) (xy 133.32206 -139.0015) (xy 133.30047 -138.910568) (xy 133.297105 -138.899196)
			(xy 133.281879 -138.881049) (xy 133.27126 -138.87577) (xy 133.246043 -138.864285) (xy 133.198941 -138.835103)
			(xy 133.156557 -138.799412) (xy 133.119785 -138.757963) (xy 133.089397 -138.71163) (xy 133.066033 -138.661387)
			(xy 133.050186 -138.608292) (xy 133.042188 -138.553463) (xy 133.041644 -138.525758) (xy 133.042119 -138.498389)
			(xy 133.049949 -138.444215) (xy 133.065442 -138.391715) (xy 133.08828 -138.34197) (xy 133.117994 -138.295999)
			(xy 133.135624 -138.27506) (xy 133.135624 -138.274806) (xy 133.135878 -138.274806) (xy 133.141466 -138.26772)
			(xy 133.147713 -138.250803) (xy 133.14807 -138.241786) (xy 133.14807 -138.17473) (xy 133.147717 -138.16571)
			(xy 133.141484 -138.148783) (xy 133.135878 -138.14171) (xy 133.135624 -138.141456) (xy 133.117986 -138.120523)
			(xy 133.088268 -138.074556) (xy 133.065428 -138.024812) (xy 133.049938 -137.972312) (xy 133.042114 -137.918137)
			(xy 133.042119 -137.8634) (xy 133.049951 -137.809226) (xy 133.065451 -137.756729) (xy 133.088298 -137.706988)
			(xy 133.118025 -137.661026) (xy 133.135624 -137.64006) (xy 133.135624 -137.639806) (xy 133.135878 -137.639806)
			(xy 133.141466 -137.63272) (xy 133.147713 -137.615803) (xy 133.14807 -137.606786) (xy 133.14807 -137.53973)
			(xy 133.147717 -137.53071) (xy 133.141484 -137.513783) (xy 133.135878 -137.50671) (xy 133.135624 -137.506456)
			(xy 133.117986 -137.485523) (xy 133.088268 -137.439556) (xy 133.065428 -137.389812) (xy 133.049938 -137.337312)
			(xy 133.042114 -137.283137) (xy 133.042119 -137.2284) (xy 133.049951 -137.174226) (xy 133.065451 -137.121729)
			(xy 133.088298 -137.071988) (xy 133.118025 -137.026026) (xy 133.135624 -137.00506) (xy 133.135624 -137.004806)
			(xy 133.135878 -137.004806) (xy 133.141466 -136.99772) (xy 133.147713 -136.980803) (xy 133.14807 -136.971786)
			(xy 133.14807 -136.90473) (xy 133.147717 -136.89571) (xy 133.141484 -136.878783) (xy 133.135878 -136.87171)
			(xy 133.135624 -136.871456) (xy 133.117983 -136.850524) (xy 133.088261 -136.804557) (xy 133.065422 -136.75481)
			(xy 133.049937 -136.702307) (xy 133.042124 -136.648128) (xy 133.041644 -136.620758) (xy 133.04213 -136.593507)
			(xy 133.049886 -136.539559) (xy 133.065241 -136.487264) (xy 133.087883 -136.437687) (xy 133.117349 -136.391837)
			(xy 133.15304 -136.350646) (xy 133.194231 -136.314955) (xy 133.240081 -136.285489) (xy 133.289658 -136.262847)
			(xy 133.341953 -136.247492) (xy 133.395901 -136.239736) (xy 133.450403 -136.239736) (xy 133.504351 -136.247492)
			(xy 133.556646 -136.262847) (xy 133.606223 -136.285489) (xy 133.652073 -136.314955) (xy 133.693264 -136.350646)
			(xy 133.728955 -136.391837) (xy 133.758421 -136.437687) (xy 133.781063 -136.487264) (xy 133.796418 -136.539559)
			(xy 133.804174 -136.593507) (xy 133.80466 -136.620758) (xy 133.804184 -136.648126) (xy 133.796352 -136.7023)
			(xy 133.780857 -136.754798) (xy 133.758018 -136.804542) (xy 133.728303 -136.850511) (xy 133.71068 -136.871456)
			(xy 133.71068 -136.87171) (xy 133.710426 -136.87171) (xy 133.70484 -136.878796) (xy 133.698598 -136.895714)
			(xy 133.698234 -136.90473) (xy 133.698234 -136.971786) (xy 133.69859 -136.980804) (xy 133.704827 -136.997728)
			(xy 133.710426 -137.004806) (xy 133.71068 -137.00506) (xy 133.728323 -137.025993) (xy 133.758054 -137.071962)
			(xy 133.780904 -137.12171) (xy 133.796406 -137.174214) (xy 133.804239 -137.228396) (xy 133.804244 -137.283141)
			(xy 133.796419 -137.337324) (xy 133.780927 -137.389831) (xy 133.758084 -137.439583) (xy 133.728362 -137.485556)
			(xy 133.71068 -137.506456) (xy 133.71068 -137.50671) (xy 133.710426 -137.50671) (xy 133.70484 -137.513796)
			(xy 133.698598 -137.530714) (xy 133.698234 -137.53973) (xy 133.698234 -137.606786) (xy 133.69859 -137.615804)
			(xy 133.704827 -137.632728) (xy 133.710426 -137.639806) (xy 133.71068 -137.64006) (xy 133.728323 -137.660993)
			(xy 133.758054 -137.706962) (xy 133.780904 -137.75671) (xy 133.796406 -137.809214) (xy 133.804239 -137.863396)
			(xy 133.804244 -137.918141) (xy 133.796419 -137.972324) (xy 133.780927 -138.024831) (xy 133.758084 -138.074583)
			(xy 133.728362 -138.120556) (xy 133.71068 -138.141456) (xy 133.71068 -138.14171) (xy 133.710426 -138.14171)
			(xy 133.70484 -138.148796) (xy 133.698598 -138.165714) (xy 133.698234 -138.17473) (xy 133.698234 -138.241786)
			(xy 133.69859 -138.250804) (xy 133.704827 -138.267728) (xy 133.710426 -138.274806) (xy 133.71068 -138.27506)
			(xy 133.728319 -138.295992) (xy 133.75804 -138.34196) (xy 133.780876 -138.391707) (xy 133.796359 -138.44421)
			(xy 133.80417 -138.498389) (xy 133.80466 -138.525758) (xy 133.8042 -138.552389) (xy 133.796798 -138.605134)
			(xy 133.782132 -138.656336) (xy 133.760488 -138.705002) (xy 133.732286 -138.750184) (xy 133.715506 -138.770868)
			(xy 133.707632 -138.780266) (xy 133.702044 -138.803634) (xy 133.723634 -138.894566) (xy 133.727005 -138.905933)
			(xy 133.742235 -138.924068) (xy 133.752844 -138.929364) (xy 133.779468 -138.941613) (xy 133.828958 -138.972995)
			(xy 133.851396 -138.991848) (xy 133.851904 -138.991848) (xy 133.851904 -138.992102) (xy 133.858991 -138.997687)
			(xy 133.875908 -139.003927) (xy 133.884924 -139.004294) (xy 133.95198 -139.004294) (xy 133.960998 -139.003938)
			(xy 133.977918 -138.997695) (xy 133.985 -138.992102) (xy 133.985254 -138.991848) (xy 134.006187 -138.974207)
			(xy 134.052155 -138.944483) (xy 134.101901 -138.921637) (xy 134.154403 -138.906141) (xy 134.208581 -138.898312)
			(xy 134.263323 -138.898312) (xy 134.317501 -138.906141) (xy 134.370003 -138.921637) (xy 134.419749 -138.944483)
			(xy 134.465717 -138.974207) (xy 134.48665 -138.991848) (xy 134.486904 -138.991848) (xy 134.486904 -138.992102)
			(xy 134.493991 -138.997687) (xy 134.510908 -139.003927) (xy 134.519924 -139.004294) (xy 134.58698 -139.004294)
			(xy 134.595998 -139.003938) (xy 134.612918 -138.997695) (xy 134.62 -138.992102) (xy 134.620254 -138.991848)
			(xy 134.641187 -138.974207) (xy 134.687155 -138.944483) (xy 134.736901 -138.921637) (xy 134.789403 -138.906141)
			(xy 134.843581 -138.898312) (xy 134.898323 -138.898312) (xy 134.952501 -138.906141) (xy 135.005003 -138.921637)
			(xy 135.054749 -138.944483) (xy 135.100717 -138.974207) (xy 135.12165 -138.991848) (xy 135.121904 -138.991848)
			(xy 135.121904 -138.992102) (xy 135.128991 -138.997687) (xy 135.145908 -139.003927) (xy 135.154924 -139.004294)
			(xy 135.22198 -139.004294) (xy 135.230998 -139.003938) (xy 135.247918 -138.997695) (xy 135.255 -138.992102)
			(xy 135.255254 -138.991848) (xy 135.262719 -138.985401) (xy 135.27822 -138.973202) (xy 135.286242 -138.967464)
			(xy 135.295881 -138.959845) (xy 135.307182 -138.938075) (xy 135.307832 -138.925808) (xy 135.307832 -132.382768)
			(xy 135.307247 -132.371542) (xy 135.297713 -132.351213) (xy 135.280459 -132.336845) (xy 135.269732 -132.333492)
			(xy 135.24283 -132.325998) (xy 135.191405 -132.304224) (xy 135.143703 -132.275186) (xy 135.100744 -132.239506)
			(xy 135.063444 -132.197944) (xy 135.032601 -132.15139) (xy 135.008873 -132.100836) (xy 134.992768 -132.047365)
			(xy 134.984628 -131.992116) (xy 134.984629 -131.936272) (xy 134.99277 -131.881024) (xy 135.008877 -131.827552)
			(xy 135.032607 -131.777) (xy 135.063451 -131.730446) (xy 135.100752 -131.688886) (xy 135.143713 -131.653207)
			(xy 135.191416 -131.624171) (xy 135.242841 -131.602398) (xy 135.269732 -131.59486) (xy 135.280453 -131.591489)
			(xy 135.297722 -131.577149) (xy 135.307217 -131.55681) (xy 135.307832 -131.545584) (xy 135.307832 -130.71475)
			(xy 135.30847 -130.66577) (xy 135.318144 -130.568288) (xy 135.337327 -130.472224) (xy 135.351012 -130.42519)
			(xy 141.234668 -111.030258) (xy 141.241868 -111.006867) (xy 141.25826 -110.960746) (xy 141.267434 -110.938056)
			(xy 143.388334 -105.817416) (xy 143.407656 -105.772399) (xy 143.453879 -105.686019) (xy 143.508343 -105.604584)
			(xy 143.570525 -105.528878) (xy 143.604742 -105.49382) (xy 144.071086 -105.027476) (xy 144.074134 -105.022396)
			(xy 144.086326 -105.002838) (xy 144.115741 -104.958082) (xy 144.18282 -104.874585) (xy 144.220184 -104.836214)
			(xy 149.151594 -99.904804) (xy 149.189986 -99.867465) (xy 149.273481 -99.800388) (xy 149.318218 -99.770946)
			(xy 149.355158 -99.747935) (xy 149.432358 -99.707742) (xy 149.472396 -99.690682) (xy 151.874982 -98.695764)
			(xy 151.911531 -98.681061) (xy 151.986503 -98.656836) (xy 152.063164 -98.638655) (xy 152.141029 -98.626633)
			(xy 152.18029 -98.623374) (xy 152.18537 -98.622612) (xy 152.227643 -98.615734) (xy 152.312978 -98.60836)
			(xy 152.355804 -98.60788) (xy 153.143204 -98.60788) (xy 153.152926 -98.607398) (xy 153.17095 -98.600088)
			(xy 153.178256 -98.593656) (xy 153.209124 -98.564737) (xy 153.274974 -98.51164) (xy 153.345084 -98.464307)
			(xy 153.418949 -98.423081) (xy 153.496039 -98.388256) (xy 153.575801 -98.360082) (xy 153.657661 -98.338763)
			(xy 153.741033 -98.32445) (xy 153.825317 -98.317247) (xy 153.867612 -98.316796) (xy 153.914303 -98.317341)
			(xy 154.007274 -98.326075) (xy 154.099022 -98.343465) (xy 154.188741 -98.369359) (xy 154.275646 -98.40353)
			(xy 154.358974 -98.445677) (xy 154.437995 -98.495433) (xy 154.512018 -98.552361) (xy 154.580392 -98.615961)
			(xy 154.642518 -98.685677) (xy 154.697853 -98.760897) (xy 154.722322 -98.800666) (xy 154.724915 -98.804647)
			(xy 154.731303 -98.811679) (xy 154.735022 -98.814636) (xy 154.757645 -98.832821) (xy 154.797647 -98.874879)
			(xy 154.830815 -98.92251) (xy 154.856386 -98.974616) (xy 154.87377 -99.029994) (xy 154.882563 -99.087367)
			(xy 154.883104 -99.116388) (xy 154.883104 -99.11715) (xy 154.882604 -99.146515) (xy 154.873673 -99.204562)
			(xy 154.865324 -99.23272) (xy 154.863984 -99.237229) (xy 154.862838 -99.246563) (xy 154.863038 -99.251262)
			(xy 154.863921 -99.266995) (xy 154.864812 -99.298497) (xy 154.864816 -99.314254) (xy 154.864384 -99.356622)
			(xy 154.857201 -99.441053) (xy 154.842874 -99.524569) (xy 154.821507 -99.606566) (xy 154.793255 -99.686453)
			(xy 154.77617 -99.725226) (xy 154.772195 -99.735269) (xy 154.772177 -99.756848) (xy 154.77617 -99.766882)
			(xy 154.793216 -99.80567) (xy 154.821456 -99.885558) (xy 154.842824 -99.967553) (xy 154.857165 -100.051063)
			(xy 154.864376 -100.135488) (xy 154.864816 -100.177854) (xy 154.864817 -100.193802) (xy 154.863928 -100.225685)
			(xy 154.863038 -100.241608) (xy 154.862844 -100.246169) (xy 154.863861 -100.25524) (xy 154.86507 -100.259642)
			(xy 154.869896 -100.276152) (xy 154.869896 -100.27666) (xy 154.873414 -100.290004) (xy 154.878752 -100.317082)
			(xy 154.880564 -100.330762) (xy 154.881834 -100.342954) (xy 154.883358 -100.375466) (xy 154.882804 -100.404669)
			(xy 154.873903 -100.462392) (xy 154.856305 -100.518083) (xy 154.830421 -100.57044) (xy 154.796857 -100.618237)
			(xy 154.756397 -100.660358) (xy 154.733498 -100.678488) (xy 154.73299 -100.678996) (xy 154.727656 -100.682806)
			(xy 154.705381 -100.719851) (xy 154.655339 -100.790342) (xy 154.599382 -100.856236) (xy 154.53793 -100.917038)
			(xy 154.471446 -100.972292) (xy 154.400429 -101.021584) (xy 154.325411 -101.064543) (xy 154.246955 -101.100847)
			(xy 154.165652 -101.130222) (xy 154.082111 -101.15245) (xy 153.996959 -101.167362) (xy 153.910836 -101.174846)
			(xy 153.867612 -101.175312) (xy 153.825301 -101.174864) (xy 153.740984 -101.167695) (xy 153.657577 -101.153407)
			(xy 153.575681 -101.132102) (xy 153.495885 -101.103935) (xy 153.418763 -101.069108) (xy 153.344869 -101.027871)
			(xy 153.274735 -100.98052) (xy 153.208865 -100.927398) (xy 153.178002 -100.898452) (xy 153.170636 -100.89134)
			(xy 153.152856 -100.884228) (xy 152.88133 -100.884228) (xy 152.880314 -100.885244) (xy 152.862788 -100.905564)
			(xy 152.859946 -100.908872) (xy 152.855348 -100.916282) (xy 152.853644 -100.920296) (xy 152.85085 -100.927662)
			(xy 152.850342 -100.936806) (xy 152.850088 -100.944426) (xy 152.850088 -100.945442) (xy 152.848342 -100.969214)
			(xy 152.839683 -101.016088) (xy 152.832816 -101.038914) (xy 152.831476 -101.043423) (xy 152.830329 -101.052757)
			(xy 152.83053 -101.057456) (xy 152.831416 -101.073252) (xy 152.832306 -101.104881) (xy 152.832308 -101.120702)
			(xy 152.831874 -101.163069) (xy 152.824687 -101.247499) (xy 152.810356 -101.331013) (xy 152.788986 -101.413009)
			(xy 152.76073 -101.492894) (xy 152.743662 -101.531674) (xy 152.739692 -101.541715) (xy 152.739693 -101.563288)
			(xy 152.743662 -101.57333) (xy 152.760705 -101.612119) (xy 152.788939 -101.692008) (xy 152.8103 -101.774002)
			(xy 152.824636 -101.857512) (xy 152.831842 -101.941936) (xy 152.832308 -101.984302) (xy 152.832306 -102.000186)
			(xy 152.831418 -102.031942) (xy 152.83053 -102.047802) (xy 152.83036 -102.0525) (xy 152.831509 -102.061829)
			(xy 152.832816 -102.066344) (xy 152.836486 -102.078229) (xy 152.842459 -102.102379) (xy 152.844754 -102.114604)
			(xy 152.844754 -102.115112) (xy 152.846024 -102.122478) (xy 152.846024 -102.122986) (xy 152.849072 -102.146862)
			(xy 152.849072 -102.147116) (xy 152.849834 -102.154736) (xy 152.86228 -102.184708) (xy 152.867868 -102.191058)
			(xy 152.87879 -102.20325) (xy 152.879298 -102.203758) (xy 152.883108 -102.207568) (xy 153.14295 -102.207568)
			(xy 153.152648 -102.207138) (xy 153.170665 -102.199955) (xy 153.178002 -102.193598) (xy 153.208858 -102.164692)
			(xy 153.274684 -102.11162) (xy 153.344768 -102.064313) (xy 153.418607 -102.023112) (xy 153.49567 -101.988312)
			(xy 153.575404 -101.960164) (xy 153.657235 -101.938869) (xy 153.740575 -101.924582) (xy 153.824826 -101.917404)
			(xy 153.867104 -101.916992) (xy 153.867612 -101.916992) (xy 153.914312 -101.917537) (xy 154.007302 -101.926271)
			(xy 154.099068 -101.943661) (xy 154.188806 -101.969554) (xy 154.27573 -102.003725) (xy 154.359079 -102.045873)
			(xy 154.438122 -102.095629) (xy 154.512166 -102.152557) (xy 154.580564 -102.216159) (xy 154.642715 -102.285878)
			(xy 154.698075 -102.361102) (xy 154.722576 -102.400862) (xy 154.725094 -102.404842) (xy 154.731359 -102.411872)
			(xy 154.735022 -102.414832) (xy 154.757646 -102.433017) (xy 154.797647 -102.475075) (xy 154.830817 -102.522706)
			(xy 154.856388 -102.574812) (xy 154.873772 -102.63019) (xy 154.882566 -102.687563) (xy 154.883104 -102.716584)
			(xy 154.883104 -102.717092) (xy 154.8826 -102.746457) (xy 154.873664 -102.804501) (xy 154.865324 -102.832662)
			(xy 154.863979 -102.83717) (xy 154.862822 -102.846505) (xy 154.863038 -102.851204) (xy 154.863921 -102.866937)
			(xy 154.86481 -102.898439) (xy 154.864816 -102.914196) (xy 154.864382 -102.956564) (xy 154.857195 -103.040993)
			(xy 154.842865 -103.124508) (xy 154.821496 -103.206504) (xy 154.79324 -103.286389) (xy 154.77617 -103.325168)
			(xy 154.772204 -103.33521) (xy 154.772202 -103.356783) (xy 154.77617 -103.366824) (xy 154.793214 -103.405613)
			(xy 154.821451 -103.485501) (xy 154.842815 -103.567495) (xy 154.857153 -103.651005) (xy 154.86436 -103.73543)
			(xy 154.864816 -103.777796) (xy 154.864817 -103.793744) (xy 154.863926 -103.825627) (xy 154.863038 -103.84155)
			(xy 154.862848 -103.84611) (xy 154.863872 -103.85518) (xy 154.86507 -103.859584) (xy 154.869896 -103.876094)
			(xy 154.869896 -103.876602) (xy 154.873416 -103.889946) (xy 154.878758 -103.917023) (xy 154.880564 -103.930704)
			(xy 154.881834 -103.942896) (xy 154.883358 -103.975408) (xy 154.8828 -104.004609) (xy 154.873894 -104.062329)
			(xy 154.856292 -104.118016) (xy 154.830405 -104.170368) (xy 154.796838 -104.21816) (xy 154.756377 -104.260276)
			(xy 154.733498 -104.27843) (xy 154.73299 -104.278938) (xy 154.727656 -104.282748) (xy 154.705368 -104.319777)
			(xy 154.655304 -104.390233) (xy 154.599331 -104.456094) (xy 154.537869 -104.516864) (xy 154.47138 -104.572088)
			(xy 154.400361 -104.621352) (xy 154.325346 -104.664285) (xy 154.246897 -104.700567) (xy 154.165604 -104.729925)
			(xy 154.082074 -104.752139) (xy 153.996936 -104.767041) (xy 153.910828 -104.774521) (xy 153.867612 -104.775)
			(xy 153.867358 -104.775) (xy 153.823435 -104.774524) (xy 153.735928 -104.7668) (xy 153.64944 -104.751409)
			(xy 153.564641 -104.728468) (xy 153.48219 -104.698157) (xy 153.402724 -104.660709) (xy 153.326861 -104.616416)
			(xy 153.255189 -104.56562) (xy 153.221436 -104.53751) (xy 153.214203 -104.531839) (xy 153.196928 -104.525603)
			(xy 153.178564 -104.525879) (xy 153.169874 -104.528874) (xy 153.126039 -104.545632) (xy 153.035907 -104.571794)
			(xy 152.943714 -104.589367) (xy 152.850278 -104.598195) (xy 152.803352 -104.598724) (xy 152.320752 -104.598724)
			(xy 152.29205 -104.598216) (xy 152.281382 -104.597962) (xy 152.26157 -104.605836) (xy 152.230836 -104.638094)
			(xy 152.228296 -104.640634) (xy 152.221184 -104.660446) (xy 152.221692 -104.67086) (xy 152.222708 -104.720898)
			(xy 152.222274 -104.763266) (xy 152.215087 -104.847695) (xy 152.200757 -104.93121) (xy 152.179387 -105.013206)
			(xy 152.151131 -105.093091) (xy 152.134062 -105.13187) (xy 152.130091 -105.141911) (xy 152.130091 -105.163485)
			(xy 152.134062 -105.173526) (xy 152.151105 -105.212315) (xy 152.179339 -105.292204) (xy 152.200701 -105.374198)
			(xy 152.215037 -105.457708) (xy 152.222244 -105.542132) (xy 152.222708 -105.584498) (xy 152.222706 -105.600382)
			(xy 152.221818 -105.632138) (xy 152.22093 -105.647998) (xy 152.22076 -105.652696) (xy 152.221908 -105.662025)
			(xy 152.223216 -105.66654) (xy 152.230074 -105.691178) (xy 152.233319 -105.704919) (xy 152.238021 -105.73276)
			(xy 152.239472 -105.746804) (xy 152.240234 -105.755186) (xy 152.249632 -105.77703) (xy 152.249886 -105.777538)
			(xy 152.253188 -105.785158) (xy 152.268174 -105.802684) (xy 152.273254 -105.807764) (xy 153.143204 -105.807764)
			(xy 153.152926 -105.807281) (xy 153.170948 -105.799969) (xy 153.178256 -105.79354) (xy 153.209123 -105.764619)
			(xy 153.274972 -105.711517) (xy 153.34508 -105.664181) (xy 153.418944 -105.622951) (xy 153.496035 -105.588123)
			(xy 153.575797 -105.559947) (xy 153.657658 -105.538625) (xy 153.741031 -105.524311) (xy 153.825316 -105.517108)
			(xy 153.867612 -105.51668) (xy 153.914303 -105.517225) (xy 154.007275 -105.525959) (xy 154.099023 -105.543349)
			(xy 154.188742 -105.569242) (xy 154.275647 -105.603413) (xy 154.358976 -105.64556) (xy 154.437998 -105.695315)
			(xy 154.512021 -105.752242) (xy 154.580396 -105.815842) (xy 154.642523 -105.885558) (xy 154.697859 -105.960777)
			(xy 154.722322 -106.00055) (xy 154.72492 -106.004527) (xy 154.731314 -106.01155) (xy 154.735022 -106.01452)
			(xy 154.757646 -106.032705) (xy 154.797649 -106.074762) (xy 154.83082 -106.122393) (xy 154.856393 -106.174499)
			(xy 154.873779 -106.229877) (xy 154.882575 -106.28725) (xy 154.883104 -106.316272) (xy 154.883104 -106.317034)
			(xy 154.882605 -106.3464) (xy 154.873677 -106.404447) (xy 154.865324 -106.432604) (xy 154.863983 -106.437112)
			(xy 154.862833 -106.446447) (xy 154.863038 -106.451146) (xy 154.86392 -106.466879) (xy 154.864808 -106.498381)
			(xy 154.864816 -106.514138) (xy 154.86438 -106.556505) (xy 154.85719 -106.640934) (xy 154.842857 -106.724447)
			(xy 154.821484 -106.806442) (xy 154.793226 -106.886325) (xy 154.77617 -106.92511) (xy 154.772213 -106.935152)
			(xy 154.772227 -106.956717) (xy 154.77617 -106.966766) (xy 154.793213 -107.005555) (xy 154.821446 -107.085444)
			(xy 154.842807 -107.167438) (xy 154.857141 -107.250948) (xy 154.864345 -107.335373) (xy 154.864816 -107.377738)
			(xy 154.864818 -107.393686) (xy 154.863929 -107.425569) (xy 154.863038 -107.441492) (xy 154.862843 -107.446053)
			(xy 154.863857 -107.455125) (xy 154.86507 -107.459526) (xy 154.869896 -107.476036) (xy 154.869896 -107.476544)
			(xy 154.873415 -107.489888) (xy 154.878754 -107.516965) (xy 154.880564 -107.530646) (xy 154.881834 -107.542838)
			(xy 154.883358 -107.57535) (xy 154.882797 -107.60455) (xy 154.873886 -107.662266) (xy 154.856279 -107.717948)
			(xy 154.830388 -107.770295) (xy 154.796819 -107.818083) (xy 154.756357 -107.860194) (xy 154.733498 -107.878372)
			(xy 154.73299 -107.87888) (xy 154.727656 -107.88269) (xy 154.705382 -107.919736) (xy 154.65534 -107.990227)
			(xy 154.599383 -108.056122) (xy 154.537932 -108.116925) (xy 154.471448 -108.172181) (xy 154.400431 -108.221473)
			(xy 154.325412 -108.264433) (xy 154.246957 -108.300737) (xy 154.165653 -108.330114) (xy 154.082112 -108.352341)
			(xy 153.996959 -108.367253) (xy 153.910836 -108.374738) (xy 153.867612 -108.375196) (xy 153.823581 -108.374704)
			(xy 153.735863 -108.36692) (xy 153.649174 -108.351431) (xy 153.564188 -108.328355) (xy 153.481569 -108.297874)
			(xy 153.40196 -108.260225) (xy 153.325982 -108.215702) (xy 153.254227 -108.16465) (xy 153.22042 -108.136436)
			(xy 153.213159 -108.130811) (xy 153.195866 -108.124662) (xy 153.177516 -108.124992) (xy 153.168858 -108.128054)
			(xy 153.124824 -108.144946) (xy 153.034265 -108.171317) (xy 152.94162 -108.189015) (xy 152.847718 -108.197883)
			(xy 152.800558 -108.198412) (xy 152.317958 -108.198412) (xy 152.291542 -108.198158) (xy 152.28097 -108.198426)
			(xy 152.26142 -108.206428) (xy 152.253696 -108.213652) (xy 152.227026 -108.241338) (xy 152.220422 -108.249974)
			(xy 152.221438 -108.27004) (xy 152.222708 -108.319824) (xy 152.222708 -108.32084) (xy 152.222272 -108.363207)
			(xy 152.215082 -108.447636) (xy 152.200748 -108.531149) (xy 152.179375 -108.613143) (xy 152.151117 -108.693027)
			(xy 152.134062 -108.731812) (xy 152.130101 -108.741853) (xy 152.130116 -108.763419) (xy 152.134062 -108.773468)
			(xy 152.151103 -108.812257) (xy 152.179334 -108.892147) (xy 152.200693 -108.974141) (xy 152.215025 -109.057651)
			(xy 152.222228 -109.142075) (xy 152.222708 -109.18444) (xy 152.222705 -109.200324) (xy 152.221816 -109.23208)
			(xy 152.22093 -109.24794) (xy 152.220763 -109.252637) (xy 152.221919 -109.261964) (xy 152.223216 -109.266482)
			(xy 152.226885 -109.278367) (xy 152.232855 -109.302517) (xy 152.235154 -109.314742) (xy 152.235154 -109.31525)
			(xy 152.236424 -109.322616) (xy 152.236424 -109.323124) (xy 152.239472 -109.347) (xy 152.239472 -109.347254)
			(xy 152.240234 -109.354874) (xy 152.252172 -109.384338) (xy 152.258014 -109.390942) (xy 152.268936 -109.403388)
			(xy 152.273508 -109.40796) (xy 153.143204 -109.40796) (xy 153.152926 -109.407477) (xy 153.170948 -109.400165)
			(xy 153.178256 -109.393736) (xy 153.209123 -109.364815) (xy 153.274972 -109.311714) (xy 153.34508 -109.264378)
			(xy 153.418945 -109.223148) (xy 153.496035 -109.18832) (xy 153.575797 -109.160144) (xy 153.657658 -109.138822)
			(xy 153.741031 -109.124508) (xy 153.825316 -109.117305) (xy 153.867612 -109.116876) (xy 153.914303 -109.117421)
			(xy 154.007275 -109.126155) (xy 154.099023 -109.143545) (xy 154.188742 -109.169438) (xy 154.275648 -109.203608)
			(xy 154.358976 -109.245756) (xy 154.437999 -109.295511) (xy 154.512022 -109.352438) (xy 154.580397 -109.416038)
			(xy 154.642525 -109.485753) (xy 154.697861 -109.560973) (xy 154.722322 -109.600746) (xy 154.72492 -109.604723)
			(xy 154.731314 -109.611747) (xy 154.735022 -109.614716) (xy 154.757646 -109.632901) (xy 154.79765 -109.674958)
			(xy 154.830821 -109.722589) (xy 154.856395 -109.774695) (xy 154.873781 -109.830073) (xy 154.882578 -109.887446)
			(xy 154.883104 -109.916468) (xy 154.883104 -109.91723) (xy 154.882605 -109.946596) (xy 154.873677 -110.004643)
			(xy 154.865324 -110.0328) (xy 154.863982 -110.037308) (xy 154.862832 -110.046643) (xy 154.863038 -110.051342)
			(xy 154.86392 -110.067075) (xy 154.864808 -110.098577) (xy 154.864816 -110.114334) (xy 154.86438 -110.156701)
			(xy 154.857191 -110.24113) (xy 154.842858 -110.324643) (xy 154.821485 -110.406638) (xy 154.793227 -110.486522)
			(xy 154.77617 -110.525306) (xy 154.772212 -110.535348) (xy 154.772225 -110.556914) (xy 154.77617 -110.566962)
			(xy 154.793213 -110.605751) (xy 154.821447 -110.68564) (xy 154.842808 -110.767634) (xy 154.857142 -110.851144)
			(xy 154.864346 -110.935569) (xy 154.864816 -110.977934) (xy 154.864818 -110.993882) (xy 154.863929 -111.025765)
			(xy 154.863038 -111.041688) (xy 154.862851 -111.046248) (xy 154.863882 -111.055315) (xy 154.86507 -111.059722)
			(xy 154.869896 -111.076232) (xy 154.869896 -111.07674) (xy 154.873415 -111.090084) (xy 154.878754 -111.117161)
			(xy 154.880564 -111.130842) (xy 154.881834 -111.143034) (xy 154.883358 -111.175546) (xy 154.882798 -111.204746)
			(xy 154.873887 -111.262462) (xy 154.85628 -111.318145) (xy 154.83039 -111.370493) (xy 154.796821 -111.418281)
			(xy 154.756359 -111.460392) (xy 154.733498 -111.478568) (xy 154.73299 -111.479076) (xy 154.727656 -111.482886)
			(xy 154.705382 -111.519932) (xy 154.65534 -111.590424) (xy 154.599383 -111.656319) (xy 154.537933 -111.717122)
			(xy 154.471449 -111.772378) (xy 154.400431 -111.821671) (xy 154.325413 -111.864631) (xy 154.246957 -111.900935)
			(xy 154.165654 -111.930311) (xy 154.082112 -111.952539) (xy 153.99696 -111.967451) (xy 153.910836 -111.974936)
			(xy 153.867612 -111.975392) (xy 153.825397 -111.97494) (xy 153.741269 -111.967784) (xy 153.658048 -111.95354)
			(xy 153.57633 -111.93231) (xy 153.4967 -111.904245) (xy 153.419728 -111.869547) (xy 153.345966 -111.828464)
			(xy 153.275942 -111.78129) (xy 153.242772 -111.755174) (xy 153.23594 -111.750108) (xy 153.219916 -111.744433)
			(xy 153.202917 -111.744359) (xy 153.194766 -111.746792) (xy 153.156372 -111.759251) (xy 153.078014 -111.778658)
			(xy 152.998344 -111.791668) (xy 152.917883 -111.798196) (xy 152.87752 -111.798608) (xy 152.394158 -111.798608)
			(xy 152.365775 -111.798438) (xy 152.309098 -111.795264) (xy 152.280874 -111.792258) (xy 152.27195 -111.791569)
			(xy 152.254556 -111.795743) (xy 152.239665 -111.805655) (xy 152.2291 -111.820089) (xy 152.226264 -111.82858)
			(xy 152.223216 -111.838994) (xy 152.221874 -111.843502) (xy 152.220723 -111.852837) (xy 152.22093 -111.857536)
			(xy 152.221815 -111.873332) (xy 152.222703 -111.904961) (xy 152.222708 -111.920782) (xy 152.222274 -111.96315)
			(xy 152.215089 -112.04758) (xy 152.20076 -112.131095) (xy 152.179391 -112.213091) (xy 152.151137 -112.292977)
			(xy 152.134062 -112.331754) (xy 152.130088 -112.341795) (xy 152.130081 -112.363372) (xy 152.134062 -112.37341)
			(xy 152.151105 -112.412199) (xy 152.179341 -112.492088) (xy 152.200704 -112.574082) (xy 152.215041 -112.657592)
			(xy 152.22225 -112.742016) (xy 152.222708 -112.784382) (xy 152.222709 -112.80033) (xy 152.221819 -112.832213)
			(xy 152.22093 -112.848136) (xy 152.220738 -112.852697) (xy 152.22176 -112.861766) (xy 152.222962 -112.86617)
			(xy 152.227788 -112.88268) (xy 152.227788 -112.883188) (xy 152.231309 -112.896531) (xy 152.236652 -112.923608)
			(xy 152.238456 -112.93729) (xy 152.239726 -112.949482) (xy 152.24125 -112.981994) (xy 152.240693 -113.011196)
			(xy 152.231789 -113.068916) (xy 152.214188 -113.124604) (xy 152.188302 -113.176957) (xy 152.154735 -113.224751)
			(xy 152.114274 -113.266868) (xy 152.09139 -113.285016) (xy 152.090882 -113.285524) (xy 152.085548 -113.289334)
			(xy 152.063273 -113.326378) (xy 152.013229 -113.396866) (xy 151.957271 -113.462758) (xy 151.895819 -113.523558)
			(xy 151.829334 -113.578811) (xy 151.758317 -113.628101) (xy 151.683299 -113.671058) (xy 151.604844 -113.707359)
			(xy 151.523541 -113.736734) (xy 151.44 -113.758959) (xy 151.354849 -113.77387) (xy 151.268727 -113.781354)
			(xy 151.225504 -113.78184) (xy 151.185443 -113.781422) (xy 151.105581 -113.774953) (xy 151.026498 -113.762089)
			(xy 150.987506 -113.752884) (xy 150.978065 -113.750969) (xy 150.958992 -113.753566) (xy 150.950422 -113.757964)
			(xy 150.92426 -113.77295) (xy 150.916082 -113.777998) (xy 150.903949 -113.792883) (xy 150.900638 -113.801906)
			(xy 150.893991 -113.822629) (xy 150.879126 -113.863537) (xy 150.87092 -113.883694) (xy 150.705312 -114.282728)
			(xy 150.68598 -114.327682) (xy 150.639753 -114.413936) (xy 150.585304 -114.495251) (xy 150.55469 -114.533426)
			(xy 150.550154 -114.539441) (xy 150.544477 -114.553386) (xy 150.543514 -114.560858) (xy 150.538155 -114.609588)
			(xy 150.519065 -114.705752) (xy 150.490622 -114.799575) (xy 150.472394 -114.845084) (xy 150.30704 -115.244372)
			(xy 150.291314 -115.281243) (xy 150.254758 -115.352587) (xy 150.212594 -115.420768) (xy 150.165095 -115.485346)
			(xy 150.139146 -115.515898) (xy 150.1394 -115.517676) (xy 150.138779 -115.566592) (xy 150.129154 -115.66395)
			(xy 150.110045 -115.759898) (xy 150.081634 -115.853514) (xy 150.063454 -115.89893) (xy 149.87397 -116.356892)
			(xy 149.856693 -116.39739) (xy 149.815986 -116.475468) (xy 149.792246 -116.512594) (xy 152.64384 -116.512594)
			(xy 152.644319 -116.485344) (xy 152.652089 -116.431399) (xy 152.667455 -116.379109) (xy 152.690105 -116.329538)
			(xy 152.719578 -116.283693) (xy 152.755274 -116.242509) (xy 152.796467 -116.206823) (xy 152.842319 -116.177361)
			(xy 152.891896 -116.154723) (xy 152.917906 -116.14658) (xy 152.925612 -116.143951) (xy 152.938946 -116.134621)
			(xy 152.944068 -116.128292) (xy 152.972262 -116.091208) (xy 152.972008 -116.080032) (xy 152.972008 -114.098578)
			(xy 152.972464 -114.072489) (xy 152.980636 -114.020956) (xy 152.996775 -113.971337) (xy 153.020482 -113.924857)
			(xy 153.051174 -113.882661) (xy 153.06929 -113.863882) (xy 155.036266 -111.896906) (xy 155.043091 -111.889494)
			(xy 155.050821 -111.870904) (xy 155.051252 -111.860838) (xy 155.051252 -97.998788) (xy 155.050846 -97.988716)
			(xy 155.043113 -97.970118) (xy 155.036266 -97.96272) (xy 154.256486 -97.18294) (xy 154.249549 -97.176623)
			(xy 154.23243 -97.168992) (xy 154.213714 -97.168002) (xy 154.20467 -97.170494) (xy 154.105102 -97.203006)
			(xy 154.08656 -97.22485) (xy 154.084274 -97.239074) (xy 154.079667 -97.265713) (xy 154.063905 -97.317424)
			(xy 154.040998 -97.366392) (xy 154.011407 -97.411635) (xy 153.975724 -97.452246) (xy 153.934664 -97.487412)
			(xy 153.88905 -97.516427) (xy 153.839796 -97.538711) (xy 153.787889 -97.553817) (xy 153.734368 -97.561442)
			(xy 153.707338 -97.561908) (xy 153.680086 -97.561409) (xy 153.626136 -97.553658) (xy 153.573839 -97.538306)
			(xy 153.524259 -97.515668) (xy 153.478406 -97.486204) (xy 153.437213 -97.450514) (xy 153.401519 -97.409325)
			(xy 153.37205 -97.363474) (xy 153.349407 -97.313896) (xy 153.334051 -97.261601) (xy 153.326293 -97.207652)
			(xy 153.32583 -97.1804) (xy 153.326293 -97.153372) (xy 153.333936 -97.099859) (xy 153.349054 -97.047961)
			(xy 153.371346 -96.998715) (xy 153.400364 -96.953108) (xy 153.435528 -96.912053) (xy 153.476134 -96.876371)
			(xy 153.521369 -96.846777) (xy 153.570328 -96.823864) (xy 153.622031 -96.808088) (xy 153.648664 -96.803464)
			(xy 153.662888 -96.801178) (xy 153.684732 -96.782636) (xy 153.717244 -96.683068) (xy 153.719828 -96.674031)
			(xy 153.718875 -96.655273) (xy 153.711207 -96.638127) (xy 153.704798 -96.631252) (xy 153.614628 -96.541082)
			(xy 153.610244 -96.536955) (xy 153.599973 -96.530677) (xy 153.594308 -96.528636) (xy 153.5938 -96.528636)
			(xy 153.568247 -96.520215) (xy 153.519643 -96.497139) (xy 153.474764 -96.467465) (xy 153.434497 -96.43178)
			(xy 153.399643 -96.390793) (xy 153.370892 -96.345316) (xy 153.348815 -96.296251) (xy 153.333849 -96.244571)
			(xy 153.326291 -96.191302) (xy 153.32583 -96.1644) (xy 153.326255 -96.137145) (xy 153.334013 -96.083191)
			(xy 153.349371 -96.03089) (xy 153.372017 -95.981308) (xy 153.401488 -95.935453) (xy 153.437186 -95.894259)
			(xy 153.478383 -95.858565) (xy 153.524241 -95.829098) (xy 153.573826 -95.806458) (xy 153.626128 -95.791105)
			(xy 153.680083 -95.783353) (xy 153.707338 -95.782892) (xy 153.734248 -95.783363) (xy 153.787532 -95.790945)
			(xy 153.839222 -95.805938) (xy 153.888293 -95.828045) (xy 153.93377 -95.856827) (xy 153.974753 -95.891714)
			(xy 154.010427 -95.932013) (xy 154.040085 -95.976925) (xy 154.063138 -96.025558) (xy 154.071574 -96.051116)
			(xy 154.071574 -96.05137) (xy 154.073541 -96.057068) (xy 154.079846 -96.06734) (xy 154.08402 -96.07169)
			(xy 154.445208 -96.432878) (xy 183.362598 -96.432878) (xy 183.366669 -96.377256) (xy 183.378795 -96.322819)
			(xy 183.398718 -96.270728) (xy 183.426014 -96.222093) (xy 183.4601 -96.17795) (xy 183.500249 -96.139241)
			(xy 183.545607 -96.10679) (xy 183.595207 -96.081289) (xy 183.647991 -96.063282) (xy 183.702834 -96.053152)
			(xy 183.758568 -96.051115) (xy 183.814005 -96.057215) (xy 183.867962 -96.071321) (xy 183.919291 -96.093133)
			(xy 183.966897 -96.122187) (xy 184.009765 -96.157862) (xy 184.046982 -96.199399) (xy 184.077755 -96.245912)
			(xy 184.101427 -96.296409) (xy 184.117495 -96.349816) (xy 184.125615 -96.404992) (xy 184.126124 -96.432878)
			(xy 184.125615 -96.460764) (xy 184.117495 -96.51594) (xy 184.101427 -96.569347) (xy 184.077755 -96.619844)
			(xy 184.046982 -96.666357) (xy 184.009765 -96.707894) (xy 183.966897 -96.743569) (xy 183.919291 -96.772623)
			(xy 183.867962 -96.794435) (xy 183.83634 -96.802702) (xy 185.421776 -96.802702) (xy 185.425847 -96.74708)
			(xy 185.437973 -96.692643) (xy 185.457896 -96.640552) (xy 185.485192 -96.591917) (xy 185.519278 -96.547774)
			(xy 185.559427 -96.509065) (xy 185.604785 -96.476614) (xy 185.654385 -96.451113) (xy 185.707169 -96.433106)
			(xy 185.762012 -96.422976) (xy 185.817746 -96.420939) (xy 185.873183 -96.427039) (xy 185.92714 -96.441145)
			(xy 185.978469 -96.462957) (xy 186.026075 -96.492011) (xy 186.068943 -96.527686) (xy 186.10616 -96.569223)
			(xy 186.136933 -96.615736) (xy 186.160605 -96.666233) (xy 186.176673 -96.71964) (xy 186.184793 -96.774816)
			(xy 186.185302 -96.802702) (xy 186.184793 -96.830588) (xy 186.176673 -96.885764) (xy 186.160605 -96.939171)
			(xy 186.136933 -96.989668) (xy 186.10616 -97.036181) (xy 186.102794 -97.039938) (xy 190.825372 -97.039938)
			(xy 190.829443 -96.984316) (xy 190.841569 -96.929879) (xy 190.861492 -96.877788) (xy 190.888788 -96.829153)
			(xy 190.922874 -96.78501) (xy 190.963023 -96.746301) (xy 191.008381 -96.71385) (xy 191.057981 -96.688349)
			(xy 191.110765 -96.670342) (xy 191.165608 -96.660212) (xy 191.221342 -96.658175) (xy 191.276779 -96.664275)
			(xy 191.330736 -96.678381) (xy 191.382065 -96.700193) (xy 191.429671 -96.729247) (xy 191.472539 -96.764922)
			(xy 191.509756 -96.806459) (xy 191.540529 -96.852972) (xy 191.564201 -96.903469) (xy 191.580269 -96.956876)
			(xy 191.587447 -97.005648) (xy 194.269358 -97.005648) (xy 194.273429 -96.950026) (xy 194.285555 -96.895589)
			(xy 194.305478 -96.843498) (xy 194.332774 -96.794863) (xy 194.36686 -96.75072) (xy 194.407009 -96.712011)
			(xy 194.452367 -96.67956) (xy 194.501967 -96.654059) (xy 194.554751 -96.636052) (xy 194.609594 -96.625922)
			(xy 194.665328 -96.623885) (xy 194.720765 -96.629985) (xy 194.774722 -96.644091) (xy 194.826051 -96.665903)
			(xy 194.873657 -96.694957) (xy 194.916525 -96.730632) (xy 194.953742 -96.772169) (xy 194.984515 -96.818682)
			(xy 195.008187 -96.869179) (xy 195.024255 -96.922586) (xy 195.032375 -96.977762) (xy 195.032884 -97.005648)
			(xy 195.032375 -97.033534) (xy 195.024255 -97.08871) (xy 195.008187 -97.142117) (xy 194.984515 -97.192614)
			(xy 194.953742 -97.239127) (xy 194.916525 -97.280664) (xy 194.873657 -97.316339) (xy 194.826051 -97.345393)
			(xy 194.774722 -97.367205) (xy 194.720765 -97.381311) (xy 194.665328 -97.387411) (xy 194.609594 -97.385374)
			(xy 194.554751 -97.375244) (xy 194.501967 -97.357237) (xy 194.452367 -97.331736) (xy 194.407009 -97.299285)
			(xy 194.36686 -97.260576) (xy 194.332774 -97.216433) (xy 194.305478 -97.167798) (xy 194.285555 -97.115707)
			(xy 194.273429 -97.06127) (xy 194.269358 -97.005648) (xy 191.587447 -97.005648) (xy 191.588389 -97.012052)
			(xy 191.588898 -97.039938) (xy 191.588389 -97.067824) (xy 191.580269 -97.123) (xy 191.564201 -97.176407)
			(xy 191.540529 -97.226904) (xy 191.509756 -97.273417) (xy 191.472539 -97.314954) (xy 191.429671 -97.350629)
			(xy 191.382065 -97.379683) (xy 191.330736 -97.401495) (xy 191.276779 -97.415601) (xy 191.221342 -97.421701)
			(xy 191.165608 -97.419664) (xy 191.110765 -97.409534) (xy 191.057981 -97.391527) (xy 191.008381 -97.366026)
			(xy 190.963023 -97.333575) (xy 190.922874 -97.294866) (xy 190.888788 -97.250723) (xy 190.861492 -97.202088)
			(xy 190.841569 -97.149997) (xy 190.829443 -97.09556) (xy 190.825372 -97.039938) (xy 186.102794 -97.039938)
			(xy 186.068943 -97.077718) (xy 186.026075 -97.113393) (xy 185.978469 -97.142447) (xy 185.92714 -97.164259)
			(xy 185.873183 -97.178365) (xy 185.817746 -97.184465) (xy 185.762012 -97.182428) (xy 185.707169 -97.172298)
			(xy 185.654385 -97.154291) (xy 185.604785 -97.12879) (xy 185.559427 -97.096339) (xy 185.519278 -97.05763)
			(xy 185.485192 -97.013487) (xy 185.457896 -96.964852) (xy 185.437973 -96.912761) (xy 185.425847 -96.858324)
			(xy 185.421776 -96.802702) (xy 183.83634 -96.802702) (xy 183.814005 -96.808541) (xy 183.758568 -96.814641)
			(xy 183.702834 -96.812604) (xy 183.647991 -96.802474) (xy 183.595207 -96.784467) (xy 183.545607 -96.758966)
			(xy 183.500249 -96.726515) (xy 183.4601 -96.687806) (xy 183.426014 -96.643663) (xy 183.398718 -96.595028)
			(xy 183.378795 -96.542937) (xy 183.366669 -96.4885) (xy 183.362598 -96.432878) (xy 154.445208 -96.432878)
			(xy 155.617926 -97.605596) (xy 155.636045 -97.624371) (xy 155.666725 -97.666572) (xy 155.690423 -97.713054)
			(xy 155.706555 -97.762673) (xy 155.714721 -97.814205) (xy 155.715208 -97.840292) (xy 155.715208 -112.019334)
			(xy 155.714692 -112.04542) (xy 155.706534 -112.096951) (xy 155.690409 -112.146568) (xy 155.666715 -112.19305)
			(xy 155.636036 -112.235248) (xy 155.617926 -112.25403) (xy 153.65095 -114.221006) (xy 153.644122 -114.228416)
			(xy 153.636394 -114.247007) (xy 153.635964 -114.257074) (xy 153.635964 -115.361212) (xy 153.636652 -115.373853)
			(xy 153.648641 -115.396111) (xy 153.658824 -115.40363) (xy 153.740612 -115.457224) (xy 153.766266 -115.459256)
			(xy 153.77795 -115.454176) (xy 153.80924 -115.441313) (xy 153.875034 -115.425597) (xy 153.90876 -115.422934)
			(xy 153.919682 -115.422426) (xy 153.938986 -115.412266) (xy 153.999692 -115.335304) (xy 154.005026 -115.314222)
			(xy 154.002994 -115.303554) (xy 154.000151 -115.286807) (xy 153.997096 -115.252975) (xy 153.996898 -115.23599)
			(xy 153.996898 -115.235228) (xy 153.997384 -115.207977) (xy 154.00514 -115.154029) (xy 154.020495 -115.101734)
			(xy 154.043137 -115.052157) (xy 154.072603 -115.006307) (xy 154.108294 -114.965116) (xy 154.149485 -114.929425)
			(xy 154.195335 -114.899959) (xy 154.244912 -114.877317) (xy 154.297207 -114.861962) (xy 154.351155 -114.854206)
			(xy 154.405657 -114.854206) (xy 154.459605 -114.861962) (xy 154.5119 -114.877317) (xy 154.561477 -114.899959)
			(xy 154.607327 -114.929425) (xy 154.648518 -114.965116) (xy 154.684209 -115.006307) (xy 154.713675 -115.052157)
			(xy 154.736317 -115.101734) (xy 154.751672 -115.154029) (xy 154.759428 -115.207977) (xy 154.759914 -115.235228)
			(xy 154.759429 -115.264123) (xy 154.750738 -115.321254) (xy 154.733528 -115.37642) (xy 154.708194 -115.42836)
			(xy 154.675315 -115.475884) (xy 154.635644 -115.517904) (xy 154.590088 -115.55346) (xy 154.539691 -115.581737)
			(xy 154.485604 -115.602088) (xy 154.429067 -115.614049) (xy 154.40025 -115.616228) (xy 154.389328 -115.616736)
			(xy 154.370024 -115.626896) (xy 154.309318 -115.703858) (xy 154.303984 -115.72494) (xy 154.306016 -115.735608)
			(xy 154.308867 -115.752353) (xy 154.311917 -115.786187) (xy 154.312112 -115.803172) (xy 154.312112 -115.803934)
			(xy 154.31163 -115.830916) (xy 154.304008 -115.884341) (xy 154.288936 -115.936158) (xy 154.266714 -115.985336)
			(xy 154.237786 -116.030892) (xy 154.202728 -116.071918) (xy 154.162239 -116.107596) (xy 154.117128 -116.137214)
			(xy 154.09291 -116.14912) (xy 154.08275 -116.153946) (xy 154.068526 -116.17071) (xy 154.04211 -116.267484)
			(xy 154.045666 -116.28882) (xy 154.052016 -116.297964) (xy 154.052016 -116.298218) (xy 154.067595 -116.322057)
			(xy 154.092249 -116.373389) (xy 154.10901 -116.427813) (xy 154.117508 -116.484121) (xy 154.118056 -116.512594)
			(xy 154.117517 -116.542177) (xy 154.108383 -116.600633) (xy 154.090334 -116.656978) (xy 154.063802 -116.70986)
			(xy 154.029423 -116.758012) (xy 153.988022 -116.800279) (xy 153.96464 -116.81841) (xy 153.956004 -116.82476)
			(xy 153.945336 -116.844318) (xy 153.938986 -116.931948) (xy 153.938688 -116.942914) (xy 153.946341 -116.963451)
			(xy 153.953718 -116.971572) (xy 157.06852 -120.086374) (xy 169.739056 -120.086374) (xy 169.739056 -119.222774)
			(xy 169.739546 -119.19279) (xy 169.747374 -119.133334) (xy 169.762895 -119.075409) (xy 169.785844 -119.020005)
			(xy 169.815828 -118.968071) (xy 169.852334 -118.920495) (xy 169.894739 -118.87809) (xy 169.942315 -118.841584)
			(xy 169.994249 -118.8116) (xy 170.049653 -118.788651) (xy 170.107578 -118.77313) (xy 170.167034 -118.765302)
			(xy 170.227002 -118.765302) (xy 170.286458 -118.77313) (xy 170.344383 -118.788651) (xy 170.399787 -118.8116)
			(xy 170.451721 -118.841584) (xy 170.499297 -118.87809) (xy 170.541702 -118.920495) (xy 170.578208 -118.968071)
			(xy 170.608192 -119.020005) (xy 170.631141 -119.075409) (xy 170.646662 -119.133334) (xy 170.65449 -119.19279)
			(xy 170.65498 -119.222774) (xy 170.65498 -120.086374) (xy 170.65449 -120.116358) (xy 170.646662 -120.175814)
			(xy 170.631141 -120.233739) (xy 170.608192 -120.289143) (xy 170.578208 -120.341077) (xy 170.541702 -120.388653)
			(xy 170.499297 -120.431058) (xy 170.451721 -120.467564) (xy 170.399787 -120.497548) (xy 170.344383 -120.520497)
			(xy 170.286458 -120.536018) (xy 170.227002 -120.543846) (xy 170.167034 -120.543846) (xy 170.107578 -120.536018)
			(xy 170.049653 -120.520497) (xy 169.994249 -120.497548) (xy 169.942315 -120.467564) (xy 169.894739 -120.431058)
			(xy 169.852334 -120.388653) (xy 169.815828 -120.341077) (xy 169.785844 -120.289143) (xy 169.762895 -120.233739)
			(xy 169.747374 -120.175814) (xy 169.739546 -120.116358) (xy 169.739056 -120.086374) (xy 157.06852 -120.086374)
			(xy 158.552134 -121.569988) (xy 158.570233 -121.588781) (xy 158.60092 -121.630975) (xy 158.624623 -121.677453)
			(xy 158.640759 -121.727068) (xy 158.648929 -121.778598) (xy 158.649416 -121.804684) (xy 158.649416 -121.886472)
			(xy 167.884856 -121.886472) (xy 167.884856 -121.022872) (xy 167.885346 -120.992888) (xy 167.893174 -120.933432)
			(xy 167.908695 -120.875507) (xy 167.931644 -120.820103) (xy 167.961628 -120.768169) (xy 167.998134 -120.720593)
			(xy 168.040539 -120.678188) (xy 168.088115 -120.641682) (xy 168.140049 -120.611698) (xy 168.195453 -120.588749)
			(xy 168.253378 -120.573228) (xy 168.312834 -120.5654) (xy 168.372802 -120.5654) (xy 168.432258 -120.573228)
			(xy 168.490183 -120.588749) (xy 168.545587 -120.611698) (xy 168.597521 -120.641682) (xy 168.645097 -120.678188)
			(xy 168.687502 -120.720593) (xy 168.724008 -120.768169) (xy 168.753992 -120.820103) (xy 168.776941 -120.875507)
			(xy 168.792462 -120.933432) (xy 168.80029 -120.992888) (xy 168.80078 -121.022872) (xy 168.80078 -121.886472)
			(xy 168.80029 -121.916456) (xy 168.792462 -121.975912) (xy 168.776941 -122.033837) (xy 168.753992 -122.089241)
			(xy 168.724008 -122.141175) (xy 168.687502 -122.188751) (xy 168.645097 -122.231156) (xy 168.597521 -122.267662)
			(xy 168.545587 -122.297646) (xy 168.490183 -122.320595) (xy 168.432258 -122.336116) (xy 168.372802 -122.343944)
			(xy 168.312834 -122.343944) (xy 168.253378 -122.336116) (xy 168.195453 -122.320595) (xy 168.140049 -122.297646)
			(xy 168.088115 -122.267662) (xy 168.040539 -122.231156) (xy 167.998134 -122.188751) (xy 167.961628 -122.141175)
			(xy 167.931644 -122.089241) (xy 167.908695 -122.033837) (xy 167.893174 -121.975912) (xy 167.885346 -121.916456)
			(xy 167.884856 -121.886472) (xy 158.649416 -121.886472) (xy 158.649416 -123.686316) (xy 169.739056 -123.686316)
			(xy 169.739056 -122.822716) (xy 169.739546 -122.792732) (xy 169.747374 -122.733276) (xy 169.762895 -122.675351)
			(xy 169.785844 -122.619947) (xy 169.815828 -122.568013) (xy 169.852334 -122.520437) (xy 169.894739 -122.478032)
			(xy 169.942315 -122.441526) (xy 169.994249 -122.411542) (xy 170.049653 -122.388593) (xy 170.107578 -122.373072)
			(xy 170.167034 -122.365244) (xy 170.227002 -122.365244) (xy 170.286458 -122.373072) (xy 170.344383 -122.388593)
			(xy 170.399787 -122.411542) (xy 170.451721 -122.441526) (xy 170.499297 -122.478032) (xy 170.541702 -122.520437)
			(xy 170.578208 -122.568013) (xy 170.608192 -122.619947) (xy 170.631141 -122.675351) (xy 170.646662 -122.733276)
			(xy 170.65449 -122.792732) (xy 170.65498 -122.822716) (xy 170.65498 -123.686316) (xy 170.65449 -123.7163)
			(xy 170.646662 -123.775756) (xy 170.631141 -123.833681) (xy 170.608192 -123.889085) (xy 170.578208 -123.941019)
			(xy 170.541702 -123.988595) (xy 170.499297 -124.031) (xy 170.451721 -124.067506) (xy 170.399787 -124.09749)
			(xy 170.344383 -124.120439) (xy 170.286458 -124.13596) (xy 170.227002 -124.143788) (xy 170.167034 -124.143788)
			(xy 170.107578 -124.13596) (xy 170.049653 -124.120439) (xy 169.994249 -124.09749) (xy 169.942315 -124.067506)
			(xy 169.894739 -124.031) (xy 169.852334 -123.988595) (xy 169.815828 -123.941019) (xy 169.785844 -123.889085)
			(xy 169.762895 -123.833681) (xy 169.747374 -123.775756) (xy 169.739546 -123.7163) (xy 169.739056 -123.686316)
			(xy 158.649416 -123.686316) (xy 158.649416 -125.486414) (xy 167.884856 -125.486414) (xy 167.884856 -124.622814)
			(xy 167.885346 -124.59283) (xy 167.893174 -124.533374) (xy 167.908695 -124.475449) (xy 167.931644 -124.420045)
			(xy 167.961628 -124.368111) (xy 167.998134 -124.320535) (xy 168.040539 -124.27813) (xy 168.088115 -124.241624)
			(xy 168.140049 -124.21164) (xy 168.195453 -124.188691) (xy 168.253378 -124.17317) (xy 168.312834 -124.165342)
			(xy 168.372802 -124.165342) (xy 168.432258 -124.17317) (xy 168.490183 -124.188691) (xy 168.545587 -124.21164)
			(xy 168.597521 -124.241624) (xy 168.645097 -124.27813) (xy 168.687502 -124.320535) (xy 168.724008 -124.368111)
			(xy 168.753992 -124.420045) (xy 168.776941 -124.475449) (xy 168.792462 -124.533374) (xy 168.80029 -124.59283)
			(xy 168.80078 -124.622814) (xy 168.80078 -125.486414) (xy 168.80029 -125.516398) (xy 168.792462 -125.575854)
			(xy 168.776941 -125.633779) (xy 168.753992 -125.689183) (xy 168.724008 -125.741117) (xy 168.687502 -125.788693)
			(xy 168.645097 -125.831098) (xy 168.597521 -125.867604) (xy 168.545587 -125.897588) (xy 168.490183 -125.920537)
			(xy 168.432258 -125.936058) (xy 168.372802 -125.943886) (xy 168.312834 -125.943886) (xy 168.253378 -125.936058)
			(xy 168.195453 -125.920537) (xy 168.140049 -125.897588) (xy 168.088115 -125.867604) (xy 168.040539 -125.831098)
			(xy 167.998134 -125.788693) (xy 167.961628 -125.741117) (xy 167.931644 -125.689183) (xy 167.908695 -125.633779)
			(xy 167.893174 -125.575854) (xy 167.885346 -125.516398) (xy 167.884856 -125.486414) (xy 158.649416 -125.486414)
			(xy 158.649416 -131.29641) (xy 169.739056 -131.29641) (xy 169.739056 -130.43281) (xy 169.739546 -130.402826)
			(xy 169.747374 -130.34337) (xy 169.762895 -130.285445) (xy 169.785844 -130.230041) (xy 169.815828 -130.178107)
			(xy 169.852334 -130.130531) (xy 169.894739 -130.088126) (xy 169.942315 -130.05162) (xy 169.994249 -130.021636)
			(xy 170.049653 -129.998687) (xy 170.107578 -129.983166) (xy 170.167034 -129.975338) (xy 170.227002 -129.975338)
			(xy 170.286458 -129.983166) (xy 170.344383 -129.998687) (xy 170.399787 -130.021636) (xy 170.451721 -130.05162)
			(xy 170.499297 -130.088126) (xy 170.541702 -130.130531) (xy 170.578208 -130.178107) (xy 170.608192 -130.230041)
			(xy 170.631141 -130.285445) (xy 170.646662 -130.34337) (xy 170.65449 -130.402826) (xy 170.65498 -130.43281)
			(xy 170.65498 -131.29641) (xy 170.65449 -131.326394) (xy 170.646662 -131.38585) (xy 170.631141 -131.443775)
			(xy 170.608192 -131.499179) (xy 170.578208 -131.551113) (xy 170.541702 -131.598689) (xy 170.499297 -131.641094)
			(xy 170.451721 -131.6776) (xy 170.399787 -131.707584) (xy 170.344383 -131.730533) (xy 170.286458 -131.746054)
			(xy 170.227002 -131.753882) (xy 170.167034 -131.753882) (xy 170.107578 -131.746054) (xy 170.049653 -131.730533)
			(xy 169.994249 -131.707584) (xy 169.942315 -131.6776) (xy 169.894739 -131.641094) (xy 169.852334 -131.598689)
			(xy 169.815828 -131.551113) (xy 169.785844 -131.499179) (xy 169.762895 -131.443775) (xy 169.747374 -131.38585)
			(xy 169.739546 -131.326394) (xy 169.739056 -131.29641) (xy 158.649416 -131.29641) (xy 158.649416 -133.096508)
			(xy 167.884856 -133.096508) (xy 167.884856 -132.232908) (xy 167.885346 -132.202924) (xy 167.893174 -132.143468)
			(xy 167.908695 -132.085543) (xy 167.931644 -132.030139) (xy 167.961628 -131.978205) (xy 167.998134 -131.930629)
			(xy 168.040539 -131.888224) (xy 168.088115 -131.851718) (xy 168.140049 -131.821734) (xy 168.195453 -131.798785)
			(xy 168.253378 -131.783264) (xy 168.312834 -131.775436) (xy 168.372802 -131.775436) (xy 168.432258 -131.783264)
			(xy 168.490183 -131.798785) (xy 168.545587 -131.821734) (xy 168.597521 -131.851718) (xy 168.645097 -131.888224)
			(xy 168.687502 -131.930629) (xy 168.724008 -131.978205) (xy 168.753992 -132.030139) (xy 168.776941 -132.085543)
			(xy 168.792462 -132.143468) (xy 168.80029 -132.202924) (xy 168.80078 -132.232908) (xy 168.80078 -133.096508)
			(xy 168.80029 -133.126492) (xy 168.792462 -133.185948) (xy 168.776941 -133.243873) (xy 168.753992 -133.299277)
			(xy 168.724008 -133.351211) (xy 168.687502 -133.398787) (xy 168.645097 -133.441192) (xy 168.597521 -133.477698)
			(xy 168.545587 -133.507682) (xy 168.490183 -133.530631) (xy 168.432258 -133.546152) (xy 168.372802 -133.55398)
			(xy 168.312834 -133.55398) (xy 168.253378 -133.546152) (xy 168.195453 -133.530631) (xy 168.140049 -133.507682)
			(xy 168.088115 -133.477698) (xy 168.040539 -133.441192) (xy 167.998134 -133.398787) (xy 167.961628 -133.351211)
			(xy 167.931644 -133.299277) (xy 167.908695 -133.243873) (xy 167.893174 -133.185948) (xy 167.885346 -133.126492)
			(xy 167.884856 -133.096508) (xy 158.649416 -133.096508) (xy 158.649416 -134.896352) (xy 169.739056 -134.896352)
			(xy 169.739056 -134.032752) (xy 169.739546 -134.002768) (xy 169.747374 -133.943312) (xy 169.762895 -133.885387)
			(xy 169.785844 -133.829983) (xy 169.815828 -133.778049) (xy 169.852334 -133.730473) (xy 169.894739 -133.688068)
			(xy 169.942315 -133.651562) (xy 169.994249 -133.621578) (xy 170.049653 -133.598629) (xy 170.107578 -133.583108)
			(xy 170.167034 -133.57528) (xy 170.227002 -133.57528) (xy 170.286458 -133.583108) (xy 170.344383 -133.598629)
			(xy 170.399787 -133.621578) (xy 170.451721 -133.651562) (xy 170.499297 -133.688068) (xy 170.541702 -133.730473)
			(xy 170.578208 -133.778049) (xy 170.608192 -133.829983) (xy 170.631141 -133.885387) (xy 170.646662 -133.943312)
			(xy 170.65449 -134.002768) (xy 170.65498 -134.032752) (xy 170.65498 -134.896352) (xy 170.65449 -134.926336)
			(xy 170.646662 -134.985792) (xy 170.631141 -135.043717) (xy 170.608192 -135.099121) (xy 170.578208 -135.151055)
			(xy 170.541702 -135.198631) (xy 170.499297 -135.241036) (xy 170.451721 -135.277542) (xy 170.399787 -135.307526)
			(xy 170.344383 -135.330475) (xy 170.286458 -135.345996) (xy 170.227002 -135.353824) (xy 170.167034 -135.353824)
			(xy 170.107578 -135.345996) (xy 170.049653 -135.330475) (xy 169.994249 -135.307526) (xy 169.942315 -135.277542)
			(xy 169.894739 -135.241036) (xy 169.852334 -135.198631) (xy 169.815828 -135.151055) (xy 169.785844 -135.099121)
			(xy 169.762895 -135.043717) (xy 169.747374 -134.985792) (xy 169.739546 -134.926336) (xy 169.739056 -134.896352)
			(xy 158.649416 -134.896352) (xy 158.649416 -136.69645) (xy 167.884856 -136.69645) (xy 167.884856 -135.83285)
			(xy 167.885346 -135.802866) (xy 167.893174 -135.74341) (xy 167.908695 -135.685485) (xy 167.931644 -135.630081)
			(xy 167.961628 -135.578147) (xy 167.998134 -135.530571) (xy 168.040539 -135.488166) (xy 168.088115 -135.45166)
			(xy 168.140049 -135.421676) (xy 168.195453 -135.398727) (xy 168.253378 -135.383206) (xy 168.312834 -135.375378)
			(xy 168.372802 -135.375378) (xy 168.432258 -135.383206) (xy 168.490183 -135.398727) (xy 168.545587 -135.421676)
			(xy 168.597521 -135.45166) (xy 168.645097 -135.488166) (xy 168.687502 -135.530571) (xy 168.724008 -135.578147)
			(xy 168.753992 -135.630081) (xy 168.776941 -135.685485) (xy 168.792462 -135.74341) (xy 168.80029 -135.802866)
			(xy 168.80078 -135.83285) (xy 168.80078 -136.69645) (xy 168.80029 -136.726434) (xy 168.792462 -136.78589)
			(xy 168.776941 -136.843815) (xy 168.753992 -136.899219) (xy 168.724008 -136.951153) (xy 168.687502 -136.998729)
			(xy 168.645097 -137.041134) (xy 168.597521 -137.07764) (xy 168.545587 -137.107624) (xy 168.490183 -137.130573)
			(xy 168.432258 -137.146094) (xy 168.372802 -137.153922) (xy 168.312834 -137.153922) (xy 168.253378 -137.146094)
			(xy 168.195453 -137.130573) (xy 168.140049 -137.107624) (xy 168.088115 -137.07764) (xy 168.040539 -137.041134)
			(xy 167.998134 -136.998729) (xy 167.961628 -136.951153) (xy 167.931644 -136.899219) (xy 167.908695 -136.843815)
			(xy 167.893174 -136.78589) (xy 167.885346 -136.726434) (xy 167.884856 -136.69645) (xy 158.649416 -136.69645)
			(xy 158.649416 -138.496548) (xy 160.072324 -138.496548) (xy 160.072324 -137.632948) (xy 160.072814 -137.602964)
			(xy 160.080642 -137.543508) (xy 160.096163 -137.485583) (xy 160.119112 -137.430179) (xy 160.149096 -137.378245)
			(xy 160.185602 -137.330669) (xy 160.228007 -137.288264) (xy 160.275583 -137.251758) (xy 160.327517 -137.221774)
			(xy 160.382921 -137.198825) (xy 160.440846 -137.183304) (xy 160.500302 -137.175476) (xy 160.56027 -137.175476)
			(xy 160.619726 -137.183304) (xy 160.677651 -137.198825) (xy 160.733055 -137.221774) (xy 160.784989 -137.251758)
			(xy 160.832565 -137.288264) (xy 160.87497 -137.330669) (xy 160.911476 -137.378245) (xy 160.94146 -137.430179)
			(xy 160.964409 -137.485583) (xy 160.97993 -137.543508) (xy 160.987758 -137.602964) (xy 160.988248 -137.632948)
			(xy 160.988248 -138.496548) (xy 160.987758 -138.526532) (xy 160.98281 -138.564112) (xy 162.791138 -138.564112)
			(xy 162.795209 -138.50849) (xy 162.807335 -138.454053) (xy 162.827258 -138.401962) (xy 162.854554 -138.353327)
			(xy 162.88864 -138.309184) (xy 162.928789 -138.270475) (xy 162.974147 -138.238024) (xy 163.023747 -138.212523)
			(xy 163.076531 -138.194516) (xy 163.131374 -138.184386) (xy 163.187108 -138.182349) (xy 163.242545 -138.188449)
			(xy 163.296502 -138.202555) (xy 163.347831 -138.224367) (xy 163.395437 -138.253421) (xy 163.438305 -138.289096)
			(xy 163.475522 -138.330633) (xy 163.506295 -138.377146) (xy 163.529967 -138.427643) (xy 163.546035 -138.48105)
			(xy 163.554155 -138.536226) (xy 163.554664 -138.564112) (xy 163.554155 -138.591998) (xy 163.546035 -138.647174)
			(xy 163.529967 -138.700581) (xy 163.506295 -138.751078) (xy 163.475522 -138.797591) (xy 163.438305 -138.839128)
			(xy 163.395437 -138.874803) (xy 163.347831 -138.903857) (xy 163.296502 -138.925669) (xy 163.242545 -138.939775)
			(xy 163.187108 -138.945875) (xy 163.131374 -138.943838) (xy 163.076531 -138.933708) (xy 163.023747 -138.915701)
			(xy 162.974147 -138.8902) (xy 162.928789 -138.857749) (xy 162.88864 -138.81904) (xy 162.854554 -138.774897)
			(xy 162.827258 -138.726262) (xy 162.807335 -138.674171) (xy 162.795209 -138.619734) (xy 162.791138 -138.564112)
			(xy 160.98281 -138.564112) (xy 160.97993 -138.585988) (xy 160.964409 -138.643913) (xy 160.94146 -138.699317)
			(xy 160.911476 -138.751251) (xy 160.87497 -138.798827) (xy 160.832565 -138.841232) (xy 160.784989 -138.877738)
			(xy 160.733055 -138.907722) (xy 160.677651 -138.930671) (xy 160.619726 -138.946192) (xy 160.56027 -138.95402)
			(xy 160.500302 -138.95402) (xy 160.440846 -138.946192) (xy 160.382921 -138.930671) (xy 160.327517 -138.907722)
			(xy 160.275583 -138.877738) (xy 160.228007 -138.841232) (xy 160.185602 -138.798827) (xy 160.149096 -138.751251)
			(xy 160.119112 -138.699317) (xy 160.096163 -138.643913) (xy 160.080642 -138.585988) (xy 160.072814 -138.526532)
			(xy 160.072324 -138.496548) (xy 158.649416 -138.496548) (xy 158.649416 -140.565378) (xy 159.689546 -140.565378)
			(xy 159.689988 -140.538007) (xy 159.69781 -140.483826) (xy 159.713304 -140.431322) (xy 159.736151 -140.381576)
			(xy 159.765882 -140.33561) (xy 159.783526 -140.31468) (xy 159.78378 -140.314426) (xy 159.789371 -140.307343)
			(xy 159.795613 -140.290423) (xy 159.795972 -140.281406) (xy 159.795972 -140.21435) (xy 159.795597 -140.205335)
			(xy 159.789363 -140.188417) (xy 159.78378 -140.18133) (xy 159.783526 -140.18133) (xy 159.783526 -140.181076)
			(xy 159.765913 -140.160123) (xy 159.736196 -140.114156) (xy 159.713355 -140.064414) (xy 159.697858 -140.011918)
			(xy 159.690023 -139.957746) (xy 159.689546 -139.930378) (xy 159.690057 -139.903128) (xy 159.697816 -139.849184)
			(xy 159.713171 -139.796892) (xy 159.735811 -139.747318) (xy 159.765276 -139.70147) (xy 159.800964 -139.660281)
			(xy 159.842151 -139.62459) (xy 159.887997 -139.595123) (xy 159.93757 -139.572479) (xy 159.98986 -139.557121)
			(xy 160.043804 -139.549359) (xy 160.071054 -139.54887) (xy 160.098424 -139.549346) (xy 160.152603 -139.557159)
			(xy 160.205107 -139.572645) (xy 160.254854 -139.595485) (xy 160.300821 -139.625209) (xy 160.321752 -139.64285)
			(xy 160.322006 -139.643104) (xy 160.329086 -139.6487) (xy 160.346008 -139.654941) (xy 160.355026 -139.655296)
			(xy 160.422082 -139.655296) (xy 160.431098 -139.654931) (xy 160.448015 -139.648689) (xy 160.455102 -139.643104)
			(xy 160.455102 -139.64285) (xy 160.455356 -139.64285) (xy 160.4763 -139.625226) (xy 160.522269 -139.59551)
			(xy 160.572013 -139.57267) (xy 160.624512 -139.557176) (xy 160.678686 -139.549345) (xy 160.706054 -139.54887)
			(xy 160.733305 -139.549398) (xy 160.787252 -139.557148) (xy 160.839547 -139.572497) (xy 160.889126 -139.595133)
			(xy 160.934978 -139.624594) (xy 160.976171 -139.660281) (xy 161.011865 -139.701467) (xy 161.041335 -139.747314)
			(xy 161.063979 -139.796889) (xy 161.079337 -139.849181) (xy 161.087097 -139.903127) (xy 161.087562 -139.930378)
			(xy 161.087092 -139.957748) (xy 161.079277 -140.011928) (xy 161.063789 -140.064431) (xy 161.040948 -140.114178)
			(xy 161.032345 -140.127482) (xy 167.705022 -140.127482) (xy 167.709093 -140.07186) (xy 167.721219 -140.017423)
			(xy 167.741142 -139.965332) (xy 167.768438 -139.916697) (xy 167.802524 -139.872554) (xy 167.842673 -139.833845)
			(xy 167.888031 -139.801394) (xy 167.937631 -139.775893) (xy 167.990415 -139.757886) (xy 168.045258 -139.747756)
			(xy 168.100992 -139.745719) (xy 168.156429 -139.751819) (xy 168.210386 -139.765925) (xy 168.261715 -139.787737)
			(xy 168.309321 -139.816791) (xy 168.352189 -139.852466) (xy 168.389406 -139.894003) (xy 168.420179 -139.940516)
			(xy 168.443851 -139.991013) (xy 168.459919 -140.04442) (xy 168.468039 -140.099596) (xy 168.468548 -140.127482)
			(xy 168.468039 -140.155368) (xy 168.459919 -140.210544) (xy 168.443851 -140.263951) (xy 168.420179 -140.314448)
			(xy 168.389406 -140.360961) (xy 168.352189 -140.402498) (xy 168.309321 -140.438173) (xy 168.261715 -140.467227)
			(xy 168.210386 -140.489039) (xy 168.156429 -140.503145) (xy 168.100992 -140.509245) (xy 168.045258 -140.507208)
			(xy 167.990415 -140.497078) (xy 167.937631 -140.479071) (xy 167.888031 -140.45357) (xy 167.842673 -140.421119)
			(xy 167.802524 -140.38241) (xy 167.768438 -140.338267) (xy 167.741142 -140.289632) (xy 167.721219 -140.237541)
			(xy 167.709093 -140.183104) (xy 167.705022 -140.127482) (xy 161.032345 -140.127482) (xy 161.011223 -140.160145)
			(xy 160.993582 -140.181076) (xy 160.993328 -140.18133) (xy 160.987756 -140.188426) (xy 160.981503 -140.205336)
			(xy 160.981136 -140.21435) (xy 160.981136 -140.281406) (xy 160.981482 -140.290424) (xy 160.987736 -140.307341)
			(xy 160.993328 -140.314426) (xy 160.993582 -140.314426) (xy 160.993582 -140.31468) (xy 161.011222 -140.335611)
			(xy 161.040935 -140.381584) (xy 161.063771 -140.431332) (xy 161.079261 -140.483833) (xy 161.087089 -140.538009)
			(xy 161.087562 -140.565378) (xy 161.087124 -140.592632) (xy 161.079369 -140.646587) (xy 161.064013 -140.698888)
			(xy 161.04137 -140.748471) (xy 161.0119 -140.794326) (xy 160.976203 -140.83552) (xy 160.935007 -140.871214)
			(xy 160.88915 -140.900682) (xy 160.839565 -140.923322) (xy 160.787263 -140.938674) (xy 160.733308 -140.946426)
			(xy 160.706054 -140.946886) (xy 160.678685 -140.946392) (xy 160.624507 -140.938581) (xy 160.572004 -140.923099)
			(xy 160.522256 -140.900263) (xy 160.476288 -140.870545) (xy 160.455356 -140.852906) (xy 160.455102 -140.852652)
			(xy 160.448023 -140.847054) (xy 160.4311 -140.840815) (xy 160.422082 -140.84046) (xy 160.355026 -140.84046)
			(xy 160.346009 -140.840816) (xy 160.329091 -140.847063) (xy 160.322006 -140.852652) (xy 160.322006 -140.852906)
			(xy 160.321752 -140.852906) (xy 160.300812 -140.870535) (xy 160.254841 -140.900248) (xy 160.205096 -140.923086)
			(xy 160.152597 -140.938579) (xy 160.098423 -140.94641) (xy 160.071054 -140.946886) (xy 160.043801 -140.946465)
			(xy 159.989849 -140.938702) (xy 159.937552 -140.923339) (xy 159.887973 -140.900691) (xy 159.842122 -140.871218)
			(xy 159.800932 -140.83552) (xy 159.765241 -140.794323) (xy 159.735776 -140.748467) (xy 159.713137 -140.698884)
			(xy 159.697784 -140.646584) (xy 159.69003 -140.592631) (xy 159.689546 -140.565378) (xy 158.649416 -140.565378)
			(xy 158.649416 -145.30578) (xy 159.238442 -145.30578) (xy 159.238881 -145.278444) (xy 159.246663 -145.224329)
			(xy 159.262091 -145.17188) (xy 159.284852 -145.122172) (xy 159.314476 -145.076223) (xy 159.350359 -145.034975)
			(xy 159.391764 -144.999273) (xy 159.437843 -144.96985) (xy 159.48765 -144.947308) (xy 159.513778 -144.939258)
			(xy 159.522649 -144.936279) (xy 159.537626 -144.925083) (xy 159.542988 -144.917414) (xy 159.583882 -144.852136)
			(xy 159.587438 -144.834356) (xy 159.585914 -144.825212) (xy 159.585914 -144.824704) (xy 159.583429 -144.809074)
			(xy 159.58076 -144.777537) (xy 159.58058 -144.761712) (xy 159.581089 -144.734462) (xy 159.588844 -144.680515)
			(xy 159.604197 -144.628222) (xy 159.626836 -144.578646) (xy 159.6563 -144.532796) (xy 159.691989 -144.491606)
			(xy 159.733177 -144.455914) (xy 159.779024 -144.426447) (xy 159.828599 -144.403805) (xy 159.880892 -144.388449)
			(xy 159.934838 -144.380691) (xy 159.962088 -144.380204) (xy 159.974059 -144.380319) (xy 159.997952 -144.381842)
			(xy 160.00984 -144.383252) (xy 160.010094 -144.383252) (xy 160.019268 -144.383962) (xy 160.037111 -144.379527)
			(xy 160.044892 -144.374616) (xy 160.101026 -144.3355) (xy 160.108433 -144.329918) (xy 160.11898 -144.314679)
			(xy 160.1216 -144.305782) (xy 160.1216 -144.305528) (xy 160.128585 -144.277974) (xy 160.14962 -144.225167)
			(xy 160.17826 -144.176067) (xy 160.21387 -144.131762) (xy 160.255663 -144.093233) (xy 160.302711 -144.061335)
			(xy 160.353973 -144.036774) (xy 160.408313 -144.020093) (xy 160.464527 -144.011663) (xy 160.492948 -144.011142)
			(xy 160.517619 -144.011555) (xy 160.566545 -144.017955) (xy 160.61424 -144.030605) (xy 160.63722 -144.03959)
			(xy 160.648323 -144.043494) (xy 160.671765 -144.041773) (xy 160.682178 -144.036288) (xy 160.752028 -143.994632)
			(xy 160.761804 -143.988159) (xy 160.774658 -143.968589) (xy 160.776666 -143.95704) (xy 160.776666 -143.956532)
			(xy 160.780373 -143.928978) (xy 160.794634 -143.875244) (xy 160.816545 -143.82415) (xy 160.845644 -143.776779)
			(xy 160.881313 -143.734136) (xy 160.922795 -143.697124) (xy 160.969212 -143.666528) (xy 161.01958 -143.642995)
			(xy 161.072831 -143.627026) (xy 161.127837 -143.618959) (xy 161.155634 -143.618458) (xy 161.182885 -143.618946)
			(xy 161.23683 -143.626706) (xy 161.289123 -143.642064) (xy 161.338698 -143.664707) (xy 161.384547 -143.694173)
			(xy 161.425736 -143.729864) (xy 161.461427 -143.771053) (xy 161.490893 -143.816902) (xy 161.513536 -143.866477)
			(xy 161.528894 -143.91877) (xy 161.536654 -143.972715) (xy 161.537142 -143.999966) (xy 161.536665 -144.026547)
			(xy 161.529283 -144.079193) (xy 161.514658 -144.130303) (xy 161.493074 -144.178885) (xy 161.464949 -144.223997)
			(xy 161.43083 -144.264764) (xy 161.411412 -144.282922) (xy 161.404814 -144.28939) (xy 161.396354 -144.305801)
			(xy 161.394902 -144.314926) (xy 161.387536 -144.381474) (xy 161.386788 -144.39065) (xy 161.391233 -144.408501)
			(xy 161.396172 -144.416272) (xy 161.412288 -144.440397) (xy 161.437822 -144.492491) (xy 161.455179 -144.547849)
			(xy 161.463958 -144.605196) (xy 161.464498 -144.634204) (xy 161.464048 -144.661457) (xy 161.456291 -144.715409)
			(xy 161.440934 -144.767708) (xy 161.41829 -144.817289) (xy 161.38882 -144.863142) (xy 161.353125 -144.904335)
			(xy 161.311931 -144.940029) (xy 161.266077 -144.969497) (xy 161.216495 -144.992138) (xy 161.164196 -145.007494)
			(xy 161.110243 -145.015249) (xy 161.08299 -145.015712) (xy 161.082482 -145.015712) (xy 161.072685 -145.015648)
			(xy 161.053117 -145.014631) (xy 161.043366 -145.01368) (xy 161.043112 -145.01368) (xy 161.033722 -145.013065)
			(xy 161.015584 -145.018034) (xy 161.007806 -145.023332) (xy 160.944814 -145.070068) (xy 160.934908 -145.08607)
			(xy 160.93313 -145.095722) (xy 160.927734 -145.121559) (xy 160.910803 -145.17155) (xy 160.887143 -145.21873)
			(xy 160.857206 -145.262199) (xy 160.821564 -145.301126) (xy 160.780896 -145.33477) (xy 160.73598 -145.362487)
			(xy 160.687672 -145.383749) (xy 160.636894 -145.39815) (xy 160.584616 -145.405415) (xy 160.558226 -145.405856)
			(xy 160.530675 -145.405407) (xy 160.476146 -145.397484) (xy 160.423324 -145.381797) (xy 160.373308 -145.358674)
			(xy 160.32714 -145.328596) (xy 160.285779 -145.292189) (xy 160.250086 -145.25021) (xy 160.220804 -145.203532)
			(xy 160.20923 -145.178526) (xy 160.20542 -145.16989) (xy 160.191958 -145.156428) (xy 160.111694 -145.121122)
			(xy 160.093152 -145.120106) (xy 160.084262 -145.1229) (xy 160.083246 -145.123408) (xy 160.06826 -145.128234)
			(xy 160.059395 -145.13123) (xy 160.044415 -145.142414) (xy 160.03905 -145.150078) (xy 159.998156 -145.215356)
			(xy 159.9946 -145.233136) (xy 159.996124 -145.24228) (xy 159.996124 -145.242788) (xy 159.998608 -145.258418)
			(xy 160.001277 -145.289955) (xy 160.001458 -145.30578) (xy 160.000972 -145.333031) (xy 159.993216 -145.386979)
			(xy 159.977861 -145.439274) (xy 159.955219 -145.488851) (xy 159.925753 -145.534701) (xy 159.890062 -145.575892)
			(xy 159.848871 -145.611583) (xy 159.803021 -145.641049) (xy 159.753444 -145.663691) (xy 159.701149 -145.679046)
			(xy 159.647201 -145.686802) (xy 159.592699 -145.686802) (xy 159.538751 -145.679046) (xy 159.486456 -145.663691)
			(xy 159.436879 -145.641049) (xy 159.391029 -145.611583) (xy 159.349838 -145.575892) (xy 159.314147 -145.534701)
			(xy 159.284681 -145.488851) (xy 159.262039 -145.439274) (xy 159.246684 -145.386979) (xy 159.238928 -145.333031)
			(xy 159.238442 -145.30578) (xy 158.649416 -145.30578) (xy 158.649416 -146.739864) (xy 165.009828 -146.739864)
			(xy 165.013899 -146.684242) (xy 165.026025 -146.629805) (xy 165.045948 -146.577714) (xy 165.073244 -146.529079)
			(xy 165.10733 -146.484936) (xy 165.147479 -146.446227) (xy 165.192837 -146.413776) (xy 165.242437 -146.388275)
			(xy 165.295221 -146.370268) (xy 165.350064 -146.360138) (xy 165.405798 -146.358101) (xy 165.461235 -146.364201)
			(xy 165.515192 -146.378307) (xy 165.566521 -146.400119) (xy 165.614127 -146.429173) (xy 165.656995 -146.464848)
			(xy 165.694212 -146.506385) (xy 165.724985 -146.552898) (xy 165.748657 -146.603395) (xy 165.764725 -146.656802)
			(xy 165.772845 -146.711978) (xy 165.773354 -146.739864) (xy 165.772845 -146.76775) (xy 165.764725 -146.822926)
			(xy 165.748657 -146.876333) (xy 165.724985 -146.92683) (xy 165.694212 -146.973343) (xy 165.656995 -147.01488)
			(xy 165.614127 -147.050555) (xy 165.566521 -147.079609) (xy 165.515192 -147.101421) (xy 165.461235 -147.115527)
			(xy 165.405798 -147.121627) (xy 165.350064 -147.11959) (xy 165.295221 -147.10946) (xy 165.242437 -147.091453)
			(xy 165.192837 -147.065952) (xy 165.147479 -147.033501) (xy 165.10733 -146.994792) (xy 165.073244 -146.950649)
			(xy 165.045948 -146.902014) (xy 165.026025 -146.849923) (xy 165.013899 -146.795486) (xy 165.009828 -146.739864)
			(xy 158.649416 -146.739864) (xy 158.649416 -148.247354) (xy 158.649862 -148.257421) (xy 158.657568 -148.276019)
			(xy 158.664402 -148.283422) (xy 160.3248 -149.94382) (xy 160.34281 -149.962611) (xy 160.373393 -150.004723)
			(xy 160.397025 -150.051094) (xy 160.413124 -150.100586) (xy 160.421297 -150.151986) (xy 160.421828 -150.178008)
			(xy 160.421828 -151.257) (xy 168.676826 -151.257) (xy 168.680897 -151.201378) (xy 168.693023 -151.146941)
			(xy 168.712946 -151.09485) (xy 168.740242 -151.046215) (xy 168.774328 -151.002072) (xy 168.814477 -150.963363)
			(xy 168.859835 -150.930912) (xy 168.909435 -150.905411) (xy 168.962219 -150.887404) (xy 169.017062 -150.877274)
			(xy 169.072796 -150.875237) (xy 169.128233 -150.881337) (xy 169.18219 -150.895443) (xy 169.233519 -150.917255)
			(xy 169.281125 -150.946309) (xy 169.323993 -150.981984) (xy 169.36121 -151.023521) (xy 169.391983 -151.070034)
			(xy 169.415655 -151.120531) (xy 169.431723 -151.173938) (xy 169.439843 -151.229114) (xy 169.440352 -151.257)
			(xy 169.439843 -151.284886) (xy 169.431723 -151.340062) (xy 169.415655 -151.393469) (xy 169.391983 -151.443966)
			(xy 169.36121 -151.490479) (xy 169.323993 -151.532016) (xy 169.281125 -151.567691) (xy 169.233519 -151.596745)
			(xy 169.18219 -151.618557) (xy 169.128233 -151.632663) (xy 169.072796 -151.638763) (xy 169.017062 -151.636726)
			(xy 168.962219 -151.626596) (xy 168.909435 -151.608589) (xy 168.859835 -151.583088) (xy 168.814477 -151.550637)
			(xy 168.774328 -151.511928) (xy 168.740242 -151.467785) (xy 168.712946 -151.41915) (xy 168.693023 -151.367059)
			(xy 168.680897 -151.312622) (xy 168.676826 -151.257) (xy 160.421828 -151.257) (xy 160.421828 -153.560018)
			(xy 168.549826 -153.560018) (xy 168.553897 -153.504396) (xy 168.566023 -153.449959) (xy 168.585946 -153.397868)
			(xy 168.613242 -153.349233) (xy 168.647328 -153.30509) (xy 168.687477 -153.266381) (xy 168.732835 -153.23393)
			(xy 168.782435 -153.208429) (xy 168.835219 -153.190422) (xy 168.890062 -153.180292) (xy 168.945796 -153.178255)
			(xy 169.001233 -153.184355) (xy 169.05519 -153.198461) (xy 169.106519 -153.220273) (xy 169.154125 -153.249327)
			(xy 169.196993 -153.285002) (xy 169.23421 -153.326539) (xy 169.264983 -153.373052) (xy 169.288655 -153.423549)
			(xy 169.304723 -153.476956) (xy 169.312843 -153.532132) (xy 169.313352 -153.560018) (xy 169.312843 -153.587904)
			(xy 169.304723 -153.64308) (xy 169.288655 -153.696487) (xy 169.264983 -153.746984) (xy 169.23421 -153.793497)
			(xy 169.196993 -153.835034) (xy 169.154125 -153.870709) (xy 169.106519 -153.899763) (xy 169.05519 -153.921575)
			(xy 169.001233 -153.935681) (xy 168.945796 -153.941781) (xy 168.890062 -153.939744) (xy 168.835219 -153.929614)
			(xy 168.782435 -153.911607) (xy 168.732835 -153.886106) (xy 168.687477 -153.853655) (xy 168.647328 -153.814946)
			(xy 168.613242 -153.770803) (xy 168.585946 -153.722168) (xy 168.566023 -153.670077) (xy 168.553897 -153.61564)
			(xy 168.549826 -153.560018) (xy 160.421828 -153.560018) (xy 160.421828 -154.159966) (xy 167.406826 -154.159966)
			(xy 167.410897 -154.104344) (xy 167.423023 -154.049907) (xy 167.442946 -153.997816) (xy 167.470242 -153.949181)
			(xy 167.504328 -153.905038) (xy 167.544477 -153.866329) (xy 167.589835 -153.833878) (xy 167.639435 -153.808377)
			(xy 167.692219 -153.79037) (xy 167.747062 -153.78024) (xy 167.802796 -153.778203) (xy 167.858233 -153.784303)
			(xy 167.91219 -153.798409) (xy 167.963519 -153.820221) (xy 168.011125 -153.849275) (xy 168.053993 -153.88495)
			(xy 168.09121 -153.926487) (xy 168.121983 -153.973) (xy 168.145655 -154.023497) (xy 168.161723 -154.076904)
			(xy 168.169843 -154.13208) (xy 168.170352 -154.159966) (xy 168.169843 -154.187852) (xy 168.161723 -154.243028)
			(xy 168.145655 -154.296435) (xy 168.121983 -154.346932) (xy 168.09121 -154.393445) (xy 168.053993 -154.434982)
			(xy 168.011125 -154.470657) (xy 167.963519 -154.499711) (xy 167.91219 -154.521523) (xy 167.858233 -154.535629)
			(xy 167.802796 -154.541729) (xy 167.747062 -154.539692) (xy 167.692219 -154.529562) (xy 167.639435 -154.511555)
			(xy 167.589835 -154.486054) (xy 167.544477 -154.453603) (xy 167.504328 -154.414894) (xy 167.470242 -154.370751)
			(xy 167.442946 -154.322116) (xy 167.423023 -154.270025) (xy 167.410897 -154.215588) (xy 167.406826 -154.159966)
			(xy 160.421828 -154.159966) (xy 160.421828 -155.0416) (xy 164.263576 -155.0416) (xy 164.267647 -154.985978)
			(xy 164.279773 -154.931541) (xy 164.299696 -154.87945) (xy 164.326992 -154.830815) (xy 164.361078 -154.786672)
			(xy 164.401227 -154.747963) (xy 164.446585 -154.715512) (xy 164.496185 -154.690011) (xy 164.548969 -154.672004)
			(xy 164.603812 -154.661874) (xy 164.659546 -154.659837) (xy 164.714983 -154.665937) (xy 164.76894 -154.680043)
			(xy 164.820269 -154.701855) (xy 164.867875 -154.730909) (xy 164.910743 -154.766584) (xy 164.94796 -154.808121)
			(xy 164.978733 -154.854634) (xy 165.002405 -154.905131) (xy 165.018473 -154.958538) (xy 165.026593 -155.013714)
			(xy 165.027102 -155.0416) (xy 165.026593 -155.069486) (xy 165.018473 -155.124662) (xy 165.002405 -155.178069)
			(xy 164.978733 -155.228566) (xy 164.94796 -155.275079) (xy 164.910743 -155.316616) (xy 164.867875 -155.352291)
			(xy 164.820269 -155.381345) (xy 164.76894 -155.403157) (xy 164.714983 -155.417263) (xy 164.659546 -155.423363)
			(xy 164.603812 -155.421326) (xy 164.548969 -155.411196) (xy 164.496185 -155.393189) (xy 164.446585 -155.367688)
			(xy 164.401227 -155.335237) (xy 164.361078 -155.296528) (xy 164.326992 -155.252385) (xy 164.299696 -155.20375)
			(xy 164.279773 -155.151659) (xy 164.267647 -155.097222) (xy 164.263576 -155.0416) (xy 160.421828 -155.0416)
			(xy 160.421828 -155.598368) (xy 167.46804 -155.598368) (xy 167.472111 -155.542746) (xy 167.484237 -155.488309)
			(xy 167.50416 -155.436218) (xy 167.531456 -155.387583) (xy 167.565542 -155.34344) (xy 167.605691 -155.304731)
			(xy 167.651049 -155.27228) (xy 167.700649 -155.246779) (xy 167.753433 -155.228772) (xy 167.808276 -155.218642)
			(xy 167.86401 -155.216605) (xy 167.919447 -155.222705) (xy 167.973404 -155.236811) (xy 168.024733 -155.258623)
			(xy 168.072339 -155.287677) (xy 168.115207 -155.323352) (xy 168.152424 -155.364889) (xy 168.183197 -155.411402)
			(xy 168.206869 -155.461899) (xy 168.222937 -155.515306) (xy 168.231057 -155.570482) (xy 168.231566 -155.598368)
			(xy 168.231057 -155.626254) (xy 168.222937 -155.68143) (xy 168.206869 -155.734837) (xy 168.183197 -155.785334)
			(xy 168.152424 -155.831847) (xy 168.115207 -155.873384) (xy 168.072339 -155.909059) (xy 168.024733 -155.938113)
			(xy 167.973404 -155.959925) (xy 167.919447 -155.974031) (xy 167.86401 -155.980131) (xy 167.808276 -155.978094)
			(xy 167.753433 -155.967964) (xy 167.700649 -155.949957) (xy 167.651049 -155.924456) (xy 167.605691 -155.892005)
			(xy 167.565542 -155.853296) (xy 167.531456 -155.809153) (xy 167.50416 -155.760518) (xy 167.484237 -155.708427)
			(xy 167.472111 -155.65399) (xy 167.46804 -155.598368) (xy 160.421828 -155.598368) (xy 160.421828 -156.544518)
			(xy 168.827702 -156.544518) (xy 168.831773 -156.488896) (xy 168.843899 -156.434459) (xy 168.863822 -156.382368)
			(xy 168.891118 -156.333733) (xy 168.925204 -156.28959) (xy 168.965353 -156.250881) (xy 169.010711 -156.21843)
			(xy 169.060311 -156.192929) (xy 169.113095 -156.174922) (xy 169.167938 -156.164792) (xy 169.223672 -156.162755)
			(xy 169.279109 -156.168855) (xy 169.333066 -156.182961) (xy 169.384395 -156.204773) (xy 169.432001 -156.233827)
			(xy 169.474869 -156.269502) (xy 169.512086 -156.311039) (xy 169.542859 -156.357552) (xy 169.566531 -156.408049)
			(xy 169.582599 -156.461456) (xy 169.590719 -156.516632) (xy 169.591228 -156.544518) (xy 169.590719 -156.572404)
			(xy 169.582599 -156.62758) (xy 169.566531 -156.680987) (xy 169.542859 -156.731484) (xy 169.512086 -156.777997)
			(xy 169.474869 -156.819534) (xy 169.432001 -156.855209) (xy 169.384395 -156.884263) (xy 169.333066 -156.906075)
			(xy 169.279109 -156.920181) (xy 169.223672 -156.926281) (xy 169.167938 -156.924244) (xy 169.113095 -156.914114)
			(xy 169.060311 -156.896107) (xy 169.010711 -156.870606) (xy 168.965353 -156.838155) (xy 168.925204 -156.799446)
			(xy 168.891118 -156.755303) (xy 168.863822 -156.706668) (xy 168.843899 -156.654577) (xy 168.831773 -156.60014)
			(xy 168.827702 -156.544518) (xy 160.421828 -156.544518) (xy 160.421828 -157.0736) (xy 167.396666 -157.0736)
			(xy 167.400737 -157.017978) (xy 167.412863 -156.963541) (xy 167.432786 -156.91145) (xy 167.460082 -156.862815)
			(xy 167.494168 -156.818672) (xy 167.534317 -156.779963) (xy 167.579675 -156.747512) (xy 167.629275 -156.722011)
			(xy 167.682059 -156.704004) (xy 167.736902 -156.693874) (xy 167.792636 -156.691837) (xy 167.848073 -156.697937)
			(xy 167.90203 -156.712043) (xy 167.953359 -156.733855) (xy 168.000965 -156.762909) (xy 168.043833 -156.798584)
			(xy 168.08105 -156.840121) (xy 168.111823 -156.886634) (xy 168.135495 -156.937131) (xy 168.151563 -156.990538)
			(xy 168.159683 -157.045714) (xy 168.160192 -157.0736) (xy 168.159683 -157.101486) (xy 168.151563 -157.156662)
			(xy 168.135495 -157.210069) (xy 168.111823 -157.260566) (xy 168.08105 -157.307079) (xy 168.043833 -157.348616)
			(xy 168.000965 -157.384291) (xy 167.953359 -157.413345) (xy 167.90203 -157.435157) (xy 167.848073 -157.449263)
			(xy 167.792636 -157.455363) (xy 167.736902 -157.453326) (xy 167.682059 -157.443196) (xy 167.629275 -157.425189)
			(xy 167.579675 -157.399688) (xy 167.534317 -157.367237) (xy 167.494168 -157.328528) (xy 167.460082 -157.284385)
			(xy 167.432786 -157.23575) (xy 167.412863 -157.183659) (xy 167.400737 -157.129222) (xy 167.396666 -157.0736)
			(xy 160.421828 -157.0736) (xy 160.421828 -160.03651) (xy 160.422844 -160.046416) (xy 160.45043 -160.1851)
			(xy 161.624023 -160.1851) (xy 161.627979 -160.093241) (xy 161.639816 -160.002062) (xy 161.659448 -159.912238)
			(xy 161.686729 -159.824435) (xy 161.721457 -159.739302) (xy 161.763375 -159.657469) (xy 161.812173 -159.579542)
			(xy 161.867488 -159.506099) (xy 161.928913 -159.437683) (xy 161.995992 -159.374801) (xy 162.068227 -159.317918)
			(xy 162.145086 -159.267455) (xy 162.225998 -159.223786) (xy 162.310364 -159.187234) (xy 162.39756 -159.15807)
			(xy 162.486941 -159.13651) (xy 162.577844 -159.122714) (xy 162.669597 -159.116782) (xy 162.761519 -159.118761)
			(xy 162.852932 -159.128634) (xy 162.943157 -159.146329) (xy 163.031528 -159.171714) (xy 163.117388 -159.204602)
			(xy 163.200104 -159.24475) (xy 163.279062 -159.291859) (xy 163.353679 -159.345582) (xy 163.4234 -159.40552)
			(xy 163.487711 -159.47123) (xy 163.546136 -159.542226) (xy 163.598241 -159.61798) (xy 163.64364 -159.697934)
			(xy 163.681999 -159.781494) (xy 163.713032 -159.868043) (xy 163.73651 -159.956939) (xy 163.75226 -160.047524)
			(xy 163.760164 -160.139128) (xy 163.760658 -160.1851) (xy 163.760164 -160.231072) (xy 163.75226 -160.322676)
			(xy 163.73651 -160.413261) (xy 163.713032 -160.502157) (xy 163.681999 -160.588706) (xy 163.64364 -160.672266)
			(xy 163.598241 -160.75222) (xy 163.546136 -160.827974) (xy 163.487711 -160.89897) (xy 163.4234 -160.96468)
			(xy 163.353679 -161.024618) (xy 163.279062 -161.078341) (xy 163.200104 -161.12545) (xy 163.117388 -161.165598)
			(xy 163.031528 -161.198486) (xy 162.943157 -161.223871) (xy 162.852932 -161.241566) (xy 162.761519 -161.251439)
			(xy 162.669597 -161.253418) (xy 162.577844 -161.247486) (xy 162.486941 -161.23369) (xy 162.39756 -161.21213)
			(xy 162.310364 -161.182966) (xy 162.225998 -161.146414) (xy 162.145086 -161.102745) (xy 162.068227 -161.052282)
			(xy 161.995992 -160.995399) (xy 161.928913 -160.932517) (xy 161.867488 -160.864101) (xy 161.812173 -160.790658)
			(xy 161.763375 -160.712731) (xy 161.721457 -160.630898) (xy 161.686729 -160.545765) (xy 161.659448 -160.457962)
			(xy 161.639816 -160.368138) (xy 161.627979 -160.276959) (xy 161.624023 -160.1851) (xy 160.45043 -160.1851)
			(xy 161.248657 -164.198046) (xy 166.809164 -164.198046) (xy 166.813235 -164.142424) (xy 166.825361 -164.087987)
			(xy 166.845284 -164.035896) (xy 166.87258 -163.987261) (xy 166.906666 -163.943118) (xy 166.946815 -163.904409)
			(xy 166.992173 -163.871958) (xy 167.041773 -163.846457) (xy 167.094557 -163.82845) (xy 167.1494 -163.81832)
			(xy 167.205134 -163.816283) (xy 167.260571 -163.822383) (xy 167.314528 -163.836489) (xy 167.365857 -163.858301)
			(xy 167.413463 -163.887355) (xy 167.456331 -163.92303) (xy 167.493548 -163.964567) (xy 167.524321 -164.01108)
			(xy 167.547993 -164.061577) (xy 167.558942 -164.09797) (xy 168.691304 -164.09797) (xy 168.695375 -164.042348)
			(xy 168.707501 -163.987911) (xy 168.727424 -163.93582) (xy 168.75472 -163.887185) (xy 168.788806 -163.843042)
			(xy 168.828955 -163.804333) (xy 168.874313 -163.771882) (xy 168.923913 -163.746381) (xy 168.976697 -163.728374)
			(xy 169.03154 -163.718244) (xy 169.087274 -163.716207) (xy 169.142711 -163.722307) (xy 169.196668 -163.736413)
			(xy 169.247997 -163.758225) (xy 169.295603 -163.787279) (xy 169.338471 -163.822954) (xy 169.375688 -163.864491)
			(xy 169.406461 -163.911004) (xy 169.430133 -163.961501) (xy 169.446201 -164.014908) (xy 169.454321 -164.070084)
			(xy 169.45483 -164.09797) (xy 169.454321 -164.125856) (xy 169.446201 -164.181032) (xy 169.430133 -164.234439)
			(xy 169.406461 -164.284936) (xy 169.375688 -164.331449) (xy 169.338471 -164.372986) (xy 169.295603 -164.408661)
			(xy 169.247997 -164.437715) (xy 169.196668 -164.459527) (xy 169.142711 -164.473633) (xy 169.087274 -164.479733)
			(xy 169.03154 -164.477696) (xy 168.976697 -164.467566) (xy 168.923913 -164.449559) (xy 168.874313 -164.424058)
			(xy 168.828955 -164.391607) (xy 168.788806 -164.352898) (xy 168.75472 -164.308755) (xy 168.727424 -164.26012)
			(xy 168.707501 -164.208029) (xy 168.695375 -164.153592) (xy 168.691304 -164.09797) (xy 167.558942 -164.09797)
			(xy 167.564061 -164.114984) (xy 167.572181 -164.17016) (xy 167.57269 -164.198046) (xy 167.572181 -164.225932)
			(xy 167.564061 -164.281108) (xy 167.547993 -164.334515) (xy 167.524321 -164.385012) (xy 167.493548 -164.431525)
			(xy 167.456331 -164.473062) (xy 167.413463 -164.508737) (xy 167.365857 -164.537791) (xy 167.314528 -164.559603)
			(xy 167.260571 -164.573709) (xy 167.205134 -164.579809) (xy 167.1494 -164.577772) (xy 167.094557 -164.567642)
			(xy 167.041773 -164.549635) (xy 166.992173 -164.524134) (xy 166.946815 -164.491683) (xy 166.906666 -164.452974)
			(xy 166.87258 -164.408831) (xy 166.845284 -164.360196) (xy 166.825361 -164.308105) (xy 166.813235 -164.253668)
			(xy 166.809164 -164.198046) (xy 161.248657 -164.198046) (xy 161.43408 -165.130226) (xy 166.766238 -165.130226)
			(xy 166.770309 -165.074604) (xy 166.782435 -165.020167) (xy 166.802358 -164.968076) (xy 166.829654 -164.919441)
			(xy 166.86374 -164.875298) (xy 166.903889 -164.836589) (xy 166.949247 -164.804138) (xy 166.998847 -164.778637)
			(xy 167.051631 -164.76063) (xy 167.106474 -164.7505) (xy 167.162208 -164.748463) (xy 167.217645 -164.754563)
			(xy 167.271602 -164.768669) (xy 167.322931 -164.790481) (xy 167.370537 -164.819535) (xy 167.413405 -164.85521)
			(xy 167.450622 -164.896747) (xy 167.481395 -164.94326) (xy 167.505067 -164.993757) (xy 167.521135 -165.047164)
			(xy 167.529255 -165.10234) (xy 167.529764 -165.130226) (xy 167.529255 -165.158112) (xy 167.521135 -165.213288)
			(xy 167.505067 -165.266695) (xy 167.481395 -165.317192) (xy 167.450622 -165.363705) (xy 167.413405 -165.405242)
			(xy 167.370537 -165.440917) (xy 167.322931 -165.469971) (xy 167.271602 -165.491783) (xy 167.217645 -165.505889)
			(xy 167.162208 -165.511989) (xy 167.106474 -165.509952) (xy 167.051631 -165.499822) (xy 166.998847 -165.481815)
			(xy 166.949247 -165.456314) (xy 166.903889 -165.423863) (xy 166.86374 -165.385154) (xy 166.829654 -165.341011)
			(xy 166.802358 -165.292376) (xy 166.782435 -165.240285) (xy 166.770309 -165.185848) (xy 166.766238 -165.130226)
			(xy 161.43408 -165.130226) (xy 162.083919 -168.397174) (xy 166.7416 -168.397174) (xy 166.745671 -168.341552)
			(xy 166.757797 -168.287115) (xy 166.77772 -168.235024) (xy 166.805016 -168.186389) (xy 166.839102 -168.142246)
			(xy 166.879251 -168.103537) (xy 166.924609 -168.071086) (xy 166.974209 -168.045585) (xy 167.026993 -168.027578)
			(xy 167.081836 -168.017448) (xy 167.13757 -168.015411) (xy 167.193007 -168.021511) (xy 167.246964 -168.035617)
			(xy 167.298293 -168.057429) (xy 167.345899 -168.086483) (xy 167.388767 -168.122158) (xy 167.425984 -168.163695)
			(xy 167.456757 -168.210208) (xy 167.480429 -168.260705) (xy 167.496497 -168.314112) (xy 167.504617 -168.369288)
			(xy 167.505126 -168.397174) (xy 167.504617 -168.42506) (xy 167.496497 -168.480236) (xy 167.480429 -168.533643)
			(xy 167.456757 -168.58414) (xy 167.425984 -168.630653) (xy 167.388767 -168.67219) (xy 167.345899 -168.707865)
			(xy 167.298293 -168.736919) (xy 167.246964 -168.758731) (xy 167.193007 -168.772837) (xy 167.13757 -168.778937)
			(xy 167.081836 -168.7769) (xy 167.026993 -168.76677) (xy 166.974209 -168.748763) (xy 166.924609 -168.723262)
			(xy 166.879251 -168.690811) (xy 166.839102 -168.652102) (xy 166.805016 -168.607959) (xy 166.77772 -168.559324)
			(xy 166.757797 -168.507233) (xy 166.745671 -168.452796) (xy 166.7416 -168.397174) (xy 162.083919 -168.397174)
			(xy 162.250345 -169.23385) (xy 167.78935 -169.23385) (xy 167.793421 -169.178228) (xy 167.805547 -169.123791)
			(xy 167.82547 -169.0717) (xy 167.852766 -169.023065) (xy 167.886852 -168.978922) (xy 167.927001 -168.940213)
			(xy 167.972359 -168.907762) (xy 168.021959 -168.882261) (xy 168.074743 -168.864254) (xy 168.129586 -168.854124)
			(xy 168.18532 -168.852087) (xy 168.240757 -168.858187) (xy 168.294714 -168.872293) (xy 168.346043 -168.894105)
			(xy 168.393649 -168.923159) (xy 168.436517 -168.958834) (xy 168.473734 -169.000371) (xy 168.504507 -169.046884)
			(xy 168.528179 -169.097381) (xy 168.544247 -169.150788) (xy 168.552367 -169.205964) (xy 168.552876 -169.23385)
			(xy 168.552367 -169.261736) (xy 168.544247 -169.316912) (xy 168.528179 -169.370319) (xy 168.504507 -169.420816)
			(xy 168.473734 -169.467329) (xy 168.436517 -169.508866) (xy 168.393649 -169.544541) (xy 168.346043 -169.573595)
			(xy 168.294714 -169.595407) (xy 168.240757 -169.609513) (xy 168.18532 -169.615613) (xy 168.129586 -169.613576)
			(xy 168.074743 -169.603446) (xy 168.021959 -169.585439) (xy 167.972359 -169.559938) (xy 167.927001 -169.527487)
			(xy 167.886852 -169.488778) (xy 167.852766 -169.444635) (xy 167.82547 -169.396) (xy 167.805547 -169.343909)
			(xy 167.793421 -169.289472) (xy 167.78935 -169.23385) (xy 162.250345 -169.23385) (xy 162.345229 -169.710862)
			(xy 164.961314 -169.710862) (xy 164.965385 -169.65524) (xy 164.977511 -169.600803) (xy 164.997434 -169.548712)
			(xy 165.02473 -169.500077) (xy 165.058816 -169.455934) (xy 165.098965 -169.417225) (xy 165.144323 -169.384774)
			(xy 165.193923 -169.359273) (xy 165.246707 -169.341266) (xy 165.30155 -169.331136) (xy 165.357284 -169.329099)
			(xy 165.412721 -169.335199) (xy 165.466678 -169.349305) (xy 165.518007 -169.371117) (xy 165.565613 -169.400171)
			(xy 165.608481 -169.435846) (xy 165.645698 -169.477383) (xy 165.676471 -169.523896) (xy 165.700143 -169.574393)
			(xy 165.716211 -169.6278) (xy 165.724331 -169.682976) (xy 165.72484 -169.710862) (xy 165.724331 -169.738748)
			(xy 165.716211 -169.793924) (xy 165.700143 -169.847331) (xy 165.676471 -169.897828) (xy 165.645698 -169.944341)
			(xy 165.608481 -169.985878) (xy 165.565613 -170.021553) (xy 165.518007 -170.050607) (xy 165.466678 -170.072419)
			(xy 165.412721 -170.086525) (xy 165.357284 -170.092625) (xy 165.30155 -170.090588) (xy 165.246707 -170.080458)
			(xy 165.193923 -170.062451) (xy 165.144323 -170.03695) (xy 165.098965 -170.004499) (xy 165.058816 -169.96579)
			(xy 165.02473 -169.921647) (xy 164.997434 -169.873012) (xy 164.977511 -169.820921) (xy 164.965385 -169.766484)
			(xy 164.961314 -169.710862) (xy 162.345229 -169.710862) (xy 162.747198 -171.731686) (xy 162.750246 -171.741084)
			(xy 164.402615 -175.730154) (xy 167.057068 -175.730154) (xy 167.061139 -175.674532) (xy 167.073265 -175.620095)
			(xy 167.093188 -175.568004) (xy 167.120484 -175.519369) (xy 167.15457 -175.475226) (xy 167.194719 -175.436517)
			(xy 167.240077 -175.404066) (xy 167.289677 -175.378565) (xy 167.342461 -175.360558) (xy 167.397304 -175.350428)
			(xy 167.453038 -175.348391) (xy 167.508475 -175.354491) (xy 167.562432 -175.368597) (xy 167.613761 -175.390409)
			(xy 167.661367 -175.419463) (xy 167.704235 -175.455138) (xy 167.741452 -175.496675) (xy 167.772225 -175.543188)
			(xy 167.795897 -175.593685) (xy 167.811965 -175.647092) (xy 167.820085 -175.702268) (xy 167.820594 -175.730154)
			(xy 167.820085 -175.75804) (xy 167.811965 -175.813216) (xy 167.795897 -175.866623) (xy 167.772225 -175.91712)
			(xy 167.741452 -175.963633) (xy 167.704235 -176.00517) (xy 167.661367 -176.040845) (xy 167.613761 -176.069899)
			(xy 167.562432 -176.091711) (xy 167.508475 -176.105817) (xy 167.453038 -176.111917) (xy 167.397304 -176.10988)
			(xy 167.342461 -176.09975) (xy 167.289677 -176.081743) (xy 167.240077 -176.056242) (xy 167.194719 -176.023791)
			(xy 167.15457 -175.985082) (xy 167.120484 -175.940939) (xy 167.093188 -175.892304) (xy 167.073265 -175.840213)
			(xy 167.061139 -175.785776) (xy 167.057068 -175.730154) (xy 164.402615 -175.730154) (xy 166.058772 -179.728368)
			(xy 167.516554 -179.728368) (xy 167.520625 -179.672746) (xy 167.532751 -179.618309) (xy 167.552674 -179.566218)
			(xy 167.57997 -179.517583) (xy 167.614056 -179.47344) (xy 167.654205 -179.434731) (xy 167.699563 -179.40228)
			(xy 167.749163 -179.376779) (xy 167.801947 -179.358772) (xy 167.85679 -179.348642) (xy 167.912524 -179.346605)
			(xy 167.967961 -179.352705) (xy 168.021918 -179.366811) (xy 168.073247 -179.388623) (xy 168.120853 -179.417677)
			(xy 168.163721 -179.453352) (xy 168.200938 -179.494889) (xy 168.231711 -179.541402) (xy 168.255383 -179.591899)
			(xy 168.271451 -179.645306) (xy 168.279571 -179.700482) (xy 168.28008 -179.728368) (xy 168.279571 -179.756254)
			(xy 168.271451 -179.81143) (xy 168.255383 -179.864837) (xy 168.231711 -179.915334) (xy 168.200938 -179.961847)
			(xy 168.163721 -180.003384) (xy 168.120853 -180.039059) (xy 168.073247 -180.068113) (xy 168.021918 -180.089925)
			(xy 167.967961 -180.104031) (xy 167.912524 -180.110131) (xy 167.85679 -180.108094) (xy 167.801947 -180.097964)
			(xy 167.749163 -180.079957) (xy 167.699563 -180.054456) (xy 167.654205 -180.022005) (xy 167.614056 -179.983296)
			(xy 167.57997 -179.939153) (xy 167.552674 -179.890518) (xy 167.532751 -179.838427) (xy 167.520625 -179.78399)
			(xy 167.516554 -179.728368) (xy 166.058772 -179.728368) (xy 171.254082 -192.270634) (xy 178.101496 -192.270634)
			(xy 178.105567 -192.215012) (xy 178.117693 -192.160575) (xy 178.137616 -192.108484) (xy 178.164912 -192.059849)
			(xy 178.198998 -192.015706) (xy 178.239147 -191.976997) (xy 178.284505 -191.944546) (xy 178.334105 -191.919045)
			(xy 178.386889 -191.901038) (xy 178.441732 -191.890908) (xy 178.497466 -191.888871) (xy 178.552903 -191.894971)
			(xy 178.60686 -191.909077) (xy 178.658189 -191.930889) (xy 178.705795 -191.959943) (xy 178.748663 -191.995618)
			(xy 178.78588 -192.037155) (xy 178.816653 -192.083668) (xy 178.840325 -192.134165) (xy 178.856393 -192.187572)
			(xy 178.864513 -192.242748) (xy 178.865022 -192.270634) (xy 178.864513 -192.29852) (xy 178.856393 -192.353696)
			(xy 178.840325 -192.407103) (xy 178.816653 -192.4576) (xy 178.78588 -192.504113) (xy 178.748663 -192.54565)
			(xy 178.705795 -192.581325) (xy 178.658189 -192.610379) (xy 178.60686 -192.632191) (xy 178.552903 -192.646297)
			(xy 178.497466 -192.652397) (xy 178.441732 -192.65036) (xy 178.386889 -192.64023) (xy 178.334105 -192.622223)
			(xy 178.284505 -192.596722) (xy 178.239147 -192.564271) (xy 178.198998 -192.525562) (xy 178.164912 -192.481419)
			(xy 178.137616 -192.432784) (xy 178.117693 -192.380693) (xy 178.105567 -192.326256) (xy 178.101496 -192.270634)
			(xy 171.254082 -192.270634) (xy 171.528688 -192.933574) (xy 175.383696 -192.933574) (xy 175.387767 -192.877952)
			(xy 175.399893 -192.823515) (xy 175.419816 -192.771424) (xy 175.447112 -192.722789) (xy 175.481198 -192.678646)
			(xy 175.521347 -192.639937) (xy 175.566705 -192.607486) (xy 175.616305 -192.581985) (xy 175.669089 -192.563978)
			(xy 175.723932 -192.553848) (xy 175.779666 -192.551811) (xy 175.835103 -192.557911) (xy 175.88906 -192.572017)
			(xy 175.940389 -192.593829) (xy 175.987995 -192.622883) (xy 176.030863 -192.658558) (xy 176.06808 -192.700095)
			(xy 176.098853 -192.746608) (xy 176.122525 -192.797105) (xy 176.138593 -192.850512) (xy 176.146713 -192.905688)
			(xy 176.147222 -192.933574) (xy 176.146713 -192.96146) (xy 176.138593 -193.016636) (xy 176.122525 -193.070043)
			(xy 176.098853 -193.12054) (xy 176.06808 -193.167053) (xy 176.030863 -193.20859) (xy 175.987995 -193.244265)
			(xy 175.940389 -193.273319) (xy 175.88906 -193.295131) (xy 175.835103 -193.309237) (xy 175.779666 -193.315337)
			(xy 175.723932 -193.3133) (xy 175.669089 -193.30317) (xy 175.616305 -193.285163) (xy 175.566705 -193.259662)
			(xy 175.521347 -193.227211) (xy 175.481198 -193.188502) (xy 175.447112 -193.144359) (xy 175.419816 -193.095724)
			(xy 175.399893 -193.043633) (xy 175.387767 -192.989196) (xy 175.383696 -192.933574) (xy 171.528688 -192.933574)
			(xy 171.88536 -193.794634) (xy 178.101496 -193.794634) (xy 178.105567 -193.739012) (xy 178.117693 -193.684575)
			(xy 178.137616 -193.632484) (xy 178.164912 -193.583849) (xy 178.198998 -193.539706) (xy 178.239147 -193.500997)
			(xy 178.284505 -193.468546) (xy 178.334105 -193.443045) (xy 178.386889 -193.425038) (xy 178.441732 -193.414908)
			(xy 178.497466 -193.412871) (xy 178.552903 -193.418971) (xy 178.60686 -193.433077) (xy 178.658189 -193.454889)
			(xy 178.705795 -193.483943) (xy 178.748663 -193.519618) (xy 178.78588 -193.561155) (xy 178.816653 -193.607668)
			(xy 178.840325 -193.658165) (xy 178.856393 -193.711572) (xy 178.864513 -193.766748) (xy 178.865022 -193.794634)
			(xy 178.864513 -193.82252) (xy 178.856393 -193.877696) (xy 178.840325 -193.931103) (xy 178.816653 -193.9816)
			(xy 178.78588 -194.028113) (xy 178.748663 -194.06965) (xy 178.705795 -194.105325) (xy 178.658189 -194.134379)
			(xy 178.60686 -194.156191) (xy 178.552903 -194.170297) (xy 178.497466 -194.176397) (xy 178.441732 -194.17436)
			(xy 178.386889 -194.16423) (xy 178.334105 -194.146223) (xy 178.284505 -194.120722) (xy 178.239147 -194.088271)
			(xy 178.198998 -194.049562) (xy 178.164912 -194.005419) (xy 178.137616 -193.956784) (xy 178.117693 -193.904693)
			(xy 178.105567 -193.850256) (xy 178.101496 -193.794634) (xy 171.88536 -193.794634) (xy 172.058225 -194.211956)
			(xy 175.476406 -194.211956) (xy 175.480477 -194.156334) (xy 175.492603 -194.101897) (xy 175.512526 -194.049806)
			(xy 175.539822 -194.001171) (xy 175.573908 -193.957028) (xy 175.614057 -193.918319) (xy 175.659415 -193.885868)
			(xy 175.709015 -193.860367) (xy 175.761799 -193.84236) (xy 175.816642 -193.83223) (xy 175.872376 -193.830193)
			(xy 175.927813 -193.836293) (xy 175.98177 -193.850399) (xy 176.033099 -193.872211) (xy 176.080705 -193.901265)
			(xy 176.123573 -193.93694) (xy 176.16079 -193.978477) (xy 176.191563 -194.02499) (xy 176.215235 -194.075487)
			(xy 176.231303 -194.128894) (xy 176.239423 -194.18407) (xy 176.239932 -194.211956) (xy 176.239423 -194.239842)
			(xy 176.231303 -194.295018) (xy 176.215235 -194.348425) (xy 176.191563 -194.398922) (xy 176.16079 -194.445435)
			(xy 176.123573 -194.486972) (xy 176.080705 -194.522647) (xy 176.033099 -194.551701) (xy 175.98177 -194.573513)
			(xy 175.927813 -194.587619) (xy 175.872376 -194.593719) (xy 175.816642 -194.591682) (xy 175.761799 -194.581552)
			(xy 175.709015 -194.563545) (xy 175.659415 -194.538044) (xy 175.614057 -194.505593) (xy 175.573908 -194.466884)
			(xy 175.539822 -194.422741) (xy 175.512526 -194.374106) (xy 175.492603 -194.322015) (xy 175.480477 -194.267578)
			(xy 175.476406 -194.211956) (xy 172.058225 -194.211956) (xy 172.987781 -196.456046) (xy 175.442116 -196.456046)
			(xy 175.446187 -196.400424) (xy 175.458313 -196.345987) (xy 175.478236 -196.293896) (xy 175.505532 -196.245261)
			(xy 175.539618 -196.201118) (xy 175.579767 -196.162409) (xy 175.625125 -196.129958) (xy 175.674725 -196.104457)
			(xy 175.727509 -196.08645) (xy 175.782352 -196.07632) (xy 175.838086 -196.074283) (xy 175.893523 -196.080383)
			(xy 175.94748 -196.094489) (xy 175.998809 -196.116301) (xy 176.046415 -196.145355) (xy 176.089283 -196.18103)
			(xy 176.1265 -196.222567) (xy 176.157273 -196.26908) (xy 176.180945 -196.319577) (xy 176.197013 -196.372984)
			(xy 176.205133 -196.42816) (xy 176.205642 -196.456046) (xy 176.205133 -196.483932) (xy 176.197013 -196.539108)
			(xy 176.180945 -196.592515) (xy 176.157273 -196.643012) (xy 176.1265 -196.689525) (xy 176.089283 -196.731062)
			(xy 176.046415 -196.766737) (xy 175.998809 -196.795791) (xy 175.94748 -196.817603) (xy 175.893523 -196.831709)
			(xy 175.838086 -196.837809) (xy 175.782352 -196.835772) (xy 175.727509 -196.825642) (xy 175.674725 -196.807635)
			(xy 175.625125 -196.782134) (xy 175.579767 -196.749683) (xy 175.539618 -196.710974) (xy 175.505532 -196.666831)
			(xy 175.478236 -196.618196) (xy 175.458313 -196.566105) (xy 175.446187 -196.511668) (xy 175.442116 -196.456046)
			(xy 172.987781 -196.456046) (xy 173.167695 -196.890386) (xy 178.09794 -196.890386) (xy 178.102011 -196.834764)
			(xy 178.114137 -196.780327) (xy 178.13406 -196.728236) (xy 178.161356 -196.679601) (xy 178.195442 -196.635458)
			(xy 178.235591 -196.596749) (xy 178.280949 -196.564298) (xy 178.330549 -196.538797) (xy 178.383333 -196.52079)
			(xy 178.438176 -196.51066) (xy 178.49391 -196.508623) (xy 178.549347 -196.514723) (xy 178.603304 -196.528829)
			(xy 178.654633 -196.550641) (xy 178.702239 -196.579695) (xy 178.745107 -196.61537) (xy 178.782324 -196.656907)
			(xy 178.813097 -196.70342) (xy 178.836769 -196.753917) (xy 178.852837 -196.807324) (xy 178.860957 -196.8625)
			(xy 178.861466 -196.890386) (xy 178.860957 -196.918272) (xy 178.852837 -196.973448) (xy 178.836769 -197.026855)
			(xy 178.813097 -197.077352) (xy 178.782324 -197.123865) (xy 178.745107 -197.165402) (xy 178.702239 -197.201077)
			(xy 178.654633 -197.230131) (xy 178.603304 -197.251943) (xy 178.549347 -197.266049) (xy 178.49391 -197.272149)
			(xy 178.438176 -197.270112) (xy 178.383333 -197.259982) (xy 178.330549 -197.241975) (xy 178.280949 -197.216474)
			(xy 178.235591 -197.184023) (xy 178.195442 -197.145314) (xy 178.161356 -197.101171) (xy 178.13406 -197.052536)
			(xy 178.114137 -197.000445) (xy 178.102011 -196.946008) (xy 178.09794 -196.890386) (xy 173.167695 -196.890386)
			(xy 173.569082 -197.859396) (xy 175.425352 -197.859396) (xy 175.429423 -197.803774) (xy 175.441549 -197.749337)
			(xy 175.461472 -197.697246) (xy 175.488768 -197.648611) (xy 175.522854 -197.604468) (xy 175.563003 -197.565759)
			(xy 175.608361 -197.533308) (xy 175.657961 -197.507807) (xy 175.710745 -197.4898) (xy 175.765588 -197.47967)
			(xy 175.821322 -197.477633) (xy 175.876759 -197.483733) (xy 175.930716 -197.497839) (xy 175.982045 -197.519651)
			(xy 176.029651 -197.548705) (xy 176.072519 -197.58438) (xy 176.109736 -197.625917) (xy 176.140509 -197.67243)
			(xy 176.164181 -197.722927) (xy 176.180249 -197.776334) (xy 176.188369 -197.83151) (xy 176.188878 -197.859396)
			(xy 176.188369 -197.887282) (xy 176.180249 -197.942458) (xy 176.164181 -197.995865) (xy 176.140509 -198.046362)
			(xy 176.109736 -198.092875) (xy 176.072519 -198.134412) (xy 176.029651 -198.170087) (xy 175.982045 -198.199141)
			(xy 175.930716 -198.220953) (xy 175.876759 -198.235059) (xy 175.821322 -198.241159) (xy 175.765588 -198.239122)
			(xy 175.710745 -198.228992) (xy 175.657961 -198.210985) (xy 175.608361 -198.185484) (xy 175.563003 -198.153033)
			(xy 175.522854 -198.114324) (xy 175.488768 -198.070181) (xy 175.461472 -198.021546) (xy 175.441549 -197.969455)
			(xy 175.429423 -197.915018) (xy 175.425352 -197.859396) (xy 173.569082 -197.859396) (xy 173.746366 -198.287386)
			(xy 178.09794 -198.287386) (xy 178.102011 -198.231764) (xy 178.114137 -198.177327) (xy 178.13406 -198.125236)
			(xy 178.161356 -198.076601) (xy 178.195442 -198.032458) (xy 178.235591 -197.993749) (xy 178.280949 -197.961298)
			(xy 178.330549 -197.935797) (xy 178.383333 -197.91779) (xy 178.438176 -197.90766) (xy 178.49391 -197.905623)
			(xy 178.549347 -197.911723) (xy 178.603304 -197.925829) (xy 178.654633 -197.947641) (xy 178.702239 -197.976695)
			(xy 178.745107 -198.01237) (xy 178.782324 -198.053907) (xy 178.813097 -198.10042) (xy 178.836769 -198.150917)
			(xy 178.852837 -198.204324) (xy 178.860957 -198.2595) (xy 178.861466 -198.287386) (xy 178.860957 -198.315272)
			(xy 178.852837 -198.370448) (xy 178.836769 -198.423855) (xy 178.813097 -198.474352) (xy 178.782324 -198.520865)
			(xy 178.745107 -198.562402) (xy 178.702239 -198.598077) (xy 178.654633 -198.627131) (xy 178.603304 -198.648943)
			(xy 178.549347 -198.663049) (xy 178.49391 -198.669149) (xy 178.438176 -198.667112) (xy 178.383333 -198.656982)
			(xy 178.330549 -198.638975) (xy 178.280949 -198.613474) (xy 178.235591 -198.581023) (xy 178.195442 -198.542314)
			(xy 178.161356 -198.498171) (xy 178.13406 -198.449536) (xy 178.114137 -198.397445) (xy 178.102011 -198.343008)
			(xy 178.09794 -198.287386) (xy 173.746366 -198.287386) (xy 173.940063 -198.755) (xy 181.846218 -198.755)
			(xy 181.850289 -198.699378) (xy 181.862415 -198.644941) (xy 181.882338 -198.59285) (xy 181.909634 -198.544215)
			(xy 181.94372 -198.500072) (xy 181.983869 -198.461363) (xy 182.029227 -198.428912) (xy 182.078827 -198.403411)
			(xy 182.131611 -198.385404) (xy 182.186454 -198.375274) (xy 182.242188 -198.373237) (xy 182.297625 -198.379337)
			(xy 182.351582 -198.393443) (xy 182.402911 -198.415255) (xy 182.450517 -198.444309) (xy 182.493385 -198.479984)
			(xy 182.530602 -198.521521) (xy 182.561375 -198.568034) (xy 182.585047 -198.618531) (xy 182.601115 -198.671938)
			(xy 182.609235 -198.727114) (xy 182.609744 -198.755) (xy 182.609235 -198.782886) (xy 182.601115 -198.838062)
			(xy 182.585047 -198.891469) (xy 182.561375 -198.941966) (xy 182.530602 -198.988479) (xy 182.493385 -199.030016)
			(xy 182.450517 -199.065691) (xy 182.402911 -199.094745) (xy 182.351582 -199.116557) (xy 182.297625 -199.130663)
			(xy 182.242188 -199.136763) (xy 182.186454 -199.134726) (xy 182.131611 -199.124596) (xy 182.078827 -199.106589)
			(xy 182.029227 -199.081088) (xy 181.983869 -199.048637) (xy 181.94372 -199.009928) (xy 181.909634 -198.965785)
			(xy 181.882338 -198.91715) (xy 181.862415 -198.865059) (xy 181.850289 -198.810622) (xy 181.846218 -198.755)
			(xy 173.940063 -198.755) (xy 174.011082 -198.92645) (xy 174.013065 -198.931027) (xy 174.018569 -198.939343)
			(xy 174.022004 -198.94296) (xy 174.756318 -199.677274) (xy 180.027832 -199.677274) (xy 180.031903 -199.621652)
			(xy 180.044029 -199.567215) (xy 180.063952 -199.515124) (xy 180.091248 -199.466489) (xy 180.125334 -199.422346)
			(xy 180.165483 -199.383637) (xy 180.210841 -199.351186) (xy 180.260441 -199.325685) (xy 180.313225 -199.307678)
			(xy 180.368068 -199.297548) (xy 180.423802 -199.295511) (xy 180.479239 -199.301611) (xy 180.533196 -199.315717)
			(xy 180.584525 -199.337529) (xy 180.632131 -199.366583) (xy 180.674999 -199.402258) (xy 180.712216 -199.443795)
			(xy 180.742989 -199.490308) (xy 180.766661 -199.540805) (xy 180.782729 -199.594212) (xy 180.790849 -199.649388)
			(xy 180.791358 -199.677274) (xy 180.790849 -199.70516) (xy 180.782729 -199.760336) (xy 180.766661 -199.813743)
			(xy 180.742989 -199.86424) (xy 180.712216 -199.910753) (xy 180.674999 -199.95229) (xy 180.632131 -199.987965)
			(xy 180.584525 -200.017019) (xy 180.533196 -200.038831) (xy 180.479239 -200.052937) (xy 180.423802 -200.059037)
			(xy 180.368068 -200.057) (xy 180.313225 -200.04687) (xy 180.260441 -200.028863) (xy 180.210841 -200.003362)
			(xy 180.165483 -199.970911) (xy 180.125334 -199.932202) (xy 180.091248 -199.888059) (xy 180.063952 -199.839424)
			(xy 180.044029 -199.787333) (xy 180.031903 -199.732896) (xy 180.027832 -199.677274) (xy 174.756318 -199.677274)
			(xy 176.580292 -201.501248) (xy 180.77688 -201.501248) (xy 180.777355 -201.473878) (xy 180.785167 -201.419698)
			(xy 180.800653 -201.367195) (xy 180.823494 -201.317447) (xy 180.853218 -201.271481) (xy 180.87086 -201.25055)
			(xy 180.871114 -201.250296) (xy 180.87671 -201.243216) (xy 180.882951 -201.226294) (xy 180.883306 -201.217276)
			(xy 180.883306 -201.15022) (xy 180.882938 -201.141204) (xy 180.876698 -201.124287) (xy 180.871114 -201.1172)
			(xy 180.87086 -201.1172) (xy 180.87086 -201.116946) (xy 180.853222 -201.096013) (xy 180.823512 -201.05004)
			(xy 180.800676 -201.000292) (xy 180.785184 -200.947792) (xy 180.777355 -200.893617) (xy 180.77688 -200.866248)
			(xy 180.777366 -200.838997) (xy 180.785122 -200.785049) (xy 180.800477 -200.732754) (xy 180.823119 -200.683177)
			(xy 180.852585 -200.637327) (xy 180.888276 -200.596136) (xy 180.929467 -200.560445) (xy 180.975317 -200.530979)
			(xy 181.024894 -200.508337) (xy 181.077189 -200.492982) (xy 181.131137 -200.485226) (xy 181.185639 -200.485226)
			(xy 181.239587 -200.492982) (xy 181.291882 -200.508337) (xy 181.341459 -200.530979) (xy 181.387309 -200.560445)
			(xy 181.4285 -200.596136) (xy 181.464191 -200.637327) (xy 181.493657 -200.683177) (xy 181.516299 -200.732754)
			(xy 181.531654 -200.785049) (xy 181.53941 -200.838997) (xy 181.539896 -200.866248) (xy 181.5394 -200.893617)
			(xy 181.53159 -200.947795) (xy 181.516108 -201.000298) (xy 181.493273 -201.050045) (xy 181.463554 -201.096013)
			(xy 181.445916 -201.116946) (xy 181.445662 -201.1172) (xy 181.440065 -201.124279) (xy 181.433826 -201.141202)
			(xy 181.43347 -201.15022) (xy 181.43347 -201.217276) (xy 181.433845 -201.226291) (xy 181.440081 -201.243208)
			(xy 181.445662 -201.250296) (xy 181.445916 -201.250296) (xy 181.445916 -201.25055) (xy 181.463548 -201.271488)
			(xy 181.49326 -201.317459) (xy 181.516097 -201.367205) (xy 181.53159 -201.419705) (xy 181.539421 -201.473879)
			(xy 181.539896 -201.501248) (xy 181.53941 -201.528499) (xy 181.531654 -201.582447) (xy 181.516299 -201.634742)
			(xy 181.493657 -201.684319) (xy 181.464191 -201.730169) (xy 181.4285 -201.77136) (xy 181.387309 -201.807051)
			(xy 181.341459 -201.836517) (xy 181.291882 -201.859159) (xy 181.239587 -201.874514) (xy 181.185639 -201.88227)
			(xy 181.131137 -201.88227) (xy 181.077189 -201.874514) (xy 181.024894 -201.859159) (xy 180.975317 -201.836517)
			(xy 180.929467 -201.807051) (xy 180.888276 -201.77136) (xy 180.852585 -201.730169) (xy 180.823119 -201.684319)
			(xy 180.800477 -201.634742) (xy 180.785122 -201.582447) (xy 180.777366 -201.528499) (xy 180.77688 -201.501248)
			(xy 176.580292 -201.501248) (xy 183.374538 -208.295494) (xy 183.40451 -208.301336) (xy 183.418734 -208.295494)
			(xy 183.427751 -208.291152) (xy 183.44184 -208.276971) (xy 183.449478 -208.258498) (xy 183.449976 -208.248504)
			(xy 183.449976 -191.691006) (xy 183.449554 -191.680936) (xy 183.441832 -191.662338) (xy 183.43499 -191.654938)
			(xy 176.296828 -184.516776) (xy 176.266856 -184.51068) (xy 176.252632 -184.516776) (xy 176.243523 -184.521026)
			(xy 176.229284 -184.535186) (xy 176.221567 -184.553726) (xy 176.221136 -184.563766) (xy 176.221136 -185.381646)
			(xy 176.221347 -185.387795) (xy 176.224289 -185.399735) (xy 176.226978 -185.405268) (xy 176.240805 -185.432799)
			(xy 176.260373 -185.491214) (xy 176.270309 -185.552012) (xy 176.27092 -185.582814) (xy 176.270434 -185.610065)
			(xy 176.262678 -185.664013) (xy 176.247323 -185.716308) (xy 176.224681 -185.765885) (xy 176.195215 -185.811735)
			(xy 176.159524 -185.852926) (xy 176.118333 -185.888617) (xy 176.072483 -185.918083) (xy 176.022906 -185.940725)
			(xy 175.970611 -185.95608) (xy 175.916663 -185.963836) (xy 175.862161 -185.963836) (xy 175.808213 -185.95608)
			(xy 175.755918 -185.940725) (xy 175.706341 -185.918083) (xy 175.660491 -185.888617) (xy 175.6193 -185.852926)
			(xy 175.583609 -185.811735) (xy 175.554143 -185.765885) (xy 175.531501 -185.716308) (xy 175.516146 -185.664013)
			(xy 175.50839 -185.610065) (xy 175.507904 -185.582814) (xy 175.508525 -185.552012) (xy 175.518446 -185.491211)
			(xy 175.538015 -185.432797) (xy 175.551846 -185.405268) (xy 175.554574 -185.399749) (xy 175.557521 -185.3878)
			(xy 175.557688 -185.381646) (xy 175.557688 -184.33923) (xy 175.55725 -184.329162) (xy 175.549539 -184.310564)
			(xy 175.542702 -184.303162) (xy 169.79519 -178.555904) (xy 169.777074 -178.537127) (xy 169.746392 -178.494927)
			(xy 169.722694 -178.448445) (xy 169.706562 -178.398827) (xy 169.698395 -178.347295) (xy 169.697908 -178.321208)
			(xy 169.697908 -155.268422) (xy 169.697444 -155.258017) (xy 169.689166 -155.238922) (xy 169.673998 -155.224672)
			(xy 169.66438 -155.22067) (xy 169.559478 -155.18257) (xy 169.528998 -155.190698) (xy 169.518584 -155.203144)
			(xy 169.500335 -155.224121) (xy 169.458837 -155.261122) (xy 169.41241 -155.29171) (xy 169.362037 -155.315239)
			(xy 169.308783 -155.331212) (xy 169.253775 -155.339289) (xy 169.225976 -155.339796) (xy 169.198725 -155.339333)
			(xy 169.144778 -155.331573) (xy 169.092485 -155.316215) (xy 169.042909 -155.293572) (xy 168.99706 -155.264104)
			(xy 168.955871 -155.228412) (xy 168.920181 -155.187221) (xy 168.890716 -155.14137) (xy 168.868076 -155.091793)
			(xy 168.852722 -155.039498) (xy 168.844966 -154.985551) (xy 168.844966 -154.931049) (xy 168.852722 -154.877102)
			(xy 168.868076 -154.824807) (xy 168.890716 -154.77523) (xy 168.920181 -154.729379) (xy 168.955871 -154.688188)
			(xy 168.99706 -154.652496) (xy 169.042909 -154.623028) (xy 169.092485 -154.600385) (xy 169.144778 -154.585027)
			(xy 169.198725 -154.577267) (xy 169.225976 -154.57678) (xy 169.253778 -154.577269) (xy 169.308795 -154.585326)
			(xy 169.362058 -154.601289) (xy 169.412438 -154.624818) (xy 169.458867 -154.655415) (xy 169.500359 -154.69243)
			(xy 169.518584 -154.713432) (xy 169.528998 -154.725878) (xy 169.559478 -154.734006) (xy 169.66438 -154.695906)
			(xy 169.674001 -154.691913) (xy 169.689165 -154.677662) (xy 169.697417 -154.658559) (xy 169.697908 -154.648154)
			(xy 169.697908 -148.640546) (xy 169.697483 -148.630476) (xy 169.689765 -148.611877) (xy 169.682922 -148.604478)
			(xy 168.527222 -147.448778) (xy 168.519811 -147.441952) (xy 168.50122 -147.434225) (xy 168.491154 -147.433792)
			(xy 167.33139 -147.433792) (xy 167.305302 -147.433328) (xy 167.253769 -147.425158) (xy 167.20415 -147.409021)
			(xy 167.15767 -147.385315) (xy 167.115474 -147.354625) (xy 167.096694 -147.33651) (xy 166.932864 -147.17268)
			(xy 166.928473 -147.168561) (xy 166.918207 -147.162278) (xy 166.912544 -147.160234) (xy 166.912036 -147.160234)
			(xy 166.88649 -147.151793) (xy 166.837885 -147.128722) (xy 166.793004 -147.099051) (xy 166.752737 -147.063369)
			(xy 166.717882 -147.022384) (xy 166.68913 -146.976909) (xy 166.667051 -146.927846) (xy 166.652085 -146.876167)
			(xy 166.644527 -146.822899) (xy 166.644066 -146.795998) (xy 166.644576 -146.768748) (xy 166.652332 -146.714802)
			(xy 166.667686 -146.66251) (xy 166.690326 -146.612934) (xy 166.71979 -146.567085) (xy 166.755478 -146.525895)
			(xy 166.796666 -146.490204) (xy 166.842513 -146.460737) (xy 166.892087 -146.438094) (xy 166.944379 -146.422737)
			(xy 166.998324 -146.414978) (xy 167.025574 -146.41449) (xy 167.052485 -146.414931) (xy 167.10577 -146.422517)
			(xy 167.157461 -146.437515) (xy 167.206532 -146.459626) (xy 167.252009 -146.488412) (xy 167.292991 -146.523303)
			(xy 167.328665 -146.563605) (xy 167.358322 -146.608519) (xy 167.381374 -146.657155) (xy 167.38981 -146.682714)
			(xy 167.38981 -146.682968) (xy 167.39179 -146.688661) (xy 167.398086 -146.698935) (xy 167.402256 -146.703288)
			(xy 167.453818 -146.75485) (xy 167.461224 -146.761684) (xy 167.479818 -146.769409) (xy 167.489886 -146.769836)
			(xy 168.64965 -146.769836) (xy 168.675737 -146.77033) (xy 168.727269 -146.778491) (xy 168.776888 -146.79462)
			(xy 168.823369 -146.81832) (xy 168.865566 -146.849005) (xy 168.884346 -146.867118) (xy 169.853864 -147.836636)
			(xy 169.883836 -147.842732) (xy 169.89806 -147.836636) (xy 169.907163 -147.832374) (xy 169.921403 -147.818219)
			(xy 169.929122 -147.799685) (xy 169.929556 -147.789646) (xy 169.929556 -144.972532) (xy 169.929125 -144.962463)
			(xy 169.92141 -144.943865) (xy 169.91457 -144.936464) (xy 168.179496 -143.20139) (xy 168.172092 -143.194554)
			(xy 168.153496 -143.186832) (xy 168.143428 -143.186404) (xy 168.08704 -143.186404) (xy 168.051641 -143.185873)
			(xy 167.98136 -143.177344) (xy 167.912619 -143.160405) (xy 167.846421 -143.135302) (xy 167.783732 -143.102404)
			(xy 167.725466 -143.062188) (xy 167.672472 -143.015242) (xy 167.625524 -142.96225) (xy 167.585307 -142.903985)
			(xy 167.552406 -142.841297) (xy 167.527301 -142.7751) (xy 167.51036 -142.70636) (xy 167.501828 -142.636079)
			(xy 167.501316 -142.60068) (xy 167.501316 -142.600426) (xy 167.501951 -142.562149) (xy 167.511949 -142.486251)
			(xy 167.531739 -142.412299) (xy 167.560984 -142.341552) (xy 167.579548 -142.308072) (xy 167.583728 -142.300208)
			(xy 167.586814 -142.282676) (xy 167.583711 -142.265146) (xy 167.579548 -142.257272) (xy 167.560987 -142.223789)
			(xy 167.531719 -142.153049) (xy 167.511925 -142.079097) (xy 167.501941 -142.003196) (xy 167.501316 -141.964918)
			(xy 167.501873 -141.929516) (xy 167.510403 -141.859226) (xy 167.527341 -141.790477) (xy 167.552441 -141.724271)
			(xy 167.585335 -141.661571) (xy 167.625546 -141.603292) (xy 167.672487 -141.550283) (xy 167.725473 -141.503318)
			(xy 167.783733 -141.463079) (xy 167.846417 -141.430155) (xy 167.912612 -141.405024) (xy 167.981353 -141.388053)
			(xy 168.051638 -141.37949) (xy 168.08704 -141.37894) (xy 168.463976 -141.37894) (xy 168.496857 -141.379384)
			(xy 168.562205 -141.386749) (xy 168.626317 -141.401389) (xy 168.688385 -141.42312) (xy 168.747627 -141.451668)
			(xy 168.803298 -141.486674) (xy 168.854696 -141.527697) (xy 168.87825 -141.550644) (xy 171.383452 -144.055846)
			(xy 171.390864 -144.06253) (xy 171.409297 -144.070127) (xy 171.429235 -144.070127) (xy 171.447668 -144.06253)
			(xy 171.45508 -144.055846) (xy 171.68749 -143.823436) (xy 171.694305 -143.816016) (xy 171.70204 -143.797432)
			(xy 171.702476 -143.787368) (xy 171.702476 -118.739666) (xy 171.701852 -118.72844) (xy 171.692222 -118.708149)
			(xy 171.683934 -118.70055) (xy 171.614592 -118.6434) (xy 171.593256 -118.637812) (xy 171.58208 -118.639844)
			(xy 171.581572 -118.639844) (xy 171.563898 -118.643017) (xy 171.528153 -118.646452) (xy 171.510198 -118.646702)
			(xy 171.482945 -118.646247) (xy 171.428993 -118.638489) (xy 171.376695 -118.623133) (xy 171.327114 -118.600489)
			(xy 171.281261 -118.571021) (xy 171.240068 -118.535326) (xy 171.204375 -118.494133) (xy 171.174907 -118.448279)
			(xy 171.152265 -118.398698) (xy 171.136909 -118.346399) (xy 171.129153 -118.292447) (xy 171.12869 -118.265194)
			(xy 171.129272 -118.236785) (xy 171.137686 -118.180594) (xy 171.154342 -118.126273) (xy 171.178871 -118.075023)
			(xy 171.210731 -118.027979) (xy 171.249217 -117.986181) (xy 171.293477 -117.950554) (xy 171.342532 -117.921887)
			(xy 171.36872 -117.910864) (xy 171.380658 -117.906038) (xy 171.396914 -117.88648) (xy 171.416472 -117.790722)
			(xy 171.418351 -117.77826) (xy 171.411159 -117.75414) (xy 171.402756 -117.744748) (xy 171.06392 -117.405658)
			(xy 171.056512 -117.398828) (xy 171.037919 -117.391104) (xy 171.027852 -117.390672) (xy 170.830494 -117.390672)
			(xy 170.804471 -117.390136) (xy 170.753067 -117.381974) (xy 170.703569 -117.365882) (xy 170.657193 -117.342256)
			(xy 170.615076 -117.311676) (xy 170.596306 -117.293644) (xy 166.973504 -113.670842) (xy 166.955476 -113.652067)
			(xy 166.924895 -113.609951) (xy 166.901267 -113.563576) (xy 166.885172 -113.51408) (xy 166.877004 -113.462677)
			(xy 166.876476 -113.436654) (xy 166.876476 -97.934272) (xy 166.877013 -97.908249) (xy 166.885178 -97.856846)
			(xy 166.90127 -97.807349) (xy 166.924895 -97.760973) (xy 166.955473 -97.718855) (xy 166.973504 -97.700084)
			(xy 167.710612 -96.962976) (xy 167.714727 -96.958582) (xy 167.721013 -96.948318) (xy 167.723058 -96.942656)
			(xy 167.723058 -96.942148) (xy 167.731513 -96.916607) (xy 167.754583 -96.868003) (xy 167.784251 -96.823122)
			(xy 167.819931 -96.782854) (xy 167.860914 -96.747998) (xy 167.906387 -96.719245) (xy 167.955449 -96.697166)
			(xy 168.007126 -96.682198) (xy 168.060394 -96.674639) (xy 168.087294 -96.674178) (xy 168.114544 -96.674683)
			(xy 168.168491 -96.682439) (xy 168.220784 -96.697792) (xy 168.270361 -96.720432) (xy 168.31621 -96.749896)
			(xy 168.3574 -96.785586) (xy 168.393092 -96.826774) (xy 168.422559 -96.872622) (xy 168.445201 -96.922197)
			(xy 168.460557 -96.97449) (xy 168.468315 -97.028436) (xy 168.468802 -97.055686) (xy 168.468377 -97.082598)
			(xy 168.460789 -97.135884) (xy 168.44579 -97.187575) (xy 168.423676 -97.236646) (xy 168.394888 -97.282124)
			(xy 168.359996 -97.323106) (xy 168.319692 -97.358779) (xy 168.274775 -97.388435) (xy 168.226138 -97.411487)
			(xy 168.200578 -97.419922) (xy 168.200324 -97.419922) (xy 168.194629 -97.421898) (xy 168.184356 -97.428197)
			(xy 168.180004 -97.432368) (xy 167.949278 -97.663) (xy 182.980582 -97.663) (xy 182.984653 -97.607378)
			(xy 182.996779 -97.552941) (xy 183.016702 -97.50085) (xy 183.043998 -97.452215) (xy 183.078084 -97.408072)
			(xy 183.118233 -97.369363) (xy 183.163591 -97.336912) (xy 183.213191 -97.311411) (xy 183.265975 -97.293404)
			(xy 183.320818 -97.283274) (xy 183.376552 -97.281237) (xy 183.431989 -97.287337) (xy 183.485946 -97.301443)
			(xy 183.537275 -97.323255) (xy 183.584881 -97.352309) (xy 183.627749 -97.387984) (xy 183.664966 -97.429521)
			(xy 183.695739 -97.476034) (xy 183.719411 -97.526531) (xy 183.735479 -97.579938) (xy 183.743599 -97.635114)
			(xy 183.743691 -97.64014) (xy 190.017906 -97.64014) (xy 190.021977 -97.584518) (xy 190.034103 -97.530081)
			(xy 190.054026 -97.47799) (xy 190.081322 -97.429355) (xy 190.115408 -97.385212) (xy 190.155557 -97.346503)
			(xy 190.200915 -97.314052) (xy 190.250515 -97.288551) (xy 190.303299 -97.270544) (xy 190.358142 -97.260414)
			(xy 190.413876 -97.258377) (xy 190.469313 -97.264477) (xy 190.52327 -97.278583) (xy 190.574599 -97.300395)
			(xy 190.622205 -97.329449) (xy 190.665073 -97.365124) (xy 190.70229 -97.406661) (xy 190.733063 -97.453174)
			(xy 190.756735 -97.503671) (xy 190.772803 -97.557078) (xy 190.780923 -97.612254) (xy 190.781432 -97.64014)
			(xy 190.780923 -97.668026) (xy 190.772803 -97.723202) (xy 190.756735 -97.776609) (xy 190.733063 -97.827106)
			(xy 190.70229 -97.873619) (xy 190.665073 -97.915156) (xy 190.622205 -97.950831) (xy 190.574599 -97.979885)
			(xy 190.52327 -98.001697) (xy 190.469313 -98.015803) (xy 190.413876 -98.021903) (xy 190.358142 -98.019866)
			(xy 190.303299 -98.009736) (xy 190.250515 -97.991729) (xy 190.200915 -97.966228) (xy 190.155557 -97.933777)
			(xy 190.115408 -97.895068) (xy 190.081322 -97.850925) (xy 190.054026 -97.80229) (xy 190.034103 -97.750199)
			(xy 190.021977 -97.695762) (xy 190.017906 -97.64014) (xy 183.743691 -97.64014) (xy 183.744108 -97.663)
			(xy 183.743599 -97.690886) (xy 183.735479 -97.746062) (xy 183.719411 -97.799469) (xy 183.695739 -97.849966)
			(xy 183.664966 -97.896479) (xy 183.627749 -97.938016) (xy 183.584881 -97.973691) (xy 183.537275 -98.002745)
			(xy 183.485946 -98.024557) (xy 183.431989 -98.038663) (xy 183.376552 -98.044763) (xy 183.320818 -98.042726)
			(xy 183.265975 -98.032596) (xy 183.213191 -98.014589) (xy 183.163591 -97.989088) (xy 183.118233 -97.956637)
			(xy 183.078084 -97.917928) (xy 183.043998 -97.873785) (xy 183.016702 -97.82515) (xy 182.996779 -97.773059)
			(xy 182.984653 -97.718622) (xy 182.980582 -97.663) (xy 167.949278 -97.663) (xy 167.55491 -98.057208)
			(xy 167.548075 -98.064612) (xy 167.540352 -98.083208) (xy 167.539924 -98.093276) (xy 167.539924 -98.171)
			(xy 191.663826 -98.171) (xy 191.667897 -98.115378) (xy 191.680023 -98.060941) (xy 191.699946 -98.00885)
			(xy 191.727242 -97.960215) (xy 191.761328 -97.916072) (xy 191.801477 -97.877363) (xy 191.846835 -97.844912)
			(xy 191.896435 -97.819411) (xy 191.949219 -97.801404) (xy 192.004062 -97.791274) (xy 192.059796 -97.789237)
			(xy 192.115233 -97.795337) (xy 192.16919 -97.809443) (xy 192.220519 -97.831255) (xy 192.268125 -97.860309)
			(xy 192.310993 -97.895984) (xy 192.34821 -97.937521) (xy 192.378983 -97.984034) (xy 192.402655 -98.034531)
			(xy 192.418723 -98.087938) (xy 192.426843 -98.143114) (xy 192.427352 -98.171) (xy 192.426843 -98.198886)
			(xy 192.418723 -98.254062) (xy 192.402655 -98.307469) (xy 192.378983 -98.357966) (xy 192.34821 -98.404479)
			(xy 192.310993 -98.446016) (xy 192.268125 -98.481691) (xy 192.220519 -98.510745) (xy 192.16919 -98.532557)
			(xy 192.115233 -98.546663) (xy 192.059796 -98.552763) (xy 192.004062 -98.550726) (xy 191.949219 -98.540596)
			(xy 191.896435 -98.522589) (xy 191.846835 -98.497088) (xy 191.801477 -98.464637) (xy 191.761328 -98.425928)
			(xy 191.727242 -98.381785) (xy 191.699946 -98.33315) (xy 191.680023 -98.281059) (xy 191.667897 -98.226622)
			(xy 191.663826 -98.171) (xy 167.539924 -98.171) (xy 167.539924 -98.766863) (xy 206.090008 -98.766863)
			(xy 206.090008 -98.633301) (xy 206.098072 -98.499983) (xy 206.114172 -98.367395) (xy 206.138247 -98.236021)
			(xy 206.17021 -98.10634) (xy 206.209945 -97.978826) (xy 206.257307 -97.853943) (xy 206.312122 -97.732148)
			(xy 206.374192 -97.613885) (xy 206.443288 -97.499586) (xy 206.51916 -97.389666) (xy 206.60153 -97.284529)
			(xy 206.690098 -97.184556) (xy 206.78454 -97.090114) (xy 206.884513 -97.001546) (xy 206.98965 -96.919176)
			(xy 207.09957 -96.843304) (xy 207.213869 -96.774208) (xy 207.332132 -96.712138) (xy 207.453927 -96.657323)
			(xy 207.57881 -96.609961) (xy 207.706324 -96.570226) (xy 207.836005 -96.538263) (xy 207.967379 -96.514188)
			(xy 208.099967 -96.498088) (xy 208.233285 -96.490024) (xy 208.366847 -96.490024) (xy 208.500165 -96.498088)
			(xy 208.632753 -96.514188) (xy 208.764127 -96.538263) (xy 208.893808 -96.570226) (xy 209.021322 -96.609961)
			(xy 209.146205 -96.657323) (xy 209.268 -96.712138) (xy 209.386263 -96.774208) (xy 209.500562 -96.843304)
			(xy 209.610482 -96.919176) (xy 209.715619 -97.001546) (xy 209.815592 -97.090114) (xy 209.910034 -97.184556)
			(xy 209.996362 -97.282) (xy 218.206826 -97.282) (xy 218.210897 -97.226378) (xy 218.223023 -97.171941)
			(xy 218.242946 -97.11985) (xy 218.270242 -97.071215) (xy 218.304328 -97.027072) (xy 218.344477 -96.988363)
			(xy 218.389835 -96.955912) (xy 218.439435 -96.930411) (xy 218.492219 -96.912404) (xy 218.547062 -96.902274)
			(xy 218.602796 -96.900237) (xy 218.658233 -96.906337) (xy 218.71219 -96.920443) (xy 218.763519 -96.942255)
			(xy 218.811125 -96.971309) (xy 218.853993 -97.006984) (xy 218.89121 -97.048521) (xy 218.921983 -97.095034)
			(xy 218.945655 -97.145531) (xy 218.961723 -97.198938) (xy 218.969843 -97.254114) (xy 218.970352 -97.282)
			(xy 218.969843 -97.309886) (xy 218.961723 -97.365062) (xy 218.945655 -97.418469) (xy 218.921983 -97.468966)
			(xy 218.89121 -97.515479) (xy 218.853993 -97.557016) (xy 218.811125 -97.592691) (xy 218.763519 -97.621745)
			(xy 218.71219 -97.643557) (xy 218.658233 -97.657663) (xy 218.602796 -97.663763) (xy 218.547062 -97.661726)
			(xy 218.492219 -97.651596) (xy 218.439435 -97.633589) (xy 218.389835 -97.608088) (xy 218.344477 -97.575637)
			(xy 218.304328 -97.536928) (xy 218.270242 -97.492785) (xy 218.242946 -97.44415) (xy 218.223023 -97.392059)
			(xy 218.210897 -97.337622) (xy 218.206826 -97.282) (xy 209.996362 -97.282) (xy 209.998602 -97.284529)
			(xy 210.080972 -97.389666) (xy 210.156844 -97.499586) (xy 210.22594 -97.613885) (xy 210.28801 -97.732148)
			(xy 210.342825 -97.853943) (xy 210.390187 -97.978826) (xy 210.429922 -98.10634) (xy 210.461885 -98.236021)
			(xy 210.48596 -98.367395) (xy 210.50206 -98.499983) (xy 210.510124 -98.633301) (xy 210.510628 -98.700082)
			(xy 210.510124 -98.766863) (xy 210.50206 -98.900181) (xy 210.48596 -99.032769) (xy 210.461885 -99.164143)
			(xy 210.429922 -99.293824) (xy 210.390187 -99.421338) (xy 210.342825 -99.546221) (xy 210.28801 -99.668016)
			(xy 210.22594 -99.786279) (xy 210.156844 -99.900578) (xy 210.080972 -100.010498) (xy 209.998602 -100.115635)
			(xy 209.910034 -100.215608) (xy 209.815592 -100.31005) (xy 209.715619 -100.398618) (xy 209.610482 -100.480988)
			(xy 209.500562 -100.55686) (xy 209.386263 -100.625956) (xy 209.268 -100.688026) (xy 209.146205 -100.742841)
			(xy 209.021322 -100.790203) (xy 208.893808 -100.829938) (xy 208.764127 -100.861901) (xy 208.632753 -100.885976)
			(xy 208.500165 -100.902076) (xy 208.366847 -100.91014) (xy 208.233285 -100.91014) (xy 208.099967 -100.902076)
			(xy 207.967379 -100.885976) (xy 207.836005 -100.861901) (xy 207.706324 -100.829938) (xy 207.57881 -100.790203)
			(xy 207.453927 -100.742841) (xy 207.332132 -100.688026) (xy 207.213869 -100.625956) (xy 207.09957 -100.55686)
			(xy 206.98965 -100.480988) (xy 206.884513 -100.398618) (xy 206.78454 -100.31005) (xy 206.690098 -100.215608)
			(xy 206.60153 -100.115635) (xy 206.51916 -100.010498) (xy 206.443288 -99.900578) (xy 206.374192 -99.786279)
			(xy 206.312122 -99.668016) (xy 206.257307 -99.546221) (xy 206.209945 -99.421338) (xy 206.17021 -99.293824)
			(xy 206.138247 -99.164143) (xy 206.114172 -99.032769) (xy 206.098072 -98.900181) (xy 206.090008 -98.766863)
			(xy 167.539924 -98.766863) (xy 167.539924 -100.17633) (xy 169.739056 -100.17633) (xy 169.739056 -99.31273)
			(xy 169.739546 -99.282746) (xy 169.747374 -99.22329) (xy 169.762895 -99.165365) (xy 169.785844 -99.109961)
			(xy 169.815828 -99.058027) (xy 169.852334 -99.010451) (xy 169.894739 -98.968046) (xy 169.942315 -98.93154)
			(xy 169.994249 -98.901556) (xy 170.049653 -98.878607) (xy 170.107578 -98.863086) (xy 170.167034 -98.855258)
			(xy 170.227002 -98.855258) (xy 170.286458 -98.863086) (xy 170.344383 -98.878607) (xy 170.399787 -98.901556)
			(xy 170.451721 -98.93154) (xy 170.499297 -98.968046) (xy 170.541702 -99.010451) (xy 170.578208 -99.058027)
			(xy 170.608192 -99.109961) (xy 170.631141 -99.165365) (xy 170.646662 -99.22329) (xy 170.65449 -99.282746)
			(xy 170.65498 -99.31273) (xy 170.65498 -99.439984) (xy 183.371742 -99.439984) (xy 183.375813 -99.384362)
			(xy 183.387939 -99.329925) (xy 183.407862 -99.277834) (xy 183.435158 -99.229199) (xy 183.469244 -99.185056)
			(xy 183.509393 -99.146347) (xy 183.554751 -99.113896) (xy 183.604351 -99.088395) (xy 183.657135 -99.070388)
			(xy 183.711978 -99.060258) (xy 183.767712 -99.058221) (xy 183.823149 -99.064321) (xy 183.877106 -99.078427)
			(xy 183.928435 -99.100239) (xy 183.976041 -99.129293) (xy 184.018909 -99.164968) (xy 184.056126 -99.206505)
			(xy 184.086899 -99.253018) (xy 184.110571 -99.303515) (xy 184.126639 -99.356922) (xy 184.134759 -99.412098)
			(xy 184.135268 -99.439984) (xy 191.409826 -99.439984) (xy 191.413897 -99.384362) (xy 191.426023 -99.329925)
			(xy 191.445946 -99.277834) (xy 191.473242 -99.229199) (xy 191.507328 -99.185056) (xy 191.547477 -99.146347)
			(xy 191.592835 -99.113896) (xy 191.642435 -99.088395) (xy 191.695219 -99.070388) (xy 191.750062 -99.060258)
			(xy 191.805796 -99.058221) (xy 191.861233 -99.064321) (xy 191.91519 -99.078427) (xy 191.966519 -99.100239)
			(xy 192.014125 -99.129293) (xy 192.056993 -99.164968) (xy 192.09421 -99.206505) (xy 192.124983 -99.253018)
			(xy 192.148655 -99.303515) (xy 192.164723 -99.356922) (xy 192.172843 -99.412098) (xy 192.173352 -99.439984)
			(xy 192.172843 -99.46787) (xy 192.164723 -99.523046) (xy 192.148655 -99.576453) (xy 192.124983 -99.62695)
			(xy 192.09421 -99.673463) (xy 192.056993 -99.715) (xy 192.014125 -99.750675) (xy 191.966519 -99.779729)
			(xy 191.91519 -99.801541) (xy 191.861233 -99.815647) (xy 191.805796 -99.821747) (xy 191.750062 -99.81971)
			(xy 191.695219 -99.80958) (xy 191.642435 -99.791573) (xy 191.592835 -99.766072) (xy 191.547477 -99.733621)
			(xy 191.507328 -99.694912) (xy 191.473242 -99.650769) (xy 191.445946 -99.602134) (xy 191.426023 -99.550043)
			(xy 191.413897 -99.495606) (xy 191.409826 -99.439984) (xy 184.135268 -99.439984) (xy 184.134759 -99.46787)
			(xy 184.126639 -99.523046) (xy 184.110571 -99.576453) (xy 184.086899 -99.62695) (xy 184.056126 -99.673463)
			(xy 184.018909 -99.715) (xy 183.976041 -99.750675) (xy 183.928435 -99.779729) (xy 183.877106 -99.801541)
			(xy 183.823149 -99.815647) (xy 183.767712 -99.821747) (xy 183.711978 -99.81971) (xy 183.657135 -99.80958)
			(xy 183.604351 -99.791573) (xy 183.554751 -99.766072) (xy 183.509393 -99.733621) (xy 183.469244 -99.694912)
			(xy 183.435158 -99.650769) (xy 183.407862 -99.602134) (xy 183.387939 -99.550043) (xy 183.375813 -99.495606)
			(xy 183.371742 -99.439984) (xy 170.65498 -99.439984) (xy 170.65498 -99.982782) (xy 186.221876 -99.982782)
			(xy 186.225947 -99.92716) (xy 186.238073 -99.872723) (xy 186.257996 -99.820632) (xy 186.285292 -99.771997)
			(xy 186.319378 -99.727854) (xy 186.359527 -99.689145) (xy 186.404885 -99.656694) (xy 186.454485 -99.631193)
			(xy 186.507269 -99.613186) (xy 186.562112 -99.603056) (xy 186.617846 -99.601019) (xy 186.673283 -99.607119)
			(xy 186.72724 -99.621225) (xy 186.778569 -99.643037) (xy 186.826175 -99.672091) (xy 186.869043 -99.707766)
			(xy 186.90626 -99.749303) (xy 186.937033 -99.795816) (xy 186.960705 -99.846313) (xy 186.976773 -99.89972)
			(xy 186.984893 -99.954896) (xy 186.985402 -99.982782) (xy 186.984893 -100.010668) (xy 186.980586 -100.039932)
			(xy 189.976758 -100.039932) (xy 189.980829 -99.98431) (xy 189.992955 -99.929873) (xy 190.012878 -99.877782)
			(xy 190.040174 -99.829147) (xy 190.07426 -99.785004) (xy 190.114409 -99.746295) (xy 190.159767 -99.713844)
			(xy 190.209367 -99.688343) (xy 190.262151 -99.670336) (xy 190.316994 -99.660206) (xy 190.372728 -99.658169)
			(xy 190.428165 -99.664269) (xy 190.482122 -99.678375) (xy 190.533451 -99.700187) (xy 190.581057 -99.729241)
			(xy 190.623925 -99.764916) (xy 190.661142 -99.806453) (xy 190.691915 -99.852966) (xy 190.715587 -99.903463)
			(xy 190.731655 -99.95687) (xy 190.739775 -100.012046) (xy 190.740284 -100.039932) (xy 190.739775 -100.067818)
			(xy 190.731655 -100.122994) (xy 190.715587 -100.176401) (xy 190.691915 -100.226898) (xy 190.661142 -100.273411)
			(xy 190.623925 -100.314948) (xy 190.581057 -100.350623) (xy 190.533451 -100.379677) (xy 190.482122 -100.401489)
			(xy 190.428165 -100.415595) (xy 190.372728 -100.421695) (xy 190.316994 -100.419658) (xy 190.262151 -100.409528)
			(xy 190.209367 -100.391521) (xy 190.159767 -100.36602) (xy 190.114409 -100.333569) (xy 190.07426 -100.29486)
			(xy 190.040174 -100.250717) (xy 190.012878 -100.202082) (xy 189.992955 -100.149991) (xy 189.980829 -100.095554)
			(xy 189.976758 -100.039932) (xy 186.980586 -100.039932) (xy 186.976773 -100.065844) (xy 186.960705 -100.119251)
			(xy 186.937033 -100.169748) (xy 186.90626 -100.216261) (xy 186.869043 -100.257798) (xy 186.826175 -100.293473)
			(xy 186.778569 -100.322527) (xy 186.72724 -100.344339) (xy 186.673283 -100.358445) (xy 186.617846 -100.364545)
			(xy 186.562112 -100.362508) (xy 186.507269 -100.352378) (xy 186.454485 -100.334371) (xy 186.404885 -100.30887)
			(xy 186.359527 -100.276419) (xy 186.319378 -100.23771) (xy 186.285292 -100.193567) (xy 186.257996 -100.144932)
			(xy 186.238073 -100.092841) (xy 186.225947 -100.038404) (xy 186.221876 -99.982782) (xy 170.65498 -99.982782)
			(xy 170.65498 -100.17633) (xy 170.65449 -100.206314) (xy 170.646662 -100.26577) (xy 170.631141 -100.323695)
			(xy 170.608192 -100.379099) (xy 170.578208 -100.431033) (xy 170.541702 -100.478609) (xy 170.499297 -100.521014)
			(xy 170.451721 -100.55752) (xy 170.399787 -100.587504) (xy 170.344383 -100.610453) (xy 170.286458 -100.625974)
			(xy 170.227002 -100.633802) (xy 170.167034 -100.633802) (xy 170.107578 -100.625974) (xy 170.049653 -100.610453)
			(xy 169.994249 -100.587504) (xy 169.942315 -100.55752) (xy 169.894739 -100.521014) (xy 169.852334 -100.478609)
			(xy 169.815828 -100.431033) (xy 169.785844 -100.379099) (xy 169.762895 -100.323695) (xy 169.747374 -100.26577)
			(xy 169.739546 -100.206314) (xy 169.739056 -100.17633) (xy 167.539924 -100.17633) (xy 167.539924 -101.976428)
			(xy 167.884856 -101.976428) (xy 167.884856 -101.112828) (xy 167.885346 -101.082844) (xy 167.893174 -101.023388)
			(xy 167.908695 -100.965463) (xy 167.931644 -100.910059) (xy 167.961628 -100.858125) (xy 167.998134 -100.810549)
			(xy 168.040539 -100.768144) (xy 168.088115 -100.731638) (xy 168.140049 -100.701654) (xy 168.195453 -100.678705)
			(xy 168.253378 -100.663184) (xy 168.312834 -100.655356) (xy 168.372802 -100.655356) (xy 168.432258 -100.663184)
			(xy 168.490183 -100.678705) (xy 168.545587 -100.701654) (xy 168.597521 -100.731638) (xy 168.642788 -100.766372)
			(xy 173.697644 -100.766372) (xy 173.701715 -100.71075) (xy 173.713841 -100.656313) (xy 173.733764 -100.604222)
			(xy 173.76106 -100.555587) (xy 173.795146 -100.511444) (xy 173.835295 -100.472735) (xy 173.880653 -100.440284)
			(xy 173.930253 -100.414783) (xy 173.983037 -100.396776) (xy 174.03788 -100.386646) (xy 174.093614 -100.384609)
			(xy 174.149051 -100.390709) (xy 174.203008 -100.404815) (xy 174.254337 -100.426627) (xy 174.301943 -100.455681)
			(xy 174.344811 -100.491356) (xy 174.382028 -100.532893) (xy 174.412801 -100.579406) (xy 174.436473 -100.629903)
			(xy 174.452541 -100.68331) (xy 174.460661 -100.738486) (xy 174.46117 -100.766372) (xy 174.460661 -100.794258)
			(xy 174.452541 -100.849434) (xy 174.436473 -100.902841) (xy 174.412801 -100.953338) (xy 174.382028 -100.999851)
			(xy 174.344811 -101.041388) (xy 174.301943 -101.077063) (xy 174.254337 -101.106117) (xy 174.203008 -101.127929)
			(xy 174.149051 -101.142035) (xy 174.093614 -101.148135) (xy 174.03788 -101.146098) (xy 173.983037 -101.135968)
			(xy 173.930253 -101.117961) (xy 173.880653 -101.09246) (xy 173.835295 -101.060009) (xy 173.795146 -101.0213)
			(xy 173.76106 -100.977157) (xy 173.733764 -100.928522) (xy 173.713841 -100.876431) (xy 173.701715 -100.821994)
			(xy 173.697644 -100.766372) (xy 168.642788 -100.766372) (xy 168.645097 -100.768144) (xy 168.687502 -100.810549)
			(xy 168.724008 -100.858125) (xy 168.753992 -100.910059) (xy 168.776941 -100.965463) (xy 168.792462 -101.023388)
			(xy 168.80029 -101.082844) (xy 168.80078 -101.112828) (xy 168.80078 -101.240082) (xy 183.371742 -101.240082)
			(xy 183.375813 -101.18446) (xy 183.387939 -101.130023) (xy 183.407862 -101.077932) (xy 183.435158 -101.029297)
			(xy 183.469244 -100.985154) (xy 183.509393 -100.946445) (xy 183.554751 -100.913994) (xy 183.604351 -100.888493)
			(xy 183.657135 -100.870486) (xy 183.711978 -100.860356) (xy 183.767712 -100.858319) (xy 183.823149 -100.864419)
			(xy 183.877106 -100.878525) (xy 183.928435 -100.900337) (xy 183.976041 -100.929391) (xy 184.018909 -100.965066)
			(xy 184.056126 -101.006603) (xy 184.086899 -101.053116) (xy 184.110571 -101.103613) (xy 184.126639 -101.15702)
			(xy 184.134759 -101.212196) (xy 184.135268 -101.240082) (xy 190.393826 -101.240082) (xy 190.397897 -101.18446)
			(xy 190.410023 -101.130023) (xy 190.429946 -101.077932) (xy 190.457242 -101.029297) (xy 190.491328 -100.985154)
			(xy 190.531477 -100.946445) (xy 190.576835 -100.913994) (xy 190.626435 -100.888493) (xy 190.679219 -100.870486)
			(xy 190.734062 -100.860356) (xy 190.789796 -100.858319) (xy 190.845233 -100.864419) (xy 190.89919 -100.878525)
			(xy 190.950519 -100.900337) (xy 190.998125 -100.929391) (xy 191.040993 -100.965066) (xy 191.07821 -101.006603)
			(xy 191.108983 -101.053116) (xy 191.116733 -101.069648) (xy 191.686178 -101.069648) (xy 191.690249 -101.014026)
			(xy 191.702375 -100.959589) (xy 191.722298 -100.907498) (xy 191.749594 -100.858863) (xy 191.78368 -100.81472)
			(xy 191.823829 -100.776011) (xy 191.869187 -100.74356) (xy 191.918787 -100.718059) (xy 191.971571 -100.700052)
			(xy 192.026414 -100.689922) (xy 192.082148 -100.687885) (xy 192.137585 -100.693985) (xy 192.191542 -100.708091)
			(xy 192.242871 -100.729903) (xy 192.290477 -100.758957) (xy 192.333345 -100.794632) (xy 192.370562 -100.836169)
			(xy 192.401335 -100.882682) (xy 192.425007 -100.933179) (xy 192.441075 -100.986586) (xy 192.449195 -101.041762)
			(xy 192.449704 -101.069648) (xy 194.269358 -101.069648) (xy 194.273429 -101.014026) (xy 194.285555 -100.959589)
			(xy 194.305478 -100.907498) (xy 194.332774 -100.858863) (xy 194.36686 -100.81472) (xy 194.407009 -100.776011)
			(xy 194.452367 -100.74356) (xy 194.501967 -100.718059) (xy 194.554751 -100.700052) (xy 194.609594 -100.689922)
			(xy 194.665328 -100.687885) (xy 194.720765 -100.693985) (xy 194.774722 -100.708091) (xy 194.826051 -100.729903)
			(xy 194.873657 -100.758957) (xy 194.916525 -100.794632) (xy 194.953742 -100.836169) (xy 194.984515 -100.882682)
			(xy 195.008187 -100.933179) (xy 195.024255 -100.986586) (xy 195.032375 -101.041762) (xy 195.032884 -101.069648)
			(xy 195.032375 -101.097534) (xy 195.024255 -101.15271) (xy 195.008187 -101.206117) (xy 194.984515 -101.256614)
			(xy 194.953742 -101.303127) (xy 194.916525 -101.344664) (xy 194.873657 -101.380339) (xy 194.826051 -101.409393)
			(xy 194.774722 -101.431205) (xy 194.720765 -101.445311) (xy 194.665328 -101.451411) (xy 194.609594 -101.449374)
			(xy 194.554751 -101.439244) (xy 194.501967 -101.421237) (xy 194.452367 -101.395736) (xy 194.407009 -101.363285)
			(xy 194.36686 -101.324576) (xy 194.332774 -101.280433) (xy 194.305478 -101.231798) (xy 194.285555 -101.179707)
			(xy 194.273429 -101.12527) (xy 194.269358 -101.069648) (xy 192.449704 -101.069648) (xy 192.449195 -101.097534)
			(xy 192.441075 -101.15271) (xy 192.425007 -101.206117) (xy 192.401335 -101.256614) (xy 192.370562 -101.303127)
			(xy 192.333345 -101.344664) (xy 192.290477 -101.380339) (xy 192.242871 -101.409393) (xy 192.191542 -101.431205)
			(xy 192.137585 -101.445311) (xy 192.082148 -101.451411) (xy 192.026414 -101.449374) (xy 191.971571 -101.439244)
			(xy 191.918787 -101.421237) (xy 191.869187 -101.395736) (xy 191.823829 -101.363285) (xy 191.78368 -101.324576)
			(xy 191.749594 -101.280433) (xy 191.722298 -101.231798) (xy 191.702375 -101.179707) (xy 191.690249 -101.12527)
			(xy 191.686178 -101.069648) (xy 191.116733 -101.069648) (xy 191.132655 -101.103613) (xy 191.148723 -101.15702)
			(xy 191.156843 -101.212196) (xy 191.157352 -101.240082) (xy 191.156843 -101.267968) (xy 191.148723 -101.323144)
			(xy 191.132655 -101.376551) (xy 191.108983 -101.427048) (xy 191.07821 -101.473561) (xy 191.040993 -101.515098)
			(xy 190.998125 -101.550773) (xy 190.950519 -101.579827) (xy 190.89919 -101.601639) (xy 190.845233 -101.615745)
			(xy 190.789796 -101.621845) (xy 190.734062 -101.619808) (xy 190.679219 -101.609678) (xy 190.626435 -101.591671)
			(xy 190.576835 -101.56617) (xy 190.531477 -101.533719) (xy 190.491328 -101.49501) (xy 190.457242 -101.450867)
			(xy 190.429946 -101.402232) (xy 190.410023 -101.350141) (xy 190.397897 -101.295704) (xy 190.393826 -101.240082)
			(xy 184.135268 -101.240082) (xy 184.134759 -101.267968) (xy 184.126639 -101.323144) (xy 184.110571 -101.376551)
			(xy 184.086899 -101.427048) (xy 184.056126 -101.473561) (xy 184.018909 -101.515098) (xy 183.976041 -101.550773)
			(xy 183.928435 -101.579827) (xy 183.877106 -101.601639) (xy 183.823149 -101.615745) (xy 183.767712 -101.621845)
			(xy 183.711978 -101.619808) (xy 183.657135 -101.609678) (xy 183.604351 -101.591671) (xy 183.554751 -101.56617)
			(xy 183.509393 -101.533719) (xy 183.469244 -101.49501) (xy 183.435158 -101.450867) (xy 183.407862 -101.402232)
			(xy 183.387939 -101.350141) (xy 183.375813 -101.295704) (xy 183.371742 -101.240082) (xy 168.80078 -101.240082)
			(xy 168.80078 -101.976428) (xy 168.80029 -102.006412) (xy 168.792462 -102.065868) (xy 168.776941 -102.123793)
			(xy 168.753992 -102.179197) (xy 168.724008 -102.231131) (xy 168.687502 -102.278707) (xy 168.645097 -102.321112)
			(xy 168.597521 -102.357618) (xy 168.545587 -102.387602) (xy 168.490183 -102.410551) (xy 168.432258 -102.426072)
			(xy 168.372802 -102.4339) (xy 168.312834 -102.4339) (xy 168.253378 -102.426072) (xy 168.195453 -102.410551)
			(xy 168.140049 -102.387602) (xy 168.088115 -102.357618) (xy 168.040539 -102.321112) (xy 167.998134 -102.278707)
			(xy 167.961628 -102.231131) (xy 167.931644 -102.179197) (xy 167.908695 -102.123793) (xy 167.893174 -102.065868)
			(xy 167.885346 -102.006412) (xy 167.884856 -101.976428) (xy 167.539924 -101.976428) (xy 167.539924 -103.776272)
			(xy 169.739056 -103.776272) (xy 169.739056 -102.912672) (xy 169.739546 -102.882688) (xy 169.747374 -102.823232)
			(xy 169.762895 -102.765307) (xy 169.785844 -102.709903) (xy 169.815828 -102.657969) (xy 169.852334 -102.610393)
			(xy 169.894739 -102.567988) (xy 169.942315 -102.531482) (xy 169.994249 -102.501498) (xy 170.049653 -102.478549)
			(xy 170.107578 -102.463028) (xy 170.167034 -102.4552) (xy 170.227002 -102.4552) (xy 170.286458 -102.463028)
			(xy 170.344383 -102.478549) (xy 170.399787 -102.501498) (xy 170.451721 -102.531482) (xy 170.499297 -102.567988)
			(xy 170.541702 -102.610393) (xy 170.578208 -102.657969) (xy 170.602957 -102.700836) (xy 181.842662 -102.700836)
			(xy 181.846733 -102.645214) (xy 181.858859 -102.590777) (xy 181.878782 -102.538686) (xy 181.906078 -102.490051)
			(xy 181.940164 -102.445908) (xy 181.980313 -102.407199) (xy 182.025671 -102.374748) (xy 182.075271 -102.349247)
			(xy 182.128055 -102.33124) (xy 182.182898 -102.32111) (xy 182.238632 -102.319073) (xy 182.294069 -102.325173)
			(xy 182.348026 -102.339279) (xy 182.399355 -102.361091) (xy 182.446961 -102.390145) (xy 182.489829 -102.42582)
			(xy 182.527046 -102.467357) (xy 182.541365 -102.489) (xy 190.901826 -102.489) (xy 190.905897 -102.433378)
			(xy 190.918023 -102.378941) (xy 190.937946 -102.32685) (xy 190.965242 -102.278215) (xy 190.999328 -102.234072)
			(xy 191.039477 -102.195363) (xy 191.084835 -102.162912) (xy 191.134435 -102.137411) (xy 191.187219 -102.119404)
			(xy 191.242062 -102.109274) (xy 191.297796 -102.107237) (xy 191.353233 -102.113337) (xy 191.40719 -102.127443)
			(xy 191.458519 -102.149255) (xy 191.506125 -102.178309) (xy 191.548993 -102.213984) (xy 191.58621 -102.255521)
			(xy 191.616983 -102.302034) (xy 191.640655 -102.352531) (xy 191.656723 -102.405938) (xy 191.664843 -102.461114)
			(xy 191.665352 -102.489) (xy 191.664843 -102.516886) (xy 191.656723 -102.572062) (xy 191.640655 -102.625469)
			(xy 191.616983 -102.675966) (xy 191.58621 -102.722479) (xy 191.548993 -102.764016) (xy 191.506125 -102.799691)
			(xy 191.458519 -102.828745) (xy 191.40719 -102.850557) (xy 191.353233 -102.864663) (xy 191.297796 -102.870763)
			(xy 191.242062 -102.868726) (xy 191.187219 -102.858596) (xy 191.134435 -102.840589) (xy 191.084835 -102.815088)
			(xy 191.039477 -102.782637) (xy 190.999328 -102.743928) (xy 190.965242 -102.699785) (xy 190.937946 -102.65115)
			(xy 190.918023 -102.599059) (xy 190.905897 -102.544622) (xy 190.901826 -102.489) (xy 182.541365 -102.489)
			(xy 182.557819 -102.51387) (xy 182.581491 -102.564367) (xy 182.597559 -102.617774) (xy 182.605679 -102.67295)
			(xy 182.606188 -102.700836) (xy 182.605679 -102.728722) (xy 182.597559 -102.783898) (xy 182.581491 -102.837305)
			(xy 182.564854 -102.872794) (xy 200.171556 -102.872794) (xy 200.175627 -102.817172) (xy 200.187753 -102.762735)
			(xy 200.207676 -102.710644) (xy 200.234972 -102.662009) (xy 200.269058 -102.617866) (xy 200.309207 -102.579157)
			(xy 200.354565 -102.546706) (xy 200.404165 -102.521205) (xy 200.456949 -102.503198) (xy 200.511792 -102.493068)
			(xy 200.567526 -102.491031) (xy 200.622963 -102.497131) (xy 200.67692 -102.511237) (xy 200.728249 -102.533049)
			(xy 200.775855 -102.562103) (xy 200.818723 -102.597778) (xy 200.85594 -102.639315) (xy 200.886713 -102.685828)
			(xy 200.910385 -102.736325) (xy 200.926453 -102.789732) (xy 200.934573 -102.844908) (xy 200.935082 -102.872794)
			(xy 200.934573 -102.90068) (xy 200.926453 -102.955856) (xy 200.910385 -103.009263) (xy 200.886713 -103.05976)
			(xy 200.85594 -103.106273) (xy 200.818723 -103.14781) (xy 200.775855 -103.183485) (xy 200.728249 -103.212539)
			(xy 200.67692 -103.234351) (xy 200.622963 -103.248457) (xy 200.567526 -103.254557) (xy 200.511792 -103.25252)
			(xy 200.456949 -103.24239) (xy 200.404165 -103.224383) (xy 200.354565 -103.198882) (xy 200.309207 -103.166431)
			(xy 200.269058 -103.127722) (xy 200.234972 -103.083579) (xy 200.207676 -103.034944) (xy 200.187753 -102.982853)
			(xy 200.175627 -102.928416) (xy 200.171556 -102.872794) (xy 182.564854 -102.872794) (xy 182.557819 -102.887802)
			(xy 182.527046 -102.934315) (xy 182.489829 -102.975852) (xy 182.446961 -103.011527) (xy 182.399355 -103.040581)
			(xy 182.348026 -103.062393) (xy 182.294069 -103.076499) (xy 182.238632 -103.082599) (xy 182.182898 -103.080562)
			(xy 182.128055 -103.070432) (xy 182.075271 -103.052425) (xy 182.025671 -103.026924) (xy 181.980313 -102.994473)
			(xy 181.940164 -102.955764) (xy 181.906078 -102.911621) (xy 181.878782 -102.862986) (xy 181.858859 -102.810895)
			(xy 181.846733 -102.756458) (xy 181.842662 -102.700836) (xy 170.602957 -102.700836) (xy 170.608192 -102.709903)
			(xy 170.631141 -102.765307) (xy 170.646662 -102.823232) (xy 170.65449 -102.882688) (xy 170.65498 -102.912672)
			(xy 170.65498 -103.776272) (xy 170.65449 -103.806256) (xy 170.646662 -103.865712) (xy 170.641226 -103.886)
			(xy 191.409826 -103.886) (xy 191.413897 -103.830378) (xy 191.426023 -103.775941) (xy 191.445946 -103.72385)
			(xy 191.473242 -103.675215) (xy 191.507328 -103.631072) (xy 191.547477 -103.592363) (xy 191.592835 -103.559912)
			(xy 191.642435 -103.534411) (xy 191.695219 -103.516404) (xy 191.750062 -103.506274) (xy 191.805796 -103.504237)
			(xy 191.861233 -103.510337) (xy 191.91519 -103.524443) (xy 191.966519 -103.546255) (xy 192.014125 -103.575309)
			(xy 192.056993 -103.610984) (xy 192.09421 -103.652521) (xy 192.124983 -103.699034) (xy 192.148655 -103.749531)
			(xy 192.164723 -103.802938) (xy 192.172843 -103.858114) (xy 192.173352 -103.886) (xy 192.172843 -103.913886)
			(xy 192.164723 -103.969062) (xy 192.151351 -104.013508) (xy 201.266804 -104.013508) (xy 201.270875 -103.957886)
			(xy 201.283001 -103.903449) (xy 201.302924 -103.851358) (xy 201.33022 -103.802723) (xy 201.364306 -103.75858)
			(xy 201.404455 -103.719871) (xy 201.449813 -103.68742) (xy 201.499413 -103.661919) (xy 201.552197 -103.643912)
			(xy 201.60704 -103.633782) (xy 201.662774 -103.631745) (xy 201.718211 -103.637845) (xy 201.772168 -103.651951)
			(xy 201.823497 -103.673763) (xy 201.871103 -103.702817) (xy 201.913971 -103.738492) (xy 201.951188 -103.780029)
			(xy 201.981961 -103.826542) (xy 202.005633 -103.877039) (xy 202.021701 -103.930446) (xy 202.029821 -103.985622)
			(xy 202.03033 -104.013508) (xy 202.029821 -104.041394) (xy 202.021701 -104.09657) (xy 202.005633 -104.149977)
			(xy 201.981961 -104.200474) (xy 201.951188 -104.246987) (xy 201.913971 -104.288524) (xy 201.871103 -104.324199)
			(xy 201.823497 -104.353253) (xy 201.772168 -104.375065) (xy 201.718211 -104.389171) (xy 201.662774 -104.395271)
			(xy 201.60704 -104.393234) (xy 201.552197 -104.383104) (xy 201.499413 -104.365097) (xy 201.449813 -104.339596)
			(xy 201.404455 -104.307145) (xy 201.364306 -104.268436) (xy 201.33022 -104.224293) (xy 201.302924 -104.175658)
			(xy 201.283001 -104.123567) (xy 201.270875 -104.06913) (xy 201.266804 -104.013508) (xy 192.151351 -104.013508)
			(xy 192.148655 -104.022469) (xy 192.124983 -104.072966) (xy 192.09421 -104.119479) (xy 192.056993 -104.161016)
			(xy 192.014125 -104.196691) (xy 191.966519 -104.225745) (xy 191.91519 -104.247557) (xy 191.861233 -104.261663)
			(xy 191.805796 -104.267763) (xy 191.750062 -104.265726) (xy 191.695219 -104.255596) (xy 191.642435 -104.237589)
			(xy 191.592835 -104.212088) (xy 191.547477 -104.179637) (xy 191.507328 -104.140928) (xy 191.473242 -104.096785)
			(xy 191.445946 -104.04815) (xy 191.426023 -103.996059) (xy 191.413897 -103.941622) (xy 191.409826 -103.886)
			(xy 170.641226 -103.886) (xy 170.631141 -103.923637) (xy 170.608192 -103.979041) (xy 170.578208 -104.030975)
			(xy 170.541702 -104.078551) (xy 170.499297 -104.120956) (xy 170.451721 -104.157462) (xy 170.399787 -104.187446)
			(xy 170.344383 -104.210395) (xy 170.286458 -104.225916) (xy 170.227002 -104.233744) (xy 170.167034 -104.233744)
			(xy 170.107578 -104.225916) (xy 170.049653 -104.210395) (xy 169.994249 -104.187446) (xy 169.942315 -104.157462)
			(xy 169.894739 -104.120956) (xy 169.852334 -104.078551) (xy 169.815828 -104.030975) (xy 169.785844 -103.979041)
			(xy 169.762895 -103.923637) (xy 169.747374 -103.865712) (xy 169.739546 -103.806256) (xy 169.739056 -103.776272)
			(xy 167.539924 -103.776272) (xy 167.539924 -105.57637) (xy 167.884856 -105.57637) (xy 167.884856 -104.71277)
			(xy 167.885346 -104.682786) (xy 167.893174 -104.62333) (xy 167.908695 -104.565405) (xy 167.931644 -104.510001)
			(xy 167.961628 -104.458067) (xy 167.998134 -104.410491) (xy 168.040539 -104.368086) (xy 168.088115 -104.33158)
			(xy 168.140049 -104.301596) (xy 168.195453 -104.278647) (xy 168.253378 -104.263126) (xy 168.312834 -104.255298)
			(xy 168.372802 -104.255298) (xy 168.432258 -104.263126) (xy 168.490183 -104.278647) (xy 168.545587 -104.301596)
			(xy 168.597521 -104.33158) (xy 168.645097 -104.368086) (xy 168.661867 -104.384856) (xy 181.762652 -104.384856)
			(xy 181.766723 -104.329234) (xy 181.778849 -104.274797) (xy 181.798772 -104.222706) (xy 181.826068 -104.174071)
			(xy 181.860154 -104.129928) (xy 181.900303 -104.091219) (xy 181.945661 -104.058768) (xy 181.995261 -104.033267)
			(xy 182.048045 -104.01526) (xy 182.102888 -104.00513) (xy 182.158622 -104.003093) (xy 182.214059 -104.009193)
			(xy 182.268016 -104.023299) (xy 182.319345 -104.045111) (xy 182.366951 -104.074165) (xy 182.409819 -104.10984)
			(xy 182.447036 -104.151377) (xy 182.477809 -104.19789) (xy 182.501481 -104.248387) (xy 182.517549 -104.301794)
			(xy 182.525669 -104.35697) (xy 182.526178 -104.384856) (xy 182.525669 -104.412742) (xy 182.517549 -104.467918)
			(xy 182.501481 -104.521325) (xy 182.477809 -104.571822) (xy 182.447036 -104.618335) (xy 182.409819 -104.659872)
			(xy 182.366951 -104.695547) (xy 182.319345 -104.724601) (xy 182.268016 -104.746413) (xy 182.214059 -104.760519)
			(xy 182.158622 -104.766619) (xy 182.102888 -104.764582) (xy 182.048045 -104.754452) (xy 181.995261 -104.736445)
			(xy 181.945661 -104.710944) (xy 181.900303 -104.678493) (xy 181.860154 -104.639784) (xy 181.826068 -104.595641)
			(xy 181.798772 -104.547006) (xy 181.778849 -104.494915) (xy 181.766723 -104.440478) (xy 181.762652 -104.384856)
			(xy 168.661867 -104.384856) (xy 168.687502 -104.410491) (xy 168.724008 -104.458067) (xy 168.753992 -104.510001)
			(xy 168.776941 -104.565405) (xy 168.792462 -104.62333) (xy 168.80029 -104.682786) (xy 168.80078 -104.71277)
			(xy 168.80078 -105.57637) (xy 168.80029 -105.606354) (xy 168.792462 -105.66581) (xy 168.776941 -105.723735)
			(xy 168.753992 -105.779139) (xy 168.724008 -105.831073) (xy 168.687502 -105.878649) (xy 168.645097 -105.921054)
			(xy 168.597521 -105.95756) (xy 168.545587 -105.987544) (xy 168.490183 -106.010493) (xy 168.432258 -106.026014)
			(xy 168.372802 -106.033842) (xy 168.312834 -106.033842) (xy 168.253378 -106.026014) (xy 168.195453 -106.010493)
			(xy 168.140049 -105.987544) (xy 168.088115 -105.95756) (xy 168.040539 -105.921054) (xy 167.998134 -105.878649)
			(xy 167.961628 -105.831073) (xy 167.931644 -105.779139) (xy 167.908695 -105.723735) (xy 167.893174 -105.66581)
			(xy 167.885346 -105.606354) (xy 167.884856 -105.57637) (xy 167.539924 -105.57637) (xy 167.539924 -107.376214)
			(xy 169.739056 -107.376214) (xy 169.739056 -106.512614) (xy 169.739546 -106.48263) (xy 169.747374 -106.423174)
			(xy 169.762895 -106.365249) (xy 169.785844 -106.309845) (xy 169.815828 -106.257911) (xy 169.852334 -106.210335)
			(xy 169.894739 -106.16793) (xy 169.942315 -106.131424) (xy 169.994249 -106.10144) (xy 170.049653 -106.078491)
			(xy 170.107578 -106.06297) (xy 170.167034 -106.055142) (xy 170.227002 -106.055142) (xy 170.286458 -106.06297)
			(xy 170.344383 -106.078491) (xy 170.399787 -106.10144) (xy 170.451721 -106.131424) (xy 170.499297 -106.16793)
			(xy 170.541702 -106.210335) (xy 170.578208 -106.257911) (xy 170.608192 -106.309845) (xy 170.631141 -106.365249)
			(xy 170.646662 -106.423174) (xy 170.65449 -106.48263) (xy 170.65498 -106.512614) (xy 170.65498 -107.376214)
			(xy 170.65449 -107.406198) (xy 170.646662 -107.465654) (xy 170.631141 -107.523579) (xy 170.608192 -107.578983)
			(xy 170.578208 -107.630917) (xy 170.541702 -107.678493) (xy 170.499297 -107.720898) (xy 170.451721 -107.757404)
			(xy 170.399787 -107.787388) (xy 170.344383 -107.810337) (xy 170.286458 -107.825858) (xy 170.227002 -107.833686)
			(xy 170.167034 -107.833686) (xy 170.107578 -107.825858) (xy 170.049653 -107.810337) (xy 169.994249 -107.787388)
			(xy 169.942315 -107.757404) (xy 169.894739 -107.720898) (xy 169.852334 -107.678493) (xy 169.815828 -107.630917)
			(xy 169.785844 -107.578983) (xy 169.762895 -107.523579) (xy 169.747374 -107.465654) (xy 169.739546 -107.406198)
			(xy 169.739056 -107.376214) (xy 167.539924 -107.376214) (xy 167.539924 -109.176312) (xy 167.884856 -109.176312)
			(xy 167.884856 -108.312712) (xy 167.885346 -108.282728) (xy 167.893174 -108.223272) (xy 167.908695 -108.165347)
			(xy 167.931644 -108.109943) (xy 167.961628 -108.058009) (xy 167.998134 -108.010433) (xy 168.040539 -107.968028)
			(xy 168.088115 -107.931522) (xy 168.140049 -107.901538) (xy 168.195453 -107.878589) (xy 168.253378 -107.863068)
			(xy 168.312834 -107.85524) (xy 168.372802 -107.85524) (xy 168.432258 -107.863068) (xy 168.490183 -107.878589)
			(xy 168.545587 -107.901538) (xy 168.597521 -107.931522) (xy 168.645097 -107.968028) (xy 168.687502 -108.010433)
			(xy 168.713438 -108.044234) (xy 198.958708 -108.044234) (xy 198.959194 -108.016983) (xy 198.96695 -107.963035)
			(xy 198.982305 -107.91074) (xy 199.004947 -107.861163) (xy 199.034413 -107.815313) (xy 199.070104 -107.774122)
			(xy 199.111295 -107.738431) (xy 199.157145 -107.708965) (xy 199.206722 -107.686323) (xy 199.259017 -107.670968)
			(xy 199.312965 -107.663212) (xy 199.367467 -107.663212) (xy 199.421415 -107.670968) (xy 199.47371 -107.686323)
			(xy 199.523287 -107.708965) (xy 199.569137 -107.738431) (xy 199.610328 -107.774122) (xy 199.646019 -107.815313)
			(xy 199.675485 -107.861163) (xy 199.698127 -107.91074) (xy 199.713482 -107.963035) (xy 199.721238 -108.016983)
			(xy 199.721724 -108.044234) (xy 199.721188 -108.071805) (xy 199.713246 -108.126373) (xy 199.697531 -108.17923)
			(xy 199.674372 -108.229273) (xy 199.644251 -108.275463) (xy 199.607794 -108.316835) (xy 199.565762 -108.352529)
			(xy 199.542654 -108.367576) (xy 199.530079 -108.376034) (xy 199.510215 -108.398904) (xy 199.497933 -108.426595)
			(xy 199.494314 -108.45667) (xy 199.499675 -108.486484) (xy 199.513547 -108.513414) (xy 199.534707 -108.53509)
			(xy 199.547734 -108.542836) (xy 199.573125 -108.557309) (xy 199.619559 -108.592795) (xy 199.660042 -108.634944)
			(xy 199.693626 -108.682772) (xy 199.719528 -108.73516) (xy 199.737142 -108.790884) (xy 199.746056 -108.848641)
			(xy 199.746616 -108.877862) (xy 199.74613 -108.905113) (xy 199.738374 -108.959061) (xy 199.723019 -109.011356)
			(xy 199.700377 -109.060933) (xy 199.670911 -109.106783) (xy 199.63522 -109.147974) (xy 199.594029 -109.183665)
			(xy 199.548179 -109.213131) (xy 199.498602 -109.235773) (xy 199.446307 -109.251128) (xy 199.392359 -109.258884)
			(xy 199.337857 -109.258884) (xy 199.283909 -109.251128) (xy 199.231614 -109.235773) (xy 199.182037 -109.213131)
			(xy 199.136187 -109.183665) (xy 199.094996 -109.147974) (xy 199.059305 -109.106783) (xy 199.029839 -109.060933)
			(xy 199.007197 -109.011356) (xy 198.991842 -108.959061) (xy 198.984086 -108.905113) (xy 198.9836 -108.877862)
			(xy 198.984122 -108.85029) (xy 198.992065 -108.795721) (xy 199.007781 -108.742864) (xy 199.030943 -108.692819)
			(xy 199.061066 -108.64663) (xy 199.097525 -108.605259) (xy 199.13956 -108.569566) (xy 199.16267 -108.55452)
			(xy 199.175246 -108.546064) (xy 199.195105 -108.523192) (xy 199.207383 -108.495502) (xy 199.211001 -108.465428)
			(xy 199.20564 -108.435615) (xy 199.191772 -108.408686) (xy 199.170615 -108.387008) (xy 199.15759 -108.37926)
			(xy 199.132203 -108.36478) (xy 199.085768 -108.329297) (xy 199.045284 -108.287149) (xy 199.011698 -108.239323)
			(xy 198.985795 -108.186935) (xy 198.968181 -108.131212) (xy 198.959268 -108.073455) (xy 198.958708 -108.044234)
			(xy 168.713438 -108.044234) (xy 168.724008 -108.058009) (xy 168.753992 -108.109943) (xy 168.776941 -108.165347)
			(xy 168.792462 -108.223272) (xy 168.80029 -108.282728) (xy 168.80078 -108.312712) (xy 168.80078 -109.176312)
			(xy 168.80029 -109.206296) (xy 168.792462 -109.265752) (xy 168.776941 -109.323677) (xy 168.753992 -109.379081)
			(xy 168.724008 -109.431015) (xy 168.687502 -109.478591) (xy 168.645097 -109.520996) (xy 168.597521 -109.557502)
			(xy 168.545587 -109.587486) (xy 168.490183 -109.610435) (xy 168.432258 -109.625956) (xy 168.372802 -109.633784)
			(xy 168.312834 -109.633784) (xy 168.253378 -109.625956) (xy 168.195453 -109.610435) (xy 168.140049 -109.587486)
			(xy 168.088115 -109.557502) (xy 168.040539 -109.520996) (xy 167.998134 -109.478591) (xy 167.961628 -109.431015)
			(xy 167.931644 -109.379081) (xy 167.908695 -109.323677) (xy 167.893174 -109.265752) (xy 167.885346 -109.206296)
			(xy 167.884856 -109.176312) (xy 167.539924 -109.176312) (xy 167.539924 -110.97641) (xy 169.739056 -110.97641)
			(xy 169.739056 -110.11281) (xy 169.739546 -110.082826) (xy 169.747374 -110.02337) (xy 169.762895 -109.965445)
			(xy 169.785844 -109.910041) (xy 169.815828 -109.858107) (xy 169.852334 -109.810531) (xy 169.894739 -109.768126)
			(xy 169.942315 -109.73162) (xy 169.994249 -109.701636) (xy 170.049653 -109.678687) (xy 170.107578 -109.663166)
			(xy 170.167034 -109.655338) (xy 170.227002 -109.655338) (xy 170.286458 -109.663166) (xy 170.344383 -109.678687)
			(xy 170.399787 -109.701636) (xy 170.451721 -109.73162) (xy 170.499297 -109.768126) (xy 170.541702 -109.810531)
			(xy 170.578208 -109.858107) (xy 170.608192 -109.910041) (xy 170.631141 -109.965445) (xy 170.646662 -110.02337)
			(xy 170.65449 -110.082826) (xy 170.65498 -110.11281) (xy 170.65498 -110.97641) (xy 170.65449 -111.006394)
			(xy 170.646662 -111.06585) (xy 170.631141 -111.123775) (xy 170.608192 -111.179179) (xy 170.578208 -111.231113)
			(xy 170.541702 -111.278689) (xy 170.499297 -111.321094) (xy 170.451721 -111.3576) (xy 170.399787 -111.387584)
			(xy 170.344383 -111.410533) (xy 170.286458 -111.426054) (xy 170.227002 -111.433882) (xy 170.167034 -111.433882)
			(xy 170.107578 -111.426054) (xy 170.049653 -111.410533) (xy 169.994249 -111.387584) (xy 169.942315 -111.3576)
			(xy 169.894739 -111.321094) (xy 169.852334 -111.278689) (xy 169.815828 -111.231113) (xy 169.785844 -111.179179)
			(xy 169.762895 -111.123775) (xy 169.747374 -111.06585) (xy 169.739546 -111.006394) (xy 169.739056 -110.97641)
			(xy 167.539924 -110.97641) (xy 167.539924 -112.776508) (xy 167.884856 -112.776508) (xy 167.884856 -111.912908)
			(xy 167.885346 -111.882924) (xy 167.893174 -111.823468) (xy 167.908695 -111.765543) (xy 167.931644 -111.710139)
			(xy 167.961628 -111.658205) (xy 167.998134 -111.610629) (xy 168.040539 -111.568224) (xy 168.088115 -111.531718)
			(xy 168.140049 -111.501734) (xy 168.195453 -111.478785) (xy 168.253378 -111.463264) (xy 168.312834 -111.455436)
			(xy 168.372802 -111.455436) (xy 168.432258 -111.463264) (xy 168.490183 -111.478785) (xy 168.545587 -111.501734)
			(xy 168.597521 -111.531718) (xy 168.645097 -111.568224) (xy 168.687502 -111.610629) (xy 168.724008 -111.658205)
			(xy 168.753992 -111.710139) (xy 168.776941 -111.765543) (xy 168.792462 -111.823468) (xy 168.80029 -111.882924)
			(xy 168.80078 -111.912908) (xy 168.80078 -112.776508) (xy 168.80029 -112.806492) (xy 168.792462 -112.865948)
			(xy 168.776941 -112.923873) (xy 168.753992 -112.979277) (xy 168.724008 -113.031211) (xy 168.687502 -113.078787)
			(xy 168.645097 -113.121192) (xy 168.597521 -113.157698) (xy 168.545587 -113.187682) (xy 168.490183 -113.210631)
			(xy 168.432258 -113.226152) (xy 168.372802 -113.23398) (xy 168.312834 -113.23398) (xy 168.253378 -113.226152)
			(xy 168.195453 -113.210631) (xy 168.140049 -113.187682) (xy 168.088115 -113.157698) (xy 168.040539 -113.121192)
			(xy 167.998134 -113.078787) (xy 167.961628 -113.031211) (xy 167.931644 -112.979277) (xy 167.908695 -112.923873)
			(xy 167.893174 -112.865948) (xy 167.885346 -112.806492) (xy 167.884856 -112.776508) (xy 167.539924 -112.776508)
			(xy 167.539924 -113.27765) (xy 167.540369 -113.287717) (xy 167.548075 -113.306315) (xy 167.55491 -113.313718)
			(xy 170.95343 -116.712238) (xy 170.960821 -116.719089) (xy 170.979427 -116.726801) (xy 170.989498 -116.727224)
			(xy 171.186856 -116.727224) (xy 171.212881 -116.72773) (xy 171.264286 -116.7359) (xy 171.313783 -116.751998)
			(xy 171.360159 -116.775631) (xy 171.402275 -116.806217) (xy 171.421044 -116.824252) (xy 172.048678 -117.451886)
			(xy 172.07865 -117.457728) (xy 172.092874 -117.451886) (xy 172.101902 -117.447566) (xy 172.115987 -117.433373)
			(xy 172.12362 -117.414893) (xy 172.124116 -117.404896) (xy 172.124116 -116.167662) (xy 172.123447 -116.155694)
			(xy 172.112562 -116.134366) (xy 172.103288 -116.126768) (xy 172.079595 -116.108643) (xy 172.037601 -116.066282)
			(xy 172.002708 -116.017903) (xy 171.975768 -115.964684) (xy 171.957436 -115.907922) (xy 171.948159 -115.848999)
			(xy 171.947586 -115.819174) (xy 171.948054 -115.791922) (xy 171.955813 -115.737974) (xy 171.971172 -115.68568)
			(xy 171.993815 -115.636103) (xy 172.023284 -115.590253) (xy 172.058977 -115.549063) (xy 172.100169 -115.513372)
			(xy 172.14602 -115.483906) (xy 172.195598 -115.461265) (xy 172.247894 -115.445909) (xy 172.301842 -115.438152)
			(xy 172.329094 -115.437666) (xy 172.356086 -115.438127) (xy 172.409534 -115.445724) (xy 172.461376 -115.460781)
			(xy 172.510578 -115.482997) (xy 172.556156 -115.511928) (xy 172.597199 -115.546997) (xy 172.632887 -115.587503)
			(xy 172.662508 -115.632635) (xy 172.685469 -115.681494) (xy 172.693838 -115.70716) (xy 172.695546 -115.712304)
			(xy 172.700793 -115.721784) (xy 172.704252 -115.725956) (xy 172.719938 -115.744257) (xy 172.746414 -115.784533)
			(xy 172.766783 -115.828217) (xy 172.780617 -115.874388) (xy 172.787624 -115.922075) (xy 172.788072 -115.946174)
			(xy 172.788072 -118.356634) (xy 172.80509 -118.382034) (xy 172.819314 -118.387876) (xy 172.828757 -118.391282)
			(xy 172.848814 -118.391248) (xy 172.867322 -118.38352) (xy 172.874686 -118.3767) (xy 180.331618 -110.919768)
			(xy 180.35518 -110.896833) (xy 180.406593 -110.855839) (xy 180.46227 -110.820853) (xy 180.52151 -110.792316)
			(xy 180.583572 -110.770584) (xy 180.647675 -110.755931) (xy 180.713014 -110.748541) (xy 180.745892 -110.748064)
			(xy 180.7813 -110.748597) (xy 180.851599 -110.757134) (xy 180.920356 -110.774085) (xy 180.986568 -110.799203)
			(xy 181.049268 -110.83212) (xy 181.107542 -110.872356) (xy 181.16054 -110.919326) (xy 181.207488 -110.972342)
			(xy 181.247702 -111.030632) (xy 181.280594 -111.093346) (xy 181.305684 -111.159567) (xy 181.322608 -111.228331)
			(xy 181.331117 -111.298634) (xy 181.331616 -111.334042) (xy 181.331144 -111.366913) (xy 181.323803 -111.432244)
			(xy 181.309194 -111.496342) (xy 181.287501 -111.558402) (xy 181.258998 -111.617643) (xy 181.224042 -111.673322)
			(xy 181.183074 -111.724737) (xy 181.160166 -111.748316) (xy 180.927647 -111.980726) (xy 190.001398 -111.980726)
			(xy 190.001938 -111.951988) (xy 190.010557 -111.895161) (xy 190.027603 -111.840271) (xy 190.052691 -111.788559)
			(xy 190.085253 -111.741195) (xy 190.104522 -111.719868) (xy 190.111126 -111.71301) (xy 190.118238 -111.694976)
			(xy 190.118238 -111.606076) (xy 190.111126 -111.588042) (xy 190.104522 -111.581184) (xy 190.085277 -111.559835)
			(xy 190.052711 -111.512476) (xy 190.027618 -111.460768) (xy 190.010566 -111.405881) (xy 190.001941 -111.349056)
			(xy 190.001939 -111.291581) (xy 190.010558 -111.234756) (xy 190.027604 -111.179867) (xy 190.052692 -111.128157)
			(xy 190.085253 -111.080795) (xy 190.104522 -111.059468) (xy 190.111126 -111.05261) (xy 190.118238 -111.034576)
			(xy 190.118238 -110.945676) (xy 190.111126 -110.927642) (xy 190.104522 -110.920784) (xy 190.085277 -110.899435)
			(xy 190.052711 -110.852076) (xy 190.027618 -110.800368) (xy 190.010566 -110.745481) (xy 190.001941 -110.688656)
			(xy 190.001939 -110.631181) (xy 190.010558 -110.574356) (xy 190.027604 -110.519467) (xy 190.052692 -110.467757)
			(xy 190.085253 -110.420395) (xy 190.104522 -110.399068) (xy 190.111126 -110.39221) (xy 190.118238 -110.374176)
			(xy 190.118238 -110.285276) (xy 190.111126 -110.267242) (xy 190.104522 -110.260384) (xy 190.085277 -110.239035)
			(xy 190.052711 -110.191676) (xy 190.027618 -110.139968) (xy 190.010566 -110.085081) (xy 190.001941 -110.028256)
			(xy 190.001939 -109.970781) (xy 190.010558 -109.913956) (xy 190.027604 -109.859067) (xy 190.052692 -109.807357)
			(xy 190.085253 -109.759995) (xy 190.104522 -109.738668) (xy 190.111126 -109.73181) (xy 190.118238 -109.713776)
			(xy 190.118238 -109.624876) (xy 190.111126 -109.606842) (xy 190.104522 -109.599984) (xy 190.085261 -109.578649)
			(xy 190.052694 -109.531289) (xy 190.0276 -109.479579) (xy 190.010547 -109.42469) (xy 190.001921 -109.367864)
			(xy 190.001398 -109.339126) (xy 190.00188 -109.311874) (xy 190.009633 -109.257923) (xy 190.024986 -109.205625)
			(xy 190.047626 -109.156045) (xy 190.077092 -109.110191) (xy 190.112784 -109.068998) (xy 190.153975 -109.033304)
			(xy 190.199827 -109.003836) (xy 190.249406 -108.981193) (xy 190.301703 -108.965837) (xy 190.355654 -108.958081)
			(xy 190.382906 -108.957618) (xy 190.40922 -108.958076) (xy 190.46135 -108.965312) (xy 190.511993 -108.979632)
			(xy 190.560192 -109.000767) (xy 190.605035 -109.028315) (xy 190.645674 -109.061755) (xy 190.66383 -109.080808)
			(xy 190.671338 -109.088226) (xy 190.690628 -109.09674) (xy 190.701168 -109.097318) (xy 190.775844 -109.097318)
			(xy 190.786391 -109.096767) (xy 190.805686 -109.088247) (xy 190.813182 -109.080808) (xy 190.831355 -109.06177)
			(xy 190.871981 -109.028311) (xy 190.916817 -109.000749) (xy 190.965015 -108.979608) (xy 191.015659 -108.965287)
			(xy 191.067791 -108.958058) (xy 191.094106 -108.957618) (xy 191.12136 -108.95805) (xy 191.175314 -108.965808)
			(xy 191.227614 -108.981166) (xy 191.277195 -109.003811) (xy 191.32305 -109.033283) (xy 191.364243 -109.06898)
			(xy 191.399937 -109.110176) (xy 191.429404 -109.156033) (xy 191.452045 -109.205616) (xy 191.467399 -109.257918)
			(xy 191.475152 -109.311872) (xy 191.475614 -109.339126) (xy 191.475102 -109.367865) (xy 191.466476 -109.424693)
			(xy 191.449423 -109.479584) (xy 191.424329 -109.531295) (xy 191.391762 -109.578657) (xy 191.37249 -109.599984)
			(xy 191.365886 -109.606842) (xy 191.358774 -109.624876) (xy 191.358774 -109.713776) (xy 191.365886 -109.73181)
			(xy 191.37249 -109.738668) (xy 191.391786 -109.759973) (xy 191.424349 -109.807339) (xy 191.449438 -109.859055)
			(xy 191.466486 -109.913949) (xy 191.475106 -109.970779) (xy 191.475103 -110.028259) (xy 191.466477 -110.085088)
			(xy 191.449424 -110.13998) (xy 191.42433 -110.191693) (xy 191.391762 -110.239057) (xy 191.37249 -110.260384)
			(xy 191.365886 -110.267242) (xy 191.358774 -110.285276) (xy 191.358774 -110.374176) (xy 191.365886 -110.39221)
			(xy 191.37249 -110.399068) (xy 191.391786 -110.420373) (xy 191.424349 -110.467739) (xy 191.449438 -110.519455)
			(xy 191.466486 -110.574349) (xy 191.475106 -110.631179) (xy 191.475106 -110.631732) (xy 209.194654 -110.631732)
			(xy 209.195149 -110.602992) (xy 209.20378 -110.546164) (xy 209.220838 -110.491273) (xy 209.245935 -110.439562)
			(xy 209.278505 -110.392201) (xy 209.297778 -110.370874) (xy 209.304382 -110.364016) (xy 209.311494 -110.345982)
			(xy 209.311494 -110.257082) (xy 209.304382 -110.239048) (xy 209.297778 -110.23219) (xy 209.278541 -110.210835)
			(xy 209.245979 -110.163476) (xy 209.220888 -110.111768) (xy 209.203838 -110.056882) (xy 209.195214 -110.00006)
			(xy 209.19521 -109.942587) (xy 209.203828 -109.885763) (xy 209.220871 -109.830875) (xy 209.245955 -109.779165)
			(xy 209.278512 -109.731802) (xy 209.297778 -109.710474) (xy 209.304382 -109.703616) (xy 209.311494 -109.685582)
			(xy 209.311494 -109.596682) (xy 209.304382 -109.578648) (xy 209.297778 -109.57179) (xy 209.278529 -109.550444)
			(xy 209.245958 -109.503088) (xy 209.220861 -109.451381) (xy 209.203805 -109.396494) (xy 209.195177 -109.33967)
			(xy 209.194654 -109.310932) (xy 209.19514 -109.283681) (xy 209.202896 -109.229733) (xy 209.218251 -109.177438)
			(xy 209.240893 -109.127861) (xy 209.270359 -109.082011) (xy 209.30605 -109.04082) (xy 209.347241 -109.005129)
			(xy 209.393091 -108.975663) (xy 209.442668 -108.953021) (xy 209.494963 -108.937666) (xy 209.548911 -108.92991)
			(xy 209.603413 -108.92991) (xy 209.657361 -108.937666) (xy 209.709656 -108.953021) (xy 209.759233 -108.975663)
			(xy 209.805083 -109.005129) (xy 209.846274 -109.04082) (xy 209.881965 -109.082011) (xy 209.911431 -109.127861)
			(xy 209.934073 -109.177438) (xy 209.949428 -109.229733) (xy 209.957184 -109.283681) (xy 209.95767 -109.310932)
			(xy 209.957147 -109.339671) (xy 209.948521 -109.396497) (xy 209.93147 -109.451387) (xy 209.906379 -109.503099)
			(xy 209.873815 -109.550462) (xy 209.854546 -109.57179) (xy 209.847942 -109.578648) (xy 209.84083 -109.596682)
			(xy 209.84083 -109.685582) (xy 209.847942 -109.703616) (xy 209.854546 -109.710474) (xy 209.87385 -109.731773)
			(xy 209.906417 -109.779139) (xy 209.931508 -109.830855) (xy 209.948558 -109.885751) (xy 209.957178 -109.942582)
			(xy 209.957174 -110.000064) (xy 209.948547 -110.056895) (xy 209.931491 -110.111788) (xy 209.906393 -110.163501)
			(xy 209.873821 -110.210864) (xy 209.854546 -110.23219) (xy 209.847942 -110.239048) (xy 209.84083 -110.257082)
			(xy 209.84083 -110.345982) (xy 209.847942 -110.364016) (xy 209.854546 -110.370874) (xy 209.873829 -110.39219)
			(xy 209.906394 -110.439555) (xy 209.931485 -110.491269) (xy 209.948532 -110.546163) (xy 209.957151 -110.602992)
			(xy 209.95767 -110.631732) (xy 209.957184 -110.658983) (xy 209.956428 -110.664244) (xy 210.788504 -110.664244)
			(xy 210.788993 -110.635504) (xy 210.797624 -110.578675) (xy 210.814682 -110.523784) (xy 210.839781 -110.472072)
			(xy 210.872354 -110.424712) (xy 210.891628 -110.403386) (xy 210.898232 -110.396528) (xy 210.905344 -110.378494)
			(xy 210.905344 -110.289594) (xy 210.898232 -110.27156) (xy 210.891628 -110.264702) (xy 210.872401 -110.243337)
			(xy 210.839834 -110.195982) (xy 210.814739 -110.144276) (xy 210.797686 -110.089391) (xy 210.789059 -110.032569)
			(xy 210.789054 -109.975095) (xy 210.797671 -109.918272) (xy 210.814716 -109.863384) (xy 210.839801 -109.811674)
			(xy 210.87236 -109.764313) (xy 210.891628 -109.742986) (xy 210.898232 -109.736128) (xy 210.905344 -109.718094)
			(xy 210.905344 -109.629194) (xy 210.898232 -109.61116) (xy 210.891628 -109.604302) (xy 210.872329 -109.582999)
			(xy 210.839767 -109.535631) (xy 210.81468 -109.483913) (xy 210.797636 -109.429017) (xy 210.789021 -109.372185)
			(xy 210.788504 -109.343444) (xy 210.78899 -109.316193) (xy 210.796746 -109.262245) (xy 210.812101 -109.20995)
			(xy 210.834743 -109.160373) (xy 210.864209 -109.114523) (xy 210.8999 -109.073332) (xy 210.941091 -109.037641)
			(xy 210.986941 -109.008175) (xy 211.036518 -108.985533) (xy 211.088813 -108.970178) (xy 211.142761 -108.962422)
			(xy 211.197263 -108.962422) (xy 211.251211 -108.970178) (xy 211.303506 -108.985533) (xy 211.353083 -109.008175)
			(xy 211.398933 -109.037641) (xy 211.440124 -109.073332) (xy 211.475815 -109.114523) (xy 211.505281 -109.160373)
			(xy 211.527923 -109.20995) (xy 211.543278 -109.262245) (xy 211.551034 -109.316193) (xy 211.55152 -109.343444)
			(xy 211.551018 -109.372184) (xy 211.542389 -109.429012) (xy 211.525334 -109.483902) (xy 211.500238 -109.535614)
			(xy 211.467668 -109.582976) (xy 211.448396 -109.604302) (xy 211.441792 -109.61116) (xy 211.43468 -109.629194)
			(xy 211.43468 -109.718094) (xy 211.441792 -109.736128) (xy 211.448396 -109.742986) (xy 211.46771 -109.764275)
			(xy 211.500272 -109.811645) (xy 211.52536 -109.863363) (xy 211.542405 -109.918259) (xy 211.551023 -109.975091)
			(xy 211.551018 -110.032573) (xy 211.542391 -110.089404) (xy 211.525336 -110.144297) (xy 211.500239 -110.196011)
			(xy 211.467669 -110.243375) (xy 211.448396 -110.264702) (xy 211.441792 -110.27156) (xy 211.43468 -110.289594)
			(xy 211.43468 -110.378494) (xy 211.441792 -110.396528) (xy 211.448396 -110.403386) (xy 211.467676 -110.424705)
			(xy 211.500244 -110.472068) (xy 211.525335 -110.523782) (xy 211.542383 -110.578675) (xy 211.551002 -110.635504)
			(xy 211.55152 -110.664244) (xy 211.551034 -110.691495) (xy 211.543278 -110.745443) (xy 211.527923 -110.797738)
			(xy 211.505281 -110.847315) (xy 211.475815 -110.893165) (xy 211.440124 -110.934356) (xy 211.398933 -110.970047)
			(xy 211.353083 -110.999513) (xy 211.303506 -111.022155) (xy 211.251211 -111.03751) (xy 211.197263 -111.045266)
			(xy 211.142761 -111.045266) (xy 211.088813 -111.03751) (xy 211.036518 -111.022155) (xy 210.986941 -110.999513)
			(xy 210.941091 -110.970047) (xy 210.8999 -110.934356) (xy 210.864209 -110.893165) (xy 210.834743 -110.847315)
			(xy 210.812101 -110.797738) (xy 210.796746 -110.745443) (xy 210.78899 -110.691495) (xy 210.788504 -110.664244)
			(xy 209.956428 -110.664244) (xy 209.949428 -110.712931) (xy 209.934073 -110.765226) (xy 209.911431 -110.814803)
			(xy 209.881965 -110.860653) (xy 209.846274 -110.901844) (xy 209.805083 -110.937535) (xy 209.759233 -110.967001)
			(xy 209.709656 -110.989643) (xy 209.657361 -111.004998) (xy 209.603413 -111.012754) (xy 209.548911 -111.012754)
			(xy 209.494963 -111.004998) (xy 209.442668 -110.989643) (xy 209.393091 -110.967001) (xy 209.347241 -110.937535)
			(xy 209.30605 -110.901844) (xy 209.270359 -110.860653) (xy 209.240893 -110.814803) (xy 209.218251 -110.765226)
			(xy 209.202896 -110.712931) (xy 209.19514 -110.658983) (xy 209.194654 -110.631732) (xy 191.475106 -110.631732)
			(xy 191.475103 -110.688659) (xy 191.466477 -110.745488) (xy 191.449424 -110.80038) (xy 191.42433 -110.852093)
			(xy 191.391762 -110.899457) (xy 191.37249 -110.920784) (xy 191.365886 -110.927642) (xy 191.358774 -110.945676)
			(xy 191.358774 -111.034576) (xy 191.365886 -111.05261) (xy 191.37249 -111.059468) (xy 191.391786 -111.080773)
			(xy 191.424349 -111.128139) (xy 191.449438 -111.179855) (xy 191.466486 -111.234749) (xy 191.475106 -111.291579)
			(xy 191.475103 -111.349059) (xy 191.466477 -111.405888) (xy 191.449424 -111.46078) (xy 191.42433 -111.512493)
			(xy 191.391762 -111.559857) (xy 191.37249 -111.581184) (xy 191.365886 -111.588042) (xy 191.358774 -111.606076)
			(xy 191.358774 -111.694976) (xy 191.365886 -111.71301) (xy 191.37249 -111.719868) (xy 191.391778 -111.74118)
			(xy 191.424341 -111.788547) (xy 191.449429 -111.840262) (xy 191.466476 -111.895156) (xy 191.475095 -111.951986)
			(xy 191.475614 -111.980726) (xy 191.475146 -112.007978) (xy 191.467387 -112.061926) (xy 191.452028 -112.11422)
			(xy 191.429385 -112.163797) (xy 191.399916 -112.209647) (xy 191.364223 -112.250837) (xy 191.323031 -112.286528)
			(xy 191.27718 -112.315994) (xy 191.227602 -112.338635) (xy 191.175306 -112.353991) (xy 191.121358 -112.361748)
			(xy 191.094106 -112.362234) (xy 191.067793 -112.361752) (xy 191.015665 -112.354518) (xy 190.965023 -112.340201)
			(xy 190.916824 -112.319072) (xy 190.87198 -112.291529) (xy 190.83134 -112.258094) (xy 190.813182 -112.239044)
			(xy 190.805663 -112.231639) (xy 190.786381 -112.223115) (xy 190.775844 -112.222534) (xy 190.701168 -112.222534)
			(xy 190.69062 -112.223076) (xy 190.671323 -112.231601) (xy 190.66383 -112.239044) (xy 190.645661 -112.258086)
			(xy 190.605034 -112.291543) (xy 190.560196 -112.319103) (xy 190.511998 -112.340243) (xy 190.461353 -112.354564)
			(xy 190.409221 -112.361793) (xy 190.382906 -112.362234) (xy 190.355656 -112.361717) (xy 190.301711 -112.353962)
			(xy 190.249418 -112.338609) (xy 190.199843 -112.31597) (xy 190.153994 -112.286507) (xy 190.112804 -112.250819)
			(xy 190.077112 -112.209632) (xy 190.047645 -112.163785) (xy 190.025003 -112.114212) (xy 190.009645 -112.06192)
			(xy 190.001886 -112.007976) (xy 190.001398 -111.980726) (xy 180.927647 -111.980726) (xy 180.620416 -112.287812)
			(xy 180.61559 -112.320578) (xy 180.62321 -112.33531) (xy 180.636653 -112.362548) (xy 180.655671 -112.420231)
			(xy 180.665297 -112.480201) (xy 180.665398 -112.485424) (xy 182.750966 -112.485424) (xy 182.755037 -112.429802)
			(xy 182.767163 -112.375365) (xy 182.787086 -112.323274) (xy 182.814382 -112.274639) (xy 182.848468 -112.230496)
			(xy 182.888617 -112.191787) (xy 182.933975 -112.159336) (xy 182.983575 -112.133835) (xy 183.036359 -112.115828)
			(xy 183.091202 -112.105698) (xy 183.146936 -112.103661) (xy 183.202373 -112.109761) (xy 183.25633 -112.123867)
			(xy 183.307659 -112.145679) (xy 183.355265 -112.174733) (xy 183.398133 -112.210408) (xy 183.43535 -112.251945)
			(xy 183.466123 -112.298458) (xy 183.489795 -112.348955) (xy 183.505863 -112.402362) (xy 183.508742 -112.421924)
			(xy 185.554872 -112.421924) (xy 185.558943 -112.366302) (xy 185.571069 -112.311865) (xy 185.590992 -112.259774)
			(xy 185.618288 -112.211139) (xy 185.652374 -112.166996) (xy 185.692523 -112.128287) (xy 185.737881 -112.095836)
			(xy 185.787481 -112.070335) (xy 185.840265 -112.052328) (xy 185.895108 -112.042198) (xy 185.950842 -112.040161)
			(xy 186.006279 -112.046261) (xy 186.060236 -112.060367) (xy 186.111565 -112.082179) (xy 186.159171 -112.111233)
			(xy 186.202039 -112.146908) (xy 186.239256 -112.188445) (xy 186.270029 -112.234958) (xy 186.293701 -112.285455)
			(xy 186.309769 -112.338862) (xy 186.317889 -112.394038) (xy 186.318398 -112.421924) (xy 186.317889 -112.44981)
			(xy 186.309769 -112.504986) (xy 186.293701 -112.558393) (xy 186.270029 -112.60889) (xy 186.239256 -112.655403)
			(xy 186.202039 -112.69694) (xy 186.159171 -112.732615) (xy 186.111565 -112.761669) (xy 186.060236 -112.783481)
			(xy 186.006279 -112.797587) (xy 185.950842 -112.803687) (xy 185.895108 -112.80165) (xy 185.840265 -112.79152)
			(xy 185.787481 -112.773513) (xy 185.737881 -112.748012) (xy 185.692523 -112.715561) (xy 185.652374 -112.676852)
			(xy 185.618288 -112.632709) (xy 185.590992 -112.584074) (xy 185.571069 -112.531983) (xy 185.558943 -112.477546)
			(xy 185.554872 -112.421924) (xy 183.508742 -112.421924) (xy 183.513983 -112.457538) (xy 183.514492 -112.485424)
			(xy 183.513983 -112.51331) (xy 183.505863 -112.568486) (xy 183.489795 -112.621893) (xy 183.466123 -112.67239)
			(xy 183.43535 -112.718903) (xy 183.398133 -112.76044) (xy 183.355265 -112.796115) (xy 183.307659 -112.825169)
			(xy 183.25633 -112.846981) (xy 183.202373 -112.861087) (xy 183.146936 -112.867187) (xy 183.091202 -112.86515)
			(xy 183.036359 -112.85502) (xy 182.983575 -112.837013) (xy 182.933975 -112.811512) (xy 182.888617 -112.779061)
			(xy 182.848468 -112.740352) (xy 182.814382 -112.696209) (xy 182.787086 -112.647574) (xy 182.767163 -112.595483)
			(xy 182.755037 -112.541046) (xy 182.750966 -112.485424) (xy 180.665398 -112.485424) (xy 180.665882 -112.51057)
			(xy 180.665882 -112.510824) (xy 180.665467 -112.538079) (xy 180.657706 -112.592033) (xy 180.642346 -112.644333)
			(xy 180.619699 -112.693915) (xy 180.590226 -112.739769) (xy 180.554527 -112.780963) (xy 180.513329 -112.816656)
			(xy 180.467471 -112.846123) (xy 180.417886 -112.868764) (xy 180.365584 -112.884117) (xy 180.311629 -112.891871)
			(xy 180.284374 -112.892332) (xy 180.28412 -112.892332) (xy 180.253753 -112.891727) (xy 180.193789 -112.882089)
			(xy 180.136104 -112.863086) (xy 180.10886 -112.84966) (xy 180.094128 -112.84204) (xy 180.061362 -112.846866)
			(xy 179.656486 -113.251742) (xy 180.406038 -113.251742) (xy 180.410109 -113.19612) (xy 180.422235 -113.141683)
			(xy 180.442158 -113.089592) (xy 180.469454 -113.040957) (xy 180.50354 -112.996814) (xy 180.543689 -112.958105)
			(xy 180.589047 -112.925654) (xy 180.638647 -112.900153) (xy 180.691431 -112.882146) (xy 180.746274 -112.872016)
			(xy 180.802008 -112.869979) (xy 180.857445 -112.876079) (xy 180.911402 -112.890185) (xy 180.962731 -112.911997)
			(xy 181.010337 -112.941051) (xy 181.053205 -112.976726) (xy 181.090422 -113.018263) (xy 181.121195 -113.064776)
			(xy 181.144867 -113.115273) (xy 181.160935 -113.16868) (xy 181.169055 -113.223856) (xy 181.169564 -113.251742)
			(xy 181.169055 -113.279628) (xy 181.160935 -113.334804) (xy 181.144867 -113.388211) (xy 181.122872 -113.43513)
			(xy 183.03062 -113.43513) (xy 183.034691 -113.379508) (xy 183.046817 -113.325071) (xy 183.06674 -113.27298)
			(xy 183.094036 -113.224345) (xy 183.128122 -113.180202) (xy 183.168271 -113.141493) (xy 183.213629 -113.109042)
			(xy 183.263229 -113.083541) (xy 183.316013 -113.065534) (xy 183.370856 -113.055404) (xy 183.42659 -113.053367)
			(xy 183.482027 -113.059467) (xy 183.535984 -113.073573) (xy 183.587313 -113.095385) (xy 183.634919 -113.124439)
			(xy 183.677787 -113.160114) (xy 183.715004 -113.201651) (xy 183.745777 -113.248164) (xy 183.769449 -113.298661)
			(xy 183.785517 -113.352068) (xy 183.793637 -113.407244) (xy 183.794146 -113.43513) (xy 183.794095 -113.437924)
			(xy 185.53379 -113.437924) (xy 185.537861 -113.382302) (xy 185.549987 -113.327865) (xy 185.56991 -113.275774)
			(xy 185.597206 -113.227139) (xy 185.631292 -113.182996) (xy 185.671441 -113.144287) (xy 185.716799 -113.111836)
			(xy 185.766399 -113.086335) (xy 185.819183 -113.068328) (xy 185.874026 -113.058198) (xy 185.92976 -113.056161)
			(xy 185.985197 -113.062261) (xy 186.039154 -113.076367) (xy 186.090483 -113.098179) (xy 186.138089 -113.127233)
			(xy 186.180957 -113.162908) (xy 186.218174 -113.204445) (xy 186.248947 -113.250958) (xy 186.272619 -113.301455)
			(xy 186.288687 -113.354862) (xy 186.296807 -113.410038) (xy 186.297316 -113.437924) (xy 186.296807 -113.46581)
			(xy 186.288687 -113.520986) (xy 186.272619 -113.574393) (xy 186.248947 -113.62489) (xy 186.218174 -113.671403)
			(xy 186.180957 -113.71294) (xy 186.138089 -113.748615) (xy 186.090483 -113.777669) (xy 186.039154 -113.799481)
			(xy 185.985197 -113.813587) (xy 185.92976 -113.819687) (xy 185.874026 -113.81765) (xy 185.819183 -113.80752)
			(xy 185.766399 -113.789513) (xy 185.716799 -113.764012) (xy 185.671441 -113.731561) (xy 185.631292 -113.692852)
			(xy 185.597206 -113.648709) (xy 185.56991 -113.600074) (xy 185.549987 -113.547983) (xy 185.537861 -113.493546)
			(xy 185.53379 -113.437924) (xy 183.794095 -113.437924) (xy 183.793637 -113.463016) (xy 183.785517 -113.518192)
			(xy 183.769449 -113.571599) (xy 183.745777 -113.622096) (xy 183.715004 -113.668609) (xy 183.677787 -113.710146)
			(xy 183.634919 -113.745821) (xy 183.587313 -113.774875) (xy 183.535984 -113.796687) (xy 183.482027 -113.810793)
			(xy 183.42659 -113.816893) (xy 183.370856 -113.814856) (xy 183.316013 -113.804726) (xy 183.263229 -113.786719)
			(xy 183.213629 -113.761218) (xy 183.168271 -113.728767) (xy 183.128122 -113.690058) (xy 183.094036 -113.645915)
			(xy 183.06674 -113.59728) (xy 183.046817 -113.545189) (xy 183.034691 -113.490752) (xy 183.03062 -113.43513)
			(xy 181.122872 -113.43513) (xy 181.121195 -113.438708) (xy 181.090422 -113.485221) (xy 181.053205 -113.526758)
			(xy 181.010337 -113.562433) (xy 180.962731 -113.591487) (xy 180.911402 -113.613299) (xy 180.857445 -113.627405)
			(xy 180.802008 -113.633505) (xy 180.746274 -113.631468) (xy 180.691431 -113.621338) (xy 180.638647 -113.603331)
			(xy 180.589047 -113.57783) (xy 180.543689 -113.545379) (xy 180.50354 -113.50667) (xy 180.469454 -113.462527)
			(xy 180.442158 -113.413892) (xy 180.422235 -113.361801) (xy 180.410109 -113.307364) (xy 180.406038 -113.251742)
			(xy 179.656486 -113.251742) (xy 179.031392 -113.876836) (xy 203.361036 -113.876836) (xy 203.361454 -113.849924)
			(xy 203.36904 -113.796636) (xy 203.384038 -113.744943) (xy 203.406151 -113.695871) (xy 203.43494 -113.650392)
			(xy 203.469834 -113.60941) (xy 203.51014 -113.573738) (xy 203.555059 -113.544083) (xy 203.603699 -113.521034)
			(xy 203.62926 -113.5126) (xy 203.629514 -113.5126) (xy 203.6352 -113.510603) (xy 203.645479 -113.504319)
			(xy 203.649834 -113.500154) (xy 205.91272 -111.237268) (xy 205.931506 -111.219252) (xy 205.973619 -111.188671)
			(xy 206.019992 -111.165041) (xy 206.069485 -111.148943) (xy 206.120886 -111.14077) (xy 206.146908 -111.14024)
			(xy 210.874864 -111.14024) (xy 210.900889 -111.140736) (xy 210.952295 -111.148908) (xy 211.001793 -111.165008)
			(xy 211.048168 -111.188643) (xy 211.090283 -111.219232) (xy 211.109052 -111.237268) (xy 214.744046 -114.872262)
			(xy 214.774018 -114.878104) (xy 214.788242 -114.872262) (xy 214.797274 -114.867947) (xy 214.811361 -114.853754)
			(xy 214.818992 -114.83527) (xy 214.819484 -114.825272) (xy 214.819484 -108.57357) (xy 214.819079 -108.563498)
			(xy 214.811344 -108.5449) (xy 214.804498 -108.537502) (xy 213.068154 -106.801158) (xy 213.046149 -106.77843)
			(xy 213.007648 -106.728231) (xy 212.976026 -106.673439) (xy 212.951822 -106.614989) (xy 212.935452 -106.553881)
			(xy 212.927194 -106.491159) (xy 212.926676 -106.459528) (xy 212.926676 -101.952552) (xy 212.927185 -101.920919)
			(xy 212.935427 -101.858192) (xy 212.95179 -101.797078) (xy 212.975993 -101.738625) (xy 213.007622 -101.683832)
			(xy 213.046135 -101.633639) (xy 213.068154 -101.610922) (xy 216.069926 -98.60915) (xy 216.092661 -98.587152)
			(xy 216.142858 -98.548651) (xy 216.197649 -98.517027) (xy 216.256097 -98.492823) (xy 216.317204 -98.476451)
			(xy 216.379925 -98.468191) (xy 216.411556 -98.467672) (xy 219.548964 -98.467672) (xy 219.574364 -98.450654)
			(xy 219.580206 -98.43643) (xy 219.583654 -98.426999) (xy 219.583601 -98.406934) (xy 219.575857 -98.388422)
			(xy 219.56903 -98.381058) (xy 219.243148 -98.055176) (xy 219.225127 -98.036395) (xy 219.194547 -97.99428)
			(xy 219.170919 -97.947906) (xy 219.154822 -97.898412) (xy 219.14665 -97.847011) (xy 219.14612 -97.820988)
			(xy 219.14612 -97.737168) (xy 219.145943 -97.731017) (xy 219.142979 -97.719076) (xy 219.140278 -97.713546)
			(xy 219.126453 -97.686014) (xy 219.106885 -97.6276) (xy 219.096948 -97.566802) (xy 219.096336 -97.536)
			(xy 219.096755 -97.508745) (xy 219.104514 -97.45479) (xy 219.119872 -97.402489) (xy 219.142518 -97.352906)
			(xy 219.17199 -97.307051) (xy 219.207688 -97.265857) (xy 219.248886 -97.230163) (xy 219.294745 -97.200696)
			(xy 219.34433 -97.178056) (xy 219.396633 -97.162704) (xy 219.450589 -97.154952) (xy 219.477844 -97.154492)
			(xy 219.505237 -97.154964) (xy 219.559462 -97.16279) (xy 219.612009 -97.178291) (xy 219.637102 -97.18929)
			(xy 219.648786 -97.194878) (xy 219.674694 -97.1931) (xy 219.757752 -97.13976) (xy 219.764754 -97.134953)
			(xy 219.775269 -97.121623) (xy 219.780816 -97.105577) (xy 219.78112 -97.097088) (xy 219.78112 -96.716342)
			(xy 219.781554 -96.683488) (xy 219.788923 -96.618194) (xy 219.803552 -96.554134) (xy 219.825255 -96.492113)
			(xy 219.853762 -96.43291) (xy 219.888713 -96.377268) (xy 219.929671 -96.325886) (xy 219.95257 -96.302322)
			(xy 220.45803 -95.796862) (xy 220.464671 -95.789414) (xy 220.472281 -95.770997) (xy 220.472294 -95.75107)
			(xy 220.464709 -95.732643) (xy 220.45803 -95.725234) (xy 220.07957 -95.346774) (xy 220.056658 -95.323221)
			(xy 220.015692 -95.271844) (xy 219.980736 -95.216202) (xy 219.952229 -95.156997) (xy 219.930531 -95.094972)
			(xy 219.915914 -95.030908) (xy 219.908561 -94.965609) (xy 219.90812 -94.932754) (xy 219.90812 -94.9325)
			(xy 219.908589 -94.8971) (xy 219.917124 -94.826815) (xy 219.934068 -94.758072) (xy 219.959176 -94.691872)
			(xy 219.99208 -94.629182) (xy 220.032301 -94.570915) (xy 220.079253 -94.517922) (xy 220.13225 -94.470974)
			(xy 220.19052 -94.430757) (xy 220.253212 -94.397858) (xy 220.319414 -94.372755) (xy 220.388158 -94.355816)
			(xy 220.458444 -94.347287) (xy 220.493844 -94.346776) (xy 220.494098 -94.346776) (xy 220.526951 -94.347262)
			(xy 220.592242 -94.354624) (xy 220.656301 -94.369245) (xy 220.718321 -94.39094) (xy 220.777525 -94.419439)
			(xy 220.833168 -94.454382) (xy 220.884553 -94.495331) (xy 220.908118 -94.518226) (xy 221.05493 -94.665038)
			(xy 221.063602 -94.672898) (xy 221.085723 -94.680449) (xy 221.108899 -94.677402) (xy 221.118938 -94.671388)
			(xy 221.142594 -94.656174) (xy 221.193439 -94.632132) (xy 221.247267 -94.615824) (xy 221.302906 -94.607605)
			(xy 221.331028 -94.607126) (xy 221.358283 -94.607529) (xy 221.412238 -94.615291) (xy 221.464539 -94.630652)
			(xy 221.514122 -94.6533) (xy 221.559976 -94.682774) (xy 221.60117 -94.718474) (xy 221.636863 -94.759673)
			(xy 221.66633 -94.805533) (xy 221.68897 -94.855119) (xy 221.704323 -94.907423) (xy 221.712075 -94.961379)
			(xy 221.712536 -94.988634) (xy 221.711266 -95.01886) (xy 226.33686 -95.01886) (xy 226.362514 -95.001842)
			(xy 226.368356 -94.987364) (xy 226.371681 -94.977967) (xy 226.371686 -94.958059) (xy 226.364105 -94.93965)
			(xy 226.357434 -94.932246) (xy 224.82048 -93.395292) (xy 224.797552 -93.371724) (xy 224.756557 -93.320312)
			(xy 224.72157 -93.264636) (xy 224.693032 -93.205397) (xy 224.671299 -93.143336) (xy 224.656645 -93.079234)
			(xy 224.649253 -93.013896) (xy 224.648776 -92.981018) (xy 224.648776 -91.824302) (xy 224.648356 -91.814232)
			(xy 224.640632 -91.795634) (xy 224.63379 -91.788234) (xy 224.007934 -91.162378) (xy 223.98503 -91.138819)
			(xy 223.944066 -91.087441) (xy 223.909112 -91.0318) (xy 223.880607 -90.972596) (xy 223.85891 -90.910572)
			(xy 223.844294 -90.846509) (xy 223.836942 -90.781213) (xy 223.836484 -90.748358) (xy 223.836484 -90.748104)
			(xy 223.836993 -90.712705) (xy 223.845526 -90.642423) (xy 223.862469 -90.573683) (xy 223.887574 -90.507485)
			(xy 223.920476 -90.444797) (xy 223.960693 -90.386531) (xy 224.007641 -90.333538) (xy 224.060635 -90.286591)
			(xy 224.1189 -90.246374) (xy 224.181589 -90.213473) (xy 224.247786 -90.188368) (xy 224.316527 -90.171426)
			(xy 224.386809 -90.162893) (xy 224.422208 -90.16238) (xy 224.422462 -90.16238) (xy 224.455316 -90.162823)
			(xy 224.520609 -90.170192) (xy 224.584668 -90.18482) (xy 224.646689 -90.206523) (xy 224.705892 -90.235028)
			(xy 224.761535 -90.269977) (xy 224.812918 -90.310932) (xy 224.836482 -90.33383) (xy 225.220276 -90.717624)
			(xy 225.226839 -90.723525) (xy 225.242855 -90.730906) (xy 225.260421 -90.732456) (xy 225.269044 -90.730578)
			(xy 225.354134 -90.707972) (xy 225.362592 -90.705405) (xy 225.377161 -90.695421) (xy 225.38745 -90.681066)
			(xy 225.390202 -90.672666) (xy 225.390202 -90.672158) (xy 225.397936 -90.645592) (xy 225.420039 -90.594868)
			(xy 225.449239 -90.54787) (xy 225.484924 -90.505584) (xy 225.526344 -90.468899) (xy 225.572629 -90.438583)
			(xy 225.62281 -90.415272) (xy 225.675832 -90.399458) (xy 225.730583 -90.39147) (xy 225.758248 -90.39098)
			(xy 225.7855 -90.391433) (xy 225.839448 -90.399196) (xy 225.891743 -90.414556) (xy 225.941319 -90.437202)
			(xy 225.987169 -90.466672) (xy 226.028358 -90.502367) (xy 226.064049 -90.54356) (xy 226.093515 -90.589412)
			(xy 226.116156 -90.638991) (xy 226.131512 -90.691287) (xy 226.139269 -90.745236) (xy 226.139756 -90.772488)
			(xy 226.139331 -90.798958) (xy 226.132038 -90.851393) (xy 226.117562 -90.902315) (xy 226.096183 -90.950745)
			(xy 226.068311 -90.995753) (xy 226.034482 -91.036474) (xy 225.995345 -91.072124) (xy 225.951654 -91.102018)
			(xy 225.904248 -91.125582) (xy 225.854039 -91.142363) (xy 225.828098 -91.147646) (xy 225.81616 -91.149932)
			(xy 225.79711 -91.16441) (xy 225.750374 -91.258898) (xy 225.750628 -91.283028) (xy 225.756216 -91.293696)
			(xy 225.771587 -91.324769) (xy 225.795719 -91.38976) (xy 225.812003 -91.457148) (xy 225.820212 -91.525987)
			(xy 225.820732 -91.56065) (xy 225.820732 -92.717366) (xy 225.821167 -92.727434) (xy 225.82888 -92.746033)
			(xy 225.835718 -92.753434) (xy 227.07854 -93.99651) (xy 227.085931 -94.003361) (xy 227.104537 -94.011074)
			(xy 227.114608 -94.011496) (xy 227.317046 -94.011496) (xy 227.328168 -94.010941) (xy 227.348328 -94.001534)
			(xy 227.362634 -93.984499) (xy 227.366068 -93.973904) (xy 227.373785 -93.947299) (xy 227.395874 -93.896498)
			(xy 227.425076 -93.849424) (xy 227.460775 -93.807066) (xy 227.502223 -93.770313) (xy 227.548548 -93.739938)
			(xy 227.598778 -93.71658) (xy 227.651857 -93.700727) (xy 227.70667 -93.692715) (xy 227.734368 -93.692218)
			(xy 227.734876 -93.692218) (xy 227.745823 -93.692306) (xy 227.767681 -93.693575) (xy 227.778564 -93.694758)
			(xy 227.766173 -93.666343) (xy 227.746783 -93.607462) (xy 227.73373 -93.546859) (xy 227.727161 -93.485216)
			(xy 227.726748 -93.45422) (xy 227.726748 -93.439234) (xy 227.699638 -93.438247) (xy 227.646108 -93.429445)
			(xy 227.594364 -93.413151) (xy 227.545449 -93.389693) (xy 227.50035 -93.359543) (xy 227.459976 -93.32331)
			(xy 227.42514 -93.281723) (xy 227.396546 -93.235622) (xy 227.374769 -93.185936) (xy 227.360249 -93.133666)
			(xy 227.353279 -93.079867) (xy 227.353999 -93.025623) (xy 227.362394 -92.972027) (xy 227.378295 -92.920161)
			(xy 227.401382 -92.87107) (xy 227.431189 -92.825743) (xy 227.467116 -92.785096) (xy 227.508437 -92.749946)
			(xy 227.55432 -92.721003) (xy 227.60384 -92.698851) (xy 227.655998 -92.683935) (xy 227.682806 -92.679774)
			(xy 227.691847 -92.678173) (xy 227.707994 -92.669458) (xy 227.720029 -92.655608) (xy 227.726408 -92.638404)
			(xy 227.726748 -92.629228) (xy 227.726748 -92.470224) (xy 227.72643 -92.461051) (xy 227.720022 -92.443863)
			(xy 227.70798 -92.430025) (xy 227.691841 -92.421304) (xy 227.682806 -92.419678) (xy 227.655745 -92.415455)
			(xy 227.603099 -92.400363) (xy 227.553153 -92.377898) (xy 227.506933 -92.348519) (xy 227.46539 -92.312833)
			(xy 227.429378 -92.271572) (xy 227.399637 -92.225584) (xy 227.37678 -92.175816) (xy 227.361275 -92.12329)
			(xy 227.353442 -92.069087) (xy 227.353441 -92.01432) (xy 227.361273 -91.960117) (xy 227.376777 -91.907591)
			(xy 227.399634 -91.857822) (xy 227.429374 -91.811834) (xy 227.465385 -91.770572) (xy 227.506927 -91.734885)
			(xy 227.553147 -91.705506) (xy 227.603093 -91.683039) (xy 227.655738 -91.667946) (xy 227.682806 -91.663774)
			(xy 227.691847 -91.662173) (xy 227.707994 -91.653458) (xy 227.720029 -91.639608) (xy 227.726408 -91.622404)
			(xy 227.726748 -91.613228) (xy 227.726748 -91.45397) (xy 227.72639 -91.44483) (xy 227.71994 -91.427725)
			(xy 227.707905 -91.413965) (xy 227.691811 -91.405294) (xy 227.682806 -91.403678) (xy 227.655745 -91.399455)
			(xy 227.603099 -91.384363) (xy 227.553153 -91.361898) (xy 227.506933 -91.332519) (xy 227.46539 -91.296833)
			(xy 227.429378 -91.255572) (xy 227.399637 -91.209584) (xy 227.37678 -91.159816) (xy 227.361275 -91.10729)
			(xy 227.353442 -91.053087) (xy 227.353441 -90.99832) (xy 227.361273 -90.944117) (xy 227.376777 -90.891591)
			(xy 227.399634 -90.841822) (xy 227.429374 -90.795834) (xy 227.465385 -90.754572) (xy 227.506927 -90.718885)
			(xy 227.553147 -90.689506) (xy 227.603093 -90.667039) (xy 227.655738 -90.651946) (xy 227.682806 -90.647774)
			(xy 227.691817 -90.646183) (xy 227.707918 -90.637517) (xy 227.719947 -90.623746) (xy 227.726368 -90.606625)
			(xy 227.726748 -90.597482) (xy 227.726748 -90.43797) (xy 227.72639 -90.42883) (xy 227.71994 -90.411725)
			(xy 227.707905 -90.397965) (xy 227.691811 -90.389294) (xy 227.682806 -90.387678) (xy 227.655745 -90.383455)
			(xy 227.603099 -90.368363) (xy 227.553153 -90.345898) (xy 227.506933 -90.316519) (xy 227.46539 -90.280833)
			(xy 227.429378 -90.239572) (xy 227.399637 -90.193584) (xy 227.37678 -90.143816) (xy 227.361275 -90.09129)
			(xy 227.353442 -90.037087) (xy 227.353441 -89.98232) (xy 227.361273 -89.928117) (xy 227.376777 -89.875591)
			(xy 227.399634 -89.825822) (xy 227.429374 -89.779834) (xy 227.465385 -89.738572) (xy 227.506927 -89.702885)
			(xy 227.553147 -89.673506) (xy 227.603093 -89.651039) (xy 227.655738 -89.635946) (xy 227.682806 -89.631774)
			(xy 227.691817 -89.630183) (xy 227.707918 -89.621517) (xy 227.719947 -89.607746) (xy 227.726368 -89.590625)
			(xy 227.726748 -89.581482) (xy 227.726748 -89.182956) (xy 227.727244 -89.148856) (xy 227.735161 -89.081116)
			(xy 227.75089 -89.014753) (xy 227.774216 -88.950665) (xy 227.804824 -88.889719) (xy 227.842301 -88.832738)
			(xy 227.88614 -88.780493) (xy 227.935747 -88.73369) (xy 227.990453 -88.692964) (xy 228.049517 -88.658863)
			(xy 228.11214 -88.63185) (xy 228.177476 -88.61229) (xy 228.24464 -88.600447) (xy 228.312726 -88.596482)
			(xy 228.380812 -88.600447) (xy 228.447976 -88.61229) (xy 228.513312 -88.63185) (xy 228.575935 -88.658863)
			(xy 228.634999 -88.692964) (xy 228.689705 -88.73369) (xy 228.739312 -88.780493) (xy 228.783151 -88.832738)
			(xy 228.820628 -88.889719) (xy 228.851236 -88.950665) (xy 228.874562 -89.014753) (xy 228.890291 -89.081116)
			(xy 228.898208 -89.148856) (xy 228.898704 -89.182956) (xy 228.898704 -90.263747) (xy 229.611726 -90.263747)
			(xy 229.611726 -90.209253) (xy 229.619481 -90.155314) (xy 229.634833 -90.103027) (xy 229.65747 -90.053457)
			(xy 229.686931 -90.007614) (xy 229.722616 -89.966429) (xy 229.763799 -89.930742) (xy 229.809642 -89.901279)
			(xy 229.85921 -89.87864) (xy 229.911496 -89.863285) (xy 229.965435 -89.855527) (xy 229.992682 -89.85504)
			(xy 230.019221 -89.85549) (xy 230.071788 -89.862832) (xy 230.122829 -89.877391) (xy 230.171359 -89.898886)
			(xy 230.216441 -89.926901) (xy 230.257203 -89.960896) (xy 230.292859 -90.000214) (xy 230.322719 -90.044095)
			(xy 230.346208 -90.091692) (xy 230.362871 -90.142085) (xy 230.372386 -90.194303) (xy 230.373936 -90.2208)
			(xy 230.374664 -90.230031) (xy 230.38189 -90.247067) (xy 230.394703 -90.260417) (xy 230.402892 -90.264742)
			(xy 230.483918 -90.303096) (xy 230.492374 -90.30672) (xy 230.510698 -90.308241) (xy 230.528377 -90.303188)
			(xy 230.535988 -90.298016) (xy 230.536242 -90.298016) (xy 230.561108 -90.28021) (xy 230.615337 -90.251937)
			(xy 230.673382 -90.232678) (xy 230.733756 -90.222926) (xy 230.764334 -90.222324) (xy 230.791588 -90.222746)
			(xy 230.845539 -90.230508) (xy 230.897837 -90.245869) (xy 230.947417 -90.268517) (xy 230.993268 -90.29799)
			(xy 231.034459 -90.333688) (xy 231.07015 -90.374885) (xy 231.099615 -90.420741) (xy 231.122254 -90.470325)
			(xy 231.137606 -90.522625) (xy 231.145358 -90.576578) (xy 231.145842 -90.603832) (xy 231.145409 -90.631204)
			(xy 231.137585 -90.685385) (xy 231.122089 -90.737889) (xy 231.09924 -90.787635) (xy 231.069507 -90.8336)
			(xy 231.051862 -90.85453) (xy 231.045818 -90.862034) (xy 231.039432 -90.880199) (xy 231.039416 -90.889836)
			(xy 231.042718 -90.969592) (xy 231.050592 -90.986864) (xy 231.05745 -90.993722) (xy 231.07528 -91.011731)
			(xy 231.106509 -91.051642) (xy 231.132179 -91.095337) (xy 231.151837 -91.142047) (xy 231.165137 -91.190948)
			(xy 231.171845 -91.241179) (xy 231.172258 -91.266518) (xy 231.171772 -91.293769) (xy 231.164016 -91.347717)
			(xy 231.148661 -91.400012) (xy 231.126019 -91.449589) (xy 231.096553 -91.495439) (xy 231.060862 -91.53663)
			(xy 231.019671 -91.572321) (xy 230.973821 -91.601787) (xy 230.924244 -91.624429) (xy 230.871949 -91.639784)
			(xy 230.818001 -91.64754) (xy 230.763499 -91.64754) (xy 230.709551 -91.639784) (xy 230.657256 -91.624429)
			(xy 230.607679 -91.601787) (xy 230.561829 -91.572321) (xy 230.520638 -91.53663) (xy 230.484947 -91.495439)
			(xy 230.455481 -91.449589) (xy 230.432839 -91.400012) (xy 230.417484 -91.347717) (xy 230.409728 -91.293769)
			(xy 230.409242 -91.266518) (xy 230.409708 -91.239148) (xy 230.417525 -91.184968) (xy 230.433013 -91.132465)
			(xy 230.455855 -91.082718) (xy 230.48558 -91.036751) (xy 230.503222 -91.01582) (xy 230.509242 -91.008299)
			(xy 230.515643 -90.990147) (xy 230.515668 -90.980514) (xy 230.512366 -90.900758) (xy 230.504492 -90.883486)
			(xy 230.497634 -90.876628) (xy 230.47735 -90.85612) (xy 230.442623 -90.810066) (xy 230.415233 -90.759303)
			(xy 230.395808 -90.704992) (xy 230.38479 -90.648374) (xy 230.38308 -90.61958) (xy 230.382357 -90.610348)
			(xy 230.375127 -90.593314) (xy 230.362313 -90.579964) (xy 230.354124 -90.575638) (xy 230.273098 -90.537284)
			(xy 230.264636 -90.533676) (xy 230.246316 -90.532151) (xy 230.228639 -90.537197) (xy 230.221028 -90.542364)
			(xy 230.220774 -90.542364) (xy 230.19591 -90.560173) (xy 230.14168 -90.588443) (xy 230.083634 -90.607701)
			(xy 230.02326 -90.617453) (xy 229.992682 -90.618056) (xy 229.965435 -90.617473) (xy 229.911496 -90.609715)
			(xy 229.85921 -90.59436) (xy 229.809642 -90.571721) (xy 229.763799 -90.542258) (xy 229.722616 -90.506571)
			(xy 229.686931 -90.465386) (xy 229.65747 -90.419543) (xy 229.634833 -90.369973) (xy 229.619481 -90.317686)
			(xy 229.611726 -90.263747) (xy 228.898704 -90.263747) (xy 228.898704 -91.988132) (xy 229.487982 -91.988132)
			(xy 229.492053 -91.93251) (xy 229.504179 -91.878073) (xy 229.524102 -91.825982) (xy 229.551398 -91.777347)
			(xy 229.585484 -91.733204) (xy 229.625633 -91.694495) (xy 229.670991 -91.662044) (xy 229.720591 -91.636543)
			(xy 229.773375 -91.618536) (xy 229.828218 -91.608406) (xy 229.883952 -91.606369) (xy 229.939389 -91.612469)
			(xy 229.993346 -91.626575) (xy 230.044675 -91.648387) (xy 230.047829 -91.650312) (xy 239.454434 -91.650312)
			(xy 239.458505 -91.59469) (xy 239.470631 -91.540253) (xy 239.490554 -91.488162) (xy 239.51785 -91.439527)
			(xy 239.551936 -91.395384) (xy 239.592085 -91.356675) (xy 239.637443 -91.324224) (xy 239.687043 -91.298723)
			(xy 239.739827 -91.280716) (xy 239.79467 -91.270586) (xy 239.850404 -91.268549) (xy 239.905841 -91.274649)
			(xy 239.959798 -91.288755) (xy 240.011127 -91.310567) (xy 240.058733 -91.339621) (xy 240.101601 -91.375296)
			(xy 240.138818 -91.416833) (xy 240.169591 -91.463346) (xy 240.193263 -91.513843) (xy 240.209331 -91.56725)
			(xy 240.217451 -91.622426) (xy 240.21796 -91.650312) (xy 240.217451 -91.678198) (xy 240.209331 -91.733374)
			(xy 240.193263 -91.786781) (xy 240.169591 -91.837278) (xy 240.138818 -91.883791) (xy 240.101601 -91.925328)
			(xy 240.058733 -91.961003) (xy 240.011127 -91.990057) (xy 239.959798 -92.011869) (xy 239.905841 -92.025975)
			(xy 239.850404 -92.032075) (xy 239.79467 -92.030038) (xy 239.739827 -92.019908) (xy 239.687043 -92.001901)
			(xy 239.637443 -91.9764) (xy 239.592085 -91.943949) (xy 239.551936 -91.90524) (xy 239.51785 -91.861097)
			(xy 239.490554 -91.812462) (xy 239.470631 -91.760371) (xy 239.458505 -91.705934) (xy 239.454434 -91.650312)
			(xy 230.047829 -91.650312) (xy 230.092281 -91.677441) (xy 230.135149 -91.713116) (xy 230.172366 -91.754653)
			(xy 230.203139 -91.801166) (xy 230.226811 -91.851663) (xy 230.242879 -91.90507) (xy 230.250999 -91.960246)
			(xy 230.251508 -91.988132) (xy 230.250999 -92.016018) (xy 230.242879 -92.071194) (xy 230.226811 -92.124601)
			(xy 230.203139 -92.175098) (xy 230.172366 -92.221611) (xy 230.135149 -92.263148) (xy 230.092281 -92.298823)
			(xy 230.044675 -92.327877) (xy 229.993346 -92.349689) (xy 229.939389 -92.363795) (xy 229.883952 -92.369895)
			(xy 229.828218 -92.367858) (xy 229.773375 -92.357728) (xy 229.720591 -92.339721) (xy 229.670991 -92.31422)
			(xy 229.625633 -92.281769) (xy 229.585484 -92.24306) (xy 229.551398 -92.198917) (xy 229.524102 -92.150282)
			(xy 229.504179 -92.098191) (xy 229.492053 -92.043754) (xy 229.487982 -91.988132) (xy 228.898704 -91.988132)
			(xy 228.898704 -92.665042) (xy 237.406432 -92.665042) (xy 237.410503 -92.60942) (xy 237.422629 -92.554983)
			(xy 237.442552 -92.502892) (xy 237.469848 -92.454257) (xy 237.503934 -92.410114) (xy 237.544083 -92.371405)
			(xy 237.589441 -92.338954) (xy 237.639041 -92.313453) (xy 237.691825 -92.295446) (xy 237.746668 -92.285316)
			(xy 237.802402 -92.283279) (xy 237.857839 -92.289379) (xy 237.911796 -92.303485) (xy 237.963125 -92.325297)
			(xy 238.010731 -92.354351) (xy 238.053599 -92.390026) (xy 238.090816 -92.431563) (xy 238.121589 -92.478076)
			(xy 238.145261 -92.528573) (xy 238.161329 -92.58198) (xy 238.169449 -92.637156) (xy 238.169958 -92.665042)
			(xy 238.169449 -92.692928) (xy 238.161329 -92.748104) (xy 238.145261 -92.801511) (xy 238.121589 -92.852008)
			(xy 238.090816 -92.898521) (xy 238.053599 -92.940058) (xy 238.010731 -92.975733) (xy 237.963125 -93.004787)
			(xy 237.911796 -93.026599) (xy 237.857839 -93.040705) (xy 237.802402 -93.046805) (xy 237.746668 -93.044768)
			(xy 237.691825 -93.034638) (xy 237.639041 -93.016631) (xy 237.589441 -92.99113) (xy 237.544083 -92.958679)
			(xy 237.503934 -92.91997) (xy 237.469848 -92.875827) (xy 237.442552 -92.827192) (xy 237.422629 -92.775101)
			(xy 237.410503 -92.720664) (xy 237.406432 -92.665042) (xy 228.898704 -92.665042) (xy 228.898704 -93.190568)
			(xy 228.899119 -93.200639) (xy 228.906844 -93.219238) (xy 228.91369 -93.226636) (xy 228.953568 -93.266514)
			(xy 229.782876 -93.266514) (xy 229.786947 -93.210892) (xy 229.799073 -93.156455) (xy 229.818996 -93.104364)
			(xy 229.846292 -93.055729) (xy 229.880378 -93.011586) (xy 229.920527 -92.972877) (xy 229.965885 -92.940426)
			(xy 230.015485 -92.914925) (xy 230.068269 -92.896918) (xy 230.123112 -92.886788) (xy 230.178846 -92.884751)
			(xy 230.234283 -92.890851) (xy 230.28824 -92.904957) (xy 230.339569 -92.926769) (xy 230.387175 -92.955823)
			(xy 230.430043 -92.991498) (xy 230.46726 -93.033035) (xy 230.498033 -93.079548) (xy 230.510427 -93.105986)
			(xy 248.549412 -93.105986) (xy 248.553483 -93.050364) (xy 248.565609 -92.995927) (xy 248.585532 -92.943836)
			(xy 248.612828 -92.895201) (xy 248.646914 -92.851058) (xy 248.687063 -92.812349) (xy 248.732421 -92.779898)
			(xy 248.782021 -92.754397) (xy 248.834805 -92.73639) (xy 248.889648 -92.72626) (xy 248.945382 -92.724223)
			(xy 249.000819 -92.730323) (xy 249.054776 -92.744429) (xy 249.106105 -92.766241) (xy 249.153711 -92.795295)
			(xy 249.196579 -92.83097) (xy 249.233796 -92.872507) (xy 249.264569 -92.91902) (xy 249.288241 -92.969517)
			(xy 249.304309 -93.022924) (xy 249.312429 -93.0781) (xy 249.312938 -93.105986) (xy 249.312429 -93.133872)
			(xy 249.304309 -93.189048) (xy 249.288241 -93.242455) (xy 249.264569 -93.292952) (xy 249.233796 -93.339465)
			(xy 249.196579 -93.381002) (xy 249.153711 -93.416677) (xy 249.106105 -93.445731) (xy 249.054776 -93.467543)
			(xy 249.000819 -93.481649) (xy 248.945382 -93.487749) (xy 248.889648 -93.485712) (xy 248.834805 -93.475582)
			(xy 248.782021 -93.457575) (xy 248.732421 -93.432074) (xy 248.687063 -93.399623) (xy 248.646914 -93.360914)
			(xy 248.612828 -93.316771) (xy 248.585532 -93.268136) (xy 248.565609 -93.216045) (xy 248.553483 -93.161608)
			(xy 248.549412 -93.105986) (xy 230.510427 -93.105986) (xy 230.521705 -93.130045) (xy 230.537773 -93.183452)
			(xy 230.545893 -93.238628) (xy 230.546402 -93.266514) (xy 230.545893 -93.2944) (xy 230.537773 -93.349576)
			(xy 230.521705 -93.402983) (xy 230.498033 -93.45348) (xy 230.46726 -93.499993) (xy 230.430043 -93.54153)
			(xy 230.387175 -93.577205) (xy 230.339569 -93.606259) (xy 230.28824 -93.628071) (xy 230.234283 -93.642177)
			(xy 230.178846 -93.648277) (xy 230.123112 -93.64624) (xy 230.068269 -93.63611) (xy 230.015485 -93.618103)
			(xy 229.965885 -93.592602) (xy 229.920527 -93.560151) (xy 229.880378 -93.521442) (xy 229.846292 -93.477299)
			(xy 229.818996 -93.428664) (xy 229.799073 -93.376573) (xy 229.786947 -93.322136) (xy 229.782876 -93.266514)
			(xy 228.953568 -93.266514) (xy 229.453694 -93.76664) (xy 236.86592 -93.76664) (xy 236.869991 -93.711018)
			(xy 236.882117 -93.656581) (xy 236.90204 -93.60449) (xy 236.929336 -93.555855) (xy 236.963422 -93.511712)
			(xy 237.003571 -93.473003) (xy 237.048929 -93.440552) (xy 237.098529 -93.415051) (xy 237.151313 -93.397044)
			(xy 237.206156 -93.386914) (xy 237.26189 -93.384877) (xy 237.317327 -93.390977) (xy 237.371284 -93.405083)
			(xy 237.422613 -93.426895) (xy 237.470219 -93.455949) (xy 237.513087 -93.491624) (xy 237.550304 -93.533161)
			(xy 237.581077 -93.579674) (xy 237.604749 -93.630171) (xy 237.620817 -93.683578) (xy 237.628937 -93.738754)
			(xy 237.629446 -93.76664) (xy 237.628937 -93.794526) (xy 237.620817 -93.849702) (xy 237.604749 -93.903109)
			(xy 237.581077 -93.953606) (xy 237.550304 -94.000119) (xy 237.513087 -94.041656) (xy 237.470219 -94.077331)
			(xy 237.43534 -94.098618) (xy 250.156724 -94.098618) (xy 250.160795 -94.042996) (xy 250.172921 -93.988559)
			(xy 250.192844 -93.936468) (xy 250.22014 -93.887833) (xy 250.254226 -93.84369) (xy 250.294375 -93.804981)
			(xy 250.339733 -93.77253) (xy 250.389333 -93.747029) (xy 250.442117 -93.729022) (xy 250.49696 -93.718892)
			(xy 250.552694 -93.716855) (xy 250.608131 -93.722955) (xy 250.662088 -93.737061) (xy 250.713417 -93.758873)
			(xy 250.761023 -93.787927) (xy 250.803891 -93.823602) (xy 250.841108 -93.865139) (xy 250.871881 -93.911652)
			(xy 250.895553 -93.962149) (xy 250.911621 -94.015556) (xy 250.919741 -94.070732) (xy 250.92025 -94.098618)
			(xy 250.919741 -94.126504) (xy 250.911621 -94.18168) (xy 250.895553 -94.235087) (xy 250.871881 -94.285584)
			(xy 250.841108 -94.332097) (xy 250.803891 -94.373634) (xy 250.761023 -94.409309) (xy 250.713417 -94.438363)
			(xy 250.662088 -94.460175) (xy 250.608131 -94.474281) (xy 250.552694 -94.480381) (xy 250.49696 -94.478344)
			(xy 250.442117 -94.468214) (xy 250.389333 -94.450207) (xy 250.339733 -94.424706) (xy 250.294375 -94.392255)
			(xy 250.254226 -94.353546) (xy 250.22014 -94.309403) (xy 250.192844 -94.260768) (xy 250.172921 -94.208677)
			(xy 250.160795 -94.15424) (xy 250.156724 -94.098618) (xy 237.43534 -94.098618) (xy 237.422613 -94.106385)
			(xy 237.371284 -94.128197) (xy 237.317327 -94.142303) (xy 237.26189 -94.148403) (xy 237.206156 -94.146366)
			(xy 237.151313 -94.136236) (xy 237.098529 -94.118229) (xy 237.048929 -94.092728) (xy 237.003571 -94.060277)
			(xy 236.963422 -94.021568) (xy 236.929336 -93.977425) (xy 236.90204 -93.92879) (xy 236.882117 -93.876699)
			(xy 236.869991 -93.822262) (xy 236.86592 -93.76664) (xy 229.453694 -93.76664) (xy 229.966012 -94.278958)
			(xy 229.974154 -94.286325) (xy 229.994745 -94.293893) (xy 230.016617 -94.292201) (xy 230.026464 -94.28734)
			(xy 230.054919 -94.272366) (xy 230.115596 -94.251098) (xy 230.178975 -94.24028) (xy 230.211122 -94.239588)
			(xy 230.211376 -94.239588) (xy 230.238628 -94.240078) (xy 230.292578 -94.247831) (xy 230.344875 -94.263184)
			(xy 230.394455 -94.285823) (xy 230.440308 -94.315289) (xy 230.481501 -94.35098) (xy 230.517195 -94.39217)
			(xy 230.546663 -94.438021) (xy 230.569306 -94.487599) (xy 230.584663 -94.539895) (xy 230.59242 -94.593844)
			(xy 230.592884 -94.621096) (xy 230.592884 -94.62135) (xy 230.592212 -94.6535) (xy 230.587869 -94.679008)
			(xy 231.593134 -94.679008) (xy 231.597205 -94.623386) (xy 231.609331 -94.568949) (xy 231.629254 -94.516858)
			(xy 231.65655 -94.468223) (xy 231.690636 -94.42408) (xy 231.730785 -94.385371) (xy 231.776143 -94.35292)
			(xy 231.825743 -94.327419) (xy 231.878527 -94.309412) (xy 231.93337 -94.299282) (xy 231.989104 -94.297245)
			(xy 232.044541 -94.303345) (xy 232.098498 -94.317451) (xy 232.149827 -94.339263) (xy 232.197433 -94.368317)
			(xy 232.240301 -94.403992) (xy 232.277518 -94.445529) (xy 232.308291 -94.492042) (xy 232.331963 -94.542539)
			(xy 232.348031 -94.595946) (xy 232.354573 -94.6404) (xy 235.823504 -94.6404) (xy 235.827575 -94.584778)
			(xy 235.839701 -94.530341) (xy 235.859624 -94.47825) (xy 235.88692 -94.429615) (xy 235.921006 -94.385472)
			(xy 235.961155 -94.346763) (xy 236.006513 -94.314312) (xy 236.056113 -94.288811) (xy 236.108897 -94.270804)
			(xy 236.16374 -94.260674) (xy 236.219474 -94.258637) (xy 236.274911 -94.264737) (xy 236.328868 -94.278843)
			(xy 236.380197 -94.300655) (xy 236.427803 -94.329709) (xy 236.470671 -94.365384) (xy 236.507888 -94.406921)
			(xy 236.538661 -94.453434) (xy 236.562333 -94.503931) (xy 236.578401 -94.557338) (xy 236.586521 -94.612514)
			(xy 236.58703 -94.6404) (xy 236.586521 -94.668286) (xy 236.578401 -94.723462) (xy 236.562333 -94.776869)
			(xy 236.538661 -94.827366) (xy 236.507888 -94.873879) (xy 236.470671 -94.915416) (xy 236.427803 -94.951091)
			(xy 236.380197 -94.980145) (xy 236.328868 -95.001957) (xy 236.274911 -95.016063) (xy 236.219474 -95.022163)
			(xy 236.16374 -95.020126) (xy 236.108897 -95.009996) (xy 236.056113 -94.991989) (xy 236.006513 -94.966488)
			(xy 235.961155 -94.934037) (xy 235.921006 -94.895328) (xy 235.88692 -94.851185) (xy 235.859624 -94.80255)
			(xy 235.839701 -94.750459) (xy 235.827575 -94.696022) (xy 235.823504 -94.6404) (xy 232.354573 -94.6404)
			(xy 232.356151 -94.651122) (xy 232.35666 -94.679008) (xy 232.356151 -94.706894) (xy 232.348031 -94.76207)
			(xy 232.331963 -94.815477) (xy 232.308291 -94.865974) (xy 232.277518 -94.912487) (xy 232.240301 -94.954024)
			(xy 232.197433 -94.989699) (xy 232.149827 -95.018753) (xy 232.098498 -95.040565) (xy 232.044541 -95.054671)
			(xy 231.989104 -95.060771) (xy 231.93337 -95.058734) (xy 231.878527 -95.048604) (xy 231.825743 -95.030597)
			(xy 231.776143 -95.005096) (xy 231.730785 -94.972645) (xy 231.690636 -94.933936) (xy 231.65655 -94.889793)
			(xy 231.629254 -94.841158) (xy 231.609331 -94.789067) (xy 231.597205 -94.73463) (xy 231.593134 -94.679008)
			(xy 230.587869 -94.679008) (xy 230.58142 -94.716889) (xy 230.560134 -94.777565) (xy 230.545132 -94.806008)
			(xy 230.540326 -94.815875) (xy 230.538626 -94.837727) (xy 230.546175 -94.858304) (xy 230.553514 -94.86646)
			(xy 230.917496 -95.230442) (xy 230.924492 -95.236967) (xy 230.941996 -95.244656) (xy 230.951532 -95.245428)
			(xy 231.02062 -95.247968) (xy 231.030076 -95.24797) (xy 231.047951 -95.241832) (xy 231.055418 -95.23603)
			(xy 231.055672 -95.235776) (xy 231.076522 -95.218516) (xy 231.122173 -95.189436) (xy 231.171475 -95.167098)
			(xy 231.223438 -95.151952) (xy 231.277021 -95.144301) (xy 231.304084 -95.143828) (xy 231.331338 -95.14427)
			(xy 231.385292 -95.152026) (xy 231.437592 -95.167382) (xy 231.487175 -95.190025) (xy 231.533029 -95.219495)
			(xy 231.574223 -95.255191) (xy 231.609917 -95.296387) (xy 231.639384 -95.342243) (xy 231.662025 -95.391827)
			(xy 231.677378 -95.444128) (xy 231.685131 -95.498082) (xy 231.685592 -95.525336) (xy 231.685093 -95.552398)
			(xy 231.677451 -95.605981) (xy 231.662312 -95.657945) (xy 231.63998 -95.707248) (xy 231.610904 -95.752899)
			(xy 231.593644 -95.773748) (xy 231.59339 -95.774002) (xy 231.587602 -95.781479) (xy 231.58146 -95.799346)
			(xy 231.581452 -95.8088) (xy 231.583992 -95.877888) (xy 231.584765 -95.887329) (xy 231.592329 -95.904682)
			(xy 231.598724 -95.91167) (xy 231.729534 -96.042734) (xy 231.736924 -96.049586) (xy 231.755531 -96.057298)
			(xy 231.765602 -96.05772) (xy 232.264712 -96.05772) (xy 232.274874 -96.057307) (xy 232.293611 -96.049434)
			(xy 232.301034 -96.04248) (xy 232.358946 -95.983552) (xy 232.366566 -95.964502) (xy 232.366312 -95.954342)
			(xy 232.366312 -95.947992) (xy 232.366798 -95.920741) (xy 232.374554 -95.866793) (xy 232.389909 -95.814498)
			(xy 232.412551 -95.764921) (xy 232.442017 -95.719071) (xy 232.477708 -95.67788) (xy 232.518899 -95.642189)
			(xy 232.564749 -95.612723) (xy 232.614326 -95.590081) (xy 232.666621 -95.574726) (xy 232.720569 -95.56697)
			(xy 232.775071 -95.56697) (xy 232.829019 -95.574726) (xy 232.881314 -95.590081) (xy 232.930891 -95.612723)
			(xy 232.976741 -95.642189) (xy 233.017932 -95.67788) (xy 233.053623 -95.719071) (xy 233.083089 -95.764921)
			(xy 233.105731 -95.814498) (xy 233.121086 -95.866793) (xy 233.128842 -95.920741) (xy 233.129328 -95.947992)
			(xy 233.129328 -95.954342) (xy 233.129074 -95.964502) (xy 233.136694 -95.983552) (xy 233.194606 -96.04248)
			(xy 233.20205 -96.049402) (xy 233.220774 -96.057266) (xy 233.230928 -96.05772) (xy 233.594402 -96.05772)
			(xy 233.60312 -96.057327) (xy 233.619527 -96.051412) (xy 233.633021 -96.040361) (xy 233.637836 -96.033082)
			(xy 233.682794 -95.958406) (xy 233.687001 -95.95073) (xy 233.690402 -95.933569) (xy 233.687852 -95.916261)
			(xy 233.684064 -95.908368) (xy 233.670075 -95.880706) (xy 233.650289 -95.821963) (xy 233.64024 -95.760798)
			(xy 233.639614 -95.729806) (xy 233.639614 -95.729552) (xy 233.6401 -95.702301) (xy 233.647856 -95.648353)
			(xy 233.663211 -95.596058) (xy 233.685853 -95.546481) (xy 233.715319 -95.500631) (xy 233.75101 -95.45944)
			(xy 233.792201 -95.423749) (xy 233.838051 -95.394283) (xy 233.887628 -95.371641) (xy 233.939923 -95.356286)
			(xy 233.993871 -95.34853) (xy 234.048373 -95.34853) (xy 234.102321 -95.356286) (xy 234.154616 -95.371641)
			(xy 234.204193 -95.394283) (xy 234.250043 -95.423749) (xy 234.291234 -95.45944) (xy 234.326925 -95.500631)
			(xy 234.356391 -95.546481) (xy 234.379033 -95.596058) (xy 234.394388 -95.648353) (xy 234.402144 -95.702301)
			(xy 234.40263 -95.729552) (xy 234.40263 -95.729806) (xy 234.402029 -95.7608) (xy 234.391989 -95.82197)
			(xy 234.372175 -95.880707) (xy 234.35818 -95.908368) (xy 234.354418 -95.91627) (xy 234.351862 -95.933568)
			(xy 234.35527 -95.950719) (xy 234.35945 -95.958406) (xy 234.404408 -96.033082) (xy 234.409164 -96.040414)
			(xy 234.422656 -96.051508) (xy 234.439107 -96.057377) (xy 234.447842 -96.05772) (xy 235.789216 -96.05772)
			(xy 235.798149 -96.057436) (xy 235.814945 -96.051349) (xy 235.828644 -96.039881) (xy 235.833412 -96.03232)
			(xy 235.884212 -95.943674) (xy 235.883958 -95.91675) (xy 235.8771 -95.904812) (xy 235.864713 -95.882858)
			(xy 235.845233 -95.836366) (xy 235.832061 -95.787709) (xy 235.825428 -95.737738) (xy 235.82503 -95.712534)
			(xy 235.825516 -95.685283) (xy 235.833272 -95.631335) (xy 235.848627 -95.57904) (xy 235.871269 -95.529463)
			(xy 235.900735 -95.483613) (xy 235.936426 -95.442422) (xy 235.977617 -95.406731) (xy 236.023467 -95.377265)
			(xy 236.073044 -95.354623) (xy 236.125339 -95.339268) (xy 236.179287 -95.331512) (xy 236.233789 -95.331512)
			(xy 236.287737 -95.339268) (xy 236.340032 -95.354623) (xy 236.389609 -95.377265) (xy 236.435459 -95.406731)
			(xy 236.47665 -95.442422) (xy 236.512341 -95.483613) (xy 236.541807 -95.529463) (xy 236.564449 -95.57904)
			(xy 236.579804 -95.631335) (xy 236.58756 -95.685283) (xy 236.588046 -95.712534) (xy 236.587612 -95.737734)
			(xy 236.580946 -95.787693) (xy 236.567774 -95.836343) (xy 236.548324 -95.88284) (xy 236.535976 -95.904812)
			(xy 236.531811 -95.912674) (xy 236.528655 -95.930172) (xy 236.531655 -95.947697) (xy 236.535722 -95.955612)
			(xy 236.579664 -96.03232) (xy 236.584446 -96.039872) (xy 236.598129 -96.051352) (xy 236.614928 -96.057417)
			(xy 236.62386 -96.05772) (xy 251.17933 -96.05772) (xy 251.189404 -96.057332) (xy 251.208003 -96.049587)
			(xy 251.215398 -96.042734) (xy 255.670812 -91.587066) (xy 255.676654 -91.557094) (xy 255.670812 -91.54287)
			(xy 255.666456 -91.533861) (xy 255.652281 -91.519771) (xy 255.633814 -91.512129) (xy 255.623822 -91.511628)
			(xy 249.310652 -91.511628) (xy 249.277771 -91.511175) (xy 249.212423 -91.503812) (xy 249.148311 -91.489174)
			(xy 249.086243 -91.467445) (xy 249.027001 -91.438898) (xy 248.97133 -91.403893) (xy 248.919932 -91.362871)
			(xy 248.896378 -91.339924) (xy 247.396 -89.839546) (xy 247.373084 -89.815967) (xy 247.33209 -89.764556)
			(xy 247.297104 -89.708882) (xy 247.268564 -89.649644) (xy 247.24683 -89.587586) (xy 247.232172 -89.523486)
			(xy 247.224776 -89.458149) (xy 247.224296 -89.425272) (xy 247.224296 -88.039448) (xy 247.22486 -88.003308)
			(xy 247.2338 -87.931583) (xy 247.25149 -87.861501) (xy 247.27766 -87.794125) (xy 247.311914 -87.730477)
			(xy 247.353732 -87.671522) (xy 247.377712 -87.644478) (xy 247.383687 -87.63726) (xy 247.390451 -87.619801)
			(xy 247.39092 -87.610442) (xy 247.39092 -87.579454) (xy 247.39055 -87.570076) (xy 247.383765 -87.552591)
			(xy 247.377712 -87.545418) (xy 247.353703 -87.518397) (xy 247.311866 -87.459448) (xy 247.277602 -87.395799)
			(xy 247.251433 -87.328416) (xy 247.233757 -87.258325) (xy 247.224841 -87.186591) (xy 247.224296 -87.150448)
			(xy 247.224835 -87.11504) (xy 247.233368 -87.044739) (xy 247.250316 -86.975981) (xy 247.275431 -86.909767)
			(xy 247.308346 -86.847065) (xy 247.348582 -86.78879) (xy 247.395551 -86.735791) (xy 247.448568 -86.688842)
			(xy 247.506859 -86.648629) (xy 247.569574 -86.615738) (xy 247.635797 -86.590648) (xy 247.704562 -86.573727)
			(xy 247.774866 -86.565221) (xy 247.810274 -86.564724) (xy 247.843146 -86.565163) (xy 247.908478 -86.572509)
			(xy 247.972578 -86.587122) (xy 248.034638 -86.60882) (xy 248.093879 -86.637328) (xy 248.149557 -86.672289)
			(xy 248.200971 -86.713264) (xy 248.224548 -86.736174) (xy 248.271284 -86.78291) (xy 249.4821 -86.78291)
			(xy 249.486171 -86.727288) (xy 249.498297 -86.672851) (xy 249.51822 -86.62076) (xy 249.545516 -86.572125)
			(xy 249.579602 -86.527982) (xy 249.619751 -86.489273) (xy 249.665109 -86.456822) (xy 249.714709 -86.431321)
			(xy 249.767493 -86.413314) (xy 249.822336 -86.403184) (xy 249.87807 -86.401147) (xy 249.933507 -86.407247)
			(xy 249.987464 -86.421353) (xy 250.038793 -86.443165) (xy 250.086399 -86.472219) (xy 250.09012 -86.475316)
			(xy 251.185172 -86.475316) (xy 251.18563 -86.447945) (xy 251.193447 -86.393765) (xy 251.208937 -86.341261)
			(xy 251.231781 -86.291514) (xy 251.261509 -86.245549) (xy 251.279152 -86.224618) (xy 251.279406 -86.224364)
			(xy 251.284973 -86.217264) (xy 251.291231 -86.200357) (xy 251.291598 -86.191344) (xy 251.291598 -86.124288)
			(xy 251.291247 -86.115271) (xy 251.284995 -86.098354) (xy 251.279406 -86.091268) (xy 251.279152 -86.091268)
			(xy 251.279152 -86.091014) (xy 251.261514 -86.070081) (xy 251.2318 -86.024109) (xy 251.208963 -85.974362)
			(xy 251.193472 -85.921861) (xy 251.185645 -85.867685) (xy 251.185172 -85.840316) (xy 251.185658 -85.813065)
			(xy 251.193414 -85.759117) (xy 251.208769 -85.706822) (xy 251.231411 -85.657245) (xy 251.260877 -85.611395)
			(xy 251.296568 -85.570204) (xy 251.337759 -85.534513) (xy 251.383609 -85.505047) (xy 251.433186 -85.482405)
			(xy 251.485481 -85.46705) (xy 251.539429 -85.459294) (xy 251.593931 -85.459294) (xy 251.647879 -85.46705)
			(xy 251.700174 -85.482405) (xy 251.749751 -85.505047) (xy 251.795601 -85.534513) (xy 251.836792 -85.570204)
			(xy 251.872483 -85.611395) (xy 251.901949 -85.657245) (xy 251.924591 -85.706822) (xy 251.939946 -85.759117)
			(xy 251.947702 -85.813065) (xy 251.948188 -85.840316) (xy 251.947734 -85.867687) (xy 251.939914 -85.921866)
			(xy 251.924422 -85.97437) (xy 251.901578 -86.024116) (xy 251.87185 -86.070083) (xy 251.854208 -86.091014)
			(xy 251.853954 -86.091268) (xy 251.848369 -86.098356) (xy 251.842123 -86.115272) (xy 251.841762 -86.124288)
			(xy 251.841762 -86.191344) (xy 251.842154 -86.200357) (xy 251.848378 -86.217274) (xy 251.853954 -86.224364)
			(xy 251.854208 -86.224364) (xy 251.854208 -86.224618) (xy 251.871823 -86.245569) (xy 251.901538 -86.291537)
			(xy 251.924379 -86.34128) (xy 251.939876 -86.393776) (xy 251.94344 -86.41842) (xy 264.566906 -86.41842)
			(xy 264.570977 -86.362798) (xy 264.583103 -86.308361) (xy 264.603026 -86.25627) (xy 264.630322 -86.207635)
			(xy 264.664408 -86.163492) (xy 264.704557 -86.124783) (xy 264.749915 -86.092332) (xy 264.799515 -86.066831)
			(xy 264.852299 -86.048824) (xy 264.907142 -86.038694) (xy 264.962876 -86.036657) (xy 265.018313 -86.042757)
			(xy 265.07227 -86.056863) (xy 265.123599 -86.078675) (xy 265.171205 -86.107729) (xy 265.214073 -86.143404)
			(xy 265.25129 -86.184941) (xy 265.282063 -86.231454) (xy 265.305735 -86.281951) (xy 265.321803 -86.335358)
			(xy 265.329923 -86.390534) (xy 265.330432 -86.41842) (xy 265.329923 -86.446306) (xy 265.321803 -86.501482)
			(xy 265.305735 -86.554889) (xy 265.282063 -86.605386) (xy 265.25129 -86.651899) (xy 265.214073 -86.693436)
			(xy 265.171205 -86.729111) (xy 265.123599 -86.758165) (xy 265.07227 -86.779977) (xy 265.018313 -86.794083)
			(xy 264.962876 -86.800183) (xy 264.907142 -86.798146) (xy 264.852299 -86.788016) (xy 264.799515 -86.770009)
			(xy 264.749915 -86.744508) (xy 264.704557 -86.712057) (xy 264.664408 -86.673348) (xy 264.630322 -86.629205)
			(xy 264.603026 -86.58057) (xy 264.583103 -86.528479) (xy 264.570977 -86.474042) (xy 264.566906 -86.41842)
			(xy 251.94344 -86.41842) (xy 251.94771 -86.447948) (xy 251.948188 -86.475316) (xy 251.947702 -86.502567)
			(xy 251.939946 -86.556515) (xy 251.924591 -86.60881) (xy 251.901949 -86.658387) (xy 251.872483 -86.704237)
			(xy 251.836792 -86.745428) (xy 251.795601 -86.781119) (xy 251.749751 -86.810585) (xy 251.700174 -86.833227)
			(xy 251.647879 -86.848582) (xy 251.593931 -86.856338) (xy 251.539429 -86.856338) (xy 251.485481 -86.848582)
			(xy 251.433186 -86.833227) (xy 251.383609 -86.810585) (xy 251.337759 -86.781119) (xy 251.296568 -86.745428)
			(xy 251.260877 -86.704237) (xy 251.231411 -86.658387) (xy 251.208769 -86.60881) (xy 251.193414 -86.556515)
			(xy 251.185658 -86.502567) (xy 251.185172 -86.475316) (xy 250.09012 -86.475316) (xy 250.129267 -86.507894)
			(xy 250.166484 -86.549431) (xy 250.197257 -86.595944) (xy 250.220929 -86.646441) (xy 250.236997 -86.699848)
			(xy 250.245117 -86.755024) (xy 250.245626 -86.78291) (xy 250.245117 -86.810796) (xy 250.236997 -86.865972)
			(xy 250.220929 -86.919379) (xy 250.197257 -86.969876) (xy 250.166484 -87.016389) (xy 250.129267 -87.057926)
			(xy 250.086399 -87.093601) (xy 250.038793 -87.122655) (xy 249.987464 -87.144467) (xy 249.933507 -87.158573)
			(xy 249.87807 -87.164673) (xy 249.822336 -87.162636) (xy 249.767493 -87.152506) (xy 249.714709 -87.134499)
			(xy 249.665109 -87.108998) (xy 249.619751 -87.076547) (xy 249.579602 -87.037838) (xy 249.545516 -86.993695)
			(xy 249.51822 -86.94506) (xy 249.498297 -86.892969) (xy 249.486171 -86.838532) (xy 249.4821 -86.78291)
			(xy 248.271284 -86.78291) (xy 248.829322 -87.340948) (xy 250.984002 -87.340948) (xy 250.988073 -87.285326)
			(xy 251.000199 -87.230889) (xy 251.020122 -87.178798) (xy 251.047418 -87.130163) (xy 251.081504 -87.08602)
			(xy 251.121653 -87.047311) (xy 251.167011 -87.01486) (xy 251.216611 -86.989359) (xy 251.269395 -86.971352)
			(xy 251.324238 -86.961222) (xy 251.379972 -86.959185) (xy 251.435409 -86.965285) (xy 251.489366 -86.979391)
			(xy 251.540695 -87.001203) (xy 251.588301 -87.030257) (xy 251.631169 -87.065932) (xy 251.668386 -87.107469)
			(xy 251.699159 -87.153982) (xy 251.722831 -87.204479) (xy 251.738899 -87.257886) (xy 251.747019 -87.313062)
			(xy 251.747528 -87.340948) (xy 251.747019 -87.368834) (xy 251.738899 -87.42401) (xy 251.722831 -87.477417)
			(xy 251.699159 -87.527914) (xy 251.668386 -87.574427) (xy 251.631169 -87.615964) (xy 251.588301 -87.651639)
			(xy 251.540695 -87.680693) (xy 251.489366 -87.702505) (xy 251.435409 -87.716611) (xy 251.405373 -87.719916)
			(xy 252.861062 -87.719916) (xy 252.865133 -87.664294) (xy 252.877259 -87.609857) (xy 252.897182 -87.557766)
			(xy 252.924478 -87.509131) (xy 252.958564 -87.464988) (xy 252.998713 -87.426279) (xy 253.044071 -87.393828)
			(xy 253.093671 -87.368327) (xy 253.146455 -87.35032) (xy 253.201298 -87.34019) (xy 253.257032 -87.338153)
			(xy 253.312469 -87.344253) (xy 253.366426 -87.358359) (xy 253.417755 -87.380171) (xy 253.465361 -87.409225)
			(xy 253.508229 -87.4449) (xy 253.545446 -87.486437) (xy 253.554051 -87.499444) (xy 256.099562 -87.499444)
			(xy 256.103633 -87.443822) (xy 256.115759 -87.389385) (xy 256.135682 -87.337294) (xy 256.162978 -87.288659)
			(xy 256.197064 -87.244516) (xy 256.237213 -87.205807) (xy 256.282571 -87.173356) (xy 256.332171 -87.147855)
			(xy 256.384955 -87.129848) (xy 256.439798 -87.119718) (xy 256.495532 -87.117681) (xy 256.550969 -87.123781)
			(xy 256.604926 -87.137887) (xy 256.656255 -87.159699) (xy 256.703861 -87.188753) (xy 256.746729 -87.224428)
			(xy 256.770794 -87.251286) (xy 269.21028 -87.251286) (xy 269.214351 -87.195664) (xy 269.226477 -87.141227)
			(xy 269.2464 -87.089136) (xy 269.273696 -87.040501) (xy 269.307782 -86.996358) (xy 269.347931 -86.957649)
			(xy 269.393289 -86.925198) (xy 269.442889 -86.899697) (xy 269.495673 -86.88169) (xy 269.550516 -86.87156)
			(xy 269.60625 -86.869523) (xy 269.661687 -86.875623) (xy 269.715644 -86.889729) (xy 269.766973 -86.911541)
			(xy 269.814579 -86.940595) (xy 269.857447 -86.97627) (xy 269.894664 -87.017807) (xy 269.925437 -87.06432)
			(xy 269.949109 -87.114817) (xy 269.965177 -87.168224) (xy 269.973297 -87.2234) (xy 269.973806 -87.251286)
			(xy 269.973297 -87.279172) (xy 269.965177 -87.334348) (xy 269.949109 -87.387755) (xy 269.925437 -87.438252)
			(xy 269.894664 -87.484765) (xy 269.857447 -87.526302) (xy 269.814579 -87.561977) (xy 269.766973 -87.591031)
			(xy 269.715644 -87.612843) (xy 269.661687 -87.626949) (xy 269.60625 -87.633049) (xy 269.550516 -87.631012)
			(xy 269.495673 -87.620882) (xy 269.442889 -87.602875) (xy 269.393289 -87.577374) (xy 269.347931 -87.544923)
			(xy 269.307782 -87.506214) (xy 269.273696 -87.462071) (xy 269.2464 -87.413436) (xy 269.226477 -87.361345)
			(xy 269.214351 -87.306908) (xy 269.21028 -87.251286) (xy 256.770794 -87.251286) (xy 256.783946 -87.265965)
			(xy 256.814719 -87.312478) (xy 256.838391 -87.362975) (xy 256.854459 -87.416382) (xy 256.862579 -87.471558)
			(xy 256.863088 -87.499444) (xy 256.862579 -87.52733) (xy 256.854459 -87.582506) (xy 256.838391 -87.635913)
			(xy 256.814719 -87.68641) (xy 256.783946 -87.732923) (xy 256.746729 -87.77446) (xy 256.703861 -87.810135)
			(xy 256.656255 -87.839189) (xy 256.604926 -87.861001) (xy 256.550969 -87.875107) (xy 256.495532 -87.881207)
			(xy 256.439798 -87.87917) (xy 256.384955 -87.86904) (xy 256.332171 -87.851033) (xy 256.282571 -87.825532)
			(xy 256.237213 -87.793081) (xy 256.197064 -87.754372) (xy 256.162978 -87.710229) (xy 256.135682 -87.661594)
			(xy 256.115759 -87.609503) (xy 256.103633 -87.555066) (xy 256.099562 -87.499444) (xy 253.554051 -87.499444)
			(xy 253.576219 -87.53295) (xy 253.599891 -87.583447) (xy 253.615959 -87.636854) (xy 253.624079 -87.69203)
			(xy 253.624588 -87.719916) (xy 253.624079 -87.747802) (xy 253.615959 -87.802978) (xy 253.599891 -87.856385)
			(xy 253.576219 -87.906882) (xy 253.545446 -87.953395) (xy 253.508229 -87.994932) (xy 253.465361 -88.030607)
			(xy 253.417755 -88.059661) (xy 253.366426 -88.081473) (xy 253.312469 -88.095579) (xy 253.257032 -88.101679)
			(xy 253.201298 -88.099642) (xy 253.146455 -88.089512) (xy 253.093671 -88.071505) (xy 253.044071 -88.046004)
			(xy 252.998713 -88.013553) (xy 252.958564 -87.974844) (xy 252.924478 -87.930701) (xy 252.897182 -87.882066)
			(xy 252.877259 -87.829975) (xy 252.865133 -87.775538) (xy 252.861062 -87.719916) (xy 251.405373 -87.719916)
			(xy 251.379972 -87.722711) (xy 251.324238 -87.720674) (xy 251.269395 -87.710544) (xy 251.216611 -87.692537)
			(xy 251.167011 -87.667036) (xy 251.121653 -87.634585) (xy 251.081504 -87.595876) (xy 251.047418 -87.551733)
			(xy 251.020122 -87.503098) (xy 251.000199 -87.451007) (xy 250.988073 -87.39657) (xy 250.984002 -87.340948)
			(xy 248.829322 -87.340948) (xy 249.05081 -87.562436) (xy 249.073729 -87.585981) (xy 249.11469 -87.637362)
			(xy 249.149642 -87.693006) (xy 249.178144 -87.752213) (xy 249.199838 -87.814239) (xy 249.214453 -87.878303)
			(xy 249.221803 -87.943601) (xy 249.22226 -87.976456) (xy 249.22226 -88.049608) (xy 249.542806 -88.049608)
			(xy 249.546877 -87.993986) (xy 249.559003 -87.939549) (xy 249.578926 -87.887458) (xy 249.606222 -87.838823)
			(xy 249.640308 -87.79468) (xy 249.680457 -87.755971) (xy 249.725815 -87.72352) (xy 249.775415 -87.698019)
			(xy 249.828199 -87.680012) (xy 249.883042 -87.669882) (xy 249.938776 -87.667845) (xy 249.994213 -87.673945)
			(xy 250.04817 -87.688051) (xy 250.099499 -87.709863) (xy 250.147105 -87.738917) (xy 250.189973 -87.774592)
			(xy 250.22719 -87.816129) (xy 250.257963 -87.862642) (xy 250.281635 -87.913139) (xy 250.297703 -87.966546)
			(xy 250.305823 -88.021722) (xy 250.306332 -88.049608) (xy 250.305823 -88.077494) (xy 250.297703 -88.13267)
			(xy 250.281635 -88.186077) (xy 250.257963 -88.236574) (xy 250.22719 -88.283087) (xy 250.189973 -88.324624)
			(xy 250.147105 -88.360299) (xy 250.099499 -88.389353) (xy 250.04817 -88.411165) (xy 249.994213 -88.425271)
			(xy 249.938776 -88.431371) (xy 249.883042 -88.429334) (xy 249.828199 -88.419204) (xy 249.775415 -88.401197)
			(xy 249.725815 -88.375696) (xy 249.680457 -88.343245) (xy 249.640308 -88.304536) (xy 249.606222 -88.260393)
			(xy 249.578926 -88.211758) (xy 249.559003 -88.159667) (xy 249.546877 -88.10523) (xy 249.542806 -88.049608)
			(xy 249.22226 -88.049608) (xy 249.22226 -88.771984) (xy 250.730256 -88.771984) (xy 250.734327 -88.716362)
			(xy 250.746453 -88.661925) (xy 250.766376 -88.609834) (xy 250.793672 -88.561199) (xy 250.827758 -88.517056)
			(xy 250.867907 -88.478347) (xy 250.913265 -88.445896) (xy 250.962865 -88.420395) (xy 251.015649 -88.402388)
			(xy 251.070492 -88.392258) (xy 251.126226 -88.390221) (xy 251.181663 -88.396321) (xy 251.23562 -88.410427)
			(xy 251.286949 -88.432239) (xy 251.334555 -88.461293) (xy 251.377423 -88.496968) (xy 251.41464 -88.538505)
			(xy 251.445413 -88.585018) (xy 251.469085 -88.635515) (xy 251.485153 -88.688922) (xy 251.493273 -88.744098)
			(xy 251.493782 -88.771984) (xy 251.493273 -88.79987) (xy 251.485153 -88.855046) (xy 251.469085 -88.908453)
			(xy 251.445413 -88.95895) (xy 251.41464 -89.005463) (xy 251.377423 -89.047) (xy 251.334555 -89.082675)
			(xy 251.286949 -89.111729) (xy 251.23562 -89.133541) (xy 251.181663 -89.147647) (xy 251.126226 -89.153747)
			(xy 251.070492 -89.15171) (xy 251.015649 -89.14158) (xy 250.962865 -89.123573) (xy 250.913265 -89.098072)
			(xy 250.867907 -89.065621) (xy 250.827758 -89.026912) (xy 250.793672 -88.982769) (xy 250.766376 -88.934134)
			(xy 250.746453 -88.882043) (xy 250.734327 -88.827606) (xy 250.730256 -88.771984) (xy 249.22226 -88.771984)
			(xy 249.22226 -88.981026) (xy 249.222771 -88.991485) (xy 249.231175 -89.010641) (xy 249.238516 -89.01811)
			(xy 249.300492 -89.076022) (xy 249.320304 -89.083134) (xy 249.330718 -89.082372) (xy 249.356626 -89.08161)
			(xy 249.383879 -89.082054) (xy 249.437829 -89.089814) (xy 249.490126 -89.105174) (xy 249.539704 -89.127819)
			(xy 249.585555 -89.15729) (xy 249.626746 -89.192986) (xy 249.662437 -89.23418) (xy 249.691902 -89.280035)
			(xy 249.714542 -89.329616) (xy 249.729895 -89.381914) (xy 249.737649 -89.435865) (xy 249.738134 -89.463118)
			(xy 249.73773 -89.488247) (xy 249.731129 -89.538068) (xy 249.718044 -89.586592) (xy 249.698702 -89.632978)
			(xy 249.673436 -89.676423) (xy 249.658378 -89.696544) (xy 249.646694 -89.711784) (xy 249.649234 -89.749884)
			(xy 249.747786 -89.84869) (xy 249.755198 -89.855515) (xy 249.773788 -89.863244) (xy 249.783854 -89.863676)
			(xy 251.800106 -89.863676) (xy 251.809266 -89.863235) (xy 251.826406 -89.856758) (xy 251.840174 -89.844669)
			(xy 251.848813 -89.828511) (xy 251.850398 -89.81948) (xy 251.850398 -89.819226) (xy 251.854428 -89.792021)
			(xy 251.869292 -89.739073) (xy 251.891606 -89.688808) (xy 251.920909 -89.64227) (xy 251.956591 -89.600422)
			(xy 251.997914 -89.564134) (xy 252.044021 -89.534156) (xy 252.093955 -89.511112) (xy 252.146682 -89.495478)
			(xy 252.201106 -89.48758) (xy 252.256102 -89.48758) (xy 252.310526 -89.495478) (xy 252.363253 -89.511112)
			(xy 252.413187 -89.534156) (xy 252.459294 -89.564134) (xy 252.500617 -89.600422) (xy 252.536299 -89.64227)
			(xy 252.565602 -89.688808) (xy 252.587916 -89.739073) (xy 252.60278 -89.792021) (xy 252.60681 -89.819226)
			(xy 252.60681 -89.81948) (xy 252.608305 -89.828542) (xy 252.616937 -89.844744) (xy 252.630736 -89.856851)
			(xy 252.647922 -89.863303) (xy 252.657102 -89.863676) (xy 252.768608 -89.863676) (xy 252.778633 -89.863286)
			(xy 252.797154 -89.855609) (xy 252.811327 -89.841428) (xy 252.818993 -89.822901) (xy 252.819408 -89.812876)
			(xy 252.819408 -89.799414) (xy 252.8062 -89.776046) (xy 252.794516 -89.769188) (xy 252.770586 -89.75434)
			(xy 252.727008 -89.718667) (xy 252.689146 -89.676978) (xy 252.657822 -89.630177) (xy 252.633716 -89.57928)
			(xy 252.617353 -89.525393) (xy 252.609087 -89.469686) (xy 252.608588 -89.441528) (xy 252.609074 -89.414277)
			(xy 252.61683 -89.360329) (xy 252.632185 -89.308034) (xy 252.654827 -89.258457) (xy 252.684293 -89.212607)
			(xy 252.719984 -89.171416) (xy 252.761175 -89.135725) (xy 252.807025 -89.106259) (xy 252.856602 -89.083617)
			(xy 252.908897 -89.068262) (xy 252.962845 -89.060506) (xy 253.017347 -89.060506) (xy 253.071295 -89.068262)
			(xy 253.12359 -89.083617) (xy 253.150897 -89.096088) (xy 258.801106 -89.096088) (xy 258.805177 -89.040466)
			(xy 258.817303 -88.986029) (xy 258.837226 -88.933938) (xy 258.864522 -88.885303) (xy 258.898608 -88.84116)
			(xy 258.938757 -88.802451) (xy 258.984115 -88.77) (xy 259.033715 -88.744499) (xy 259.086499 -88.726492)
			(xy 259.141342 -88.716362) (xy 259.197076 -88.714325) (xy 259.252513 -88.720425) (xy 259.30647 -88.734531)
			(xy 259.357799 -88.756343) (xy 259.405405 -88.785397) (xy 259.448273 -88.821072) (xy 259.48549 -88.862609)
			(xy 259.516263 -88.909122) (xy 259.539935 -88.959619) (xy 259.554629 -89.008458) (xy 261.557768 -89.008458)
			(xy 261.561839 -88.952836) (xy 261.573965 -88.898399) (xy 261.593888 -88.846308) (xy 261.621184 -88.797673)
			(xy 261.65527 -88.75353) (xy 261.695419 -88.714821) (xy 261.740777 -88.68237) (xy 261.790377 -88.656869)
			(xy 261.843161 -88.638862) (xy 261.898004 -88.628732) (xy 261.953738 -88.626695) (xy 262.009175 -88.632795)
			(xy 262.063132 -88.646901) (xy 262.114461 -88.668713) (xy 262.162067 -88.697767) (xy 262.204935 -88.733442)
			(xy 262.242152 -88.774979) (xy 262.272925 -88.821492) (xy 262.296597 -88.871989) (xy 262.312665 -88.925396)
			(xy 262.320785 -88.980572) (xy 262.321294 -89.008458) (xy 262.320785 -89.036344) (xy 262.312665 -89.09152)
			(xy 262.296597 -89.144927) (xy 262.272925 -89.195424) (xy 262.242152 -89.241937) (xy 262.204935 -89.283474)
			(xy 262.162067 -89.319149) (xy 262.114461 -89.348203) (xy 262.063132 -89.370015) (xy 262.009175 -89.384121)
			(xy 261.953738 -89.390221) (xy 261.898004 -89.388184) (xy 261.843161 -89.378054) (xy 261.790377 -89.360047)
			(xy 261.740777 -89.334546) (xy 261.695419 -89.302095) (xy 261.65527 -89.263386) (xy 261.621184 -89.219243)
			(xy 261.593888 -89.170608) (xy 261.573965 -89.118517) (xy 261.561839 -89.06408) (xy 261.557768 -89.008458)
			(xy 259.554629 -89.008458) (xy 259.556003 -89.013026) (xy 259.564123 -89.068202) (xy 259.564632 -89.096088)
			(xy 259.564123 -89.123974) (xy 259.556003 -89.17915) (xy 259.539935 -89.232557) (xy 259.516263 -89.283054)
			(xy 259.48549 -89.329567) (xy 259.448273 -89.371104) (xy 259.405405 -89.406779) (xy 259.357799 -89.435833)
			(xy 259.30647 -89.457645) (xy 259.252513 -89.471751) (xy 259.197076 -89.477851) (xy 259.141342 -89.475814)
			(xy 259.086499 -89.465684) (xy 259.033715 -89.447677) (xy 258.984115 -89.422176) (xy 258.938757 -89.389725)
			(xy 258.898608 -89.351016) (xy 258.864522 -89.306873) (xy 258.837226 -89.258238) (xy 258.817303 -89.206147)
			(xy 258.805177 -89.15171) (xy 258.801106 -89.096088) (xy 253.150897 -89.096088) (xy 253.173167 -89.106259)
			(xy 253.219017 -89.135725) (xy 253.260208 -89.171416) (xy 253.295899 -89.212607) (xy 253.325365 -89.258457)
			(xy 253.348007 -89.308034) (xy 253.363362 -89.360329) (xy 253.371118 -89.414277) (xy 253.371604 -89.441528)
			(xy 253.371092 -89.469202) (xy 253.363097 -89.523969) (xy 253.347266 -89.577005) (xy 253.323931 -89.627193)
			(xy 253.293583 -89.673479) (xy 253.275592 -89.694512) (xy 253.269439 -89.702115) (xy 253.262842 -89.720506)
			(xy 253.263606 -89.740031) (xy 253.26721 -89.749122) (xy 253.30531 -89.833704) (xy 253.309653 -89.842444)
			(xy 253.323691 -89.855981) (xy 253.341786 -89.863256) (xy 253.351538 -89.863676) (xy 253.684024 -89.863676)
			(xy 253.695626 -89.863112) (xy 253.716515 -89.853021) (xy 253.730835 -89.83477) (xy 253.733808 -89.823544)
			(xy 253.740035 -89.796989) (xy 253.759056 -89.745871) (xy 253.785162 -89.697982) (xy 253.817822 -89.654299)
			(xy 253.85637 -89.615712) (xy 253.90002 -89.583007) (xy 253.947883 -89.556853) (xy 253.998982 -89.53778)
			(xy 254.052277 -89.526179) (xy 254.10668 -89.522285) (xy 254.161083 -89.526179) (xy 254.214378 -89.53778)
			(xy 254.265477 -89.556853) (xy 254.31334 -89.583007) (xy 254.35699 -89.615712) (xy 254.395538 -89.654299)
			(xy 254.428198 -89.697982) (xy 254.454304 -89.745871) (xy 254.473325 -89.796989) (xy 254.479552 -89.823544)
			(xy 254.482535 -89.83476) (xy 254.496885 -89.852976) (xy 254.517742 -89.863113) (xy 254.529336 -89.863676)
			(xy 264.430002 -89.863676) (xy 264.440072 -89.863258) (xy 264.45867 -89.855533) (xy 264.46607 -89.84869)
			(xy 266.194286 -88.12022) (xy 266.217854 -88.097292) (xy 266.269267 -88.056299) (xy 266.324943 -88.021313)
			(xy 266.384183 -87.992775) (xy 266.446243 -87.971042) (xy 266.510344 -87.956387) (xy 266.575683 -87.948995)
			(xy 266.60856 -87.948516) (xy 274.284694 -87.948516) (xy 274.317575 -87.948955) (xy 274.382923 -87.956322)
			(xy 274.447035 -87.970964) (xy 274.509102 -87.992696) (xy 274.568345 -88.021244) (xy 274.624015 -88.05625)
			(xy 274.675414 -88.097273) (xy 274.698968 -88.12022) (xy 274.765516 -88.186768) (xy 274.773991 -88.194435)
			(xy 274.795517 -88.202034) (xy 274.818214 -88.199599) (xy 274.828254 -88.194134) (xy 274.850867 -88.18075)
			(xy 274.899002 -88.15967) (xy 274.949573 -88.145392) (xy 275.001624 -88.138184) (xy 275.027898 -88.137746)
			(xy 275.058701 -88.138357) (xy 275.119502 -88.148281) (xy 275.177916 -88.167855) (xy 275.205444 -88.181688)
			(xy 275.205952 -88.181942) (xy 275.211272 -88.184421) (xy 275.222691 -88.187113) (xy 275.228558 -88.187276)
			(xy 275.866098 -88.187276) (xy 275.889614 -88.187655) (xy 275.936176 -88.194283) (xy 275.981335 -88.207421)
			(xy 276.024187 -88.226805) (xy 276.063871 -88.252047) (xy 276.081998 -88.267032) (xy 276.089078 -88.272627)
			(xy 276.106 -88.278868) (xy 276.115018 -88.279224) (xy 277.372064 -88.279224) (xy 277.397464 -88.262206)
			(xy 277.403306 -88.247982) (xy 277.406708 -88.238538) (xy 277.406673 -88.218483) (xy 277.398948 -88.199975)
			(xy 277.39213 -88.19261) (xy 276.395688 -87.195914) (xy 276.388285 -87.189078) (xy 276.369688 -87.181355)
			(xy 276.35962 -87.180928) (xy 275.196554 -87.180928) (xy 275.17053 -87.180401) (xy 275.119127 -87.172234)
			(xy 275.06963 -87.156139) (xy 275.023254 -87.132512) (xy 274.981137 -87.101932) (xy 274.962366 -87.0839)
			(xy 274.810728 -86.932262) (xy 274.806346 -86.928133) (xy 274.796074 -86.921856) (xy 274.790408 -86.919816)
			(xy 274.7899 -86.919816) (xy 274.764341 -86.911413) (xy 274.715736 -86.888335) (xy 274.670856 -86.858659)
			(xy 274.630589 -86.822972) (xy 274.595735 -86.781982) (xy 274.566985 -86.736503) (xy 274.544909 -86.687436)
			(xy 274.529945 -86.635754) (xy 274.522389 -86.582482) (xy 274.52193 -86.55558) (xy 274.522336 -86.528325)
			(xy 274.530097 -86.47437) (xy 274.545458 -86.422069) (xy 274.568105 -86.372486) (xy 274.597579 -86.326631)
			(xy 274.633279 -86.285437) (xy 274.674477 -86.249744) (xy 274.720337 -86.220277) (xy 274.769923 -86.197637)
			(xy 274.822227 -86.182285) (xy 274.876183 -86.174532) (xy 274.903438 -86.174072) (xy 274.930347 -86.174557)
			(xy 274.98363 -86.182138) (xy 275.035319 -86.19713) (xy 275.084389 -86.219236) (xy 275.129866 -86.248017)
			(xy 275.170849 -86.282902) (xy 275.206523 -86.323199) (xy 275.236182 -86.368108) (xy 275.259237 -86.416739)
			(xy 275.267674 -86.442296) (xy 275.267674 -86.44255) (xy 275.269647 -86.448246) (xy 275.275947 -86.458519)
			(xy 275.28012 -86.46287) (xy 275.298916 -86.481666) (xy 275.30635 -86.488382) (xy 275.32485 -86.496018)
			(xy 275.344864 -86.496018) (xy 275.363364 -86.488382) (xy 275.370798 -86.481666) (xy 275.377054 -86.474794)
			(xy 275.384652 -86.457857) (xy 275.385685 -86.439323) (xy 275.383244 -86.430358) (xy 275.383244 -86.42985)
			(xy 275.374652 -86.401404) (xy 275.365333 -86.342719) (xy 275.364702 -86.31301) (xy 275.365165 -86.285757)
			(xy 275.372921 -86.231805) (xy 275.388276 -86.179507) (xy 275.410918 -86.129926) (xy 275.440386 -86.084073)
			(xy 275.47608 -86.04288) (xy 275.517273 -86.007186) (xy 275.563126 -85.977718) (xy 275.612707 -85.955076)
			(xy 275.665005 -85.939721) (xy 275.718957 -85.931965) (xy 275.74621 -85.931502) (xy 275.777013 -85.932114)
			(xy 275.837814 -85.942038) (xy 275.896227 -85.961611) (xy 275.923756 -85.975444) (xy 275.924264 -85.975698)
			(xy 275.929578 -85.978191) (xy 275.941002 -85.980883) (xy 275.94687 -85.981032) (xy 276.60473 -85.981032)
			(xy 276.630817 -85.981539) (xy 276.682348 -85.989698) (xy 276.731966 -86.005824) (xy 276.778448 -86.02952)
			(xy 276.820645 -86.060202) (xy 276.839426 -86.078314) (xy 276.876002 -86.11489) (xy 276.884226 -86.122351)
			(xy 276.905038 -86.130005) (xy 276.916134 -86.129622) (xy 277.00478 -86.122256) (xy 277.024338 -86.11108)
			(xy 277.030688 -86.101936) (xy 277.051337 -86.073737) (xy 277.098268 -86.021941) (xy 277.151029 -85.976098)
			(xy 277.208871 -85.93686) (xy 277.27097 -85.904784) (xy 277.336446 -85.880326) (xy 277.404367 -85.863834)
			(xy 277.473768 -85.855542) (xy 277.508716 -85.855048) (xy 277.541586 -85.855547) (xy 277.606915 -85.862885)
			(xy 277.671013 -85.877491) (xy 277.733072 -85.899179) (xy 277.792314 -85.927678) (xy 277.847993 -85.962629)
			(xy 277.89941 -86.003593) (xy 277.92299 -86.026498) (xy 278.342852 -86.44636) (xy 278.34952 -86.45251)
			(xy 278.365998 -86.460068) (xy 278.384074 -86.46145) (xy 278.39289 -86.459314) (xy 278.491696 -86.430866)
			(xy 278.510746 -86.4108) (xy 278.513794 -86.397084) (xy 278.520613 -86.369306) (xy 278.541398 -86.316022)
			(xy 278.569905 -86.266438) (xy 278.605496 -86.221665) (xy 278.647372 -86.182709) (xy 278.694596 -86.150441)
			(xy 278.746107 -86.125585) (xy 278.800753 -86.108699) (xy 278.857307 -86.10016) (xy 278.885904 -86.09965)
			(xy 278.913142 -86.100173) (xy 278.95369 -86.106) (xy 282.827982 -86.106) (xy 282.832053 -86.050378)
			(xy 282.844179 -85.995941) (xy 282.864102 -85.94385) (xy 282.891398 -85.895215) (xy 282.925484 -85.851072)
			(xy 282.965633 -85.812363) (xy 283.010991 -85.779912) (xy 283.060591 -85.754411) (xy 283.113375 -85.736404)
			(xy 283.168218 -85.726274) (xy 283.223952 -85.724237) (xy 283.279389 -85.730337) (xy 283.333346 -85.744443)
			(xy 283.384675 -85.766255) (xy 283.432281 -85.795309) (xy 283.475149 -85.830984) (xy 283.512366 -85.872521)
			(xy 283.543139 -85.919034) (xy 283.566811 -85.969531) (xy 283.582879 -86.022938) (xy 283.590999 -86.078114)
			(xy 283.591508 -86.106) (xy 283.590999 -86.133886) (xy 283.582879 -86.189062) (xy 283.566811 -86.242469)
			(xy 283.543139 -86.292966) (xy 283.512366 -86.339479) (xy 283.475149 -86.381016) (xy 283.432281 -86.416691)
			(xy 283.384675 -86.445745) (xy 283.333346 -86.467557) (xy 283.279389 -86.481663) (xy 283.223952 -86.487763)
			(xy 283.168218 -86.485726) (xy 283.113375 -86.475596) (xy 283.060591 -86.457589) (xy 283.010991 -86.432088)
			(xy 282.965633 -86.399637) (xy 282.925484 -86.360928) (xy 282.891398 -86.316785) (xy 282.864102 -86.26815)
			(xy 282.844179 -86.216059) (xy 282.832053 -86.161622) (xy 282.827982 -86.106) (xy 278.95369 -86.106)
			(xy 278.967064 -86.107922) (xy 279.019335 -86.123263) (xy 279.068893 -86.145883) (xy 279.114729 -86.175322)
			(xy 279.155911 -86.210982) (xy 279.191602 -86.252137) (xy 279.221077 -86.297951) (xy 279.243735 -86.347491)
			(xy 279.259115 -86.399751) (xy 279.266906 -86.453666) (xy 279.267412 -86.480904) (xy 279.267412 -86.481412)
			(xy 279.267158 -86.498176) (xy 279.26665 -86.50859) (xy 279.273762 -86.527894) (xy 279.331928 -86.5886)
			(xy 279.339417 -86.595739) (xy 279.358423 -86.603864) (xy 279.368758 -86.604348) (xy 279.78862 -86.604348)
			(xy 279.798692 -86.603947) (xy 279.817291 -86.596211) (xy 279.824688 -86.589362) (xy 279.882854 -86.530688)
			(xy 279.89022 -86.511892) (xy 279.89022 -86.498176) (xy 279.890706 -86.470925) (xy 279.898462 -86.416977)
			(xy 279.913817 -86.364682) (xy 279.936459 -86.315105) (xy 279.965925 -86.269255) (xy 280.001616 -86.228064)
			(xy 280.042807 -86.192373) (xy 280.088657 -86.162907) (xy 280.138234 -86.140265) (xy 280.190529 -86.12491)
			(xy 280.244477 -86.117154) (xy 280.298979 -86.117154) (xy 280.352927 -86.12491) (xy 280.405222 -86.140265)
			(xy 280.454799 -86.162907) (xy 280.500649 -86.192373) (xy 280.54184 -86.228064) (xy 280.577531 -86.269255)
			(xy 280.606997 -86.315105) (xy 280.629639 -86.364682) (xy 280.644994 -86.416977) (xy 280.65275 -86.470925)
			(xy 280.653236 -86.498176) (xy 280.653236 -86.511892) (xy 280.660602 -86.530688) (xy 280.718768 -86.589362)
			(xy 280.72619 -86.596175) (xy 280.744772 -86.603912) (xy 280.754836 -86.604348) (xy 290.655756 -86.604348)
			(xy 290.666003 -86.603893) (xy 290.684888 -86.595948) (xy 290.699144 -86.581232) (xy 290.703254 -86.571836)
			(xy 290.73729 -86.482936) (xy 290.740553 -86.473226) (xy 290.739819 -86.452771) (xy 290.731138 -86.434234)
			(xy 290.723828 -86.427056) (xy 290.704355 -86.408869) (xy 290.670103 -86.368058) (xy 290.641862 -86.322877)
			(xy 290.620183 -86.274206) (xy 290.605487 -86.222993) (xy 290.598061 -86.170232) (xy 290.59759 -86.143592)
			(xy 290.598076 -86.116341) (xy 290.605832 -86.062393) (xy 290.621187 -86.010098) (xy 290.643829 -85.960521)
			(xy 290.673295 -85.914671) (xy 290.708986 -85.87348) (xy 290.750177 -85.837789) (xy 290.796027 -85.808323)
			(xy 290.845604 -85.785681) (xy 290.897899 -85.770326) (xy 290.951847 -85.76257) (xy 291.006349 -85.76257)
			(xy 291.060297 -85.770326) (xy 291.112592 -85.785681) (xy 291.162169 -85.808323) (xy 291.208019 -85.837789)
			(xy 291.24921 -85.87348) (xy 291.284901 -85.914671) (xy 291.314367 -85.960521) (xy 291.337009 -86.010098)
			(xy 291.352364 -86.062393) (xy 291.36012 -86.116341) (xy 291.360606 -86.143592) (xy 291.360178 -86.170237)
			(xy 291.352769 -86.223009) (xy 291.345607 -86.247986) (xy 307.43855 -86.247986) (xy 307.442621 -86.192364)
			(xy 307.454747 -86.137927) (xy 307.47467 -86.085836) (xy 307.501966 -86.037201) (xy 307.536052 -85.993058)
			(xy 307.576201 -85.954349) (xy 307.621559 -85.921898) (xy 307.671159 -85.896397) (xy 307.723943 -85.87839)
			(xy 307.778786 -85.86826) (xy 307.83452 -85.866223) (xy 307.889957 -85.872323) (xy 307.943914 -85.886429)
			(xy 307.995243 -85.908241) (xy 308.042849 -85.937295) (xy 308.085717 -85.97297) (xy 308.122934 -86.014507)
			(xy 308.153707 -86.06102) (xy 308.177379 -86.111517) (xy 308.193447 -86.164924) (xy 308.201567 -86.2201)
			(xy 308.202076 -86.247986) (xy 308.201567 -86.275872) (xy 308.193447 -86.331048) (xy 308.177379 -86.384455)
			(xy 308.153707 -86.434952) (xy 308.122934 -86.481465) (xy 308.085717 -86.523002) (xy 308.042849 -86.558677)
			(xy 307.995243 -86.587731) (xy 307.943914 -86.609543) (xy 307.889957 -86.623649) (xy 307.83452 -86.629749)
			(xy 307.778786 -86.627712) (xy 307.723943 -86.617582) (xy 307.671159 -86.599575) (xy 307.621559 -86.574074)
			(xy 307.576201 -86.541623) (xy 307.536052 -86.502914) (xy 307.501966 -86.458771) (xy 307.47467 -86.410136)
			(xy 307.454747 -86.358045) (xy 307.442621 -86.303608) (xy 307.43855 -86.247986) (xy 291.345607 -86.247986)
			(xy 291.338081 -86.274234) (xy 291.316401 -86.322914) (xy 291.28815 -86.368098) (xy 291.253881 -86.408907)
			(xy 291.234368 -86.427056) (xy 291.227111 -86.434265) (xy 291.218485 -86.452793) (xy 291.217719 -86.473216)
			(xy 291.220906 -86.482936) (xy 291.254942 -86.571836) (xy 291.259079 -86.581212) (xy 291.273347 -86.595897)
			(xy 291.292203 -86.60388) (xy 291.30244 -86.604348) (xy 303.99228 -86.604348) (xy 304.025133 -86.604825)
			(xy 304.090426 -86.612186) (xy 304.154485 -86.626806) (xy 304.216506 -86.648503) (xy 304.27571 -86.677003)
			(xy 304.331353 -86.711949) (xy 304.382736 -86.752901) (xy 304.4063 -86.775798) (xy 306.006431 -88.375998)
			(xy 312.02325 -88.375998) (xy 312.027321 -88.320376) (xy 312.039447 -88.265939) (xy 312.05937 -88.213848)
			(xy 312.086666 -88.165213) (xy 312.120752 -88.12107) (xy 312.160901 -88.082361) (xy 312.206259 -88.04991)
			(xy 312.255859 -88.024409) (xy 312.308643 -88.006402) (xy 312.363486 -87.996272) (xy 312.41922 -87.994235)
			(xy 312.474657 -88.000335) (xy 312.528614 -88.014441) (xy 312.579943 -88.036253) (xy 312.627549 -88.065307)
			(xy 312.670417 -88.100982) (xy 312.707634 -88.142519) (xy 312.738407 -88.189032) (xy 312.762079 -88.239529)
			(xy 312.778147 -88.292936) (xy 312.786267 -88.348112) (xy 312.786776 -88.375998) (xy 312.786414 -88.39581)
			(xy 313.457588 -88.39581) (xy 313.461659 -88.340188) (xy 313.473785 -88.285751) (xy 313.493708 -88.23366)
			(xy 313.521004 -88.185025) (xy 313.55509 -88.140882) (xy 313.595239 -88.102173) (xy 313.640597 -88.069722)
			(xy 313.690197 -88.044221) (xy 313.742981 -88.026214) (xy 313.797824 -88.016084) (xy 313.853558 -88.014047)
			(xy 313.908995 -88.020147) (xy 313.962952 -88.034253) (xy 314.014281 -88.056065) (xy 314.061887 -88.085119)
			(xy 314.104755 -88.120794) (xy 314.141972 -88.162331) (xy 314.172745 -88.208844) (xy 314.196417 -88.259341)
			(xy 314.212485 -88.312748) (xy 314.220605 -88.367924) (xy 314.221114 -88.39581) (xy 314.220605 -88.423696)
			(xy 314.212485 -88.478872) (xy 314.196417 -88.532279) (xy 314.172745 -88.582776) (xy 314.141972 -88.629289)
			(xy 314.104755 -88.670826) (xy 314.061887 -88.706501) (xy 314.014281 -88.735555) (xy 313.962952 -88.757367)
			(xy 313.908995 -88.771473) (xy 313.853558 -88.777573) (xy 313.797824 -88.775536) (xy 313.742981 -88.765406)
			(xy 313.690197 -88.747399) (xy 313.640597 -88.721898) (xy 313.595239 -88.689447) (xy 313.55509 -88.650738)
			(xy 313.521004 -88.606595) (xy 313.493708 -88.55796) (xy 313.473785 -88.505869) (xy 313.461659 -88.451432)
			(xy 313.457588 -88.39581) (xy 312.786414 -88.39581) (xy 312.786267 -88.403884) (xy 312.778147 -88.45906)
			(xy 312.762079 -88.512467) (xy 312.738407 -88.562964) (xy 312.707634 -88.609477) (xy 312.670417 -88.651014)
			(xy 312.627549 -88.686689) (xy 312.579943 -88.715743) (xy 312.528614 -88.737555) (xy 312.474657 -88.751661)
			(xy 312.41922 -88.757761) (xy 312.363486 -88.755724) (xy 312.308643 -88.745594) (xy 312.255859 -88.727587)
			(xy 312.206259 -88.702086) (xy 312.160901 -88.669635) (xy 312.120752 -88.630926) (xy 312.086666 -88.586783)
			(xy 312.05937 -88.538148) (xy 312.039447 -88.486057) (xy 312.027321 -88.43162) (xy 312.02325 -88.375998)
			(xy 306.006431 -88.375998) (xy 307.411752 -89.78138) (xy 312.420506 -89.78138) (xy 312.424577 -89.725758)
			(xy 312.436703 -89.671321) (xy 312.456626 -89.61923) (xy 312.483922 -89.570595) (xy 312.518008 -89.526452)
			(xy 312.558157 -89.487743) (xy 312.603515 -89.455292) (xy 312.653115 -89.429791) (xy 312.705899 -89.411784)
			(xy 312.760742 -89.401654) (xy 312.816476 -89.399617) (xy 312.871913 -89.405717) (xy 312.92587 -89.419823)
			(xy 312.977199 -89.441635) (xy 313.024805 -89.470689) (xy 313.067673 -89.506364) (xy 313.10489 -89.547901)
			(xy 313.135663 -89.594414) (xy 313.159335 -89.644911) (xy 313.175403 -89.698318) (xy 313.183523 -89.753494)
			(xy 313.184032 -89.78138) (xy 313.183523 -89.809266) (xy 313.175403 -89.864442) (xy 313.159335 -89.917849)
			(xy 313.135663 -89.968346) (xy 313.10489 -90.014859) (xy 313.067673 -90.056396) (xy 313.024805 -90.092071)
			(xy 312.977199 -90.121125) (xy 312.92587 -90.142937) (xy 312.871913 -90.157043) (xy 312.816476 -90.163143)
			(xy 312.760742 -90.161106) (xy 312.705899 -90.150976) (xy 312.653115 -90.132969) (xy 312.603515 -90.107468)
			(xy 312.558157 -90.075017) (xy 312.518008 -90.036308) (xy 312.483922 -89.992165) (xy 312.456626 -89.94353)
			(xy 312.436703 -89.891439) (xy 312.424577 -89.837002) (xy 312.420506 -89.78138) (xy 307.411752 -89.78138)
			(xy 308.912066 -91.281758) (xy 325.860408 -91.281758) (xy 325.864479 -91.226136) (xy 325.876605 -91.171699)
			(xy 325.896528 -91.119608) (xy 325.923824 -91.070973) (xy 325.95791 -91.02683) (xy 325.998059 -90.988121)
			(xy 326.043417 -90.95567) (xy 326.093017 -90.930169) (xy 326.145801 -90.912162) (xy 326.200644 -90.902032)
			(xy 326.256378 -90.899995) (xy 326.311815 -90.906095) (xy 326.365772 -90.920201) (xy 326.417101 -90.942013)
			(xy 326.464707 -90.971067) (xy 326.507575 -91.006742) (xy 326.544792 -91.048279) (xy 326.575565 -91.094792)
			(xy 326.599237 -91.145289) (xy 326.615305 -91.198696) (xy 326.623425 -91.253872) (xy 326.623934 -91.281758)
			(xy 326.623425 -91.309644) (xy 326.615305 -91.36482) (xy 326.599237 -91.418227) (xy 326.575565 -91.468724)
			(xy 326.544792 -91.515237) (xy 326.507575 -91.556774) (xy 326.464707 -91.592449) (xy 326.417101 -91.621503)
			(xy 326.365772 -91.643315) (xy 326.311815 -91.657421) (xy 326.256378 -91.663521) (xy 326.200644 -91.661484)
			(xy 326.145801 -91.651354) (xy 326.093017 -91.633347) (xy 326.043417 -91.607846) (xy 325.998059 -91.575395)
			(xy 325.95791 -91.536686) (xy 325.923824 -91.492543) (xy 325.896528 -91.443908) (xy 325.876605 -91.391817)
			(xy 325.864479 -91.33738) (xy 325.860408 -91.281758) (xy 308.912066 -91.281758) (xy 310.298846 -92.668598)
			(xy 310.306271 -92.675407) (xy 310.324851 -92.683145) (xy 310.334914 -92.683584) (xy 311.65038 -92.683584)
			(xy 311.683232 -92.684079) (xy 311.748524 -92.69144) (xy 311.812582 -92.706058) (xy 311.874602 -92.727753)
			(xy 311.933806 -92.756249) (xy 311.98945 -92.791191) (xy 312.040835 -92.832139) (xy 312.0644 -92.855034)
			(xy 312.611262 -93.401896) (xy 312.634153 -93.425468) (xy 312.675118 -93.476843) (xy 312.710073 -93.532482)
			(xy 312.73858 -93.591684) (xy 312.760279 -93.653706) (xy 312.774898 -93.717767) (xy 312.782253 -93.783062)
			(xy 312.782712 -93.815916) (xy 312.782712 -93.81617) (xy 312.782116 -93.851571) (xy 312.773588 -93.921858)
			(xy 312.756652 -93.990605) (xy 312.731555 -94.05681) (xy 312.698663 -94.119508) (xy 312.658456 -94.177786)
			(xy 312.611519 -94.230794) (xy 312.558536 -94.27776) (xy 312.50028 -94.317999) (xy 312.4376 -94.350924)
			(xy 312.371408 -94.376057) (xy 312.302671 -94.39303) (xy 312.232389 -94.401597) (xy 312.196988 -94.402148)
			(xy 312.164106 -94.401731) (xy 312.098757 -94.394362) (xy 312.034644 -94.379717) (xy 311.972576 -94.357982)
			(xy 311.913334 -94.32943) (xy 311.857664 -94.29442) (xy 311.806267 -94.253393) (xy 311.782714 -94.230444)
			(xy 311.664858 -94.112588) (xy 311.657769 -94.10606) (xy 311.640082 -94.09844) (xy 311.620831 -94.097883)
			(xy 311.602734 -94.104468) (xy 311.595262 -94.110556) (xy 311.574719 -94.128139) (xy 311.529605 -94.157946)
			(xy 311.480737 -94.181092) (xy 311.455054 -94.18955) (xy 311.4548 -94.18955) (xy 311.449111 -94.191541)
			(xy 311.438834 -94.197829) (xy 311.43448 -94.201996) (xy 311.207658 -94.428818) (xy 321.675758 -94.428818)
			(xy 321.679829 -94.373196) (xy 321.691955 -94.318759) (xy 321.711878 -94.266668) (xy 321.739174 -94.218033)
			(xy 321.77326 -94.17389) (xy 321.813409 -94.135181) (xy 321.858767 -94.10273) (xy 321.908367 -94.077229)
			(xy 321.961151 -94.059222) (xy 322.015994 -94.049092) (xy 322.071728 -94.047055) (xy 322.127165 -94.053155)
			(xy 322.181122 -94.067261) (xy 322.232451 -94.089073) (xy 322.280057 -94.118127) (xy 322.322925 -94.153802)
			(xy 322.360142 -94.195339) (xy 322.390915 -94.241852) (xy 322.414587 -94.292349) (xy 322.430655 -94.345756)
			(xy 322.438775 -94.400932) (xy 322.439284 -94.428818) (xy 322.438775 -94.456704) (xy 322.430655 -94.51188)
			(xy 322.414587 -94.565287) (xy 322.390915 -94.615784) (xy 322.360142 -94.662297) (xy 322.322925 -94.703834)
			(xy 322.280057 -94.739509) (xy 322.232451 -94.768563) (xy 322.181122 -94.790375) (xy 322.127165 -94.804481)
			(xy 322.071728 -94.810581) (xy 322.015994 -94.808544) (xy 321.961151 -94.798414) (xy 321.908367 -94.780407)
			(xy 321.858767 -94.754906) (xy 321.813409 -94.722455) (xy 321.77326 -94.683746) (xy 321.739174 -94.639603)
			(xy 321.711878 -94.590968) (xy 321.691955 -94.538877) (xy 321.679829 -94.48444) (xy 321.675758 -94.428818)
			(xy 311.207658 -94.428818) (xy 310.815228 -94.821248) (xy 310.796468 -94.839291) (xy 310.754347 -94.869868)
			(xy 310.707968 -94.893492) (xy 310.658469 -94.909584) (xy 310.607064 -94.917749) (xy 310.58104 -94.918276)
			(xy 308.943756 -94.918276) (xy 308.917732 -94.917762) (xy 308.866327 -94.909595) (xy 308.816829 -94.893498)
			(xy 308.770453 -94.869867) (xy 308.728338 -94.839282) (xy 308.709568 -94.821248) (xy 302.846486 -88.958166)
			(xy 302.839089 -88.951323) (xy 302.820487 -88.943606) (xy 302.810418 -88.94318) (xy 275.958046 -88.94318)
			(xy 275.934532 -88.942762) (xy 275.887972 -88.936142) (xy 275.842813 -88.923012) (xy 275.799961 -88.903637)
			(xy 275.760275 -88.878405) (xy 275.742146 -88.863424) (xy 275.735057 -88.857842) (xy 275.718142 -88.851594)
			(xy 275.709126 -88.851232) (xy 275.53666 -88.851232) (xy 275.51126 -88.86825) (xy 275.505418 -88.882474)
			(xy 275.50196 -88.891902) (xy 275.502015 -88.911971) (xy 275.509764 -88.930483) (xy 275.516594 -88.937846)
			(xy 276.299676 -89.721182) (xy 276.307092 -89.728002) (xy 276.325679 -89.735734) (xy 276.335744 -89.736168)
			(xy 277.084282 -89.736168) (xy 277.093221 -89.735767) (xy 277.110003 -89.7296) (xy 277.123647 -89.718046)
			(xy 277.132493 -89.702508) (xy 277.13432 -89.69375) (xy 277.139497 -89.666019) (xy 277.156942 -89.612372)
			(xy 277.182096 -89.56188) (xy 277.214413 -89.515642) (xy 277.253187 -89.474669) (xy 277.297573 -89.439852)
			(xy 277.346602 -89.411953) (xy 277.399206 -89.391578) (xy 277.454236 -89.379173) (xy 277.510494 -89.375007)
			(xy 277.566752 -89.379173) (xy 277.621782 -89.391578) (xy 277.674386 -89.411953) (xy 277.723415 -89.439852)
			(xy 277.767801 -89.474669) (xy 277.806575 -89.515642) (xy 277.838892 -89.56188) (xy 277.864046 -89.612372)
			(xy 277.881491 -89.666019) (xy 277.886668 -89.69375) (xy 277.888508 -89.702513) (xy 277.897324 -89.71808)
			(xy 277.910966 -89.729655) (xy 277.927761 -89.735819) (xy 277.936706 -89.736168) (xy 278.285702 -89.736168)
			(xy 278.295772 -89.735752) (xy 278.314371 -89.728026) (xy 278.32177 -89.721182) (xy 278.692356 -89.350342)
			(xy 278.715901 -89.327423) (xy 278.767281 -89.28646) (xy 278.822925 -89.251508) (xy 278.882132 -89.223005)
			(xy 278.944158 -89.20131) (xy 279.008222 -89.186697) (xy 279.073521 -89.179348) (xy 279.106376 -89.178892)
			(xy 279.10663 -89.178892) (xy 279.140242 -89.179334) (xy 279.207023 -89.187034) (xy 279.272484 -89.202328)
			(xy 279.335764 -89.225015) (xy 279.39603 -89.254798) (xy 279.452491 -89.291285) (xy 279.504403 -89.333995)
			(xy 279.551084 -89.382368) (xy 279.591921 -89.435766) (xy 279.60955 -89.464388) (xy 279.615431 -89.473239)
			(xy 279.632767 -89.485494) (xy 279.653573 -89.489718) (xy 279.674316 -89.485193) (xy 279.68321 -89.479374)
			(xy 279.707804 -89.462131) (xy 279.761287 -89.4348) (xy 279.818395 -89.416196) (xy 279.877715 -89.406782)
			(xy 279.907746 -89.406222) (xy 279.934775 -89.406681) (xy 279.98829 -89.414329) (xy 280.040187 -89.429464)
			(xy 280.089423 -89.451783) (xy 280.11247 -89.465912) (xy 280.122521 -89.471595) (xy 280.145434 -89.474222)
			(xy 280.167199 -89.466593) (xy 280.175716 -89.4588) (xy 280.258774 -89.375742) (xy 280.282357 -89.352863)
			(xy 280.33373 -89.311897) (xy 280.389366 -89.27694) (xy 280.448567 -89.248432) (xy 280.510587 -89.226731)
			(xy 280.574647 -89.21211) (xy 280.63994 -89.204753) (xy 280.672794 -89.204292) (xy 280.673048 -89.204292)
			(xy 280.708447 -89.204765) (xy 280.778729 -89.213304) (xy 280.847468 -89.230252) (xy 280.913664 -89.255362)
			(xy 280.976351 -89.288268) (xy 281.034614 -89.32849) (xy 281.087605 -89.375441) (xy 281.13455 -89.428436)
			(xy 281.174765 -89.486704) (xy 281.207664 -89.549394) (xy 281.232767 -89.615593) (xy 281.249707 -89.684335)
			(xy 281.258239 -89.754617) (xy 281.258772 -89.790016) (xy 281.258772 -89.79027) (xy 281.258283 -89.823123)
			(xy 281.250923 -89.888415) (xy 281.236304 -89.952474) (xy 281.21461 -90.014494) (xy 281.186111 -90.073698)
			(xy 281.151168 -90.129341) (xy 281.110218 -90.180725) (xy 281.087322 -90.20429) (xy 280.072338 -91.219274)
			(xy 280.048798 -91.242199) (xy 279.997417 -91.283161) (xy 279.941772 -91.318112) (xy 279.882565 -91.346614)
			(xy 279.820538 -91.368308) (xy 279.756472 -91.38292) (xy 279.691174 -91.390268) (xy 279.658318 -91.390724)
			(xy 275.894038 -91.390724) (xy 275.875125 -91.390585) (xy 275.837377 -91.388167) (xy 275.8186 -91.385898)
			(xy 275.809583 -91.385025) (xy 275.791919 -91.388989) (xy 275.776765 -91.398893) (xy 275.771102 -91.405964)
			(xy 275.757927 -91.423526) (xy 275.729319 -91.456833) (xy 275.713952 -91.472512) (xy 275.53666 -91.64955)
			(xy 275.528849 -91.65817) (xy 275.521363 -91.680175) (xy 275.52421 -91.703244) (xy 275.530056 -91.713304)
			(xy 275.53031 -91.713558) (xy 275.545824 -91.73783) (xy 275.572581 -91.788848) (xy 275.594212 -91.84224)
			(xy 275.6027 -91.869768) (xy 275.6027 -91.870022) (xy 275.604683 -91.875926) (xy 275.611106 -91.886592)
			(xy 275.6154 -91.891104) (xy 277.17369 -93.449394) (xy 277.1811 -93.456221) (xy 277.199692 -93.463949)
			(xy 277.209758 -93.46438) (xy 277.566882 -93.46438) (xy 277.599764 -93.464808) (xy 277.665113 -93.472175)
			(xy 277.729225 -93.486817) (xy 277.791293 -93.50855) (xy 277.850536 -93.537101) (xy 277.906206 -93.572109)
			(xy 277.957603 -93.613135) (xy 277.981156 -93.636084) (xy 278.249888 -93.904816) (xy 278.272832 -93.928369)
			(xy 278.313824 -93.979785) (xy 278.348807 -94.035463) (xy 278.377343 -94.094706) (xy 278.399073 -94.156768)
			(xy 278.413725 -94.220872) (xy 278.421115 -94.286212) (xy 278.421592 -94.31909) (xy 278.421034 -94.354502)
			(xy 278.412498 -94.42481) (xy 278.39555 -94.493576) (xy 278.370437 -94.559798) (xy 278.337525 -94.622511)
			(xy 278.297293 -94.680799) (xy 278.250329 -94.733812) (xy 278.197317 -94.780778) (xy 278.139031 -94.821012)
			(xy 278.07632 -94.853927) (xy 278.010099 -94.879043) (xy 277.941334 -94.895994) (xy 277.871026 -94.904533)
			(xy 277.835614 -94.905068) (xy 277.788624 -94.903036) (xy 277.78837 -94.903036) (xy 277.775985 -94.902664)
			(xy 277.75322 -94.912366) (xy 277.744936 -94.921578) (xy 277.692104 -94.986856) (xy 277.684905 -94.996955)
			(xy 277.680143 -95.021258) (xy 277.68296 -95.033338) (xy 277.68296 -95.033846) (xy 277.694524 -95.074856)
			(xy 277.707015 -95.159139) (xy 277.707852 -95.20174) (xy 277.707664 -95.214948) (xy 279.473927 -95.214948)
			(xy 279.477883 -95.123089) (xy 279.48972 -95.03191) (xy 279.509352 -94.942086) (xy 279.536633 -94.854283)
			(xy 279.571361 -94.76915) (xy 279.613279 -94.687317) (xy 279.662077 -94.60939) (xy 279.717392 -94.535947)
			(xy 279.778817 -94.467531) (xy 279.845896 -94.404649) (xy 279.918131 -94.347766) (xy 279.99499 -94.297303)
			(xy 280.075902 -94.253634) (xy 280.160268 -94.217082) (xy 280.247464 -94.187918) (xy 280.336845 -94.166358)
			(xy 280.427748 -94.152562) (xy 280.519501 -94.14663) (xy 280.611423 -94.148609) (xy 280.702836 -94.158482)
			(xy 280.793061 -94.176177) (xy 280.881432 -94.201562) (xy 280.967292 -94.23445) (xy 281.050008 -94.274598)
			(xy 281.128966 -94.321707) (xy 281.203583 -94.37543) (xy 281.273304 -94.435368) (xy 281.337615 -94.501078)
			(xy 281.39604 -94.572074) (xy 281.448145 -94.647828) (xy 281.493544 -94.727782) (xy 281.531903 -94.811342)
			(xy 281.562936 -94.897891) (xy 281.586414 -94.986787) (xy 281.602164 -95.077372) (xy 281.610068 -95.168976)
			(xy 281.610562 -95.214948) (xy 303.838877 -95.214948) (xy 303.842833 -95.123089) (xy 303.85467 -95.03191)
			(xy 303.874302 -94.942086) (xy 303.901583 -94.854283) (xy 303.936311 -94.76915) (xy 303.978229 -94.687317)
			(xy 304.027027 -94.60939) (xy 304.082342 -94.535947) (xy 304.143767 -94.467531) (xy 304.210846 -94.404649)
			(xy 304.283081 -94.347766) (xy 304.35994 -94.297303) (xy 304.440852 -94.253634) (xy 304.525218 -94.217082)
			(xy 304.612414 -94.187918) (xy 304.701795 -94.166358) (xy 304.792698 -94.152562) (xy 304.884451 -94.14663)
			(xy 304.976373 -94.148609) (xy 305.067786 -94.158482) (xy 305.158011 -94.176177) (xy 305.246382 -94.201562)
			(xy 305.332242 -94.23445) (xy 305.414958 -94.274598) (xy 305.493916 -94.321707) (xy 305.568533 -94.37543)
			(xy 305.638254 -94.435368) (xy 305.702565 -94.501078) (xy 305.76099 -94.572074) (xy 305.813095 -94.647828)
			(xy 305.858494 -94.727782) (xy 305.896853 -94.811342) (xy 305.927886 -94.897891) (xy 305.951364 -94.986787)
			(xy 305.967114 -95.077372) (xy 305.975018 -95.168976) (xy 305.975512 -95.214948) (xy 305.975018 -95.26092)
			(xy 305.967114 -95.352524) (xy 305.951364 -95.443109) (xy 305.927886 -95.532005) (xy 305.896853 -95.618554)
			(xy 305.858494 -95.702114) (xy 305.813095 -95.782068) (xy 305.76099 -95.857822) (xy 305.702565 -95.928818)
			(xy 305.64303 -95.989648) (xy 307.763924 -95.989648) (xy 307.767995 -95.934026) (xy 307.780121 -95.879589)
			(xy 307.800044 -95.827498) (xy 307.82734 -95.778863) (xy 307.861426 -95.73472) (xy 307.901575 -95.696011)
			(xy 307.946933 -95.66356) (xy 307.996533 -95.638059) (xy 308.049317 -95.620052) (xy 308.10416 -95.609922)
			(xy 308.159894 -95.607885) (xy 308.215331 -95.613985) (xy 308.269288 -95.628091) (xy 308.320617 -95.649903)
			(xy 308.368223 -95.678957) (xy 308.411091 -95.714632) (xy 308.448308 -95.756169) (xy 308.479081 -95.802682)
			(xy 308.502753 -95.853179) (xy 308.518821 -95.906586) (xy 308.526941 -95.961762) (xy 308.52745 -95.989648)
			(xy 310.369456 -95.989648) (xy 310.373527 -95.934026) (xy 310.385653 -95.879589) (xy 310.405576 -95.827498)
			(xy 310.432872 -95.778863) (xy 310.466958 -95.73472) (xy 310.507107 -95.696011) (xy 310.552465 -95.66356)
			(xy 310.602065 -95.638059) (xy 310.654849 -95.620052) (xy 310.709692 -95.609922) (xy 310.765426 -95.607885)
			(xy 310.820863 -95.613985) (xy 310.87482 -95.628091) (xy 310.926149 -95.649903) (xy 310.973755 -95.678957)
			(xy 311.016623 -95.714632) (xy 311.05384 -95.756169) (xy 311.084123 -95.801942) (xy 320.841368 -95.801942)
			(xy 320.845439 -95.74632) (xy 320.857565 -95.691883) (xy 320.877488 -95.639792) (xy 320.904784 -95.591157)
			(xy 320.93887 -95.547014) (xy 320.979019 -95.508305) (xy 321.024377 -95.475854) (xy 321.073977 -95.450353)
			(xy 321.126761 -95.432346) (xy 321.181604 -95.422216) (xy 321.237338 -95.420179) (xy 321.292775 -95.426279)
			(xy 321.346732 -95.440385) (xy 321.398061 -95.462197) (xy 321.445667 -95.491251) (xy 321.488535 -95.526926)
			(xy 321.525752 -95.568463) (xy 321.556525 -95.614976) (xy 321.580197 -95.665473) (xy 321.596265 -95.71888)
			(xy 321.604385 -95.774056) (xy 321.604894 -95.801942) (xy 321.604385 -95.829828) (xy 321.601873 -95.8469)
			(xy 323.324726 -95.8469) (xy 323.328797 -95.791278) (xy 323.340923 -95.736841) (xy 323.360846 -95.68475)
			(xy 323.388142 -95.636115) (xy 323.422228 -95.591972) (xy 323.462377 -95.553263) (xy 323.507735 -95.520812)
			(xy 323.557335 -95.495311) (xy 323.610119 -95.477304) (xy 323.664962 -95.467174) (xy 323.720696 -95.465137)
			(xy 323.776133 -95.471237) (xy 323.83009 -95.485343) (xy 323.881419 -95.507155) (xy 323.929025 -95.536209)
			(xy 323.971893 -95.571884) (xy 324.00911 -95.613421) (xy 324.039883 -95.659934) (xy 324.063555 -95.710431)
			(xy 324.079623 -95.763838) (xy 324.085231 -95.801942) (xy 324.915528 -95.801942) (xy 324.919599 -95.74632)
			(xy 324.931725 -95.691883) (xy 324.951648 -95.639792) (xy 324.978944 -95.591157) (xy 325.01303 -95.547014)
			(xy 325.053179 -95.508305) (xy 325.098537 -95.475854) (xy 325.148137 -95.450353) (xy 325.200921 -95.432346)
			(xy 325.255764 -95.422216) (xy 325.311498 -95.420179) (xy 325.366935 -95.426279) (xy 325.420892 -95.440385)
			(xy 325.472221 -95.462197) (xy 325.519827 -95.491251) (xy 325.562695 -95.526926) (xy 325.599912 -95.568463)
			(xy 325.630685 -95.614976) (xy 325.654357 -95.665473) (xy 325.670425 -95.71888) (xy 325.678545 -95.774056)
			(xy 325.679054 -95.801942) (xy 325.921368 -95.801942) (xy 325.925439 -95.74632) (xy 325.937565 -95.691883)
			(xy 325.957488 -95.639792) (xy 325.984784 -95.591157) (xy 326.01887 -95.547014) (xy 326.059019 -95.508305)
			(xy 326.104377 -95.475854) (xy 326.153977 -95.450353) (xy 326.206761 -95.432346) (xy 326.261604 -95.422216)
			(xy 326.317338 -95.420179) (xy 326.372775 -95.426279) (xy 326.426732 -95.440385) (xy 326.478061 -95.462197)
			(xy 326.525667 -95.491251) (xy 326.568535 -95.526926) (xy 326.605752 -95.568463) (xy 326.636525 -95.614976)
			(xy 326.660197 -95.665473) (xy 326.676265 -95.71888) (xy 326.684385 -95.774056) (xy 326.684894 -95.801942)
			(xy 326.684385 -95.829828) (xy 326.676265 -95.885004) (xy 326.660197 -95.938411) (xy 326.636525 -95.988908)
			(xy 326.605752 -96.035421) (xy 326.568535 -96.076958) (xy 326.525667 -96.112633) (xy 326.478061 -96.141687)
			(xy 326.426732 -96.163499) (xy 326.372775 -96.177605) (xy 326.317338 -96.183705) (xy 326.261604 -96.181668)
			(xy 326.206761 -96.171538) (xy 326.153977 -96.153531) (xy 326.104377 -96.12803) (xy 326.059019 -96.095579)
			(xy 326.01887 -96.05687) (xy 325.984784 -96.012727) (xy 325.957488 -95.964092) (xy 325.937565 -95.912001)
			(xy 325.925439 -95.857564) (xy 325.921368 -95.801942) (xy 325.679054 -95.801942) (xy 325.678545 -95.829828)
			(xy 325.670425 -95.885004) (xy 325.654357 -95.938411) (xy 325.630685 -95.988908) (xy 325.599912 -96.035421)
			(xy 325.562695 -96.076958) (xy 325.519827 -96.112633) (xy 325.472221 -96.141687) (xy 325.420892 -96.163499)
			(xy 325.366935 -96.177605) (xy 325.311498 -96.183705) (xy 325.255764 -96.181668) (xy 325.200921 -96.171538)
			(xy 325.148137 -96.153531) (xy 325.098537 -96.12803) (xy 325.053179 -96.095579) (xy 325.01303 -96.05687)
			(xy 324.978944 -96.012727) (xy 324.951648 -95.964092) (xy 324.931725 -95.912001) (xy 324.919599 -95.857564)
			(xy 324.915528 -95.801942) (xy 324.085231 -95.801942) (xy 324.087743 -95.819014) (xy 324.088252 -95.8469)
			(xy 324.087743 -95.874786) (xy 324.079623 -95.929962) (xy 324.063555 -95.983369) (xy 324.039883 -96.033866)
			(xy 324.00911 -96.080379) (xy 323.971893 -96.121916) (xy 323.929025 -96.157591) (xy 323.881419 -96.186645)
			(xy 323.83009 -96.208457) (xy 323.776133 -96.222563) (xy 323.720696 -96.228663) (xy 323.664962 -96.226626)
			(xy 323.610119 -96.216496) (xy 323.557335 -96.198489) (xy 323.507735 -96.172988) (xy 323.462377 -96.140537)
			(xy 323.422228 -96.101828) (xy 323.388142 -96.057685) (xy 323.360846 -96.00905) (xy 323.340923 -95.956959)
			(xy 323.328797 -95.902522) (xy 323.324726 -95.8469) (xy 321.601873 -95.8469) (xy 321.596265 -95.885004)
			(xy 321.580197 -95.938411) (xy 321.556525 -95.988908) (xy 321.525752 -96.035421) (xy 321.488535 -96.076958)
			(xy 321.445667 -96.112633) (xy 321.398061 -96.141687) (xy 321.346732 -96.163499) (xy 321.292775 -96.177605)
			(xy 321.237338 -96.183705) (xy 321.181604 -96.181668) (xy 321.126761 -96.171538) (xy 321.073977 -96.153531)
			(xy 321.024377 -96.12803) (xy 320.979019 -96.095579) (xy 320.93887 -96.05687) (xy 320.904784 -96.012727)
			(xy 320.877488 -95.964092) (xy 320.857565 -95.912001) (xy 320.845439 -95.857564) (xy 320.841368 -95.801942)
			(xy 311.084123 -95.801942) (xy 311.084613 -95.802682) (xy 311.108285 -95.853179) (xy 311.124353 -95.906586)
			(xy 311.132473 -95.961762) (xy 311.132982 -95.989648) (xy 311.132473 -96.017534) (xy 311.124353 -96.07271)
			(xy 311.108285 -96.126117) (xy 311.084613 -96.176614) (xy 311.05384 -96.223127) (xy 311.016623 -96.264664)
			(xy 310.973755 -96.300339) (xy 310.926149 -96.329393) (xy 310.87482 -96.351205) (xy 310.820863 -96.365311)
			(xy 310.765426 -96.371411) (xy 310.709692 -96.369374) (xy 310.654849 -96.359244) (xy 310.602065 -96.341237)
			(xy 310.552465 -96.315736) (xy 310.507107 -96.283285) (xy 310.466958 -96.244576) (xy 310.432872 -96.200433)
			(xy 310.405576 -96.151798) (xy 310.385653 -96.099707) (xy 310.373527 -96.04527) (xy 310.369456 -95.989648)
			(xy 308.52745 -95.989648) (xy 308.526941 -96.017534) (xy 308.518821 -96.07271) (xy 308.502753 -96.126117)
			(xy 308.479081 -96.176614) (xy 308.448308 -96.223127) (xy 308.411091 -96.264664) (xy 308.368223 -96.300339)
			(xy 308.320617 -96.329393) (xy 308.269288 -96.351205) (xy 308.215331 -96.365311) (xy 308.159894 -96.371411)
			(xy 308.10416 -96.369374) (xy 308.049317 -96.359244) (xy 307.996533 -96.341237) (xy 307.946933 -96.315736)
			(xy 307.901575 -96.283285) (xy 307.861426 -96.244576) (xy 307.82734 -96.200433) (xy 307.800044 -96.151798)
			(xy 307.780121 -96.099707) (xy 307.767995 -96.04527) (xy 307.763924 -95.989648) (xy 305.64303 -95.989648)
			(xy 305.638254 -95.994528) (xy 305.568533 -96.054466) (xy 305.493916 -96.108189) (xy 305.414958 -96.155298)
			(xy 305.332242 -96.195446) (xy 305.246382 -96.228334) (xy 305.158011 -96.253719) (xy 305.067786 -96.271414)
			(xy 304.976373 -96.281287) (xy 304.884451 -96.283266) (xy 304.792698 -96.277334) (xy 304.701795 -96.263538)
			(xy 304.612414 -96.241978) (xy 304.525218 -96.212814) (xy 304.440852 -96.176262) (xy 304.35994 -96.132593)
			(xy 304.283081 -96.08213) (xy 304.210846 -96.025247) (xy 304.143767 -95.962365) (xy 304.082342 -95.893949)
			(xy 304.027027 -95.820506) (xy 303.978229 -95.742579) (xy 303.936311 -95.660746) (xy 303.901583 -95.575613)
			(xy 303.874302 -95.48781) (xy 303.85467 -95.397986) (xy 303.842833 -95.306807) (xy 303.838877 -95.214948)
			(xy 281.610562 -95.214948) (xy 281.610068 -95.26092) (xy 281.602164 -95.352524) (xy 281.586414 -95.443109)
			(xy 281.562936 -95.532005) (xy 281.531903 -95.618554) (xy 281.493544 -95.702114) (xy 281.448145 -95.782068)
			(xy 281.39604 -95.857822) (xy 281.337615 -95.928818) (xy 281.273304 -95.994528) (xy 281.203583 -96.054466)
			(xy 281.128966 -96.108189) (xy 281.050008 -96.155298) (xy 280.967292 -96.195446) (xy 280.881432 -96.228334)
			(xy 280.793061 -96.253719) (xy 280.702836 -96.271414) (xy 280.611423 -96.281287) (xy 280.519501 -96.283266)
			(xy 280.427748 -96.277334) (xy 280.336845 -96.263538) (xy 280.247464 -96.241978) (xy 280.160268 -96.212814)
			(xy 280.075902 -96.176262) (xy 279.99499 -96.132593) (xy 279.918131 -96.08213) (xy 279.845896 -96.025247)
			(xy 279.778817 -95.962365) (xy 279.717392 -95.893949) (xy 279.662077 -95.820506) (xy 279.613279 -95.742579)
			(xy 279.571361 -95.660746) (xy 279.536633 -95.575613) (xy 279.509352 -95.48781) (xy 279.48972 -95.397986)
			(xy 279.477883 -95.306807) (xy 279.473927 -95.214948) (xy 277.707664 -95.214948) (xy 277.707348 -95.237148)
			(xy 277.698805 -95.307448) (xy 277.68185 -95.376205) (xy 277.656729 -95.442416) (xy 277.623808 -95.505115)
			(xy 277.583569 -95.563388) (xy 277.536597 -95.616385) (xy 277.483579 -95.663333) (xy 277.425287 -95.703546)
			(xy 277.362573 -95.736438) (xy 277.29635 -95.761529) (xy 277.227586 -95.778453) (xy 277.157282 -95.786964)
			(xy 277.121874 -95.787464) (xy 277.089003 -95.786997) (xy 277.023671 -95.779656) (xy 276.959573 -95.765048)
			(xy 276.897512 -95.743355) (xy 276.838271 -95.714851) (xy 276.782592 -95.679894) (xy 276.731178 -95.638923)
			(xy 276.7076 -95.616014) (xy 271.65935 -90.56751) (xy 271.651926 -90.560701) (xy 271.633345 -90.552963)
			(xy 271.623282 -90.552524) (xy 269.804642 -90.552524) (xy 269.77848 -90.57132) (xy 269.773146 -90.586814)
			(xy 269.763599 -90.612939) (xy 269.738014 -90.662325) (xy 269.70553 -90.707474) (xy 269.666835 -90.747427)
			(xy 269.622749 -90.781339) (xy 269.574206 -90.80849) (xy 269.522235 -90.828306) (xy 269.467939 -90.840366)
			(xy 269.412466 -90.844414) (xy 269.356993 -90.840366) (xy 269.302697 -90.828306) (xy 269.250726 -90.80849)
			(xy 269.202183 -90.781339) (xy 269.158097 -90.747427) (xy 269.119402 -90.707474) (xy 269.086918 -90.662325)
			(xy 269.061333 -90.612939) (xy 269.051786 -90.586814) (xy 269.046452 -90.57132) (xy 269.02029 -90.552524)
			(xy 267.530326 -90.552524) (xy 267.520257 -90.552957) (xy 267.501659 -90.560671) (xy 267.494258 -90.56751)
			(xy 265.775948 -92.286074) (xy 265.752404 -92.308994) (xy 265.701023 -92.349956) (xy 265.64538 -92.384908)
			(xy 265.586172 -92.413411) (xy 265.524146 -92.435105) (xy 265.460082 -92.449719) (xy 265.394783 -92.457068)
			(xy 265.361928 -92.457524) (xy 257.259328 -92.457524) (xy 257.24926 -92.457958) (xy 257.230661 -92.465672)
			(xy 257.22326 -92.47251) (xy 256.153719 -93.542104) (xy 269.030448 -93.542104) (xy 269.034519 -93.486482)
			(xy 269.046645 -93.432045) (xy 269.066568 -93.379954) (xy 269.093864 -93.331319) (xy 269.12795 -93.287176)
			(xy 269.168099 -93.248467) (xy 269.213457 -93.216016) (xy 269.263057 -93.190515) (xy 269.315841 -93.172508)
			(xy 269.370684 -93.162378) (xy 269.426418 -93.160341) (xy 269.481855 -93.166441) (xy 269.535812 -93.180547)
			(xy 269.587141 -93.202359) (xy 269.634747 -93.231413) (xy 269.677615 -93.267088) (xy 269.714832 -93.308625)
			(xy 269.745605 -93.355138) (xy 269.769277 -93.405635) (xy 269.785345 -93.459042) (xy 269.793465 -93.514218)
			(xy 269.793974 -93.542104) (xy 269.793465 -93.56999) (xy 269.785345 -93.625166) (xy 269.769277 -93.678573)
			(xy 269.745605 -93.72907) (xy 269.714832 -93.775583) (xy 269.677615 -93.81712) (xy 269.634747 -93.852795)
			(xy 269.587141 -93.881849) (xy 269.535812 -93.903661) (xy 269.481855 -93.917767) (xy 269.426418 -93.923867)
			(xy 269.370684 -93.92183) (xy 269.315841 -93.9117) (xy 269.263057 -93.893693) (xy 269.213457 -93.868192)
			(xy 269.168099 -93.835741) (xy 269.12795 -93.797032) (xy 269.093864 -93.752889) (xy 269.066568 -93.704254)
			(xy 269.046645 -93.652163) (xy 269.034519 -93.597726) (xy 269.030448 -93.542104) (xy 256.153719 -93.542104)
			(xy 252.114812 -97.581212) (xy 252.091233 -97.604129) (xy 252.039823 -97.645125) (xy 251.98415 -97.680113)
			(xy 251.924912 -97.708653) (xy 251.862853 -97.730388) (xy 251.798753 -97.745044) (xy 251.733415 -97.752437)
			(xy 251.700538 -97.752916) (xy 231.367584 -97.752916) (xy 231.334703 -97.752482) (xy 231.269355 -97.745113)
			(xy 231.205243 -97.73047) (xy 231.143176 -97.708737) (xy 231.083934 -97.680188) (xy 231.028263 -97.645181)
			(xy 230.976864 -97.604159) (xy 230.95331 -97.581212) (xy 230.356918 -96.98482) (xy 230.326946 -96.978978)
			(xy 230.312722 -96.98482) (xy 230.30369 -96.989134) (xy 230.289606 -97.003329) (xy 230.281974 -97.021812)
			(xy 230.28148 -97.03181) (xy 230.28148 -97.21596) (xy 230.281905 -97.22603) (xy 230.289624 -97.244629)
			(xy 230.296466 -97.252028) (xy 231.055672 -98.011234) (xy 231.063084 -98.018059) (xy 231.081674 -98.025787)
			(xy 231.09174 -98.02622) (xy 231.12222 -98.02622) (xy 231.131574 -98.02572) (xy 231.149026 -98.018966)
			(xy 231.156256 -98.013012) (xy 231.177392 -97.99452) (xy 231.224108 -97.963351) (xy 231.274894 -97.939378)
			(xy 231.328649 -97.923121) (xy 231.384208 -97.914932) (xy 231.412288 -97.91446) (xy 231.439537 -97.914989)
			(xy 231.493482 -97.922743) (xy 231.545774 -97.938095) (xy 231.595349 -97.960733) (xy 231.641198 -97.990195)
			(xy 231.682387 -98.025882) (xy 231.718079 -98.067067) (xy 231.747546 -98.112913) (xy 231.770189 -98.162485)
			(xy 231.785547 -98.214775) (xy 231.793308 -98.268719) (xy 231.793796 -98.295968) (xy 231.79317 -98.325944)
			(xy 231.783785 -98.385157) (xy 231.765258 -98.442174) (xy 231.738044 -98.495593) (xy 231.702812 -98.5441)
			(xy 231.682036 -98.565716) (xy 231.681782 -98.56597) (xy 231.675109 -98.573392) (xy 231.667501 -98.59182)
			(xy 231.667497 -98.611757) (xy 231.675096 -98.630189) (xy 231.681782 -98.637598) (xy 231.706674 -98.66249)
			(xy 231.71409 -98.66931) (xy 231.732677 -98.677042) (xy 231.742742 -98.677476) (xy 232.034334 -98.677476)
			(xy 232.043637 -98.677086) (xy 232.061036 -98.670505) (xy 232.074917 -98.658122) (xy 232.079546 -98.650044)
			(xy 232.127552 -98.556826) (xy 232.12552 -98.528632) (xy 232.117392 -98.516948) (xy 232.100732 -98.492617)
			(xy 232.07434 -98.439886) (xy 232.056394 -98.383716) (xy 232.047323 -98.325452) (xy 232.04678 -98.295968)
			(xy 232.047266 -98.268717) (xy 232.055022 -98.214769) (xy 232.070377 -98.162474) (xy 232.093019 -98.112897)
			(xy 232.122485 -98.067047) (xy 232.158176 -98.025856) (xy 232.199367 -97.990165) (xy 232.245217 -97.960699)
			(xy 232.294794 -97.938057) (xy 232.347089 -97.922702) (xy 232.401037 -97.914946) (xy 232.455539 -97.914946)
			(xy 232.509487 -97.922702) (xy 232.561782 -97.938057) (xy 232.611359 -97.960699) (xy 232.657209 -97.990165)
			(xy 232.6984 -98.025856) (xy 232.734091 -98.067047) (xy 232.763557 -98.112897) (xy 232.786199 -98.162474)
			(xy 232.801554 -98.214769) (xy 232.80931 -98.268717) (xy 232.809796 -98.295968) (xy 236.11027 -98.295968)
			(xy 236.114341 -98.240346) (xy 236.126467 -98.185909) (xy 236.14639 -98.133818) (xy 236.173686 -98.085183)
			(xy 236.207772 -98.04104) (xy 236.247921 -98.002331) (xy 236.293279 -97.96988) (xy 236.342879 -97.944379)
			(xy 236.395663 -97.926372) (xy 236.450506 -97.916242) (xy 236.50624 -97.914205) (xy 236.561677 -97.920305)
			(xy 236.615634 -97.934411) (xy 236.666963 -97.956223) (xy 236.714569 -97.985277) (xy 236.757437 -98.020952)
			(xy 236.794654 -98.062489) (xy 236.825427 -98.109002) (xy 236.849099 -98.159499) (xy 236.865167 -98.212906)
			(xy 236.873287 -98.268082) (xy 236.873796 -98.295968) (xy 236.873287 -98.323854) (xy 236.865167 -98.37903)
			(xy 236.849099 -98.432437) (xy 236.825427 -98.482934) (xy 236.794654 -98.529447) (xy 236.757437 -98.570984)
			(xy 236.714569 -98.606659) (xy 236.666963 -98.635713) (xy 236.615634 -98.657525) (xy 236.561677 -98.671631)
			(xy 236.50624 -98.677731) (xy 236.450506 -98.675694) (xy 236.395663 -98.665564) (xy 236.342879 -98.647557)
			(xy 236.293279 -98.622056) (xy 236.247921 -98.589605) (xy 236.207772 -98.550896) (xy 236.173686 -98.506753)
			(xy 236.14639 -98.458118) (xy 236.126467 -98.406027) (xy 236.114341 -98.35159) (xy 236.11027 -98.295968)
			(xy 232.809796 -98.295968) (xy 232.809211 -98.325446) (xy 232.800103 -98.383696) (xy 232.78216 -98.439857)
			(xy 232.755808 -98.492598) (xy 232.739184 -98.516948) (xy 232.731056 -98.528632) (xy 232.729024 -98.556826)
			(xy 232.77703 -98.650044) (xy 232.781686 -98.658097) (xy 232.795578 -98.670447) (xy 232.812949 -98.677063)
			(xy 232.822242 -98.677476) (xy 232.900982 -98.677476) (xy 232.933834 -98.677972) (xy 232.999126 -98.685333)
			(xy 233.063184 -98.699952) (xy 233.125204 -98.721646) (xy 233.184408 -98.750142) (xy 233.211035 -98.766863)
			(xy 257.089906 -98.766863) (xy 257.089906 -98.633301) (xy 257.09797 -98.499983) (xy 257.11407 -98.367395)
			(xy 257.138145 -98.236021) (xy 257.170108 -98.10634) (xy 257.209843 -97.978826) (xy 257.257205 -97.853943)
			(xy 257.31202 -97.732148) (xy 257.37409 -97.613885) (xy 257.443186 -97.499586) (xy 257.519058 -97.389666)
			(xy 257.601428 -97.284529) (xy 257.689996 -97.184556) (xy 257.784438 -97.090114) (xy 257.884411 -97.001546)
			(xy 257.989548 -96.919176) (xy 258.099468 -96.843304) (xy 258.213767 -96.774208) (xy 258.33203 -96.712138)
			(xy 258.453825 -96.657323) (xy 258.578708 -96.609961) (xy 258.706222 -96.570226) (xy 258.835903 -96.538263)
			(xy 258.967277 -96.514188) (xy 259.099865 -96.498088) (xy 259.233183 -96.490024) (xy 259.366745 -96.490024)
			(xy 259.500063 -96.498088) (xy 259.632651 -96.514188) (xy 259.764025 -96.538263) (xy 259.893706 -96.570226)
			(xy 260.02122 -96.609961) (xy 260.146103 -96.657323) (xy 260.267898 -96.712138) (xy 260.386161 -96.774208)
			(xy 260.50046 -96.843304) (xy 260.61038 -96.919176) (xy 260.715517 -97.001546) (xy 260.81549 -97.090114)
			(xy 260.909932 -97.184556) (xy 260.9985 -97.284529) (xy 261.08087 -97.389666) (xy 261.156742 -97.499586)
			(xy 261.225838 -97.613885) (xy 261.287908 -97.732148) (xy 261.342723 -97.853943) (xy 261.390085 -97.978826)
			(xy 261.42982 -98.10634) (xy 261.461783 -98.236021) (xy 261.485858 -98.367395) (xy 261.501958 -98.499983)
			(xy 261.510022 -98.633301) (xy 261.510526 -98.700082) (xy 261.510022 -98.766863) (xy 261.501958 -98.900181)
			(xy 261.485858 -99.032769) (xy 261.461783 -99.164143) (xy 261.42982 -99.293824) (xy 261.390085 -99.421338)
			(xy 261.342723 -99.546221) (xy 261.287908 -99.668016) (xy 261.225838 -99.786279) (xy 261.156742 -99.900578)
			(xy 261.08087 -100.010498) (xy 260.9985 -100.115635) (xy 260.909932 -100.215608) (xy 260.81549 -100.31005)
			(xy 260.715517 -100.398618) (xy 260.61038 -100.480988) (xy 260.50046 -100.55686) (xy 260.386161 -100.625956)
			(xy 260.267898 -100.688026) (xy 260.146103 -100.742841) (xy 260.02122 -100.790203) (xy 259.893706 -100.829938)
			(xy 259.764025 -100.861901) (xy 259.632651 -100.885976) (xy 259.500063 -100.902076) (xy 259.366745 -100.91014)
			(xy 259.233183 -100.91014) (xy 259.099865 -100.902076) (xy 258.967277 -100.885976) (xy 258.835903 -100.861901)
			(xy 258.706222 -100.829938) (xy 258.578708 -100.790203) (xy 258.453825 -100.742841) (xy 258.33203 -100.688026)
			(xy 258.213767 -100.625956) (xy 258.099468 -100.55686) (xy 257.989548 -100.480988) (xy 257.884411 -100.398618)
			(xy 257.784438 -100.31005) (xy 257.689996 -100.215608) (xy 257.601428 -100.115635) (xy 257.519058 -100.010498)
			(xy 257.443186 -99.900578) (xy 257.37409 -99.786279) (xy 257.31202 -99.668016) (xy 257.257205 -99.546221)
			(xy 257.209843 -99.421338) (xy 257.170108 -99.293824) (xy 257.138145 -99.164143) (xy 257.11407 -99.032769)
			(xy 257.09797 -98.900181) (xy 257.089906 -98.766863) (xy 233.211035 -98.766863) (xy 233.240051 -98.785084)
			(xy 233.291437 -98.826031) (xy 233.315002 -98.848926) (xy 234.238999 -99.772978) (xy 243.553486 -99.772978)
			(xy 243.557557 -99.717356) (xy 243.569683 -99.662919) (xy 243.589606 -99.610828) (xy 243.616902 -99.562193)
			(xy 243.650988 -99.51805) (xy 243.691137 -99.479341) (xy 243.736495 -99.44689) (xy 243.786095 -99.421389)
			(xy 243.838879 -99.403382) (xy 243.893722 -99.393252) (xy 243.949456 -99.391215) (xy 244.004893 -99.397315)
			(xy 244.05885 -99.411421) (xy 244.110179 -99.433233) (xy 244.157785 -99.462287) (xy 244.200653 -99.497962)
			(xy 244.23787 -99.539499) (xy 244.268643 -99.586012) (xy 244.292315 -99.636509) (xy 244.308383 -99.689916)
			(xy 244.316503 -99.745092) (xy 244.317012 -99.772978) (xy 244.316503 -99.800864) (xy 244.308383 -99.85604)
			(xy 244.292315 -99.909447) (xy 244.268643 -99.959944) (xy 244.23787 -100.006457) (xy 244.200653 -100.047994)
			(xy 244.157785 -100.083669) (xy 244.110179 -100.112723) (xy 244.05885 -100.134535) (xy 244.004893 -100.148641)
			(xy 243.949456 -100.154741) (xy 243.893722 -100.152704) (xy 243.838879 -100.142574) (xy 243.786095 -100.124567)
			(xy 243.736495 -100.099066) (xy 243.691137 -100.066615) (xy 243.650988 -100.027906) (xy 243.616902 -99.983763)
			(xy 243.589606 -99.935128) (xy 243.569683 -99.883037) (xy 243.557557 -99.8286) (xy 243.553486 -99.772978)
			(xy 234.238999 -99.772978) (xy 236.667603 -102.201726) (xy 245.578374 -102.201726) (xy 245.582445 -102.146104)
			(xy 245.594571 -102.091667) (xy 245.614494 -102.039576) (xy 245.64179 -101.990941) (xy 245.675876 -101.946798)
			(xy 245.716025 -101.908089) (xy 245.761383 -101.875638) (xy 245.810983 -101.850137) (xy 245.863767 -101.83213)
			(xy 245.91861 -101.822) (xy 245.974344 -101.819963) (xy 246.029781 -101.826063) (xy 246.083738 -101.840169)
			(xy 246.135067 -101.861981) (xy 246.182673 -101.891035) (xy 246.225541 -101.92671) (xy 246.262758 -101.968247)
			(xy 246.293531 -102.01476) (xy 246.317203 -102.065257) (xy 246.333271 -102.118664) (xy 246.341391 -102.17384)
			(xy 246.3419 -102.201726) (xy 246.341391 -102.229612) (xy 246.333271 -102.284788) (xy 246.317203 -102.338195)
			(xy 246.293531 -102.388692) (xy 246.262758 -102.435205) (xy 246.225541 -102.476742) (xy 246.182673 -102.512417)
			(xy 246.135067 -102.541471) (xy 246.083738 -102.563283) (xy 246.029781 -102.577389) (xy 245.974344 -102.583489)
			(xy 245.91861 -102.581452) (xy 245.863767 -102.571322) (xy 245.810983 -102.553315) (xy 245.761383 -102.527814)
			(xy 245.716025 -102.495363) (xy 245.675876 -102.456654) (xy 245.64179 -102.412511) (xy 245.614494 -102.363876)
			(xy 245.594571 -102.311785) (xy 245.582445 -102.257348) (xy 245.578374 -102.201726) (xy 236.667603 -102.201726)
			(xy 237.602268 -103.136446) (xy 237.609719 -103.143213) (xy 237.628284 -103.150929) (xy 237.638336 -103.151432)
			(xy 240.508282 -103.151432) (xy 240.541135 -103.151912) (xy 240.606428 -103.159273) (xy 240.670486 -103.173894)
			(xy 240.732507 -103.19559) (xy 240.791711 -103.224089) (xy 240.847354 -103.259034) (xy 240.898738 -103.299985)
			(xy 240.922302 -103.322882) (xy 241.170968 -103.571548) (xy 246.435116 -103.571548) (xy 246.439187 -103.515926)
			(xy 246.451313 -103.461489) (xy 246.471236 -103.409398) (xy 246.498532 -103.360763) (xy 246.532618 -103.31662)
			(xy 246.572767 -103.277911) (xy 246.618125 -103.24546) (xy 246.667725 -103.219959) (xy 246.720509 -103.201952)
			(xy 246.775352 -103.191822) (xy 246.831086 -103.189785) (xy 246.886523 -103.195885) (xy 246.94048 -103.209991)
			(xy 246.991809 -103.231803) (xy 247.039415 -103.260857) (xy 247.082283 -103.296532) (xy 247.1195 -103.338069)
			(xy 247.150273 -103.384582) (xy 247.173945 -103.435079) (xy 247.190013 -103.488486) (xy 247.198133 -103.543662)
			(xy 247.198642 -103.571548) (xy 247.198133 -103.599434) (xy 247.190013 -103.65461) (xy 247.173945 -103.708017)
			(xy 247.150273 -103.758514) (xy 247.1195 -103.805027) (xy 247.082283 -103.846564) (xy 247.039415 -103.882239)
			(xy 246.991809 -103.911293) (xy 246.94048 -103.933105) (xy 246.897199 -103.94442) (xy 251.43155 -103.94442)
			(xy 251.435621 -103.888798) (xy 251.447747 -103.834361) (xy 251.46767 -103.78227) (xy 251.494966 -103.733635)
			(xy 251.529052 -103.689492) (xy 251.569201 -103.650783) (xy 251.614559 -103.618332) (xy 251.664159 -103.592831)
			(xy 251.716943 -103.574824) (xy 251.771786 -103.564694) (xy 251.82752 -103.562657) (xy 251.882957 -103.568757)
			(xy 251.936914 -103.582863) (xy 251.988243 -103.604675) (xy 252.035849 -103.633729) (xy 252.078717 -103.669404)
			(xy 252.115934 -103.710941) (xy 252.146707 -103.757454) (xy 252.170379 -103.807951) (xy 252.186447 -103.861358)
			(xy 252.194567 -103.916534) (xy 252.195076 -103.94442) (xy 252.194567 -103.972306) (xy 252.186447 -104.027482)
			(xy 252.170379 -104.080889) (xy 252.146707 -104.131386) (xy 252.115934 -104.177899) (xy 252.078717 -104.219436)
			(xy 252.035849 -104.255111) (xy 251.988243 -104.284165) (xy 251.936914 -104.305977) (xy 251.882957 -104.320083)
			(xy 251.82752 -104.326183) (xy 251.771786 -104.324146) (xy 251.716943 -104.314016) (xy 251.664159 -104.296009)
			(xy 251.614559 -104.270508) (xy 251.569201 -104.238057) (xy 251.529052 -104.199348) (xy 251.494966 -104.155205)
			(xy 251.46767 -104.10657) (xy 251.447747 -104.054479) (xy 251.435621 -104.000042) (xy 251.43155 -103.94442)
			(xy 246.897199 -103.94442) (xy 246.886523 -103.947211) (xy 246.831086 -103.953311) (xy 246.775352 -103.951274)
			(xy 246.720509 -103.941144) (xy 246.667725 -103.923137) (xy 246.618125 -103.897636) (xy 246.572767 -103.865185)
			(xy 246.532618 -103.826476) (xy 246.498532 -103.782333) (xy 246.471236 -103.733698) (xy 246.451313 -103.681607)
			(xy 246.439187 -103.62717) (xy 246.435116 -103.571548) (xy 241.170968 -103.571548) (xy 244.465856 -106.866436)
			(xy 244.488756 -106.890031) (xy 244.529752 -106.941439) (xy 244.564741 -106.997109) (xy 244.593283 -107.056344)
			(xy 244.615021 -107.1184) (xy 244.62968 -107.182498) (xy 244.637079 -107.247834) (xy 244.63756 -107.28071)
			(xy 244.63756 -108.610146) (xy 245.158768 -108.610146) (xy 245.159298 -108.582895) (xy 245.167048 -108.528948)
			(xy 245.182397 -108.476653) (xy 245.205032 -108.427075) (xy 245.234493 -108.381222) (xy 245.27018 -108.34003)
			(xy 245.311366 -108.304335) (xy 245.357213 -108.274866) (xy 245.406787 -108.252222) (xy 245.45908 -108.236863)
			(xy 245.513025 -108.229103) (xy 245.540276 -108.228638) (xy 245.568957 -108.229202) (xy 245.625669 -108.237809)
			(xy 245.680456 -108.254802) (xy 245.732084 -108.2798) (xy 245.779392 -108.312239) (xy 245.821316 -108.351389)
			(xy 245.856911 -108.396371) (xy 245.885378 -108.446171) (xy 245.906074 -108.499669) (xy 245.918535 -108.55566)
			(xy 245.921022 -108.584238) (xy 245.922507 -108.59876) (xy 245.93262 -108.626129) (xy 245.950059 -108.649522)
			(xy 245.973399 -108.667031) (xy 246.000737 -108.677228) (xy 246.015256 -108.678726) (xy 246.043842 -108.681195)
			(xy 246.099854 -108.693625) (xy 246.153373 -108.7143) (xy 246.203194 -108.742756) (xy 246.248193 -108.778351)
			(xy 246.287354 -108.820282) (xy 246.319797 -108.867604) (xy 246.344788 -108.91925) (xy 246.361765 -108.974055)
			(xy 246.370345 -109.030785) (xy 246.370856 -109.059472) (xy 246.370296 -109.08672) (xy 246.362544 -109.140663)
			(xy 246.347195 -109.192953) (xy 246.324561 -109.242527) (xy 246.308516 -109.267498) (xy 246.461786 -109.267498)
			(xy 246.465857 -109.211876) (xy 246.477983 -109.157439) (xy 246.497906 -109.105348) (xy 246.525202 -109.056713)
			(xy 246.559288 -109.01257) (xy 246.599437 -108.973861) (xy 246.644795 -108.94141) (xy 246.694395 -108.915909)
			(xy 246.747179 -108.897902) (xy 246.802022 -108.887772) (xy 246.857756 -108.885735) (xy 246.913193 -108.891835)
			(xy 246.96715 -108.905941) (xy 247.018479 -108.927753) (xy 247.066085 -108.956807) (xy 247.108953 -108.992482)
			(xy 247.14617 -109.034019) (xy 247.176943 -109.080532) (xy 247.200615 -109.131029) (xy 247.216683 -109.184436)
			(xy 247.224803 -109.239612) (xy 247.225312 -109.267498) (xy 247.224803 -109.295384) (xy 247.216683 -109.35056)
			(xy 247.200615 -109.403967) (xy 247.176943 -109.454464) (xy 247.14617 -109.500977) (xy 247.108953 -109.542514)
			(xy 247.066085 -109.578189) (xy 247.018479 -109.607243) (xy 246.96715 -109.629055) (xy 246.913193 -109.643161)
			(xy 246.857756 -109.649261) (xy 246.802022 -109.647224) (xy 246.747179 -109.637094) (xy 246.694395 -109.619087)
			(xy 246.644795 -109.593586) (xy 246.599437 -109.561135) (xy 246.559288 -109.522426) (xy 246.525202 -109.478283)
			(xy 246.497906 -109.429648) (xy 246.477983 -109.377557) (xy 246.465857 -109.32312) (xy 246.461786 -109.267498)
			(xy 246.308516 -109.267498) (xy 246.295102 -109.288375) (xy 246.259418 -109.329565) (xy 246.218236 -109.365256)
			(xy 246.172394 -109.394724) (xy 246.122825 -109.417369) (xy 246.070537 -109.432728) (xy 246.016596 -109.44049)
			(xy 245.989348 -109.44098) (xy 245.960666 -109.440469) (xy 245.903953 -109.431852) (xy 245.849166 -109.41485)
			(xy 245.797538 -109.389845) (xy 245.750231 -109.357399) (xy 245.708309 -109.318243) (xy 245.672714 -109.273257)
			(xy 245.644249 -109.223454) (xy 245.623552 -109.169953) (xy 245.611089 -109.113959) (xy 245.608602 -109.08538)
			(xy 245.607171 -109.070849) (xy 245.597053 -109.043471) (xy 245.579603 -109.020073) (xy 245.556247 -109.002566)
			(xy 245.528894 -108.992381) (xy 245.514368 -108.990892) (xy 245.485786 -108.988385) (xy 245.429776 -108.975959)
			(xy 245.376258 -108.955288) (xy 245.326438 -108.926836) (xy 245.28144 -108.891246) (xy 245.242278 -108.849319)
			(xy 245.209834 -108.802002) (xy 245.184842 -108.75036) (xy 245.167863 -108.695558) (xy 245.159281 -108.638832)
			(xy 245.158768 -108.610146) (xy 244.63756 -108.610146) (xy 244.63756 -112.10671) (xy 244.656864 -112.13338)
			(xy 244.672612 -112.13846) (xy 244.699348 -112.147587) (xy 244.749954 -112.1727) (xy 244.796303 -112.205003)
			(xy 244.837381 -112.243788) (xy 244.87229 -112.288207) (xy 244.900266 -112.337289) (xy 244.920697 -112.38996)
			(xy 244.933137 -112.445068) (xy 244.937313 -112.501408) (xy 244.933134 -112.557748) (xy 244.920692 -112.612856)
			(xy 244.900259 -112.665526) (xy 244.872281 -112.714606) (xy 244.83737 -112.759024) (xy 244.796291 -112.797807)
			(xy 244.749941 -112.830108) (xy 244.699334 -112.855219) (xy 244.672612 -112.864392) (xy 244.662579 -112.868107)
			(xy 244.6467 -112.882423) (xy 244.638021 -112.901962) (xy 244.63756 -112.912652) (xy 244.63756 -113.302034)
			(xy 246.513602 -113.302034) (xy 246.517673 -113.246412) (xy 246.529799 -113.191975) (xy 246.549722 -113.139884)
			(xy 246.577018 -113.091249) (xy 246.611104 -113.047106) (xy 246.651253 -113.008397) (xy 246.696611 -112.975946)
			(xy 246.746211 -112.950445) (xy 246.798995 -112.932438) (xy 246.853838 -112.922308) (xy 246.909572 -112.920271)
			(xy 246.965009 -112.926371) (xy 247.018966 -112.940477) (xy 247.070295 -112.962289) (xy 247.117901 -112.991343)
			(xy 247.160769 -113.027018) (xy 247.197986 -113.068555) (xy 247.228759 -113.115068) (xy 247.252431 -113.165565)
			(xy 247.257725 -113.183162) (xy 248.515122 -113.183162) (xy 248.519193 -113.12754) (xy 248.531319 -113.073103)
			(xy 248.551242 -113.021012) (xy 248.578538 -112.972377) (xy 248.612624 -112.928234) (xy 248.652773 -112.889525)
			(xy 248.698131 -112.857074) (xy 248.747731 -112.831573) (xy 248.800515 -112.813566) (xy 248.855358 -112.803436)
			(xy 248.911092 -112.801399) (xy 248.966529 -112.807499) (xy 249.020486 -112.821605) (xy 249.071815 -112.843417)
			(xy 249.119421 -112.872471) (xy 249.162289 -112.908146) (xy 249.199506 -112.949683) (xy 249.230279 -112.996196)
			(xy 249.253951 -113.046693) (xy 249.270019 -113.1001) (xy 249.278139 -113.155276) (xy 249.278648 -113.183162)
			(xy 249.278139 -113.211048) (xy 249.270019 -113.266224) (xy 249.253951 -113.319631) (xy 249.230279 -113.370128)
			(xy 249.199506 -113.416641) (xy 249.162289 -113.458178) (xy 249.119421 -113.493853) (xy 249.071815 -113.522907)
			(xy 249.020486 -113.544719) (xy 248.966529 -113.558825) (xy 248.911092 -113.564925) (xy 248.855358 -113.562888)
			(xy 248.800515 -113.552758) (xy 248.747731 -113.534751) (xy 248.698131 -113.50925) (xy 248.652773 -113.476799)
			(xy 248.612624 -113.43809) (xy 248.578538 -113.393947) (xy 248.551242 -113.345312) (xy 248.531319 -113.293221)
			(xy 248.519193 -113.238784) (xy 248.515122 -113.183162) (xy 247.257725 -113.183162) (xy 247.268499 -113.218972)
			(xy 247.276619 -113.274148) (xy 247.277128 -113.302034) (xy 247.276619 -113.32992) (xy 247.268499 -113.385096)
			(xy 247.252431 -113.438503) (xy 247.228759 -113.489) (xy 247.197986 -113.535513) (xy 247.160769 -113.57705)
			(xy 247.117901 -113.612725) (xy 247.070295 -113.641779) (xy 247.018966 -113.663591) (xy 246.965009 -113.677697)
			(xy 246.909572 -113.683797) (xy 246.853838 -113.68176) (xy 246.798995 -113.67163) (xy 246.746211 -113.653623)
			(xy 246.696611 -113.628122) (xy 246.651253 -113.595671) (xy 246.611104 -113.556962) (xy 246.577018 -113.512819)
			(xy 246.549722 -113.464184) (xy 246.529799 -113.412093) (xy 246.517673 -113.357656) (xy 246.513602 -113.302034)
			(xy 244.63756 -113.302034) (xy 244.63756 -114.26952) (xy 244.656102 -114.295682) (xy 244.671088 -114.301016)
			(xy 244.696942 -114.310675) (xy 244.745736 -114.336466) (xy 244.790304 -114.36902) (xy 244.829715 -114.407656)
			(xy 244.863148 -114.451568) (xy 244.889903 -114.49984) (xy 244.909423 -114.551464) (xy 244.9213 -114.605362)
			(xy 244.925286 -114.660409) (xy 244.921298 -114.715455) (xy 244.909418 -114.769353) (xy 244.889896 -114.820976)
			(xy 244.863138 -114.869246) (xy 244.829704 -114.913157) (xy 244.79029 -114.951792) (xy 244.745721 -114.984343)
			(xy 244.696926 -115.010132) (xy 244.671088 -115.019836) (xy 244.656102 -115.02517) (xy 244.63756 -115.051332)
			(xy 244.63756 -116.043202) (xy 244.638108 -116.053627) (xy 244.646453 -116.072738) (xy 244.661692 -116.086973)
			(xy 244.671342 -116.090954) (xy 244.697155 -116.100718) (xy 244.745949 -116.126499) (xy 244.790517 -116.159043)
			(xy 244.829929 -116.19767) (xy 244.863364 -116.241574) (xy 244.890121 -116.289839) (xy 244.909644 -116.341455)
			(xy 244.921523 -116.395347) (xy 244.925512 -116.450388) (xy 244.921527 -116.505429) (xy 244.909651 -116.559322)
			(xy 244.890131 -116.61094) (xy 244.863377 -116.659206) (xy 244.829945 -116.703112) (xy 244.790535 -116.741742)
			(xy 244.745969 -116.774288) (xy 244.697178 -116.800073) (xy 244.671342 -116.809774) (xy 244.661643 -116.813677)
			(xy 244.646359 -116.827915) (xy 244.638048 -116.84708) (xy 244.63756 -116.857526) (xy 244.63756 -117.434106)
			(xy 245.576852 -117.434106) (xy 245.577309 -117.406735) (xy 245.585127 -117.352555) (xy 245.600618 -117.300052)
			(xy 245.623462 -117.250305) (xy 245.653189 -117.204339) (xy 245.670832 -117.183408) (xy 245.671086 -117.183154)
			(xy 245.676655 -117.176055) (xy 245.682913 -117.159148) (xy 245.683278 -117.150134) (xy 245.683278 -117.083078)
			(xy 245.682936 -117.074059) (xy 245.676679 -117.057142) (xy 245.671086 -117.050058) (xy 245.670832 -117.050058)
			(xy 245.670832 -117.049804) (xy 245.653197 -117.028867) (xy 245.623472 -116.9829) (xy 245.600626 -116.933154)
			(xy 245.585129 -116.880653) (xy 245.577299 -116.826475) (xy 245.577299 -116.771734) (xy 245.585127 -116.717556)
			(xy 245.600622 -116.665054) (xy 245.623467 -116.615308) (xy 245.653192 -116.569341) (xy 245.670832 -116.548408)
			(xy 245.671086 -116.548154) (xy 245.676655 -116.541055) (xy 245.682913 -116.524148) (xy 245.683278 -116.515134)
			(xy 245.683278 -116.448078) (xy 245.682936 -116.439059) (xy 245.676679 -116.422142) (xy 245.671086 -116.415058)
			(xy 245.670832 -116.415058) (xy 245.670832 -116.414804) (xy 245.653186 -116.393877) (xy 245.623474 -116.347903)
			(xy 245.600639 -116.298155) (xy 245.58515 -116.245653) (xy 245.577324 -116.191476) (xy 245.576852 -116.164106)
			(xy 245.577383 -116.136857) (xy 245.585138 -116.082913) (xy 245.60049 -116.030621) (xy 245.623128 -115.981047)
			(xy 245.65259 -115.935198) (xy 245.688276 -115.894009) (xy 245.729461 -115.858317) (xy 245.775306 -115.82885)
			(xy 245.824878 -115.806206) (xy 245.877168 -115.790848) (xy 245.931111 -115.783087) (xy 245.95836 -115.782598)
			(xy 245.985729 -115.783088) (xy 246.039907 -115.7909) (xy 246.09241 -115.806384) (xy 246.142157 -115.82922)
			(xy 246.188125 -115.858939) (xy 246.209058 -115.876578) (xy 246.209312 -115.876832) (xy 246.216388 -115.882433)
			(xy 246.233313 -115.88867) (xy 246.242332 -115.889024) (xy 246.309388 -115.889024) (xy 246.318404 -115.888656)
			(xy 246.33532 -115.882415) (xy 246.342408 -115.876832) (xy 246.342408 -115.876578) (xy 246.342662 -115.876578)
			(xy 246.363595 -115.85894) (xy 246.409568 -115.829229) (xy 246.459315 -115.806393) (xy 246.511815 -115.790901)
			(xy 246.565991 -115.783073) (xy 246.59336 -115.782598) (xy 246.620612 -115.783093) (xy 246.674562 -115.790844)
			(xy 246.72686 -115.806195) (xy 246.77644 -115.828834) (xy 246.822294 -115.858298) (xy 246.863487 -115.893989)
			(xy 246.899181 -115.935179) (xy 246.92865 -115.98103) (xy 246.951293 -116.030608) (xy 246.966649 -116.082904)
			(xy 246.974405 -116.136854) (xy 246.974868 -116.164106) (xy 246.974413 -116.191477) (xy 246.966594 -116.245657)
			(xy 246.951103 -116.29816) (xy 246.928258 -116.347907) (xy 246.898531 -116.393873) (xy 246.880888 -116.414804)
			(xy 246.880634 -116.415058) (xy 246.875051 -116.422147) (xy 246.868804 -116.439062) (xy 246.868442 -116.448078)
			(xy 246.868442 -116.515134) (xy 246.868774 -116.524154) (xy 246.875038 -116.541071) (xy 246.880634 -116.548154)
			(xy 246.880888 -116.548154) (xy 246.880888 -116.548408) (xy 246.898534 -116.569336) (xy 246.928257 -116.615305)
			(xy 246.951101 -116.665052) (xy 246.966597 -116.717555) (xy 246.974424 -116.771734) (xy 246.974424 -116.826475)
			(xy 246.966595 -116.880654) (xy 246.951098 -116.933156) (xy 246.928253 -116.982903) (xy 246.898528 -117.028871)
			(xy 246.880888 -117.049804) (xy 246.880634 -117.050058) (xy 246.875051 -117.057147) (xy 246.868804 -117.074062)
			(xy 246.868442 -117.083078) (xy 246.868442 -117.150134) (xy 246.868774 -117.159154) (xy 246.875038 -117.176071)
			(xy 246.880634 -117.183154) (xy 246.880888 -117.183154) (xy 246.880888 -117.183408) (xy 246.898542 -117.204328)
			(xy 246.928252 -117.250304) (xy 246.951086 -117.300054) (xy 246.966573 -117.352558) (xy 246.974397 -117.406736)
			(xy 246.974868 -117.434106) (xy 246.97473 -117.442234) (xy 247.85904 -117.442234) (xy 247.863111 -117.386612)
			(xy 247.875237 -117.332175) (xy 247.89516 -117.280084) (xy 247.922456 -117.231449) (xy 247.956542 -117.187306)
			(xy 247.996691 -117.148597) (xy 248.042049 -117.116146) (xy 248.091649 -117.090645) (xy 248.144433 -117.072638)
			(xy 248.199276 -117.062508) (xy 248.25501 -117.060471) (xy 248.310447 -117.066571) (xy 248.364404 -117.080677)
			(xy 248.415733 -117.102489) (xy 248.463339 -117.131543) (xy 248.506207 -117.167218) (xy 248.543424 -117.208755)
			(xy 248.574197 -117.255268) (xy 248.597869 -117.305765) (xy 248.613937 -117.359172) (xy 248.622057 -117.414348)
			(xy 248.622566 -117.442234) (xy 248.622057 -117.47012) (xy 248.613937 -117.525296) (xy 248.597869 -117.578703)
			(xy 248.574197 -117.6292) (xy 248.543424 -117.675713) (xy 248.506207 -117.71725) (xy 248.463339 -117.752925)
			(xy 248.415733 -117.781979) (xy 248.364404 -117.803791) (xy 248.310447 -117.817897) (xy 248.25501 -117.823997)
			(xy 248.199276 -117.82196) (xy 248.144433 -117.81183) (xy 248.091649 -117.793823) (xy 248.042049 -117.768322)
			(xy 247.996691 -117.735871) (xy 247.956542 -117.697162) (xy 247.922456 -117.653019) (xy 247.89516 -117.604384)
			(xy 247.875237 -117.552293) (xy 247.863111 -117.497856) (xy 247.85904 -117.442234) (xy 246.97473 -117.442234)
			(xy 246.974416 -117.460663) (xy 246.967047 -117.513262) (xy 246.952452 -117.564331) (xy 246.942102 -117.588792)
			(xy 246.937753 -117.60016) (xy 246.939101 -117.624434) (xy 246.944642 -117.635274) (xy 246.986044 -117.706394)
			(xy 246.99276 -117.716478) (xy 247.013181 -117.729461) (xy 247.02516 -117.731286) (xy 247.053143 -117.73446)
			(xy 247.107807 -117.747998) (xy 247.159886 -117.769425) (xy 247.208249 -117.798277) (xy 247.251844 -117.833926)
			(xy 247.289724 -117.875598) (xy 247.321066 -117.922386) (xy 247.345188 -117.973274) (xy 247.361565 -118.027155)
			(xy 247.367007 -118.063772) (xy 249.006104 -118.063772) (xy 249.010175 -118.00815) (xy 249.022301 -117.953713)
			(xy 249.042224 -117.901622) (xy 249.06952 -117.852987) (xy 249.103606 -117.808844) (xy 249.143755 -117.770135)
			(xy 249.189113 -117.737684) (xy 249.238713 -117.712183) (xy 249.291497 -117.694176) (xy 249.34634 -117.684046)
			(xy 249.402074 -117.682009) (xy 249.457511 -117.688109) (xy 249.511468 -117.702215) (xy 249.562797 -117.724027)
			(xy 249.610403 -117.753081) (xy 249.653271 -117.788756) (xy 249.690488 -117.830293) (xy 249.721261 -117.876806)
			(xy 249.744933 -117.927303) (xy 249.761001 -117.98071) (xy 249.76702 -118.021608) (xy 249.885454 -118.021608)
			(xy 249.885912 -117.994237) (xy 249.893729 -117.940057) (xy 249.90922 -117.887554) (xy 249.932064 -117.837807)
			(xy 249.961791 -117.791841) (xy 249.979434 -117.77091) (xy 249.979688 -117.770656) (xy 249.985256 -117.763557)
			(xy 249.991514 -117.74665) (xy 249.99188 -117.737636) (xy 249.99188 -117.67058) (xy 249.991537 -117.661562)
			(xy 249.98528 -117.644645) (xy 249.979688 -117.63756) (xy 249.979434 -117.63756) (xy 249.979434 -117.637306)
			(xy 249.961801 -117.616367) (xy 249.932075 -117.570401) (xy 249.909229 -117.520655) (xy 249.893732 -117.468154)
			(xy 249.885902 -117.413976) (xy 249.885901 -117.359236) (xy 249.893729 -117.305058) (xy 249.909225 -117.252556)
			(xy 249.932069 -117.20281) (xy 249.961794 -117.156843) (xy 249.979434 -117.13591) (xy 249.979688 -117.135656)
			(xy 249.985256 -117.128557) (xy 249.991514 -117.11165) (xy 249.99188 -117.102636) (xy 249.99188 -117.03558)
			(xy 249.991537 -117.026562) (xy 249.98528 -117.009645) (xy 249.979688 -117.00256) (xy 249.979434 -117.00256)
			(xy 249.979434 -117.002306) (xy 249.96179 -116.981378) (xy 249.932077 -116.935405) (xy 249.909242 -116.885656)
			(xy 249.893752 -116.833154) (xy 249.885926 -116.778978) (xy 249.885454 -116.751608) (xy 249.885985 -116.724359)
			(xy 249.89374 -116.670415) (xy 249.909092 -116.618123) (xy 249.931729 -116.568548) (xy 249.961191 -116.5227)
			(xy 249.996878 -116.48151) (xy 250.038063 -116.445819) (xy 250.083908 -116.416351) (xy 250.13348 -116.393708)
			(xy 250.18577 -116.378349) (xy 250.239713 -116.370588) (xy 250.266962 -116.3701) (xy 250.294331 -116.370588)
			(xy 250.34851 -116.378401) (xy 250.401012 -116.393885) (xy 250.45076 -116.416721) (xy 250.496728 -116.446441)
			(xy 250.51766 -116.46408) (xy 250.517914 -116.464334) (xy 250.52499 -116.469936) (xy 250.541915 -116.476172)
			(xy 250.550934 -116.476526) (xy 250.61799 -116.476526) (xy 250.627006 -116.476158) (xy 250.643922 -116.469918)
			(xy 250.65101 -116.464334) (xy 250.65101 -116.46408) (xy 250.651264 -116.46408) (xy 250.672196 -116.446441)
			(xy 250.718169 -116.41673) (xy 250.767917 -116.393894) (xy 250.820417 -116.378403) (xy 250.874593 -116.370574)
			(xy 250.901962 -116.3701) (xy 250.929214 -116.370591) (xy 250.983165 -116.378343) (xy 251.035462 -116.393694)
			(xy 251.085043 -116.416333) (xy 251.130897 -116.445798) (xy 251.17209 -116.481489) (xy 251.207784 -116.522679)
			(xy 251.237253 -116.568531) (xy 251.259895 -116.618109) (xy 251.275251 -116.670406) (xy 251.283007 -116.724356)
			(xy 251.28347 -116.751608) (xy 251.283016 -116.778979) (xy 251.275196 -116.833159) (xy 251.259705 -116.885662)
			(xy 251.23686 -116.935409) (xy 251.207133 -116.981375) (xy 251.18949 -117.002306) (xy 251.189236 -117.00256)
			(xy 251.183652 -117.009648) (xy 251.177406 -117.026564) (xy 251.177044 -117.03558) (xy 251.177044 -117.102636)
			(xy 251.177374 -117.111656) (xy 251.183639 -117.128573) (xy 251.189236 -117.135656) (xy 251.18949 -117.135656)
			(xy 251.18949 -117.13591) (xy 251.207138 -117.156837) (xy 251.236861 -117.202806) (xy 251.259705 -117.252553)
			(xy 251.2752 -117.305056) (xy 251.283027 -117.359235) (xy 251.283026 -117.413977) (xy 251.275197 -117.468156)
			(xy 251.259701 -117.520658) (xy 251.236855 -117.570405) (xy 251.207131 -117.616373) (xy 251.18949 -117.637306)
			(xy 251.189236 -117.63756) (xy 251.183652 -117.644648) (xy 251.177406 -117.661564) (xy 251.177044 -117.67058)
			(xy 251.177044 -117.737636) (xy 251.177374 -117.746656) (xy 251.183639 -117.763573) (xy 251.189236 -117.770656)
			(xy 251.18949 -117.770656) (xy 251.18949 -117.77091) (xy 251.207146 -117.791829) (xy 251.236855 -117.837805)
			(xy 251.259688 -117.887556) (xy 251.275175 -117.94006) (xy 251.282999 -117.994238) (xy 251.28347 -118.021608)
			(xy 251.283052 -118.048863) (xy 251.275293 -118.102817) (xy 251.259934 -118.155118) (xy 251.237288 -118.204701)
			(xy 251.207815 -118.250556) (xy 251.172117 -118.291749) (xy 251.130919 -118.327443) (xy 251.085061 -118.35691)
			(xy 251.035475 -118.37955) (xy 250.983172 -118.394903) (xy 250.929217 -118.402655) (xy 250.901962 -118.403116)
			(xy 250.874592 -118.402634) (xy 250.820413 -118.394823) (xy 250.767909 -118.379339) (xy 250.718162 -118.3565)
			(xy 250.672195 -118.326777) (xy 250.651264 -118.309136) (xy 250.65101 -118.308882) (xy 250.643926 -118.303291)
			(xy 250.627007 -118.297048) (xy 250.61799 -118.29669) (xy 250.550934 -118.29669) (xy 250.541919 -118.297065)
			(xy 250.525002 -118.3033) (xy 250.517914 -118.308882) (xy 250.517914 -118.309136) (xy 250.51766 -118.309136)
			(xy 250.496721 -118.326766) (xy 250.450749 -118.356478) (xy 250.401004 -118.379315) (xy 250.348505 -118.394808)
			(xy 250.294331 -118.40264) (xy 250.266962 -118.403116) (xy 250.23971 -118.402658) (xy 250.185762 -118.394896)
			(xy 250.133467 -118.379537) (xy 250.08389 -118.356892) (xy 250.03804 -118.327422) (xy 249.996851 -118.291728)
			(xy 249.96116 -118.250535) (xy 249.931694 -118.204683) (xy 249.909053 -118.155105) (xy 249.893698 -118.102809)
			(xy 249.88594 -118.04886) (xy 249.885454 -118.021608) (xy 249.76702 -118.021608) (xy 249.769121 -118.035886)
			(xy 249.76963 -118.063772) (xy 249.769121 -118.091658) (xy 249.761001 -118.146834) (xy 249.744933 -118.200241)
			(xy 249.721261 -118.250738) (xy 249.690488 -118.297251) (xy 249.653271 -118.338788) (xy 249.610403 -118.374463)
			(xy 249.562797 -118.403517) (xy 249.511468 -118.425329) (xy 249.457511 -118.439435) (xy 249.402074 -118.445535)
			(xy 249.34634 -118.443498) (xy 249.291497 -118.433368) (xy 249.238713 -118.415361) (xy 249.189113 -118.38986)
			(xy 249.143755 -118.357409) (xy 249.103606 -118.3187) (xy 249.06952 -118.274557) (xy 249.042224 -118.225922)
			(xy 249.022301 -118.173831) (xy 249.010175 -118.119394) (xy 249.006104 -118.063772) (xy 247.367007 -118.063772)
			(xy 247.369843 -118.082858) (xy 247.370346 -118.111016) (xy 247.36986 -118.138267) (xy 247.362104 -118.192215)
			(xy 247.346749 -118.24451) (xy 247.324107 -118.294087) (xy 247.294641 -118.339937) (xy 247.25895 -118.381128)
			(xy 247.217759 -118.416819) (xy 247.171909 -118.446285) (xy 247.122332 -118.468927) (xy 247.070037 -118.484282)
			(xy 247.016089 -118.492038) (xy 246.961587 -118.492038) (xy 246.907639 -118.484282) (xy 246.855344 -118.468927)
			(xy 246.805767 -118.446285) (xy 246.759917 -118.416819) (xy 246.718726 -118.381128) (xy 246.683035 -118.339937)
			(xy 246.653569 -118.294087) (xy 246.630927 -118.24451) (xy 246.615572 -118.192215) (xy 246.607816 -118.138267)
			(xy 246.60733 -118.111016) (xy 246.60779 -118.08446) (xy 246.615156 -118.03186) (xy 246.629747 -117.980791)
			(xy 246.640096 -117.95633) (xy 246.644431 -117.944957) (xy 246.643093 -117.920688) (xy 246.637556 -117.909848)
			(xy 246.596154 -117.838728) (xy 246.58941 -117.828667) (xy 246.569009 -117.815676) (xy 246.557038 -117.813836)
			(xy 246.527564 -117.810453) (xy 246.470096 -117.795736) (xy 246.415599 -117.772298) (xy 246.365389 -117.740703)
			(xy 246.342662 -117.721634) (xy 246.342408 -117.72138) (xy 246.335325 -117.715788) (xy 246.318405 -117.709545)
			(xy 246.309388 -117.709188) (xy 246.242332 -117.709188) (xy 246.233317 -117.709563) (xy 246.2164 -117.715798)
			(xy 246.209312 -117.72138) (xy 246.209312 -117.721634) (xy 246.209058 -117.721634) (xy 246.188119 -117.739265)
			(xy 246.142148 -117.768977) (xy 246.092402 -117.791814) (xy 246.039903 -117.807307) (xy 245.985729 -117.815138)
			(xy 245.95836 -117.815614) (xy 245.931108 -117.815159) (xy 245.87716 -117.807398) (xy 245.824865 -117.792038)
			(xy 245.775288 -117.769392) (xy 245.729438 -117.739922) (xy 245.688248 -117.704228) (xy 245.652557 -117.663035)
			(xy 245.623091 -117.617183) (xy 245.60045 -117.567604) (xy 245.585095 -117.515307) (xy 245.577338 -117.461358)
			(xy 245.576852 -117.434106) (xy 244.63756 -117.434106) (xy 244.63756 -117.484398) (xy 244.638079 -117.495385)
			(xy 244.647146 -117.515397) (xy 244.655086 -117.523006) (xy 244.713252 -117.573044) (xy 244.721824 -117.57982)
			(xy 244.742759 -117.586003) (xy 244.753638 -117.584982) (xy 244.753892 -117.584982) (xy 244.767657 -117.583086)
			(xy 244.79537 -117.581053) (xy 244.809264 -117.580918) (xy 244.83652 -117.581326) (xy 244.890479 -117.58908)
			(xy 244.942785 -117.604434) (xy 244.992373 -117.627076) (xy 245.038234 -117.656545) (xy 245.079434 -117.692241)
			(xy 245.115134 -117.733437) (xy 245.144607 -117.779295) (xy 245.167254 -117.828881) (xy 245.182613 -117.881186)
			(xy 245.190371 -117.935144) (xy 245.190371 -117.989656) (xy 245.182613 -118.043614) (xy 245.167254 -118.095919)
			(xy 245.144607 -118.145505) (xy 245.115134 -118.191363) (xy 245.079434 -118.232559) (xy 245.038234 -118.268255)
			(xy 244.992373 -118.297724) (xy 244.942785 -118.320366) (xy 244.890479 -118.33572) (xy 244.83652 -118.343474)
			(xy 244.809264 -118.343934) (xy 244.791245 -118.343714) (xy 244.75537 -118.340279) (xy 244.737636 -118.337076)
			(xy 244.727984 -118.335298) (xy 244.708934 -118.338854) (xy 244.641878 -118.382034) (xy 244.634039 -118.387468)
			(xy 244.622827 -118.402884) (xy 244.620034 -118.412006) (xy 244.620034 -118.412768) (xy 244.611952 -118.44343)
			(xy 244.590063 -118.502945) (xy 244.561873 -118.559747) (xy 244.52771 -118.61317) (xy 244.487974 -118.662589)
			(xy 244.465856 -118.68531) (xy 243.365274 -119.785892) (xy 243.34342 -119.807163) (xy 243.296042 -119.845569)
			(xy 243.244928 -119.87884) (xy 243.190632 -119.906616) (xy 243.162328 -119.917972) (xy 243.152331 -119.922426)
			(xy 243.137074 -119.938094) (xy 243.132864 -119.948198) (xy 243.103146 -120.031002) (xy 243.104924 -120.052592)
			(xy 243.110258 -120.062244) (xy 243.121808 -120.083651) (xy 243.135565 -120.11787) (xy 243.411246 -120.11787)
			(xy 243.415317 -120.062248) (xy 243.427443 -120.007811) (xy 243.447366 -119.95572) (xy 243.474662 -119.907085)
			(xy 243.508748 -119.862942) (xy 243.548897 -119.824233) (xy 243.594255 -119.791782) (xy 243.643855 -119.766281)
			(xy 243.696639 -119.748274) (xy 243.751482 -119.738144) (xy 243.807216 -119.736107) (xy 243.862653 -119.742207)
			(xy 243.91661 -119.756313) (xy 243.967939 -119.778125) (xy 244.015545 -119.807179) (xy 244.058413 -119.842854)
			(xy 244.09563 -119.884391) (xy 244.126403 -119.930904) (xy 244.150075 -119.981401) (xy 244.166143 -120.034808)
			(xy 244.174263 -120.089984) (xy 244.174772 -120.11787) (xy 244.427246 -120.11787) (xy 244.431317 -120.062248)
			(xy 244.443443 -120.007811) (xy 244.463366 -119.95572) (xy 244.490662 -119.907085) (xy 244.524748 -119.862942)
			(xy 244.564897 -119.824233) (xy 244.610255 -119.791782) (xy 244.659855 -119.766281) (xy 244.712639 -119.748274)
			(xy 244.767482 -119.738144) (xy 244.823216 -119.736107) (xy 244.878653 -119.742207) (xy 244.93261 -119.756313)
			(xy 244.983939 -119.778125) (xy 245.031545 -119.807179) (xy 245.074413 -119.842854) (xy 245.11163 -119.884391)
			(xy 245.142403 -119.930904) (xy 245.166075 -119.981401) (xy 245.182143 -120.034808) (xy 245.190263 -120.089984)
			(xy 245.190772 -120.11787) (xy 245.190263 -120.145756) (xy 245.189134 -120.15343) (xy 247.62282 -120.15343)
			(xy 247.626891 -120.097808) (xy 247.639017 -120.043371) (xy 247.65894 -119.99128) (xy 247.686236 -119.942645)
			(xy 247.720322 -119.898502) (xy 247.760471 -119.859793) (xy 247.805829 -119.827342) (xy 247.855429 -119.801841)
			(xy 247.908213 -119.783834) (xy 247.963056 -119.773704) (xy 248.01879 -119.771667) (xy 248.074227 -119.777767)
			(xy 248.128184 -119.791873) (xy 248.179513 -119.813685) (xy 248.227119 -119.842739) (xy 248.269987 -119.878414)
			(xy 248.307204 -119.919951) (xy 248.337977 -119.966464) (xy 248.361649 -120.016961) (xy 248.377717 -120.070368)
			(xy 248.385837 -120.125544) (xy 248.386346 -120.15343) (xy 248.385837 -120.181316) (xy 248.377717 -120.236492)
			(xy 248.361649 -120.289899) (xy 248.337977 -120.340396) (xy 248.307204 -120.386909) (xy 248.269987 -120.428446)
			(xy 248.227119 -120.464121) (xy 248.179513 -120.493175) (xy 248.128184 -120.514987) (xy 248.074227 -120.529093)
			(xy 248.01879 -120.535193) (xy 247.963056 -120.533156) (xy 247.908213 -120.523026) (xy 247.855429 -120.505019)
			(xy 247.805829 -120.479518) (xy 247.760471 -120.447067) (xy 247.720322 -120.408358) (xy 247.686236 -120.364215)
			(xy 247.65894 -120.31558) (xy 247.639017 -120.263489) (xy 247.626891 -120.209052) (xy 247.62282 -120.15343)
			(xy 245.189134 -120.15343) (xy 245.182143 -120.200932) (xy 245.166075 -120.254339) (xy 245.142403 -120.304836)
			(xy 245.11163 -120.351349) (xy 245.074413 -120.392886) (xy 245.031545 -120.428561) (xy 244.983939 -120.457615)
			(xy 244.93261 -120.479427) (xy 244.878653 -120.493533) (xy 244.823216 -120.499633) (xy 244.767482 -120.497596)
			(xy 244.712639 -120.487466) (xy 244.659855 -120.469459) (xy 244.610255 -120.443958) (xy 244.564897 -120.411507)
			(xy 244.524748 -120.372798) (xy 244.490662 -120.328655) (xy 244.463366 -120.28002) (xy 244.443443 -120.227929)
			(xy 244.431317 -120.173492) (xy 244.427246 -120.11787) (xy 244.174772 -120.11787) (xy 244.174263 -120.145756)
			(xy 244.166143 -120.200932) (xy 244.150075 -120.254339) (xy 244.126403 -120.304836) (xy 244.09563 -120.351349)
			(xy 244.058413 -120.392886) (xy 244.015545 -120.428561) (xy 243.967939 -120.457615) (xy 243.91661 -120.479427)
			(xy 243.862653 -120.493533) (xy 243.807216 -120.499633) (xy 243.751482 -120.497596) (xy 243.696639 -120.487466)
			(xy 243.643855 -120.469459) (xy 243.594255 -120.443958) (xy 243.548897 -120.411507) (xy 243.508748 -120.372798)
			(xy 243.474662 -120.328655) (xy 243.447366 -120.28002) (xy 243.427443 -120.227929) (xy 243.415317 -120.173492)
			(xy 243.411246 -120.11787) (xy 243.135565 -120.11787) (xy 243.139952 -120.128783) (xy 243.152213 -120.175856)
			(xy 243.158392 -120.224105) (xy 243.158772 -120.248426) (xy 243.158286 -120.275677) (xy 243.15053 -120.329625)
			(xy 243.135175 -120.38192) (xy 243.112533 -120.431497) (xy 243.083067 -120.477347) (xy 243.047376 -120.518538)
			(xy 243.006185 -120.554229) (xy 242.960335 -120.583695) (xy 242.910758 -120.606337) (xy 242.858463 -120.621692)
			(xy 242.804515 -120.629448) (xy 242.750013 -120.629448) (xy 242.696065 -120.621692) (xy 242.64377 -120.606337)
			(xy 242.594193 -120.583695) (xy 242.548343 -120.554229) (xy 242.507152 -120.518538) (xy 242.471461 -120.477347)
			(xy 242.441995 -120.431497) (xy 242.419353 -120.38192) (xy 242.403998 -120.329625) (xy 242.396242 -120.275677)
			(xy 242.395756 -120.248426) (xy 242.397534 -120.21185) (xy 242.398027 -120.201421) (xy 242.391596 -120.181582)
			(xy 242.377803 -120.165938) (xy 242.368578 -120.16105) (xy 242.281964 -120.120156) (xy 242.272296 -120.116173)
			(xy 242.251421 -120.115525) (xy 242.23202 -120.123258) (xy 242.224306 -120.130316) (xy 240.783872 -121.57075)
			(xy 245.81993 -121.57075) (xy 245.820355 -121.544434) (xy 245.827597 -121.492304) (xy 245.841924 -121.44166)
			(xy 245.863064 -121.393461) (xy 245.890618 -121.348618) (xy 245.924065 -121.307981) (xy 245.94312 -121.289826)
			(xy 245.950515 -121.282299) (xy 245.959043 -121.263023) (xy 245.95963 -121.252488) (xy 245.95963 -121.177812)
			(xy 245.959099 -121.167263) (xy 245.950564 -121.147968) (xy 245.94312 -121.140474) (xy 245.924063 -121.12232)
			(xy 245.890605 -121.081691) (xy 245.863046 -121.03685) (xy 245.841907 -120.988649) (xy 245.827591 -120.938001)
			(xy 245.820368 -120.885866) (xy 245.81993 -120.85955) (xy 245.820416 -120.832299) (xy 245.828172 -120.778351)
			(xy 245.843527 -120.726056) (xy 245.866169 -120.676479) (xy 245.895635 -120.630629) (xy 245.931326 -120.589438)
			(xy 245.972517 -120.553747) (xy 246.018367 -120.524281) (xy 246.067944 -120.501639) (xy 246.120239 -120.486284)
			(xy 246.174187 -120.478528) (xy 246.228689 -120.478528) (xy 246.282637 -120.486284) (xy 246.334932 -120.501639)
			(xy 246.384509 -120.524281) (xy 246.430359 -120.553747) (xy 246.47155 -120.589438) (xy 246.507241 -120.630629)
			(xy 246.536707 -120.676479) (xy 246.559349 -120.726056) (xy 246.574704 -120.778351) (xy 246.58246 -120.832299)
			(xy 246.582946 -120.85955) (xy 246.582529 -120.885866) (xy 246.575286 -120.937997) (xy 246.560959 -120.988642)
			(xy 246.539817 -121.036841) (xy 246.512261 -121.081683) (xy 246.478812 -121.12232) (xy 246.459756 -121.140474)
			(xy 246.452372 -121.148011) (xy 246.443836 -121.167279) (xy 246.443246 -121.177812) (xy 246.443246 -121.252488)
			(xy 246.443754 -121.26304) (xy 246.452303 -121.282337) (xy 246.459756 -121.289826) (xy 246.478828 -121.307965)
			(xy 246.512281 -121.348599) (xy 246.539837 -121.393444) (xy 246.560972 -121.441647) (xy 246.575286 -121.492297)
			(xy 246.582509 -121.544433) (xy 246.582946 -121.57075) (xy 246.58246 -121.598001) (xy 246.574704 -121.651949)
			(xy 246.559349 -121.704244) (xy 246.536707 -121.753821) (xy 246.507241 -121.799671) (xy 246.47155 -121.840862)
			(xy 246.430359 -121.876553) (xy 246.384509 -121.906019) (xy 246.334932 -121.928661) (xy 246.282637 -121.944016)
			(xy 246.228689 -121.951772) (xy 246.174187 -121.951772) (xy 246.120239 -121.944016) (xy 246.067944 -121.928661)
			(xy 246.018367 -121.906019) (xy 245.972517 -121.876553) (xy 245.931326 -121.840862) (xy 245.895635 -121.799671)
			(xy 245.866169 -121.753821) (xy 245.843527 -121.704244) (xy 245.828172 -121.651949) (xy 245.820416 -121.598001)
			(xy 245.81993 -121.57075) (xy 240.783872 -121.57075) (xy 240.226342 -122.12828) (xy 240.219524 -122.135698)
			(xy 240.21179 -122.154283) (xy 240.211356 -122.164348) (xy 240.211356 -122.292618) (xy 241.98021 -122.292618)
			(xy 241.984281 -122.236996) (xy 241.996407 -122.182559) (xy 242.01633 -122.130468) (xy 242.043626 -122.081833)
			(xy 242.077712 -122.03769) (xy 242.117861 -121.998981) (xy 242.163219 -121.96653) (xy 242.212819 -121.941029)
			(xy 242.265603 -121.923022) (xy 242.320446 -121.912892) (xy 242.37618 -121.910855) (xy 242.431617 -121.916955)
			(xy 242.485574 -121.931061) (xy 242.536903 -121.952873) (xy 242.584509 -121.981927) (xy 242.627377 -122.017602)
			(xy 242.664594 -122.059139) (xy 242.695367 -122.105652) (xy 242.719039 -122.156149) (xy 242.735107 -122.209556)
			(xy 242.743227 -122.264732) (xy 242.743736 -122.292618) (xy 242.743227 -122.320504) (xy 242.735107 -122.37568)
			(xy 242.719039 -122.429087) (xy 242.699902 -122.46991) (xy 243.136926 -122.46991) (xy 243.140997 -122.414288)
			(xy 243.153123 -122.359851) (xy 243.173046 -122.30776) (xy 243.200342 -122.259125) (xy 243.234428 -122.214982)
			(xy 243.274577 -122.176273) (xy 243.319935 -122.143822) (xy 243.369535 -122.118321) (xy 243.422319 -122.100314)
			(xy 243.477162 -122.090184) (xy 243.532896 -122.088147) (xy 243.588333 -122.094247) (xy 243.64229 -122.108353)
			(xy 243.693619 -122.130165) (xy 243.741225 -122.159219) (xy 243.784093 -122.194894) (xy 243.82131 -122.236431)
			(xy 243.852083 -122.282944) (xy 243.875755 -122.333441) (xy 243.891823 -122.386848) (xy 243.899943 -122.442024)
			(xy 243.900452 -122.46991) (xy 243.899943 -122.497796) (xy 243.891823 -122.552972) (xy 243.875755 -122.606379)
			(xy 243.852083 -122.656876) (xy 243.82131 -122.703389) (xy 243.784093 -122.744926) (xy 243.741225 -122.780601)
			(xy 243.693619 -122.809655) (xy 243.64229 -122.831467) (xy 243.588333 -122.845573) (xy 243.532896 -122.851673)
			(xy 243.477162 -122.849636) (xy 243.422319 -122.839506) (xy 243.369535 -122.821499) (xy 243.319935 -122.795998)
			(xy 243.274577 -122.763547) (xy 243.234428 -122.724838) (xy 243.200342 -122.680695) (xy 243.173046 -122.63206)
			(xy 243.153123 -122.579969) (xy 243.140997 -122.525532) (xy 243.136926 -122.46991) (xy 242.699902 -122.46991)
			(xy 242.695367 -122.479584) (xy 242.664594 -122.526097) (xy 242.627377 -122.567634) (xy 242.584509 -122.603309)
			(xy 242.536903 -122.632363) (xy 242.485574 -122.654175) (xy 242.431617 -122.668281) (xy 242.37618 -122.674381)
			(xy 242.320446 -122.672344) (xy 242.265603 -122.662214) (xy 242.212819 -122.644207) (xy 242.163219 -122.618706)
			(xy 242.117861 -122.586255) (xy 242.077712 -122.547546) (xy 242.043626 -122.503403) (xy 242.01633 -122.454768)
			(xy 241.996407 -122.402677) (xy 241.984281 -122.34824) (xy 241.98021 -122.292618) (xy 240.211356 -122.292618)
			(xy 240.211356 -123.249752) (xy 244.109967 -123.249752) (xy 244.109967 -123.195248) (xy 244.117724 -123.141299)
			(xy 244.13308 -123.089002) (xy 244.155722 -123.039423) (xy 244.185189 -122.993572) (xy 244.220882 -122.95238)
			(xy 244.262073 -122.916688) (xy 244.307925 -122.887221) (xy 244.357504 -122.864579) (xy 244.4098 -122.849224)
			(xy 244.46375 -122.841467) (xy 244.491002 -122.841004) (xy 244.518032 -122.841498) (xy 244.571549 -122.849136)
			(xy 244.623451 -122.864259) (xy 244.672695 -122.886564) (xy 244.718294 -122.915602) (xy 244.759332 -122.950791)
			(xy 244.777514 -122.970798) (xy 244.777768 -122.971052) (xy 244.785208 -122.978703) (xy 244.804695 -122.987369)
			(xy 244.81536 -122.987816) (xy 244.90299 -122.988324) (xy 244.922548 -122.979688) (xy 244.929914 -122.971306)
			(xy 244.948074 -122.951582) (xy 244.988975 -122.916918) (xy 245.034331 -122.88833) (xy 245.083246 -122.866381)
			(xy 245.134755 -122.851505) (xy 245.187841 -122.843997) (xy 245.214648 -122.843544) (xy 245.242018 -122.84403)
			(xy 245.296196 -122.851841) (xy 245.3487 -122.867325) (xy 245.398447 -122.890163) (xy 245.444414 -122.919884)
			(xy 245.465346 -122.937524) (xy 245.4656 -122.937778) (xy 245.472676 -122.94338) (xy 245.489601 -122.949615)
			(xy 245.49862 -122.94997) (xy 245.565676 -122.94997) (xy 245.574692 -122.949608) (xy 245.59161 -122.943364)
			(xy 245.598696 -122.937778) (xy 245.598696 -122.937524) (xy 245.59895 -122.937524) (xy 245.619883 -122.919883)
			(xy 245.665851 -122.890159) (xy 245.715597 -122.867313) (xy 245.768099 -122.851817) (xy 245.822277 -122.843988)
			(xy 245.877019 -122.843988) (xy 245.931197 -122.851817) (xy 245.983699 -122.867313) (xy 246.033445 -122.890159)
			(xy 246.079413 -122.919883) (xy 246.100346 -122.937524) (xy 246.1006 -122.937778) (xy 246.107676 -122.94338)
			(xy 246.124601 -122.949615) (xy 246.13362 -122.94997) (xy 246.200676 -122.94997) (xy 246.209692 -122.949608)
			(xy 246.22661 -122.943364) (xy 246.233696 -122.937778) (xy 246.234204 -122.937524) (xy 246.246938 -122.926579)
			(xy 246.274029 -122.906738) (xy 246.288306 -122.8979) (xy 246.297196 -122.892566) (xy 246.309388 -122.875548)
			(xy 246.329708 -122.78233) (xy 246.32539 -122.761756) (xy 246.319548 -122.75312) (xy 246.303548 -122.729056)
			(xy 246.278207 -122.677124) (xy 246.260982 -122.621966) (xy 246.252266 -122.564842) (xy 246.25173 -122.53595)
			(xy 246.252216 -122.508699) (xy 246.259972 -122.454751) (xy 246.275327 -122.402456) (xy 246.297969 -122.352879)
			(xy 246.327435 -122.307029) (xy 246.363126 -122.265838) (xy 246.404317 -122.230147) (xy 246.450167 -122.200681)
			(xy 246.499744 -122.178039) (xy 246.552039 -122.162684) (xy 246.605987 -122.154928) (xy 246.660489 -122.154928)
			(xy 246.714437 -122.162684) (xy 246.766732 -122.178039) (xy 246.816309 -122.200681) (xy 246.862159 -122.230147)
			(xy 246.90335 -122.265838) (xy 246.939041 -122.307029) (xy 246.968507 -122.352879) (xy 246.991149 -122.402456)
			(xy 247.006504 -122.454751) (xy 247.01426 -122.508699) (xy 247.014746 -122.53595) (xy 247.014198 -122.56404)
			(xy 247.005979 -122.619614) (xy 246.989696 -122.673381) (xy 246.965702 -122.724178) (xy 246.934515 -122.770905)
			(xy 246.896812 -122.812552) (xy 246.853407 -122.848217) (xy 246.82958 -122.863102) (xy 246.82069 -122.868436)
			(xy 246.808498 -122.885454) (xy 246.788178 -122.978672) (xy 246.792496 -122.999246) (xy 246.798338 -123.007882)
			(xy 246.814337 -123.031946) (xy 246.839679 -123.083878) (xy 246.856905 -123.139036) (xy 246.865621 -123.19616)
			(xy 246.866156 -123.225052) (xy 246.865577 -123.2523) (xy 246.857829 -123.306242) (xy 246.842482 -123.358532)
			(xy 246.81985 -123.408106) (xy 246.790393 -123.453954) (xy 246.754711 -123.495143) (xy 246.713531 -123.530836)
			(xy 246.66769 -123.560304) (xy 246.618122 -123.582948) (xy 246.565836 -123.598308) (xy 246.511896 -123.60607)
			(xy 246.484648 -123.60656) (xy 246.457278 -123.606076) (xy 246.4031 -123.598264) (xy 246.350596 -123.582779)
			(xy 246.300849 -123.559942) (xy 246.254882 -123.53022) (xy 246.23395 -123.51258) (xy 246.233696 -123.512326)
			(xy 246.226621 -123.506723) (xy 246.209695 -123.500488) (xy 246.200676 -123.500134) (xy 246.13362 -123.500134)
			(xy 246.124603 -123.500493) (xy 246.107686 -123.506739) (xy 246.1006 -123.512326) (xy 246.1006 -123.51258)
			(xy 246.100346 -123.51258) (xy 246.079413 -123.530221) (xy 246.033445 -123.559945) (xy 245.983699 -123.582791)
			(xy 245.931197 -123.598287) (xy 245.877019 -123.606116) (xy 245.822277 -123.606116) (xy 245.768099 -123.598287)
			(xy 245.715597 -123.582791) (xy 245.665851 -123.559945) (xy 245.619883 -123.530221) (xy 245.59895 -123.51258)
			(xy 245.598696 -123.512326) (xy 245.591621 -123.506723) (xy 245.574695 -123.500488) (xy 245.565676 -123.500134)
			(xy 245.49862 -123.500134) (xy 245.489603 -123.500493) (xy 245.472686 -123.506739) (xy 245.4656 -123.512326)
			(xy 245.4656 -123.51258) (xy 245.465346 -123.51258) (xy 245.444405 -123.530208) (xy 245.398435 -123.559922)
			(xy 245.34869 -123.582761) (xy 245.296191 -123.598254) (xy 245.242017 -123.606085) (xy 245.214648 -123.60656)
			(xy 245.187618 -123.606078) (xy 245.134101 -123.598435) (xy 245.0822 -123.583308) (xy 245.032957 -123.561001)
			(xy 244.987358 -123.531961) (xy 244.946319 -123.496772) (xy 244.928136 -123.476766) (xy 244.927882 -123.476512)
			(xy 244.920414 -123.468893) (xy 244.900949 -123.460207) (xy 244.89029 -123.459748) (xy 244.80266 -123.45924)
			(xy 244.783102 -123.467876) (xy 244.775736 -123.476258) (xy 244.757564 -123.49597) (xy 244.716664 -123.530633)
			(xy 244.67131 -123.559221) (xy 244.622398 -123.581172) (xy 244.570891 -123.59605) (xy 244.517808 -123.603564)
			(xy 244.491002 -123.60402) (xy 244.46375 -123.603533) (xy 244.4098 -123.595776) (xy 244.357504 -123.580421)
			(xy 244.307925 -123.557779) (xy 244.262073 -123.528312) (xy 244.220882 -123.49262) (xy 244.185189 -123.451428)
			(xy 244.155722 -123.405577) (xy 244.13308 -123.355998) (xy 244.117724 -123.303701) (xy 244.109967 -123.249752)
			(xy 240.211356 -123.249752) (xy 240.211356 -124.963428) (xy 240.873024 -124.963428) (xy 240.877095 -124.907806)
			(xy 240.889221 -124.853369) (xy 240.909144 -124.801278) (xy 240.93644 -124.752643) (xy 240.970526 -124.7085)
			(xy 241.010675 -124.669791) (xy 241.056033 -124.63734) (xy 241.105633 -124.611839) (xy 241.158417 -124.593832)
			(xy 241.21326 -124.583702) (xy 241.268994 -124.581665) (xy 241.324431 -124.587765) (xy 241.378388 -124.601871)
			(xy 241.429717 -124.623683) (xy 241.477323 -124.652737) (xy 241.520191 -124.688412) (xy 241.557408 -124.729949)
			(xy 241.588181 -124.776462) (xy 241.611853 -124.826959) (xy 241.627921 -124.880366) (xy 241.636041 -124.935542)
			(xy 241.63655 -124.963428) (xy 241.636041 -124.991314) (xy 241.627921 -125.04649) (xy 241.624483 -125.057916)
			(xy 242.981478 -125.057916) (xy 242.985549 -125.002294) (xy 242.997675 -124.947857) (xy 243.017598 -124.895766)
			(xy 243.044894 -124.847131) (xy 243.07898 -124.802988) (xy 243.119129 -124.764279) (xy 243.164487 -124.731828)
			(xy 243.214087 -124.706327) (xy 243.266871 -124.68832) (xy 243.321714 -124.67819) (xy 243.377448 -124.676153)
			(xy 243.432885 -124.682253) (xy 243.486842 -124.696359) (xy 243.538171 -124.718171) (xy 243.585777 -124.747225)
			(xy 243.628645 -124.7829) (xy 243.665862 -124.824437) (xy 243.696635 -124.87095) (xy 243.720307 -124.921447)
			(xy 243.736375 -124.974854) (xy 243.744495 -125.03003) (xy 243.745004 -125.057916) (xy 243.744495 -125.085802)
			(xy 243.736375 -125.140978) (xy 243.720307 -125.194385) (xy 243.696635 -125.244882) (xy 243.665862 -125.291395)
			(xy 243.628645 -125.332932) (xy 243.585777 -125.368607) (xy 243.538171 -125.397661) (xy 243.524769 -125.403356)
			(xy 247.744234 -125.403356) (xy 247.744725 -125.375987) (xy 247.752535 -125.321808) (xy 247.768018 -125.269305)
			(xy 247.790855 -125.219558) (xy 247.820575 -125.17359) (xy 247.838214 -125.152658) (xy 247.838468 -125.152404)
			(xy 247.844067 -125.145326) (xy 247.850304 -125.128402) (xy 247.85066 -125.119384) (xy 247.85066 -125.052328)
			(xy 247.850298 -125.043311) (xy 247.844055 -125.026394) (xy 247.838468 -125.019308) (xy 247.838214 -125.019308)
			(xy 247.838214 -125.019054) (xy 247.820589 -124.998111) (xy 247.790875 -124.952141) (xy 247.768036 -124.902397)
			(xy 247.752541 -124.849898) (xy 247.74471 -124.795724) (xy 247.744234 -124.768356) (xy 247.74472 -124.741105)
			(xy 247.752476 -124.687157) (xy 247.767831 -124.634862) (xy 247.790473 -124.585285) (xy 247.819939 -124.539435)
			(xy 247.85563 -124.498244) (xy 247.896821 -124.462553) (xy 247.942671 -124.433087) (xy 247.992248 -124.410445)
			(xy 248.044543 -124.39509) (xy 248.098491 -124.387334) (xy 248.152993 -124.387334) (xy 248.206941 -124.39509)
			(xy 248.259236 -124.410445) (xy 248.308813 -124.433087) (xy 248.354663 -124.462553) (xy 248.395854 -124.498244)
			(xy 248.431545 -124.539435) (xy 248.461011 -124.585285) (xy 248.483653 -124.634862) (xy 248.499008 -124.687157)
			(xy 248.506764 -124.741105) (xy 248.50725 -124.768356) (xy 248.50677 -124.795726) (xy 248.498958 -124.849905)
			(xy 248.483472 -124.902408) (xy 248.460633 -124.952155) (xy 248.430911 -124.998122) (xy 248.41327 -125.019054)
			(xy 248.413016 -125.019308) (xy 248.407422 -125.026389) (xy 248.401179 -125.04331) (xy 248.400824 -125.052328)
			(xy 248.400824 -125.119384) (xy 248.401184 -125.128401) (xy 248.407429 -125.145318) (xy 248.413016 -125.152404)
			(xy 248.41327 -125.152404) (xy 248.41327 -125.152658) (xy 248.430898 -125.173599) (xy 248.460613 -125.219569)
			(xy 248.483451 -125.269314) (xy 248.498945 -125.321813) (xy 248.506775 -125.375987) (xy 248.50725 -125.403356)
			(xy 248.506764 -125.430607) (xy 248.499008 -125.484555) (xy 248.483653 -125.53685) (xy 248.461011 -125.586427)
			(xy 248.431545 -125.632277) (xy 248.395854 -125.673468) (xy 248.354663 -125.709159) (xy 248.308813 -125.738625)
			(xy 248.259236 -125.761267) (xy 248.206941 -125.776622) (xy 248.152993 -125.784378) (xy 248.098491 -125.784378)
			(xy 248.044543 -125.776622) (xy 247.992248 -125.761267) (xy 247.942671 -125.738625) (xy 247.896821 -125.709159)
			(xy 247.85563 -125.673468) (xy 247.819939 -125.632277) (xy 247.790473 -125.586427) (xy 247.767831 -125.53685)
			(xy 247.752476 -125.484555) (xy 247.74472 -125.430607) (xy 247.744234 -125.403356) (xy 243.524769 -125.403356)
			(xy 243.486842 -125.419473) (xy 243.432885 -125.433579) (xy 243.377448 -125.439679) (xy 243.321714 -125.437642)
			(xy 243.266871 -125.427512) (xy 243.214087 -125.409505) (xy 243.164487 -125.384004) (xy 243.119129 -125.351553)
			(xy 243.07898 -125.312844) (xy 243.044894 -125.268701) (xy 243.017598 -125.220066) (xy 242.997675 -125.167975)
			(xy 242.985549 -125.113538) (xy 242.981478 -125.057916) (xy 241.624483 -125.057916) (xy 241.611853 -125.099897)
			(xy 241.588181 -125.150394) (xy 241.557408 -125.196907) (xy 241.520191 -125.238444) (xy 241.477323 -125.274119)
			(xy 241.429717 -125.303173) (xy 241.378388 -125.324985) (xy 241.324431 -125.339091) (xy 241.268994 -125.345191)
			(xy 241.21326 -125.343154) (xy 241.158417 -125.333024) (xy 241.105633 -125.315017) (xy 241.056033 -125.289516)
			(xy 241.010675 -125.257065) (xy 240.970526 -125.218356) (xy 240.93644 -125.174213) (xy 240.909144 -125.125578)
			(xy 240.889221 -125.073487) (xy 240.877095 -125.01905) (xy 240.873024 -124.963428) (xy 240.211356 -124.963428)
			(xy 240.211356 -125.979428) (xy 240.873024 -125.979428) (xy 240.877095 -125.923806) (xy 240.889221 -125.869369)
			(xy 240.909144 -125.817278) (xy 240.93644 -125.768643) (xy 240.970526 -125.7245) (xy 241.010675 -125.685791)
			(xy 241.056033 -125.65334) (xy 241.105633 -125.627839) (xy 241.158417 -125.609832) (xy 241.21326 -125.599702)
			(xy 241.268994 -125.597665) (xy 241.324431 -125.603765) (xy 241.378388 -125.617871) (xy 241.429717 -125.639683)
			(xy 241.477323 -125.668737) (xy 241.520191 -125.704412) (xy 241.557408 -125.745949) (xy 241.588181 -125.792462)
			(xy 241.611853 -125.842959) (xy 241.627921 -125.896366) (xy 241.636041 -125.951542) (xy 241.63655 -125.979428)
			(xy 241.636041 -126.007314) (xy 241.627921 -126.06249) (xy 241.614396 -126.107444) (xy 243.356382 -126.107444)
			(xy 243.360453 -126.051822) (xy 243.372579 -125.997385) (xy 243.392502 -125.945294) (xy 243.419798 -125.896659)
			(xy 243.453884 -125.852516) (xy 243.494033 -125.813807) (xy 243.539391 -125.781356) (xy 243.588991 -125.755855)
			(xy 243.641775 -125.737848) (xy 243.696618 -125.727718) (xy 243.752352 -125.725681) (xy 243.807789 -125.731781)
			(xy 243.861746 -125.745887) (xy 243.913075 -125.767699) (xy 243.960681 -125.796753) (xy 244.003549 -125.832428)
			(xy 244.022607 -125.853698) (xy 248.684796 -125.853698) (xy 248.685262 -125.826328) (xy 248.69308 -125.772149)
			(xy 248.708569 -125.719646) (xy 248.731411 -125.669899) (xy 248.761135 -125.623932) (xy 248.778776 -125.603)
			(xy 248.77903 -125.602746) (xy 248.784607 -125.595653) (xy 248.790858 -125.578741) (xy 248.791222 -125.569726)
			(xy 248.791222 -125.50267) (xy 248.790875 -125.493652) (xy 248.78462 -125.476736) (xy 248.77903 -125.46965)
			(xy 248.778776 -125.46965) (xy 248.778776 -125.469396) (xy 248.761118 -125.448479) (xy 248.73141 -125.402502)
			(xy 248.708578 -125.35275) (xy 248.693091 -125.300247) (xy 248.685268 -125.246068) (xy 248.684796 -125.218698)
			(xy 248.685282 -125.191447) (xy 248.693038 -125.137499) (xy 248.708393 -125.085204) (xy 248.731035 -125.035627)
			(xy 248.760501 -124.989777) (xy 248.796192 -124.948586) (xy 248.837383 -124.912895) (xy 248.883233 -124.883429)
			(xy 248.93281 -124.860787) (xy 248.985105 -124.845432) (xy 249.039053 -124.837676) (xy 249.093555 -124.837676)
			(xy 249.147503 -124.845432) (xy 249.199798 -124.860787) (xy 249.249375 -124.883429) (xy 249.295225 -124.912895)
			(xy 249.336416 -124.948586) (xy 249.372107 -124.989777) (xy 249.401573 -125.035627) (xy 249.424215 -125.085204)
			(xy 249.43957 -125.137499) (xy 249.447326 -125.191447) (xy 249.447812 -125.218698) (xy 249.447342 -125.246068)
			(xy 249.439525 -125.300247) (xy 249.424036 -125.35275) (xy 249.401196 -125.402497) (xy 249.371472 -125.448464)
			(xy 249.353832 -125.469396) (xy 249.353578 -125.46965) (xy 249.348004 -125.476745) (xy 249.34175 -125.493655)
			(xy 249.341386 -125.50267) (xy 249.341386 -125.569726) (xy 249.341734 -125.578744) (xy 249.347988 -125.59566)
			(xy 249.353578 -125.602746) (xy 249.353832 -125.602746) (xy 249.353832 -125.603) (xy 249.37149 -125.623917)
			(xy 249.401198 -125.669895) (xy 249.424029 -125.719646) (xy 249.439516 -125.77215) (xy 249.44734 -125.826328)
			(xy 249.447812 -125.853698) (xy 249.447326 -125.880949) (xy 249.43957 -125.934897) (xy 249.424215 -125.987192)
			(xy 249.401573 -126.036769) (xy 249.372107 -126.082619) (xy 249.336416 -126.12381) (xy 249.295225 -126.159501)
			(xy 249.249375 -126.188967) (xy 249.199798 -126.211609) (xy 249.147503 -126.226964) (xy 249.093555 -126.23472)
			(xy 249.039053 -126.23472) (xy 248.985105 -126.226964) (xy 248.93281 -126.211609) (xy 248.883233 -126.188967)
			(xy 248.837383 -126.159501) (xy 248.796192 -126.12381) (xy 248.760501 -126.082619) (xy 248.731035 -126.036769)
			(xy 248.708393 -125.987192) (xy 248.693038 -125.934897) (xy 248.685282 -125.880949) (xy 248.684796 -125.853698)
			(xy 244.022607 -125.853698) (xy 244.040766 -125.873965) (xy 244.071539 -125.920478) (xy 244.095211 -125.970975)
			(xy 244.111279 -126.024382) (xy 244.119399 -126.079558) (xy 244.119908 -126.107444) (xy 244.119399 -126.13533)
			(xy 244.111279 -126.190506) (xy 244.095211 -126.243913) (xy 244.071539 -126.29441) (xy 244.040766 -126.340923)
			(xy 244.003549 -126.38246) (xy 243.960681 -126.418135) (xy 243.913075 -126.447189) (xy 243.861746 -126.469001)
			(xy 243.807789 -126.483107) (xy 243.752352 -126.489207) (xy 243.696618 -126.48717) (xy 243.641775 -126.47704)
			(xy 243.588991 -126.459033) (xy 243.539391 -126.433532) (xy 243.494033 -126.401081) (xy 243.453884 -126.362372)
			(xy 243.419798 -126.318229) (xy 243.392502 -126.269594) (xy 243.372579 -126.217503) (xy 243.360453 -126.163066)
			(xy 243.356382 -126.107444) (xy 241.614396 -126.107444) (xy 241.611853 -126.115897) (xy 241.588181 -126.166394)
			(xy 241.557408 -126.212907) (xy 241.520191 -126.254444) (xy 241.477323 -126.290119) (xy 241.429717 -126.319173)
			(xy 241.378388 -126.340985) (xy 241.324431 -126.355091) (xy 241.268994 -126.361191) (xy 241.21326 -126.359154)
			(xy 241.158417 -126.349024) (xy 241.105633 -126.331017) (xy 241.056033 -126.305516) (xy 241.010675 -126.273065)
			(xy 240.970526 -126.234356) (xy 240.93644 -126.190213) (xy 240.909144 -126.141578) (xy 240.889221 -126.089487)
			(xy 240.877095 -126.03505) (xy 240.873024 -125.979428) (xy 240.211356 -125.979428) (xy 240.211356 -126.530354)
			(xy 249.893328 -126.530354) (xy 249.893869 -126.50269) (xy 249.901862 -126.447941) (xy 249.917672 -126.39492)
			(xy 249.94097 -126.344735) (xy 249.971267 -126.298439) (xy 250.007929 -126.257001) (xy 250.050188 -126.221287)
			(xy 250.073414 -126.20625) (xy 250.083065 -126.199582) (xy 250.095524 -126.179744) (xy 250.09729 -126.16815)
			(xy 250.105164 -126.08814) (xy 250.105759 -126.076503) (xy 250.097704 -126.054668) (xy 250.08967 -126.04623)
			(xy 250.089416 -126.045976) (xy 250.070844 -126.027886) (xy 250.038264 -125.987556) (xy 250.011449 -125.943184)
			(xy 249.990895 -125.895587) (xy 249.97698 -125.845644) (xy 249.969961 -125.794277) (xy 249.969528 -125.768354)
			(xy 249.969935 -125.7411) (xy 249.977699 -125.687148) (xy 249.993062 -125.634849) (xy 250.015711 -125.585269)
			(xy 250.045185 -125.539417) (xy 250.080885 -125.498227) (xy 250.122083 -125.462536) (xy 250.167941 -125.433071)
			(xy 250.217526 -125.410433) (xy 250.269828 -125.395081) (xy 250.323782 -125.387329) (xy 250.351036 -125.386846)
			(xy 250.378408 -125.38728) (xy 250.432588 -125.395104) (xy 250.485092 -125.4106) (xy 250.534839 -125.433449)
			(xy 250.580804 -125.463181) (xy 250.601734 -125.480826) (xy 250.601988 -125.48108) (xy 250.609067 -125.486677)
			(xy 250.62599 -125.492915) (xy 250.635008 -125.493272) (xy 250.702064 -125.493272) (xy 250.71108 -125.492904)
			(xy 250.727997 -125.486665) (xy 250.735084 -125.48108) (xy 250.735084 -125.480826) (xy 250.735338 -125.480826)
			(xy 250.756286 -125.463207) (xy 250.802254 -125.433491) (xy 250.851997 -125.410651) (xy 250.904495 -125.395155)
			(xy 250.958668 -125.387322) (xy 250.986036 -125.386846) (xy 251.013286 -125.387344) (xy 251.067231 -125.395104)
			(xy 251.119523 -125.410462) (xy 251.169097 -125.433104) (xy 251.214945 -125.462569) (xy 251.256134 -125.498259)
			(xy 251.291824 -125.539447) (xy 251.321291 -125.585294) (xy 251.343935 -125.634868) (xy 251.359293 -125.687159)
			(xy 251.367055 -125.741104) (xy 251.367544 -125.768354) (xy 251.367014 -125.797271) (xy 251.35829 -125.854442)
			(xy 251.341036 -125.909642) (xy 251.315647 -125.961604) (xy 251.282704 -126.009138) (xy 251.242964 -126.051155)
			(xy 251.220478 -126.069344) (xy 251.211657 -126.076938) (xy 251.201482 -126.097849) (xy 251.20092 -126.109476)
			(xy 251.20092 -126.189232) (xy 251.201448 -126.200865) (xy 251.211644 -126.221775) (xy 251.220478 -126.229364)
			(xy 251.24294 -126.247581) (xy 251.282677 -126.289595) (xy 251.315619 -126.337124) (xy 251.341012 -126.38908)
			(xy 251.358273 -126.444273) (xy 251.367006 -126.501439) (xy 251.367544 -126.530354) (xy 251.367002 -126.557604)
			(xy 251.359252 -126.61155) (xy 251.347151 -126.652782) (xy 251.638816 -126.652782) (xy 251.639268 -126.625411)
			(xy 251.647088 -126.571231) (xy 251.662581 -126.518728) (xy 251.685426 -126.468981) (xy 251.715153 -126.423015)
			(xy 251.732796 -126.402084) (xy 251.73305 -126.40183) (xy 251.738636 -126.394743) (xy 251.744882 -126.377826)
			(xy 251.745242 -126.36881) (xy 251.745242 -126.301754) (xy 251.744872 -126.292738) (xy 251.738635 -126.27582)
			(xy 251.73305 -126.268734) (xy 251.732796 -126.268734) (xy 251.732796 -126.26848) (xy 251.715139 -126.247561)
			(xy 251.685417 -126.20159) (xy 251.662575 -126.151841) (xy 251.647081 -126.099337) (xy 251.639255 -126.045158)
			(xy 251.639257 -125.990415) (xy 251.647087 -125.936236) (xy 251.662584 -125.883733) (xy 251.68543 -125.833986)
			(xy 251.715155 -125.788017) (xy 251.732796 -125.767084) (xy 251.73305 -125.76683) (xy 251.738636 -125.759743)
			(xy 251.744882 -125.742826) (xy 251.745242 -125.73381) (xy 251.745242 -125.666754) (xy 251.744872 -125.657738)
			(xy 251.738635 -125.64082) (xy 251.73305 -125.633734) (xy 251.732796 -125.633734) (xy 251.732796 -125.63348)
			(xy 251.715139 -125.612561) (xy 251.685417 -125.56659) (xy 251.662575 -125.516841) (xy 251.647081 -125.464337)
			(xy 251.639255 -125.410158) (xy 251.639257 -125.355415) (xy 251.647087 -125.301236) (xy 251.662584 -125.248733)
			(xy 251.68543 -125.198986) (xy 251.715155 -125.153017) (xy 251.732796 -125.132084) (xy 251.73305 -125.13183)
			(xy 251.738636 -125.124743) (xy 251.744882 -125.107826) (xy 251.745242 -125.09881) (xy 251.745242 -125.031754)
			(xy 251.744872 -125.022738) (xy 251.738635 -125.00582) (xy 251.73305 -124.998734) (xy 251.732796 -124.998734)
			(xy 251.732796 -124.99848) (xy 251.71518 -124.977529) (xy 251.685465 -124.931561) (xy 251.662625 -124.881819)
			(xy 251.647128 -124.829322) (xy 251.639294 -124.77515) (xy 251.638816 -124.747782) (xy 251.639302 -124.720531)
			(xy 251.647058 -124.666583) (xy 251.662413 -124.614288) (xy 251.685055 -124.564711) (xy 251.714521 -124.518861)
			(xy 251.750212 -124.47767) (xy 251.791403 -124.441979) (xy 251.837253 -124.412513) (xy 251.88683 -124.389871)
			(xy 251.939125 -124.374516) (xy 251.993073 -124.36676) (xy 252.047575 -124.36676) (xy 252.101523 -124.374516)
			(xy 252.153818 -124.389871) (xy 252.203395 -124.412513) (xy 252.249245 -124.441979) (xy 252.290436 -124.47767)
			(xy 252.326127 -124.518861) (xy 252.355593 -124.564711) (xy 252.378235 -124.614288) (xy 252.39359 -124.666583)
			(xy 252.401346 -124.720531) (xy 252.401832 -124.747782) (xy 252.401372 -124.775153) (xy 252.393555 -124.829333)
			(xy 252.378066 -124.881836) (xy 252.355222 -124.931583) (xy 252.325495 -124.977549) (xy 252.307852 -124.99848)
			(xy 252.307598 -124.998734) (xy 252.302033 -125.005835) (xy 252.295773 -125.022741) (xy 252.295406 -125.031754)
			(xy 252.295406 -125.09881) (xy 252.295757 -125.107828) (xy 252.302009 -125.124744) (xy 252.307598 -125.13183)
			(xy 252.307852 -125.13183) (xy 252.307852 -125.132084) (xy 252.325476 -125.153031) (xy 252.355203 -125.198995)
			(xy 252.378051 -125.248739) (xy 252.393549 -125.301239) (xy 252.40138 -125.355416) (xy 252.401382 -125.410156)
			(xy 252.393555 -125.464334) (xy 252.37806 -125.516835) (xy 252.355216 -125.566581) (xy 252.325492 -125.612548)
			(xy 252.307852 -125.63348) (xy 252.307598 -125.633734) (xy 252.302033 -125.640835) (xy 252.295773 -125.657741)
			(xy 252.295406 -125.666754) (xy 252.295406 -125.73381) (xy 252.295757 -125.742828) (xy 252.302009 -125.759744)
			(xy 252.307598 -125.76683) (xy 252.307852 -125.76683) (xy 252.307852 -125.767084) (xy 252.325476 -125.788031)
			(xy 252.355203 -125.833995) (xy 252.378051 -125.883739) (xy 252.393549 -125.936239) (xy 252.40138 -125.990416)
			(xy 252.401382 -126.045156) (xy 252.393555 -126.099334) (xy 252.37806 -126.151835) (xy 252.355216 -126.201581)
			(xy 252.325492 -126.247548) (xy 252.307852 -126.26848) (xy 252.307598 -126.268734) (xy 252.302033 -126.275835)
			(xy 252.295773 -126.292741) (xy 252.295406 -126.301754) (xy 252.295406 -126.36881) (xy 252.295757 -126.377828)
			(xy 252.302009 -126.394744) (xy 252.307598 -126.40183) (xy 252.307852 -126.40183) (xy 252.307852 -126.402084)
			(xy 252.32549 -126.423017) (xy 252.355203 -126.468989) (xy 252.37804 -126.518736) (xy 252.393532 -126.571237)
			(xy 252.401359 -126.625413) (xy 252.401832 -126.652782) (xy 252.401346 -126.680033) (xy 252.39359 -126.733981)
			(xy 252.378235 -126.786276) (xy 252.355593 -126.835853) (xy 252.326127 -126.881703) (xy 252.290436 -126.922894)
			(xy 252.249245 -126.958585) (xy 252.203395 -126.988051) (xy 252.153818 -127.010693) (xy 252.101523 -127.026048)
			(xy 252.047575 -127.033804) (xy 251.993073 -127.033804) (xy 251.939125 -127.026048) (xy 251.88683 -127.010693)
			(xy 251.837253 -126.988051) (xy 251.791403 -126.958585) (xy 251.750212 -126.922894) (xy 251.714521 -126.881703)
			(xy 251.685055 -126.835853) (xy 251.662413 -126.786276) (xy 251.647058 -126.733981) (xy 251.639302 -126.680033)
			(xy 251.638816 -126.652782) (xy 251.347151 -126.652782) (xy 251.343904 -126.663845) (xy 251.321269 -126.713422)
			(xy 251.291809 -126.759274) (xy 251.256124 -126.800466) (xy 251.214939 -126.83616) (xy 251.169094 -126.86563)
			(xy 251.119521 -126.888275) (xy 251.067231 -126.903635) (xy 251.013286 -126.911396) (xy 250.986036 -126.911862)
			(xy 250.95972 -126.911449) (xy 250.907589 -126.904205) (xy 250.856944 -126.889876) (xy 250.808745 -126.868733)
			(xy 250.763903 -126.841177) (xy 250.723267 -126.807728) (xy 250.705112 -126.788672) (xy 250.697578 -126.781284)
			(xy 250.678308 -126.772749) (xy 250.667774 -126.772162) (xy 250.593098 -126.772162) (xy 250.582548 -126.772688)
			(xy 250.563254 -126.781227) (xy 250.55576 -126.788672) (xy 250.537611 -126.807735) (xy 250.496981 -126.841192)
			(xy 250.452139 -126.868751) (xy 250.403937 -126.889888) (xy 250.353288 -126.904204) (xy 250.301153 -126.911425)
			(xy 250.274836 -126.911862) (xy 250.247582 -126.911411) (xy 250.193628 -126.903658) (xy 250.141327 -126.888304)
			(xy 250.091744 -126.865662) (xy 250.045889 -126.836194) (xy 250.004694 -126.800499) (xy 249.969 -126.759303)
			(xy 249.939533 -126.713447) (xy 249.916892 -126.663863) (xy 249.90154 -126.611562) (xy 249.893788 -126.557608)
			(xy 249.893328 -126.530354) (xy 240.211356 -126.530354) (xy 240.211356 -127.051308) (xy 242.94414 -127.051308)
			(xy 242.948211 -126.995686) (xy 242.960337 -126.941249) (xy 242.98026 -126.889158) (xy 243.007556 -126.840523)
			(xy 243.041642 -126.79638) (xy 243.081791 -126.757671) (xy 243.127149 -126.72522) (xy 243.176749 -126.699719)
			(xy 243.229533 -126.681712) (xy 243.284376 -126.671582) (xy 243.34011 -126.669545) (xy 243.395547 -126.675645)
			(xy 243.449504 -126.689751) (xy 243.500833 -126.711563) (xy 243.548439 -126.740617) (xy 243.591307 -126.776292)
			(xy 243.628524 -126.817829) (xy 243.659297 -126.864342) (xy 243.682969 -126.914839) (xy 243.699037 -126.968246)
			(xy 243.707157 -127.023422) (xy 243.707666 -127.051308) (xy 243.707157 -127.079194) (xy 243.699037 -127.13437)
			(xy 243.682969 -127.187777) (xy 243.659297 -127.238274) (xy 243.628524 -127.284787) (xy 243.591307 -127.326324)
			(xy 243.548439 -127.361999) (xy 243.500833 -127.391053) (xy 243.449504 -127.412865) (xy 243.395547 -127.426971)
			(xy 243.34011 -127.433071) (xy 243.284376 -127.431034) (xy 243.229533 -127.420904) (xy 243.176749 -127.402897)
			(xy 243.127149 -127.377396) (xy 243.081791 -127.344945) (xy 243.041642 -127.306236) (xy 243.007556 -127.262093)
			(xy 242.98026 -127.213458) (xy 242.960337 -127.161367) (xy 242.948211 -127.10693) (xy 242.94414 -127.051308)
			(xy 240.211356 -127.051308) (xy 240.211356 -127.630936) (xy 240.210915 -127.66379) (xy 240.203547 -127.729084)
			(xy 240.188921 -127.793144) (xy 240.167218 -127.855165) (xy 240.138713 -127.914368) (xy 240.103762 -127.97001)
			(xy 240.062805 -128.021393) (xy 240.039906 -128.044956) (xy 239.832115 -128.252747) (xy 241.928428 -128.252747)
			(xy 241.928428 -128.198253) (xy 241.936184 -128.144312) (xy 241.951536 -128.092025) (xy 241.974174 -128.042454)
			(xy 242.003636 -127.99661) (xy 242.039323 -127.955426) (xy 242.080507 -127.919739) (xy 242.126351 -127.890276)
			(xy 242.175921 -127.867638) (xy 242.228208 -127.852284) (xy 242.282149 -127.844528) (xy 242.309396 -127.844042)
			(xy 242.336767 -127.8445) (xy 242.390946 -127.852318) (xy 242.44345 -127.867809) (xy 242.493197 -127.890652)
			(xy 242.539163 -127.920379) (xy 242.560094 -127.938022) (xy 242.560348 -127.938276) (xy 242.567439 -127.943856)
			(xy 242.584353 -127.950105) (xy 242.593368 -127.950468) (xy 242.660424 -127.950468) (xy 242.669443 -127.950129)
			(xy 242.68636 -127.94387) (xy 242.693444 -127.938276) (xy 242.693444 -127.938022) (xy 242.693698 -127.938022)
			(xy 242.714631 -127.920381) (xy 242.760599 -127.890657) (xy 242.810345 -127.867811) (xy 242.862847 -127.852315)
			(xy 242.917025 -127.844486) (xy 242.971767 -127.844486) (xy 243.025945 -127.852315) (xy 243.078447 -127.867811)
			(xy 243.128193 -127.890657) (xy 243.174161 -127.920381) (xy 243.195094 -127.938022) (xy 243.195348 -127.938276)
			(xy 243.202439 -127.943856) (xy 243.219353 -127.950105) (xy 243.228368 -127.950468) (xy 243.295424 -127.950468)
			(xy 243.304443 -127.950129) (xy 243.32136 -127.94387) (xy 243.328444 -127.938276) (xy 243.328444 -127.938022)
			(xy 243.328698 -127.938022) (xy 243.349623 -127.920374) (xy 243.395597 -127.890663) (xy 243.445347 -127.867828)
			(xy 243.497849 -127.852339) (xy 243.552026 -127.844514) (xy 243.579396 -127.844042) (xy 243.606653 -127.844405)
			(xy 243.660611 -127.852162) (xy 243.712916 -127.86752) (xy 243.762504 -127.890165) (xy 243.808363 -127.919637)
			(xy 243.849562 -127.955335) (xy 243.885261 -127.996534) (xy 243.914733 -128.042393) (xy 243.937379 -128.09198)
			(xy 243.952737 -128.144285) (xy 243.960495 -128.198243) (xy 243.960495 -128.252757) (xy 243.952737 -128.306715)
			(xy 243.937379 -128.35902) (xy 243.914733 -128.408607) (xy 243.885261 -128.454466) (xy 243.849562 -128.495665)
			(xy 243.808363 -128.531363) (xy 243.762504 -128.560835) (xy 243.712916 -128.58348) (xy 243.660611 -128.598838)
			(xy 243.606653 -128.606595) (xy 243.579396 -128.607058) (xy 243.552025 -128.606605) (xy 243.497845 -128.598785)
			(xy 243.445342 -128.583294) (xy 243.395595 -128.560449) (xy 243.349629 -128.530721) (xy 243.328698 -128.513078)
			(xy 243.328444 -128.512824) (xy 243.321355 -128.507241) (xy 243.30444 -128.500994) (xy 243.295424 -128.500632)
			(xy 243.228368 -128.500632) (xy 243.219349 -128.500967) (xy 243.202432 -128.507229) (xy 243.195348 -128.512824)
			(xy 243.195348 -128.513078) (xy 243.195094 -128.513078) (xy 243.174161 -128.530719) (xy 243.128193 -128.560443)
			(xy 243.078447 -128.583289) (xy 243.025945 -128.598785) (xy 242.971767 -128.606614) (xy 242.917025 -128.606614)
			(xy 242.862847 -128.598785) (xy 242.810345 -128.583289) (xy 242.760599 -128.560443) (xy 242.714631 -128.530719)
			(xy 242.693698 -128.513078) (xy 242.693444 -128.512824) (xy 242.686355 -128.507241) (xy 242.66944 -128.500994)
			(xy 242.660424 -128.500632) (xy 242.593368 -128.500632) (xy 242.584349 -128.500967) (xy 242.567432 -128.507229)
			(xy 242.560348 -128.512824) (xy 242.560348 -128.513078) (xy 242.560094 -128.513078) (xy 242.539172 -128.53073)
			(xy 242.493197 -128.560441) (xy 242.443447 -128.583274) (xy 242.390944 -128.598762) (xy 242.336766 -128.606586)
			(xy 242.309396 -128.607058) (xy 242.282149 -128.606472) (xy 242.228208 -128.598716) (xy 242.175921 -128.583362)
			(xy 242.126351 -128.560724) (xy 242.080507 -128.531261) (xy 242.039323 -128.495574) (xy 242.003636 -128.45439)
			(xy 241.974174 -128.408546) (xy 241.951536 -128.358975) (xy 241.936184 -128.306688) (xy 241.928428 -128.252747)
			(xy 239.832115 -128.252747) (xy 237.81385 -130.271012) (xy 237.807019 -130.27842) (xy 237.799292 -130.297013)
			(xy 237.798864 -130.30708) (xy 237.798864 -131.447157) (xy 241.913309 -131.447157) (xy 241.913309 -131.392643)
			(xy 241.921067 -131.338685) (xy 241.936426 -131.28638) (xy 241.959072 -131.236793) (xy 241.988544 -131.190934)
			(xy 242.024243 -131.149736) (xy 242.065442 -131.114038) (xy 242.111302 -131.084567) (xy 242.160889 -131.061922)
			(xy 242.213195 -131.046565) (xy 242.267153 -131.038808) (xy 242.29441 -131.038346) (xy 242.321781 -131.038795)
			(xy 242.375961 -131.046615) (xy 242.428465 -131.062108) (xy 242.478212 -131.084953) (xy 242.524177 -131.114682)
			(xy 242.545108 -131.132326) (xy 242.545362 -131.13258) (xy 242.552448 -131.138166) (xy 242.569366 -131.144411)
			(xy 242.578382 -131.144772) (xy 242.645438 -131.144772) (xy 242.654457 -131.144439) (xy 242.671375 -131.138175)
			(xy 242.678458 -131.13258) (xy 242.678458 -131.132326) (xy 242.678712 -131.132326) (xy 242.699645 -131.114685)
			(xy 242.745613 -131.084961) (xy 242.795359 -131.062115) (xy 242.847861 -131.046619) (xy 242.902039 -131.03879)
			(xy 242.956781 -131.03879) (xy 243.010959 -131.046619) (xy 243.063461 -131.062115) (xy 243.113207 -131.084961)
			(xy 243.159175 -131.114685) (xy 243.180108 -131.132326) (xy 243.180362 -131.13258) (xy 243.187448 -131.138166)
			(xy 243.204366 -131.144411) (xy 243.213382 -131.144772) (xy 243.280438 -131.144772) (xy 243.289457 -131.144439)
			(xy 243.306375 -131.138175) (xy 243.313458 -131.13258) (xy 243.313458 -131.132326) (xy 243.313712 -131.132326)
			(xy 243.33467 -131.114719) (xy 243.380635 -131.085001) (xy 243.430376 -131.062159) (xy 243.482871 -131.04666)
			(xy 243.537043 -131.038824) (xy 243.56441 -131.038346) (xy 243.591657 -131.038925) (xy 243.645598 -131.046682)
			(xy 243.697885 -131.062036) (xy 243.747455 -131.084675) (xy 243.793298 -131.114138) (xy 243.834482 -131.149825)
			(xy 243.870168 -131.19101) (xy 243.89963 -131.236854) (xy 243.922268 -131.286425) (xy 243.937621 -131.338712)
			(xy 243.945376 -131.392653) (xy 243.945376 -131.447147) (xy 243.937621 -131.501088) (xy 243.922268 -131.553375)
			(xy 243.89963 -131.602946) (xy 243.870168 -131.64879) (xy 243.834482 -131.689975) (xy 243.793298 -131.725662)
			(xy 243.747455 -131.755125) (xy 243.697885 -131.777764) (xy 243.645598 -131.793118) (xy 243.591657 -131.800875)
			(xy 243.56441 -131.801362) (xy 243.53704 -131.800899) (xy 243.48286 -131.793082) (xy 243.430356 -131.777593)
			(xy 243.38061 -131.75475) (xy 243.334643 -131.725024) (xy 243.313712 -131.707382) (xy 243.313458 -131.707128)
			(xy 243.306365 -131.701551) (xy 243.289453 -131.695301) (xy 243.280438 -131.694936) (xy 243.213382 -131.694936)
			(xy 243.204363 -131.695276) (xy 243.187446 -131.701535) (xy 243.180362 -131.707128) (xy 243.180362 -131.707382)
			(xy 243.180108 -131.707382) (xy 243.159175 -131.725023) (xy 243.113207 -131.754747) (xy 243.063461 -131.777593)
			(xy 243.010959 -131.793089) (xy 242.956781 -131.800918) (xy 242.902039 -131.800918) (xy 242.847861 -131.793089)
			(xy 242.795359 -131.777593) (xy 242.745613 -131.754747) (xy 242.699645 -131.725023) (xy 242.678712 -131.707382)
			(xy 242.678458 -131.707128) (xy 242.671365 -131.701551) (xy 242.654453 -131.695301) (xy 242.645438 -131.694936)
			(xy 242.578382 -131.694936) (xy 242.569363 -131.695276) (xy 242.552446 -131.701535) (xy 242.545362 -131.707128)
			(xy 242.545362 -131.707382) (xy 242.545108 -131.707382) (xy 242.524181 -131.725028) (xy 242.478207 -131.754739)
			(xy 242.428459 -131.777574) (xy 242.375957 -131.793064) (xy 242.32178 -131.800889) (xy 242.29441 -131.801362)
			(xy 242.267153 -131.800992) (xy 242.213195 -131.793235) (xy 242.160889 -131.777878) (xy 242.111302 -131.755233)
			(xy 242.065442 -131.725762) (xy 242.024243 -131.690064) (xy 241.988544 -131.648866) (xy 241.959072 -131.603007)
			(xy 241.936426 -131.55342) (xy 241.921067 -131.501115) (xy 241.913309 -131.447157) (xy 237.798864 -131.447157)
			(xy 237.798864 -133.333236) (xy 237.799268 -133.343399) (xy 237.807148 -133.362135) (xy 237.814104 -133.369558)
			(xy 237.873032 -133.42747) (xy 237.892082 -133.43509) (xy 237.902242 -133.434836) (xy 237.909862 -133.434836)
			(xy 237.93712 -133.435208) (xy 237.991081 -133.442962) (xy 237.993684 -133.443726) (xy 243.322856 -133.443726)
			(xy 243.323323 -133.417412) (xy 243.330555 -133.365283) (xy 243.344873 -133.314639) (xy 243.366006 -133.26644)
			(xy 243.393553 -133.221596) (xy 243.426993 -133.180958) (xy 243.446046 -133.162802) (xy 243.453441 -133.155274)
			(xy 243.461971 -133.135999) (xy 243.462556 -133.125464) (xy 243.462556 -133.050788) (xy 243.46206 -133.040234)
			(xy 243.453503 -133.020938) (xy 243.446046 -133.01345) (xy 243.426963 -132.995322) (xy 243.39351 -132.954685)
			(xy 243.365956 -132.909839) (xy 243.344823 -132.861633) (xy 243.330511 -132.810981) (xy 243.323292 -132.758844)
			(xy 243.322856 -132.732526) (xy 243.323342 -132.705275) (xy 243.331098 -132.651327) (xy 243.346453 -132.599032)
			(xy 243.369095 -132.549455) (xy 243.398561 -132.503605) (xy 243.434252 -132.462414) (xy 243.475443 -132.426723)
			(xy 243.521293 -132.397257) (xy 243.57087 -132.374615) (xy 243.623165 -132.35926) (xy 243.677113 -132.351504)
			(xy 243.731615 -132.351504) (xy 243.785563 -132.35926) (xy 243.837858 -132.374615) (xy 243.887435 -132.397257)
			(xy 243.933285 -132.426723) (xy 243.974476 -132.462414) (xy 244.010167 -132.503605) (xy 244.039633 -132.549455)
			(xy 244.062275 -132.599032) (xy 244.07763 -132.651327) (xy 244.085386 -132.705275) (xy 244.085872 -132.732526)
			(xy 244.085431 -132.758841) (xy 244.078192 -132.810971) (xy 244.063868 -132.861615) (xy 244.042731 -132.909814)
			(xy 244.01518 -132.954656) (xy 243.981736 -132.995295) (xy 243.962682 -133.01345) (xy 243.955254 -133.020949)
			(xy 243.946745 -133.040246) (xy 243.946172 -133.050788) (xy 243.946172 -133.125464) (xy 243.946716 -133.136012)
			(xy 243.955242 -133.155307) (xy 243.962682 -133.162802) (xy 243.981728 -133.180967) (xy 244.015187 -133.221594)
			(xy 244.042747 -133.266433) (xy 244.063888 -133.314631) (xy 244.078207 -133.365277) (xy 244.085433 -133.41741)
			(xy 244.085872 -133.443726) (xy 244.085386 -133.470977) (xy 244.07763 -133.524925) (xy 244.062275 -133.57722)
			(xy 244.039633 -133.626797) (xy 244.010167 -133.672647) (xy 243.974476 -133.713838) (xy 243.933285 -133.749529)
			(xy 243.887435 -133.778995) (xy 243.837858 -133.801637) (xy 243.785563 -133.816992) (xy 243.731615 -133.824748)
			(xy 243.677113 -133.824748) (xy 243.623165 -133.816992) (xy 243.57087 -133.801637) (xy 243.521293 -133.778995)
			(xy 243.475443 -133.749529) (xy 243.434252 -133.713838) (xy 243.398561 -133.672647) (xy 243.369095 -133.626797)
			(xy 243.346453 -133.57722) (xy 243.331098 -133.524925) (xy 243.323342 -133.470977) (xy 243.322856 -133.443726)
			(xy 237.993684 -133.443726) (xy 238.04339 -133.458316) (xy 238.09298 -133.480959) (xy 238.138844 -133.51043)
			(xy 238.180046 -133.546128) (xy 238.215747 -133.587326) (xy 238.245222 -133.633186) (xy 238.26787 -133.682775)
			(xy 238.28323 -133.735082) (xy 238.290989 -133.789042) (xy 238.290989 -133.843558) (xy 238.28323 -133.897518)
			(xy 238.26787 -133.949825) (xy 238.245222 -133.999414) (xy 238.217592 -134.042404) (xy 238.37595 -134.042404)
			(xy 238.380021 -133.986782) (xy 238.392147 -133.932345) (xy 238.41207 -133.880254) (xy 238.439366 -133.831619)
			(xy 238.473452 -133.787476) (xy 238.513601 -133.748767) (xy 238.558959 -133.716316) (xy 238.608559 -133.690815)
			(xy 238.661343 -133.672808) (xy 238.716186 -133.662678) (xy 238.77192 -133.660641) (xy 238.827357 -133.666741)
			(xy 238.881314 -133.680847) (xy 238.932643 -133.702659) (xy 238.980249 -133.731713) (xy 239.023117 -133.767388)
			(xy 239.060334 -133.808925) (xy 239.091107 -133.855438) (xy 239.114779 -133.905935) (xy 239.130847 -133.959342)
			(xy 239.138967 -134.014518) (xy 239.139476 -134.042404) (xy 239.138967 -134.07029) (xy 239.130847 -134.125466)
			(xy 239.114779 -134.178873) (xy 239.091107 -134.22937) (xy 239.060334 -134.275883) (xy 239.023117 -134.31742)
			(xy 238.980249 -134.353095) (xy 238.932643 -134.382149) (xy 238.881314 -134.403961) (xy 238.827357 -134.418067)
			(xy 238.77192 -134.424167) (xy 238.716186 -134.42213) (xy 238.661343 -134.412) (xy 238.608559 -134.393993)
			(xy 238.558959 -134.368492) (xy 238.513601 -134.336041) (xy 238.473452 -134.297332) (xy 238.439366 -134.253189)
			(xy 238.41207 -134.204554) (xy 238.392147 -134.152463) (xy 238.380021 -134.098026) (xy 238.37595 -134.042404)
			(xy 238.217592 -134.042404) (xy 238.215747 -134.045274) (xy 238.180046 -134.086472) (xy 238.138844 -134.12217)
			(xy 238.09298 -134.151641) (xy 238.04339 -134.174284) (xy 237.991081 -134.189638) (xy 237.93712 -134.197392)
			(xy 237.909862 -134.197852) (xy 237.902242 -134.197852) (xy 237.892082 -134.197598) (xy 237.873032 -134.205218)
			(xy 237.814104 -134.26313) (xy 237.80717 -134.270564) (xy 237.799313 -134.289296) (xy 237.798864 -134.299452)
			(xy 237.798864 -135.142051) (xy 241.56187 -135.142051) (xy 241.56187 -135.087549) (xy 241.569626 -135.033603)
			(xy 241.58498 -134.981309) (xy 241.60762 -134.931732) (xy 241.637084 -134.885882) (xy 241.672774 -134.844692)
			(xy 241.713962 -134.809) (xy 241.75981 -134.779532) (xy 241.809385 -134.756889) (xy 241.861677 -134.741531)
			(xy 241.915623 -134.733772) (xy 241.942874 -134.733284) (xy 241.971792 -134.733789) (xy 242.028965 -134.742516)
			(xy 242.084166 -134.759775) (xy 242.136128 -134.785169) (xy 242.183661 -134.818116) (xy 242.225676 -134.857862)
			(xy 242.243864 -134.88035) (xy 242.251656 -134.889338) (xy 242.273122 -134.899526) (xy 242.285012 -134.899908)
			(xy 242.378484 -134.897876) (xy 242.39982 -134.8867) (xy 242.406678 -134.876794) (xy 242.422076 -134.855884)
			(xy 242.457654 -134.818057) (xy 242.498033 -134.785405) (xy 242.542468 -134.75853) (xy 242.590136 -134.73793)
			(xy 242.640158 -134.723985) (xy 242.691609 -134.716952) (xy 242.717574 -134.71652) (xy 242.744944 -134.716996)
			(xy 242.799123 -134.724811) (xy 242.851626 -134.740297) (xy 242.901373 -134.763137) (xy 242.94734 -134.79286)
			(xy 242.968272 -134.8105) (xy 242.968526 -134.810754) (xy 242.975625 -134.816322) (xy 242.992532 -134.822579)
			(xy 243.001546 -134.822946) (xy 243.068602 -134.822946) (xy 243.07762 -134.822601) (xy 243.094538 -134.816346)
			(xy 243.101622 -134.810754) (xy 243.101622 -134.8105) (xy 243.101876 -134.8105) (xy 243.122809 -134.792859)
			(xy 243.168777 -134.763135) (xy 243.218523 -134.740289) (xy 243.271025 -134.724793) (xy 243.325203 -134.716964)
			(xy 243.379945 -134.716964) (xy 243.434123 -134.724793) (xy 243.486625 -134.740289) (xy 243.536371 -134.763135)
			(xy 243.582339 -134.792859) (xy 243.603272 -134.8105) (xy 243.603526 -134.810754) (xy 243.610625 -134.816322)
			(xy 243.627532 -134.822579) (xy 243.636546 -134.822946) (xy 243.703602 -134.822946) (xy 243.71262 -134.822601)
			(xy 243.729538 -134.816346) (xy 243.736622 -134.810754) (xy 243.73713 -134.8105) (xy 243.749868 -134.79956)
			(xy 243.776957 -134.779716) (xy 243.791232 -134.770876) (xy 243.800122 -134.765542) (xy 243.812314 -134.748524)
			(xy 243.832634 -134.655306) (xy 243.828316 -134.634732) (xy 243.822474 -134.626096) (xy 243.806467 -134.602037)
			(xy 243.781127 -134.550103) (xy 243.763903 -134.494944) (xy 243.75519 -134.437819) (xy 243.754656 -134.408926)
			(xy 243.755142 -134.381675) (xy 243.762898 -134.327727) (xy 243.778253 -134.275432) (xy 243.800895 -134.225855)
			(xy 243.830361 -134.180005) (xy 243.866052 -134.138814) (xy 243.907243 -134.103123) (xy 243.953093 -134.073657)
			(xy 244.00267 -134.051015) (xy 244.054965 -134.03566) (xy 244.108913 -134.027904) (xy 244.163415 -134.027904)
			(xy 244.217363 -134.03566) (xy 244.269658 -134.051015) (xy 244.319235 -134.073657) (xy 244.365085 -134.103123)
			(xy 244.406276 -134.138814) (xy 244.441967 -134.180005) (xy 244.471433 -134.225855) (xy 244.494075 -134.275432)
			(xy 244.50943 -134.327727) (xy 244.517186 -134.381675) (xy 244.517672 -134.408926) (xy 244.51722 -134.437019)
			(xy 244.508988 -134.492599) (xy 244.492691 -134.546371) (xy 244.468682 -134.597169) (xy 244.43748 -134.643895)
			(xy 244.399761 -134.685539) (xy 244.35634 -134.721198) (xy 244.332506 -134.736078) (xy 244.323616 -134.741412)
			(xy 244.311424 -134.75843) (xy 244.291104 -134.851648) (xy 244.295422 -134.872222) (xy 244.301264 -134.880858)
			(xy 244.317244 -134.904934) (xy 244.342592 -134.956861) (xy 244.359824 -135.012015) (xy 244.368545 -135.069136)
			(xy 244.369082 -135.098028) (xy 244.368648 -135.125281) (xy 244.360887 -135.179232) (xy 244.345527 -135.231529)
			(xy 244.322881 -135.281108) (xy 244.293409 -135.32696) (xy 244.257712 -135.368151) (xy 244.216517 -135.403842)
			(xy 244.170661 -135.433307) (xy 244.121079 -135.455946) (xy 244.068779 -135.471299) (xy 244.014827 -135.479052)
			(xy 243.987574 -135.479536) (xy 243.960202 -135.479101) (xy 243.906021 -135.471278) (xy 243.853517 -135.455782)
			(xy 243.803771 -135.432933) (xy 243.757806 -135.403201) (xy 243.736876 -135.385556) (xy 243.736622 -135.385302)
			(xy 243.729533 -135.379719) (xy 243.712618 -135.37347) (xy 243.703602 -135.37311) (xy 243.636546 -135.37311)
			(xy 243.627531 -135.373487) (xy 243.610614 -135.379721) (xy 243.603526 -135.385302) (xy 243.603526 -135.385556)
			(xy 243.603272 -135.385556) (xy 243.582339 -135.403197) (xy 243.536371 -135.432921) (xy 243.486625 -135.455767)
			(xy 243.434123 -135.471263) (xy 243.379945 -135.479092) (xy 243.325203 -135.479092) (xy 243.271025 -135.471263)
			(xy 243.218523 -135.455767) (xy 243.168777 -135.432921) (xy 243.122809 -135.403197) (xy 243.101876 -135.385556)
			(xy 243.101622 -135.385302) (xy 243.094533 -135.379719) (xy 243.077618 -135.37347) (xy 243.068602 -135.37311)
			(xy 243.001546 -135.37311) (xy 242.992531 -135.373487) (xy 242.975614 -135.379721) (xy 242.968526 -135.385302)
			(xy 242.968526 -135.385556) (xy 242.968272 -135.385556) (xy 242.947318 -135.403168) (xy 242.901352 -135.432885)
			(xy 242.85161 -135.455727) (xy 242.799114 -135.471225) (xy 242.744942 -135.479059) (xy 242.717574 -135.479536)
			(xy 242.688658 -135.478989) (xy 242.631487 -135.470269) (xy 242.576288 -135.453018) (xy 242.524325 -135.427632)
			(xy 242.476791 -135.394693) (xy 242.434774 -135.354954) (xy 242.416584 -135.33247) (xy 242.408767 -135.323508)
			(xy 242.38732 -135.313305) (xy 242.375436 -135.312912) (xy 242.281964 -135.314944) (xy 242.260628 -135.32612)
			(xy 242.25377 -135.336026) (xy 242.238348 -135.356918) (xy 242.202774 -135.394744) (xy 242.162398 -135.427397)
			(xy 242.117968 -135.454274) (xy 242.070303 -135.474877) (xy 242.020285 -135.488827) (xy 241.968837 -135.495865)
			(xy 241.942874 -135.4963) (xy 241.915623 -135.495828) (xy 241.861677 -135.488069) (xy 241.809385 -135.472711)
			(xy 241.75981 -135.450068) (xy 241.713962 -135.4206) (xy 241.672774 -135.384908) (xy 241.637084 -135.343718)
			(xy 241.60762 -135.297868) (xy 241.58498 -135.248291) (xy 241.569626 -135.195997) (xy 241.56187 -135.142051)
			(xy 237.798864 -135.142051) (xy 237.798864 -135.689594) (xy 239.483136 -135.689594) (xy 239.487207 -135.633972)
			(xy 239.499333 -135.579535) (xy 239.519256 -135.527444) (xy 239.546552 -135.478809) (xy 239.580638 -135.434666)
			(xy 239.620787 -135.395957) (xy 239.666145 -135.363506) (xy 239.715745 -135.338005) (xy 239.768529 -135.319998)
			(xy 239.823372 -135.309868) (xy 239.879106 -135.307831) (xy 239.934543 -135.313931) (xy 239.9885 -135.328037)
			(xy 240.039829 -135.349849) (xy 240.087435 -135.378903) (xy 240.130303 -135.414578) (xy 240.16752 -135.456115)
			(xy 240.198293 -135.502628) (xy 240.221965 -135.553125) (xy 240.238033 -135.606532) (xy 240.246153 -135.661708)
			(xy 240.246662 -135.689594) (xy 240.246153 -135.71748) (xy 240.238033 -135.772656) (xy 240.221965 -135.826063)
			(xy 240.202828 -135.866886) (xy 240.639852 -135.866886) (xy 240.643923 -135.811264) (xy 240.656049 -135.756827)
			(xy 240.675972 -135.704736) (xy 240.703268 -135.656101) (xy 240.737354 -135.611958) (xy 240.777503 -135.573249)
			(xy 240.822861 -135.540798) (xy 240.872461 -135.515297) (xy 240.925245 -135.49729) (xy 240.980088 -135.48716)
			(xy 241.035822 -135.485123) (xy 241.091259 -135.491223) (xy 241.145216 -135.505329) (xy 241.196545 -135.527141)
			(xy 241.244151 -135.556195) (xy 241.287019 -135.59187) (xy 241.324236 -135.633407) (xy 241.355009 -135.67992)
			(xy 241.378681 -135.730417) (xy 241.394749 -135.783824) (xy 241.402869 -135.839) (xy 241.403378 -135.866886)
			(xy 241.402869 -135.894772) (xy 241.394749 -135.949948) (xy 241.378681 -136.003355) (xy 241.355009 -136.053852)
			(xy 241.324236 -136.100365) (xy 241.287019 -136.141902) (xy 241.244151 -136.177577) (xy 241.196545 -136.206631)
			(xy 241.145216 -136.228443) (xy 241.091259 -136.242549) (xy 241.035822 -136.248649) (xy 240.980088 -136.246612)
			(xy 240.925245 -136.236482) (xy 240.872461 -136.218475) (xy 240.822861 -136.192974) (xy 240.777503 -136.160523)
			(xy 240.737354 -136.121814) (xy 240.703268 -136.077671) (xy 240.675972 -136.029036) (xy 240.656049 -135.976945)
			(xy 240.643923 -135.922508) (xy 240.639852 -135.866886) (xy 240.202828 -135.866886) (xy 240.198293 -135.87656)
			(xy 240.16752 -135.923073) (xy 240.130303 -135.96461) (xy 240.087435 -136.000285) (xy 240.039829 -136.029339)
			(xy 239.9885 -136.051151) (xy 239.934543 -136.065257) (xy 239.879106 -136.071357) (xy 239.823372 -136.06932)
			(xy 239.768529 -136.05919) (xy 239.715745 -136.041183) (xy 239.666145 -136.015682) (xy 239.620787 -135.983231)
			(xy 239.580638 -135.944522) (xy 239.546552 -135.900379) (xy 239.519256 -135.851744) (xy 239.499333 -135.799653)
			(xy 239.487207 -135.745216) (xy 239.483136 -135.689594) (xy 237.798864 -135.689594) (xy 237.798864 -137.44829)
			(xy 240.54511 -137.44829) (xy 240.549181 -137.392668) (xy 240.561307 -137.338231) (xy 240.58123 -137.28614)
			(xy 240.608526 -137.237505) (xy 240.642612 -137.193362) (xy 240.682761 -137.154653) (xy 240.728119 -137.122202)
			(xy 240.777719 -137.096701) (xy 240.830503 -137.078694) (xy 240.885346 -137.068564) (xy 240.94108 -137.066527)
			(xy 240.996517 -137.072627) (xy 241.050474 -137.086733) (xy 241.101803 -137.108545) (xy 241.149409 -137.137599)
			(xy 241.192277 -137.173274) (xy 241.229494 -137.214811) (xy 241.260267 -137.261324) (xy 241.267302 -137.276332)
			(xy 245.24716 -137.276332) (xy 245.247563 -137.250016) (xy 245.254808 -137.197884) (xy 245.269139 -137.147239)
			(xy 245.290283 -137.09904) (xy 245.317842 -137.054198) (xy 245.351292 -137.013562) (xy 245.37035 -136.995408)
			(xy 245.377743 -136.987879) (xy 245.386274 -136.968605) (xy 245.38686 -136.95807) (xy 245.38686 -136.883394)
			(xy 245.386359 -136.872841) (xy 245.377805 -136.853545) (xy 245.37035 -136.846056) (xy 245.351271 -136.827925)
			(xy 245.317818 -136.787289) (xy 245.290263 -136.742443) (xy 245.269129 -136.694238) (xy 245.254816 -136.643586)
			(xy 245.247596 -136.591449) (xy 245.24716 -136.565132) (xy 245.247646 -136.537881) (xy 245.255402 -136.483933)
			(xy 245.270757 -136.431638) (xy 245.293399 -136.382061) (xy 245.322865 -136.336211) (xy 245.358556 -136.29502)
			(xy 245.399747 -136.259329) (xy 245.445597 -136.229863) (xy 245.495174 -136.207221) (xy 245.547469 -136.191866)
			(xy 245.601417 -136.18411) (xy 245.655919 -136.18411) (xy 245.709867 -136.191866) (xy 245.762162 -136.207221)
			(xy 245.811739 -136.229863) (xy 245.857589 -136.259329) (xy 245.89878 -136.29502) (xy 245.934471 -136.336211)
			(xy 245.963937 -136.382061) (xy 245.986579 -136.431638) (xy 246.001934 -136.483933) (xy 246.00969 -136.537881)
			(xy 246.010176 -136.565132) (xy 246.009738 -136.591447) (xy 246.002498 -136.643577) (xy 245.988174 -136.694221)
			(xy 245.967036 -136.74242) (xy 245.939484 -136.787262) (xy 245.90604 -136.827901) (xy 245.886986 -136.846056)
			(xy 245.8796 -136.85359) (xy 245.871067 -136.872861) (xy 245.870476 -136.883394) (xy 245.870476 -136.95807)
			(xy 245.871015 -136.968618) (xy 245.879544 -136.987913) (xy 245.886986 -136.995408) (xy 245.906036 -137.013569)
			(xy 245.939494 -137.054198) (xy 245.967054 -137.099036) (xy 245.988194 -137.147236) (xy 246.002512 -137.197883)
			(xy 246.009737 -137.250016) (xy 246.010176 -137.276332) (xy 246.00969 -137.303583) (xy 246.001934 -137.357531)
			(xy 245.986579 -137.409826) (xy 245.963937 -137.459403) (xy 245.934471 -137.505253) (xy 245.89878 -137.546444)
			(xy 245.857589 -137.582135) (xy 245.811739 -137.611601) (xy 245.762162 -137.634243) (xy 245.709867 -137.649598)
			(xy 245.655919 -137.657354) (xy 245.601417 -137.657354) (xy 245.547469 -137.649598) (xy 245.495174 -137.634243)
			(xy 245.445597 -137.611601) (xy 245.399747 -137.582135) (xy 245.358556 -137.546444) (xy 245.322865 -137.505253)
			(xy 245.293399 -137.459403) (xy 245.270757 -137.409826) (xy 245.255402 -137.357531) (xy 245.247646 -137.303583)
			(xy 245.24716 -137.276332) (xy 241.267302 -137.276332) (xy 241.283939 -137.311821) (xy 241.300007 -137.365228)
			(xy 241.308127 -137.420404) (xy 241.308636 -137.44829) (xy 241.308127 -137.476176) (xy 241.300007 -137.531352)
			(xy 241.283939 -137.584759) (xy 241.260267 -137.635256) (xy 241.229494 -137.681769) (xy 241.192277 -137.723306)
			(xy 241.18823 -137.726674) (xy 246.187722 -137.726674) (xy 246.188167 -137.699303) (xy 246.195989 -137.645123)
			(xy 246.211483 -137.592619) (xy 246.234329 -137.542873) (xy 246.264059 -137.496907) (xy 246.281702 -137.475976)
			(xy 246.281956 -137.475722) (xy 246.287546 -137.468638) (xy 246.293789 -137.451719) (xy 246.294148 -137.442702)
			(xy 246.294148 -137.375646) (xy 246.29378 -137.36663) (xy 246.287541 -137.349712) (xy 246.281956 -137.342626)
			(xy 246.281702 -137.342626) (xy 246.281702 -137.342372) (xy 246.264084 -137.321423) (xy 246.234369 -137.275455)
			(xy 246.211529 -137.225712) (xy 246.196033 -137.173215) (xy 246.188199 -137.119042) (xy 246.187722 -137.091674)
			(xy 246.188208 -137.064423) (xy 246.195964 -137.010475) (xy 246.211319 -136.95818) (xy 246.233961 -136.908603)
			(xy 246.263427 -136.862753) (xy 246.299118 -136.821562) (xy 246.340309 -136.785871) (xy 246.386159 -136.756405)
			(xy 246.435736 -136.733763) (xy 246.488031 -136.718408) (xy 246.541979 -136.710652) (xy 246.596481 -136.710652)
			(xy 246.650429 -136.718408) (xy 246.702724 -136.733763) (xy 246.752301 -136.756405) (xy 246.798151 -136.785871)
			(xy 246.839342 -136.821562) (xy 246.875033 -136.862753) (xy 246.904499 -136.908603) (xy 246.927141 -136.95818)
			(xy 246.942496 -137.010475) (xy 246.950252 -137.064423) (xy 246.950738 -137.091674) (xy 246.950272 -137.119044)
			(xy 246.942456 -137.173224) (xy 246.926968 -137.225728) (xy 246.904126 -137.275475) (xy 246.8744 -137.321441)
			(xy 246.856758 -137.342372) (xy 246.856504 -137.342626) (xy 246.850943 -137.34973) (xy 246.844681 -137.366633)
			(xy 246.844312 -137.375646) (xy 246.844312 -137.442702) (xy 246.844665 -137.451719) (xy 246.850915 -137.468636)
			(xy 246.856504 -137.475722) (xy 246.856758 -137.475722) (xy 246.856758 -137.475976) (xy 246.874393 -137.496912)
			(xy 246.904107 -137.542883) (xy 246.926944 -137.592629) (xy 246.942436 -137.645129) (xy 246.950264 -137.699305)
			(xy 246.950738 -137.726674) (xy 246.950252 -137.753925) (xy 246.942496 -137.807873) (xy 246.927141 -137.860168)
			(xy 246.904499 -137.909745) (xy 246.875033 -137.955595) (xy 246.839342 -137.996786) (xy 246.798151 -138.032477)
			(xy 246.752301 -138.061943) (xy 246.702724 -138.084585) (xy 246.650429 -138.09994) (xy 246.596481 -138.107696)
			(xy 246.541979 -138.107696) (xy 246.488031 -138.09994) (xy 246.435736 -138.084585) (xy 246.386159 -138.061943)
			(xy 246.340309 -138.032477) (xy 246.299118 -137.996786) (xy 246.263427 -137.955595) (xy 246.233961 -137.909745)
			(xy 246.211319 -137.860168) (xy 246.195964 -137.807873) (xy 246.188208 -137.753925) (xy 246.187722 -137.726674)
			(xy 241.18823 -137.726674) (xy 241.149409 -137.758981) (xy 241.101803 -137.788035) (xy 241.050474 -137.809847)
			(xy 240.996517 -137.823953) (xy 240.94108 -137.830053) (xy 240.885346 -137.828016) (xy 240.830503 -137.817886)
			(xy 240.777719 -137.799879) (xy 240.728119 -137.774378) (xy 240.682761 -137.741927) (xy 240.642612 -137.703218)
			(xy 240.608526 -137.659075) (xy 240.58123 -137.61044) (xy 240.561307 -137.558349) (xy 240.549181 -137.503912)
			(xy 240.54511 -137.44829) (xy 237.798864 -137.44829) (xy 237.798864 -138.360404) (xy 238.37595 -138.360404)
			(xy 238.380021 -138.304782) (xy 238.392147 -138.250345) (xy 238.41207 -138.198254) (xy 238.439366 -138.149619)
			(xy 238.473452 -138.105476) (xy 238.513601 -138.066767) (xy 238.558959 -138.034316) (xy 238.608559 -138.008815)
			(xy 238.661343 -137.990808) (xy 238.716186 -137.980678) (xy 238.77192 -137.978641) (xy 238.827357 -137.984741)
			(xy 238.881314 -137.998847) (xy 238.932643 -138.020659) (xy 238.980249 -138.049713) (xy 239.023117 -138.085388)
			(xy 239.060334 -138.126925) (xy 239.091107 -138.173438) (xy 239.114779 -138.223935) (xy 239.130847 -138.277342)
			(xy 239.138967 -138.332518) (xy 239.139476 -138.360404) (xy 239.138967 -138.38829) (xy 239.136754 -138.40333)
			(xy 247.396254 -138.40333) (xy 247.396765 -138.375665) (xy 247.404761 -138.320914) (xy 247.420576 -138.267891)
			(xy 247.443879 -138.217707) (xy 247.474181 -138.171411) (xy 247.510848 -138.129973) (xy 247.553112 -138.094262)
			(xy 247.57634 -138.079226) (xy 247.586005 -138.072575) (xy 247.598456 -138.052725) (xy 247.600216 -138.041126)
			(xy 247.60809 -137.961116) (xy 247.608693 -137.949479) (xy 247.600631 -137.927644) (xy 247.592596 -137.919206)
			(xy 247.592342 -137.918952) (xy 247.573763 -137.900868) (xy 247.541183 -137.860538) (xy 247.514369 -137.816164)
			(xy 247.493815 -137.768566) (xy 247.479902 -137.718622) (xy 247.472885 -137.667253) (xy 247.472454 -137.64133)
			(xy 247.473006 -137.614081) (xy 247.480757 -137.560138) (xy 247.496107 -137.507847) (xy 247.518742 -137.458272)
			(xy 247.548201 -137.412424) (xy 247.583886 -137.371234) (xy 247.625069 -137.335542) (xy 247.670913 -137.306074)
			(xy 247.720483 -137.283431) (xy 247.772771 -137.268072) (xy 247.826713 -137.260311) (xy 247.853962 -137.259822)
			(xy 247.881332 -137.260305) (xy 247.93551 -137.268118) (xy 247.988013 -137.283603) (xy 248.037761 -137.306441)
			(xy 248.083728 -137.336162) (xy 248.10466 -137.353802) (xy 248.104914 -137.354056) (xy 248.111988 -137.359661)
			(xy 248.128915 -137.365895) (xy 248.137934 -137.366248) (xy 248.20499 -137.366248) (xy 248.214008 -137.365897)
			(xy 248.230925 -137.359647) (xy 248.23801 -137.354056) (xy 248.23801 -137.353802) (xy 248.238264 -137.353802)
			(xy 248.259199 -137.336167) (xy 248.305171 -137.306454) (xy 248.354918 -137.283617) (xy 248.407418 -137.268126)
			(xy 248.461593 -137.260296) (xy 248.488962 -137.259822) (xy 248.516215 -137.260291) (xy 248.570168 -137.268043)
			(xy 248.622467 -137.283396) (xy 248.672049 -137.306036) (xy 248.717904 -137.335503) (xy 248.759098 -137.371197)
			(xy 248.794792 -137.41239) (xy 248.82426 -137.458244) (xy 248.846901 -137.507825) (xy 248.862255 -137.560125)
			(xy 248.870009 -137.614077) (xy 248.87047 -137.64133) (xy 248.869913 -137.670246) (xy 248.861194 -137.727416)
			(xy 248.843944 -137.782614) (xy 248.81856 -137.834576) (xy 248.785623 -137.882111) (xy 248.745887 -137.924129)
			(xy 248.723404 -137.94232) (xy 248.714598 -137.949929) (xy 248.704414 -137.970828) (xy 248.703846 -137.982452)
			(xy 248.703846 -138.062208) (xy 248.704379 -138.073841) (xy 248.71457 -138.094752) (xy 248.723404 -138.10234)
			(xy 248.745907 -138.120507) (xy 248.785641 -138.162532) (xy 248.818578 -138.210072) (xy 248.843963 -138.262038)
			(xy 248.861215 -138.31724) (xy 248.869938 -138.374413) (xy 248.87047 -138.40333) (xy 248.870073 -138.430585)
			(xy 248.862311 -138.484541) (xy 248.846949 -138.536842) (xy 248.8243 -138.586425) (xy 248.794826 -138.63228)
			(xy 248.759125 -138.673473) (xy 248.717925 -138.709166) (xy 248.672065 -138.738633) (xy 248.622478 -138.761273)
			(xy 248.570174 -138.776625) (xy 248.516217 -138.784378) (xy 248.488962 -138.784838) (xy 248.462646 -138.784416)
			(xy 248.410515 -138.777174) (xy 248.359871 -138.762848) (xy 248.311671 -138.741707) (xy 248.266829 -138.714152)
			(xy 248.226192 -138.680704) (xy 248.208038 -138.661648) (xy 248.200498 -138.654268) (xy 248.181232 -138.64573)
			(xy 248.1707 -138.645138) (xy 248.096024 -138.645138) (xy 248.085473 -138.645655) (xy 248.066177 -138.654197)
			(xy 248.058686 -138.661648) (xy 248.04054 -138.680712) (xy 247.999907 -138.714167) (xy 247.955064 -138.741724)
			(xy 247.906862 -138.76286) (xy 247.856213 -138.777176) (xy 247.804079 -138.7844) (xy 247.777762 -138.784838)
			(xy 247.750511 -138.784358) (xy 247.696565 -138.776597) (xy 247.644272 -138.761238) (xy 247.594696 -138.738595)
			(xy 247.548848 -138.709127) (xy 247.507659 -138.673436) (xy 247.471968 -138.632246) (xy 247.442501 -138.586397)
			(xy 247.419859 -138.536821) (xy 247.404502 -138.484527) (xy 247.396742 -138.430581) (xy 247.396254 -138.40333)
			(xy 239.136754 -138.40333) (xy 239.130847 -138.443466) (xy 239.114779 -138.496873) (xy 239.091107 -138.54737)
			(xy 239.060334 -138.593883) (xy 239.023117 -138.63542) (xy 238.980249 -138.671095) (xy 238.932643 -138.700149)
			(xy 238.881314 -138.721961) (xy 238.827357 -138.736067) (xy 238.77192 -138.742167) (xy 238.716186 -138.74013)
			(xy 238.661343 -138.73) (xy 238.608559 -138.711993) (xy 238.558959 -138.686492) (xy 238.513601 -138.654041)
			(xy 238.473452 -138.615332) (xy 238.439366 -138.571189) (xy 238.41207 -138.522554) (xy 238.392147 -138.470463)
			(xy 238.380021 -138.416026) (xy 238.37595 -138.360404) (xy 237.798864 -138.360404) (xy 237.798864 -138.824462)
			(xy 240.561874 -138.824462) (xy 240.565945 -138.76884) (xy 240.578071 -138.714403) (xy 240.597994 -138.662312)
			(xy 240.62529 -138.613677) (xy 240.659376 -138.569534) (xy 240.699525 -138.530825) (xy 240.744883 -138.498374)
			(xy 240.794483 -138.472873) (xy 240.847267 -138.454866) (xy 240.90211 -138.444736) (xy 240.957844 -138.442699)
			(xy 241.013281 -138.448799) (xy 241.067238 -138.462905) (xy 241.118567 -138.484717) (xy 241.166173 -138.513771)
			(xy 241.209041 -138.549446) (xy 241.246258 -138.590983) (xy 241.277031 -138.637496) (xy 241.300703 -138.687993)
			(xy 241.316771 -138.7414) (xy 241.324891 -138.796576) (xy 241.3254 -138.824462) (xy 241.324891 -138.852348)
			(xy 241.316771 -138.907524) (xy 241.300703 -138.960931) (xy 241.277031 -139.011428) (xy 241.246258 -139.057941)
			(xy 241.209041 -139.099478) (xy 241.166173 -139.135153) (xy 241.118567 -139.164207) (xy 241.067238 -139.186019)
			(xy 241.013281 -139.200125) (xy 240.957844 -139.206225) (xy 240.90211 -139.204188) (xy 240.847267 -139.194058)
			(xy 240.794483 -139.176051) (xy 240.744883 -139.15055) (xy 240.699525 -139.118099) (xy 240.659376 -139.07939)
			(xy 240.62529 -139.035247) (xy 240.597994 -138.986612) (xy 240.578071 -138.934521) (xy 240.565945 -138.880084)
			(xy 240.561874 -138.824462) (xy 237.798864 -138.824462) (xy 237.798864 -139.358878) (xy 237.799284 -139.368948)
			(xy 237.80238 -139.376404) (xy 238.37595 -139.376404) (xy 238.380021 -139.320782) (xy 238.392147 -139.266345)
			(xy 238.41207 -139.214254) (xy 238.439366 -139.165619) (xy 238.473452 -139.121476) (xy 238.513601 -139.082767)
			(xy 238.558959 -139.050316) (xy 238.608559 -139.024815) (xy 238.661343 -139.006808) (xy 238.716186 -138.996678)
			(xy 238.77192 -138.994641) (xy 238.827357 -139.000741) (xy 238.881314 -139.014847) (xy 238.932643 -139.036659)
			(xy 238.980249 -139.065713) (xy 239.023117 -139.101388) (xy 239.060334 -139.142925) (xy 239.091107 -139.189438)
			(xy 239.114779 -139.239935) (xy 239.130847 -139.293342) (xy 239.138967 -139.348518) (xy 239.139476 -139.376404)
			(xy 239.138967 -139.40429) (xy 239.130847 -139.459466) (xy 239.114779 -139.512873) (xy 239.091107 -139.56337)
			(xy 239.060334 -139.609883) (xy 239.023117 -139.65142) (xy 238.980249 -139.687095) (xy 238.932643 -139.716149)
			(xy 238.881314 -139.737961) (xy 238.827357 -139.752067) (xy 238.77192 -139.758167) (xy 238.716186 -139.75613)
			(xy 238.661343 -139.746) (xy 238.608559 -139.727993) (xy 238.558959 -139.702492) (xy 238.513601 -139.670041)
			(xy 238.473452 -139.631332) (xy 238.439366 -139.587189) (xy 238.41207 -139.538554) (xy 238.392147 -139.486463)
			(xy 238.380021 -139.432026) (xy 238.37595 -139.376404) (xy 237.80238 -139.376404) (xy 237.807007 -139.387547)
			(xy 237.81385 -139.394946) (xy 238.485426 -140.066522) (xy 238.494014 -140.074409) (xy 238.516036 -140.082001)
			(xy 238.539145 -140.079067) (xy 238.54918 -140.073126) (xy 238.57257 -140.058409) (xy 238.622697 -140.03515)
			(xy 238.675656 -140.019366) (xy 238.730338 -140.011389) (xy 238.757968 -140.010896) (xy 238.78522 -140.011385)
			(xy 238.83917 -140.019138) (xy 238.891468 -140.03449) (xy 238.941048 -140.057129) (xy 238.986902 -140.086594)
			(xy 239.028095 -140.122285) (xy 239.063789 -140.163476) (xy 239.093258 -140.209327) (xy 239.1159 -140.258906)
			(xy 239.131256 -140.311202) (xy 239.139013 -140.365152) (xy 239.139476 -140.392404) (xy 240.567716 -140.392404)
			(xy 240.571787 -140.336782) (xy 240.583913 -140.282345) (xy 240.603836 -140.230254) (xy 240.631132 -140.181619)
			(xy 240.665218 -140.137476) (xy 240.705367 -140.098767) (xy 240.750725 -140.066316) (xy 240.800325 -140.040815)
			(xy 240.853109 -140.022808) (xy 240.907952 -140.012678) (xy 240.963686 -140.010641) (xy 241.019123 -140.016741)
			(xy 241.07308 -140.030847) (xy 241.124409 -140.052659) (xy 241.172015 -140.081713) (xy 241.214883 -140.117388)
			(xy 241.2521 -140.158925) (xy 241.282873 -140.205438) (xy 241.306545 -140.255935) (xy 241.322613 -140.309342)
			(xy 241.330733 -140.364518) (xy 241.331242 -140.392404) (xy 241.330733 -140.42029) (xy 241.322613 -140.475466)
			(xy 241.306545 -140.528873) (xy 241.282873 -140.57937) (xy 241.2521 -140.625883) (xy 241.214883 -140.66742)
			(xy 241.172015 -140.703095) (xy 241.124409 -140.732149) (xy 241.07308 -140.753961) (xy 241.019123 -140.768067)
			(xy 240.963686 -140.774167) (xy 240.907952 -140.77213) (xy 240.853109 -140.762) (xy 240.800325 -140.743993)
			(xy 240.750725 -140.718492) (xy 240.705367 -140.686041) (xy 240.665218 -140.647332) (xy 240.631132 -140.603189)
			(xy 240.603836 -140.554554) (xy 240.583913 -140.502463) (xy 240.571787 -140.448026) (xy 240.567716 -140.392404)
			(xy 239.139476 -140.392404) (xy 239.138986 -140.420035) (xy 239.131017 -140.474719) (xy 239.115234 -140.527679)
			(xy 239.091966 -140.577803) (xy 239.077246 -140.601192) (xy 239.071397 -140.611251) (xy 239.068531 -140.634317)
			(xy 239.076052 -140.656311) (xy 239.08385 -140.664946) (xy 239.465455 -141.046551) (xy 242.955054 -141.046551)
			(xy 242.955054 -140.992049) (xy 242.96281 -140.938101) (xy 242.978164 -140.885806) (xy 243.000804 -140.836228)
			(xy 243.030269 -140.790376) (xy 243.065959 -140.749184) (xy 243.107147 -140.71349) (xy 243.152996 -140.684021)
			(xy 243.202572 -140.661377) (xy 243.254865 -140.646017) (xy 243.308813 -140.638256) (xy 243.336064 -140.637768)
			(xy 243.362379 -140.638203) (xy 243.414508 -140.645446) (xy 243.465151 -140.659772) (xy 243.51335 -140.680911)
			(xy 243.558193 -140.708462) (xy 243.598832 -140.741905) (xy 243.616988 -140.760958) (xy 243.624518 -140.76835)
			(xy 243.643791 -140.776881) (xy 243.654326 -140.777468) (xy 243.729002 -140.777468) (xy 243.739555 -140.776963)
			(xy 243.75885 -140.768412) (xy 243.76634 -140.760958) (xy 243.784475 -140.741882) (xy 243.82511 -140.708428)
			(xy 243.869955 -140.680873) (xy 243.91816 -140.659738) (xy 243.96881 -140.645425) (xy 244.020947 -140.638204)
			(xy 244.047264 -140.637768) (xy 244.074517 -140.638277) (xy 244.128468 -140.646029) (xy 244.180767 -140.661381)
			(xy 244.230349 -140.68402) (xy 244.276203 -140.713485) (xy 244.317398 -140.749177) (xy 244.353093 -140.790368)
			(xy 244.382563 -140.83622) (xy 244.405206 -140.885799) (xy 244.420563 -140.938097) (xy 244.428321 -140.992047)
			(xy 244.428321 -141.046553) (xy 244.420563 -141.100503) (xy 244.405206 -141.152801) (xy 244.382563 -141.20238)
			(xy 244.353093 -141.248232) (xy 244.317398 -141.289423) (xy 244.276203 -141.325115) (xy 244.230349 -141.35458)
			(xy 244.180767 -141.377219) (xy 244.128468 -141.392571) (xy 244.074517 -141.400323) (xy 244.047264 -141.400784)
			(xy 244.020949 -141.400346) (xy 243.968819 -141.393106) (xy 243.918176 -141.378781) (xy 243.869977 -141.357643)
			(xy 243.825134 -141.330092) (xy 243.784496 -141.296648) (xy 243.76634 -141.277594) (xy 243.758806 -141.270207)
			(xy 243.739535 -141.261675) (xy 243.729002 -141.261084) (xy 243.654326 -141.261084) (xy 243.643777 -141.261619)
			(xy 243.624482 -141.270151) (xy 243.616988 -141.277594) (xy 243.59883 -141.296647) (xy 243.558201 -141.330105)
			(xy 243.513361 -141.357664) (xy 243.465161 -141.378803) (xy 243.414514 -141.393121) (xy 243.36238 -141.400346)
			(xy 243.336064 -141.400784) (xy 243.308813 -141.400344) (xy 243.254865 -141.392583) (xy 243.202572 -141.377223)
			(xy 243.152996 -141.354579) (xy 243.107147 -141.32511) (xy 243.065959 -141.289416) (xy 243.030269 -141.248224)
			(xy 243.000804 -141.202372) (xy 242.978164 -141.152794) (xy 242.96281 -141.100499) (xy 242.955054 -141.046551)
			(xy 239.465455 -141.046551) (xy 240.039906 -141.621002) (xy 240.062808 -141.644563) (xy 240.10377 -141.695941)
			(xy 240.138724 -141.751582) (xy 240.167228 -141.810786) (xy 240.188926 -141.872809) (xy 240.203543 -141.936872)
			(xy 240.210897 -142.002168) (xy 240.211356 -142.035022) (xy 240.211356 -143.078551) (xy 242.955054 -143.078551)
			(xy 242.955054 -143.024049) (xy 242.96281 -142.970101) (xy 242.978164 -142.917806) (xy 243.000804 -142.868228)
			(xy 243.030269 -142.822376) (xy 243.065959 -142.781184) (xy 243.107147 -142.74549) (xy 243.152996 -142.716021)
			(xy 243.202572 -142.693377) (xy 243.254865 -142.678017) (xy 243.308813 -142.670256) (xy 243.336064 -142.669768)
			(xy 243.362379 -142.670203) (xy 243.414508 -142.677446) (xy 243.465151 -142.691772) (xy 243.51335 -142.712911)
			(xy 243.558193 -142.740462) (xy 243.598832 -142.773905) (xy 243.616988 -142.792958) (xy 243.624518 -142.80035)
			(xy 243.643791 -142.808881) (xy 243.654326 -142.809468) (xy 243.729002 -142.809468) (xy 243.739555 -142.808963)
			(xy 243.75885 -142.800412) (xy 243.76634 -142.792958) (xy 243.784475 -142.773882) (xy 243.82511 -142.740428)
			(xy 243.869955 -142.712873) (xy 243.91816 -142.691738) (xy 243.96881 -142.677425) (xy 244.020947 -142.670204)
			(xy 244.047264 -142.669768) (xy 244.074517 -142.670277) (xy 244.128468 -142.678029) (xy 244.180767 -142.693381)
			(xy 244.230349 -142.71602) (xy 244.276203 -142.745485) (xy 244.317398 -142.781177) (xy 244.353093 -142.822368)
			(xy 244.382563 -142.86822) (xy 244.405206 -142.917799) (xy 244.420563 -142.970097) (xy 244.428321 -143.024047)
			(xy 244.428321 -143.078553) (xy 244.420563 -143.132503) (xy 244.405206 -143.184801) (xy 244.382563 -143.23438)
			(xy 244.353093 -143.280232) (xy 244.317398 -143.321423) (xy 244.276203 -143.357115) (xy 244.230349 -143.38658)
			(xy 244.180767 -143.409219) (xy 244.128468 -143.424571) (xy 244.074517 -143.432323) (xy 244.047264 -143.432784)
			(xy 244.020949 -143.432346) (xy 243.968819 -143.425106) (xy 243.918176 -143.410781) (xy 243.869977 -143.389643)
			(xy 243.825134 -143.362092) (xy 243.784496 -143.328648) (xy 243.76634 -143.309594) (xy 243.758806 -143.302207)
			(xy 243.739535 -143.293675) (xy 243.729002 -143.293084) (xy 243.654326 -143.293084) (xy 243.643777 -143.293619)
			(xy 243.624482 -143.302151) (xy 243.616988 -143.309594) (xy 243.59883 -143.328647) (xy 243.558201 -143.362105)
			(xy 243.513361 -143.389664) (xy 243.465161 -143.410803) (xy 243.414514 -143.425121) (xy 243.36238 -143.432346)
			(xy 243.336064 -143.432784) (xy 243.308813 -143.432344) (xy 243.254865 -143.424583) (xy 243.202572 -143.409223)
			(xy 243.152996 -143.386579) (xy 243.107147 -143.35711) (xy 243.065959 -143.321416) (xy 243.030269 -143.280224)
			(xy 243.000804 -143.234372) (xy 242.978164 -143.184794) (xy 242.96281 -143.132499) (xy 242.955054 -143.078551)
			(xy 240.211356 -143.078551) (xy 240.211356 -145.110551) (xy 242.955054 -145.110551) (xy 242.955054 -145.056049)
			(xy 242.96281 -145.002101) (xy 242.978164 -144.949806) (xy 243.000804 -144.900228) (xy 243.030269 -144.854376)
			(xy 243.065959 -144.813184) (xy 243.107147 -144.77749) (xy 243.152996 -144.748021) (xy 243.202572 -144.725377)
			(xy 243.254865 -144.710017) (xy 243.308813 -144.702256) (xy 243.336064 -144.701768) (xy 243.362379 -144.702203)
			(xy 243.414508 -144.709446) (xy 243.465151 -144.723772) (xy 243.51335 -144.744911) (xy 243.558193 -144.772462)
			(xy 243.598832 -144.805905) (xy 243.616988 -144.824958) (xy 243.624518 -144.83235) (xy 243.643791 -144.840881)
			(xy 243.654326 -144.841468) (xy 243.729002 -144.841468) (xy 243.739555 -144.840963) (xy 243.75885 -144.832412)
			(xy 243.76634 -144.824958) (xy 243.784475 -144.805882) (xy 243.82511 -144.772428) (xy 243.869955 -144.744873)
			(xy 243.91816 -144.723738) (xy 243.96881 -144.709425) (xy 244.020947 -144.702204) (xy 244.047264 -144.701768)
			(xy 244.074517 -144.702277) (xy 244.128468 -144.710029) (xy 244.180767 -144.725381) (xy 244.230349 -144.74802)
			(xy 244.276203 -144.777485) (xy 244.317398 -144.813177) (xy 244.353093 -144.854368) (xy 244.382563 -144.90022)
			(xy 244.405206 -144.949799) (xy 244.406511 -144.954244) (xy 250.138946 -144.954244) (xy 250.139519 -144.926996)
			(xy 250.147268 -144.873054) (xy 250.162616 -144.820764) (xy 250.185248 -144.77119) (xy 250.214706 -144.725341)
			(xy 250.250388 -144.684152) (xy 250.291569 -144.64846) (xy 250.337411 -144.618991) (xy 250.386979 -144.596347)
			(xy 250.439266 -144.580988) (xy 250.493206 -144.573225) (xy 250.520454 -144.572736) (xy 250.549228 -144.573258)
			(xy 250.606123 -144.581908) (xy 250.661074 -144.599005) (xy 250.712834 -144.624159) (xy 250.76023 -144.656801)
			(xy 250.781566 -144.676114) (xy 250.78944 -144.68348) (xy 250.809252 -144.690592) (xy 250.905518 -144.683226)
			(xy 250.924314 -144.67332) (xy 250.930918 -144.664938) (xy 250.949154 -144.642763) (xy 250.991086 -144.603551)
			(xy 251.03842 -144.571064) (xy 251.090085 -144.546034) (xy 251.144918 -144.529026) (xy 251.201679 -144.520423)
			(xy 251.230384 -144.519904) (xy 251.257637 -144.52037) (xy 251.311588 -144.528125) (xy 251.363887 -144.54348)
			(xy 251.413468 -144.566121) (xy 251.459322 -144.595589) (xy 251.500515 -144.631282) (xy 251.536209 -144.672475)
			(xy 251.565677 -144.718329) (xy 251.588319 -144.767909) (xy 251.603674 -144.820208) (xy 251.611429 -144.874159)
			(xy 251.611892 -144.901412) (xy 251.611444 -144.928315) (xy 251.603871 -144.981586) (xy 251.588889 -145.033265)
			(xy 251.566797 -145.082327) (xy 251.538032 -145.127799) (xy 251.503165 -145.16878) (xy 251.462887 -145.204457)
			(xy 251.440696 -145.219674) (xy 251.429774 -145.226786) (xy 251.417836 -145.249646) (xy 251.419868 -145.361914)
			(xy 251.432822 -145.384266) (xy 251.443998 -145.391124) (xy 251.467599 -145.406047) (xy 251.510551 -145.441725)
			(xy 251.547844 -145.483283) (xy 251.578682 -145.529833) (xy 251.602406 -145.58038) (xy 251.618508 -145.633846)
			(xy 251.626646 -145.689087) (xy 251.627132 -145.717006) (xy 251.626677 -145.744) (xy 251.61907 -145.797448)
			(xy 251.604009 -145.849292) (xy 251.581793 -145.898496) (xy 251.552867 -145.94408) (xy 251.535692 -145.96491)
			(xy 251.52858 -145.973038) (xy 251.522484 -145.993612) (xy 251.533406 -146.078956) (xy 251.535196 -146.089497)
			(xy 251.546239 -146.107781) (xy 251.554742 -146.114262) (xy 251.575947 -146.129649) (xy 251.614401 -146.16523)
			(xy 251.647622 -146.205741) (xy 251.674984 -146.250418) (xy 251.695972 -146.298421) (xy 251.71019 -146.348845)
			(xy 251.717371 -146.400741) (xy 251.71781 -146.426936) (xy 251.717324 -146.454187) (xy 251.709568 -146.508135)
			(xy 251.694213 -146.56043) (xy 251.671571 -146.610007) (xy 251.642105 -146.655857) (xy 251.606414 -146.697048)
			(xy 251.565223 -146.732739) (xy 251.519373 -146.762205) (xy 251.469796 -146.784847) (xy 251.417501 -146.800202)
			(xy 251.363553 -146.807958) (xy 251.309051 -146.807958) (xy 251.255103 -146.800202) (xy 251.202808 -146.784847)
			(xy 251.153231 -146.762205) (xy 251.107381 -146.732739) (xy 251.06619 -146.697048) (xy 251.030499 -146.655857)
			(xy 251.001033 -146.610007) (xy 250.978391 -146.56043) (xy 250.963036 -146.508135) (xy 250.95528 -146.454187)
			(xy 250.954794 -146.426936) (xy 250.955291 -146.399944) (xy 250.96289 -146.346498) (xy 250.977943 -146.294656)
			(xy 251.000149 -146.245451) (xy 251.029064 -146.199864) (xy 251.046234 -146.179032) (xy 251.053346 -146.170904)
			(xy 251.059442 -146.15033) (xy 251.04852 -146.064986) (xy 251.046749 -146.054441) (xy 251.035691 -146.036159)
			(xy 251.027184 -146.02968) (xy 251.002883 -146.012068) (xy 250.959624 -145.970472) (xy 250.941078 -145.946876)
			(xy 250.935236 -145.939002) (xy 250.91771 -145.928588) (xy 250.827286 -145.91538) (xy 250.807982 -145.920206)
			(xy 250.800108 -145.926048) (xy 250.799854 -145.926048) (xy 250.775111 -145.943553) (xy 250.721258 -145.971356)
			(xy 250.663686 -145.990292) (xy 250.603843 -145.999883) (xy 250.57354 -146.00047) (xy 250.546286 -146.000007)
			(xy 250.492333 -145.992255) (xy 250.440033 -145.976902) (xy 250.390451 -145.954261) (xy 250.344596 -145.924794)
			(xy 250.303401 -145.8891) (xy 250.267707 -145.847906) (xy 250.23824 -145.802051) (xy 250.215599 -145.752469)
			(xy 250.200246 -145.700168) (xy 250.192493 -145.646216) (xy 250.192032 -145.618962) (xy 250.192467 -145.592928)
			(xy 250.199559 -145.541345) (xy 250.213591 -145.491203) (xy 250.234305 -145.443433) (xy 250.261315 -145.398918)
			(xy 250.277376 -145.378424) (xy 250.283116 -145.370666) (xy 250.288858 -145.352256) (xy 250.288552 -145.34261)
			(xy 250.282202 -145.262854) (xy 250.273566 -145.245074) (xy 250.2662 -145.238724) (xy 250.246561 -145.220536)
			(xy 250.212035 -145.179632) (xy 250.183562 -145.134305) (xy 250.161703 -145.085445) (xy 250.146885 -145.034009)
			(xy 250.1394 -144.981008) (xy 250.138946 -144.954244) (xy 244.406511 -144.954244) (xy 244.420563 -145.002097)
			(xy 244.428321 -145.056047) (xy 244.428321 -145.110553) (xy 244.420563 -145.164503) (xy 244.405206 -145.216801)
			(xy 244.382563 -145.26638) (xy 244.353093 -145.312232) (xy 244.317398 -145.353423) (xy 244.276203 -145.389115)
			(xy 244.230349 -145.41858) (xy 244.180767 -145.441219) (xy 244.128468 -145.456571) (xy 244.074517 -145.464323)
			(xy 244.047264 -145.464784) (xy 244.020949 -145.464346) (xy 243.968819 -145.457106) (xy 243.918176 -145.442781)
			(xy 243.869977 -145.421643) (xy 243.825134 -145.394092) (xy 243.784496 -145.360648) (xy 243.76634 -145.341594)
			(xy 243.758806 -145.334207) (xy 243.739535 -145.325675) (xy 243.729002 -145.325084) (xy 243.654326 -145.325084)
			(xy 243.643777 -145.325619) (xy 243.624482 -145.334151) (xy 243.616988 -145.341594) (xy 243.59883 -145.360647)
			(xy 243.558201 -145.394105) (xy 243.513361 -145.421664) (xy 243.465161 -145.442803) (xy 243.414514 -145.457121)
			(xy 243.36238 -145.464346) (xy 243.336064 -145.464784) (xy 243.308813 -145.464344) (xy 243.254865 -145.456583)
			(xy 243.202572 -145.441223) (xy 243.152996 -145.418579) (xy 243.107147 -145.38911) (xy 243.065959 -145.353416)
			(xy 243.030269 -145.312224) (xy 243.000804 -145.266372) (xy 242.978164 -145.216794) (xy 242.96281 -145.164499)
			(xy 242.955054 -145.110551) (xy 240.211356 -145.110551) (xy 240.211356 -146.032728) (xy 240.210909 -146.065582)
			(xy 240.203543 -146.130876) (xy 240.188917 -146.194936) (xy 240.167216 -146.256957) (xy 240.138711 -146.31616)
			(xy 240.103761 -146.371802) (xy 240.062805 -146.423185) (xy 240.039906 -146.446748) (xy 239.571567 -146.91487)
			(xy 251.816106 -146.91487) (xy 251.820177 -146.859248) (xy 251.832303 -146.804811) (xy 251.852226 -146.75272)
			(xy 251.879522 -146.704085) (xy 251.913608 -146.659942) (xy 251.953757 -146.621233) (xy 251.999115 -146.588782)
			(xy 252.048715 -146.563281) (xy 252.101499 -146.545274) (xy 252.156342 -146.535144) (xy 252.212076 -146.533107)
			(xy 252.267513 -146.539207) (xy 252.32147 -146.553313) (xy 252.372799 -146.575125) (xy 252.420405 -146.604179)
			(xy 252.463273 -146.639854) (xy 252.50049 -146.681391) (xy 252.531263 -146.727904) (xy 252.554935 -146.778401)
			(xy 252.571003 -146.831808) (xy 252.579123 -146.886984) (xy 252.579632 -146.91487) (xy 252.579123 -146.942756)
			(xy 252.571003 -146.997932) (xy 252.554935 -147.051339) (xy 252.549729 -147.062444) (xy 253.19431 -147.062444)
			(xy 253.198381 -147.006822) (xy 253.210507 -146.952385) (xy 253.23043 -146.900294) (xy 253.257726 -146.851659)
			(xy 253.291812 -146.807516) (xy 253.331961 -146.768807) (xy 253.377319 -146.736356) (xy 253.426919 -146.710855)
			(xy 253.479703 -146.692848) (xy 253.534546 -146.682718) (xy 253.59028 -146.680681) (xy 253.645717 -146.686781)
			(xy 253.699674 -146.700887) (xy 253.751003 -146.722699) (xy 253.798609 -146.751753) (xy 253.841477 -146.787428)
			(xy 253.878694 -146.828965) (xy 253.909467 -146.875478) (xy 253.933139 -146.925975) (xy 253.949207 -146.979382)
			(xy 253.957327 -147.034558) (xy 253.957836 -147.062444) (xy 253.957327 -147.09033) (xy 253.949207 -147.145506)
			(xy 253.933139 -147.198913) (xy 253.909467 -147.24941) (xy 253.878694 -147.295923) (xy 253.841477 -147.33746)
			(xy 253.798609 -147.373135) (xy 253.751003 -147.402189) (xy 253.699674 -147.424001) (xy 253.645717 -147.438107)
			(xy 253.59028 -147.444207) (xy 253.534546 -147.44217) (xy 253.479703 -147.43204) (xy 253.426919 -147.414033)
			(xy 253.377319 -147.388532) (xy 253.331961 -147.356081) (xy 253.291812 -147.317372) (xy 253.257726 -147.273229)
			(xy 253.23043 -147.224594) (xy 253.210507 -147.172503) (xy 253.198381 -147.118066) (xy 253.19431 -147.062444)
			(xy 252.549729 -147.062444) (xy 252.531263 -147.101836) (xy 252.50049 -147.148349) (xy 252.463273 -147.189886)
			(xy 252.420405 -147.225561) (xy 252.372799 -147.254615) (xy 252.32147 -147.276427) (xy 252.267513 -147.290533)
			(xy 252.212076 -147.296633) (xy 252.156342 -147.294596) (xy 252.101499 -147.284466) (xy 252.048715 -147.266459)
			(xy 251.999115 -147.240958) (xy 251.953757 -147.208507) (xy 251.913608 -147.169798) (xy 251.879522 -147.125655)
			(xy 251.852226 -147.07702) (xy 251.832303 -147.024929) (xy 251.820177 -146.970492) (xy 251.816106 -146.91487)
			(xy 239.571567 -146.91487) (xy 239.49279 -146.99361) (xy 239.485952 -147.001011) (xy 239.478231 -147.01961)
			(xy 239.477804 -147.029678) (xy 239.477804 -147.657656) (xy 243.350443 -147.657656) (xy 243.350443 -147.603144)
			(xy 243.358201 -147.549188) (xy 243.37356 -147.496885) (xy 243.396206 -147.447301) (xy 243.425679 -147.401444)
			(xy 243.461379 -147.360249) (xy 243.502578 -147.324554) (xy 243.548437 -147.295086) (xy 243.598024 -147.272445)
			(xy 243.650329 -147.257092) (xy 243.704286 -147.24934) (xy 243.731542 -147.24888) (xy 243.757857 -147.249326)
			(xy 243.809986 -147.256566) (xy 243.860629 -147.27089) (xy 243.908827 -147.292026) (xy 243.95367 -147.319576)
			(xy 243.99431 -147.353017) (xy 244.012466 -147.37207) (xy 244.020002 -147.379454) (xy 244.039271 -147.38799)
			(xy 244.049804 -147.38858) (xy 244.12448 -147.38858) (xy 244.135031 -147.38806) (xy 244.154327 -147.379519)
			(xy 244.161818 -147.37207) (xy 244.181638 -147.351282) (xy 244.22641 -147.315307) (xy 244.276068 -147.286447)
			(xy 244.32949 -147.265354) (xy 244.385469 -147.252505) (xy 244.442742 -147.24819) (xy 244.500015 -147.252505)
			(xy 244.555994 -147.265354) (xy 244.609416 -147.286447) (xy 244.659074 -147.315307) (xy 244.703846 -147.351282)
			(xy 244.723666 -147.37207) (xy 244.731202 -147.379454) (xy 244.750471 -147.38799) (xy 244.761004 -147.38858)
			(xy 244.83568 -147.38858) (xy 244.846231 -147.38806) (xy 244.865527 -147.379519) (xy 244.873018 -147.37207)
			(xy 244.891166 -147.353007) (xy 244.931798 -147.319552) (xy 244.97664 -147.291994) (xy 245.024842 -147.270857)
			(xy 245.075491 -147.256542) (xy 245.127626 -147.249318) (xy 245.153942 -147.24888) (xy 245.18119 -147.249393)
			(xy 245.235132 -147.257154) (xy 245.28742 -147.272512) (xy 245.33699 -147.295155) (xy 245.382834 -147.324622)
			(xy 245.424018 -147.360312) (xy 245.459703 -147.4015) (xy 245.489165 -147.447347) (xy 245.511802 -147.49692)
			(xy 245.527155 -147.549209) (xy 245.53491 -147.603152) (xy 245.53491 -147.657648) (xy 245.527155 -147.711591)
			(xy 245.511802 -147.76388) (xy 245.489165 -147.813453) (xy 245.459703 -147.8593) (xy 245.424018 -147.900488)
			(xy 245.382834 -147.936178) (xy 245.33699 -147.965645) (xy 245.28742 -147.988288) (xy 245.235132 -148.003646)
			(xy 245.18119 -148.011407) (xy 245.153942 -148.011896) (xy 245.127627 -148.011469) (xy 245.075496 -148.004226)
			(xy 245.024853 -147.989899) (xy 244.976654 -147.968759) (xy 244.931811 -147.941206) (xy 244.891174 -147.907761)
			(xy 244.873018 -147.888706) (xy 244.865491 -147.881311) (xy 244.846215 -147.872783) (xy 244.83568 -147.872196)
			(xy 244.761004 -147.872196) (xy 244.750453 -147.872715) (xy 244.731158 -147.881257) (xy 244.723666 -147.888706)
			(xy 244.703846 -147.909494) (xy 244.659074 -147.945469) (xy 244.609416 -147.974329) (xy 244.555994 -147.995422)
			(xy 244.500015 -148.008271) (xy 244.442742 -148.012586) (xy 244.385469 -148.008271) (xy 244.32949 -147.995422)
			(xy 244.276068 -147.974329) (xy 244.22641 -147.945469) (xy 244.181638 -147.909494) (xy 244.161818 -147.888706)
			(xy 244.154291 -147.881311) (xy 244.135015 -147.872783) (xy 244.12448 -147.872196) (xy 244.049804 -147.872196)
			(xy 244.039253 -147.872715) (xy 244.019958 -147.881257) (xy 244.012466 -147.888706) (xy 243.994321 -147.907772)
			(xy 243.953689 -147.941228) (xy 243.908846 -147.968786) (xy 243.860644 -147.989922) (xy 243.809994 -148.004237)
			(xy 243.757859 -148.011459) (xy 243.731542 -148.011896) (xy 243.704286 -148.01146) (xy 243.650329 -148.003708)
			(xy 243.598024 -147.988355) (xy 243.548437 -147.965714) (xy 243.502578 -147.936246) (xy 243.461379 -147.900551)
			(xy 243.425679 -147.859356) (xy 243.396206 -147.813499) (xy 243.37356 -147.763915) (xy 243.358201 -147.711612)
			(xy 243.350443 -147.657656) (xy 239.477804 -147.657656) (xy 239.477804 -148.017738) (xy 248.177556 -148.017738)
			(xy 248.181627 -147.962116) (xy 248.193753 -147.907679) (xy 248.213676 -147.855588) (xy 248.240972 -147.806953)
			(xy 248.275058 -147.76281) (xy 248.315207 -147.724101) (xy 248.360565 -147.69165) (xy 248.410165 -147.666149)
			(xy 248.462949 -147.648142) (xy 248.517792 -147.638012) (xy 248.573526 -147.635975) (xy 248.628963 -147.642075)
			(xy 248.68292 -147.656181) (xy 248.734249 -147.677993) (xy 248.781855 -147.707047) (xy 248.824723 -147.742722)
			(xy 248.86194 -147.784259) (xy 248.892713 -147.830772) (xy 248.916385 -147.881269) (xy 248.932453 -147.934676)
			(xy 248.940573 -147.989852) (xy 248.941082 -148.017738) (xy 248.940573 -148.045624) (xy 248.932453 -148.1008)
			(xy 248.916385 -148.154207) (xy 248.892713 -148.204704) (xy 248.86194 -148.251217) (xy 248.824723 -148.292754)
			(xy 248.781855 -148.328429) (xy 248.734249 -148.357483) (xy 248.68292 -148.379295) (xy 248.628963 -148.393401)
			(xy 248.573526 -148.399501) (xy 248.517792 -148.397464) (xy 248.462949 -148.387334) (xy 248.410165 -148.369327)
			(xy 248.360565 -148.343826) (xy 248.315207 -148.311375) (xy 248.275058 -148.272666) (xy 248.240972 -148.228523)
			(xy 248.213676 -148.179888) (xy 248.193753 -148.127797) (xy 248.181627 -148.07336) (xy 248.177556 -148.017738)
			(xy 239.477804 -148.017738) (xy 239.477804 -149.830282) (xy 239.478211 -149.840354) (xy 239.485942 -149.858953)
			(xy 239.49279 -149.86635) (xy 239.49533 -149.86889) (xy 239.515573 -149.853453) (xy 239.559396 -149.827547)
			(xy 239.606279 -149.807706) (xy 239.655385 -149.794284) (xy 239.705842 -149.787519) (xy 239.731296 -149.787102)
			(xy 239.73155 -149.787102) (xy 239.758802 -149.787602) (xy 239.812752 -149.795352) (xy 239.86505 -149.810702)
			(xy 239.914631 -149.83334) (xy 239.960484 -149.862804) (xy 240.001678 -149.898494) (xy 240.037372 -149.939683)
			(xy 240.066841 -149.985534) (xy 240.089484 -150.035112) (xy 240.104839 -150.087409) (xy 240.112595 -150.141358)
			(xy 240.113058 -150.16861) (xy 240.113058 -150.168864) (xy 240.112596 -150.195664) (xy 240.112569 -150.195854)
			(xy 243.350465 -150.195854) (xy 243.350465 -150.141346) (xy 243.358223 -150.087393) (xy 243.373581 -150.035093)
			(xy 243.396226 -149.985511) (xy 243.425697 -149.939657) (xy 243.461394 -149.898465) (xy 243.502591 -149.862772)
			(xy 243.548448 -149.833306) (xy 243.598032 -149.810666) (xy 243.650334 -149.795314) (xy 243.704288 -149.787562)
			(xy 243.731542 -149.787102) (xy 243.757857 -149.787541) (xy 243.809987 -149.794781) (xy 243.86063 -149.809106)
			(xy 243.908829 -149.830244) (xy 243.953672 -149.857795) (xy 243.99431 -149.891238) (xy 244.012466 -149.910292)
			(xy 244.019999 -149.917679) (xy 244.03927 -149.926212) (xy 244.049804 -149.926802) (xy 244.12448 -149.926802)
			(xy 244.13503 -149.926275) (xy 244.154325 -149.917738) (xy 244.161818 -149.910292) (xy 244.181638 -149.889504)
			(xy 244.22641 -149.853529) (xy 244.276068 -149.824669) (xy 244.32949 -149.803576) (xy 244.385469 -149.790727)
			(xy 244.442742 -149.786412) (xy 244.500015 -149.790727) (xy 244.555994 -149.803576) (xy 244.609416 -149.824669)
			(xy 244.659074 -149.853529) (xy 244.703846 -149.889504) (xy 244.723666 -149.910292) (xy 244.731199 -149.917679)
			(xy 244.75047 -149.926212) (xy 244.761004 -149.926802) (xy 244.83568 -149.926802) (xy 244.84623 -149.926275)
			(xy 244.865525 -149.917738) (xy 244.873018 -149.910292) (xy 244.89117 -149.891233) (xy 244.931801 -149.857777)
			(xy 244.976642 -149.830218) (xy 245.024843 -149.80908) (xy 245.075491 -149.794764) (xy 245.127626 -149.78754)
			(xy 245.153942 -149.787102) (xy 245.181192 -149.787571) (xy 245.235137 -149.795332) (xy 245.287428 -149.810691)
			(xy 245.337001 -149.833336) (xy 245.382847 -149.862804) (xy 245.424034 -149.898496) (xy 245.459721 -149.939686)
			(xy 245.489185 -149.985536) (xy 245.511823 -150.035112) (xy 245.520145 -150.063454) (xy 248.03811 -150.063454)
			(xy 248.042181 -150.007832) (xy 248.054307 -149.953395) (xy 248.07423 -149.901304) (xy 248.101526 -149.852669)
			(xy 248.135612 -149.808526) (xy 248.175761 -149.769817) (xy 248.221119 -149.737366) (xy 248.270719 -149.711865)
			(xy 248.323503 -149.693858) (xy 248.378346 -149.683728) (xy 248.43408 -149.681691) (xy 248.489517 -149.687791)
			(xy 248.543474 -149.701897) (xy 248.594803 -149.723709) (xy 248.642409 -149.752763) (xy 248.685277 -149.788438)
			(xy 248.722494 -149.829975) (xy 248.753267 -149.876488) (xy 248.776939 -149.926985) (xy 248.793007 -149.980392)
			(xy 248.801127 -150.035568) (xy 248.801636 -150.063454) (xy 248.801127 -150.09134) (xy 248.793007 -150.146516)
			(xy 248.776939 -150.199923) (xy 248.753267 -150.25042) (xy 248.722494 -150.296933) (xy 248.685277 -150.33847)
			(xy 248.642409 -150.374145) (xy 248.594803 -150.403199) (xy 248.543474 -150.425011) (xy 248.489517 -150.439117)
			(xy 248.43408 -150.445217) (xy 248.378346 -150.44318) (xy 248.323503 -150.43305) (xy 248.270719 -150.415043)
			(xy 248.221119 -150.389542) (xy 248.175761 -150.357091) (xy 248.135612 -150.318382) (xy 248.101526 -150.274239)
			(xy 248.07423 -150.225604) (xy 248.054307 -150.173513) (xy 248.042181 -150.119076) (xy 248.03811 -150.063454)
			(xy 245.520145 -150.063454) (xy 245.527177 -150.087404) (xy 245.534932 -150.14135) (xy 245.534932 -150.19585)
			(xy 245.527177 -150.249796) (xy 245.511823 -150.302088) (xy 245.489185 -150.351664) (xy 245.459721 -150.397514)
			(xy 245.424034 -150.438704) (xy 245.382847 -150.474396) (xy 245.337001 -150.503864) (xy 245.287428 -150.526509)
			(xy 245.235137 -150.541868) (xy 245.181192 -150.549629) (xy 245.153942 -150.550118) (xy 245.127627 -150.549683)
			(xy 245.075497 -150.542441) (xy 245.024854 -150.528115) (xy 244.976655 -150.506976) (xy 244.931813 -150.479425)
			(xy 244.891174 -150.445982) (xy 244.873018 -150.426928) (xy 244.865488 -150.419536) (xy 244.846215 -150.411005)
			(xy 244.83568 -150.410418) (xy 244.761004 -150.410418) (xy 244.750452 -150.410931) (xy 244.731157 -150.419477)
			(xy 244.723666 -150.426928) (xy 244.703846 -150.447716) (xy 244.659074 -150.483691) (xy 244.609416 -150.512551)
			(xy 244.555994 -150.533644) (xy 244.500015 -150.546493) (xy 244.442742 -150.550808) (xy 244.385469 -150.546493)
			(xy 244.32949 -150.533644) (xy 244.276068 -150.512551) (xy 244.22641 -150.483691) (xy 244.181638 -150.447716)
			(xy 244.161818 -150.426928) (xy 244.154288 -150.419536) (xy 244.135015 -150.411005) (xy 244.12448 -150.410418)
			(xy 244.049804 -150.410418) (xy 244.039252 -150.410931) (xy 244.019957 -150.419477) (xy 244.012466 -150.426928)
			(xy 243.994325 -150.445998) (xy 243.953692 -150.479453) (xy 243.908848 -150.507009) (xy 243.860645 -150.528145)
			(xy 243.809995 -150.542459) (xy 243.757859 -150.549681) (xy 243.731542 -150.550118) (xy 243.704288 -150.549638)
			(xy 243.650334 -150.541886) (xy 243.598032 -150.526534) (xy 243.548448 -150.503894) (xy 243.502591 -150.474428)
			(xy 243.461394 -150.438735) (xy 243.425697 -150.397543) (xy 243.396226 -150.351689) (xy 243.373581 -150.302107)
			(xy 243.358223 -150.249807) (xy 243.350465 -150.195854) (xy 240.112569 -150.195854) (xy 240.105068 -150.248732)
			(xy 240.090196 -150.300228) (xy 240.068273 -150.34914) (xy 240.054384 -150.372064) (xy 240.04873 -150.382083)
			(xy 240.046104 -150.404907) (xy 240.05372 -150.426583) (xy 240.061496 -150.435056) (xy 241.297574 -151.67102)
			(xy 247.99366 -151.67102) (xy 247.997731 -151.615398) (xy 248.009857 -151.560961) (xy 248.02978 -151.50887)
			(xy 248.057076 -151.460235) (xy 248.091162 -151.416092) (xy 248.131311 -151.377383) (xy 248.176669 -151.344932)
			(xy 248.226269 -151.319431) (xy 248.279053 -151.301424) (xy 248.333896 -151.291294) (xy 248.38963 -151.289257)
			(xy 248.445067 -151.295357) (xy 248.499024 -151.309463) (xy 248.550353 -151.331275) (xy 248.597959 -151.360329)
			(xy 248.640827 -151.396004) (xy 248.678044 -151.437541) (xy 248.708817 -151.484054) (xy 248.732489 -151.534551)
			(xy 248.748557 -151.587958) (xy 248.756677 -151.643134) (xy 248.757186 -151.67102) (xy 248.756713 -151.696928)
			(xy 249.00966 -151.696928) (xy 249.013731 -151.641306) (xy 249.025857 -151.586869) (xy 249.04578 -151.534778)
			(xy 249.073076 -151.486143) (xy 249.107162 -151.442) (xy 249.147311 -151.403291) (xy 249.192669 -151.37084)
			(xy 249.242269 -151.345339) (xy 249.295053 -151.327332) (xy 249.349896 -151.317202) (xy 249.40563 -151.315165)
			(xy 249.461067 -151.321265) (xy 249.515024 -151.335371) (xy 249.566353 -151.357183) (xy 249.613959 -151.386237)
			(xy 249.638435 -151.406606) (xy 250.236734 -151.406606) (xy 250.240805 -151.350984) (xy 250.252931 -151.296547)
			(xy 250.272854 -151.244456) (xy 250.30015 -151.195821) (xy 250.334236 -151.151678) (xy 250.374385 -151.112969)
			(xy 250.419743 -151.080518) (xy 250.469343 -151.055017) (xy 250.522127 -151.03701) (xy 250.57697 -151.02688)
			(xy 250.632704 -151.024843) (xy 250.688141 -151.030943) (xy 250.742098 -151.045049) (xy 250.793427 -151.066861)
			(xy 250.841033 -151.095915) (xy 250.883901 -151.13159) (xy 250.921118 -151.173127) (xy 250.951891 -151.21964)
			(xy 250.975563 -151.270137) (xy 250.991631 -151.323544) (xy 250.999751 -151.37872) (xy 251.00026 -151.406606)
			(xy 250.999751 -151.434492) (xy 250.991631 -151.489668) (xy 250.975563 -151.543075) (xy 250.957021 -151.582628)
			(xy 251.56236 -151.582628) (xy 251.566431 -151.527006) (xy 251.578557 -151.472569) (xy 251.59848 -151.420478)
			(xy 251.625776 -151.371843) (xy 251.659862 -151.3277) (xy 251.700011 -151.288991) (xy 251.745369 -151.25654)
			(xy 251.794969 -151.231039) (xy 251.847753 -151.213032) (xy 251.902596 -151.202902) (xy 251.95833 -151.200865)
			(xy 252.013767 -151.206965) (xy 252.067724 -151.221071) (xy 252.119053 -151.242883) (xy 252.166659 -151.271937)
			(xy 252.209527 -151.307612) (xy 252.246744 -151.349149) (xy 252.277517 -151.395662) (xy 252.301189 -151.446159)
			(xy 252.317257 -151.499566) (xy 252.325377 -151.554742) (xy 252.32564 -151.569166) (xy 253.07366 -151.569166)
			(xy 253.077731 -151.513544) (xy 253.089857 -151.459107) (xy 253.10978 -151.407016) (xy 253.137076 -151.358381)
			(xy 253.171162 -151.314238) (xy 253.211311 -151.275529) (xy 253.256669 -151.243078) (xy 253.306269 -151.217577)
			(xy 253.359053 -151.19957) (xy 253.413896 -151.18944) (xy 253.46963 -151.187403) (xy 253.525067 -151.193503)
			(xy 253.579024 -151.207609) (xy 253.630353 -151.229421) (xy 253.677959 -151.258475) (xy 253.720827 -151.29415)
			(xy 253.758044 -151.335687) (xy 253.788817 -151.3822) (xy 253.812489 -151.432697) (xy 253.828557 -151.486104)
			(xy 253.836677 -151.54128) (xy 253.837186 -151.569166) (xy 253.836677 -151.597052) (xy 253.828557 -151.652228)
			(xy 253.812489 -151.705635) (xy 253.788817 -151.756132) (xy 253.758044 -151.802645) (xy 253.720827 -151.844182)
			(xy 253.677959 -151.879857) (xy 253.630353 -151.908911) (xy 253.579024 -151.930723) (xy 253.525067 -151.944829)
			(xy 253.46963 -151.950929) (xy 253.413896 -151.948892) (xy 253.359053 -151.938762) (xy 253.306269 -151.920755)
			(xy 253.256669 -151.895254) (xy 253.211311 -151.862803) (xy 253.171162 -151.824094) (xy 253.137076 -151.779951)
			(xy 253.10978 -151.731316) (xy 253.089857 -151.679225) (xy 253.077731 -151.624788) (xy 253.07366 -151.569166)
			(xy 252.32564 -151.569166) (xy 252.325886 -151.582628) (xy 252.325377 -151.610514) (xy 252.317257 -151.66569)
			(xy 252.301189 -151.719097) (xy 252.277517 -151.769594) (xy 252.246744 -151.816107) (xy 252.209527 -151.857644)
			(xy 252.166659 -151.893319) (xy 252.119053 -151.922373) (xy 252.067724 -151.944185) (xy 252.013767 -151.958291)
			(xy 251.95833 -151.964391) (xy 251.902596 -151.962354) (xy 251.847753 -151.952224) (xy 251.794969 -151.934217)
			(xy 251.745369 -151.908716) (xy 251.700011 -151.876265) (xy 251.659862 -151.837556) (xy 251.625776 -151.793413)
			(xy 251.59848 -151.744778) (xy 251.578557 -151.692687) (xy 251.566431 -151.63825) (xy 251.56236 -151.582628)
			(xy 250.957021 -151.582628) (xy 250.951891 -151.593572) (xy 250.921118 -151.640085) (xy 250.883901 -151.681622)
			(xy 250.841033 -151.717297) (xy 250.793427 -151.746351) (xy 250.742098 -151.768163) (xy 250.688141 -151.782269)
			(xy 250.632704 -151.788369) (xy 250.57697 -151.786332) (xy 250.522127 -151.776202) (xy 250.469343 -151.758195)
			(xy 250.419743 -151.732694) (xy 250.374385 -151.700243) (xy 250.334236 -151.661534) (xy 250.30015 -151.617391)
			(xy 250.272854 -151.568756) (xy 250.252931 -151.516665) (xy 250.240805 -151.462228) (xy 250.236734 -151.406606)
			(xy 249.638435 -151.406606) (xy 249.656827 -151.421912) (xy 249.694044 -151.463449) (xy 249.724817 -151.509962)
			(xy 249.748489 -151.560459) (xy 249.764557 -151.613866) (xy 249.772677 -151.669042) (xy 249.773186 -151.696928)
			(xy 249.772677 -151.724814) (xy 249.764557 -151.77999) (xy 249.748489 -151.833397) (xy 249.724817 -151.883894)
			(xy 249.694044 -151.930407) (xy 249.656827 -151.971944) (xy 249.613959 -152.007619) (xy 249.566353 -152.036673)
			(xy 249.515024 -152.058485) (xy 249.461067 -152.072591) (xy 249.40563 -152.078691) (xy 249.349896 -152.076654)
			(xy 249.295053 -152.066524) (xy 249.242269 -152.048517) (xy 249.192669 -152.023016) (xy 249.147311 -151.990565)
			(xy 249.107162 -151.951856) (xy 249.073076 -151.907713) (xy 249.04578 -151.859078) (xy 249.025857 -151.806987)
			(xy 249.013731 -151.75255) (xy 249.00966 -151.696928) (xy 248.756713 -151.696928) (xy 248.756677 -151.698906)
			(xy 248.748557 -151.754082) (xy 248.732489 -151.807489) (xy 248.708817 -151.857986) (xy 248.678044 -151.904499)
			(xy 248.640827 -151.946036) (xy 248.597959 -151.981711) (xy 248.550353 -152.010765) (xy 248.499024 -152.032577)
			(xy 248.445067 -152.046683) (xy 248.38963 -152.052783) (xy 248.333896 -152.050746) (xy 248.279053 -152.040616)
			(xy 248.226269 -152.022609) (xy 248.176669 -151.997108) (xy 248.131311 -151.964657) (xy 248.091162 -151.925948)
			(xy 248.057076 -151.881805) (xy 248.02978 -151.83317) (xy 248.009857 -151.781079) (xy 247.997731 -151.726642)
			(xy 247.99366 -151.67102) (xy 241.297574 -151.67102) (xy 242.808252 -153.181558) (xy 242.815679 -153.188364)
			(xy 242.834258 -153.196105) (xy 242.84432 -153.196544) (xy 247.359678 -153.196544) (xy 247.395628 -153.197107)
			(xy 247.466987 -153.205918) (xy 247.53673 -153.223396) (xy 247.60381 -153.24928) (xy 247.667217 -153.283181)
			(xy 247.725998 -153.324587) (xy 247.779268 -153.372877) (xy 247.803162 -153.399744) (xy 247.811933 -153.408856)
			(xy 247.835507 -153.417926) (xy 247.84812 -153.417016) (xy 247.860585 -153.415472) (xy 247.885613 -153.413311)
			(xy 247.898158 -153.412698) (xy 247.898412 -153.412698) (xy 247.90771 -153.411814) (xy 247.924773 -153.404249)
			(xy 247.931686 -153.397966) (xy 247.961404 -153.368248) (xy 247.984968 -153.345316) (xy 248.036382 -153.304322)
			(xy 248.092058 -153.269337) (xy 248.151298 -153.240799) (xy 248.213359 -153.219067) (xy 248.277461 -153.204413)
			(xy 248.3428 -153.197022) (xy 248.375678 -153.196544) (xy 248.410668 -153.197058) (xy 248.480149 -153.205401)
			(xy 248.548142 -153.221959) (xy 248.613679 -153.246496) (xy 248.675828 -153.278663) (xy 248.733704 -153.318002)
			(xy 248.786483 -153.363954) (xy 248.833415 -153.415864) (xy 248.87383 -153.472994) (xy 248.907155 -153.53453)
			(xy 248.920508 -153.566876) (xy 248.925588 -153.579576) (xy 248.946416 -153.59634) (xy 249.060462 -153.613612)
			(xy 249.085354 -153.603706) (xy 249.09399 -153.593038) (xy 249.112225 -153.571176) (xy 249.154064 -153.532572)
			(xy 249.201171 -153.500608) (xy 249.252502 -153.475993) (xy 249.306918 -153.459273) (xy 249.363214 -153.450817)
			(xy 249.391678 -153.45029) (xy 249.41893 -153.450776) (xy 249.47288 -153.45853) (xy 249.525178 -153.473883)
			(xy 249.574757 -153.496523) (xy 249.620611 -153.525988) (xy 249.661803 -153.56168) (xy 249.697497 -153.60287)
			(xy 249.726966 -153.648721) (xy 249.749609 -153.6983) (xy 249.764965 -153.750596) (xy 249.769556 -153.782522)
			(xy 252.05766 -153.782522) (xy 252.061731 -153.7269) (xy 252.073857 -153.672463) (xy 252.09378 -153.620372)
			(xy 252.121076 -153.571737) (xy 252.155162 -153.527594) (xy 252.195311 -153.488885) (xy 252.240669 -153.456434)
			(xy 252.290269 -153.430933) (xy 252.343053 -153.412926) (xy 252.397896 -153.402796) (xy 252.45363 -153.400759)
			(xy 252.509067 -153.406859) (xy 252.563024 -153.420965) (xy 252.614353 -153.442777) (xy 252.661959 -153.471831)
			(xy 252.704827 -153.507506) (xy 252.742044 -153.549043) (xy 252.772817 -153.595556) (xy 252.796489 -153.646053)
			(xy 252.812557 -153.69946) (xy 252.820677 -153.754636) (xy 252.821186 -153.782522) (xy 252.820677 -153.810408)
			(xy 252.812557 -153.865584) (xy 252.796489 -153.918991) (xy 252.772817 -153.969488) (xy 252.742044 -154.016001)
			(xy 252.704827 -154.057538) (xy 252.661959 -154.093213) (xy 252.614353 -154.122267) (xy 252.563024 -154.144079)
			(xy 252.509067 -154.158185) (xy 252.45363 -154.164285) (xy 252.397896 -154.162248) (xy 252.343053 -154.152118)
			(xy 252.290269 -154.134111) (xy 252.240669 -154.10861) (xy 252.195311 -154.076159) (xy 252.155162 -154.03745)
			(xy 252.121076 -153.993307) (xy 252.09378 -153.944672) (xy 252.073857 -153.892581) (xy 252.061731 -153.838144)
			(xy 252.05766 -153.782522) (xy 249.769556 -153.782522) (xy 249.772723 -153.804546) (xy 249.773186 -153.831798)
			(xy 249.772695 -153.858708) (xy 249.765118 -153.911991) (xy 249.750129 -153.963682) (xy 249.728026 -154.012753)
			(xy 249.699246 -154.058231) (xy 249.664361 -154.099214) (xy 249.624063 -154.134889) (xy 249.579152 -154.164546)
			(xy 249.53052 -154.187599) (xy 249.504962 -154.196034) (xy 249.504708 -154.196034) (xy 249.499022 -154.19803)
			(xy 249.488743 -154.204315) (xy 249.484388 -154.20848) (xy 249.391678 -154.30119) (xy 249.385363 -154.308078)
			(xy 249.377817 -154.325159) (xy 249.376946 -154.334464) (xy 249.375213 -154.358708) (xy 249.365542 -154.406341)
			(xy 249.349034 -154.452056) (xy 249.326041 -154.494878) (xy 249.297054 -154.533893) (xy 249.280172 -154.55138)
			(xy 248.48693 -155.344622) (xy 248.468143 -155.362728) (xy 248.425946 -155.39341) (xy 248.379466 -155.417111)
			(xy 248.32985 -155.433245) (xy 248.278321 -155.441415) (xy 248.252234 -155.441904) (xy 247.64365 -155.441904)
			(xy 247.63358 -155.442328) (xy 247.614981 -155.450047) (xy 247.607582 -155.45689) (xy 246.772176 -156.292296)
			(xy 246.753386 -156.310307) (xy 246.711274 -156.34089) (xy 246.664903 -156.364522) (xy 246.61541 -156.380621)
			(xy 246.56401 -156.388794) (xy 246.537988 -156.389324) (xy 242.569746 -156.389324) (xy 242.543722 -156.388803)
			(xy 242.492319 -156.380635) (xy 242.442821 -156.364539) (xy 242.396445 -156.34091) (xy 242.354329 -156.310329)
			(xy 242.335558 -156.292296) (xy 241.66449 -155.621228) (xy 241.646385 -155.60244) (xy 241.615702 -155.560243)
			(xy 241.592001 -155.513764) (xy 241.575867 -155.464148) (xy 241.567696 -155.412619) (xy 241.567208 -155.386532)
			(xy 241.567208 -154.821128) (xy 241.566792 -154.811057) (xy 241.559067 -154.792458) (xy 241.552222 -154.78506)
			(xy 237.709456 -150.942294) (xy 237.702044 -150.93561) (xy 237.683611 -150.928013) (xy 237.663673 -150.928013)
			(xy 237.64524 -150.93561) (xy 237.637828 -150.942294) (xy 237.629192 -150.95093) (xy 237.621572 -150.973282)
			(xy 237.62335 -150.985474) (xy 237.625574 -151.001639) (xy 237.627987 -151.034182) (xy 237.628176 -151.050498)
			(xy 237.628176 -151.914098) (xy 237.627686 -151.944082) (xy 237.619858 -152.003538) (xy 237.604337 -152.061463)
			(xy 237.581388 -152.116867) (xy 237.551404 -152.168801) (xy 237.514898 -152.216377) (xy 237.472493 -152.258782)
			(xy 237.424917 -152.295288) (xy 237.372983 -152.325272) (xy 237.317579 -152.348221) (xy 237.259654 -152.363742)
			(xy 237.200198 -152.37157) (xy 237.14023 -152.37157) (xy 237.080774 -152.363742) (xy 237.022849 -152.348221)
			(xy 236.967445 -152.325272) (xy 236.915511 -152.295288) (xy 236.867935 -152.258782) (xy 236.82553 -152.216377)
			(xy 236.789024 -152.168801) (xy 236.75904 -152.116867) (xy 236.736091 -152.061463) (xy 236.72057 -152.003538)
			(xy 236.712742 -151.944082) (xy 236.712252 -151.914098) (xy 236.712252 -151.050498) (xy 236.712705 -151.020512)
			(xy 236.720534 -150.961052) (xy 236.736056 -150.903123) (xy 236.759007 -150.847716) (xy 236.788994 -150.795779)
			(xy 236.825504 -150.7482) (xy 236.867912 -150.705794) (xy 236.915492 -150.669285) (xy 236.96743 -150.6393)
			(xy 237.022838 -150.616351) (xy 237.080768 -150.600831) (xy 237.140228 -150.593004) (xy 237.170214 -150.592536)
			(xy 237.200058 -150.593042) (xy 237.259236 -150.600846) (xy 237.316899 -150.616266) (xy 237.372072 -150.639043)
			(xy 237.42382 -150.668791) (xy 237.447836 -150.686516) (xy 237.45063 -150.688548) (xy 237.458912 -150.693607)
			(xy 237.477899 -150.697573) (xy 237.497001 -150.694202) (xy 237.513484 -150.683978) (xy 237.52499 -150.668362)
			(xy 237.527846 -150.659084) (xy 237.528803 -150.65503) (xy 237.52957 -150.646735) (xy 237.52937 -150.642574)
			(xy 237.528608 -150.624032) (xy 237.528608 -150.186136) (xy 237.528195 -150.177419) (xy 237.522289 -150.161013)
			(xy 237.511246 -150.147518) (xy 237.50397 -150.142702) (xy 237.429548 -150.097744) (xy 237.421944 -150.093603)
			(xy 237.404991 -150.09015) (xy 237.387856 -150.092543) (xy 237.380018 -150.09622) (xy 237.379764 -150.09622)
			(xy 237.355022 -150.108807) (xy 237.303152 -150.128586) (xy 237.249266 -150.141932) (xy 237.194161 -150.148648)
			(xy 237.166404 -150.149052) (xy 237.16615 -150.149052) (xy 237.136175 -150.148619) (xy 237.076737 -150.140791)
			(xy 237.01883 -150.125274) (xy 236.963441 -150.102335) (xy 236.911519 -150.072365) (xy 236.863951 -150.035877)
			(xy 236.821551 -149.993495) (xy 236.785043 -149.945942) (xy 236.755051 -149.894033) (xy 236.732088 -149.838654)
			(xy 236.716547 -149.780753) (xy 236.708693 -149.721319) (xy 236.708188 -149.691344) (xy 236.708188 -148.827744)
			(xy 236.708703 -148.797766) (xy 236.716526 -148.738321) (xy 236.732045 -148.680408) (xy 236.754993 -148.625016)
			(xy 236.784977 -148.573096) (xy 236.821485 -148.525535) (xy 236.86389 -148.483149) (xy 236.911467 -148.446663)
			(xy 236.963401 -148.416702) (xy 237.018803 -148.393779) (xy 237.076724 -148.378286) (xy 237.136171 -148.370489)
			(xy 237.16615 -148.370036) (xy 237.193936 -148.370456) (xy 237.249101 -148.377179) (xy 237.303049 -148.390519)
			(xy 237.354989 -148.41028) (xy 237.379764 -148.422868) (xy 237.380018 -148.422868) (xy 237.387843 -148.42659)
			(xy 237.404992 -148.429) (xy 237.421957 -148.425523) (xy 237.429548 -148.421344) (xy 237.50397 -148.376386)
			(xy 237.511257 -148.371569) (xy 237.52236 -148.358105) (xy 237.52825 -148.341678) (xy 237.528608 -148.332952)
			(xy 237.528608 -146.338544) (xy 237.529106 -146.312457) (xy 237.537268 -146.260926) (xy 237.553396 -146.211307)
			(xy 237.577095 -146.164826) (xy 237.607778 -146.122629) (xy 237.62589 -146.103848) (xy 238.247174 -145.482564)
			(xy 238.254019 -145.475167) (xy 238.261736 -145.456566) (xy 238.26216 -145.446496) (xy 238.26216 -142.621254)
			(xy 238.261717 -142.611186) (xy 238.25401 -142.592588) (xy 238.247174 -142.585186) (xy 237.185962 -141.523974)
			(xy 237.178259 -141.516994) (xy 237.158923 -141.509411) (xy 237.138165 -141.510094) (xy 237.128558 -141.514068)
			(xy 237.027466 -141.561312) (xy 237.011464 -141.589252) (xy 237.012988 -141.605254) (xy 237.014766 -141.640814)
			(xy 237.014307 -141.668063) (xy 237.006549 -141.722007) (xy 236.991194 -141.774298) (xy 236.968553 -141.823871)
			(xy 236.939088 -141.869718) (xy 236.903398 -141.910905) (xy 236.86221 -141.946593) (xy 236.816363 -141.976057)
			(xy 236.766789 -141.998697) (xy 236.714498 -142.014051) (xy 236.660554 -142.021807) (xy 236.606055 -142.021808)
			(xy 236.552111 -142.014053) (xy 236.49982 -141.9987) (xy 236.450245 -141.976062) (xy 236.404397 -141.946599)
			(xy 236.363209 -141.910911) (xy 236.327518 -141.869725) (xy 236.298052 -141.823879) (xy 236.27541 -141.774307)
			(xy 236.260053 -141.722016) (xy 236.252294 -141.668073) (xy 236.252291 -141.613574) (xy 236.260043 -141.559629)
			(xy 236.275393 -141.507337) (xy 236.298029 -141.457762) (xy 236.32749 -141.411912) (xy 236.363176 -141.370722)
			(xy 236.40436 -141.335029) (xy 236.450204 -141.305561) (xy 236.499776 -141.282916) (xy 236.552065 -141.267557)
			(xy 236.606009 -141.259795) (xy 236.633258 -141.259306) (xy 236.668818 -141.261084) (xy 236.679248 -141.26158)
			(xy 236.699091 -141.255153) (xy 236.714734 -141.241356) (xy 236.719618 -141.232128) (xy 236.760004 -141.145514)
			(xy 236.764003 -141.135916) (xy 236.764678 -141.115154) (xy 236.75707 -141.095825) (xy 236.750098 -141.08811)
			(xy 235.946696 -140.284708) (xy 235.928651 -140.265949) (xy 235.898072 -140.223829) (xy 235.874448 -140.17745)
			(xy 235.858356 -140.12795) (xy 235.850193 -140.076544) (xy 235.849668 -140.05052) (xy 235.849668 -129.615438)
			(xy 235.850186 -129.589414) (xy 235.858356 -129.53801) (xy 235.874452 -129.488513) (xy 235.898081 -129.442137)
			(xy 235.928663 -129.400021) (xy 235.946696 -129.38125) (xy 238.247174 -127.080772) (xy 238.254015 -127.073373)
			(xy 238.261735 -127.054773) (xy 238.26216 -127.044704) (xy 238.26216 -121.570496) (xy 238.262613 -121.544407)
			(xy 238.270783 -121.492873) (xy 238.286922 -121.443254) (xy 238.310631 -121.396773) (xy 238.341325 -121.354578)
			(xy 238.359442 -121.3358) (xy 242.599718 -117.095524) (xy 242.606542 -117.088112) (xy 242.614271 -117.069522)
			(xy 242.614704 -117.059456) (xy 242.614704 -115.710462) (xy 242.614324 -115.700387) (xy 242.606574 -115.681788)
			(xy 242.599718 -115.674394) (xy 242.322604 -115.39728) (xy 242.304595 -115.378488) (xy 242.274011 -115.336377)
			(xy 242.25038 -115.290006) (xy 242.23428 -115.240514) (xy 242.226107 -115.189114) (xy 242.225576 -115.163092)
			(xy 242.225576 -114.095022) (xy 242.226082 -114.068998) (xy 242.234254 -114.017593) (xy 242.250353 -113.968096)
			(xy 242.273985 -113.92172) (xy 242.30457 -113.879604) (xy 242.322604 -113.860834) (xy 242.599718 -113.583974)
			(xy 242.606564 -113.576579) (xy 242.61428 -113.557976) (xy 242.614704 -113.547906) (xy 242.614704 -107.793028)
			(xy 242.614289 -107.782957) (xy 242.606564 -107.764358) (xy 242.599718 -107.75696) (xy 239.958118 -105.115614)
			(xy 239.950704 -105.108791) (xy 239.932116 -105.101061) (xy 239.92205 -105.100628) (xy 236.947202 -105.100628)
			(xy 236.921115 -105.100146) (xy 236.869583 -105.091979) (xy 236.819965 -105.075846) (xy 236.773484 -105.052144)
			(xy 236.731287 -105.021459) (xy 236.712506 -105.003346) (xy 232.259124 -100.54971) (xy 232.251709 -100.542889)
			(xy 232.233121 -100.535158) (xy 232.223056 -100.534724) (xy 231.049322 -100.534724) (xy 231.023298 -100.534218)
			(xy 230.971893 -100.526046) (xy 230.922396 -100.509947) (xy 230.87602 -100.486315) (xy 230.833904 -100.45573)
			(xy 230.815134 -100.437696) (xy 228.385624 -98.008186) (xy 228.367603 -97.989405) (xy 228.337025 -97.947289)
			(xy 228.313397 -97.900915) (xy 228.297299 -97.851421) (xy 228.289127 -97.800021) (xy 228.288596 -97.773998)
			(xy 228.288596 -97.768918) (xy 228.287944 -97.756651) (xy 228.276646 -97.734879) (xy 228.267006 -97.727262)
			(xy 228.199188 -97.67951) (xy 228.188765 -97.673038) (xy 228.164488 -97.669731) (xy 228.152706 -97.67316)
			(xy 228.121772 -97.683452) (xy 228.057538 -97.694569) (xy 228.024944 -97.695258) (xy 227.99769 -97.694804)
			(xy 227.943736 -97.687051) (xy 227.891435 -97.671698) (xy 227.841852 -97.649057) (xy 227.795996 -97.619589)
			(xy 227.754801 -97.583894) (xy 227.719107 -97.542699) (xy 227.68964 -97.496843) (xy 227.667 -97.447259)
			(xy 227.651647 -97.394958) (xy 227.643896 -97.341004) (xy 227.643436 -97.31375) (xy 227.643872 -97.287429)
			(xy 227.651092 -97.235284) (xy 227.665415 -97.184628) (xy 227.68657 -97.136423) (xy 227.714154 -97.091587)
			(xy 227.747642 -97.05097) (xy 227.786399 -97.015345) (xy 227.829687 -96.98539) (xy 227.852986 -96.973136)
			(xy 227.860098 -96.96958) (xy 227.86594 -96.963738) (xy 227.872603 -96.956308) (xy 227.880208 -96.937883)
			(xy 227.880215 -96.91795) (xy 227.872622 -96.89952) (xy 227.86594 -96.89211) (xy 227.857812 -96.883982)
			(xy 227.850404 -96.877152) (xy 227.831811 -96.869427) (xy 227.821744 -96.868996) (xy 224.046796 -96.868996)
			(xy 224.03675 -96.869419) (xy 224.018196 -96.877127) (xy 224.004016 -96.891361) (xy 223.999806 -96.900492)
			(xy 223.964246 -96.98736) (xy 223.960899 -96.99675) (xy 223.960902 -97.016664) (xy 223.968492 -97.035075)
			(xy 223.975168 -97.042478) (xy 223.975422 -97.042732) (xy 223.996459 -97.064352) (xy 224.032106 -97.113015)
			(xy 224.059647 -97.166683) (xy 224.078395 -97.224018) (xy 224.087884 -97.283589) (xy 224.088452 -97.31375)
			(xy 224.087966 -97.341001) (xy 224.08021 -97.394949) (xy 224.064855 -97.447244) (xy 224.042213 -97.496821)
			(xy 224.012747 -97.542671) (xy 223.977056 -97.583862) (xy 223.935865 -97.619553) (xy 223.890015 -97.649019)
			(xy 223.840438 -97.671661) (xy 223.788143 -97.687016) (xy 223.734195 -97.694772) (xy 223.679693 -97.694772)
			(xy 223.625745 -97.687016) (xy 223.57345 -97.671661) (xy 223.523873 -97.649019) (xy 223.478023 -97.619553)
			(xy 223.436832 -97.583862) (xy 223.401141 -97.542671) (xy 223.371675 -97.496821) (xy 223.349033 -97.447244)
			(xy 223.333678 -97.394949) (xy 223.325922 -97.341001) (xy 223.325436 -97.31375) (xy 223.326044 -97.283592)
			(xy 223.335539 -97.224028) (xy 223.354286 -97.166699) (xy 223.381817 -97.113033) (xy 223.417447 -97.064366)
			(xy 223.438466 -97.042732) (xy 223.43872 -97.042478) (xy 223.445405 -97.035084) (xy 223.452984 -97.016667)
			(xy 223.452988 -96.996751) (xy 223.449642 -96.98736) (xy 223.414082 -96.900492) (xy 223.409879 -96.891357)
			(xy 223.395696 -96.877124) (xy 223.377139 -96.869419) (xy 223.367092 -96.868996) (xy 223.030796 -96.868996)
			(xy 223.02075 -96.869419) (xy 223.002196 -96.877127) (xy 222.988016 -96.891361) (xy 222.983806 -96.900492)
			(xy 222.948246 -96.98736) (xy 222.944899 -96.99675) (xy 222.944902 -97.016664) (xy 222.952492 -97.035075)
			(xy 222.959168 -97.042478) (xy 222.959422 -97.042732) (xy 222.980459 -97.064352) (xy 223.016106 -97.113015)
			(xy 223.043647 -97.166683) (xy 223.062395 -97.224018) (xy 223.071884 -97.283589) (xy 223.072452 -97.31375)
			(xy 223.071966 -97.341001) (xy 223.06421 -97.394949) (xy 223.048855 -97.447244) (xy 223.026213 -97.496821)
			(xy 222.996747 -97.542671) (xy 222.961056 -97.583862) (xy 222.919865 -97.619553) (xy 222.874015 -97.649019)
			(xy 222.824438 -97.671661) (xy 222.772143 -97.687016) (xy 222.718195 -97.694772) (xy 222.663693 -97.694772)
			(xy 222.609745 -97.687016) (xy 222.55745 -97.671661) (xy 222.507873 -97.649019) (xy 222.462023 -97.619553)
			(xy 222.420832 -97.583862) (xy 222.385141 -97.542671) (xy 222.355675 -97.496821) (xy 222.333033 -97.447244)
			(xy 222.317678 -97.394949) (xy 222.309922 -97.341001) (xy 222.309436 -97.31375) (xy 222.310044 -97.283592)
			(xy 222.319539 -97.224028) (xy 222.338286 -97.166699) (xy 222.365817 -97.113033) (xy 222.401447 -97.064366)
			(xy 222.422466 -97.042732) (xy 222.42272 -97.042478) (xy 222.429405 -97.035084) (xy 222.436984 -97.016667)
			(xy 222.436988 -96.996751) (xy 222.433642 -96.98736) (xy 222.398082 -96.900492) (xy 222.393879 -96.891357)
			(xy 222.379696 -96.877124) (xy 222.361139 -96.869419) (xy 222.351092 -96.868996) (xy 221.54007 -96.868996)
			(xy 221.530023 -96.86935) (xy 221.511425 -96.876947) (xy 221.504002 -96.883728) (xy 221.429326 -96.958404)
			(xy 221.422496 -96.965812) (xy 221.41477 -96.984405) (xy 221.41434 -96.994472) (xy 221.41434 -97.852484)
			(xy 221.414866 -97.864021) (xy 221.424927 -97.884785) (xy 221.433644 -97.892362) (xy 221.496382 -97.941892)
			(xy 221.505891 -97.948461) (xy 221.528445 -97.95335) (xy 221.539816 -97.95129) (xy 221.567525 -97.945026)
			(xy 221.623933 -97.938281) (xy 221.652338 -97.937828) (xy 226.377754 -97.937828) (xy 226.40939 -97.938248)
			(xy 226.472123 -97.946501) (xy 226.533241 -97.962873) (xy 226.591699 -97.987082) (xy 226.646497 -98.018715)
			(xy 226.696697 -98.05723) (xy 226.741439 -98.101969) (xy 226.779959 -98.152165) (xy 226.811598 -98.20696)
			(xy 226.835812 -98.265416) (xy 226.85219 -98.326532) (xy 226.860449 -98.389264) (xy 226.860449 -98.452536)
			(xy 226.85219 -98.515268) (xy 226.835812 -98.576384) (xy 226.811598 -98.63484) (xy 226.779959 -98.689635)
			(xy 226.741439 -98.739831) (xy 226.696697 -98.78457) (xy 226.646497 -98.823085) (xy 226.591699 -98.854718)
			(xy 226.533241 -98.878927) (xy 226.472123 -98.895298) (xy 226.40939 -98.903552) (xy 226.377754 -98.904044)
			(xy 224.612454 -98.904044) (xy 224.602542 -98.904479) (xy 224.584186 -98.911958) (xy 224.57005 -98.925852)
			(xy 224.565718 -98.934778) (xy 224.528888 -99.02063) (xy 224.525444 -99.02994) (xy 224.525111 -99.049763)
			(xy 224.532306 -99.068238) (xy 224.538794 -99.075748) (xy 224.558476 -99.097178) (xy 224.591803 -99.14487)
			(xy 224.617512 -99.197064) (xy 224.635008 -99.252554) (xy 224.643885 -99.310055) (xy 224.644458 -99.339146)
			(xy 224.643972 -99.366397) (xy 224.636216 -99.420345) (xy 224.620861 -99.47264) (xy 224.598219 -99.522217)
			(xy 224.568753 -99.568067) (xy 224.560448 -99.577652) (xy 225.818444 -99.577652) (xy 225.822515 -99.52203)
			(xy 225.834641 -99.467593) (xy 225.854564 -99.415502) (xy 225.88186 -99.366867) (xy 225.915946 -99.322724)
			(xy 225.956095 -99.284015) (xy 226.001453 -99.251564) (xy 226.051053 -99.226063) (xy 226.103837 -99.208056)
			(xy 226.15868 -99.197926) (xy 226.214414 -99.195889) (xy 226.269851 -99.201989) (xy 226.323808 -99.216095)
			(xy 226.375137 -99.237907) (xy 226.422743 -99.266961) (xy 226.465611 -99.302636) (xy 226.502828 -99.344173)
			(xy 226.533601 -99.390686) (xy 226.557273 -99.441183) (xy 226.573341 -99.49459) (xy 226.581461 -99.549766)
			(xy 226.58197 -99.577652) (xy 226.581461 -99.605538) (xy 226.573341 -99.660714) (xy 226.557273 -99.714121)
			(xy 226.533601 -99.764618) (xy 226.502828 -99.811131) (xy 226.465611 -99.852668) (xy 226.422743 -99.888343)
			(xy 226.375137 -99.917397) (xy 226.323808 -99.939209) (xy 226.269851 -99.953315) (xy 226.214414 -99.959415)
			(xy 226.15868 -99.957378) (xy 226.103837 -99.947248) (xy 226.051053 -99.929241) (xy 226.001453 -99.90374)
			(xy 225.956095 -99.871289) (xy 225.915946 -99.83258) (xy 225.88186 -99.788437) (xy 225.854564 -99.739802)
			(xy 225.834641 -99.687711) (xy 225.822515 -99.633274) (xy 225.818444 -99.577652) (xy 224.560448 -99.577652)
			(xy 224.533062 -99.609258) (xy 224.491871 -99.644949) (xy 224.446021 -99.674415) (xy 224.396444 -99.697057)
			(xy 224.344149 -99.712412) (xy 224.290201 -99.720168) (xy 224.235699 -99.720168) (xy 224.181751 -99.712412)
			(xy 224.129456 -99.697057) (xy 224.079879 -99.674415) (xy 224.034029 -99.644949) (xy 223.992838 -99.609258)
			(xy 223.957147 -99.568067) (xy 223.927681 -99.522217) (xy 223.905039 -99.47264) (xy 223.889684 -99.420345)
			(xy 223.881928 -99.366397) (xy 223.881442 -99.339146) (xy 223.882001 -99.310051) (xy 223.890841 -99.252537)
			(xy 223.908323 -99.197035) (xy 223.934041 -99.144837) (xy 223.967395 -99.097156) (xy 223.987106 -99.075748)
			(xy 223.99362 -99.068252) (xy 224.000832 -99.049768) (xy 224.000497 -99.02993) (xy 223.997012 -99.02063)
			(xy 223.960182 -98.934778) (xy 223.95582 -98.925876) (xy 223.941678 -98.912012) (xy 223.923348 -98.904516)
			(xy 223.913446 -98.904044) (xy 221.873572 -98.904044) (xy 221.863526 -98.904413) (xy 221.84493 -98.912002)
			(xy 221.837504 -98.918776) (xy 221.774258 -98.982022) (xy 221.768449 -98.988233) (xy 221.761 -99.003511)
			(xy 221.759013 -99.020392) (xy 221.760542 -99.028758) (xy 221.78137 -99.12477) (xy 221.79788 -99.144328)
			(xy 221.809818 -99.1489) (xy 221.810326 -99.1489) (xy 221.837073 -99.159636) (xy 221.887273 -99.187946)
			(xy 221.932641 -99.223489) (xy 221.972144 -99.265453) (xy 222.004882 -99.312883) (xy 222.030111 -99.3647)
			(xy 222.047256 -99.419723) (xy 222.055926 -99.4767) (xy 222.056345 -99.499674) (xy 222.606868 -99.499674)
			(xy 222.610939 -99.444052) (xy 222.623065 -99.389615) (xy 222.642988 -99.337524) (xy 222.670284 -99.288889)
			(xy 222.70437 -99.244746) (xy 222.744519 -99.206037) (xy 222.789877 -99.173586) (xy 222.839477 -99.148085)
			(xy 222.892261 -99.130078) (xy 222.947104 -99.119948) (xy 223.002838 -99.117911) (xy 223.058275 -99.124011)
			(xy 223.112232 -99.138117) (xy 223.163561 -99.159929) (xy 223.211167 -99.188983) (xy 223.254035 -99.224658)
			(xy 223.291252 -99.266195) (xy 223.322025 -99.312708) (xy 223.345697 -99.363205) (xy 223.361765 -99.416612)
			(xy 223.369885 -99.471788) (xy 223.370394 -99.499674) (xy 223.369885 -99.52756) (xy 223.361765 -99.582736)
			(xy 223.345697 -99.636143) (xy 223.322025 -99.68664) (xy 223.291252 -99.733153) (xy 223.254035 -99.77469)
			(xy 223.211167 -99.810365) (xy 223.163561 -99.839419) (xy 223.112232 -99.861231) (xy 223.058275 -99.875337)
			(xy 223.002838 -99.881437) (xy 222.947104 -99.8794) (xy 222.892261 -99.86927) (xy 222.839477 -99.851263)
			(xy 222.789877 -99.825762) (xy 222.744519 -99.793311) (xy 222.70437 -99.754602) (xy 222.670284 -99.710459)
			(xy 222.642988 -99.661824) (xy 222.623065 -99.609733) (xy 222.610939 -99.555296) (xy 222.606868 -99.499674)
			(xy 222.056345 -99.499674) (xy 222.056452 -99.505516) (xy 222.055937 -99.532766) (xy 222.04818 -99.58671)
			(xy 222.032825 -99.639002) (xy 222.010185 -99.688576) (xy 221.980721 -99.734424) (xy 221.945033 -99.775613)
			(xy 221.903847 -99.811304) (xy 221.858001 -99.840772) (xy 221.808428 -99.863415) (xy 221.756137 -99.878774)
			(xy 221.702194 -99.886535) (xy 221.674944 -99.887024) (xy 221.645981 -99.886464) (xy 221.588721 -99.877714)
			(xy 221.533442 -99.860407) (xy 221.481414 -99.834943) (xy 221.433834 -99.801906) (xy 221.391795 -99.762056)
			(xy 221.356263 -99.716309) (xy 221.328056 -99.665716) (xy 221.307822 -99.61144) (xy 221.296025 -99.554729)
			(xy 221.293944 -99.525836) (xy 221.293436 -99.515168) (xy 221.284292 -99.496372) (xy 221.210886 -99.434904)
			(xy 221.19082 -99.429062) (xy 221.180406 -99.430332) (xy 221.165985 -99.431989) (xy 221.137009 -99.433768)
			(xy 221.122494 -99.433888) (xy 220.755718 -99.433888) (xy 220.746374 -99.434338) (xy 220.728959 -99.44113)
			(xy 220.715107 -99.453682) (xy 220.710506 -99.461828) (xy 220.663008 -99.555554) (xy 220.665294 -99.584002)
			(xy 220.67393 -99.595686) (xy 220.69145 -99.620419) (xy 220.71925 -99.674275) (xy 220.738182 -99.731851)
			(xy 220.747769 -99.791696) (xy 220.748352 -99.822) (xy 220.747866 -99.849251) (xy 220.74011 -99.903199)
			(xy 220.724755 -99.955494) (xy 220.702113 -100.005071) (xy 220.672647 -100.050921) (xy 220.636956 -100.092112)
			(xy 220.595765 -100.127803) (xy 220.549915 -100.157269) (xy 220.500338 -100.179911) (xy 220.448043 -100.195266)
			(xy 220.394095 -100.203022) (xy 220.339593 -100.203022) (xy 220.285645 -100.195266) (xy 220.23335 -100.179911)
			(xy 220.183773 -100.157269) (xy 220.137923 -100.127803) (xy 220.096732 -100.092112) (xy 220.061041 -100.050921)
			(xy 220.031575 -100.005071) (xy 220.008933 -99.955494) (xy 219.993578 -99.903199) (xy 219.985822 -99.849251)
			(xy 219.985336 -99.822) (xy 219.985942 -99.791697) (xy 219.995518 -99.731852) (xy 220.014444 -99.674276)
			(xy 220.042243 -99.620421) (xy 220.059758 -99.595686) (xy 220.068394 -99.584002) (xy 220.07068 -99.555554)
			(xy 220.023182 -99.461828) (xy 220.018665 -99.453611) (xy 220.004819 -99.440988) (xy 219.987339 -99.434242)
			(xy 219.97797 -99.433888) (xy 217.326972 -99.433888) (xy 217.317632 -99.434376) (xy 217.300218 -99.44115)
			(xy 217.286364 -99.453688) (xy 217.28176 -99.461828) (xy 217.234262 -99.555554) (xy 217.236548 -99.584002)
			(xy 217.245184 -99.595686) (xy 217.262628 -99.620419) (xy 217.290338 -99.674223) (xy 217.309209 -99.731726)
			(xy 217.318769 -99.791486) (xy 217.319352 -99.821746) (xy 217.318866 -99.848997) (xy 217.31111 -99.902945)
			(xy 217.295755 -99.95524) (xy 217.273113 -100.004817) (xy 217.243647 -100.050667) (xy 217.221697 -100.076)
			(xy 218.371672 -100.076) (xy 218.375743 -100.020378) (xy 218.387869 -99.965941) (xy 218.407792 -99.91385)
			(xy 218.435088 -99.865215) (xy 218.469174 -99.821072) (xy 218.509323 -99.782363) (xy 218.554681 -99.749912)
			(xy 218.604281 -99.724411) (xy 218.657065 -99.706404) (xy 218.711908 -99.696274) (xy 218.767642 -99.694237)
			(xy 218.823079 -99.700337) (xy 218.877036 -99.714443) (xy 218.928365 -99.736255) (xy 218.975971 -99.765309)
			(xy 219.018839 -99.800984) (xy 219.056056 -99.842521) (xy 219.086829 -99.889034) (xy 219.110501 -99.939531)
			(xy 219.126569 -99.992938) (xy 219.134689 -100.048114) (xy 219.135198 -100.076) (xy 219.134689 -100.103886)
			(xy 219.126569 -100.159062) (xy 219.110501 -100.212469) (xy 219.086829 -100.262966) (xy 219.056056 -100.309479)
			(xy 219.018839 -100.351016) (xy 218.975971 -100.386691) (xy 218.928365 -100.415745) (xy 218.877036 -100.437557)
			(xy 218.823079 -100.451663) (xy 218.767642 -100.457763) (xy 218.711908 -100.455726) (xy 218.657065 -100.445596)
			(xy 218.604281 -100.427589) (xy 218.554681 -100.402088) (xy 218.509323 -100.369637) (xy 218.469174 -100.330928)
			(xy 218.435088 -100.286785) (xy 218.407792 -100.23815) (xy 218.387869 -100.186059) (xy 218.375743 -100.131622)
			(xy 218.371672 -100.076) (xy 217.221697 -100.076) (xy 217.207956 -100.091858) (xy 217.166765 -100.127549)
			(xy 217.120915 -100.157015) (xy 217.071338 -100.179657) (xy 217.019043 -100.195012) (xy 216.965095 -100.202768)
			(xy 216.910593 -100.202768) (xy 216.856645 -100.195012) (xy 216.80435 -100.179657) (xy 216.754773 -100.157015)
			(xy 216.708923 -100.127549) (xy 216.667732 -100.091858) (xy 216.632041 -100.050667) (xy 216.602575 -100.004817)
			(xy 216.579933 -99.95524) (xy 216.564578 -99.902945) (xy 216.556822 -99.848997) (xy 216.556336 -99.821746)
			(xy 216.556891 -99.793283) (xy 216.565338 -99.736987) (xy 216.582051 -99.68257) (xy 216.60666 -99.631238)
			(xy 216.63862 -99.58413) (xy 216.67722 -99.54229) (xy 216.699084 -99.524058) (xy 216.708228 -99.516692)
			(xy 216.718134 -99.496118) (xy 216.718134 -99.484688) (xy 216.717622 -99.474684) (xy 216.709965 -99.456198)
			(xy 216.69582 -99.442047) (xy 216.677338 -99.434382) (xy 216.667334 -99.433888) (xy 216.63279 -99.433888)
			(xy 216.622717 -99.434285) (xy 216.604118 -99.442023) (xy 216.596722 -99.448874) (xy 214.826596 -101.219)
			(xy 220.238826 -101.219) (xy 220.242897 -101.163378) (xy 220.255023 -101.108941) (xy 220.274946 -101.05685)
			(xy 220.302242 -101.008215) (xy 220.336328 -100.964072) (xy 220.376477 -100.925363) (xy 220.421835 -100.892912)
			(xy 220.471435 -100.867411) (xy 220.524219 -100.849404) (xy 220.579062 -100.839274) (xy 220.634796 -100.837237)
			(xy 220.690233 -100.843337) (xy 220.74419 -100.857443) (xy 220.795519 -100.879255) (xy 220.843125 -100.908309)
			(xy 220.885993 -100.943984) (xy 220.92321 -100.985521) (xy 220.953983 -101.032034) (xy 220.977655 -101.082531)
			(xy 220.993723 -101.135938) (xy 221.001843 -101.191114) (xy 221.002352 -101.219) (xy 221.001843 -101.246886)
			(xy 220.993723 -101.302062) (xy 220.977655 -101.355469) (xy 220.953983 -101.405966) (xy 220.92321 -101.452479)
			(xy 220.885993 -101.494016) (xy 220.843125 -101.529691) (xy 220.795519 -101.558745) (xy 220.74419 -101.580557)
			(xy 220.690233 -101.594663) (xy 220.634796 -101.600763) (xy 220.579062 -101.598726) (xy 220.524219 -101.588596)
			(xy 220.471435 -101.570589) (xy 220.421835 -101.545088) (xy 220.376477 -101.512637) (xy 220.336328 -101.473928)
			(xy 220.302242 -101.429785) (xy 220.274946 -101.38115) (xy 220.255023 -101.329059) (xy 220.242897 -101.274622)
			(xy 220.238826 -101.219) (xy 214.826596 -101.219) (xy 213.907878 -102.137718) (xy 213.901034 -102.145115)
			(xy 213.893317 -102.163717) (xy 213.892892 -102.173786) (xy 213.892892 -102.910132) (xy 224.984056 -102.910132)
			(xy 224.984527 -102.882762) (xy 224.992342 -102.828582) (xy 225.007829 -102.776079) (xy 225.03067 -102.726332)
			(xy 225.060394 -102.680365) (xy 225.078036 -102.659434) (xy 225.07829 -102.65918) (xy 225.08389 -102.652103)
			(xy 225.090129 -102.635179) (xy 225.090482 -102.62616) (xy 225.090482 -102.559104) (xy 225.090127 -102.550087)
			(xy 225.083879 -102.53317) (xy 225.07829 -102.526084) (xy 225.078036 -102.526084) (xy 225.078036 -102.52583)
			(xy 225.060426 -102.504872) (xy 225.0307 -102.458909) (xy 225.007852 -102.409167) (xy 224.992353 -102.356669)
			(xy 224.984521 -102.302493) (xy 224.984517 -102.247755) (xy 224.992342 -102.193579) (xy 225.007835 -102.141078)
			(xy 225.030676 -102.091333) (xy 225.060397 -102.045367) (xy 225.078036 -102.024434) (xy 225.07829 -102.02418)
			(xy 225.08389 -102.017103) (xy 225.090129 -102.000179) (xy 225.090482 -101.99116) (xy 225.090482 -101.924104)
			(xy 225.090127 -101.915087) (xy 225.083879 -101.89817) (xy 225.07829 -101.891084) (xy 225.078036 -101.891084)
			(xy 225.078036 -101.89083) (xy 225.060403 -101.869893) (xy 225.030689 -101.823922) (xy 225.007851 -101.774176)
			(xy 224.992359 -101.721676) (xy 224.98453 -101.667501) (xy 224.984056 -101.640132) (xy 224.984542 -101.612881)
			(xy 224.992298 -101.558933) (xy 225.007653 -101.506638) (xy 225.030295 -101.457061) (xy 225.059761 -101.411211)
			(xy 225.095452 -101.37002) (xy 225.136643 -101.334329) (xy 225.182493 -101.304863) (xy 225.23207 -101.282221)
			(xy 225.284365 -101.266866) (xy 225.338313 -101.25911) (xy 225.392815 -101.25911) (xy 225.446763 -101.266866)
			(xy 225.499058 -101.282221) (xy 225.548635 -101.304863) (xy 225.594485 -101.334329) (xy 225.635676 -101.37002)
			(xy 225.671367 -101.411211) (xy 225.700833 -101.457061) (xy 225.723475 -101.506638) (xy 225.73883 -101.558933)
			(xy 225.746586 -101.612881) (xy 225.747072 -101.640132) (xy 225.746632 -101.667503) (xy 225.738809 -101.721684)
			(xy 225.723314 -101.774187) (xy 225.700466 -101.823934) (xy 225.670736 -101.869899) (xy 225.653092 -101.89083)
			(xy 225.652838 -101.891084) (xy 225.647245 -101.898166) (xy 225.641004 -101.915086) (xy 225.640646 -101.924104)
			(xy 225.640646 -101.99116) (xy 225.641012 -102.000176) (xy 225.647252 -102.017094) (xy 225.652838 -102.02418)
			(xy 225.653092 -102.02418) (xy 225.653092 -102.024434) (xy 225.670763 -102.045342) (xy 225.700485 -102.091314)
			(xy 225.723328 -102.141065) (xy 225.738821 -102.193571) (xy 225.746646 -102.247752) (xy 225.746642 -102.302496)
			(xy 225.73881 -102.356677) (xy 225.723311 -102.40918) (xy 225.700462 -102.458928) (xy 225.670734 -102.504897)
			(xy 225.653092 -102.52583) (xy 225.652838 -102.526084) (xy 225.647245 -102.533166) (xy 225.641004 -102.550086)
			(xy 225.640646 -102.559104) (xy 225.640646 -102.62616) (xy 225.641012 -102.635176) (xy 225.647252 -102.652094)
			(xy 225.648871 -102.654148) (xy 226.6389 -102.654148) (xy 226.6389 -102.599652) (xy 226.646655 -102.54571)
			(xy 226.662008 -102.493421) (xy 226.684645 -102.443849) (xy 226.714107 -102.398003) (xy 226.749792 -102.356816)
			(xy 226.790976 -102.321127) (xy 226.836819 -102.291661) (xy 226.886389 -102.26902) (xy 226.938677 -102.253663)
			(xy 226.992618 -102.245903) (xy 227.019866 -102.245414) (xy 227.046182 -102.245833) (xy 227.098312 -102.253077)
			(xy 227.148956 -102.267405) (xy 227.197155 -102.288547) (xy 227.241997 -102.316102) (xy 227.282635 -102.349549)
			(xy 227.30079 -102.368604) (xy 227.308313 -102.376004) (xy 227.327592 -102.384529) (xy 227.338128 -102.385114)
			(xy 227.412804 -102.385114) (xy 227.423355 -102.384596) (xy 227.44265 -102.376053) (xy 227.450142 -102.368604)
			(xy 227.468285 -102.349536) (xy 227.508917 -102.31608) (xy 227.55376 -102.288522) (xy 227.601963 -102.267386)
			(xy 227.652613 -102.253072) (xy 227.704749 -102.24585) (xy 227.731066 -102.245414) (xy 227.758322 -102.245831)
			(xy 227.81228 -102.253584) (xy 227.864585 -102.268938) (xy 227.914172 -102.29158) (xy 227.960032 -102.321049)
			(xy 228.001231 -102.356745) (xy 228.036931 -102.397941) (xy 228.066404 -102.443798) (xy 228.08612 -102.486968)
			(xy 228.66223 -102.486968) (xy 228.66267 -102.459597) (xy 228.670493 -102.405416) (xy 228.685988 -102.352913)
			(xy 228.708835 -102.303166) (xy 228.738566 -102.257201) (xy 228.75621 -102.23627) (xy 228.756464 -102.236016)
			(xy 228.762058 -102.228935) (xy 228.768298 -102.212014) (xy 228.768656 -102.202996) (xy 228.768656 -102.13594)
			(xy 228.768289 -102.126924) (xy 228.76205 -102.110006) (xy 228.756464 -102.10292) (xy 228.75621 -102.10292)
			(xy 228.75621 -102.102666) (xy 228.738539 -102.081758) (xy 228.708816 -102.035786) (xy 228.685974 -101.986035)
			(xy 228.670481 -101.93353) (xy 228.662656 -101.879348) (xy 228.662659 -101.824604) (xy 228.670491 -101.770423)
			(xy 228.685991 -101.71792) (xy 228.70884 -101.668172) (xy 228.738568 -101.622203) (xy 228.75621 -101.60127)
			(xy 228.756464 -101.601016) (xy 228.762058 -101.593935) (xy 228.768298 -101.577014) (xy 228.768656 -101.567996)
			(xy 228.768656 -101.50094) (xy 228.768289 -101.491924) (xy 228.76205 -101.475006) (xy 228.756464 -101.46792)
			(xy 228.75621 -101.46792) (xy 228.75621 -101.467666) (xy 228.73859 -101.446719) (xy 228.708875 -101.40075)
			(xy 228.686035 -101.351007) (xy 228.67054 -101.298509) (xy 228.662707 -101.244336) (xy 228.66223 -101.216968)
			(xy 228.662716 -101.189717) (xy 228.670472 -101.135769) (xy 228.685827 -101.083474) (xy 228.708469 -101.033897)
			(xy 228.737935 -100.988047) (xy 228.773626 -100.946856) (xy 228.814817 -100.911165) (xy 228.860667 -100.881699)
			(xy 228.910244 -100.859057) (xy 228.962539 -100.843702) (xy 229.016487 -100.835946) (xy 229.070989 -100.835946)
			(xy 229.124937 -100.843702) (xy 229.177232 -100.859057) (xy 229.226809 -100.881699) (xy 229.272659 -100.911165)
			(xy 229.31385 -100.946856) (xy 229.349541 -100.988047) (xy 229.379007 -101.033897) (xy 229.401649 -101.083474)
			(xy 229.417004 -101.135769) (xy 229.42476 -101.189717) (xy 229.425246 -101.216968) (xy 229.424774 -101.244338)
			(xy 229.41696 -101.298518) (xy 229.401473 -101.351021) (xy 229.378632 -101.400768) (xy 229.348907 -101.446735)
			(xy 229.331266 -101.467666) (xy 229.331012 -101.46792) (xy 229.325412 -101.474998) (xy 229.319173 -101.491921)
			(xy 229.31882 -101.50094) (xy 229.31882 -101.567996) (xy 229.319174 -101.577013) (xy 229.325423 -101.59393)
			(xy 229.331012 -101.601016) (xy 229.331266 -101.601016) (xy 229.331266 -101.60127) (xy 229.348876 -101.622228)
			(xy 229.378602 -101.668191) (xy 229.40145 -101.717933) (xy 229.416949 -101.770432) (xy 229.424781 -101.824607)
			(xy 229.424784 -101.879345) (xy 229.416959 -101.933521) (xy 229.401467 -101.986022) (xy 229.378625 -102.035766)
			(xy 229.348905 -102.081733) (xy 229.331266 -102.102666) (xy 229.331012 -102.10292) (xy 229.325412 -102.109998)
			(xy 229.319173 -102.126921) (xy 229.31882 -102.13594) (xy 229.31882 -102.202996) (xy 229.319174 -102.212013)
			(xy 229.325423 -102.22893) (xy 229.331012 -102.236016) (xy 229.331266 -102.236016) (xy 229.331266 -102.23627)
			(xy 229.348899 -102.257207) (xy 229.378613 -102.303178) (xy 229.401451 -102.352924) (xy 229.416943 -102.405424)
			(xy 229.424772 -102.459599) (xy 229.425246 -102.486968) (xy 229.424979 -102.501954) (xy 231.856534 -102.501954)
			(xy 231.857023 -102.474585) (xy 231.864834 -102.420406) (xy 231.880318 -102.367903) (xy 231.903154 -102.318156)
			(xy 231.932875 -102.272188) (xy 231.950514 -102.251256) (xy 231.950768 -102.251002) (xy 231.956368 -102.243925)
			(xy 231.962605 -102.227001) (xy 231.96296 -102.217982) (xy 231.96296 -102.150926) (xy 231.962599 -102.141909)
			(xy 231.956355 -102.124992) (xy 231.950768 -102.117906) (xy 231.950514 -102.117906) (xy 231.950514 -102.117652)
			(xy 231.932829 -102.096755) (xy 231.903107 -102.050781) (xy 231.880265 -102.001029) (xy 231.864773 -101.948521)
			(xy 231.856949 -101.894338) (xy 231.856954 -101.839593) (xy 231.864788 -101.785411) (xy 231.880289 -101.732906)
			(xy 231.90314 -101.683158) (xy 231.932871 -101.637189) (xy 231.950514 -101.616256) (xy 231.950768 -101.616002)
			(xy 231.956368 -101.608925) (xy 231.962605 -101.592001) (xy 231.96296 -101.582982) (xy 231.96296 -101.515926)
			(xy 231.962599 -101.506909) (xy 231.956355 -101.489992) (xy 231.950768 -101.482906) (xy 231.950514 -101.482906)
			(xy 231.950514 -101.482652) (xy 231.932888 -101.461709) (xy 231.903174 -101.41574) (xy 231.880335 -101.365995)
			(xy 231.864841 -101.313496) (xy 231.85701 -101.259322) (xy 231.856534 -101.231954) (xy 231.85702 -101.204703)
			(xy 231.864776 -101.150755) (xy 231.880131 -101.09846) (xy 231.902773 -101.048883) (xy 231.932239 -101.003033)
			(xy 231.96793 -100.961842) (xy 232.009121 -100.926151) (xy 232.054971 -100.896685) (xy 232.104548 -100.874043)
			(xy 232.156843 -100.858688) (xy 232.210791 -100.850932) (xy 232.265293 -100.850932) (xy 232.319241 -100.858688)
			(xy 232.371536 -100.874043) (xy 232.421113 -100.896685) (xy 232.466963 -100.926151) (xy 232.508154 -100.961842)
			(xy 232.543845 -101.003033) (xy 232.573311 -101.048883) (xy 232.595953 -101.09846) (xy 232.611308 -101.150755)
			(xy 232.619064 -101.204703) (xy 232.61955 -101.231954) (xy 232.619069 -101.259324) (xy 232.611257 -101.313503)
			(xy 232.595772 -101.366006) (xy 232.572933 -101.415753) (xy 232.543211 -101.46172) (xy 232.52557 -101.482652)
			(xy 232.525316 -101.482906) (xy 232.519723 -101.489988) (xy 232.513479 -101.506908) (xy 232.513124 -101.515926)
			(xy 232.513124 -101.582982) (xy 232.513485 -101.591999) (xy 232.519729 -101.608916) (xy 232.525316 -101.616002)
			(xy 232.52557 -101.616002) (xy 232.52557 -101.616256) (xy 232.543166 -101.637225) (xy 232.572893 -101.683187)
			(xy 232.595741 -101.732927) (xy 232.611241 -101.785423) (xy 232.619074 -101.839597) (xy 232.619079 -101.894334)
			(xy 232.611256 -101.948509) (xy 232.595765 -102.001008) (xy 232.572926 -102.050753) (xy 232.543208 -102.096719)
			(xy 232.52557 -102.117652) (xy 232.525316 -102.117906) (xy 232.519723 -102.124988) (xy 232.513479 -102.141908)
			(xy 232.513124 -102.150926) (xy 232.513124 -102.217982) (xy 232.513485 -102.226999) (xy 232.519729 -102.243916)
			(xy 232.525316 -102.251002) (xy 232.52557 -102.251002) (xy 232.52557 -102.251256) (xy 232.543197 -102.272198)
			(xy 232.572912 -102.318167) (xy 232.595751 -102.367912) (xy 232.611244 -102.420411) (xy 232.619075 -102.474585)
			(xy 232.61955 -102.501954) (xy 232.619064 -102.529205) (xy 232.611308 -102.583153) (xy 232.595953 -102.635448)
			(xy 232.573311 -102.685025) (xy 232.543845 -102.730875) (xy 232.508154 -102.772066) (xy 232.466963 -102.807757)
			(xy 232.421113 -102.837223) (xy 232.371536 -102.859865) (xy 232.319241 -102.87522) (xy 232.265293 -102.882976)
			(xy 232.210791 -102.882976) (xy 232.156843 -102.87522) (xy 232.104548 -102.859865) (xy 232.054971 -102.837223)
			(xy 232.009121 -102.807757) (xy 231.96793 -102.772066) (xy 231.932239 -102.730875) (xy 231.902773 -102.685025)
			(xy 231.880131 -102.635448) (xy 231.864776 -102.583153) (xy 231.85702 -102.529205) (xy 231.856534 -102.501954)
			(xy 229.424979 -102.501954) (xy 229.42476 -102.514219) (xy 229.417004 -102.568167) (xy 229.401649 -102.620462)
			(xy 229.379007 -102.670039) (xy 229.349541 -102.715889) (xy 229.31385 -102.75708) (xy 229.272659 -102.792771)
			(xy 229.226809 -102.822237) (xy 229.177232 -102.844879) (xy 229.124937 -102.860234) (xy 229.070989 -102.86799)
			(xy 229.016487 -102.86799) (xy 228.962539 -102.860234) (xy 228.910244 -102.844879) (xy 228.860667 -102.822237)
			(xy 228.814817 -102.792771) (xy 228.773626 -102.75708) (xy 228.737935 -102.715889) (xy 228.708469 -102.670039)
			(xy 228.685827 -102.620462) (xy 228.670472 -102.568167) (xy 228.662716 -102.514219) (xy 228.66223 -102.486968)
			(xy 228.08612 -102.486968) (xy 228.08905 -102.493383) (xy 228.104409 -102.545687) (xy 228.112167 -102.599644)
			(xy 228.112167 -102.654156) (xy 228.104409 -102.708113) (xy 228.08905 -102.760417) (xy 228.066404 -102.810002)
			(xy 228.036931 -102.855859) (xy 228.001231 -102.897055) (xy 227.960032 -102.932751) (xy 227.914172 -102.96222)
			(xy 227.864585 -102.984862) (xy 227.81228 -103.000216) (xy 227.758322 -103.007969) (xy 227.731066 -103.00843)
			(xy 227.704752 -103.007976) (xy 227.652623 -103.000737) (xy 227.60198 -102.986414) (xy 227.553782 -102.96528)
			(xy 227.508938 -102.937732) (xy 227.468299 -102.904292) (xy 227.450142 -102.88524) (xy 227.442601 -102.877861)
			(xy 227.423336 -102.869322) (xy 227.412804 -102.86873) (xy 227.338128 -102.86873) (xy 227.327577 -102.869252)
			(xy 227.308281 -102.877791) (xy 227.30079 -102.88524) (xy 227.28264 -102.904301) (xy 227.242008 -102.937756)
			(xy 227.197167 -102.965313) (xy 227.148965 -102.986451) (xy 227.098317 -103.000767) (xy 227.046182 -103.007991)
			(xy 227.019866 -103.00843) (xy 226.992618 -103.007897) (xy 226.938677 -103.000137) (xy 226.886389 -102.98478)
			(xy 226.836819 -102.962139) (xy 226.790976 -102.932673) (xy 226.749792 -102.896984) (xy 226.714107 -102.855797)
			(xy 226.684645 -102.809951) (xy 226.662008 -102.760379) (xy 226.646655 -102.70809) (xy 226.6389 -102.654148)
			(xy 225.648871 -102.654148) (xy 225.652838 -102.65918) (xy 225.653092 -102.659688) (xy 225.664036 -102.672422)
			(xy 225.683877 -102.699514) (xy 225.692716 -102.71379) (xy 225.69805 -102.72268) (xy 225.715068 -102.734872)
			(xy 225.808286 -102.755192) (xy 225.82886 -102.750874) (xy 225.837496 -102.745032) (xy 225.861562 -102.729035)
			(xy 225.913492 -102.703691) (xy 225.96865 -102.686464) (xy 226.025774 -102.677749) (xy 226.054666 -102.677214)
			(xy 226.081922 -102.677631) (xy 226.13588 -102.685384) (xy 226.188185 -102.700738) (xy 226.237772 -102.72338)
			(xy 226.283632 -102.752849) (xy 226.324831 -102.788545) (xy 226.360531 -102.829741) (xy 226.390004 -102.875598)
			(xy 226.41265 -102.925183) (xy 226.428009 -102.977487) (xy 226.435767 -103.031444) (xy 226.435767 -103.085956)
			(xy 226.428009 -103.139913) (xy 226.41265 -103.192217) (xy 226.390004 -103.241802) (xy 226.360531 -103.287659)
			(xy 226.324831 -103.328855) (xy 226.283632 -103.364551) (xy 226.237772 -103.39402) (xy 226.188185 -103.416662)
			(xy 226.13588 -103.432016) (xy 226.081922 -103.439769) (xy 226.054666 -103.44023) (xy 226.026574 -103.439756)
			(xy 225.970996 -103.431525) (xy 225.917227 -103.415229) (xy 225.866429 -103.391223) (xy 225.819703 -103.360025)
			(xy 225.778058 -103.322311) (xy 225.742396 -103.278895) (xy 225.727514 -103.255064) (xy 225.72218 -103.246174)
			(xy 225.705162 -103.233982) (xy 225.611944 -103.213662) (xy 225.59137 -103.21798) (xy 225.582734 -103.223822)
			(xy 225.558664 -103.239812) (xy 225.506735 -103.265157) (xy 225.451579 -103.282385) (xy 225.394456 -103.291103)
			(xy 225.365564 -103.29164) (xy 225.338313 -103.291156) (xy 225.284367 -103.283395) (xy 225.232074 -103.268037)
			(xy 225.182499 -103.245394) (xy 225.13665 -103.215927) (xy 225.095462 -103.180236) (xy 225.059771 -103.139046)
			(xy 225.030304 -103.093197) (xy 225.007661 -103.043622) (xy 224.992304 -102.991329) (xy 224.984544 -102.937383)
			(xy 224.984056 -102.910132) (xy 213.892892 -102.910132) (xy 213.892892 -103.81361) (xy 214.526874 -103.81361)
			(xy 214.530945 -103.757988) (xy 214.543071 -103.703551) (xy 214.562994 -103.65146) (xy 214.59029 -103.602825)
			(xy 214.624376 -103.558682) (xy 214.664525 -103.519973) (xy 214.709883 -103.487522) (xy 214.759483 -103.462021)
			(xy 214.812267 -103.444014) (xy 214.86711 -103.433884) (xy 214.922844 -103.431847) (xy 214.978281 -103.437947)
			(xy 215.032238 -103.452053) (xy 215.083567 -103.473865) (xy 215.131173 -103.502919) (xy 215.172436 -103.537258)
			(xy 220.43085 -103.537258) (xy 220.434921 -103.481636) (xy 220.447047 -103.427199) (xy 220.46697 -103.375108)
			(xy 220.494266 -103.326473) (xy 220.528352 -103.28233) (xy 220.568501 -103.243621) (xy 220.613859 -103.21117)
			(xy 220.663459 -103.185669) (xy 220.716243 -103.167662) (xy 220.771086 -103.157532) (xy 220.82682 -103.155495)
			(xy 220.882257 -103.161595) (xy 220.936214 -103.175701) (xy 220.987543 -103.197513) (xy 221.035149 -103.226567)
			(xy 221.078017 -103.262242) (xy 221.115234 -103.303779) (xy 221.146007 -103.350292) (xy 221.169679 -103.400789)
			(xy 221.185747 -103.454196) (xy 221.193867 -103.509372) (xy 221.194376 -103.537258) (xy 221.193867 -103.565144)
			(xy 221.185747 -103.62032) (xy 221.169679 -103.673727) (xy 221.146007 -103.724224) (xy 221.115234 -103.770737)
			(xy 221.078017 -103.812274) (xy 221.035149 -103.847949) (xy 220.987543 -103.877003) (xy 220.936214 -103.898815)
			(xy 220.882257 -103.912921) (xy 220.82682 -103.919021) (xy 220.771086 -103.916984) (xy 220.716243 -103.906854)
			(xy 220.663459 -103.888847) (xy 220.613859 -103.863346) (xy 220.568501 -103.830895) (xy 220.528352 -103.792186)
			(xy 220.494266 -103.748043) (xy 220.46697 -103.699408) (xy 220.447047 -103.647317) (xy 220.434921 -103.59288)
			(xy 220.43085 -103.537258) (xy 215.172436 -103.537258) (xy 215.174041 -103.538594) (xy 215.211258 -103.580131)
			(xy 215.242031 -103.626644) (xy 215.265703 -103.677141) (xy 215.281771 -103.730548) (xy 215.289891 -103.785724)
			(xy 215.2904 -103.81361) (xy 215.289891 -103.841496) (xy 215.281771 -103.896672) (xy 215.265703 -103.950079)
			(xy 215.242031 -104.000576) (xy 215.211258 -104.047089) (xy 215.174041 -104.088626) (xy 215.131173 -104.124301)
			(xy 215.083567 -104.153355) (xy 215.032238 -104.175167) (xy 214.978281 -104.189273) (xy 214.922844 -104.195373)
			(xy 214.86711 -104.193336) (xy 214.812267 -104.183206) (xy 214.759483 -104.165199) (xy 214.709883 -104.139698)
			(xy 214.664525 -104.107247) (xy 214.624376 -104.068538) (xy 214.59029 -104.024395) (xy 214.562994 -103.97576)
			(xy 214.543071 -103.923669) (xy 214.530945 -103.869232) (xy 214.526874 -103.81361) (xy 213.892892 -103.81361)
			(xy 213.892892 -104.492552) (xy 215.414096 -104.492552) (xy 215.418167 -104.43693) (xy 215.430293 -104.382493)
			(xy 215.450216 -104.330402) (xy 215.477512 -104.281767) (xy 215.511598 -104.237624) (xy 215.551747 -104.198915)
			(xy 215.597105 -104.166464) (xy 215.646705 -104.140963) (xy 215.699489 -104.122956) (xy 215.754332 -104.112826)
			(xy 215.810066 -104.110789) (xy 215.865503 -104.116889) (xy 215.91946 -104.130995) (xy 215.970789 -104.152807)
			(xy 216.018395 -104.181861) (xy 216.061263 -104.217536) (xy 216.09848 -104.259073) (xy 216.129253 -104.305586)
			(xy 216.152925 -104.356083) (xy 216.168993 -104.40949) (xy 216.177113 -104.464666) (xy 216.177622 -104.492552)
			(xy 216.177113 -104.520438) (xy 216.168993 -104.575614) (xy 216.152925 -104.629021) (xy 216.147719 -104.640126)
			(xy 216.7923 -104.640126) (xy 216.796371 -104.584504) (xy 216.808497 -104.530067) (xy 216.82842 -104.477976)
			(xy 216.855716 -104.429341) (xy 216.889802 -104.385198) (xy 216.929951 -104.346489) (xy 216.975309 -104.314038)
			(xy 217.024909 -104.288537) (xy 217.077693 -104.27053) (xy 217.132536 -104.2604) (xy 217.18827 -104.258363)
			(xy 217.243707 -104.264463) (xy 217.297664 -104.278569) (xy 217.348993 -104.300381) (xy 217.396599 -104.329435)
			(xy 217.439467 -104.36511) (xy 217.476684 -104.406647) (xy 217.507457 -104.45316) (xy 217.531129 -104.503657)
			(xy 217.547197 -104.557064) (xy 217.550344 -104.578448) (xy 222.806304 -104.578448) (xy 222.806304 -104.523952)
			(xy 222.814059 -104.470012) (xy 222.829411 -104.417724) (xy 222.852048 -104.368153) (xy 222.881508 -104.322308)
			(xy 222.917193 -104.281121) (xy 222.958376 -104.245432) (xy 223.004218 -104.215967) (xy 223.053787 -104.193325)
			(xy 223.106073 -104.177968) (xy 223.160013 -104.170207) (xy 223.18726 -104.169718) (xy 223.21463 -104.170203)
			(xy 223.268808 -104.178016) (xy 223.321311 -104.1935) (xy 223.371058 -104.216338) (xy 223.417026 -104.246058)
			(xy 223.437958 -104.263698) (xy 223.438212 -104.263952) (xy 223.445286 -104.269556) (xy 223.462213 -104.275791)
			(xy 223.471232 -104.276144) (xy 223.538288 -104.276144) (xy 223.547306 -104.275793) (xy 223.564223 -104.269543)
			(xy 223.571308 -104.263952) (xy 223.571308 -104.263698) (xy 223.571562 -104.263698) (xy 223.592497 -104.246063)
			(xy 223.638469 -104.216351) (xy 223.688216 -104.193514) (xy 223.740716 -104.178022) (xy 223.794891 -104.170193)
			(xy 223.82226 -104.169718) (xy 223.849517 -104.170126) (xy 223.903476 -104.177879) (xy 223.955782 -104.193233)
			(xy 224.00537 -104.215874) (xy 224.051232 -104.245343) (xy 224.092432 -104.28104) (xy 224.128133 -104.322236)
			(xy 224.157606 -104.368094) (xy 224.180253 -104.417681) (xy 224.195612 -104.469985) (xy 224.203371 -104.523943)
			(xy 224.203371 -104.578457) (xy 224.195612 -104.632415) (xy 224.180253 -104.684719) (xy 224.157606 -104.734306)
			(xy 224.128133 -104.780164) (xy 224.092432 -104.82136) (xy 224.051232 -104.857057) (xy 224.00537 -104.886526)
			(xy 223.955782 -104.909167) (xy 223.903476 -104.924521) (xy 223.849517 -104.932274) (xy 223.82226 -104.932734)
			(xy 223.79489 -104.932249) (xy 223.740711 -104.924438) (xy 223.688208 -104.908954) (xy 223.638461 -104.886116)
			(xy 223.592494 -104.856394) (xy 223.571562 -104.838754) (xy 223.571308 -104.8385) (xy 223.564223 -104.832911)
			(xy 223.547305 -104.826666) (xy 223.538288 -104.826308) (xy 223.471232 -104.826308) (xy 223.462216 -104.826678)
			(xy 223.445299 -104.832916) (xy 223.438212 -104.8385) (xy 223.438212 -104.838754) (xy 223.437958 -104.838754)
			(xy 223.417009 -104.856372) (xy 223.371042 -104.886089) (xy 223.321298 -104.908929) (xy 223.268801 -104.924425)
			(xy 223.214628 -104.932258) (xy 223.18726 -104.932734) (xy 223.160013 -104.932193) (xy 223.106073 -104.924432)
			(xy 223.053787 -104.909075) (xy 223.004218 -104.886433) (xy 222.958376 -104.856968) (xy 222.917193 -104.821279)
			(xy 222.881508 -104.780092) (xy 222.852048 -104.734247) (xy 222.829411 -104.684676) (xy 222.814059 -104.632388)
			(xy 222.806304 -104.578448) (xy 217.550344 -104.578448) (xy 217.555317 -104.61224) (xy 217.555826 -104.640126)
			(xy 217.555317 -104.668012) (xy 217.547197 -104.723188) (xy 217.531129 -104.776595) (xy 217.507457 -104.827092)
			(xy 217.476684 -104.873605) (xy 217.439467 -104.915142) (xy 217.396599 -104.950817) (xy 217.348993 -104.979871)
			(xy 217.297664 -105.001683) (xy 217.243707 -105.015789) (xy 217.18827 -105.021889) (xy 217.132536 -105.019852)
			(xy 217.077693 -105.009722) (xy 217.024909 -104.991715) (xy 216.975309 -104.966214) (xy 216.929951 -104.933763)
			(xy 216.889802 -104.895054) (xy 216.855716 -104.850911) (xy 216.82842 -104.802276) (xy 216.808497 -104.750185)
			(xy 216.796371 -104.695748) (xy 216.7923 -104.640126) (xy 216.147719 -104.640126) (xy 216.129253 -104.679518)
			(xy 216.09848 -104.726031) (xy 216.061263 -104.767568) (xy 216.018395 -104.803243) (xy 215.970789 -104.832297)
			(xy 215.91946 -104.854109) (xy 215.865503 -104.868215) (xy 215.810066 -104.874315) (xy 215.754332 -104.872278)
			(xy 215.699489 -104.862148) (xy 215.646705 -104.844141) (xy 215.597105 -104.81864) (xy 215.551747 -104.786189)
			(xy 215.511598 -104.74748) (xy 215.477512 -104.703337) (xy 215.450216 -104.654702) (xy 215.430293 -104.602611)
			(xy 215.418167 -104.548174) (xy 215.414096 -104.492552) (xy 213.892892 -104.492552) (xy 213.892892 -105.12806)
			(xy 217.654632 -105.12806) (xy 217.655118 -105.100809) (xy 217.662874 -105.046861) (xy 217.678229 -104.994566)
			(xy 217.700871 -104.944989) (xy 217.730337 -104.899139) (xy 217.766028 -104.857948) (xy 217.807219 -104.822257)
			(xy 217.853069 -104.792791) (xy 217.902646 -104.770149) (xy 217.954941 -104.754794) (xy 218.008889 -104.747038)
			(xy 218.063391 -104.747038) (xy 218.117339 -104.754794) (xy 218.169634 -104.770149) (xy 218.219211 -104.792791)
			(xy 218.265061 -104.822257) (xy 218.306252 -104.857948) (xy 218.341943 -104.899139) (xy 218.371409 -104.944989)
			(xy 218.394051 -104.994566) (xy 218.409406 -105.046861) (xy 218.417162 -105.100809) (xy 218.417648 -105.12806)
			(xy 218.417163 -105.155052) (xy 218.409562 -105.208499) (xy 218.394508 -105.260343) (xy 218.372299 -105.309548)
			(xy 218.34338 -105.355133) (xy 218.326208 -105.375964) (xy 218.319096 -105.384092) (xy 218.313 -105.404666)
			(xy 218.323922 -105.49001) (xy 218.32568 -105.500559) (xy 218.336746 -105.51884) (xy 218.337029 -105.519055)
			(xy 222.355843 -105.519055) (xy 222.355843 -105.464545) (xy 222.363601 -105.410591) (xy 222.378958 -105.35829)
			(xy 222.401603 -105.308707) (xy 222.431073 -105.262852) (xy 222.46677 -105.221657) (xy 222.507966 -105.185962)
			(xy 222.553823 -105.156494) (xy 222.603407 -105.133852) (xy 222.655709 -105.118497) (xy 222.709663 -105.110742)
			(xy 222.736918 -105.11028) (xy 222.76429 -105.110716) (xy 222.818471 -105.118538) (xy 222.870975 -105.134033)
			(xy 222.920721 -105.156882) (xy 222.966686 -105.186615) (xy 222.987616 -105.20426) (xy 222.98787 -105.204514)
			(xy 222.99496 -105.210096) (xy 223.011874 -105.216345) (xy 223.02089 -105.216706) (xy 223.087946 -105.216706)
			(xy 223.09696 -105.216322) (xy 223.113877 -105.210093) (xy 223.120966 -105.204514) (xy 223.120966 -105.20426)
			(xy 223.12122 -105.20426) (xy 223.142166 -105.186638) (xy 223.188136 -105.156925) (xy 223.23788 -105.134086)
			(xy 223.290377 -105.118591) (xy 223.34455 -105.110757) (xy 223.371918 -105.11028) (xy 223.399168 -105.110791)
			(xy 223.453112 -105.11855) (xy 223.505402 -105.133906) (xy 223.554976 -105.156547) (xy 223.600822 -105.186013)
			(xy 223.642009 -105.221704) (xy 223.677698 -105.262892) (xy 223.707161 -105.30874) (xy 223.7298 -105.358314)
			(xy 223.745154 -105.410606) (xy 223.75291 -105.46455) (xy 223.75291 -105.51905) (xy 223.745154 -105.572994)
			(xy 223.7298 -105.625286) (xy 223.707161 -105.67486) (xy 223.677698 -105.720708) (xy 223.642009 -105.761896)
			(xy 223.600822 -105.797587) (xy 223.554976 -105.827053) (xy 223.505402 -105.849694) (xy 223.453112 -105.86505)
			(xy 223.399168 -105.872809) (xy 223.371918 -105.873296) (xy 223.344548 -105.87282) (xy 223.290369 -105.865005)
			(xy 223.237866 -105.849518) (xy 223.188119 -105.826679) (xy 223.142152 -105.796956) (xy 223.12122 -105.779316)
			(xy 223.120966 -105.779062) (xy 223.113868 -105.773493) (xy 223.09696 -105.767237) (xy 223.087946 -105.76687)
			(xy 223.02089 -105.76687) (xy 223.011873 -105.767229) (xy 222.994957 -105.773476) (xy 222.98787 -105.779062)
			(xy 222.98787 -105.779316) (xy 222.987616 -105.779316) (xy 222.966691 -105.796964) (xy 222.920716 -105.826674)
			(xy 222.870967 -105.849508) (xy 222.818464 -105.864997) (xy 222.764288 -105.872823) (xy 222.736918 -105.873296)
			(xy 222.709663 -105.872858) (xy 222.655709 -105.865103) (xy 222.603407 -105.849748) (xy 222.553823 -105.827106)
			(xy 222.507966 -105.797638) (xy 222.46677 -105.761943) (xy 222.431073 -105.720748) (xy 222.401603 -105.674893)
			(xy 222.378958 -105.62531) (xy 222.363601 -105.573009) (xy 222.355843 -105.519055) (xy 218.337029 -105.519055)
			(xy 218.345258 -105.525316) (xy 218.369563 -105.542923) (xy 218.41282 -105.584522) (xy 218.431364 -105.60812)
			(xy 218.437206 -105.615994) (xy 218.454732 -105.626408) (xy 218.545156 -105.639616) (xy 218.56446 -105.63479)
			(xy 218.572334 -105.628948) (xy 218.572588 -105.628948) (xy 218.597318 -105.611424) (xy 218.651176 -105.583625)
			(xy 218.708752 -105.564695) (xy 218.768598 -105.555109) (xy 218.798902 -105.554526) (xy 218.826156 -105.554954)
			(xy 218.88011 -105.562712) (xy 218.932411 -105.57807) (xy 218.981993 -105.600715) (xy 219.027848 -105.630186)
			(xy 219.069042 -105.665884) (xy 219.104735 -105.707081) (xy 219.134202 -105.752938) (xy 219.156843 -105.802523)
			(xy 219.172196 -105.854825) (xy 219.179949 -105.90878) (xy 219.18041 -105.936034) (xy 219.179985 -105.962068)
			(xy 219.172893 -106.013652) (xy 219.158859 -106.063794) (xy 219.138143 -106.111565) (xy 219.111129 -106.156079)
			(xy 219.095066 -106.176572) (xy 219.089322 -106.184327) (xy 219.083584 -106.202739) (xy 219.08389 -106.212386)
			(xy 219.09024 -106.292142) (xy 219.098876 -106.309922) (xy 219.106242 -106.316272) (xy 219.125887 -106.334454)
			(xy 219.160411 -106.37536) (xy 219.188882 -106.420688) (xy 219.21074 -106.46955) (xy 219.225557 -106.520986)
			(xy 219.233042 -106.573988) (xy 219.233496 -106.600752) (xy 219.233 -106.628004) (xy 219.225249 -106.681955)
			(xy 219.209899 -106.734253) (xy 219.187261 -106.783833) (xy 219.157797 -106.829687) (xy 219.122106 -106.870881)
			(xy 219.080916 -106.906575) (xy 219.035065 -106.936044) (xy 218.985486 -106.958686) (xy 218.93319 -106.974042)
			(xy 218.87924 -106.981797) (xy 218.851988 -106.98226) (xy 218.823214 -106.981747) (xy 218.76632 -106.973091)
			(xy 218.71137 -106.955991) (xy 218.65961 -106.930835) (xy 218.612213 -106.898194) (xy 218.590876 -106.878882)
			(xy 218.583002 -106.871516) (xy 218.56319 -106.864404) (xy 218.466924 -106.87177) (xy 218.448128 -106.881676)
			(xy 218.441524 -106.890058) (xy 218.42332 -106.91226) (xy 218.381381 -106.95147) (xy 218.334041 -106.983954)
			(xy 218.282369 -107.00898) (xy 218.227531 -107.025982) (xy 218.170765 -107.034577) (xy 218.142058 -107.035092)
			(xy 218.114805 -107.034661) (xy 218.060854 -107.026899) (xy 218.008558 -107.011537) (xy 217.958979 -106.98889)
			(xy 217.913128 -106.959418) (xy 217.871938 -106.923721) (xy 217.836247 -106.882525) (xy 217.806782 -106.83667)
			(xy 217.784142 -106.787088) (xy 217.768789 -106.734789) (xy 217.761035 -106.680837) (xy 217.76055 -106.653584)
			(xy 217.761021 -106.626682) (xy 217.768594 -106.573413) (xy 217.783573 -106.521736) (xy 217.805662 -106.472675)
			(xy 217.834423 -106.427203) (xy 217.869285 -106.386221) (xy 217.909558 -106.350541) (xy 217.931746 -106.335322)
			(xy 217.942668 -106.32821) (xy 217.954606 -106.30535) (xy 217.952574 -106.193082) (xy 217.93962 -106.17073)
			(xy 217.928444 -106.163872) (xy 217.904851 -106.148937) (xy 217.861897 -106.113262) (xy 217.824601 -106.071707)
			(xy 217.793762 -106.02516) (xy 217.770037 -105.974614) (xy 217.753934 -105.921149) (xy 217.745796 -105.865908)
			(xy 217.74531 -105.83799) (xy 217.745776 -105.810997) (xy 217.753383 -105.75755) (xy 217.768442 -105.705707)
			(xy 217.790655 -105.656502) (xy 217.819577 -105.610917) (xy 217.83675 -105.590086) (xy 217.843862 -105.581958)
			(xy 217.849958 -105.561384) (xy 217.839036 -105.47604) (xy 217.837233 -105.465503) (xy 217.826198 -105.447218)
			(xy 217.8177 -105.440734) (xy 217.79648 -105.425367) (xy 217.758029 -105.38978) (xy 217.724811 -105.349265)
			(xy 217.697452 -105.304585) (xy 217.676467 -105.256579) (xy 217.66225 -105.206153) (xy 217.65507 -105.154256)
			(xy 217.654632 -105.12806) (xy 213.892892 -105.12806) (xy 213.892892 -106.238294) (xy 213.893296 -106.248366)
			(xy 213.901029 -106.266965) (xy 213.907878 -106.274362) (xy 215.045036 -107.41152) (xy 221.678754 -107.41152)
			(xy 221.679217 -107.385206) (xy 221.686451 -107.333076) (xy 221.700769 -107.282433) (xy 221.721902 -107.234233)
			(xy 221.74945 -107.18939) (xy 221.782891 -107.148752) (xy 221.801944 -107.130596) (xy 221.809341 -107.12307)
			(xy 221.81787 -107.103794) (xy 221.818454 -107.093258) (xy 221.818454 -107.018582) (xy 221.817907 -107.008034)
			(xy 221.809386 -106.988738) (xy 221.801944 -106.981244) (xy 221.782858 -106.96312) (xy 221.749405 -106.922482)
			(xy 221.721852 -106.877635) (xy 221.700719 -106.829428) (xy 221.686408 -106.778776) (xy 221.679189 -106.726638)
			(xy 221.678754 -106.70032) (xy 221.679297 -106.673071) (xy 221.68705 -106.619127) (xy 221.7024 -106.566836)
			(xy 221.725036 -106.517261) (xy 221.754497 -106.471413) (xy 221.790182 -106.430223) (xy 221.831366 -106.394532)
			(xy 221.877211 -106.365064) (xy 221.926782 -106.34242) (xy 221.979071 -106.327062) (xy 222.033013 -106.319301)
			(xy 222.060262 -106.318812) (xy 222.087926 -106.319348) (xy 222.142675 -106.327343) (xy 222.195696 -106.343155)
			(xy 222.24588 -106.366454) (xy 222.292176 -106.396751) (xy 222.333615 -106.433413) (xy 222.369328 -106.475672)
			(xy 222.384366 -106.498898) (xy 222.391031 -106.508552) (xy 222.410871 -106.52101) (xy 222.422466 -106.522774)
			(xy 222.502476 -106.530648) (xy 222.514114 -106.531258) (xy 222.53595 -106.523193) (xy 222.544386 -106.515154)
			(xy 222.54464 -106.5149) (xy 222.562719 -106.496317) (xy 222.603052 -106.463739) (xy 222.647426 -106.436926)
			(xy 222.695025 -106.416374) (xy 222.74497 -106.402461) (xy 222.796339 -106.395444) (xy 222.822262 -106.395012)
			(xy 222.849515 -106.395491) (xy 222.903466 -106.403243) (xy 222.955765 -106.418595) (xy 223.005346 -106.441235)
			(xy 223.051201 -106.470701) (xy 223.092394 -106.506393) (xy 223.128089 -106.547585) (xy 223.157557 -106.593438)
			(xy 223.180198 -106.643018) (xy 223.195553 -106.695316) (xy 223.203308 -106.749267) (xy 223.20377 -106.77652)
			(xy 223.203323 -106.803891) (xy 223.195502 -106.858071) (xy 223.180009 -106.910575) (xy 223.157162 -106.960321)
			(xy 223.127433 -107.006287) (xy 223.10979 -107.027218) (xy 223.109536 -107.027472) (xy 223.103947 -107.034557)
			(xy 223.097704 -107.051475) (xy 223.097344 -107.060492) (xy 223.097344 -107.127548) (xy 223.097716 -107.136564)
			(xy 223.103952 -107.153481) (xy 223.109536 -107.160568) (xy 223.10979 -107.160568) (xy 223.10979 -107.160822)
			(xy 223.127404 -107.181774) (xy 223.15712 -107.227741) (xy 223.179961 -107.277484) (xy 223.195458 -107.32998)
			(xy 223.203293 -107.384152) (xy 223.20377 -107.41152) (xy 223.203364 -107.438775) (xy 223.195603 -107.49273)
			(xy 223.180242 -107.545031) (xy 223.157595 -107.594614) (xy 223.128121 -107.640469) (xy 223.092421 -107.681663)
			(xy 223.051223 -107.717356) (xy 223.005363 -107.746823) (xy 222.955777 -107.769463) (xy 222.903473 -107.784815)
			(xy 222.849517 -107.792568) (xy 222.822262 -107.793028) (xy 222.793345 -107.792492) (xy 222.736174 -107.783771)
			(xy 222.680974 -107.766518) (xy 222.629012 -107.74113) (xy 222.581478 -107.708188) (xy 222.539462 -107.668447)
			(xy 222.521272 -107.645962) (xy 222.513674 -107.637146) (xy 222.492766 -107.626969) (xy 222.48114 -107.626404)
			(xy 222.401384 -107.626404) (xy 222.389753 -107.626947) (xy 222.368843 -107.637133) (xy 222.361252 -107.645962)
			(xy 222.343022 -107.668413) (xy 222.301012 -107.708152) (xy 222.253485 -107.741096) (xy 222.201531 -107.76649)
			(xy 222.14634 -107.783753) (xy 222.089176 -107.792489) (xy 222.060262 -107.793028) (xy 222.033011 -107.792558)
			(xy 221.979063 -107.784796) (xy 221.92677 -107.769437) (xy 221.877194 -107.746793) (xy 221.831344 -107.717325)
			(xy 221.790155 -107.681632) (xy 221.754464 -107.640441) (xy 221.724998 -107.594591) (xy 221.702356 -107.545013)
			(xy 221.687 -107.492719) (xy 221.679241 -107.438771) (xy 221.678754 -107.41152) (xy 215.045036 -107.41152)
			(xy 215.469767 -107.836251) (xy 233.797585 -107.836251) (xy 233.797585 -107.781749) (xy 233.805342 -107.727802)
			(xy 233.820697 -107.675508) (xy 233.843337 -107.625932) (xy 233.872803 -107.580082) (xy 233.908494 -107.538893)
			(xy 233.949684 -107.503202) (xy 233.995534 -107.473737) (xy 234.04511 -107.451096) (xy 234.097404 -107.435741)
			(xy 234.151351 -107.427985) (xy 234.178602 -107.427522) (xy 234.204916 -107.427981) (xy 234.257045 -107.435217)
			(xy 234.307689 -107.449537) (xy 234.355888 -107.470671) (xy 234.400731 -107.498219) (xy 234.44137 -107.531659)
			(xy 234.459526 -107.550712) (xy 234.467034 -107.558129) (xy 234.486325 -107.566644) (xy 234.496864 -107.567222)
			(xy 234.57154 -107.567222) (xy 234.582087 -107.566667) (xy 234.601382 -107.558149) (xy 234.608878 -107.550712)
			(xy 234.628698 -107.529924) (xy 234.67347 -107.493949) (xy 234.723128 -107.465089) (xy 234.77655 -107.443996)
			(xy 234.832529 -107.431147) (xy 234.889802 -107.426832) (xy 234.947075 -107.431147) (xy 235.003054 -107.443996)
			(xy 235.056476 -107.465089) (xy 235.106134 -107.493949) (xy 235.150906 -107.529924) (xy 235.170726 -107.550712)
			(xy 235.178234 -107.558129) (xy 235.197525 -107.566644) (xy 235.208064 -107.567222) (xy 235.28274 -107.567222)
			(xy 235.293287 -107.566667) (xy 235.312582 -107.558149) (xy 235.320078 -107.550712) (xy 235.338254 -107.531676)
			(xy 235.378879 -107.498217) (xy 235.423715 -107.470655) (xy 235.471912 -107.449513) (xy 235.522556 -107.435192)
			(xy 235.574687 -107.427963) (xy 235.601002 -107.427522) (xy 235.628255 -107.427948) (xy 235.682207 -107.435705)
			(xy 235.734506 -107.451062) (xy 235.784087 -107.473705) (xy 235.82994 -107.503174) (xy 235.871134 -107.538868)
			(xy 235.906828 -107.580061) (xy 235.936296 -107.625915) (xy 235.958939 -107.675496) (xy 235.974295 -107.727795)
			(xy 235.982052 -107.781747) (xy 235.982052 -107.836253) (xy 235.974295 -107.890205) (xy 235.958939 -107.942504)
			(xy 235.936296 -107.992085) (xy 235.906828 -108.037939) (xy 235.871134 -108.079132) (xy 235.82994 -108.114826)
			(xy 235.784087 -108.144295) (xy 235.734506 -108.166938) (xy 235.682207 -108.182295) (xy 235.628255 -108.190052)
			(xy 235.601002 -108.190538) (xy 235.574687 -108.190089) (xy 235.522557 -108.182853) (xy 235.471913 -108.168532)
			(xy 235.423714 -108.147396) (xy 235.378871 -108.119846) (xy 235.338233 -108.086402) (xy 235.320078 -108.067348)
			(xy 235.31256 -108.059942) (xy 235.293278 -108.051419) (xy 235.28274 -108.050838) (xy 235.208064 -108.050838)
			(xy 235.197515 -108.051377) (xy 235.178219 -108.059904) (xy 235.170726 -108.067348) (xy 235.150906 -108.088136)
			(xy 235.106134 -108.124111) (xy 235.056476 -108.152971) (xy 235.003054 -108.174064) (xy 234.947075 -108.186913)
			(xy 234.889802 -108.191228) (xy 234.832529 -108.186913) (xy 234.77655 -108.174064) (xy 234.723128 -108.152971)
			(xy 234.67347 -108.124111) (xy 234.628698 -108.088136) (xy 234.608878 -108.067348) (xy 234.60136 -108.059942)
			(xy 234.582078 -108.051419) (xy 234.57154 -108.050838) (xy 234.496864 -108.050838) (xy 234.486315 -108.051377)
			(xy 234.467019 -108.059904) (xy 234.459526 -108.067348) (xy 234.44136 -108.086393) (xy 234.400732 -108.119849)
			(xy 234.355893 -108.147409) (xy 234.307695 -108.168548) (xy 234.257049 -108.182868) (xy 234.204917 -108.190097)
			(xy 234.178602 -108.190538) (xy 234.151351 -108.190015) (xy 234.097404 -108.182259) (xy 234.04511 -108.166904)
			(xy 233.995534 -108.144263) (xy 233.949684 -108.114798) (xy 233.908494 -108.079107) (xy 233.872803 -108.037918)
			(xy 233.843337 -107.992068) (xy 233.820697 -107.942492) (xy 233.805342 -107.890198) (xy 233.797585 -107.836251)
			(xy 215.469767 -107.836251) (xy 215.644222 -108.010706) (xy 215.666205 -108.033455) (xy 215.704709 -108.083648)
			(xy 215.736335 -108.138436) (xy 215.760542 -108.196882) (xy 215.776917 -108.257987) (xy 215.785179 -108.320706)
			(xy 215.7857 -108.352336) (xy 215.7857 -108.473054) (xy 221.556763 -108.473054) (xy 221.556763 -108.418546)
			(xy 221.564521 -108.364593) (xy 221.579879 -108.312294) (xy 221.602523 -108.262713) (xy 221.631994 -108.216859)
			(xy 221.66769 -108.175666) (xy 221.708886 -108.139973) (xy 221.754742 -108.110507) (xy 221.804326 -108.087867)
			(xy 221.856627 -108.072514) (xy 221.91058 -108.064761) (xy 221.937834 -108.0643) (xy 221.965205 -108.064746)
			(xy 222.019385 -108.072569) (xy 222.071888 -108.088063) (xy 222.121635 -108.110909) (xy 222.167601 -108.140637)
			(xy 222.188532 -108.15828) (xy 222.188786 -108.158534) (xy 222.19587 -108.164125) (xy 222.212789 -108.170368)
			(xy 222.221806 -108.170726) (xy 222.288862 -108.170726) (xy 222.297876 -108.170345) (xy 222.314793 -108.164114)
			(xy 222.321882 -108.158534) (xy 222.321882 -108.15828) (xy 222.322136 -108.15828) (xy 222.343069 -108.140639)
			(xy 222.389037 -108.110915) (xy 222.438783 -108.088069) (xy 222.491285 -108.072573) (xy 222.545463 -108.064744)
			(xy 222.600205 -108.064744) (xy 222.654383 -108.072573) (xy 222.706885 -108.088069) (xy 222.756631 -108.110915)
			(xy 222.802599 -108.140639) (xy 222.823532 -108.15828) (xy 222.823786 -108.158534) (xy 222.83087 -108.164125)
			(xy 222.847789 -108.170368) (xy 222.856806 -108.170726) (xy 222.923862 -108.170726) (xy 222.932876 -108.170345)
			(xy 222.949793 -108.164114) (xy 222.956882 -108.158534) (xy 222.956882 -108.15828) (xy 222.957136 -108.15828)
			(xy 222.978069 -108.140639) (xy 223.024037 -108.110915) (xy 223.073783 -108.088069) (xy 223.126285 -108.072573)
			(xy 223.180463 -108.064744) (xy 223.235205 -108.064744) (xy 223.289383 -108.072573) (xy 223.341885 -108.088069)
			(xy 223.391631 -108.110915) (xy 223.437599 -108.140639) (xy 223.458532 -108.15828) (xy 223.458786 -108.158534)
			(xy 223.46587 -108.164125) (xy 223.482789 -108.170368) (xy 223.491806 -108.170726) (xy 223.558862 -108.170726)
			(xy 223.567876 -108.170345) (xy 223.584793 -108.164114) (xy 223.591882 -108.158534) (xy 223.591882 -108.15828)
			(xy 223.592136 -108.15828) (xy 223.613079 -108.140654) (xy 223.659049 -108.110941) (xy 223.708794 -108.088103)
			(xy 223.761292 -108.072609) (xy 223.815466 -108.064776) (xy 223.842834 -108.0643) (xy 223.870084 -108.064772)
			(xy 223.924029 -108.072533) (xy 223.976321 -108.087891) (xy 224.025895 -108.110535) (xy 224.071742 -108.140002)
			(xy 224.112929 -108.175695) (xy 224.148618 -108.216885) (xy 224.178082 -108.262735) (xy 224.200721 -108.312311)
			(xy 224.216075 -108.364604) (xy 224.22383 -108.41855) (xy 224.22383 -108.47305) (xy 224.216075 -108.526996)
			(xy 224.200721 -108.579289) (xy 224.178082 -108.628865) (xy 224.148618 -108.674715) (xy 224.112929 -108.715905)
			(xy 224.071742 -108.751598) (xy 224.025895 -108.781065) (xy 223.976321 -108.803709) (xy 223.924029 -108.819067)
			(xy 223.870084 -108.826828) (xy 223.842834 -108.827316) (xy 223.815464 -108.82685) (xy 223.761284 -108.819036)
			(xy 223.70878 -108.803548) (xy 223.659033 -108.780705) (xy 223.613067 -108.750979) (xy 223.592136 -108.733336)
			(xy 223.591882 -108.733082) (xy 223.584806 -108.72748) (xy 223.567881 -108.721243) (xy 223.558862 -108.72089)
			(xy 223.491806 -108.72089) (xy 223.48279 -108.721252) (xy 223.465873 -108.727496) (xy 223.458786 -108.733082)
			(xy 223.458786 -108.733336) (xy 223.458532 -108.733336) (xy 223.437599 -108.750977) (xy 223.391631 -108.780701)
			(xy 223.341885 -108.803547) (xy 223.289383 -108.819043) (xy 223.235205 -108.826872) (xy 223.180463 -108.826872)
			(xy 223.126285 -108.819043) (xy 223.073783 -108.803547) (xy 223.024037 -108.780701) (xy 222.978069 -108.750977)
			(xy 222.957136 -108.733336) (xy 222.956882 -108.733082) (xy 222.949806 -108.72748) (xy 222.932881 -108.721243)
			(xy 222.923862 -108.72089) (xy 222.856806 -108.72089) (xy 222.84779 -108.721252) (xy 222.830873 -108.727496)
			(xy 222.823786 -108.733082) (xy 222.823786 -108.733336) (xy 222.823532 -108.733336) (xy 222.802599 -108.750977)
			(xy 222.756631 -108.780701) (xy 222.706885 -108.803547) (xy 222.654383 -108.819043) (xy 222.600205 -108.826872)
			(xy 222.545463 -108.826872) (xy 222.491285 -108.819043) (xy 222.438783 -108.803547) (xy 222.389037 -108.780701)
			(xy 222.343069 -108.750977) (xy 222.322136 -108.733336) (xy 222.321882 -108.733082) (xy 222.314806 -108.72748)
			(xy 222.297881 -108.721243) (xy 222.288862 -108.72089) (xy 222.221806 -108.72089) (xy 222.21279 -108.721252)
			(xy 222.195873 -108.727496) (xy 222.188786 -108.733082) (xy 222.188786 -108.733336) (xy 222.188532 -108.733336)
			(xy 222.167603 -108.750979) (xy 222.121629 -108.780689) (xy 222.071881 -108.803524) (xy 222.019379 -108.819014)
			(xy 221.965203 -108.826842) (xy 221.937834 -108.827316) (xy 221.91058 -108.826839) (xy 221.856627 -108.819086)
			(xy 221.804326 -108.803733) (xy 221.754742 -108.781093) (xy 221.708886 -108.751627) (xy 221.66769 -108.715934)
			(xy 221.631994 -108.674741) (xy 221.602523 -108.628887) (xy 221.579879 -108.579306) (xy 221.564521 -108.527007)
			(xy 221.556763 -108.473054) (xy 215.7857 -108.473054) (xy 215.7857 -111.128853) (xy 221.497087 -111.128853)
			(xy 221.497087 -111.074347) (xy 221.504845 -111.020397) (xy 221.520202 -110.9681) (xy 221.542846 -110.918521)
			(xy 221.572315 -110.87267) (xy 221.608011 -110.83148) (xy 221.649205 -110.795789) (xy 221.69506 -110.766325)
			(xy 221.744641 -110.743686) (xy 221.79694 -110.728335) (xy 221.850891 -110.720584) (xy 221.878144 -110.720124)
			(xy 221.905513 -110.720617) (xy 221.959691 -110.728427) (xy 222.012195 -110.74391) (xy 222.061942 -110.766746)
			(xy 222.10791 -110.796465) (xy 222.128842 -110.814104) (xy 222.129096 -110.814358) (xy 222.136175 -110.819956)
			(xy 222.153098 -110.826194) (xy 222.162116 -110.82655) (xy 222.229172 -110.82655) (xy 222.238189 -110.82619)
			(xy 222.255106 -110.819946) (xy 222.262192 -110.814358) (xy 222.262192 -110.814104) (xy 222.262446 -110.814104)
			(xy 222.283379 -110.796463) (xy 222.329347 -110.766739) (xy 222.379093 -110.743893) (xy 222.431595 -110.728397)
			(xy 222.485773 -110.720568) (xy 222.540515 -110.720568) (xy 222.594693 -110.728397) (xy 222.647195 -110.743893)
			(xy 222.696941 -110.766739) (xy 222.742909 -110.796463) (xy 222.763842 -110.814104) (xy 222.764096 -110.814358)
			(xy 222.771175 -110.819956) (xy 222.788098 -110.826194) (xy 222.797116 -110.82655) (xy 222.864172 -110.82655)
			(xy 222.873189 -110.82619) (xy 222.890106 -110.819946) (xy 222.897192 -110.814358) (xy 222.897192 -110.814104)
			(xy 222.897446 -110.814104) (xy 222.918379 -110.796463) (xy 222.964347 -110.766739) (xy 223.014093 -110.743893)
			(xy 223.066595 -110.728397) (xy 223.120773 -110.720568) (xy 223.175515 -110.720568) (xy 223.229693 -110.728397)
			(xy 223.282195 -110.743893) (xy 223.331941 -110.766739) (xy 223.377909 -110.796463) (xy 223.398842 -110.814104)
			(xy 223.399096 -110.814358) (xy 223.406175 -110.819956) (xy 223.423098 -110.826194) (xy 223.432116 -110.82655)
			(xy 223.499172 -110.82655) (xy 223.508189 -110.82619) (xy 223.525106 -110.819946) (xy 223.532192 -110.814358)
			(xy 223.532192 -110.814104) (xy 223.532446 -110.814104) (xy 223.553388 -110.796477) (xy 223.599358 -110.766764)
			(xy 223.649103 -110.743925) (xy 223.701602 -110.728431) (xy 223.755776 -110.7206) (xy 223.783144 -110.720124)
			(xy 223.810395 -110.720549) (xy 223.864343 -110.728311) (xy 223.916637 -110.743671) (xy 223.966213 -110.766317)
			(xy 224.012061 -110.795787) (xy 224.05325 -110.831481) (xy 224.08894 -110.872674) (xy 224.118404 -110.918526)
			(xy 224.134218 -110.953156) (xy 233.725619 -110.953156) (xy 233.725619 -110.898644) (xy 233.733377 -110.844686)
			(xy 233.748736 -110.792381) (xy 233.771382 -110.742795) (xy 233.800855 -110.696937) (xy 233.836554 -110.65574)
			(xy 233.877753 -110.620043) (xy 233.923613 -110.590572) (xy 233.9732 -110.567929) (xy 234.025505 -110.552573)
			(xy 234.079464 -110.544818) (xy 234.10672 -110.544356) (xy 234.133035 -110.544792) (xy 234.185166 -110.552031)
			(xy 234.23581 -110.566355) (xy 234.284009 -110.587493) (xy 234.328852 -110.615046) (xy 234.369489 -110.648491)
			(xy 234.387644 -110.667546) (xy 234.395155 -110.674961) (xy 234.414443 -110.68348) (xy 234.424982 -110.684056)
			(xy 234.499658 -110.684056) (xy 234.510208 -110.683531) (xy 234.529505 -110.674994) (xy 234.536996 -110.667546)
			(xy 234.556816 -110.646758) (xy 234.601588 -110.610783) (xy 234.651246 -110.581923) (xy 234.704668 -110.56083)
			(xy 234.760647 -110.547981) (xy 234.81792 -110.543666) (xy 234.875193 -110.547981) (xy 234.931172 -110.56083)
			(xy 234.984594 -110.581923) (xy 235.034252 -110.610783) (xy 235.079024 -110.646758) (xy 235.098844 -110.667546)
			(xy 235.106355 -110.674961) (xy 235.125643 -110.68348) (xy 235.136182 -110.684056) (xy 235.210858 -110.684056)
			(xy 235.221408 -110.683531) (xy 235.240705 -110.674994) (xy 235.248196 -110.667546) (xy 235.26635 -110.648489)
			(xy 235.306981 -110.615034) (xy 235.351822 -110.587477) (xy 235.400023 -110.566339) (xy 235.45067 -110.552021)
			(xy 235.502804 -110.544795) (xy 235.52912 -110.544356) (xy 235.556368 -110.544916) (xy 235.610308 -110.552674)
			(xy 235.662595 -110.568029) (xy 235.712165 -110.590669) (xy 235.758009 -110.620133) (xy 235.799193 -110.655821)
			(xy 235.834879 -110.697007) (xy 235.86434 -110.742852) (xy 235.886978 -110.792423) (xy 235.902331 -110.844711)
			(xy 235.910086 -110.898652) (xy 235.910086 -110.953148) (xy 235.902331 -111.007089) (xy 235.886978 -111.059377)
			(xy 235.86434 -111.108948) (xy 235.834879 -111.154793) (xy 235.799193 -111.195979) (xy 235.758009 -111.231667)
			(xy 235.712165 -111.261131) (xy 235.662595 -111.283771) (xy 235.610308 -111.299126) (xy 235.556368 -111.306884)
			(xy 235.52912 -111.307372) (xy 235.502806 -111.3069) (xy 235.450677 -111.299667) (xy 235.400034 -111.28535)
			(xy 235.351835 -111.264218) (xy 235.306992 -111.236673) (xy 235.266352 -111.203234) (xy 235.248196 -111.184182)
			(xy 235.24068 -111.176774) (xy 235.221396 -111.168254) (xy 235.210858 -111.167672) (xy 235.136182 -111.167672)
			(xy 235.125637 -111.16824) (xy 235.106342 -111.176749) (xy 235.098844 -111.184182) (xy 235.079024 -111.20497)
			(xy 235.034252 -111.240945) (xy 234.984594 -111.269805) (xy 234.931172 -111.290898) (xy 234.875193 -111.303747)
			(xy 234.81792 -111.308062) (xy 234.760647 -111.303747) (xy 234.704668 -111.290898) (xy 234.651246 -111.269805)
			(xy 234.601588 -111.240945) (xy 234.556816 -111.20497) (xy 234.536996 -111.184182) (xy 234.52948 -111.176774)
			(xy 234.510196 -111.168254) (xy 234.499658 -111.167672) (xy 234.424982 -111.167672) (xy 234.414437 -111.16824)
			(xy 234.395142 -111.176749) (xy 234.387644 -111.184182) (xy 234.369505 -111.203254) (xy 234.328872 -111.236711)
			(xy 234.284029 -111.264268) (xy 234.235824 -111.285404) (xy 234.185174 -111.299717) (xy 234.133037 -111.306936)
			(xy 234.10672 -111.307372) (xy 234.079464 -111.306982) (xy 234.025505 -111.299227) (xy 233.9732 -111.283871)
			(xy 233.923613 -111.261228) (xy 233.877753 -111.231757) (xy 233.836554 -111.19606) (xy 233.800855 -111.154863)
			(xy 233.771382 -111.109005) (xy 233.748736 -111.059419) (xy 233.733377 -111.007114) (xy 233.725619 -110.953156)
			(xy 224.134218 -110.953156) (xy 224.141044 -110.968104) (xy 224.156398 -111.0204) (xy 224.164154 -111.074348)
			(xy 224.164154 -111.128852) (xy 224.156398 -111.1828) (xy 224.141044 -111.235096) (xy 224.118404 -111.284674)
			(xy 224.08894 -111.330526) (xy 224.05325 -111.371719) (xy 224.012061 -111.407413) (xy 223.966213 -111.436883)
			(xy 223.916637 -111.459529) (xy 223.864343 -111.474889) (xy 223.810395 -111.482651) (xy 223.783144 -111.48314)
			(xy 223.755774 -111.482663) (xy 223.701595 -111.47485) (xy 223.649091 -111.459364) (xy 223.599344 -111.436525)
			(xy 223.553377 -111.406801) (xy 223.532446 -111.38916) (xy 223.532192 -111.388906) (xy 223.525111 -111.383311)
			(xy 223.50819 -111.377069) (xy 223.499172 -111.376714) (xy 223.432116 -111.376714) (xy 223.4231 -111.377075)
			(xy 223.406182 -111.38332) (xy 223.399096 -111.388906) (xy 223.399096 -111.38916) (xy 223.398842 -111.38916)
			(xy 223.377909 -111.406801) (xy 223.331941 -111.436525) (xy 223.282195 -111.459371) (xy 223.229693 -111.474867)
			(xy 223.175515 -111.482696) (xy 223.120773 -111.482696) (xy 223.066595 -111.474867) (xy 223.014093 -111.459371)
			(xy 222.964347 -111.436525) (xy 222.918379 -111.406801) (xy 222.897446 -111.38916) (xy 222.897192 -111.388906)
			(xy 222.890111 -111.383311) (xy 222.87319 -111.377069) (xy 222.864172 -111.376714) (xy 222.797116 -111.376714)
			(xy 222.7881 -111.377075) (xy 222.771182 -111.38332) (xy 222.764096 -111.388906) (xy 222.764096 -111.38916)
			(xy 222.763842 -111.38916) (xy 222.742909 -111.406801) (xy 222.696941 -111.436525) (xy 222.647195 -111.459371)
			(xy 222.594693 -111.474867) (xy 222.540515 -111.482696) (xy 222.485773 -111.482696) (xy 222.431595 -111.474867)
			(xy 222.379093 -111.459371) (xy 222.329347 -111.436525) (xy 222.283379 -111.406801) (xy 222.262446 -111.38916)
			(xy 222.262192 -111.388906) (xy 222.255111 -111.383311) (xy 222.23819 -111.377069) (xy 222.229172 -111.376714)
			(xy 222.162116 -111.376714) (xy 222.1531 -111.377075) (xy 222.136182 -111.38332) (xy 222.129096 -111.388906)
			(xy 222.129096 -111.38916) (xy 222.128842 -111.38916) (xy 222.1079 -111.406787) (xy 222.06193 -111.436502)
			(xy 222.012186 -111.459341) (xy 221.959687 -111.474835) (xy 221.905513 -111.482665) (xy 221.878144 -111.48314)
			(xy 221.850891 -111.482616) (xy 221.79694 -111.474865) (xy 221.744641 -111.459514) (xy 221.69506 -111.436875)
			(xy 221.649205 -111.407411) (xy 221.608011 -111.37172) (xy 221.572315 -111.33053) (xy 221.542846 -111.284679)
			(xy 221.520202 -111.2351) (xy 221.504845 -111.182803) (xy 221.497087 -111.128853) (xy 215.7857 -111.128853)
			(xy 215.7857 -112.72012) (xy 232.673906 -112.72012) (xy 232.674382 -112.69275) (xy 232.682197 -112.638571)
			(xy 232.697684 -112.586068) (xy 232.720524 -112.536321) (xy 232.750246 -112.490354) (xy 232.767886 -112.469422)
			(xy 232.76814 -112.469168) (xy 232.773709 -112.46207) (xy 232.779965 -112.445162) (xy 232.780332 -112.436148)
			(xy 232.780332 -112.369092) (xy 232.779972 -112.360076) (xy 232.773726 -112.343159) (xy 232.76814 -112.336072)
			(xy 232.767886 -112.336072) (xy 232.767886 -112.335818) (xy 232.75024 -112.314892) (xy 232.720529 -112.268917)
			(xy 232.697695 -112.219168) (xy 232.682206 -112.166666) (xy 232.674379 -112.11249) (xy 232.673906 -112.08512)
			(xy 232.674392 -112.057869) (xy 232.682148 -112.003921) (xy 232.697503 -111.951626) (xy 232.720145 -111.902049)
			(xy 232.749611 -111.856199) (xy 232.785302 -111.815008) (xy 232.826493 -111.779317) (xy 232.872343 -111.749851)
			(xy 232.92192 -111.727209) (xy 232.974215 -111.711854) (xy 233.028163 -111.704098) (xy 233.082665 -111.704098)
			(xy 233.136613 -111.711854) (xy 233.188908 -111.727209) (xy 233.238485 -111.749851) (xy 233.284335 -111.779317)
			(xy 233.325526 -111.815008) (xy 233.361217 -111.856199) (xy 233.390683 -111.902049) (xy 233.413325 -111.951626)
			(xy 233.42868 -112.003921) (xy 233.436436 -112.057869) (xy 233.436922 -112.08512) (xy 233.436487 -112.112492)
			(xy 233.428664 -112.166673) (xy 233.413169 -112.219177) (xy 233.39032 -112.268923) (xy 233.360587 -112.314888)
			(xy 233.342942 -112.335818) (xy 233.342688 -112.336072) (xy 233.337106 -112.343161) (xy 233.330857 -112.360076)
			(xy 233.330496 -112.369092) (xy 233.330496 -112.436148) (xy 233.330879 -112.445162) (xy 233.337109 -112.462079)
			(xy 233.342688 -112.469168) (xy 233.342942 -112.469168) (xy 233.342942 -112.469422) (xy 233.360565 -112.490367)
			(xy 233.390278 -112.536337) (xy 233.413116 -112.586081) (xy 233.428611 -112.638579) (xy 233.436445 -112.692752)
			(xy 233.436922 -112.72012) (xy 233.436436 -112.747371) (xy 233.42868 -112.801319) (xy 233.413325 -112.853614)
			(xy 233.390683 -112.903191) (xy 233.361217 -112.949041) (xy 233.325526 -112.990232) (xy 233.284335 -113.025923)
			(xy 233.238485 -113.055389) (xy 233.188908 -113.078031) (xy 233.136613 -113.093386) (xy 233.082665 -113.101142)
			(xy 233.028163 -113.101142) (xy 232.974215 -113.093386) (xy 232.92192 -113.078031) (xy 232.872343 -113.055389)
			(xy 232.826493 -113.025923) (xy 232.785302 -112.990232) (xy 232.749611 -112.949041) (xy 232.720145 -112.903191)
			(xy 232.697503 -112.853614) (xy 232.682148 -112.801319) (xy 232.674392 -112.747371) (xy 232.673906 -112.72012)
			(xy 215.7857 -112.72012) (xy 215.7857 -113.653062) (xy 235.227366 -113.653062) (xy 235.231437 -113.59744)
			(xy 235.243563 -113.543003) (xy 235.263486 -113.490912) (xy 235.290782 -113.442277) (xy 235.324868 -113.398134)
			(xy 235.365017 -113.359425) (xy 235.410375 -113.326974) (xy 235.459975 -113.301473) (xy 235.512759 -113.283466)
			(xy 235.567602 -113.273336) (xy 235.623336 -113.271299) (xy 235.678773 -113.277399) (xy 235.73273 -113.291505)
			(xy 235.784059 -113.313317) (xy 235.831665 -113.342371) (xy 235.874533 -113.378046) (xy 235.91175 -113.419583)
			(xy 235.942523 -113.466096) (xy 235.966195 -113.516593) (xy 235.982263 -113.57) (xy 235.990383 -113.625176)
			(xy 235.990892 -113.653062) (xy 235.990383 -113.680948) (xy 235.982263 -113.736124) (xy 235.966195 -113.789531)
			(xy 235.942523 -113.840028) (xy 235.91175 -113.886541) (xy 235.874533 -113.928078) (xy 235.831665 -113.963753)
			(xy 235.784059 -113.992807) (xy 235.73273 -114.014619) (xy 235.678773 -114.028725) (xy 235.623336 -114.034825)
			(xy 235.567602 -114.032788) (xy 235.512759 -114.022658) (xy 235.459975 -114.004651) (xy 235.410375 -113.97915)
			(xy 235.365017 -113.946699) (xy 235.324868 -113.90799) (xy 235.290782 -113.863847) (xy 235.263486 -113.815212)
			(xy 235.243563 -113.763121) (xy 235.231437 -113.708684) (xy 235.227366 -113.653062) (xy 215.7857 -113.653062)
			(xy 215.7857 -116.188224) (xy 223.368955 -116.188224) (xy 223.373268 -116.130954) (xy 223.386114 -116.074977)
			(xy 223.407204 -116.021557) (xy 223.436062 -115.971901) (xy 223.472035 -115.927131) (xy 223.492822 -115.907312)
			(xy 223.500224 -115.899791) (xy 223.508747 -115.88051) (xy 223.509332 -115.869974) (xy 223.509332 -115.795298)
			(xy 223.508808 -115.784748) (xy 223.500268 -115.765453) (xy 223.492822 -115.75796) (xy 223.473758 -115.739813)
			(xy 223.440301 -115.699182) (xy 223.412743 -115.65434) (xy 223.391605 -115.606137) (xy 223.37729 -115.555488)
			(xy 223.370069 -115.503353) (xy 223.369632 -115.477036) (xy 223.370118 -115.449785) (xy 223.377874 -115.395837)
			(xy 223.393229 -115.343542) (xy 223.415871 -115.293965) (xy 223.445337 -115.248115) (xy 223.481028 -115.206924)
			(xy 223.522219 -115.171233) (xy 223.568069 -115.141767) (xy 223.617646 -115.119125) (xy 223.669941 -115.10377)
			(xy 223.723889 -115.096014) (xy 223.778391 -115.096014) (xy 223.832339 -115.10377) (xy 223.884634 -115.119125)
			(xy 223.934211 -115.141767) (xy 223.980061 -115.171233) (xy 224.021252 -115.206924) (xy 224.056943 -115.248115)
			(xy 224.086409 -115.293965) (xy 224.109051 -115.343542) (xy 224.124406 -115.395837) (xy 224.132162 -115.449785)
			(xy 224.132648 -115.477036) (xy 224.132221 -115.503352) (xy 224.12498 -115.555482) (xy 224.110654 -115.606127)
			(xy 224.089514 -115.654326) (xy 224.06196 -115.699168) (xy 224.028514 -115.739805) (xy 224.009458 -115.75796)
			(xy 224.002081 -115.765502) (xy 223.99354 -115.784766) (xy 223.992948 -115.795298) (xy 223.992948 -115.869974)
			(xy 223.993464 -115.880526) (xy 224.002007 -115.899822) (xy 224.009458 -115.907312) (xy 224.03028 -115.927097)
			(xy 224.066251 -115.971876) (xy 224.095107 -116.021539) (xy 224.116195 -116.074966) (xy 224.12904 -116.130949)
			(xy 224.133352 -116.188224) (xy 225.907203 -116.188224) (xy 225.911514 -116.130957) (xy 225.924357 -116.074981)
			(xy 225.945443 -116.021562) (xy 225.974294 -115.971906) (xy 226.010261 -115.927133) (xy 226.031044 -115.907312)
			(xy 226.038434 -115.89978) (xy 226.046967 -115.880508) (xy 226.047554 -115.869974) (xy 226.047554 -115.795298)
			(xy 226.047053 -115.784745) (xy 226.0385 -115.765449) (xy 226.031044 -115.75796) (xy 226.011965 -115.739828)
			(xy 225.978512 -115.699192) (xy 225.950958 -115.654346) (xy 225.929824 -115.606141) (xy 225.915511 -115.55549)
			(xy 225.90829 -115.503353) (xy 225.907854 -115.477036) (xy 225.90834 -115.449785) (xy 225.916096 -115.395837)
			(xy 225.931451 -115.343542) (xy 225.954093 -115.293965) (xy 225.983559 -115.248115) (xy 226.01925 -115.206924)
			(xy 226.060441 -115.171233) (xy 226.106291 -115.141767) (xy 226.155868 -115.119125) (xy 226.208163 -115.10377)
			(xy 226.262111 -115.096014) (xy 226.316613 -115.096014) (xy 226.370561 -115.10377) (xy 226.422856 -115.119125)
			(xy 226.472433 -115.141767) (xy 226.518283 -115.171233) (xy 226.559474 -115.206924) (xy 226.595165 -115.248115)
			(xy 226.624631 -115.293965) (xy 226.647273 -115.343542) (xy 226.662628 -115.395837) (xy 226.670384 -115.449785)
			(xy 226.67087 -115.477036) (xy 226.670436 -115.503351) (xy 226.663196 -115.555482) (xy 226.648871 -115.606125)
			(xy 226.627732 -115.654324) (xy 226.60018 -115.699167) (xy 226.566735 -115.739805) (xy 226.54768 -115.75796)
			(xy 226.540291 -115.765492) (xy 226.53176 -115.784764) (xy 226.53117 -115.795298) (xy 226.53117 -115.869974)
			(xy 226.531708 -115.880522) (xy 226.540238 -115.899817) (xy 226.54768 -115.907312) (xy 226.568506 -115.927095)
			(xy 226.604484 -115.971871) (xy 226.633345 -116.021534) (xy 226.654438 -116.074961) (xy 226.667286 -116.130946)
			(xy 226.668309 -116.144533) (xy 230.110137 -116.144533) (xy 230.114448 -116.087265) (xy 230.127291 -116.03129)
			(xy 230.148377 -115.977871) (xy 230.17723 -115.928215) (xy 230.213198 -115.883444) (xy 230.233982 -115.863624)
			(xy 230.241372 -115.856093) (xy 230.249904 -115.83682) (xy 230.250492 -115.826286) (xy 230.250492 -115.75161)
			(xy 230.249973 -115.741059) (xy 230.241431 -115.721764) (xy 230.233982 -115.714272) (xy 230.213242 -115.694404)
			(xy 230.177267 -115.649638) (xy 230.148405 -115.599988) (xy 230.12731 -115.546573) (xy 230.114457 -115.4906)
			(xy 230.110137 -115.433333) (xy 230.114448 -115.376065) (xy 230.127291 -115.32009) (xy 230.148377 -115.266671)
			(xy 230.17723 -115.217015) (xy 230.213198 -115.172244) (xy 230.233982 -115.152424) (xy 230.241372 -115.144893)
			(xy 230.249904 -115.12562) (xy 230.250492 -115.115086) (xy 230.250492 -115.04041) (xy 230.249973 -115.029859)
			(xy 230.241431 -115.010564) (xy 230.233982 -115.003072) (xy 230.214916 -114.984927) (xy 230.181461 -114.944294)
			(xy 230.153904 -114.899452) (xy 230.132767 -114.851249) (xy 230.118452 -114.8006) (xy 230.111229 -114.748465)
			(xy 230.110792 -114.722148) (xy 230.1113 -114.694896) (xy 230.11905 -114.640947) (xy 230.1344 -114.58865)
			(xy 230.157037 -114.53907) (xy 230.1865 -114.493217) (xy 230.222189 -114.452023) (xy 230.263378 -114.416329)
			(xy 230.309228 -114.38686) (xy 230.358805 -114.364217) (xy 230.4111 -114.348861) (xy 230.465048 -114.341103)
			(xy 230.4923 -114.34064) (xy 230.518615 -114.341095) (xy 230.570744 -114.34833) (xy 230.621388 -114.362651)
			(xy 230.669587 -114.383786) (xy 230.71443 -114.411335) (xy 230.755068 -114.444777) (xy 230.773224 -114.46383)
			(xy 230.780744 -114.471234) (xy 230.800025 -114.479759) (xy 230.810562 -114.48034) (xy 230.885238 -114.48034)
			(xy 230.895784 -114.479779) (xy 230.915079 -114.471265) (xy 230.922576 -114.46383) (xy 230.940756 -114.444799)
			(xy 230.98138 -114.411338) (xy 231.026215 -114.383775) (xy 231.074411 -114.362632) (xy 231.125054 -114.34831)
			(xy 231.177185 -114.341081) (xy 231.2035 -114.34064) (xy 231.230755 -114.341055) (xy 231.28471 -114.348814)
			(xy 231.337012 -114.364172) (xy 231.386595 -114.386818) (xy 231.426389 -114.412395) (xy 232.727135 -114.412395)
			(xy 232.727135 -114.360405) (xy 232.735269 -114.309056) (xy 232.751336 -114.259612) (xy 232.774941 -114.21329)
			(xy 232.805502 -114.171231) (xy 232.842266 -114.134472) (xy 232.884329 -114.103917) (xy 232.930654 -114.080318)
			(xy 232.980101 -114.064258) (xy 233.031451 -114.056132) (xy 233.057446 -114.055652) (xy 233.084091 -114.056131)
			(xy 233.136694 -114.064663) (xy 233.187244 -114.081529) (xy 233.234431 -114.106293) (xy 233.277029 -114.138312)
			(xy 233.313934 -114.176754) (xy 233.32948 -114.1984) (xy 233.337844 -114.209686) (xy 233.359517 -114.227541)
			(xy 233.385231 -114.238824) (xy 233.413046 -114.242682) (xy 233.440861 -114.238824) (xy 233.466575 -114.227541)
			(xy 233.488248 -114.209686) (xy 233.496612 -114.1984) (xy 233.512202 -114.176793) (xy 233.549115 -114.138375)
			(xy 233.59171 -114.106373) (xy 233.638886 -114.081616) (xy 233.689421 -114.064743) (xy 233.742007 -114.056191)
			(xy 233.768646 -114.055652) (xy 233.794628 -114.056245) (xy 233.84595 -114.064381) (xy 233.895369 -114.080444)
			(xy 233.941666 -114.104039) (xy 233.983703 -114.134586) (xy 234.020444 -114.171332) (xy 234.050985 -114.213373)
			(xy 234.074574 -114.259674) (xy 234.09063 -114.309095) (xy 234.098758 -114.360418) (xy 234.098758 -114.412382)
			(xy 234.09063 -114.463705) (xy 234.074574 -114.513126) (xy 234.050985 -114.559427) (xy 234.020444 -114.601468)
			(xy 233.983703 -114.638214) (xy 233.945097 -114.666268) (xy 236.640876 -114.666268) (xy 236.644947 -114.610646)
			(xy 236.657073 -114.556209) (xy 236.676996 -114.504118) (xy 236.704292 -114.455483) (xy 236.738378 -114.41134)
			(xy 236.778527 -114.372631) (xy 236.823885 -114.34018) (xy 236.873485 -114.314679) (xy 236.926269 -114.296672)
			(xy 236.981112 -114.286542) (xy 237.036846 -114.284505) (xy 237.092283 -114.290605) (xy 237.14624 -114.304711)
			(xy 237.197569 -114.326523) (xy 237.245175 -114.355577) (xy 237.288043 -114.391252) (xy 237.32526 -114.432789)
			(xy 237.356033 -114.479302) (xy 237.379705 -114.529799) (xy 237.395773 -114.583206) (xy 237.403893 -114.638382)
			(xy 237.404402 -114.666268) (xy 237.403893 -114.694154) (xy 237.395773 -114.74933) (xy 237.379705 -114.802737)
			(xy 237.356033 -114.853234) (xy 237.32526 -114.899747) (xy 237.288043 -114.941284) (xy 237.245175 -114.976959)
			(xy 237.197569 -115.006013) (xy 237.14624 -115.027825) (xy 237.092283 -115.041931) (xy 237.036846 -115.048031)
			(xy 236.981112 -115.045994) (xy 236.926269 -115.035864) (xy 236.873485 -115.017857) (xy 236.823885 -114.992356)
			(xy 236.778527 -114.959905) (xy 236.738378 -114.921196) (xy 236.704292 -114.877053) (xy 236.676996 -114.828418)
			(xy 236.657073 -114.776327) (xy 236.644947 -114.72189) (xy 236.640876 -114.666268) (xy 233.945097 -114.666268)
			(xy 233.941666 -114.668761) (xy 233.895369 -114.692356) (xy 233.84595 -114.708419) (xy 233.794628 -114.716555)
			(xy 233.768646 -114.717068) (xy 233.742001 -114.716586) (xy 233.689399 -114.708054) (xy 233.638849 -114.691187)
			(xy 233.591663 -114.666424) (xy 233.549064 -114.634406) (xy 233.512158 -114.595965) (xy 233.496612 -114.57432)
			(xy 233.488248 -114.563034) (xy 233.466575 -114.545179) (xy 233.440861 -114.533896) (xy 233.413046 -114.530038)
			(xy 233.385231 -114.533896) (xy 233.359517 -114.545179) (xy 233.337844 -114.563034) (xy 233.32948 -114.57432)
			(xy 233.3139 -114.595935) (xy 233.276985 -114.634351) (xy 233.234387 -114.666352) (xy 233.18721 -114.691108)
			(xy 233.136673 -114.707979) (xy 233.084085 -114.716529) (xy 233.057446 -114.717068) (xy 233.031451 -114.716668)
			(xy 232.980101 -114.708542) (xy 232.930654 -114.692482) (xy 232.884329 -114.668883) (xy 232.842266 -114.638328)
			(xy 232.805502 -114.601569) (xy 232.774941 -114.55951) (xy 232.751336 -114.513188) (xy 232.735269 -114.463744)
			(xy 232.727135 -114.412395) (xy 231.426389 -114.412395) (xy 231.432451 -114.416291) (xy 231.473645 -114.451989)
			(xy 231.509338 -114.493188) (xy 231.538805 -114.539047) (xy 231.561445 -114.588633) (xy 231.576797 -114.640937)
			(xy 231.584548 -114.694893) (xy 231.585008 -114.722148) (xy 231.58457 -114.748463) (xy 231.577329 -114.800593)
			(xy 231.563004 -114.851236) (xy 231.541866 -114.899435) (xy 231.514315 -114.944277) (xy 231.480872 -114.984916)
			(xy 231.461818 -115.003072) (xy 231.454429 -115.010604) (xy 231.445897 -115.029876) (xy 231.445308 -115.04041)
			(xy 231.445308 -115.115086) (xy 231.445829 -115.125637) (xy 231.45437 -115.144932) (xy 231.461818 -115.152424)
			(xy 231.482654 -115.172196) (xy 231.518629 -115.216975) (xy 231.547487 -115.26664) (xy 231.565585 -115.312489)
			(xy 232.727211 -115.312489) (xy 232.727211 -115.260511) (xy 232.735343 -115.209174) (xy 232.751406 -115.159741)
			(xy 232.775005 -115.113429) (xy 232.805559 -115.071381) (xy 232.842316 -115.034629) (xy 232.884369 -115.004081)
			(xy 232.930683 -114.980489) (xy 232.980119 -114.964432) (xy 233.031457 -114.956308) (xy 233.057446 -114.955828)
			(xy 233.084091 -114.956318) (xy 233.136692 -114.964848) (xy 233.187242 -114.981713) (xy 233.234428 -115.006475)
			(xy 233.277027 -115.038492) (xy 233.313933 -115.076932) (xy 233.32948 -115.098576) (xy 233.337844 -115.109862)
			(xy 233.359517 -115.127717) (xy 233.385231 -115.139) (xy 233.413046 -115.142858) (xy 233.440861 -115.139)
			(xy 233.466575 -115.127717) (xy 233.488248 -115.109862) (xy 233.496612 -115.098576) (xy 233.512195 -115.076964)
			(xy 233.54911 -115.038547) (xy 233.591707 -115.006547) (xy 233.638884 -114.98179) (xy 233.68942 -114.964918)
			(xy 233.742007 -114.956367) (xy 233.768646 -114.955828) (xy 233.794634 -114.956269) (xy 233.845968 -114.964406)
			(xy 233.895398 -114.980473) (xy 233.941706 -115.004074) (xy 233.983753 -115.034628) (xy 234.020502 -115.071383)
			(xy 234.05105 -115.113433) (xy 234.074645 -115.159745) (xy 234.090705 -115.209177) (xy 234.098835 -115.260512)
			(xy 234.098835 -115.312488) (xy 234.090704 -115.363823) (xy 234.074645 -115.413255) (xy 234.05105 -115.459567)
			(xy 234.020502 -115.501617) (xy 233.983753 -115.538372) (xy 233.941706 -115.568926) (xy 233.895398 -115.592527)
			(xy 233.845968 -115.608594) (xy 233.794634 -115.616731) (xy 233.768646 -115.617244) (xy 233.742 -115.616772)
			(xy 233.689397 -115.608239) (xy 233.638847 -115.591372) (xy 233.59166 -115.566606) (xy 233.549062 -115.534586)
			(xy 233.512158 -115.496142) (xy 233.496612 -115.474496) (xy 233.488248 -115.46321) (xy 233.466575 -115.445355)
			(xy 233.440861 -115.434072) (xy 233.413046 -115.430214) (xy 233.385231 -115.434072) (xy 233.359517 -115.445355)
			(xy 233.337844 -115.46321) (xy 233.32948 -115.474496) (xy 233.313923 -115.496128) (xy 233.277 -115.53454)
			(xy 233.234397 -115.566536) (xy 233.187215 -115.591288) (xy 233.136676 -115.608157) (xy 233.084086 -115.616705)
			(xy 233.057446 -115.617244) (xy 233.031457 -115.616692) (xy 232.980119 -115.608568) (xy 232.930683 -115.592511)
			(xy 232.884369 -115.568919) (xy 232.842316 -115.538371) (xy 232.805559 -115.501619) (xy 232.775005 -115.45957)
			(xy 232.751406 -115.413259) (xy 232.735343 -115.363826) (xy 232.727211 -115.312489) (xy 231.565585 -115.312489)
			(xy 231.568577 -115.320069) (xy 231.581422 -115.376054) (xy 231.585733 -115.433333) (xy 231.581413 -115.49061)
			(xy 231.568557 -115.546594) (xy 231.547458 -115.600018) (xy 231.518592 -115.649678) (xy 231.482609 -115.694452)
			(xy 231.461818 -115.714272) (xy 231.454429 -115.721804) (xy 231.445897 -115.741076) (xy 231.445308 -115.75161)
			(xy 231.445308 -115.826286) (xy 231.445829 -115.836837) (xy 231.45437 -115.856132) (xy 231.461818 -115.863624)
			(xy 231.482654 -115.883396) (xy 231.518629 -115.928175) (xy 231.547487 -115.97784) (xy 231.568577 -116.031269)
			(xy 231.581422 -116.087254) (xy 231.585733 -116.144533) (xy 231.581413 -116.20181) (xy 231.578959 -116.212495)
			(xy 232.727133 -116.212495) (xy 232.727133 -116.160505) (xy 232.735267 -116.109156) (xy 232.751334 -116.059711)
			(xy 232.774939 -116.013389) (xy 232.8055 -115.97133) (xy 232.842265 -115.93457) (xy 232.884328 -115.904015)
			(xy 232.930653 -115.880417) (xy 232.9801 -115.864356) (xy 233.031451 -115.85623) (xy 233.057446 -115.85575)
			(xy 233.084091 -115.85623) (xy 233.136694 -115.864762) (xy 233.187244 -115.881628) (xy 233.23443 -115.906392)
			(xy 233.277029 -115.93841) (xy 233.313934 -115.976852) (xy 233.32948 -115.998498) (xy 233.337844 -116.009784)
			(xy 233.359517 -116.027639) (xy 233.385231 -116.038922) (xy 233.413046 -116.04278) (xy 233.440861 -116.038922)
			(xy 233.466575 -116.027639) (xy 233.488248 -116.009784) (xy 233.496612 -115.998498) (xy 233.512202 -115.976891)
			(xy 233.549115 -115.938473) (xy 233.59171 -115.906471) (xy 233.638886 -115.881714) (xy 233.689421 -115.864841)
			(xy 233.742007 -115.856289) (xy 233.768646 -115.85575) (xy 233.794627 -115.856347) (xy 233.84595 -115.864483)
			(xy 233.895368 -115.880546) (xy 233.941665 -115.904141) (xy 233.983702 -115.934687) (xy 233.985283 -115.936268)
			(xy 235.270546 -115.936268) (xy 235.274617 -115.880646) (xy 235.286743 -115.826209) (xy 235.306666 -115.774118)
			(xy 235.333962 -115.725483) (xy 235.368048 -115.68134) (xy 235.408197 -115.642631) (xy 235.453555 -115.61018)
			(xy 235.503155 -115.584679) (xy 235.555939 -115.566672) (xy 235.610782 -115.556542) (xy 235.666516 -115.554505)
			(xy 235.721953 -115.560605) (xy 235.77591 -115.574711) (xy 235.827239 -115.596523) (xy 235.874845 -115.625577)
			(xy 235.917713 -115.661252) (xy 235.95493 -115.702789) (xy 235.985703 -115.749302) (xy 236.009375 -115.799799)
			(xy 236.025443 -115.853206) (xy 236.033563 -115.908382) (xy 236.034072 -115.936268) (xy 236.033563 -115.964154)
			(xy 236.025443 -116.01933) (xy 236.009375 -116.072737) (xy 235.985703 -116.123234) (xy 235.95493 -116.169747)
			(xy 235.917713 -116.211284) (xy 235.874845 -116.246959) (xy 235.827239 -116.276013) (xy 235.77591 -116.297825)
			(xy 235.721953 -116.311931) (xy 235.666516 -116.318031) (xy 235.610782 -116.315994) (xy 235.555939 -116.305864)
			(xy 235.503155 -116.287857) (xy 235.453555 -116.262356) (xy 235.408197 -116.229905) (xy 235.368048 -116.191196)
			(xy 235.333962 -116.147053) (xy 235.306666 -116.098418) (xy 235.286743 -116.046327) (xy 235.274617 -115.99189)
			(xy 235.270546 -115.936268) (xy 233.985283 -115.936268) (xy 234.020442 -115.971434) (xy 234.050983 -116.013474)
			(xy 234.074572 -116.059775) (xy 234.090628 -116.109195) (xy 234.098756 -116.160518) (xy 234.098756 -116.212482)
			(xy 234.090628 -116.263805) (xy 234.074572 -116.313225) (xy 234.050983 -116.359526) (xy 234.020442 -116.401566)
			(xy 233.983702 -116.438313) (xy 233.970963 -116.44757) (xy 236.707678 -116.44757) (xy 236.711749 -116.391948)
			(xy 236.723875 -116.337511) (xy 236.743798 -116.28542) (xy 236.771094 -116.236785) (xy 236.80518 -116.192642)
			(xy 236.845329 -116.153933) (xy 236.890687 -116.121482) (xy 236.940287 -116.095981) (xy 236.993071 -116.077974)
			(xy 237.047914 -116.067844) (xy 237.103648 -116.065807) (xy 237.159085 -116.071907) (xy 237.213042 -116.086013)
			(xy 237.264371 -116.107825) (xy 237.311977 -116.136879) (xy 237.354845 -116.172554) (xy 237.392062 -116.214091)
			(xy 237.422835 -116.260604) (xy 237.446507 -116.311101) (xy 237.462575 -116.364508) (xy 237.470695 -116.419684)
			(xy 237.471204 -116.44757) (xy 237.470695 -116.475456) (xy 237.462575 -116.530632) (xy 237.446507 -116.584039)
			(xy 237.422835 -116.634536) (xy 237.392062 -116.681049) (xy 237.354845 -116.722586) (xy 237.311977 -116.758261)
			(xy 237.264371 -116.787315) (xy 237.213042 -116.809127) (xy 237.159085 -116.823233) (xy 237.103648 -116.829333)
			(xy 237.047914 -116.827296) (xy 236.993071 -116.817166) (xy 236.940287 -116.799159) (xy 236.890687 -116.773658)
			(xy 236.845329 -116.741207) (xy 236.80518 -116.702498) (xy 236.771094 -116.658355) (xy 236.743798 -116.60972)
			(xy 236.723875 -116.557629) (xy 236.711749 -116.503192) (xy 236.707678 -116.44757) (xy 233.970963 -116.44757)
			(xy 233.941665 -116.468859) (xy 233.895368 -116.492454) (xy 233.84595 -116.508517) (xy 233.794627 -116.516653)
			(xy 233.768646 -116.517166) (xy 233.742001 -116.516685) (xy 233.689399 -116.508153) (xy 233.638849 -116.491286)
			(xy 233.591663 -116.466523) (xy 233.549064 -116.434505) (xy 233.512158 -116.396063) (xy 233.496612 -116.374418)
			(xy 233.488248 -116.363132) (xy 233.466575 -116.345277) (xy 233.440861 -116.333994) (xy 233.413046 -116.330136)
			(xy 233.385231 -116.333994) (xy 233.359517 -116.345277) (xy 233.337844 -116.363132) (xy 233.32948 -116.374418)
			(xy 233.3139 -116.396033) (xy 233.276984 -116.434449) (xy 233.234387 -116.46645) (xy 233.187209 -116.491206)
			(xy 233.136673 -116.508077) (xy 233.084085 -116.516627) (xy 233.057446 -116.517166) (xy 233.031451 -116.51677)
			(xy 232.9801 -116.508644) (xy 232.930654 -116.492583) (xy 232.884328 -116.468985) (xy 232.842265 -116.43843)
			(xy 232.8055 -116.40167) (xy 232.774939 -116.359611) (xy 232.751334 -116.313289) (xy 232.735267 -116.263844)
			(xy 232.727133 -116.212495) (xy 231.578959 -116.212495) (xy 231.568557 -116.257794) (xy 231.547458 -116.311218)
			(xy 231.518592 -116.360878) (xy 231.482609 -116.405652) (xy 231.461818 -116.425472) (xy 231.454429 -116.433004)
			(xy 231.445897 -116.452276) (xy 231.445308 -116.46281) (xy 231.445308 -116.537486) (xy 231.445829 -116.548037)
			(xy 231.45437 -116.567332) (xy 231.461818 -116.574824) (xy 231.480882 -116.592971) (xy 231.514337 -116.633603)
			(xy 231.541895 -116.678445) (xy 231.563032 -116.726648) (xy 231.577347 -116.777296) (xy 231.58457 -116.829431)
			(xy 231.585008 -116.855748) (xy 231.584567 -116.883) (xy 231.576804 -116.93695) (xy 231.561443 -116.989245)
			(xy 231.538796 -117.038823) (xy 231.509325 -117.084673) (xy 231.485302 -117.112393) (xy 232.727155 -117.112393)
			(xy 232.727155 -117.060407) (xy 232.735289 -117.009061) (xy 232.751355 -116.959619) (xy 232.774958 -116.9133)
			(xy 232.805517 -116.871244) (xy 232.842279 -116.834487) (xy 232.88434 -116.803934) (xy 232.930662 -116.780337)
			(xy 232.980106 -116.764278) (xy 233.031453 -116.756152) (xy 233.057446 -116.755672) (xy 233.084092 -116.756143)
			(xy 233.136695 -116.764675) (xy 233.187246 -116.781542) (xy 233.234433 -116.806308) (xy 233.277031 -116.838328)
			(xy 233.313935 -116.876773) (xy 233.32948 -116.89842) (xy 233.337844 -116.909706) (xy 233.359517 -116.927561)
			(xy 233.385231 -116.938844) (xy 233.413046 -116.942702) (xy 233.440861 -116.938844) (xy 233.466575 -116.927561)
			(xy 233.488248 -116.909706) (xy 233.496612 -116.89842) (xy 233.512179 -116.876796) (xy 233.549099 -116.838383)
			(xy 233.5917 -116.806385) (xy 233.63888 -116.781631) (xy 233.689418 -116.764761) (xy 233.742006 -116.756211)
			(xy 233.768646 -116.755672) (xy 233.794629 -116.756225) (xy 233.845955 -116.764361) (xy 233.895376 -116.780425)
			(xy 233.941677 -116.804022) (xy 233.983716 -116.83457) (xy 234.02046 -116.871319) (xy 234.051002 -116.913362)
			(xy 234.074593 -116.959666) (xy 234.09065 -117.00909) (xy 234.098779 -117.060417) (xy 234.098779 -117.112383)
			(xy 234.09065 -117.16371) (xy 234.074593 -117.213134) (xy 234.051002 -117.259438) (xy 234.02046 -117.301481)
			(xy 233.983716 -117.33823) (xy 233.941677 -117.368778) (xy 233.895376 -117.392375) (xy 233.845955 -117.408439)
			(xy 233.794629 -117.416575) (xy 233.768646 -117.417088) (xy 233.742001 -117.416597) (xy 233.6894 -117.408066)
			(xy 233.638851 -117.391201) (xy 233.591665 -117.366439) (xy 233.549066 -117.334423) (xy 233.512159 -117.295984)
			(xy 233.496612 -117.27434) (xy 233.488248 -117.263054) (xy 233.466575 -117.245199) (xy 233.440861 -117.233916)
			(xy 233.413046 -117.230058) (xy 233.385231 -117.233916) (xy 233.359517 -117.245199) (xy 233.337844 -117.263054)
			(xy 233.32948 -117.27434) (xy 233.313906 -117.295959) (xy 233.276989 -117.334375) (xy 233.23439 -117.366374)
			(xy 233.187211 -117.391129) (xy 233.136674 -117.408) (xy 233.084085 -117.416549) (xy 233.057446 -117.417088)
			(xy 233.031453 -117.416648) (xy 232.980106 -117.408522) (xy 232.930662 -117.392463) (xy 232.88434 -117.368866)
			(xy 232.842279 -117.338313) (xy 232.805517 -117.301556) (xy 232.774958 -117.2595) (xy 232.751355 -117.213181)
			(xy 232.735289 -117.163739) (xy 232.727155 -117.112393) (xy 231.485302 -117.112393) (xy 231.473629 -117.125863)
			(xy 231.432434 -117.161553) (xy 231.386581 -117.191019) (xy 231.337 -117.213659) (xy 231.284703 -117.229014)
			(xy 231.230752 -117.23677) (xy 231.2035 -117.237256) (xy 231.177185 -117.236803) (xy 231.125056 -117.229567)
			(xy 231.074412 -117.215246) (xy 231.026213 -117.194111) (xy 230.98137 -117.166562) (xy 230.940732 -117.133119)
			(xy 230.922576 -117.114066) (xy 230.915056 -117.106662) (xy 230.895775 -117.098136) (xy 230.885238 -117.097556)
			(xy 230.810562 -117.097556) (xy 230.800017 -117.098118) (xy 230.780722 -117.106632) (xy 230.773224 -117.114066)
			(xy 230.755063 -117.133116) (xy 230.714433 -117.166571) (xy 230.669593 -117.194129) (xy 230.621394 -117.215268)
			(xy 230.570748 -117.229587) (xy 230.518616 -117.236815) (xy 230.4923 -117.237256) (xy 230.465051 -117.236722)
			(xy 230.411107 -117.228967) (xy 230.358816 -117.213614) (xy 230.309242 -117.190977) (xy 230.263394 -117.161515)
			(xy 230.222205 -117.125829) (xy 230.186514 -117.084644) (xy 230.157046 -117.0388) (xy 230.134402 -116.989229)
			(xy 230.119043 -116.93694) (xy 230.111281 -116.882997) (xy 230.110792 -116.855748) (xy 230.111227 -116.829433)
			(xy 230.118469 -116.777303) (xy 230.132795 -116.72666) (xy 230.153933 -116.678461) (xy 230.181485 -116.633618)
			(xy 230.214928 -116.59298) (xy 230.233982 -116.574824) (xy 230.241372 -116.567293) (xy 230.249904 -116.54802)
			(xy 230.250492 -116.537486) (xy 230.250492 -116.46281) (xy 230.249973 -116.452259) (xy 230.241431 -116.432964)
			(xy 230.233982 -116.425472) (xy 230.213242 -116.405604) (xy 230.177267 -116.360838) (xy 230.148405 -116.311188)
			(xy 230.12731 -116.257773) (xy 230.114457 -116.2018) (xy 230.110137 -116.144533) (xy 226.668309 -116.144533)
			(xy 226.671599 -116.188224) (xy 226.667279 -116.245502) (xy 226.654424 -116.301485) (xy 226.633324 -116.35491)
			(xy 226.604456 -116.404569) (xy 226.568472 -116.449341) (xy 226.54768 -116.46916) (xy 226.540291 -116.476692)
			(xy 226.53176 -116.495964) (xy 226.53117 -116.506498) (xy 226.53117 -116.581174) (xy 226.531708 -116.591722)
			(xy 226.540238 -116.611017) (xy 226.54768 -116.618512) (xy 226.566731 -116.636673) (xy 226.600189 -116.677301)
			(xy 226.627749 -116.72214) (xy 226.648889 -116.77034) (xy 226.663207 -116.820987) (xy 226.670432 -116.87312)
			(xy 226.67087 -116.899436) (xy 226.670384 -116.926687) (xy 226.662628 -116.980635) (xy 226.647273 -117.03293)
			(xy 226.624631 -117.082507) (xy 226.595165 -117.128357) (xy 226.559474 -117.169548) (xy 226.518283 -117.205239)
			(xy 226.472433 -117.234705) (xy 226.422856 -117.257347) (xy 226.370561 -117.272702) (xy 226.316613 -117.280458)
			(xy 226.262111 -117.280458) (xy 226.208163 -117.272702) (xy 226.155868 -117.257347) (xy 226.106291 -117.234705)
			(xy 226.060441 -117.205239) (xy 226.01925 -117.169548) (xy 225.983559 -117.128357) (xy 225.954093 -117.082507)
			(xy 225.931451 -117.03293) (xy 225.916096 -116.980635) (xy 225.90834 -116.926687) (xy 225.907854 -116.899436)
			(xy 225.908262 -116.87312) (xy 225.915506 -116.820988) (xy 225.929836 -116.770343) (xy 225.950979 -116.722144)
			(xy 225.978537 -116.677302) (xy 226.011987 -116.636666) (xy 226.031044 -116.618512) (xy 226.038434 -116.61098)
			(xy 226.046967 -116.591708) (xy 226.047554 -116.581174) (xy 226.047554 -116.506498) (xy 226.047053 -116.495945)
			(xy 226.0385 -116.476649) (xy 226.031044 -116.46916) (xy 226.010294 -116.449303) (xy 225.974322 -116.404534)
			(xy 225.945464 -116.354882) (xy 225.924372 -116.301465) (xy 225.911521 -116.245492) (xy 225.907203 -116.188224)
			(xy 224.133352 -116.188224) (xy 224.129033 -116.2455) (xy 224.11618 -116.301481) (xy 224.095085 -116.354905)
			(xy 224.066223 -116.404564) (xy 224.030247 -116.449339) (xy 224.009458 -116.46916) (xy 224.002081 -116.476702)
			(xy 223.99354 -116.495966) (xy 223.992948 -116.506498) (xy 223.992948 -116.581174) (xy 223.993464 -116.591726)
			(xy 224.002007 -116.611022) (xy 224.009458 -116.618512) (xy 224.028523 -116.636657) (xy 224.061977 -116.677291)
			(xy 224.089534 -116.722133) (xy 224.11067 -116.770336) (xy 224.124986 -116.820985) (xy 224.13221 -116.873119)
			(xy 224.132648 -116.899436) (xy 224.132162 -116.926687) (xy 224.124406 -116.980635) (xy 224.109051 -117.03293)
			(xy 224.086409 -117.082507) (xy 224.056943 -117.128357) (xy 224.021252 -117.169548) (xy 223.980061 -117.205239)
			(xy 223.934211 -117.234705) (xy 223.884634 -117.257347) (xy 223.832339 -117.272702) (xy 223.778391 -117.280458)
			(xy 223.723889 -117.280458) (xy 223.669941 -117.272702) (xy 223.617646 -117.257347) (xy 223.568069 -117.234705)
			(xy 223.522219 -117.205239) (xy 223.481028 -117.169548) (xy 223.445337 -117.128357) (xy 223.415871 -117.082507)
			(xy 223.393229 -117.03293) (xy 223.377874 -116.980635) (xy 223.370118 -116.926687) (xy 223.369632 -116.899436)
			(xy 223.370047 -116.87312) (xy 223.377291 -116.820989) (xy 223.39162 -116.770345) (xy 223.412762 -116.722146)
			(xy 223.440318 -116.677304) (xy 223.473766 -116.636667) (xy 223.492822 -116.618512) (xy 223.500224 -116.610991)
			(xy 223.508747 -116.59171) (xy 223.509332 -116.581174) (xy 223.509332 -116.506498) (xy 223.508808 -116.495948)
			(xy 223.500268 -116.476653) (xy 223.492822 -116.46916) (xy 223.472068 -116.449305) (xy 223.436089 -116.404539)
			(xy 223.407225 -116.354887) (xy 223.386128 -116.30147) (xy 223.373275 -116.245494) (xy 223.368955 -116.188224)
			(xy 215.7857 -116.188224) (xy 215.7857 -117.294914) (xy 216.75852 -117.294914) (xy 216.75899 -117.2686)
			(xy 216.766224 -117.216471) (xy 216.780542 -117.165828) (xy 216.801674 -117.117629) (xy 216.82922 -117.072786)
			(xy 216.862658 -117.032146) (xy 216.88171 -117.01399) (xy 216.88912 -117.006475) (xy 216.897639 -116.98719)
			(xy 216.89822 -116.976652) (xy 216.89822 -116.901976) (xy 216.897658 -116.89143) (xy 216.889145 -116.872135)
			(xy 216.88171 -116.864638) (xy 216.862633 -116.846504) (xy 216.829178 -116.80587) (xy 216.801621 -116.761025)
			(xy 216.780486 -116.71282) (xy 216.766174 -116.662169) (xy 216.758955 -116.610031) (xy 216.75852 -116.583714)
			(xy 216.759006 -116.556463) (xy 216.766762 -116.502515) (xy 216.782117 -116.45022) (xy 216.804759 -116.400643)
			(xy 216.834225 -116.354793) (xy 216.869916 -116.313602) (xy 216.911107 -116.277911) (xy 216.956957 -116.248445)
			(xy 217.006534 -116.225803) (xy 217.058829 -116.210448) (xy 217.112777 -116.202692) (xy 217.167279 -116.202692)
			(xy 217.221227 -116.210448) (xy 217.273522 -116.225803) (xy 217.323099 -116.248445) (xy 217.368949 -116.277911)
			(xy 217.41014 -116.313602) (xy 217.445831 -116.354793) (xy 217.475297 -116.400643) (xy 217.497939 -116.45022)
			(xy 217.513294 -116.502515) (xy 217.52105 -116.556463) (xy 217.521536 -116.583714) (xy 217.521066 -116.610028)
			(xy 217.51383 -116.662156) (xy 217.499511 -116.712798) (xy 217.478379 -116.760997) (xy 217.450834 -116.80584)
			(xy 217.417397 -116.846481) (xy 217.398346 -116.864638) (xy 217.390933 -116.87215) (xy 217.382413 -116.891437)
			(xy 217.381836 -116.901976) (xy 217.381836 -116.976652) (xy 217.382367 -116.987202) (xy 217.3909 -117.006498)
			(xy 217.398346 -117.01399) (xy 217.417398 -117.032148) (xy 217.450854 -117.072779) (xy 217.478412 -117.117619)
			(xy 217.499551 -117.165819) (xy 217.513869 -117.216465) (xy 217.521096 -117.268598) (xy 217.521536 -117.294914)
			(xy 218.79052 -117.294914) (xy 218.79099 -117.2686) (xy 218.798224 -117.216471) (xy 218.812542 -117.165828)
			(xy 218.833674 -117.117629) (xy 218.86122 -117.072786) (xy 218.894658 -117.032146) (xy 218.91371 -117.01399)
			(xy 218.92112 -117.006475) (xy 218.929639 -116.98719) (xy 218.93022 -116.976652) (xy 218.93022 -116.901976)
			(xy 218.929658 -116.89143) (xy 218.921145 -116.872135) (xy 218.91371 -116.864638) (xy 218.894633 -116.846504)
			(xy 218.861178 -116.80587) (xy 218.833621 -116.761025) (xy 218.812486 -116.71282) (xy 218.798174 -116.662169)
			(xy 218.790955 -116.610031) (xy 218.79052 -116.583714) (xy 218.791006 -116.556463) (xy 218.798762 -116.502515)
			(xy 218.814117 -116.45022) (xy 218.836759 -116.400643) (xy 218.866225 -116.354793) (xy 218.901916 -116.313602)
			(xy 218.943107 -116.277911) (xy 218.988957 -116.248445) (xy 219.038534 -116.225803) (xy 219.090829 -116.210448)
			(xy 219.144777 -116.202692) (xy 219.199279 -116.202692) (xy 219.253227 -116.210448) (xy 219.305522 -116.225803)
			(xy 219.355099 -116.248445) (xy 219.400949 -116.277911) (xy 219.44214 -116.313602) (xy 219.477831 -116.354793)
			(xy 219.507297 -116.400643) (xy 219.529939 -116.45022) (xy 219.545294 -116.502515) (xy 219.55305 -116.556463)
			(xy 219.553536 -116.583714) (xy 219.553066 -116.610028) (xy 219.54583 -116.662156) (xy 219.531511 -116.712798)
			(xy 219.510379 -116.760997) (xy 219.482834 -116.80584) (xy 219.449397 -116.846481) (xy 219.430346 -116.864638)
			(xy 219.422933 -116.87215) (xy 219.414413 -116.891437) (xy 219.413836 -116.901976) (xy 219.413836 -116.976652)
			(xy 219.414367 -116.987202) (xy 219.4229 -117.006498) (xy 219.430346 -117.01399) (xy 219.449398 -117.032148)
			(xy 219.482854 -117.072779) (xy 219.510412 -117.117619) (xy 219.531551 -117.165819) (xy 219.545869 -117.216465)
			(xy 219.553096 -117.268598) (xy 219.553536 -117.294914) (xy 220.82252 -117.294914) (xy 220.82299 -117.2686)
			(xy 220.830224 -117.216471) (xy 220.844542 -117.165828) (xy 220.865674 -117.117629) (xy 220.89322 -117.072786)
			(xy 220.926658 -117.032146) (xy 220.94571 -117.01399) (xy 220.95312 -117.006475) (xy 220.961639 -116.98719)
			(xy 220.96222 -116.976652) (xy 220.96222 -116.901976) (xy 220.961658 -116.89143) (xy 220.953145 -116.872135)
			(xy 220.94571 -116.864638) (xy 220.926633 -116.846504) (xy 220.893178 -116.80587) (xy 220.865621 -116.761025)
			(xy 220.844486 -116.71282) (xy 220.830174 -116.662169) (xy 220.822955 -116.610031) (xy 220.82252 -116.583714)
			(xy 220.823006 -116.556463) (xy 220.830762 -116.502515) (xy 220.846117 -116.45022) (xy 220.868759 -116.400643)
			(xy 220.898225 -116.354793) (xy 220.933916 -116.313602) (xy 220.975107 -116.277911) (xy 221.020957 -116.248445)
			(xy 221.070534 -116.225803) (xy 221.122829 -116.210448) (xy 221.176777 -116.202692) (xy 221.231279 -116.202692)
			(xy 221.285227 -116.210448) (xy 221.337522 -116.225803) (xy 221.387099 -116.248445) (xy 221.432949 -116.277911)
			(xy 221.47414 -116.313602) (xy 221.509831 -116.354793) (xy 221.539297 -116.400643) (xy 221.561939 -116.45022)
			(xy 221.577294 -116.502515) (xy 221.58505 -116.556463) (xy 221.585536 -116.583714) (xy 221.585066 -116.610028)
			(xy 221.57783 -116.662156) (xy 221.563511 -116.712798) (xy 221.542379 -116.760997) (xy 221.514834 -116.80584)
			(xy 221.481397 -116.846481) (xy 221.462346 -116.864638) (xy 221.454933 -116.87215) (xy 221.446413 -116.891437)
			(xy 221.445836 -116.901976) (xy 221.445836 -116.976652) (xy 221.446367 -116.987202) (xy 221.4549 -117.006498)
			(xy 221.462346 -117.01399) (xy 221.481398 -117.032148) (xy 221.514854 -117.072779) (xy 221.542412 -117.117619)
			(xy 221.563551 -117.165819) (xy 221.577869 -117.216465) (xy 221.585096 -117.268598) (xy 221.585536 -117.294914)
			(xy 221.58505 -117.322165) (xy 221.577294 -117.376113) (xy 221.561939 -117.428408) (xy 221.539297 -117.477985)
			(xy 221.509831 -117.523835) (xy 221.47414 -117.565026) (xy 221.432949 -117.600717) (xy 221.387099 -117.630183)
			(xy 221.337522 -117.652825) (xy 221.285227 -117.66818) (xy 221.231279 -117.675936) (xy 221.176777 -117.675936)
			(xy 221.122829 -117.66818) (xy 221.070534 -117.652825) (xy 221.020957 -117.630183) (xy 220.975107 -117.600717)
			(xy 220.933916 -117.565026) (xy 220.898225 -117.523835) (xy 220.868759 -117.477985) (xy 220.846117 -117.428408)
			(xy 220.830762 -117.376113) (xy 220.823006 -117.322165) (xy 220.82252 -117.294914) (xy 219.553536 -117.294914)
			(xy 219.55305 -117.322165) (xy 219.545294 -117.376113) (xy 219.529939 -117.428408) (xy 219.507297 -117.477985)
			(xy 219.477831 -117.523835) (xy 219.44214 -117.565026) (xy 219.400949 -117.600717) (xy 219.355099 -117.630183)
			(xy 219.305522 -117.652825) (xy 219.253227 -117.66818) (xy 219.199279 -117.675936) (xy 219.144777 -117.675936)
			(xy 219.090829 -117.66818) (xy 219.038534 -117.652825) (xy 218.988957 -117.630183) (xy 218.943107 -117.600717)
			(xy 218.901916 -117.565026) (xy 218.866225 -117.523835) (xy 218.836759 -117.477985) (xy 218.814117 -117.428408)
			(xy 218.798762 -117.376113) (xy 218.791006 -117.322165) (xy 218.79052 -117.294914) (xy 217.521536 -117.294914)
			(xy 217.52105 -117.322165) (xy 217.513294 -117.376113) (xy 217.497939 -117.428408) (xy 217.475297 -117.477985)
			(xy 217.445831 -117.523835) (xy 217.41014 -117.565026) (xy 217.368949 -117.600717) (xy 217.323099 -117.630183)
			(xy 217.273522 -117.652825) (xy 217.221227 -117.66818) (xy 217.167279 -117.675936) (xy 217.112777 -117.675936)
			(xy 217.058829 -117.66818) (xy 217.006534 -117.652825) (xy 216.956957 -117.630183) (xy 216.911107 -117.600717)
			(xy 216.869916 -117.565026) (xy 216.834225 -117.523835) (xy 216.804759 -117.477985) (xy 216.782117 -117.428408)
			(xy 216.766762 -117.376113) (xy 216.759006 -117.322165) (xy 216.75852 -117.294914) (xy 215.7857 -117.294914)
			(xy 215.7857 -117.719348) (xy 236.702598 -117.719348) (xy 236.706669 -117.663726) (xy 236.718795 -117.609289)
			(xy 236.738718 -117.557198) (xy 236.766014 -117.508563) (xy 236.8001 -117.46442) (xy 236.840249 -117.425711)
			(xy 236.885607 -117.39326) (xy 236.935207 -117.367759) (xy 236.987991 -117.349752) (xy 237.042834 -117.339622)
			(xy 237.098568 -117.337585) (xy 237.154005 -117.343685) (xy 237.207962 -117.357791) (xy 237.259291 -117.379603)
			(xy 237.306897 -117.408657) (xy 237.349765 -117.444332) (xy 237.386982 -117.485869) (xy 237.417755 -117.532382)
			(xy 237.441427 -117.582879) (xy 237.457495 -117.636286) (xy 237.465615 -117.691462) (xy 237.466124 -117.719348)
			(xy 237.465615 -117.747234) (xy 237.457495 -117.80241) (xy 237.441427 -117.855817) (xy 237.417755 -117.906314)
			(xy 237.386982 -117.952827) (xy 237.349765 -117.994364) (xy 237.306897 -118.030039) (xy 237.259291 -118.059093)
			(xy 237.207962 -118.080905) (xy 237.154005 -118.095011) (xy 237.098568 -118.101111) (xy 237.042834 -118.099074)
			(xy 236.987991 -118.088944) (xy 236.935207 -118.070937) (xy 236.885607 -118.045436) (xy 236.840249 -118.012985)
			(xy 236.8001 -117.974276) (xy 236.766014 -117.930133) (xy 236.738718 -117.881498) (xy 236.718795 -117.829407)
			(xy 236.706669 -117.77497) (xy 236.702598 -117.719348) (xy 215.7857 -117.719348) (xy 215.7857 -117.768624)
			(xy 215.786023 -117.777103) (xy 215.791612 -117.793118) (xy 215.802107 -117.806442) (xy 215.809068 -117.811296)
			(xy 215.892126 -117.864636) (xy 215.918034 -117.866414) (xy 215.929718 -117.860826) (xy 215.954954 -117.849685)
			(xy 216.007825 -117.833956) (xy 216.062411 -117.826008) (xy 216.089992 -117.82552) (xy 216.117247 -117.825926)
			(xy 216.171203 -117.833683) (xy 216.223506 -117.849039) (xy 216.273091 -117.871683) (xy 216.318948 -117.901153)
			(xy 216.360145 -117.936849) (xy 216.395842 -117.978045) (xy 216.425313 -118.023902) (xy 216.447958 -118.073487)
			(xy 216.463315 -118.125789) (xy 216.470979 -118.179088) (xy 230.817926 -118.179088) (xy 230.821997 -118.123466)
			(xy 230.834123 -118.069029) (xy 230.854046 -118.016938) (xy 230.881342 -117.968303) (xy 230.915428 -117.92416)
			(xy 230.955577 -117.885451) (xy 231.000935 -117.853) (xy 231.050535 -117.827499) (xy 231.103319 -117.809492)
			(xy 231.158162 -117.799362) (xy 231.213896 -117.797325) (xy 231.269333 -117.803425) (xy 231.32329 -117.817531)
			(xy 231.374619 -117.839343) (xy 231.422225 -117.868397) (xy 231.465093 -117.904072) (xy 231.50231 -117.945609)
			(xy 231.533083 -117.992122) (xy 231.556755 -118.042619) (xy 231.572823 -118.096026) (xy 231.580943 -118.151202)
			(xy 231.581452 -118.179088) (xy 231.580943 -118.206974) (xy 231.572823 -118.26215) (xy 231.556755 -118.315557)
			(xy 231.533083 -118.366054) (xy 231.50231 -118.412567) (xy 231.465093 -118.454104) (xy 231.422225 -118.489779)
			(xy 231.374619 -118.518833) (xy 231.32329 -118.540645) (xy 231.269333 -118.554751) (xy 231.213896 -118.560851)
			(xy 231.158162 -118.558814) (xy 231.103319 -118.548684) (xy 231.050535 -118.530677) (xy 231.000935 -118.505176)
			(xy 230.955577 -118.472725) (xy 230.915428 -118.434016) (xy 230.881342 -118.389873) (xy 230.854046 -118.341238)
			(xy 230.834123 -118.289147) (xy 230.821997 -118.23471) (xy 230.817926 -118.179088) (xy 216.470979 -118.179088)
			(xy 216.471073 -118.179745) (xy 216.471073 -118.234255) (xy 216.463315 -118.288211) (xy 216.447958 -118.340513)
			(xy 216.425313 -118.390098) (xy 216.395842 -118.435955) (xy 216.360145 -118.477151) (xy 216.318948 -118.512847)
			(xy 216.273091 -118.542317) (xy 216.223506 -118.564961) (xy 216.171203 -118.580317) (xy 216.117247 -118.588074)
			(xy 216.089992 -118.588536) (xy 216.062412 -118.588035) (xy 216.007826 -118.580092) (xy 215.954952 -118.564373)
			(xy 215.929718 -118.55323) (xy 215.918034 -118.547642) (xy 215.892126 -118.54942) (xy 215.809068 -118.60276)
			(xy 215.802106 -118.607619) (xy 215.791583 -118.620925) (xy 215.786017 -118.63695) (xy 215.7857 -118.645432)
			(xy 215.7857 -118.782592) (xy 215.785999 -118.791053) (xy 215.791472 -118.807064) (xy 215.801884 -118.820401)
			(xy 215.808814 -118.825264) (xy 215.891364 -118.878604) (xy 215.917272 -118.880636) (xy 215.928956 -118.875302)
			(xy 215.953728 -118.864616) (xy 216.00554 -118.849577) (xy 216.058953 -118.841984) (xy 216.085928 -118.84152)
			(xy 216.11318 -118.841952) (xy 216.167129 -118.849712) (xy 216.219424 -118.865071) (xy 216.269001 -118.887715)
			(xy 216.314851 -118.917184) (xy 216.356041 -118.952879) (xy 216.391732 -118.994071) (xy 216.421198 -119.039923)
			(xy 216.443839 -119.089502) (xy 216.459194 -119.141799) (xy 216.462035 -119.16156) (xy 232.432604 -119.16156)
			(xy 232.436675 -119.105938) (xy 232.448801 -119.051501) (xy 232.468724 -118.99941) (xy 232.49602 -118.950775)
			(xy 232.530106 -118.906632) (xy 232.570255 -118.867923) (xy 232.615613 -118.835472) (xy 232.665213 -118.809971)
			(xy 232.717997 -118.791964) (xy 232.77284 -118.781834) (xy 232.828574 -118.779797) (xy 232.884011 -118.785897)
			(xy 232.937968 -118.800003) (xy 232.989297 -118.821815) (xy 233.036903 -118.850869) (xy 233.079771 -118.886544)
			(xy 233.116988 -118.928081) (xy 233.147761 -118.974594) (xy 233.171433 -119.025091) (xy 233.187501 -119.078498)
			(xy 233.195621 -119.133674) (xy 233.19613 -119.16156) (xy 233.195621 -119.189446) (xy 233.192697 -119.209312)
			(xy 233.799124 -119.209312) (xy 233.803195 -119.15369) (xy 233.815321 -119.099253) (xy 233.835244 -119.047162)
			(xy 233.86254 -118.998527) (xy 233.896626 -118.954384) (xy 233.936775 -118.915675) (xy 233.982133 -118.883224)
			(xy 234.031733 -118.857723) (xy 234.084517 -118.839716) (xy 234.13936 -118.829586) (xy 234.195094 -118.827549)
			(xy 234.250531 -118.833649) (xy 234.304488 -118.847755) (xy 234.355817 -118.869567) (xy 234.403423 -118.898621)
			(xy 234.446291 -118.934296) (xy 234.483508 -118.975833) (xy 234.514281 -119.022346) (xy 234.537953 -119.072843)
			(xy 234.554021 -119.12625) (xy 234.55619 -119.140986) (xy 235.177836 -119.140986) (xy 235.181907 -119.085364)
			(xy 235.194033 -119.030927) (xy 235.213956 -118.978836) (xy 235.241252 -118.930201) (xy 235.275338 -118.886058)
			(xy 235.315487 -118.847349) (xy 235.360845 -118.814898) (xy 235.410445 -118.789397) (xy 235.463229 -118.77139)
			(xy 235.518072 -118.76126) (xy 235.573806 -118.759223) (xy 235.629243 -118.765323) (xy 235.6832 -118.779429)
			(xy 235.734529 -118.801241) (xy 235.782135 -118.830295) (xy 235.825003 -118.86597) (xy 235.86222 -118.907507)
			(xy 235.892993 -118.95402) (xy 235.916665 -119.004517) (xy 235.932733 -119.057924) (xy 235.940583 -119.111268)
			(xy 236.70463 -119.111268) (xy 236.708701 -119.055646) (xy 236.720827 -119.001209) (xy 236.74075 -118.949118)
			(xy 236.768046 -118.900483) (xy 236.802132 -118.85634) (xy 236.842281 -118.817631) (xy 236.887639 -118.78518)
			(xy 236.937239 -118.759679) (xy 236.990023 -118.741672) (xy 237.044866 -118.731542) (xy 237.1006 -118.729505)
			(xy 237.156037 -118.735605) (xy 237.209994 -118.749711) (xy 237.261323 -118.771523) (xy 237.308929 -118.800577)
			(xy 237.351797 -118.836252) (xy 237.389014 -118.877789) (xy 237.419787 -118.924302) (xy 237.443459 -118.974799)
			(xy 237.459527 -119.028206) (xy 237.467647 -119.083382) (xy 237.468156 -119.111268) (xy 237.467647 -119.139154)
			(xy 237.459527 -119.19433) (xy 237.443459 -119.247737) (xy 237.419787 -119.298234) (xy 237.389014 -119.344747)
			(xy 237.351797 -119.386284) (xy 237.308929 -119.421959) (xy 237.261323 -119.451013) (xy 237.209994 -119.472825)
			(xy 237.156037 -119.486931) (xy 237.1006 -119.493031) (xy 237.044866 -119.490994) (xy 236.990023 -119.480864)
			(xy 236.937239 -119.462857) (xy 236.887639 -119.437356) (xy 236.842281 -119.404905) (xy 236.802132 -119.366196)
			(xy 236.768046 -119.322053) (xy 236.74075 -119.273418) (xy 236.720827 -119.221327) (xy 236.708701 -119.16689)
			(xy 236.70463 -119.111268) (xy 235.940583 -119.111268) (xy 235.940853 -119.1131) (xy 235.941362 -119.140986)
			(xy 235.940853 -119.168872) (xy 235.932733 -119.224048) (xy 235.916665 -119.277455) (xy 235.892993 -119.327952)
			(xy 235.86222 -119.374465) (xy 235.825003 -119.416002) (xy 235.782135 -119.451677) (xy 235.734529 -119.480731)
			(xy 235.6832 -119.502543) (xy 235.629243 -119.516649) (xy 235.573806 -119.522749) (xy 235.518072 -119.520712)
			(xy 235.463229 -119.510582) (xy 235.410445 -119.492575) (xy 235.360845 -119.467074) (xy 235.315487 -119.434623)
			(xy 235.275338 -119.395914) (xy 235.241252 -119.351771) (xy 235.213956 -119.303136) (xy 235.194033 -119.251045)
			(xy 235.181907 -119.196608) (xy 235.177836 -119.140986) (xy 234.55619 -119.140986) (xy 234.562141 -119.181426)
			(xy 234.56265 -119.209312) (xy 234.562141 -119.237198) (xy 234.554021 -119.292374) (xy 234.537953 -119.345781)
			(xy 234.514281 -119.396278) (xy 234.483508 -119.442791) (xy 234.446291 -119.484328) (xy 234.403423 -119.520003)
			(xy 234.355817 -119.549057) (xy 234.304488 -119.570869) (xy 234.250531 -119.584975) (xy 234.195094 -119.591075)
			(xy 234.13936 -119.589038) (xy 234.084517 -119.578908) (xy 234.031733 -119.560901) (xy 233.982133 -119.5354)
			(xy 233.936775 -119.502949) (xy 233.896626 -119.46424) (xy 233.86254 -119.420097) (xy 233.835244 -119.371462)
			(xy 233.815321 -119.319371) (xy 233.803195 -119.264934) (xy 233.799124 -119.209312) (xy 233.192697 -119.209312)
			(xy 233.187501 -119.244622) (xy 233.171433 -119.298029) (xy 233.147761 -119.348526) (xy 233.116988 -119.395039)
			(xy 233.079771 -119.436576) (xy 233.036903 -119.472251) (xy 232.989297 -119.501305) (xy 232.937968 -119.523117)
			(xy 232.884011 -119.537223) (xy 232.828574 -119.543323) (xy 232.77284 -119.541286) (xy 232.717997 -119.531156)
			(xy 232.665213 -119.513149) (xy 232.615613 -119.487648) (xy 232.570255 -119.455197) (xy 232.530106 -119.416488)
			(xy 232.49602 -119.372345) (xy 232.468724 -119.32371) (xy 232.448801 -119.271619) (xy 232.436675 -119.217182)
			(xy 232.432604 -119.16156) (xy 216.462035 -119.16156) (xy 216.46695 -119.195748) (xy 216.46695 -119.250252)
			(xy 216.459194 -119.304201) (xy 216.443839 -119.356498) (xy 216.421198 -119.406077) (xy 216.391732 -119.451929)
			(xy 216.356041 -119.493121) (xy 216.314851 -119.528816) (xy 216.269001 -119.558285) (xy 216.219424 -119.580929)
			(xy 216.167129 -119.596288) (xy 216.11318 -119.604048) (xy 216.085928 -119.604536) (xy 216.058953 -119.604082)
			(xy 216.005541 -119.596482) (xy 215.953733 -119.58143) (xy 215.928956 -119.570754) (xy 215.917272 -119.56542)
			(xy 215.891364 -119.567452) (xy 215.808814 -119.620792) (xy 215.798511 -119.628313) (xy 215.786392 -119.650725)
			(xy 215.7857 -119.663464) (xy 215.7857 -120.779794) (xy 230.950768 -120.779794) (xy 230.954839 -120.724172)
			(xy 230.966965 -120.669735) (xy 230.986888 -120.617644) (xy 231.014184 -120.569009) (xy 231.04827 -120.524866)
			(xy 231.088419 -120.486157) (xy 231.133777 -120.453706) (xy 231.183377 -120.428205) (xy 231.236161 -120.410198)
			(xy 231.291004 -120.400068) (xy 231.346738 -120.398031) (xy 231.402175 -120.404131) (xy 231.456132 -120.418237)
			(xy 231.507461 -120.440049) (xy 231.555067 -120.469103) (xy 231.597935 -120.504778) (xy 231.635152 -120.546315)
			(xy 231.665925 -120.592828) (xy 231.689597 -120.643325) (xy 231.705665 -120.696732) (xy 231.713785 -120.751908)
			(xy 231.714294 -120.779794) (xy 231.713785 -120.80768) (xy 231.705665 -120.862856) (xy 231.689597 -120.916263)
			(xy 231.665925 -120.96676) (xy 231.635152 -121.013273) (xy 231.597935 -121.05481) (xy 231.555067 -121.090485)
			(xy 231.507461 -121.119539) (xy 231.456132 -121.141351) (xy 231.402175 -121.155457) (xy 231.346738 -121.161557)
			(xy 231.291004 -121.15952) (xy 231.236161 -121.14939) (xy 231.183377 -121.131383) (xy 231.133777 -121.105882)
			(xy 231.088419 -121.073431) (xy 231.04827 -121.034722) (xy 231.014184 -120.990579) (xy 230.986888 -120.941944)
			(xy 230.966965 -120.889853) (xy 230.954839 -120.835416) (xy 230.950768 -120.779794) (xy 215.7857 -120.779794)
			(xy 215.7857 -121.021094) (xy 215.785227 -121.052728) (xy 215.776979 -121.115457) (xy 215.76061 -121.176572)
			(xy 215.7364 -121.235025) (xy 215.704764 -121.289817) (xy 215.666244 -121.340008) (xy 215.644222 -121.362724)
			(xy 215.263984 -121.742962) (xy 220.459298 -121.742962) (xy 220.463369 -121.68734) (xy 220.475495 -121.632903)
			(xy 220.495418 -121.580812) (xy 220.522714 -121.532177) (xy 220.5568 -121.488034) (xy 220.596949 -121.449325)
			(xy 220.642307 -121.416874) (xy 220.691907 -121.391373) (xy 220.744691 -121.373366) (xy 220.799534 -121.363236)
			(xy 220.855268 -121.361199) (xy 220.910705 -121.367299) (xy 220.964662 -121.381405) (xy 221.005578 -121.398792)
			(xy 233.551728 -121.398792) (xy 233.555799 -121.34317) (xy 233.567925 -121.288733) (xy 233.587848 -121.236642)
			(xy 233.615144 -121.188007) (xy 233.64923 -121.143864) (xy 233.689379 -121.105155) (xy 233.734737 -121.072704)
			(xy 233.784337 -121.047203) (xy 233.837121 -121.029196) (xy 233.891964 -121.019066) (xy 233.947698 -121.017029)
			(xy 234.003135 -121.023129) (xy 234.057092 -121.037235) (xy 234.108421 -121.059047) (xy 234.156027 -121.088101)
			(xy 234.198895 -121.123776) (xy 234.236112 -121.165313) (xy 234.266885 -121.211826) (xy 234.290557 -121.262323)
			(xy 234.306625 -121.31573) (xy 234.314745 -121.370906) (xy 234.315254 -121.398792) (xy 234.567728 -121.398792)
			(xy 234.571799 -121.34317) (xy 234.583925 -121.288733) (xy 234.603848 -121.236642) (xy 234.631144 -121.188007)
			(xy 234.66523 -121.143864) (xy 234.705379 -121.105155) (xy 234.750737 -121.072704) (xy 234.800337 -121.047203)
			(xy 234.853121 -121.029196) (xy 234.907964 -121.019066) (xy 234.963698 -121.017029) (xy 235.019135 -121.023129)
			(xy 235.073092 -121.037235) (xy 235.124421 -121.059047) (xy 235.172027 -121.088101) (xy 235.214895 -121.123776)
			(xy 235.252112 -121.165313) (xy 235.282885 -121.211826) (xy 235.306557 -121.262323) (xy 235.322625 -121.31573)
			(xy 235.330745 -121.370906) (xy 235.331254 -121.398792) (xy 235.583728 -121.398792) (xy 235.587799 -121.34317)
			(xy 235.599925 -121.288733) (xy 235.619848 -121.236642) (xy 235.647144 -121.188007) (xy 235.68123 -121.143864)
			(xy 235.721379 -121.105155) (xy 235.766737 -121.072704) (xy 235.816337 -121.047203) (xy 235.869121 -121.029196)
			(xy 235.923964 -121.019066) (xy 235.979698 -121.017029) (xy 236.035135 -121.023129) (xy 236.089092 -121.037235)
			(xy 236.140421 -121.059047) (xy 236.188027 -121.088101) (xy 236.230895 -121.123776) (xy 236.268112 -121.165313)
			(xy 236.298885 -121.211826) (xy 236.322557 -121.262323) (xy 236.338625 -121.31573) (xy 236.346745 -121.370906)
			(xy 236.347254 -121.398792) (xy 236.346745 -121.426678) (xy 236.338625 -121.481854) (xy 236.322557 -121.535261)
			(xy 236.298885 -121.585758) (xy 236.268112 -121.632271) (xy 236.230895 -121.673808) (xy 236.188027 -121.709483)
			(xy 236.140421 -121.738537) (xy 236.089092 -121.760349) (xy 236.035135 -121.774455) (xy 235.979698 -121.780555)
			(xy 235.923964 -121.778518) (xy 235.869121 -121.768388) (xy 235.816337 -121.750381) (xy 235.766737 -121.72488)
			(xy 235.721379 -121.692429) (xy 235.68123 -121.65372) (xy 235.647144 -121.609577) (xy 235.619848 -121.560942)
			(xy 235.599925 -121.508851) (xy 235.587799 -121.454414) (xy 235.583728 -121.398792) (xy 235.331254 -121.398792)
			(xy 235.330745 -121.426678) (xy 235.322625 -121.481854) (xy 235.306557 -121.535261) (xy 235.282885 -121.585758)
			(xy 235.252112 -121.632271) (xy 235.214895 -121.673808) (xy 235.172027 -121.709483) (xy 235.124421 -121.738537)
			(xy 235.073092 -121.760349) (xy 235.019135 -121.774455) (xy 234.963698 -121.780555) (xy 234.907964 -121.778518)
			(xy 234.853121 -121.768388) (xy 234.800337 -121.750381) (xy 234.750737 -121.72488) (xy 234.705379 -121.692429)
			(xy 234.66523 -121.65372) (xy 234.631144 -121.609577) (xy 234.603848 -121.560942) (xy 234.583925 -121.508851)
			(xy 234.571799 -121.454414) (xy 234.567728 -121.398792) (xy 234.315254 -121.398792) (xy 234.314745 -121.426678)
			(xy 234.306625 -121.481854) (xy 234.290557 -121.535261) (xy 234.266885 -121.585758) (xy 234.236112 -121.632271)
			(xy 234.198895 -121.673808) (xy 234.156027 -121.709483) (xy 234.108421 -121.738537) (xy 234.057092 -121.760349)
			(xy 234.003135 -121.774455) (xy 233.947698 -121.780555) (xy 233.891964 -121.778518) (xy 233.837121 -121.768388)
			(xy 233.784337 -121.750381) (xy 233.734737 -121.72488) (xy 233.689379 -121.692429) (xy 233.64923 -121.65372)
			(xy 233.615144 -121.609577) (xy 233.587848 -121.560942) (xy 233.567925 -121.508851) (xy 233.555799 -121.454414)
			(xy 233.551728 -121.398792) (xy 221.005578 -121.398792) (xy 221.015991 -121.403217) (xy 221.063597 -121.432271)
			(xy 221.106465 -121.467946) (xy 221.143682 -121.509483) (xy 221.174455 -121.555996) (xy 221.198127 -121.606493)
			(xy 221.214195 -121.6599) (xy 221.222315 -121.715076) (xy 221.222824 -121.742962) (xy 221.222315 -121.770848)
			(xy 221.214195 -121.826024) (xy 221.198127 -121.879431) (xy 221.174455 -121.929928) (xy 221.143682 -121.976441)
			(xy 221.106465 -122.017978) (xy 221.063597 -122.053653) (xy 221.015991 -122.082707) (xy 220.964662 -122.104519)
			(xy 220.910705 -122.118625) (xy 220.855268 -122.124725) (xy 220.799534 -122.122688) (xy 220.744691 -122.112558)
			(xy 220.691907 -122.094551) (xy 220.642307 -122.06905) (xy 220.596949 -122.036599) (xy 220.5568 -121.99789)
			(xy 220.522714 -121.953747) (xy 220.495418 -121.905112) (xy 220.475495 -121.853021) (xy 220.463369 -121.798584)
			(xy 220.459298 -121.742962) (xy 215.263984 -121.742962) (xy 214.775288 -122.231658) (xy 214.754322 -122.251941)
			(xy 214.708399 -122.287915) (xy 214.658476 -122.318093) (xy 214.605281 -122.342036) (xy 214.549588 -122.359394)
			(xy 214.49221 -122.369915) (xy 214.463122 -122.37212) (xy 214.45282 -122.373238) (xy 214.434327 -122.382533)
			(xy 214.427308 -122.390154) (xy 214.372952 -122.454162) (xy 214.36711 -122.473974) (xy 214.368126 -122.484388)
			(xy 214.369173 -122.494516) (xy 214.370319 -122.514847) (xy 214.370412 -122.525028) (xy 214.369806 -122.555831)
			(xy 214.359879 -122.616632) (xy 214.340304 -122.675046) (xy 214.32647 -122.702574) (xy 214.323762 -122.708101)
			(xy 214.320802 -122.720044) (xy 214.320628 -122.726196) (xy 214.320628 -122.758962) (xy 218.430854 -122.758962)
			(xy 218.434925 -122.70334) (xy 218.447051 -122.648903) (xy 218.466974 -122.596812) (xy 218.49427 -122.548177)
			(xy 218.528356 -122.504034) (xy 218.568505 -122.465325) (xy 218.613863 -122.432874) (xy 218.663463 -122.407373)
			(xy 218.716247 -122.389366) (xy 218.77109 -122.379236) (xy 218.826824 -122.377199) (xy 218.882261 -122.383299)
			(xy 218.936218 -122.397405) (xy 218.987547 -122.419217) (xy 219.035153 -122.448271) (xy 219.078021 -122.483946)
			(xy 219.115238 -122.525483) (xy 219.146011 -122.571996) (xy 219.169683 -122.622493) (xy 219.185751 -122.6759)
			(xy 219.193871 -122.731076) (xy 219.19438 -122.758962) (xy 219.193871 -122.786848) (xy 219.185751 -122.842024)
			(xy 219.169683 -122.895431) (xy 219.146011 -122.945928) (xy 219.115238 -122.992441) (xy 219.078021 -123.033978)
			(xy 219.035153 -123.069653) (xy 218.987547 -123.098707) (xy 218.936218 -123.120519) (xy 218.882261 -123.134625)
			(xy 218.826824 -123.140725) (xy 218.77109 -123.138688) (xy 218.716247 -123.128558) (xy 218.663463 -123.110551)
			(xy 218.613863 -123.08505) (xy 218.568505 -123.052599) (xy 218.528356 -123.01389) (xy 218.49427 -122.969747)
			(xy 218.466974 -122.921112) (xy 218.447051 -122.869021) (xy 218.434925 -122.814584) (xy 218.430854 -122.758962)
			(xy 214.320628 -122.758962) (xy 214.320628 -123.774962) (xy 218.430854 -123.774962) (xy 218.434925 -123.71934)
			(xy 218.447051 -123.664903) (xy 218.466974 -123.612812) (xy 218.49427 -123.564177) (xy 218.528356 -123.520034)
			(xy 218.568505 -123.481325) (xy 218.613863 -123.448874) (xy 218.663463 -123.423373) (xy 218.716247 -123.405366)
			(xy 218.77109 -123.395236) (xy 218.826824 -123.393199) (xy 218.882261 -123.399299) (xy 218.936218 -123.413405)
			(xy 218.987547 -123.435217) (xy 219.035153 -123.464271) (xy 219.078021 -123.499946) (xy 219.115238 -123.541483)
			(xy 219.146011 -123.587996) (xy 219.169683 -123.638493) (xy 219.185751 -123.6919) (xy 219.193871 -123.747076)
			(xy 219.19438 -123.774962) (xy 220.586298 -123.774962) (xy 220.590369 -123.71934) (xy 220.602495 -123.664903)
			(xy 220.622418 -123.612812) (xy 220.649714 -123.564177) (xy 220.6838 -123.520034) (xy 220.723949 -123.481325)
			(xy 220.769307 -123.448874) (xy 220.818907 -123.423373) (xy 220.871691 -123.405366) (xy 220.926534 -123.395236)
			(xy 220.982268 -123.393199) (xy 221.037705 -123.399299) (xy 221.091662 -123.413405) (xy 221.142991 -123.435217)
			(xy 221.190597 -123.464271) (xy 221.233465 -123.499946) (xy 221.241599 -123.509024) (xy 223.888298 -123.509024)
			(xy 223.892369 -123.453402) (xy 223.904495 -123.398965) (xy 223.924418 -123.346874) (xy 223.951714 -123.298239)
			(xy 223.9858 -123.254096) (xy 224.025949 -123.215387) (xy 224.071307 -123.182936) (xy 224.120907 -123.157435)
			(xy 224.173691 -123.139428) (xy 224.228534 -123.129298) (xy 224.284268 -123.127261) (xy 224.339705 -123.133361)
			(xy 224.393662 -123.147467) (xy 224.444991 -123.169279) (xy 224.492597 -123.198333) (xy 224.535465 -123.234008)
			(xy 224.572682 -123.275545) (xy 224.603455 -123.322058) (xy 224.627127 -123.372555) (xy 224.643195 -123.425962)
			(xy 224.651315 -123.481138) (xy 224.651824 -123.509024) (xy 224.651606 -123.520962) (xy 226.047298 -123.520962)
			(xy 226.051369 -123.46534) (xy 226.063495 -123.410903) (xy 226.083418 -123.358812) (xy 226.110714 -123.310177)
			(xy 226.1448 -123.266034) (xy 226.184949 -123.227325) (xy 226.230307 -123.194874) (xy 226.279907 -123.169373)
			(xy 226.332691 -123.151366) (xy 226.387534 -123.141236) (xy 226.443268 -123.139199) (xy 226.498705 -123.145299)
			(xy 226.552662 -123.159405) (xy 226.603991 -123.181217) (xy 226.651597 -123.210271) (xy 226.694465 -123.245946)
			(xy 226.731682 -123.287483) (xy 226.762455 -123.333996) (xy 226.786127 -123.384493) (xy 226.802195 -123.4379)
			(xy 226.810315 -123.493076) (xy 226.810824 -123.520962) (xy 226.810315 -123.548848) (xy 226.802195 -123.604024)
			(xy 226.786127 -123.657431) (xy 226.762455 -123.707928) (xy 226.731682 -123.754441) (xy 226.694465 -123.795978)
			(xy 226.651597 -123.831653) (xy 226.603991 -123.860707) (xy 226.552662 -123.882519) (xy 226.498705 -123.896625)
			(xy 226.443268 -123.902725) (xy 226.387534 -123.900688) (xy 226.332691 -123.890558) (xy 226.279907 -123.872551)
			(xy 226.230307 -123.84705) (xy 226.184949 -123.814599) (xy 226.1448 -123.77589) (xy 226.110714 -123.731747)
			(xy 226.083418 -123.683112) (xy 226.063495 -123.631021) (xy 226.051369 -123.576584) (xy 226.047298 -123.520962)
			(xy 224.651606 -123.520962) (xy 224.651315 -123.53691) (xy 224.643195 -123.592086) (xy 224.627127 -123.645493)
			(xy 224.603455 -123.69599) (xy 224.572682 -123.742503) (xy 224.535465 -123.78404) (xy 224.492597 -123.819715)
			(xy 224.444991 -123.848769) (xy 224.393662 -123.870581) (xy 224.339705 -123.884687) (xy 224.284268 -123.890787)
			(xy 224.228534 -123.88875) (xy 224.173691 -123.87862) (xy 224.120907 -123.860613) (xy 224.071307 -123.835112)
			(xy 224.025949 -123.802661) (xy 223.9858 -123.763952) (xy 223.951714 -123.719809) (xy 223.924418 -123.671174)
			(xy 223.904495 -123.619083) (xy 223.892369 -123.564646) (xy 223.888298 -123.509024) (xy 221.241599 -123.509024)
			(xy 221.270682 -123.541483) (xy 221.301455 -123.587996) (xy 221.325127 -123.638493) (xy 221.341195 -123.6919)
			(xy 221.349315 -123.747076) (xy 221.349824 -123.774962) (xy 221.349315 -123.802848) (xy 221.341195 -123.858024)
			(xy 221.325127 -123.911431) (xy 221.301455 -123.961928) (xy 221.270682 -124.008441) (xy 221.233465 -124.049978)
			(xy 221.190597 -124.085653) (xy 221.142991 -124.114707) (xy 221.091662 -124.136519) (xy 221.037705 -124.150625)
			(xy 220.982268 -124.156725) (xy 220.926534 -124.154688) (xy 220.871691 -124.144558) (xy 220.818907 -124.126551)
			(xy 220.769307 -124.10105) (xy 220.723949 -124.068599) (xy 220.6838 -124.02989) (xy 220.649714 -123.985747)
			(xy 220.622418 -123.937112) (xy 220.602495 -123.885021) (xy 220.590369 -123.830584) (xy 220.586298 -123.774962)
			(xy 219.19438 -123.774962) (xy 219.193871 -123.802848) (xy 219.185751 -123.858024) (xy 219.169683 -123.911431)
			(xy 219.146011 -123.961928) (xy 219.115238 -124.008441) (xy 219.078021 -124.049978) (xy 219.035153 -124.085653)
			(xy 218.987547 -124.114707) (xy 218.936218 -124.136519) (xy 218.882261 -124.150625) (xy 218.826824 -124.156725)
			(xy 218.77109 -124.154688) (xy 218.716247 -124.144558) (xy 218.663463 -124.126551) (xy 218.613863 -124.10105)
			(xy 218.568505 -124.068599) (xy 218.528356 -124.02989) (xy 218.49427 -123.985747) (xy 218.466974 -123.937112)
			(xy 218.447051 -123.885021) (xy 218.434925 -123.830584) (xy 218.430854 -123.774962) (xy 214.320628 -123.774962)
			(xy 214.320628 -124.745496) (xy 214.321048 -124.755566) (xy 214.328772 -124.774164) (xy 214.335614 -124.781564)
			(xy 215.292178 -125.738128) (xy 217.592908 -125.738128) (xy 217.596979 -125.682506) (xy 217.609105 -125.628069)
			(xy 217.629028 -125.575978) (xy 217.656324 -125.527343) (xy 217.69041 -125.4832) (xy 217.730559 -125.444491)
			(xy 217.775917 -125.41204) (xy 217.825517 -125.386539) (xy 217.878301 -125.368532) (xy 217.933144 -125.358402)
			(xy 217.988878 -125.356365) (xy 218.044315 -125.362465) (xy 218.098272 -125.376571) (xy 218.149601 -125.398383)
			(xy 218.197207 -125.427437) (xy 218.240075 -125.463112) (xy 218.277292 -125.504649) (xy 218.308065 -125.551162)
			(xy 218.331737 -125.601659) (xy 218.347805 -125.655066) (xy 218.355925 -125.710242) (xy 218.356434 -125.738128)
			(xy 218.355925 -125.766014) (xy 218.347805 -125.82119) (xy 218.331737 -125.874597) (xy 218.308065 -125.925094)
			(xy 218.277292 -125.971607) (xy 218.240075 -126.013144) (xy 218.197207 -126.048819) (xy 218.149601 -126.077873)
			(xy 218.098272 -126.099685) (xy 218.044315 -126.113791) (xy 217.988878 -126.119891) (xy 217.933144 -126.117854)
			(xy 217.878301 -126.107724) (xy 217.825517 -126.089717) (xy 217.775917 -126.064216) (xy 217.730559 -126.031765)
			(xy 217.69041 -125.993056) (xy 217.656324 -125.948913) (xy 217.629028 -125.900278) (xy 217.609105 -125.848187)
			(xy 217.596979 -125.79375) (xy 217.592908 -125.738128) (xy 215.292178 -125.738128) (xy 216.64422 -127.09017)
			(xy 216.651623 -127.097007) (xy 216.67022 -127.104729) (xy 216.680288 -127.105156) (xy 232.046018 -127.105156)
			(xy 232.05609 -127.104752) (xy 232.074688 -127.097017) (xy 232.082086 -127.09017) (xy 237.165642 -122.006614)
			(xy 237.172474 -121.999208) (xy 237.180197 -121.980613) (xy 237.180628 -121.970546) (xy 237.180628 -120.862852)
			(xy 237.181138 -120.836828) (xy 237.189306 -120.785423) (xy 237.205404 -120.735925) (xy 237.229036 -120.689549)
			(xy 237.259621 -120.647434) (xy 237.277656 -120.628664) (xy 239.616234 -118.290086) (xy 239.623077 -118.282689)
			(xy 239.630794 -118.264087) (xy 239.63122 -118.254018) (xy 239.63122 -112.885474) (xy 239.63083 -112.8754)
			(xy 239.623087 -112.856802) (xy 239.616234 -112.849406) (xy 239.142778 -112.37595) (xy 239.138376 -112.371843)
			(xy 239.128118 -112.365552) (xy 239.122458 -112.363504) (xy 239.12195 -112.363504) (xy 239.096397 -112.355081)
			(xy 239.047791 -112.332009) (xy 239.002909 -112.302337) (xy 238.962641 -112.266653) (xy 238.927785 -112.225666)
			(xy 238.899034 -112.180188) (xy 238.876957 -112.131122) (xy 238.861993 -112.079441) (xy 238.854439 -112.02617)
			(xy 238.85398 -111.999268) (xy 238.854448 -111.972017) (xy 238.862209 -111.918069) (xy 238.877567 -111.865774)
			(xy 238.900211 -111.816198) (xy 238.92968 -111.770348) (xy 238.965373 -111.729159) (xy 239.006564 -111.693468)
			(xy 239.052415 -111.664002) (xy 239.101993 -111.64136) (xy 239.154288 -111.626004) (xy 239.208236 -111.618247)
			(xy 239.235488 -111.61776) (xy 239.262396 -111.618298) (xy 239.315676 -111.625872) (xy 239.367363 -111.640857)
			(xy 239.416432 -111.662956) (xy 239.461909 -111.69173) (xy 239.502892 -111.726608) (xy 239.538568 -111.766899)
			(xy 239.568229 -111.811803) (xy 239.591286 -111.860429) (xy 239.599724 -111.885984) (xy 239.599724 -111.886238)
			(xy 239.60171 -111.891929) (xy 239.608002 -111.902205) (xy 239.61217 -111.906558) (xy 240.197894 -112.492282)
			(xy 240.216001 -112.511068) (xy 240.246684 -112.553265) (xy 240.270385 -112.599745) (xy 240.286519 -112.649361)
			(xy 240.294688 -112.700891) (xy 240.295176 -112.726978) (xy 240.295176 -118.412514) (xy 240.294719 -118.438603)
			(xy 240.286548 -118.490136) (xy 240.27041 -118.539755) (xy 240.246702 -118.586235) (xy 240.21601 -118.628431)
			(xy 240.197894 -118.64721) (xy 237.859062 -120.985788) (xy 237.852229 -120.993194) (xy 237.844506 -121.011789)
			(xy 237.844076 -121.021856) (xy 237.844076 -122.12955) (xy 237.843566 -122.155574) (xy 237.835397 -122.206979)
			(xy 237.8193 -122.256477) (xy 237.795668 -122.302853) (xy 237.765083 -122.344968) (xy 237.747048 -122.363738)
			(xy 232.43921 -127.671576) (xy 232.420462 -127.689633) (xy 232.378337 -127.720207) (xy 232.331955 -127.743828)
			(xy 232.282454 -127.759917) (xy 232.231047 -127.768079) (xy 232.205022 -127.768604) (xy 216.521284 -127.768604)
			(xy 216.495261 -127.768065) (xy 216.443858 -127.759902) (xy 216.394361 -127.743811) (xy 216.347984 -127.720186)
			(xy 216.305867 -127.689607) (xy 216.287096 -127.671576) (xy 213.754208 -125.138688) (xy 213.736203 -125.119892)
			(xy 213.705619 -125.077782) (xy 213.681986 -125.031412) (xy 213.665886 -124.981921) (xy 213.657711 -124.930522)
			(xy 213.65718 -124.9045) (xy 213.65718 -122.726196) (xy 213.656987 -122.720046) (xy 213.654033 -122.708106)
			(xy 213.651338 -122.702574) (xy 213.637957 -122.676003) (xy 213.618722 -122.619709) (xy 213.608474 -122.561109)
			(xy 213.607396 -122.531378) (xy 213.606888 -122.524012) (xy 213.604792 -122.510712) (xy 213.602502 -122.483881)
			(xy 213.602316 -122.470418) (xy 213.602316 -121.574306) (xy 213.602788 -121.548218) (xy 213.610955 -121.496685)
			(xy 213.62709 -121.447067) (xy 213.650794 -121.400586) (xy 213.681483 -121.35839) (xy 213.699598 -121.33961)
			(xy 214.435182 -120.60428) (xy 214.442021 -120.596879) (xy 214.449742 -120.578281) (xy 214.450168 -120.568212)
			(xy 214.450168 -120.552972) (xy 214.449715 -120.543652) (xy 214.443042 -120.526248) (xy 214.430588 -120.512378)
			(xy 214.422482 -120.50776) (xy 214.32901 -120.460262) (xy 214.300816 -120.462294) (xy 214.289132 -120.470676)
			(xy 214.26459 -120.487637) (xy 214.211376 -120.514592) (xy 214.154616 -120.532939) (xy 214.095692 -120.542231)
			(xy 214.065866 -120.542812) (xy 214.038617 -120.542316) (xy 213.984673 -120.534556) (xy 213.932383 -120.519198)
			(xy 213.882811 -120.496555) (xy 213.836965 -120.467088) (xy 213.795779 -120.431397) (xy 213.760092 -120.390208)
			(xy 213.730629 -120.34436) (xy 213.70799 -120.294785) (xy 213.692637 -120.242494) (xy 213.684882 -120.188549)
			(xy 213.684882 -120.134051) (xy 213.692637 -120.080106) (xy 213.70799 -120.027815) (xy 213.730629 -119.97824)
			(xy 213.760092 -119.932392) (xy 213.795779 -119.891203) (xy 213.836965 -119.855512) (xy 213.882811 -119.826045)
			(xy 213.932383 -119.803402) (xy 213.984673 -119.788044) (xy 214.038617 -119.780284) (xy 214.065866 -119.779796)
			(xy 214.095694 -119.780357) (xy 214.154624 -119.789639) (xy 214.21139 -119.807984) (xy 214.264608 -119.834942)
			(xy 214.289132 -119.851932) (xy 214.29691 -119.856984) (xy 214.314824 -119.861726) (xy 214.333254 -119.859805)
			(xy 214.34171 -119.855996) (xy 214.422482 -119.814848) (xy 214.430628 -119.810284) (xy 214.443097 -119.796398)
			(xy 214.449762 -119.778967) (xy 214.450168 -119.769636) (xy 214.450168 -119.035068) (xy 214.449819 -119.026089)
			(xy 214.443569 -119.009251) (xy 214.431911 -118.995587) (xy 214.42426 -118.990872) (xy 214.347298 -118.947184)
			(xy 214.339375 -118.943112) (xy 214.321821 -118.940167) (xy 214.304325 -118.943442) (xy 214.296498 -118.947692)
			(xy 214.296244 -118.947692) (xy 214.273985 -118.960515) (xy 214.22676 -118.980732) (xy 214.177249 -118.994428)
			(xy 214.126349 -119.001357) (xy 214.100664 -119.001794) (xy 214.073413 -119.001334) (xy 214.019468 -118.993573)
			(xy 213.967175 -118.978214) (xy 213.917601 -118.95557) (xy 213.871753 -118.926102) (xy 213.830566 -118.890409)
			(xy 213.794877 -118.849218) (xy 213.765413 -118.803368) (xy 213.742773 -118.753791) (xy 213.72742 -118.701497)
			(xy 213.719664 -118.647551) (xy 213.719664 -118.593049) (xy 213.72742 -118.539103) (xy 213.742773 -118.486809)
			(xy 213.765413 -118.437232) (xy 213.794877 -118.391382) (xy 213.830566 -118.350191) (xy 213.871753 -118.314498)
			(xy 213.917601 -118.28503) (xy 213.967175 -118.262386) (xy 214.019468 -118.247027) (xy 214.073413 -118.239266)
			(xy 214.100664 -118.238778) (xy 214.126349 -118.239215) (xy 214.17725 -118.246144) (xy 214.226761 -118.259839)
			(xy 214.273986 -118.280055) (xy 214.296244 -118.29288) (xy 214.296498 -118.29288) (xy 214.304338 -118.297085)
			(xy 214.321821 -118.300321) (xy 214.339361 -118.297411) (xy 214.347298 -118.293388) (xy 214.42426 -118.2497)
			(xy 214.431949 -118.245035) (xy 214.443621 -118.231364) (xy 214.449825 -118.214493) (xy 214.450168 -118.205504)
			(xy 214.450168 -117.52453) (xy 214.449753 -117.514381) (xy 214.441921 -117.495656) (xy 214.427434 -117.481441)
			(xy 214.418164 -117.477286) (xy 214.315802 -117.436392) (xy 214.285576 -117.442996) (xy 214.274908 -117.454172)
			(xy 214.256836 -117.472508) (xy 214.216648 -117.504684) (xy 214.172495 -117.531157) (xy 214.125179 -117.551445)
			(xy 214.075564 -117.56518) (xy 214.024551 -117.572112) (xy 213.99881 -117.572536) (xy 213.971559 -117.572017)
			(xy 213.917611 -117.564262) (xy 213.865315 -117.548908) (xy 213.815738 -117.526268) (xy 213.769887 -117.496802)
			(xy 213.728696 -117.461111) (xy 213.693004 -117.419921) (xy 213.663537 -117.374071) (xy 213.640895 -117.324494)
			(xy 213.62554 -117.272199) (xy 213.617783 -117.218251) (xy 213.617783 -117.163749) (xy 213.62554 -117.109801)
			(xy 213.640895 -117.057506) (xy 213.663537 -117.007929) (xy 213.693004 -116.962079) (xy 213.728696 -116.920889)
			(xy 213.769887 -116.885198) (xy 213.815738 -116.855732) (xy 213.865315 -116.833092) (xy 213.917611 -116.817738)
			(xy 213.971559 -116.809983) (xy 213.99881 -116.80952) (xy 214.024551 -116.809928) (xy 214.075565 -116.816868)
			(xy 214.12518 -116.830607) (xy 214.172497 -116.850896) (xy 214.216655 -116.877365) (xy 214.25685 -116.909534)
			(xy 214.274908 -116.927884) (xy 214.285576 -116.93906) (xy 214.315802 -116.945664) (xy 214.418164 -116.90477)
			(xy 214.427429 -116.900619) (xy 214.441884 -116.886383) (xy 214.449724 -116.86767) (xy 214.450168 -116.857526)
			(xy 214.450168 -115.537996) (xy 214.449753 -115.527925) (xy 214.442026 -115.509327) (xy 214.435182 -115.501928)
			(xy 210.751928 -111.818674) (xy 210.744516 -111.81185) (xy 210.725926 -111.804122) (xy 210.71586 -111.803688)
			(xy 207.738726 -111.803688) (xy 207.730025 -111.804051) (xy 207.71362 -111.809852) (xy 207.700115 -111.820823)
			(xy 207.695292 -111.828072) (xy 207.643222 -111.913924) (xy 207.642206 -111.939832) (xy 207.648302 -111.95177)
			(xy 207.661603 -111.978866) (xy 207.680394 -112.036227) (xy 207.689899 -112.095834) (xy 207.690466 -112.126014)
			(xy 207.690466 -112.126268) (xy 207.690035 -112.152714) (xy 207.682721 -112.205097) (xy 207.668242 -112.255968)
			(xy 207.646877 -112.304352) (xy 207.619034 -112.349322) (xy 207.585248 -112.390016) (xy 207.546165 -112.425653)
			(xy 207.524604 -112.440974) (xy 207.51593 -112.447449) (xy 207.504608 -112.46587) (xy 207.50276 -112.476534)
			(xy 207.49895 -112.508792) (xy 207.498044 -112.519483) (xy 207.504222 -112.540009) (xy 207.510888 -112.548416)
			(xy 207.52435 -112.564672) (xy 207.531976 -112.573458) (xy 207.552863 -112.58365) (xy 207.564482 -112.58423)
			(xy 207.644238 -112.58423) (xy 207.655875 -112.583723) (xy 207.676785 -112.573514) (xy 207.68437 -112.564672)
			(xy 207.702571 -112.542197) (xy 207.744589 -112.502463) (xy 207.792123 -112.469523) (xy 207.844082 -112.444134)
			(xy 207.899277 -112.426875) (xy 207.956445 -112.418143) (xy 207.98536 -112.417606) (xy 208.012616 -112.418038)
			(xy 208.066573 -112.425791) (xy 208.118878 -112.441144) (xy 208.168465 -112.463785) (xy 208.214325 -112.493253)
			(xy 208.255524 -112.528948) (xy 208.291223 -112.570143) (xy 208.320696 -112.616) (xy 208.343342 -112.665585)
			(xy 208.358701 -112.717888) (xy 208.366459 -112.771844) (xy 208.366459 -112.826356) (xy 208.358701 -112.880312)
			(xy 208.343342 -112.932615) (xy 208.320696 -112.9822) (xy 208.291223 -113.028057) (xy 208.255524 -113.069252)
			(xy 208.214325 -113.104947) (xy 208.168465 -113.134415) (xy 208.118878 -113.157056) (xy 208.066573 -113.172409)
			(xy 208.012616 -113.180162) (xy 207.98536 -113.180622) (xy 207.956443 -113.18009) (xy 207.899271 -113.171368)
			(xy 207.844072 -113.154115) (xy 207.792109 -113.128726) (xy 207.744575 -113.095783) (xy 207.702559 -113.056042)
			(xy 207.68437 -113.033556) (xy 207.676774 -113.024738) (xy 207.655864 -113.014562) (xy 207.644238 -113.013998)
			(xy 207.564482 -113.013998) (xy 207.552851 -113.014542) (xy 207.531941 -113.024727) (xy 207.52435 -113.033556)
			(xy 207.50612 -113.056006) (xy 207.464109 -113.095746) (xy 207.416583 -113.12869) (xy 207.364629 -113.154084)
			(xy 207.309438 -113.171347) (xy 207.252274 -113.180083) (xy 207.22336 -113.180622) (xy 207.196108 -113.180159)
			(xy 207.142161 -113.172398) (xy 207.089866 -113.157038) (xy 207.04029 -113.134394) (xy 206.99444 -113.104924)
			(xy 206.953251 -113.069231) (xy 206.91756 -113.028039) (xy 206.888094 -112.982187) (xy 206.865453 -112.932609)
			(xy 206.850097 -112.880314) (xy 206.842339 -112.826366) (xy 206.841852 -112.799114) (xy 206.842337 -112.77267)
			(xy 206.849641 -112.720289) (xy 206.864109 -112.669418) (xy 206.885465 -112.621034) (xy 206.9133 -112.576063)
			(xy 206.94708 -112.535369) (xy 206.986156 -112.49973) (xy 207.007714 -112.484408) (xy 207.016398 -112.477945)
			(xy 207.027714 -112.459515) (xy 207.029558 -112.448848) (xy 207.033622 -112.41659) (xy 207.034441 -112.405878)
			(xy 207.028135 -112.38536) (xy 207.02143 -112.376966) (xy 207.021176 -112.376712) (xy 207.013541 -112.368696)
			(xy 206.993377 -112.359614) (xy 206.982314 -112.359186) (xy 206.949802 -112.359694) (xy 206.938787 -112.360335)
			(xy 206.918897 -112.36984) (xy 206.911448 -112.377982) (xy 206.893221 -112.399159) (xy 206.851659 -112.436499)
			(xy 206.805096 -112.467377) (xy 206.754527 -112.491135) (xy 206.701033 -112.507262) (xy 206.64576 -112.515414)
			(xy 206.617824 -112.515904) (xy 206.61757 -112.515904) (xy 206.58961 -112.515431) (xy 206.534291 -112.507246)
			(xy 206.480765 -112.491058) (xy 206.455264 -112.479582) (xy 206.44381 -112.474794) (xy 206.419032 -112.475877)
			(xy 206.40802 -112.481614) (xy 206.33563 -112.523524) (xy 206.325391 -112.530303) (xy 206.312249 -112.550997)
			(xy 206.310484 -112.563148) (xy 206.310484 -112.563656) (xy 206.307683 -112.591985) (xy 206.294811 -112.647435)
			(xy 206.273839 -112.700356) (xy 206.245234 -112.749571) (xy 206.20963 -112.793987) (xy 206.16782 -112.832616)
			(xy 206.120732 -112.864602) (xy 206.069412 -112.889232) (xy 206.015001 -112.90596) (xy 205.958708 -112.914414)
			(xy 205.930246 -112.914938) (xy 205.903273 -112.91443) (xy 205.849864 -112.906849) (xy 205.798055 -112.891817)
			(xy 205.748881 -112.869636) (xy 205.703324 -112.840746) (xy 205.662293 -112.805725) (xy 205.626605 -112.765272)
			(xy 205.596974 -112.720193) (xy 205.58506 -112.69599) (xy 205.579726 -112.684814) (xy 205.560168 -112.669828)
			(xy 205.465934 -112.653318) (xy 205.453827 -112.651904) (xy 205.430609 -112.659205) (xy 205.421484 -112.667288)
			(xy 204.242416 -113.846356) (xy 205.461106 -113.846356) (xy 205.465177 -113.790734) (xy 205.477303 -113.736297)
			(xy 205.497226 -113.684206) (xy 205.524522 -113.635571) (xy 205.558608 -113.591428) (xy 205.598757 -113.552719)
			(xy 205.644115 -113.520268) (xy 205.693715 -113.494767) (xy 205.746499 -113.47676) (xy 205.801342 -113.46663)
			(xy 205.857076 -113.464593) (xy 205.912513 -113.470693) (xy 205.96647 -113.484799) (xy 206.017799 -113.506611)
			(xy 206.065405 -113.535665) (xy 206.108273 -113.57134) (xy 206.14549 -113.612877) (xy 206.176263 -113.65939)
			(xy 206.199935 -113.709887) (xy 206.216003 -113.763294) (xy 206.224123 -113.81847) (xy 206.224632 -113.846356)
			(xy 206.224123 -113.874242) (xy 206.216003 -113.929418) (xy 206.199935 -113.982825) (xy 206.176263 -114.033322)
			(xy 206.14549 -114.079835) (xy 206.108273 -114.121372) (xy 206.065405 -114.157047) (xy 206.017799 -114.186101)
			(xy 205.96647 -114.207913) (xy 205.912513 -114.222019) (xy 205.857076 -114.228119) (xy 205.801342 -114.226082)
			(xy 205.746499 -114.215952) (xy 205.693715 -114.197945) (xy 205.644115 -114.172444) (xy 205.598757 -114.139993)
			(xy 205.558608 -114.101284) (xy 205.524522 -114.057141) (xy 205.497226 -114.008506) (xy 205.477303 -113.956415)
			(xy 205.465177 -113.901978) (xy 205.461106 -113.846356) (xy 204.242416 -113.846356) (xy 204.119226 -113.969546)
			(xy 204.115111 -113.97394) (xy 204.108825 -113.984204) (xy 204.10678 -113.989866) (xy 204.10678 -113.990374)
			(xy 204.098305 -114.015908) (xy 204.075236 -114.06451) (xy 204.045568 -114.109389) (xy 204.009891 -114.149656)
			(xy 203.96891 -114.184512) (xy 203.92344 -114.213265) (xy 203.874382 -114.235346) (xy 203.822708 -114.250317)
			(xy 203.769443 -114.25788) (xy 203.742544 -114.258344) (xy 203.715294 -114.257804) (xy 203.661348 -114.250054)
			(xy 203.609053 -114.234705) (xy 203.559476 -114.21207) (xy 203.513624 -114.18261) (xy 203.472432 -114.146925)
			(xy 203.436738 -114.10574) (xy 203.407268 -114.059895) (xy 203.384623 -114.010322) (xy 203.369263 -113.958031)
			(xy 203.361502 -113.904086) (xy 203.361036 -113.876836) (xy 179.031392 -113.876836) (xy 178.326796 -114.581432)
			(xy 182.39943 -114.581432) (xy 182.403501 -114.52581) (xy 182.415627 -114.471373) (xy 182.43555 -114.419282)
			(xy 182.462846 -114.370647) (xy 182.496932 -114.326504) (xy 182.537081 -114.287795) (xy 182.582439 -114.255344)
			(xy 182.632039 -114.229843) (xy 182.684823 -114.211836) (xy 182.739666 -114.201706) (xy 182.7954 -114.199669)
			(xy 182.850837 -114.205769) (xy 182.904794 -114.219875) (xy 182.956123 -114.241687) (xy 183.003729 -114.270741)
			(xy 183.026984 -114.290094) (xy 186.460128 -114.290094) (xy 186.464199 -114.234472) (xy 186.476325 -114.180035)
			(xy 186.496248 -114.127944) (xy 186.523544 -114.079309) (xy 186.55763 -114.035166) (xy 186.597779 -113.996457)
			(xy 186.643137 -113.964006) (xy 186.692737 -113.938505) (xy 186.745521 -113.920498) (xy 186.800364 -113.910368)
			(xy 186.856098 -113.908331) (xy 186.911535 -113.914431) (xy 186.965492 -113.928537) (xy 187.016821 -113.950349)
			(xy 187.064427 -113.979403) (xy 187.107295 -114.015078) (xy 187.144512 -114.056615) (xy 187.175285 -114.103128)
			(xy 187.198957 -114.153625) (xy 187.215025 -114.207032) (xy 187.223145 -114.262208) (xy 187.223654 -114.290094)
			(xy 187.223145 -114.31798) (xy 187.215025 -114.373156) (xy 187.198957 -114.426563) (xy 187.175285 -114.47706)
			(xy 187.144512 -114.523573) (xy 187.107295 -114.56511) (xy 187.064427 -114.600785) (xy 187.016821 -114.629839)
			(xy 186.965492 -114.651651) (xy 186.911535 -114.665757) (xy 186.856098 -114.671857) (xy 186.800364 -114.66982)
			(xy 186.745521 -114.65969) (xy 186.692737 -114.641683) (xy 186.643137 -114.616182) (xy 186.597779 -114.583731)
			(xy 186.55763 -114.545022) (xy 186.523544 -114.500879) (xy 186.496248 -114.452244) (xy 186.476325 -114.400153)
			(xy 186.464199 -114.345716) (xy 186.460128 -114.290094) (xy 183.026984 -114.290094) (xy 183.046597 -114.306416)
			(xy 183.083814 -114.347953) (xy 183.114587 -114.394466) (xy 183.138259 -114.444963) (xy 183.154327 -114.49837)
			(xy 183.162447 -114.553546) (xy 183.162956 -114.581432) (xy 183.162447 -114.609318) (xy 183.154327 -114.664494)
			(xy 183.138259 -114.717901) (xy 183.114587 -114.768398) (xy 183.083814 -114.814911) (xy 183.046597 -114.856448)
			(xy 183.003729 -114.892123) (xy 182.956123 -114.921177) (xy 182.904794 -114.942989) (xy 182.850837 -114.957095)
			(xy 182.7954 -114.963195) (xy 182.739666 -114.961158) (xy 182.684823 -114.951028) (xy 182.632039 -114.933021)
			(xy 182.582439 -114.90752) (xy 182.537081 -114.875069) (xy 182.496932 -114.83636) (xy 182.462846 -114.792217)
			(xy 182.43555 -114.743582) (xy 182.415627 -114.691491) (xy 182.403501 -114.637054) (xy 182.39943 -114.581432)
			(xy 178.326796 -114.581432) (xy 177.622454 -115.285774) (xy 183.03062 -115.285774) (xy 183.034691 -115.230152)
			(xy 183.046817 -115.175715) (xy 183.06674 -115.123624) (xy 183.094036 -115.074989) (xy 183.128122 -115.030846)
			(xy 183.168271 -114.992137) (xy 183.213629 -114.959686) (xy 183.263229 -114.934185) (xy 183.316013 -114.916178)
			(xy 183.370856 -114.906048) (xy 183.42659 -114.904011) (xy 183.482027 -114.910111) (xy 183.535984 -114.924217)
			(xy 183.587313 -114.946029) (xy 183.634919 -114.975083) (xy 183.677787 -115.010758) (xy 183.715004 -115.052295)
			(xy 183.745777 -115.098808) (xy 183.769449 -115.149305) (xy 183.785517 -115.202712) (xy 183.793637 -115.257888)
			(xy 183.794146 -115.285774) (xy 183.793637 -115.31366) (xy 183.786676 -115.360958) (xy 190.218314 -115.360958)
			(xy 190.218811 -115.333589) (xy 190.226621 -115.279411) (xy 190.242102 -115.226908) (xy 190.264937 -115.177161)
			(xy 190.294656 -115.131193) (xy 190.312294 -115.11026) (xy 190.312548 -115.110006) (xy 190.318144 -115.102926)
			(xy 190.324384 -115.086004) (xy 190.32474 -115.076986) (xy 190.32474 -115.00993) (xy 190.324382 -115.000913)
			(xy 190.318136 -114.983995) (xy 190.312548 -114.97691) (xy 190.312294 -114.97691) (xy 190.312294 -114.976656)
			(xy 190.294667 -114.955714) (xy 190.264953 -114.909744) (xy 190.242115 -114.859999) (xy 190.226621 -114.807501)
			(xy 190.21879 -114.753326) (xy 190.218314 -114.725958) (xy 190.218739 -114.698705) (xy 190.226502 -114.644754)
			(xy 190.241863 -114.592456) (xy 190.264511 -114.542878) (xy 190.293984 -114.497026) (xy 190.329681 -114.455836)
			(xy 190.370878 -114.420145) (xy 190.416734 -114.39068) (xy 190.466316 -114.368041) (xy 190.518616 -114.352688)
			(xy 190.572569 -114.344934) (xy 190.599822 -114.34445) (xy 190.627193 -114.344891) (xy 190.681374 -114.352713)
			(xy 190.733878 -114.368207) (xy 190.783624 -114.391055) (xy 190.82959 -114.420786) (xy 190.85052 -114.43843)
			(xy 190.850774 -114.438684) (xy 190.857865 -114.444264) (xy 190.874778 -114.450515) (xy 190.883794 -114.450876)
			(xy 190.95085 -114.450876) (xy 190.959865 -114.4505) (xy 190.976782 -114.444266) (xy 190.98387 -114.438684)
			(xy 190.98387 -114.43843) (xy 190.984124 -114.43843) (xy 191.005078 -114.420818) (xy 191.051044 -114.391101)
			(xy 191.100786 -114.368259) (xy 191.153282 -114.352762) (xy 191.207454 -114.344927) (xy 191.234822 -114.34445)
			(xy 191.262072 -114.344957) (xy 191.316017 -114.352716) (xy 191.368308 -114.368071) (xy 191.417883 -114.390712)
			(xy 191.463731 -114.420177) (xy 191.474537 -114.42954) (xy 201.337924 -114.42954) (xy 201.341995 -114.373918)
			(xy 201.354121 -114.319481) (xy 201.374044 -114.26739) (xy 201.40134 -114.218755) (xy 201.435426 -114.174612)
			(xy 201.475575 -114.135903) (xy 201.520933 -114.103452) (xy 201.570533 -114.077951) (xy 201.623317 -114.059944)
			(xy 201.67816 -114.049814) (xy 201.733894 -114.047777) (xy 201.789331 -114.053877) (xy 201.843288 -114.067983)
			(xy 201.894617 -114.089795) (xy 201.942223 -114.118849) (xy 201.985091 -114.154524) (xy 202.022308 -114.196061)
			(xy 202.053081 -114.242574) (xy 202.076753 -114.293071) (xy 202.081436 -114.308636) (xy 209.079082 -114.308636)
			(xy 209.083153 -114.253014) (xy 209.095279 -114.198577) (xy 209.115202 -114.146486) (xy 209.142498 -114.097851)
			(xy 209.176584 -114.053708) (xy 209.216733 -114.014999) (xy 209.262091 -113.982548) (xy 209.311691 -113.957047)
			(xy 209.364475 -113.93904) (xy 209.419318 -113.92891) (xy 209.475052 -113.926873) (xy 209.530489 -113.932973)
			(xy 209.584446 -113.947079) (xy 209.635775 -113.968891) (xy 209.683381 -113.997945) (xy 209.726249 -114.03362)
			(xy 209.763466 -114.075157) (xy 209.794239 -114.12167) (xy 209.817911 -114.172167) (xy 209.833979 -114.225574)
			(xy 209.842099 -114.28075) (xy 209.842608 -114.308636) (xy 209.842099 -114.336522) (xy 209.833979 -114.391698)
			(xy 209.817911 -114.445105) (xy 209.794239 -114.495602) (xy 209.763466 -114.542115) (xy 209.726249 -114.583652)
			(xy 209.683381 -114.619327) (xy 209.635775 -114.648381) (xy 209.584446 -114.670193) (xy 209.530489 -114.684299)
			(xy 209.475052 -114.690399) (xy 209.419318 -114.688362) (xy 209.364475 -114.678232) (xy 209.311691 -114.660225)
			(xy 209.262091 -114.634724) (xy 209.216733 -114.602273) (xy 209.176584 -114.563564) (xy 209.142498 -114.519421)
			(xy 209.115202 -114.470786) (xy 209.095279 -114.418695) (xy 209.083153 -114.364258) (xy 209.079082 -114.308636)
			(xy 202.081436 -114.308636) (xy 202.092821 -114.346478) (xy 202.100941 -114.401654) (xy 202.10145 -114.42954)
			(xy 202.100941 -114.457426) (xy 202.092821 -114.512602) (xy 202.076753 -114.566009) (xy 202.053081 -114.616506)
			(xy 202.022308 -114.663019) (xy 201.985091 -114.704556) (xy 201.942223 -114.740231) (xy 201.894617 -114.769285)
			(xy 201.843288 -114.791097) (xy 201.789331 -114.805203) (xy 201.733894 -114.811303) (xy 201.67816 -114.809266)
			(xy 201.623317 -114.799136) (xy 201.570533 -114.781129) (xy 201.520933 -114.755628) (xy 201.475575 -114.723177)
			(xy 201.435426 -114.684468) (xy 201.40134 -114.640325) (xy 201.374044 -114.59169) (xy 201.354121 -114.539599)
			(xy 201.341995 -114.485162) (xy 201.337924 -114.42954) (xy 191.474537 -114.42954) (xy 191.50492 -114.455866)
			(xy 191.540611 -114.497053) (xy 191.570078 -114.542899) (xy 191.592722 -114.592473) (xy 191.60808 -114.644764)
			(xy 191.615841 -114.698708) (xy 191.61633 -114.725958) (xy 191.615856 -114.753328) (xy 191.608043 -114.807508)
			(xy 191.592557 -114.860011) (xy 191.569716 -114.909758) (xy 191.539992 -114.955725) (xy 191.52235 -114.976656)
			(xy 191.522096 -114.97691) (xy 191.516499 -114.983989) (xy 191.510259 -115.000912) (xy 191.509904 -115.00993)
			(xy 191.509904 -115.076986) (xy 191.510267 -115.086002) (xy 191.51651 -115.102919) (xy 191.522096 -115.110006)
			(xy 191.52235 -115.110006) (xy 191.52235 -115.11026) (xy 191.539976 -115.131203) (xy 191.549425 -115.14582)
			(xy 205.473044 -115.14582) (xy 205.477115 -115.090198) (xy 205.489241 -115.035761) (xy 205.509164 -114.98367)
			(xy 205.53646 -114.935035) (xy 205.570546 -114.890892) (xy 205.610695 -114.852183) (xy 205.656053 -114.819732)
			(xy 205.705653 -114.794231) (xy 205.758437 -114.776224) (xy 205.81328 -114.766094) (xy 205.869014 -114.764057)
			(xy 205.924451 -114.770157) (xy 205.978408 -114.784263) (xy 206.029737 -114.806075) (xy 206.077343 -114.835129)
			(xy 206.120211 -114.870804) (xy 206.157428 -114.912341) (xy 206.188201 -114.958854) (xy 206.211873 -115.009351)
			(xy 206.227941 -115.062758) (xy 206.236061 -115.117934) (xy 206.23657 -115.14582) (xy 206.236061 -115.173706)
			(xy 206.227941 -115.228882) (xy 206.211873 -115.282289) (xy 206.188201 -115.332786) (xy 206.157428 -115.379299)
			(xy 206.120211 -115.420836) (xy 206.077343 -115.456511) (xy 206.029737 -115.485565) (xy 205.978408 -115.507377)
			(xy 205.924451 -115.521483) (xy 205.869014 -115.527583) (xy 205.81328 -115.525546) (xy 205.758437 -115.515416)
			(xy 205.705653 -115.497409) (xy 205.656053 -115.471908) (xy 205.610695 -115.439457) (xy 205.570546 -115.400748)
			(xy 205.53646 -115.356605) (xy 205.509164 -115.30797) (xy 205.489241 -115.255879) (xy 205.477115 -115.201442)
			(xy 205.473044 -115.14582) (xy 191.549425 -115.14582) (xy 191.569692 -115.177172) (xy 191.592531 -115.226917)
			(xy 191.608025 -115.279415) (xy 191.615855 -115.333589) (xy 191.61633 -115.360958) (xy 191.615806 -115.388209)
			(xy 191.608055 -115.442156) (xy 191.592705 -115.494452) (xy 191.570069 -115.54403) (xy 191.540608 -115.589883)
			(xy 191.50492 -115.631075) (xy 191.463734 -115.666769) (xy 191.417887 -115.696239) (xy 191.368312 -115.718883)
			(xy 191.316019 -115.734241) (xy 191.262073 -115.742001) (xy 191.234822 -115.742466) (xy 191.207452 -115.741995)
			(xy 191.153273 -115.73418) (xy 191.100769 -115.718692) (xy 191.051022 -115.695851) (xy 191.005056 -115.666127)
			(xy 190.984124 -115.648486) (xy 190.98387 -115.648232) (xy 190.976773 -115.642661) (xy 190.959864 -115.636407)
			(xy 190.95085 -115.63604) (xy 190.883794 -115.63604) (xy 190.874776 -115.636385) (xy 190.857858 -115.64264)
			(xy 190.850774 -115.648232) (xy 190.850774 -115.648486) (xy 190.85052 -115.648486) (xy 190.829589 -115.666127)
			(xy 190.783616 -115.695839) (xy 190.733869 -115.718675) (xy 190.681367 -115.734165) (xy 190.627191 -115.741993)
			(xy 190.599822 -115.742466) (xy 190.572568 -115.742024) (xy 190.518614 -115.734269) (xy 190.466313 -115.718914)
			(xy 190.41673 -115.696271) (xy 190.370875 -115.666801) (xy 190.329681 -115.631105) (xy 190.293987 -115.589909)
			(xy 190.26452 -115.544052) (xy 190.241879 -115.494468) (xy 190.226527 -115.442167) (xy 190.218774 -115.388212)
			(xy 190.218314 -115.360958) (xy 183.786676 -115.360958) (xy 183.785517 -115.368836) (xy 183.769449 -115.422243)
			(xy 183.745777 -115.47274) (xy 183.715004 -115.519253) (xy 183.677787 -115.56079) (xy 183.634919 -115.596465)
			(xy 183.587313 -115.625519) (xy 183.535984 -115.647331) (xy 183.482027 -115.661437) (xy 183.42659 -115.667537)
			(xy 183.370856 -115.6655) (xy 183.316013 -115.65537) (xy 183.263229 -115.637363) (xy 183.213629 -115.611862)
			(xy 183.168271 -115.579411) (xy 183.128122 -115.540702) (xy 183.094036 -115.496559) (xy 183.06674 -115.447924)
			(xy 183.046817 -115.395833) (xy 183.034691 -115.341396) (xy 183.03062 -115.285774) (xy 177.622454 -115.285774)
			(xy 176.999138 -115.90909) (xy 180.121304 -115.90909) (xy 180.125375 -115.853468) (xy 180.137501 -115.799031)
			(xy 180.157424 -115.74694) (xy 180.18472 -115.698305) (xy 180.218806 -115.654162) (xy 180.258955 -115.615453)
			(xy 180.304313 -115.583002) (xy 180.353913 -115.557501) (xy 180.406697 -115.539494) (xy 180.46154 -115.529364)
			(xy 180.517274 -115.527327) (xy 180.572711 -115.533427) (xy 180.626668 -115.547533) (xy 180.677997 -115.569345)
			(xy 180.725603 -115.598399) (xy 180.768471 -115.634074) (xy 180.805688 -115.675611) (xy 180.836461 -115.722124)
			(xy 180.860133 -115.772621) (xy 180.876201 -115.826028) (xy 180.882149 -115.866447) (xy 206.842418 -115.866447)
			(xy 206.842418 -115.811953) (xy 206.850173 -115.758015) (xy 206.865524 -115.705729) (xy 206.88816 -115.65616)
			(xy 206.917619 -115.610316) (xy 206.953303 -115.569131) (xy 206.994484 -115.533443) (xy 207.040324 -115.503979)
			(xy 207.089891 -115.481338) (xy 207.142176 -115.465981) (xy 207.196114 -115.458221) (xy 207.22336 -115.457732)
			(xy 207.252276 -115.458267) (xy 207.309447 -115.466991) (xy 207.364646 -115.484245) (xy 207.416609 -115.509633)
			(xy 207.464143 -115.542574) (xy 207.50616 -115.582313) (xy 207.52435 -115.604798) (xy 207.531989 -115.613572)
			(xy 207.552865 -115.623774) (xy 207.564482 -115.624356) (xy 207.644238 -115.624356) (xy 207.655873 -115.62384)
			(xy 207.676783 -115.613636) (xy 207.68437 -115.604798) (xy 207.702577 -115.582328) (xy 207.744594 -115.542592)
			(xy 207.792125 -115.509652) (xy 207.844083 -115.484261) (xy 207.899278 -115.467002) (xy 207.956445 -115.458269)
			(xy 207.98536 -115.457732) (xy 208.012618 -115.458112) (xy 208.066579 -115.465865) (xy 208.118887 -115.48122)
			(xy 208.168477 -115.503862) (xy 208.21434 -115.533332) (xy 208.255542 -115.56903) (xy 208.263867 -115.578636)
			(xy 209.079082 -115.578636) (xy 209.083153 -115.523014) (xy 209.095279 -115.468577) (xy 209.115202 -115.416486)
			(xy 209.142498 -115.367851) (xy 209.176584 -115.323708) (xy 209.216733 -115.284999) (xy 209.262091 -115.252548)
			(xy 209.311691 -115.227047) (xy 209.364475 -115.20904) (xy 209.419318 -115.19891) (xy 209.475052 -115.196873)
			(xy 209.530489 -115.202973) (xy 209.584446 -115.217079) (xy 209.635775 -115.238891) (xy 209.683381 -115.267945)
			(xy 209.726249 -115.30362) (xy 209.763466 -115.345157) (xy 209.794239 -115.39167) (xy 209.817911 -115.442167)
			(xy 209.833979 -115.495574) (xy 209.842099 -115.55075) (xy 209.842608 -115.578636) (xy 209.842099 -115.606522)
			(xy 209.833979 -115.661698) (xy 209.817911 -115.715105) (xy 209.794239 -115.765602) (xy 209.763466 -115.812115)
			(xy 209.726249 -115.853652) (xy 209.683381 -115.889327) (xy 209.635775 -115.918381) (xy 209.584446 -115.940193)
			(xy 209.530489 -115.954299) (xy 209.475052 -115.960399) (xy 209.419318 -115.958362) (xy 209.364475 -115.948232)
			(xy 209.311691 -115.930225) (xy 209.262091 -115.904724) (xy 209.216733 -115.872273) (xy 209.176584 -115.833564)
			(xy 209.142498 -115.789421) (xy 209.115202 -115.740786) (xy 209.095279 -115.688695) (xy 209.083153 -115.634258)
			(xy 209.079082 -115.578636) (xy 208.263867 -115.578636) (xy 208.291244 -115.610228) (xy 208.320719 -115.656088)
			(xy 208.343366 -115.705676) (xy 208.358726 -115.757982) (xy 208.366485 -115.811942) (xy 208.366485 -115.866458)
			(xy 208.358726 -115.920418) (xy 208.343366 -115.972724) (xy 208.320719 -116.022312) (xy 208.291244 -116.068172)
			(xy 208.255542 -116.10937) (xy 208.21434 -116.145068) (xy 208.168477 -116.174538) (xy 208.118887 -116.19718)
			(xy 208.066579 -116.212535) (xy 208.012618 -116.220288) (xy 207.98536 -116.220748) (xy 207.956444 -116.220207)
			(xy 207.899273 -116.211485) (xy 207.844073 -116.194233) (xy 207.792111 -116.168846) (xy 207.744577 -116.135905)
			(xy 207.70256 -116.096167) (xy 207.68437 -116.073682) (xy 207.676769 -116.064868) (xy 207.655864 -116.054689)
			(xy 207.644238 -116.054124) (xy 207.564482 -116.054124) (xy 207.552849 -116.054659) (xy 207.531939 -116.06485)
			(xy 207.52435 -116.073682) (xy 207.506126 -116.096138) (xy 207.464114 -116.135876) (xy 207.416586 -116.168818)
			(xy 207.364631 -116.194212) (xy 207.309439 -116.211474) (xy 207.252274 -116.220209) (xy 207.22336 -116.220748)
			(xy 207.196114 -116.220179) (xy 207.142176 -116.212419) (xy 207.089891 -116.197062) (xy 207.040324 -116.174421)
			(xy 206.994484 -116.144957) (xy 206.953303 -116.109269) (xy 206.917619 -116.068084) (xy 206.88816 -116.02224)
			(xy 206.865524 -115.972671) (xy 206.850173 -115.920385) (xy 206.842418 -115.866447) (xy 180.882149 -115.866447)
			(xy 180.884321 -115.881204) (xy 180.88483 -115.90909) (xy 180.884321 -115.936976) (xy 180.876201 -115.992152)
			(xy 180.860133 -116.045559) (xy 180.836461 -116.096056) (xy 180.805688 -116.142569) (xy 180.768471 -116.184106)
			(xy 180.725603 -116.219781) (xy 180.677997 -116.248835) (xy 180.626668 -116.270647) (xy 180.572711 -116.284753)
			(xy 180.517274 -116.290853) (xy 180.46154 -116.288816) (xy 180.406697 -116.278686) (xy 180.353913 -116.260679)
			(xy 180.304313 -116.235178) (xy 180.258955 -116.202727) (xy 180.218806 -116.164018) (xy 180.18472 -116.119875)
			(xy 180.157424 -116.07124) (xy 180.137501 -116.019149) (xy 180.125375 -115.964712) (xy 180.121304 -115.90909)
			(xy 176.999138 -115.90909) (xy 176.460658 -116.44757) (xy 182.256936 -116.44757) (xy 182.261007 -116.391948)
			(xy 182.273133 -116.337511) (xy 182.293056 -116.28542) (xy 182.320352 -116.236785) (xy 182.354438 -116.192642)
			(xy 182.394587 -116.153933) (xy 182.439945 -116.121482) (xy 182.489545 -116.095981) (xy 182.542329 -116.077974)
			(xy 182.597172 -116.067844) (xy 182.652906 -116.065807) (xy 182.708343 -116.071907) (xy 182.7623 -116.086013)
			(xy 182.813629 -116.107825) (xy 182.861235 -116.136879) (xy 182.904103 -116.172554) (xy 182.94132 -116.214091)
			(xy 182.972093 -116.260604) (xy 182.995765 -116.311101) (xy 183.011833 -116.364508) (xy 183.019953 -116.419684)
			(xy 183.020462 -116.44757) (xy 183.019953 -116.475456) (xy 183.019683 -116.477288) (xy 187.404246 -116.477288)
			(xy 187.408317 -116.421666) (xy 187.420443 -116.367229) (xy 187.440366 -116.315138) (xy 187.467662 -116.266503)
			(xy 187.501748 -116.22236) (xy 187.541897 -116.183651) (xy 187.587255 -116.1512) (xy 187.636855 -116.125699)
			(xy 187.689639 -116.107692) (xy 187.744482 -116.097562) (xy 187.800216 -116.095525) (xy 187.855653 -116.101625)
			(xy 187.90961 -116.115731) (xy 187.960939 -116.137543) (xy 188.008545 -116.166597) (xy 188.051413 -116.202272)
			(xy 188.08863 -116.243809) (xy 188.119403 -116.290322) (xy 188.143075 -116.340819) (xy 188.159143 -116.394226)
			(xy 188.167263 -116.449402) (xy 188.167772 -116.477288) (xy 188.167263 -116.505174) (xy 188.159143 -116.56035)
			(xy 188.143075 -116.613757) (xy 188.119403 -116.664254) (xy 188.08863 -116.710767) (xy 188.051413 -116.752304)
			(xy 188.008545 -116.787979) (xy 187.960939 -116.817033) (xy 187.90961 -116.838845) (xy 187.855653 -116.852951)
			(xy 187.800216 -116.859051) (xy 187.744482 -116.857014) (xy 187.689639 -116.846884) (xy 187.636855 -116.828877)
			(xy 187.587255 -116.803376) (xy 187.541897 -116.770925) (xy 187.501748 -116.732216) (xy 187.467662 -116.688073)
			(xy 187.440366 -116.639438) (xy 187.420443 -116.587347) (xy 187.408317 -116.53291) (xy 187.404246 -116.477288)
			(xy 183.019683 -116.477288) (xy 183.011833 -116.530632) (xy 182.995765 -116.584039) (xy 182.972093 -116.634536)
			(xy 182.94132 -116.681049) (xy 182.904103 -116.722586) (xy 182.861235 -116.758261) (xy 182.813629 -116.787315)
			(xy 182.7623 -116.809127) (xy 182.708343 -116.823233) (xy 182.652906 -116.829333) (xy 182.597172 -116.827296)
			(xy 182.542329 -116.817166) (xy 182.489545 -116.799159) (xy 182.439945 -116.773658) (xy 182.394587 -116.741207)
			(xy 182.354438 -116.702498) (xy 182.320352 -116.658355) (xy 182.293056 -116.60972) (xy 182.273133 -116.557629)
			(xy 182.261007 -116.503192) (xy 182.256936 -116.44757) (xy 176.460658 -116.44757) (xy 175.184562 -117.723666)
			(xy 185.789568 -117.723666) (xy 185.793639 -117.668044) (xy 185.805765 -117.613607) (xy 185.825688 -117.561516)
			(xy 185.852984 -117.512881) (xy 185.88707 -117.468738) (xy 185.927219 -117.430029) (xy 185.972577 -117.397578)
			(xy 186.022177 -117.372077) (xy 186.074961 -117.35407) (xy 186.129804 -117.34394) (xy 186.185538 -117.341903)
			(xy 186.240975 -117.348003) (xy 186.294932 -117.362109) (xy 186.346261 -117.383921) (xy 186.393867 -117.412975)
			(xy 186.436735 -117.44865) (xy 186.473952 -117.490187) (xy 186.504725 -117.5367) (xy 186.528397 -117.587197)
			(xy 186.544465 -117.640604) (xy 186.552585 -117.69578) (xy 186.553094 -117.723666) (xy 186.552585 -117.751552)
			(xy 186.55153 -117.758718) (xy 190.574676 -117.758718) (xy 190.574676 -116.895118) (xy 190.575166 -116.865134)
			(xy 190.582994 -116.805678) (xy 190.598515 -116.747753) (xy 190.621464 -116.692349) (xy 190.651448 -116.640415)
			(xy 190.687954 -116.592839) (xy 190.730359 -116.550434) (xy 190.777935 -116.513928) (xy 190.829869 -116.483944)
			(xy 190.885273 -116.460995) (xy 190.943198 -116.445474) (xy 191.002654 -116.437646) (xy 191.062622 -116.437646)
			(xy 191.122078 -116.445474) (xy 191.180003 -116.460995) (xy 191.235407 -116.483944) (xy 191.287341 -116.513928)
			(xy 191.334917 -116.550434) (xy 191.377322 -116.592839) (xy 191.413828 -116.640415) (xy 191.443812 -116.692349)
			(xy 191.466761 -116.747753) (xy 191.482282 -116.805678) (xy 191.49011 -116.865134) (xy 191.4906 -116.895118)
			(xy 191.4906 -117.758718) (xy 191.49011 -117.788702) (xy 191.482282 -117.848158) (xy 191.466761 -117.906083)
			(xy 191.443812 -117.961487) (xy 191.413828 -118.013421) (xy 191.377322 -118.060997) (xy 191.334917 -118.103402)
			(xy 191.287341 -118.139908) (xy 191.235407 -118.169892) (xy 191.180003 -118.192841) (xy 191.122078 -118.208362)
			(xy 191.062622 -118.21619) (xy 191.002654 -118.21619) (xy 190.943198 -118.208362) (xy 190.885273 -118.192841)
			(xy 190.829869 -118.169892) (xy 190.777935 -118.139908) (xy 190.730359 -118.103402) (xy 190.687954 -118.060997)
			(xy 190.651448 -118.013421) (xy 190.621464 -117.961487) (xy 190.598515 -117.906083) (xy 190.582994 -117.848158)
			(xy 190.575166 -117.788702) (xy 190.574676 -117.758718) (xy 186.55153 -117.758718) (xy 186.544465 -117.806728)
			(xy 186.528397 -117.860135) (xy 186.504725 -117.910632) (xy 186.473952 -117.957145) (xy 186.436735 -117.998682)
			(xy 186.393867 -118.034357) (xy 186.346261 -118.063411) (xy 186.294932 -118.085223) (xy 186.240975 -118.099329)
			(xy 186.185538 -118.105429) (xy 186.129804 -118.103392) (xy 186.074961 -118.093262) (xy 186.022177 -118.075255)
			(xy 185.972577 -118.049754) (xy 185.927219 -118.017303) (xy 185.88707 -117.978594) (xy 185.852984 -117.934451)
			(xy 185.825688 -117.885816) (xy 185.805765 -117.833725) (xy 185.793639 -117.779288) (xy 185.789568 -117.723666)
			(xy 175.184562 -117.723666) (xy 173.57471 -119.333518) (xy 173.567871 -119.340919) (xy 173.56015 -119.359517)
			(xy 173.559724 -119.369586) (xy 173.559724 -133.953504) (xy 173.560141 -133.963574) (xy 173.567867 -133.982172)
			(xy 173.57471 -133.989572) (xy 173.791118 -134.205726) (xy 173.814028 -134.229281) (xy 173.854994 -134.280658)
			(xy 173.889951 -134.336299) (xy 173.918458 -134.395504) (xy 173.940157 -134.457528) (xy 173.954774 -134.521593)
			(xy 173.962127 -134.586891) (xy 173.962568 -134.619746) (xy 173.962568 -134.62) (xy 173.96199 -134.655396)
			(xy 173.953457 -134.725671) (xy 173.936517 -134.794406) (xy 173.911415 -134.860598) (xy 173.878518 -134.923281)
			(xy 173.838305 -134.981543) (xy 173.791364 -135.034532) (xy 173.738377 -135.081478) (xy 173.680119 -135.121695)
			(xy 173.617438 -135.154597) (xy 173.551248 -135.179704) (xy 173.482515 -135.196649) (xy 173.41224 -135.205187)
			(xy 173.376844 -135.205724) (xy 173.37659 -135.205724) (xy 173.343737 -135.205246) (xy 173.278445 -135.197882)
			(xy 173.214387 -135.183261) (xy 173.152366 -135.161564) (xy 173.093163 -135.133064) (xy 173.03752 -135.09812)
			(xy 172.986135 -135.05717) (xy 172.96257 -135.034274) (xy 172.86351 -134.935214) (xy 172.833538 -134.929372)
			(xy 172.819314 -134.935214) (xy 172.810283 -134.939529) (xy 172.7962 -134.953725) (xy 172.788567 -134.972207)
			(xy 172.788072 -134.982204) (xy 172.788072 -136.334754) (xy 172.788502 -136.344823) (xy 172.796217 -136.363422)
			(xy 172.803058 -136.370822) (xy 173.342554 -136.910318) (xy 173.346942 -136.914441) (xy 173.35721 -136.920722)
			(xy 173.362874 -136.922764) (xy 173.363382 -136.922764) (xy 173.388932 -136.931196) (xy 173.437535 -136.954269)
			(xy 173.482416 -136.983942) (xy 173.522682 -137.019625) (xy 173.557537 -137.060611) (xy 173.586289 -137.106087)
			(xy 173.608367 -137.155151) (xy 173.623333 -137.20683) (xy 173.630891 -137.260099) (xy 173.631352 -137.287)
			(xy 173.630822 -137.314249) (xy 173.623067 -137.368193) (xy 173.607714 -137.420484) (xy 173.585076 -137.470059)
			(xy 173.555614 -137.515907) (xy 173.519927 -137.557096) (xy 173.478742 -137.592788) (xy 173.432897 -137.622255)
			(xy 173.383326 -137.644899) (xy 173.331036 -137.660258) (xy 173.277093 -137.668019) (xy 173.249844 -137.668508)
			(xy 173.222933 -137.668052) (xy 173.169649 -137.660469) (xy 173.117958 -137.645473) (xy 173.068888 -137.623364)
			(xy 173.02341 -137.59458) (xy 172.982428 -137.559691) (xy 172.946754 -137.51939) (xy 172.917097 -137.474477)
			(xy 172.894044 -137.425843) (xy 172.885608 -137.400284) (xy 172.885608 -137.40003) (xy 172.883625 -137.394338)
			(xy 172.877331 -137.384063) (xy 172.873162 -137.37971) (xy 172.441616 -136.948164) (xy 172.411644 -136.942068)
			(xy 172.39742 -136.948164) (xy 172.388313 -136.952418) (xy 172.374075 -136.966577) (xy 172.366357 -136.985115)
			(xy 172.365924 -136.995154) (xy 172.365924 -138.95705) (xy 172.614336 -138.95705) (xy 172.614822 -138.929799)
			(xy 172.622578 -138.875851) (xy 172.637933 -138.823556) (xy 172.660575 -138.773979) (xy 172.690041 -138.728129)
			(xy 172.725732 -138.686938) (xy 172.766923 -138.651247) (xy 172.812773 -138.621781) (xy 172.86235 -138.599139)
			(xy 172.914645 -138.583784) (xy 172.968593 -138.576028) (xy 173.023095 -138.576028) (xy 173.077043 -138.583784)
			(xy 173.129338 -138.599139) (xy 173.178915 -138.621781) (xy 173.224765 -138.651247) (xy 173.265956 -138.686938)
			(xy 173.301647 -138.728129) (xy 173.331113 -138.773979) (xy 173.353755 -138.823556) (xy 173.365879 -138.864848)
			(xy 178.040284 -138.864848) (xy 178.040779 -138.837353) (xy 178.048676 -138.782933) (xy 178.064298 -138.730209)
			(xy 178.087322 -138.680271) (xy 178.117272 -138.634153) (xy 178.153529 -138.592808) (xy 178.195342 -138.557093)
			(xy 178.218338 -138.542014) (xy 178.226974 -138.535156) (xy 178.373532 -138.388598) (xy 178.379591 -138.382033)
			(xy 178.387066 -138.365817) (xy 178.388523 -138.348021) (xy 178.386486 -138.339322) (xy 178.359562 -138.241024)
			(xy 178.340258 -138.22172) (xy 178.32705 -138.218418) (xy 178.300076 -138.210941) (xy 178.248469 -138.189269)
			(xy 178.200583 -138.16029) (xy 178.157444 -138.124624) (xy 178.11998 -138.083039) (xy 178.088994 -138.036426)
			(xy 178.065152 -137.985785) (xy 178.048964 -137.932205) (xy 178.040779 -137.876834) (xy 178.040284 -137.848848)
			(xy 178.0408 -137.821597) (xy 178.04855 -137.767648) (xy 178.0639 -137.715352) (xy 178.086536 -137.665772)
			(xy 178.115998 -137.619919) (xy 178.151687 -137.578726) (xy 178.192874 -137.543032) (xy 178.238723 -137.513563)
			(xy 178.288299 -137.490919) (xy 178.340593 -137.475562) (xy 178.394541 -137.467804) (xy 178.421792 -137.46734)
			(xy 178.449782 -137.46779) (xy 178.505163 -137.47597) (xy 178.558753 -137.492155) (xy 178.609402 -137.515998)
			(xy 178.656024 -137.546987) (xy 178.697616 -137.584457) (xy 178.733285 -137.627602) (xy 178.762267 -137.675497)
			(xy 178.783938 -137.727114) (xy 178.791362 -137.754106) (xy 178.794664 -137.767314) (xy 178.813968 -137.786618)
			(xy 178.912266 -137.813542) (xy 178.920962 -137.815584) (xy 178.938755 -137.814114) (xy 178.954967 -137.806636)
			(xy 178.961542 -137.800588) (xy 179.03063 -137.7315) (xy 179.037467 -137.724098) (xy 179.045188 -137.7055)
			(xy 179.045616 -137.695432) (xy 179.045616 -118.52656) (xy 179.043076 -118.515384) (xy 179.040282 -118.51005)
			(xy 179.039774 -118.509034) (xy 179.026065 -118.481553) (xy 179.006605 -118.423309) (xy 178.996725 -118.3627)
			(xy 178.996086 -118.331996) (xy 178.996572 -118.304745) (xy 179.004328 -118.250797) (xy 179.019683 -118.198502)
			(xy 179.042325 -118.148925) (xy 179.071791 -118.103075) (xy 179.107482 -118.061884) (xy 179.148673 -118.026193)
			(xy 179.194523 -117.996727) (xy 179.2441 -117.974085) (xy 179.296395 -117.95873) (xy 179.350343 -117.950974)
			(xy 179.404845 -117.950974) (xy 179.458793 -117.95873) (xy 179.511088 -117.974085) (xy 179.560665 -117.996727)
			(xy 179.606515 -118.026193) (xy 179.647706 -118.061884) (xy 179.683397 -118.103075) (xy 179.712863 -118.148925)
			(xy 179.735505 -118.198502) (xy 179.75086 -118.250797) (xy 179.758616 -118.304745) (xy 179.759102 -118.331996)
			(xy 179.758484 -118.362798) (xy 179.748562 -118.423599) (xy 179.728992 -118.482013) (xy 179.71516 -118.509542)
			(xy 179.714906 -118.51005) (xy 179.712418 -118.515366) (xy 179.709722 -118.526788) (xy 179.709572 -118.532656)
			(xy 179.709572 -119.567198) (xy 182.69966 -119.567198) (xy 182.69966 -118.703598) (xy 182.70015 -118.67363)
			(xy 182.707973 -118.614208) (xy 182.723486 -118.556315) (xy 182.746422 -118.500942) (xy 182.776389 -118.449036)
			(xy 182.812876 -118.401486) (xy 182.855256 -118.359106) (xy 182.902806 -118.322619) (xy 182.954712 -118.292652)
			(xy 183.010085 -118.269716) (xy 183.067978 -118.254203) (xy 183.1274 -118.24638) (xy 183.187336 -118.24638)
			(xy 183.246758 -118.254203) (xy 183.304651 -118.269716) (xy 183.360024 -118.292652) (xy 183.41193 -118.322619)
			(xy 183.45948 -118.359106) (xy 183.50186 -118.401486) (xy 183.538347 -118.449036) (xy 183.568314 -118.500942)
			(xy 183.59125 -118.556315) (xy 183.606763 -118.614208) (xy 183.614586 -118.67363) (xy 183.615076 -118.703598)
			(xy 183.615076 -118.711218) (xy 185.909202 -118.711218) (xy 185.913273 -118.655596) (xy 185.925399 -118.601159)
			(xy 185.945322 -118.549068) (xy 185.972618 -118.500433) (xy 186.006704 -118.45629) (xy 186.046853 -118.417581)
			(xy 186.092211 -118.38513) (xy 186.141811 -118.359629) (xy 186.194595 -118.341622) (xy 186.249438 -118.331492)
			(xy 186.305172 -118.329455) (xy 186.360609 -118.335555) (xy 186.414566 -118.349661) (xy 186.465895 -118.371473)
			(xy 186.513501 -118.400527) (xy 186.556369 -118.436202) (xy 186.593586 -118.477739) (xy 186.624359 -118.524252)
			(xy 186.648031 -118.574749) (xy 186.664099 -118.628156) (xy 186.672219 -118.683332) (xy 186.672728 -118.711218)
			(xy 186.672219 -118.739104) (xy 186.664099 -118.79428) (xy 186.648031 -118.847687) (xy 186.624359 -118.898184)
			(xy 186.593586 -118.944697) (xy 186.556369 -118.986234) (xy 186.513501 -119.021909) (xy 186.465895 -119.050963)
			(xy 186.414566 -119.072775) (xy 186.360609 -119.086881) (xy 186.305172 -119.092981) (xy 186.249438 -119.090944)
			(xy 186.194595 -119.080814) (xy 186.141811 -119.062807) (xy 186.092211 -119.037306) (xy 186.046853 -119.004855)
			(xy 186.006704 -118.966146) (xy 185.972618 -118.922003) (xy 185.945322 -118.873368) (xy 185.925399 -118.821277)
			(xy 185.913273 -118.76684) (xy 185.909202 -118.711218) (xy 183.615076 -118.711218) (xy 183.615076 -119.567198)
			(xy 183.614586 -119.597166) (xy 183.606763 -119.656588) (xy 183.59125 -119.714481) (xy 183.568314 -119.769854)
			(xy 183.538347 -119.82176) (xy 183.50186 -119.86931) (xy 183.45948 -119.91169) (xy 183.41193 -119.948177)
			(xy 183.360024 -119.978144) (xy 183.304651 -120.00108) (xy 183.246758 -120.016593) (xy 183.187336 -120.024416)
			(xy 183.1274 -120.024416) (xy 183.067978 -120.016593) (xy 183.010085 -120.00108) (xy 182.954712 -119.978144)
			(xy 182.902806 -119.948177) (xy 182.855256 -119.91169) (xy 182.812876 -119.86931) (xy 182.776389 -119.82176)
			(xy 182.746422 -119.769854) (xy 182.723486 -119.714481) (xy 182.707973 -119.656588) (xy 182.70015 -119.597166)
			(xy 182.69966 -119.567198) (xy 179.709572 -119.567198) (xy 179.709572 -121.367296) (xy 180.84546 -121.367296)
			(xy 180.84546 -120.503696) (xy 180.84595 -120.473728) (xy 180.853773 -120.414306) (xy 180.869286 -120.356413)
			(xy 180.892222 -120.30104) (xy 180.922189 -120.249134) (xy 180.958676 -120.201584) (xy 181.001056 -120.159204)
			(xy 181.048606 -120.122717) (xy 181.100512 -120.09275) (xy 181.155885 -120.069814) (xy 181.213778 -120.054301)
			(xy 181.2732 -120.046478) (xy 181.333136 -120.046478) (xy 181.392558 -120.054301) (xy 181.450451 -120.069814)
			(xy 181.505824 -120.09275) (xy 181.55773 -120.122717) (xy 181.60528 -120.159204) (xy 181.64766 -120.201584)
			(xy 181.684147 -120.249134) (xy 181.714114 -120.30104) (xy 181.73705 -120.356413) (xy 181.752563 -120.414306)
			(xy 181.760386 -120.473728) (xy 181.760876 -120.503696) (xy 181.760876 -121.367296) (xy 181.760386 -121.397264)
			(xy 181.752563 -121.456686) (xy 181.73705 -121.514579) (xy 181.714114 -121.569952) (xy 181.684147 -121.621858)
			(xy 181.64766 -121.669408) (xy 181.60528 -121.711788) (xy 181.55773 -121.748275) (xy 181.505824 -121.778242)
			(xy 181.450451 -121.801178) (xy 181.392558 -121.816691) (xy 181.333136 -121.824514) (xy 181.2732 -121.824514)
			(xy 181.213778 -121.816691) (xy 181.155885 -121.801178) (xy 181.100512 -121.778242) (xy 181.048606 -121.748275)
			(xy 181.001056 -121.711788) (xy 180.958676 -121.669408) (xy 180.922189 -121.621858) (xy 180.892222 -121.569952)
			(xy 180.869286 -121.514579) (xy 180.853773 -121.456686) (xy 180.84595 -121.397264) (xy 180.84546 -121.367296)
			(xy 179.709572 -121.367296) (xy 179.709572 -123.16714) (xy 182.69966 -123.16714) (xy 182.69966 -122.30354)
			(xy 182.70015 -122.273572) (xy 182.707973 -122.21415) (xy 182.723486 -122.156257) (xy 182.746422 -122.100884)
			(xy 182.776389 -122.048978) (xy 182.812876 -122.001428) (xy 182.855256 -121.959048) (xy 182.902806 -121.922561)
			(xy 182.954712 -121.892594) (xy 183.010085 -121.869658) (xy 183.067978 -121.854145) (xy 183.1274 -121.846322)
			(xy 183.187336 -121.846322) (xy 183.246758 -121.854145) (xy 183.304651 -121.869658) (xy 183.360024 -121.892594)
			(xy 183.41193 -121.922561) (xy 183.45948 -121.959048) (xy 183.50186 -122.001428) (xy 183.538347 -122.048978)
			(xy 183.568314 -122.100884) (xy 183.59125 -122.156257) (xy 183.606763 -122.21415) (xy 183.614586 -122.273572)
			(xy 183.615076 -122.30354) (xy 183.615076 -123.16714) (xy 183.614586 -123.197108) (xy 183.606763 -123.25653)
			(xy 183.59125 -123.314423) (xy 183.568314 -123.369796) (xy 183.538347 -123.421702) (xy 183.50186 -123.469252)
			(xy 183.45948 -123.511632) (xy 183.41193 -123.548119) (xy 183.360024 -123.578086) (xy 183.304651 -123.601022)
			(xy 183.246758 -123.616535) (xy 183.187336 -123.624358) (xy 183.1274 -123.624358) (xy 183.067978 -123.616535)
			(xy 183.010085 -123.601022) (xy 182.954712 -123.578086) (xy 182.902806 -123.548119) (xy 182.855256 -123.511632)
			(xy 182.812876 -123.469252) (xy 182.776389 -123.421702) (xy 182.746422 -123.369796) (xy 182.723486 -123.314423)
			(xy 182.707973 -123.25653) (xy 182.70015 -123.197108) (xy 182.69966 -123.16714) (xy 179.709572 -123.16714)
			(xy 179.709572 -124.967238) (xy 180.84546 -124.967238) (xy 180.84546 -124.103638) (xy 180.84595 -124.07367)
			(xy 180.853773 -124.014248) (xy 180.869286 -123.956355) (xy 180.892222 -123.900982) (xy 180.922189 -123.849076)
			(xy 180.958676 -123.801526) (xy 181.001056 -123.759146) (xy 181.048606 -123.722659) (xy 181.100512 -123.692692)
			(xy 181.155885 -123.669756) (xy 181.213778 -123.654243) (xy 181.2732 -123.64642) (xy 181.333136 -123.64642)
			(xy 181.392558 -123.654243) (xy 181.450451 -123.669756) (xy 181.505824 -123.692692) (xy 181.55773 -123.722659)
			(xy 181.60528 -123.759146) (xy 181.64766 -123.801526) (xy 181.684147 -123.849076) (xy 181.714114 -123.900982)
			(xy 181.73705 -123.956355) (xy 181.752563 -124.014248) (xy 181.760386 -124.07367) (xy 181.760876 -124.103638)
			(xy 181.760876 -124.967238) (xy 181.760386 -124.997206) (xy 181.752563 -125.056628) (xy 181.73705 -125.114521)
			(xy 181.714114 -125.169894) (xy 181.684147 -125.2218) (xy 181.64766 -125.26935) (xy 181.60528 -125.31173)
			(xy 181.55773 -125.348217) (xy 181.505824 -125.378184) (xy 181.450451 -125.40112) (xy 181.392558 -125.416633)
			(xy 181.333136 -125.424456) (xy 181.2732 -125.424456) (xy 181.213778 -125.416633) (xy 181.155885 -125.40112)
			(xy 181.100512 -125.378184) (xy 181.048606 -125.348217) (xy 181.001056 -125.31173) (xy 180.958676 -125.26935)
			(xy 180.922189 -125.2218) (xy 180.892222 -125.169894) (xy 180.869286 -125.114521) (xy 180.853773 -125.056628)
			(xy 180.84595 -124.997206) (xy 180.84546 -124.967238) (xy 179.709572 -124.967238) (xy 179.709572 -128.201674)
			(xy 183.60593 -128.201674) (xy 183.610001 -128.146052) (xy 183.622127 -128.091615) (xy 183.64205 -128.039524)
			(xy 183.669346 -127.990889) (xy 183.703432 -127.946746) (xy 183.743581 -127.908037) (xy 183.788939 -127.875586)
			(xy 183.838539 -127.850085) (xy 183.891323 -127.832078) (xy 183.946166 -127.821948) (xy 184.0019 -127.819911)
			(xy 184.057337 -127.826011) (xy 184.111294 -127.840117) (xy 184.162623 -127.861929) (xy 184.210229 -127.890983)
			(xy 184.253097 -127.926658) (xy 184.290314 -127.968195) (xy 184.321087 -128.014708) (xy 184.344759 -128.065205)
			(xy 184.360827 -128.118612) (xy 184.368947 -128.173788) (xy 184.369456 -128.201674) (xy 184.368947 -128.22956)
			(xy 184.360827 -128.284736) (xy 184.344759 -128.338143) (xy 184.321087 -128.38864) (xy 184.290314 -128.435153)
			(xy 184.253097 -128.47669) (xy 184.210229 -128.512365) (xy 184.162623 -128.541419) (xy 184.111294 -128.563231)
			(xy 184.057337 -128.577337) (xy 184.0019 -128.583437) (xy 183.946166 -128.5814) (xy 183.891323 -128.57127)
			(xy 183.838539 -128.553263) (xy 183.788939 -128.527762) (xy 183.743581 -128.495311) (xy 183.703432 -128.456602)
			(xy 183.669346 -128.412459) (xy 183.64205 -128.363824) (xy 183.622127 -128.311733) (xy 183.610001 -128.257296)
			(xy 183.60593 -128.201674) (xy 179.709572 -128.201674) (xy 179.709572 -130.777234) (xy 182.69966 -130.777234)
			(xy 182.69966 -129.913634) (xy 182.70015 -129.883666) (xy 182.707973 -129.824244) (xy 182.723486 -129.766351)
			(xy 182.746422 -129.710978) (xy 182.776389 -129.659072) (xy 182.812876 -129.611522) (xy 182.855256 -129.569142)
			(xy 182.902806 -129.532655) (xy 182.954712 -129.502688) (xy 183.010085 -129.479752) (xy 183.067978 -129.464239)
			(xy 183.1274 -129.456416) (xy 183.187336 -129.456416) (xy 183.246758 -129.464239) (xy 183.304651 -129.479752)
			(xy 183.360024 -129.502688) (xy 183.41193 -129.532655) (xy 183.45948 -129.569142) (xy 183.50186 -129.611522)
			(xy 183.538347 -129.659072) (xy 183.568314 -129.710978) (xy 183.59125 -129.766351) (xy 183.606763 -129.824244)
			(xy 183.614586 -129.883666) (xy 183.615076 -129.913634) (xy 183.615076 -130.777234) (xy 183.614586 -130.807202)
			(xy 183.606763 -130.866624) (xy 183.59125 -130.924517) (xy 183.568314 -130.97989) (xy 183.538347 -131.031796)
			(xy 183.50186 -131.079346) (xy 183.45948 -131.121726) (xy 183.41193 -131.158213) (xy 183.360024 -131.18818)
			(xy 183.304651 -131.211116) (xy 183.246758 -131.226629) (xy 183.187336 -131.234452) (xy 183.1274 -131.234452)
			(xy 183.067978 -131.226629) (xy 183.010085 -131.211116) (xy 182.954712 -131.18818) (xy 182.902806 -131.158213)
			(xy 182.855256 -131.121726) (xy 182.812876 -131.079346) (xy 182.776389 -131.031796) (xy 182.746422 -130.97989)
			(xy 182.723486 -130.924517) (xy 182.707973 -130.866624) (xy 182.70015 -130.807202) (xy 182.69966 -130.777234)
			(xy 179.709572 -130.777234) (xy 179.709572 -132.577332) (xy 180.84546 -132.577332) (xy 180.84546 -131.713732)
			(xy 180.84595 -131.683764) (xy 180.853773 -131.624342) (xy 180.869286 -131.566449) (xy 180.892222 -131.511076)
			(xy 180.922189 -131.45917) (xy 180.958676 -131.41162) (xy 181.001056 -131.36924) (xy 181.048606 -131.332753)
			(xy 181.100512 -131.302786) (xy 181.155885 -131.27985) (xy 181.213778 -131.264337) (xy 181.2732 -131.256514)
			(xy 181.333136 -131.256514) (xy 181.392558 -131.264337) (xy 181.450451 -131.27985) (xy 181.505824 -131.302786)
			(xy 181.55773 -131.332753) (xy 181.60528 -131.36924) (xy 181.64766 -131.41162) (xy 181.684147 -131.45917)
			(xy 181.714114 -131.511076) (xy 181.73705 -131.566449) (xy 181.752563 -131.624342) (xy 181.760386 -131.683764)
			(xy 181.760876 -131.713732) (xy 181.760876 -132.577332) (xy 181.760386 -132.6073) (xy 181.752563 -132.666722)
			(xy 181.73705 -132.724615) (xy 181.714114 -132.779988) (xy 181.684147 -132.831894) (xy 181.64766 -132.879444)
			(xy 181.60528 -132.921824) (xy 181.55773 -132.958311) (xy 181.505824 -132.988278) (xy 181.450451 -133.011214)
			(xy 181.392558 -133.026727) (xy 181.333136 -133.03455) (xy 181.2732 -133.03455) (xy 181.213778 -133.026727)
			(xy 181.155885 -133.011214) (xy 181.100512 -132.988278) (xy 181.048606 -132.958311) (xy 181.001056 -132.921824)
			(xy 180.958676 -132.879444) (xy 180.922189 -132.831894) (xy 180.892222 -132.779988) (xy 180.869286 -132.724615)
			(xy 180.853773 -132.666722) (xy 180.84595 -132.6073) (xy 180.84546 -132.577332) (xy 179.709572 -132.577332)
			(xy 179.709572 -134.377176) (xy 182.69966 -134.377176) (xy 182.69966 -133.513576) (xy 182.70015 -133.483608)
			(xy 182.707973 -133.424186) (xy 182.723486 -133.366293) (xy 182.746422 -133.31092) (xy 182.776389 -133.259014)
			(xy 182.812876 -133.211464) (xy 182.855256 -133.169084) (xy 182.902806 -133.132597) (xy 182.954712 -133.10263)
			(xy 183.010085 -133.079694) (xy 183.067978 -133.064181) (xy 183.1274 -133.056358) (xy 183.187336 -133.056358)
			(xy 183.246758 -133.064181) (xy 183.304651 -133.079694) (xy 183.360024 -133.10263) (xy 183.41193 -133.132597)
			(xy 183.45948 -133.169084) (xy 183.50186 -133.211464) (xy 183.538347 -133.259014) (xy 183.568314 -133.31092)
			(xy 183.59125 -133.366293) (xy 183.606763 -133.424186) (xy 183.614586 -133.483608) (xy 183.615076 -133.513576)
			(xy 183.615076 -134.377176) (xy 183.614586 -134.407144) (xy 183.606763 -134.466566) (xy 183.59125 -134.524459)
			(xy 183.568314 -134.579832) (xy 183.538347 -134.631738) (xy 183.50186 -134.679288) (xy 183.45948 -134.721668)
			(xy 183.41193 -134.758155) (xy 183.360024 -134.788122) (xy 183.304651 -134.811058) (xy 183.246758 -134.826571)
			(xy 183.187336 -134.834394) (xy 183.1274 -134.834394) (xy 183.067978 -134.826571) (xy 183.010085 -134.811058)
			(xy 182.954712 -134.788122) (xy 182.902806 -134.758155) (xy 182.855256 -134.721668) (xy 182.812876 -134.679288)
			(xy 182.776389 -134.631738) (xy 182.746422 -134.579832) (xy 182.723486 -134.524459) (xy 182.707973 -134.466566)
			(xy 182.70015 -134.407144) (xy 182.69966 -134.377176) (xy 179.709572 -134.377176) (xy 179.709572 -136.177274)
			(xy 180.84546 -136.177274) (xy 180.84546 -135.313674) (xy 180.84595 -135.283706) (xy 180.853773 -135.224284)
			(xy 180.869286 -135.166391) (xy 180.892222 -135.111018) (xy 180.922189 -135.059112) (xy 180.958676 -135.011562)
			(xy 181.001056 -134.969182) (xy 181.048606 -134.932695) (xy 181.100512 -134.902728) (xy 181.155885 -134.879792)
			(xy 181.213778 -134.864279) (xy 181.2732 -134.856456) (xy 181.333136 -134.856456) (xy 181.392558 -134.864279)
			(xy 181.450451 -134.879792) (xy 181.505824 -134.902728) (xy 181.55773 -134.932695) (xy 181.60528 -134.969182)
			(xy 181.64766 -135.011562) (xy 181.684147 -135.059112) (xy 181.714114 -135.111018) (xy 181.73705 -135.166391)
			(xy 181.752563 -135.224284) (xy 181.760386 -135.283706) (xy 181.760876 -135.313674) (xy 181.760876 -136.177274)
			(xy 181.760386 -136.207242) (xy 181.752563 -136.266664) (xy 181.73705 -136.324557) (xy 181.714114 -136.37993)
			(xy 181.684147 -136.431836) (xy 181.64766 -136.479386) (xy 181.60528 -136.521766) (xy 181.55773 -136.558253)
			(xy 181.505824 -136.58822) (xy 181.450451 -136.611156) (xy 181.392558 -136.626669) (xy 181.333136 -136.634492)
			(xy 181.2732 -136.634492) (xy 181.213778 -136.626669) (xy 181.155885 -136.611156) (xy 181.100512 -136.58822)
			(xy 181.048606 -136.558253) (xy 181.001056 -136.521766) (xy 180.958676 -136.479386) (xy 180.922189 -136.431836)
			(xy 180.892222 -136.37993) (xy 180.869286 -136.324557) (xy 180.853773 -136.266664) (xy 180.84595 -136.207242)
			(xy 180.84546 -136.177274) (xy 179.709572 -136.177274) (xy 179.709572 -136.98601) (xy 196.657466 -136.98601)
			(xy 196.661537 -136.930388) (xy 196.673663 -136.875951) (xy 196.693586 -136.82386) (xy 196.720882 -136.775225)
			(xy 196.754968 -136.731082) (xy 196.795117 -136.692373) (xy 196.840475 -136.659922) (xy 196.890075 -136.634421)
			(xy 196.942859 -136.616414) (xy 196.997702 -136.606284) (xy 197.053436 -136.604247) (xy 197.108873 -136.610347)
			(xy 197.16283 -136.624453) (xy 197.214159 -136.646265) (xy 197.261765 -136.675319) (xy 197.304633 -136.710994)
			(xy 197.34185 -136.752531) (xy 197.372623 -136.799044) (xy 197.396295 -136.849541) (xy 197.412363 -136.902948)
			(xy 197.420483 -136.958124) (xy 197.420992 -136.98601) (xy 197.420483 -137.013896) (xy 197.412363 -137.069072)
			(xy 197.396295 -137.122479) (xy 197.372623 -137.172976) (xy 197.34185 -137.219489) (xy 197.304633 -137.261026)
			(xy 197.261765 -137.296701) (xy 197.214159 -137.325755) (xy 197.16283 -137.347567) (xy 197.108873 -137.361673)
			(xy 197.053436 -137.367773) (xy 196.997702 -137.365736) (xy 196.942859 -137.355606) (xy 196.890075 -137.337599)
			(xy 196.840475 -137.312098) (xy 196.795117 -137.279647) (xy 196.754968 -137.240938) (xy 196.720882 -137.196795)
			(xy 196.693586 -137.14816) (xy 196.673663 -137.096069) (xy 196.661537 -137.041632) (xy 196.657466 -136.98601)
			(xy 179.709572 -136.98601) (xy 179.709572 -137.853928) (xy 179.709062 -137.880015) (xy 179.700904 -137.931546)
			(xy 179.684779 -137.981164) (xy 179.661083 -138.027645) (xy 179.630401 -138.069843) (xy 179.61229 -138.088624)
			(xy 179.266596 -138.434318) (xy 198.100948 -138.434318) (xy 198.105019 -138.378696) (xy 198.117145 -138.324259)
			(xy 198.137068 -138.272168) (xy 198.164364 -138.223533) (xy 198.19845 -138.17939) (xy 198.238599 -138.140681)
			(xy 198.283957 -138.10823) (xy 198.333557 -138.082729) (xy 198.386341 -138.064722) (xy 198.441184 -138.054592)
			(xy 198.496918 -138.052555) (xy 198.552355 -138.058655) (xy 198.606312 -138.072761) (xy 198.657641 -138.094573)
			(xy 198.705247 -138.123627) (xy 198.748115 -138.159302) (xy 198.785332 -138.200839) (xy 198.816105 -138.247352)
			(xy 198.839777 -138.297849) (xy 198.855845 -138.351256) (xy 198.863965 -138.406432) (xy 198.864474 -138.434318)
			(xy 198.863965 -138.462204) (xy 198.855845 -138.51738) (xy 198.839777 -138.570787) (xy 198.816105 -138.621284)
			(xy 198.785332 -138.667797) (xy 198.748115 -138.709334) (xy 198.705247 -138.745009) (xy 198.657641 -138.774063)
			(xy 198.606312 -138.795875) (xy 198.552355 -138.809981) (xy 198.496918 -138.816081) (xy 198.441184 -138.814044)
			(xy 198.386341 -138.803914) (xy 198.333557 -138.785907) (xy 198.283957 -138.760406) (xy 198.238599 -138.727955)
			(xy 198.19845 -138.689246) (xy 198.164364 -138.645103) (xy 198.137068 -138.596468) (xy 198.117145 -138.544377)
			(xy 198.105019 -138.48994) (xy 198.100948 -138.434318) (xy 179.266596 -138.434318) (xy 178.836066 -138.864848)
			(xy 180.329584 -138.864848) (xy 180.333655 -138.809226) (xy 180.345781 -138.754789) (xy 180.365704 -138.702698)
			(xy 180.393 -138.654063) (xy 180.427086 -138.60992) (xy 180.467235 -138.571211) (xy 180.512593 -138.53876)
			(xy 180.562193 -138.513259) (xy 180.614977 -138.495252) (xy 180.66982 -138.485122) (xy 180.725554 -138.483085)
			(xy 180.780991 -138.489185) (xy 180.834948 -138.503291) (xy 180.886277 -138.525103) (xy 180.933883 -138.554157)
			(xy 180.976751 -138.589832) (xy 181.013968 -138.631369) (xy 181.044741 -138.677882) (xy 181.068413 -138.728379)
			(xy 181.084481 -138.781786) (xy 181.092601 -138.836962) (xy 181.09311 -138.864848) (xy 181.092601 -138.892734)
			(xy 181.084481 -138.94791) (xy 181.068413 -139.001317) (xy 181.044741 -139.051814) (xy 181.013968 -139.098327)
			(xy 180.976751 -139.139864) (xy 180.933883 -139.175539) (xy 180.886277 -139.204593) (xy 180.834948 -139.226405)
			(xy 180.780991 -139.240511) (xy 180.725554 -139.246611) (xy 180.66982 -139.244574) (xy 180.614977 -139.234444)
			(xy 180.562193 -139.216437) (xy 180.512593 -139.190936) (xy 180.467235 -139.158485) (xy 180.427086 -139.119776)
			(xy 180.393 -139.075633) (xy 180.365704 -139.026998) (xy 180.345781 -138.974907) (xy 180.333655 -138.92047)
			(xy 180.329584 -138.864848) (xy 178.836066 -138.864848) (xy 178.814476 -138.886438) (xy 178.808841 -138.89256)
			(xy 178.801453 -138.907456) (xy 178.799998 -138.915648) (xy 178.795809 -138.942761) (xy 178.780779 -138.995519)
			(xy 178.758349 -139.045582) (xy 178.728983 -139.091919) (xy 178.693285 -139.133573) (xy 178.651992 -139.169687)
			(xy 178.605953 -139.199517) (xy 178.556117 -139.222448) (xy 178.503512 -139.238007) (xy 178.449221 -139.245874)
			(xy 178.421792 -139.246356) (xy 178.394543 -139.24583) (xy 178.340599 -139.238073) (xy 178.288308 -139.22272)
			(xy 178.238734 -139.200081) (xy 178.192886 -139.170619) (xy 178.151697 -139.134931) (xy 178.116005 -139.093746)
			(xy 178.086538 -139.047901) (xy 178.063894 -138.99833) (xy 178.048535 -138.94604) (xy 178.040773 -138.892097)
			(xy 178.040284 -138.864848) (xy 173.365879 -138.864848) (xy 173.36911 -138.875851) (xy 173.376866 -138.929799)
			(xy 173.377352 -138.95705) (xy 173.376854 -138.98483) (xy 173.368781 -139.039801) (xy 173.352811 -139.093017)
			(xy 173.329285 -139.14335) (xy 173.298701 -139.189735) (xy 173.280578 -139.210796) (xy 173.280324 -139.21105)
			(xy 173.274021 -139.218931) (xy 173.267603 -139.238047) (xy 173.267878 -139.248134) (xy 173.273212 -139.321286)
			(xy 173.27438 -139.331363) (xy 173.283553 -139.34944) (xy 173.290992 -139.356338) (xy 173.291246 -139.356592)
			(xy 173.312272 -139.3748) (xy 173.349311 -139.416293) (xy 173.379938 -139.46272) (xy 173.403506 -139.5131)
			(xy 173.419516 -139.566366) (xy 173.427628 -139.621391) (xy 173.428152 -139.6492) (xy 173.427666 -139.676451)
			(xy 173.41991 -139.730399) (xy 173.404555 -139.782694) (xy 173.381913 -139.832271) (xy 173.352447 -139.878121)
			(xy 173.316756 -139.919312) (xy 173.275565 -139.955003) (xy 173.229715 -139.984469) (xy 173.180138 -140.007111)
			(xy 173.127843 -140.022466) (xy 173.073895 -140.030222) (xy 173.019393 -140.030222) (xy 172.965445 -140.022466)
			(xy 172.91315 -140.007111) (xy 172.863573 -139.984469) (xy 172.817723 -139.955003) (xy 172.776532 -139.919312)
			(xy 172.740841 -139.878121) (xy 172.711375 -139.832271) (xy 172.688733 -139.782694) (xy 172.673378 -139.730399)
			(xy 172.665622 -139.676451) (xy 172.665136 -139.6492) (xy 172.665667 -139.621421) (xy 172.673733 -139.566452)
			(xy 172.689695 -139.513237) (xy 172.713214 -139.462903) (xy 172.743791 -139.416516) (xy 172.76191 -139.395454)
			(xy 172.762164 -139.3952) (xy 172.768489 -139.387334) (xy 172.774894 -139.368207) (xy 172.77461 -139.358116)
			(xy 172.769276 -139.284964) (xy 172.768136 -139.274881) (xy 172.758943 -139.256807) (xy 172.751496 -139.249912)
			(xy 172.751242 -139.249658) (xy 172.730238 -139.231426) (xy 172.693198 -139.189938) (xy 172.662568 -139.143515)
			(xy 172.638996 -139.093141) (xy 172.622982 -139.039879) (xy 172.614864 -138.984858) (xy 172.614336 -138.95705)
			(xy 172.365924 -138.95705) (xy 172.365924 -140.534898) (xy 197.155814 -140.534898) (xy 197.159885 -140.479276)
			(xy 197.172011 -140.424839) (xy 197.191934 -140.372748) (xy 197.21923 -140.324113) (xy 197.253316 -140.27997)
			(xy 197.293465 -140.241261) (xy 197.338823 -140.20881) (xy 197.388423 -140.183309) (xy 197.441207 -140.165302)
			(xy 197.49605 -140.155172) (xy 197.551784 -140.153135) (xy 197.607221 -140.159235) (xy 197.661178 -140.173341)
			(xy 197.712507 -140.195153) (xy 197.760113 -140.224207) (xy 197.802981 -140.259882) (xy 197.840198 -140.301419)
			(xy 197.870971 -140.347932) (xy 197.894643 -140.398429) (xy 197.910711 -140.451836) (xy 197.918831 -140.507012)
			(xy 197.91934 -140.534898) (xy 197.918831 -140.562784) (xy 197.910711 -140.61796) (xy 197.894643 -140.671367)
			(xy 197.870971 -140.721864) (xy 197.840198 -140.768377) (xy 197.802981 -140.809914) (xy 197.760113 -140.845589)
			(xy 197.712507 -140.874643) (xy 197.661178 -140.896455) (xy 197.607221 -140.910561) (xy 197.551784 -140.916661)
			(xy 197.49605 -140.914624) (xy 197.441207 -140.904494) (xy 197.388423 -140.886487) (xy 197.338823 -140.860986)
			(xy 197.293465 -140.828535) (xy 197.253316 -140.789826) (xy 197.21923 -140.745683) (xy 197.191934 -140.697048)
			(xy 197.172011 -140.644957) (xy 197.159885 -140.59052) (xy 197.155814 -140.534898) (xy 172.365924 -140.534898)
			(xy 172.365924 -141.9352) (xy 172.623986 -141.9352) (xy 172.628057 -141.879578) (xy 172.640183 -141.825141)
			(xy 172.660106 -141.77305) (xy 172.687402 -141.724415) (xy 172.721488 -141.680272) (xy 172.761637 -141.641563)
			(xy 172.806995 -141.609112) (xy 172.856595 -141.583611) (xy 172.909379 -141.565604) (xy 172.964222 -141.555474)
			(xy 173.019956 -141.553437) (xy 173.075393 -141.559537) (xy 173.12935 -141.573643) (xy 173.180679 -141.595455)
			(xy 173.228285 -141.624509) (xy 173.271153 -141.660184) (xy 173.30837 -141.701721) (xy 173.339143 -141.748234)
			(xy 173.362815 -141.798731) (xy 173.378883 -141.852138) (xy 173.387003 -141.907314) (xy 173.387512 -141.9352)
			(xy 173.387003 -141.963086) (xy 173.378883 -142.018262) (xy 173.362815 -142.071669) (xy 173.339143 -142.122166)
			(xy 173.30837 -142.168679) (xy 173.271153 -142.210216) (xy 173.228285 -142.245891) (xy 173.180679 -142.274945)
			(xy 173.12935 -142.296757) (xy 173.075393 -142.310863) (xy 173.019956 -142.316963) (xy 172.964222 -142.314926)
			(xy 172.909379 -142.304796) (xy 172.856595 -142.286789) (xy 172.806995 -142.261288) (xy 172.761637 -142.228837)
			(xy 172.721488 -142.190128) (xy 172.687402 -142.145985) (xy 172.660106 -142.09735) (xy 172.640183 -142.045259)
			(xy 172.628057 -141.990822) (xy 172.623986 -141.9352) (xy 172.365924 -141.9352) (xy 172.365924 -142.9512)
			(xy 172.640242 -142.9512) (xy 172.644313 -142.895578) (xy 172.656439 -142.841141) (xy 172.676362 -142.78905)
			(xy 172.703658 -142.740415) (xy 172.737744 -142.696272) (xy 172.777893 -142.657563) (xy 172.823251 -142.625112)
			(xy 172.872851 -142.599611) (xy 172.925635 -142.581604) (xy 172.980478 -142.571474) (xy 173.036212 -142.569437)
			(xy 173.091649 -142.575537) (xy 173.145606 -142.589643) (xy 173.196935 -142.611455) (xy 173.244541 -142.640509)
			(xy 173.287409 -142.676184) (xy 173.324626 -142.717721) (xy 173.355399 -142.764234) (xy 173.379071 -142.814731)
			(xy 173.395139 -142.868138) (xy 173.403259 -142.923314) (xy 173.403768 -142.9512) (xy 173.403259 -142.979086)
			(xy 173.395139 -143.034262) (xy 173.379071 -143.087669) (xy 173.355399 -143.138166) (xy 173.324626 -143.184679)
			(xy 173.287409 -143.226216) (xy 173.244541 -143.261891) (xy 173.196935 -143.290945) (xy 173.145606 -143.312757)
			(xy 173.091649 -143.326863) (xy 173.036212 -143.332963) (xy 172.980478 -143.330926) (xy 172.925635 -143.320796)
			(xy 172.872851 -143.302789) (xy 172.823251 -143.277288) (xy 172.777893 -143.244837) (xy 172.737744 -143.206128)
			(xy 172.703658 -143.161985) (xy 172.676362 -143.11335) (xy 172.656439 -143.061259) (xy 172.644313 -143.006822)
			(xy 172.640242 -142.9512) (xy 172.365924 -142.9512) (xy 172.365924 -143.48714) (xy 182.69966 -143.48714)
			(xy 182.69966 -142.62354) (xy 182.70015 -142.593572) (xy 182.707973 -142.53415) (xy 182.723486 -142.476257)
			(xy 182.746422 -142.420884) (xy 182.776389 -142.368978) (xy 182.812876 -142.321428) (xy 182.855256 -142.279048)
			(xy 182.902806 -142.242561) (xy 182.954712 -142.212594) (xy 183.010085 -142.189658) (xy 183.067978 -142.174145)
			(xy 183.1274 -142.166322) (xy 183.187336 -142.166322) (xy 183.246758 -142.174145) (xy 183.304651 -142.189658)
			(xy 183.360024 -142.212594) (xy 183.41193 -142.242561) (xy 183.45948 -142.279048) (xy 183.50186 -142.321428)
			(xy 183.538347 -142.368978) (xy 183.568314 -142.420884) (xy 183.59125 -142.476257) (xy 183.606763 -142.53415)
			(xy 183.614586 -142.593572) (xy 183.615076 -142.62354) (xy 183.615076 -143.48714) (xy 183.614586 -143.517108)
			(xy 183.606763 -143.57653) (xy 183.59125 -143.634423) (xy 183.568314 -143.689796) (xy 183.538347 -143.741702)
			(xy 183.50186 -143.789252) (xy 183.45948 -143.831632) (xy 183.41193 -143.868119) (xy 183.360024 -143.898086)
			(xy 183.304651 -143.921022) (xy 183.246758 -143.936535) (xy 183.187336 -143.944358) (xy 183.1274 -143.944358)
			(xy 183.067978 -143.936535) (xy 183.010085 -143.921022) (xy 182.954712 -143.898086) (xy 182.902806 -143.868119)
			(xy 182.855256 -143.831632) (xy 182.812876 -143.789252) (xy 182.776389 -143.741702) (xy 182.746422 -143.689796)
			(xy 182.723486 -143.634423) (xy 182.707973 -143.57653) (xy 182.70015 -143.517108) (xy 182.69966 -143.48714)
			(xy 172.365924 -143.48714) (xy 172.365924 -143.946372) (xy 172.365414 -143.972396) (xy 172.357243 -144.0238)
			(xy 172.341145 -144.073298) (xy 172.317514 -144.119673) (xy 172.28693 -144.16179) (xy 172.268896 -144.18056)
			(xy 172.177401 -144.272) (xy 172.486826 -144.272) (xy 172.490897 -144.216378) (xy 172.503023 -144.161941)
			(xy 172.522946 -144.10985) (xy 172.550242 -144.061215) (xy 172.584328 -144.017072) (xy 172.624477 -143.978363)
			(xy 172.669835 -143.945912) (xy 172.719435 -143.920411) (xy 172.772219 -143.902404) (xy 172.827062 -143.892274)
			(xy 172.882796 -143.890237) (xy 172.938233 -143.896337) (xy 172.99219 -143.910443) (xy 173.043519 -143.932255)
			(xy 173.091125 -143.961309) (xy 173.133993 -143.996984) (xy 173.17121 -144.038521) (xy 173.201983 -144.085034)
			(xy 173.225655 -144.135531) (xy 173.241723 -144.188938) (xy 173.249843 -144.244114) (xy 173.250352 -144.272)
			(xy 173.249843 -144.299886) (xy 173.241723 -144.355062) (xy 173.225655 -144.408469) (xy 173.201983 -144.458966)
			(xy 173.17121 -144.505479) (xy 173.133993 -144.547016) (xy 173.091125 -144.582691) (xy 173.043519 -144.611745)
			(xy 172.99219 -144.633557) (xy 172.938233 -144.647663) (xy 172.882796 -144.653763) (xy 172.827062 -144.651726)
			(xy 172.772219 -144.641596) (xy 172.719435 -144.623589) (xy 172.669835 -144.598088) (xy 172.624477 -144.565637)
			(xy 172.584328 -144.526928) (xy 172.550242 -144.482785) (xy 172.522946 -144.43415) (xy 172.503023 -144.382059)
			(xy 172.490897 -144.327622) (xy 172.486826 -144.272) (xy 172.177401 -144.272) (xy 171.84751 -144.601692)
			(xy 171.840682 -144.609102) (xy 171.832955 -144.627694) (xy 171.832524 -144.63776) (xy 171.832524 -145.287238)
			(xy 180.84546 -145.287238) (xy 180.84546 -144.423638) (xy 180.84595 -144.39367) (xy 180.853773 -144.334248)
			(xy 180.869286 -144.276355) (xy 180.892222 -144.220982) (xy 180.922189 -144.169076) (xy 180.958676 -144.121526)
			(xy 181.001056 -144.079146) (xy 181.048606 -144.042659) (xy 181.100512 -144.012692) (xy 181.155885 -143.989756)
			(xy 181.213778 -143.974243) (xy 181.2732 -143.96642) (xy 181.333136 -143.96642) (xy 181.392558 -143.974243)
			(xy 181.450451 -143.989756) (xy 181.505824 -144.012692) (xy 181.55773 -144.042659) (xy 181.60528 -144.079146)
			(xy 181.64766 -144.121526) (xy 181.684147 -144.169076) (xy 181.714114 -144.220982) (xy 181.73705 -144.276355)
			(xy 181.752563 -144.334248) (xy 181.760386 -144.39367) (xy 181.760876 -144.423638) (xy 181.760876 -145.287238)
			(xy 181.760386 -145.317206) (xy 181.752563 -145.376628) (xy 181.73705 -145.434521) (xy 181.714114 -145.489894)
			(xy 181.684147 -145.5418) (xy 181.64766 -145.58935) (xy 181.60528 -145.63173) (xy 181.55773 -145.668217)
			(xy 181.505824 -145.698184) (xy 181.450451 -145.72112) (xy 181.392558 -145.736633) (xy 181.333136 -145.744456)
			(xy 181.2732 -145.744456) (xy 181.213778 -145.736633) (xy 181.155885 -145.72112) (xy 181.100512 -145.698184)
			(xy 181.048606 -145.668217) (xy 181.001056 -145.63173) (xy 180.958676 -145.58935) (xy 180.922189 -145.5418)
			(xy 180.892222 -145.489894) (xy 180.869286 -145.434521) (xy 180.853773 -145.376628) (xy 180.84595 -145.317206)
			(xy 180.84546 -145.287238) (xy 171.832524 -145.287238) (xy 171.832524 -147.087336) (xy 182.69966 -147.087336)
			(xy 182.69966 -146.223736) (xy 182.70015 -146.193768) (xy 182.707973 -146.134346) (xy 182.723486 -146.076453)
			(xy 182.746422 -146.02108) (xy 182.776389 -145.969174) (xy 182.812876 -145.921624) (xy 182.855256 -145.879244)
			(xy 182.902806 -145.842757) (xy 182.954712 -145.81279) (xy 183.010085 -145.789854) (xy 183.067978 -145.774341)
			(xy 183.1274 -145.766518) (xy 183.187336 -145.766518) (xy 183.246758 -145.774341) (xy 183.304651 -145.789854)
			(xy 183.360024 -145.81279) (xy 183.41193 -145.842757) (xy 183.45948 -145.879244) (xy 183.50186 -145.921624)
			(xy 183.538347 -145.969174) (xy 183.568314 -146.02108) (xy 183.59125 -146.076453) (xy 183.606763 -146.134346)
			(xy 183.614586 -146.193768) (xy 183.615076 -146.223736) (xy 183.615076 -147.087336) (xy 183.614586 -147.117304)
			(xy 183.606763 -147.176726) (xy 183.59125 -147.234619) (xy 183.568314 -147.289992) (xy 183.538347 -147.341898)
			(xy 183.50186 -147.389448) (xy 183.45948 -147.431828) (xy 183.41193 -147.468315) (xy 183.360024 -147.498282)
			(xy 183.304651 -147.521218) (xy 183.246758 -147.536731) (xy 183.187336 -147.544554) (xy 183.1274 -147.544554)
			(xy 183.067978 -147.536731) (xy 183.010085 -147.521218) (xy 182.954712 -147.498282) (xy 182.902806 -147.468315)
			(xy 182.855256 -147.431828) (xy 182.812876 -147.389448) (xy 182.776389 -147.341898) (xy 182.746422 -147.289992)
			(xy 182.723486 -147.234619) (xy 182.707973 -147.176726) (xy 182.70015 -147.117304) (xy 182.69966 -147.087336)
			(xy 171.832524 -147.087336) (xy 171.832524 -148.887434) (xy 180.84546 -148.887434) (xy 180.84546 -148.023834)
			(xy 180.84595 -147.993866) (xy 180.853773 -147.934444) (xy 180.869286 -147.876551) (xy 180.892222 -147.821178)
			(xy 180.922189 -147.769272) (xy 180.958676 -147.721722) (xy 181.001056 -147.679342) (xy 181.048606 -147.642855)
			(xy 181.100512 -147.612888) (xy 181.155885 -147.589952) (xy 181.213778 -147.574439) (xy 181.2732 -147.566616)
			(xy 181.333136 -147.566616) (xy 181.392558 -147.574439) (xy 181.450451 -147.589952) (xy 181.505824 -147.612888)
			(xy 181.55773 -147.642855) (xy 181.60528 -147.679342) (xy 181.64766 -147.721722) (xy 181.684147 -147.769272)
			(xy 181.714114 -147.821178) (xy 181.73705 -147.876551) (xy 181.752563 -147.934444) (xy 181.760386 -147.993866)
			(xy 181.760876 -148.023834) (xy 181.760876 -148.887434) (xy 181.760386 -148.917402) (xy 181.752563 -148.976824)
			(xy 181.73705 -149.034717) (xy 181.714114 -149.09009) (xy 181.684147 -149.141996) (xy 181.64766 -149.189546)
			(xy 181.60528 -149.231926) (xy 181.55773 -149.268413) (xy 181.505824 -149.29838) (xy 181.450451 -149.321316)
			(xy 181.392558 -149.336829) (xy 181.333136 -149.344652) (xy 181.2732 -149.344652) (xy 181.213778 -149.336829)
			(xy 181.155885 -149.321316) (xy 181.100512 -149.29838) (xy 181.048606 -149.268413) (xy 181.001056 -149.231926)
			(xy 180.958676 -149.189546) (xy 180.922189 -149.141996) (xy 180.892222 -149.09009) (xy 180.869286 -149.034717)
			(xy 180.853773 -148.976824) (xy 180.84595 -148.917402) (xy 180.84546 -148.887434) (xy 171.832524 -148.887434)
			(xy 171.832524 -150.687278) (xy 182.69966 -150.687278) (xy 182.69966 -149.823678) (xy 182.70015 -149.79371)
			(xy 182.707973 -149.734288) (xy 182.723486 -149.676395) (xy 182.746422 -149.621022) (xy 182.776389 -149.569116)
			(xy 182.812876 -149.521566) (xy 182.855256 -149.479186) (xy 182.902806 -149.442699) (xy 182.954712 -149.412732)
			(xy 183.010085 -149.389796) (xy 183.067978 -149.374283) (xy 183.1274 -149.36646) (xy 183.187336 -149.36646)
			(xy 183.246758 -149.374283) (xy 183.304651 -149.389796) (xy 183.360024 -149.412732) (xy 183.41193 -149.442699)
			(xy 183.45948 -149.479186) (xy 183.50186 -149.521566) (xy 183.538347 -149.569116) (xy 183.568314 -149.621022)
			(xy 183.59125 -149.676395) (xy 183.606763 -149.734288) (xy 183.614586 -149.79371) (xy 183.615076 -149.823678)
			(xy 183.615076 -150.687278) (xy 183.614586 -150.717246) (xy 183.606763 -150.776668) (xy 183.59125 -150.834561)
			(xy 183.568314 -150.889934) (xy 183.538347 -150.94184) (xy 183.50186 -150.98939) (xy 183.45948 -151.03177)
			(xy 183.41193 -151.068257) (xy 183.360024 -151.098224) (xy 183.304651 -151.12116) (xy 183.246758 -151.136673)
			(xy 183.187336 -151.144496) (xy 183.1274 -151.144496) (xy 183.067978 -151.136673) (xy 183.010085 -151.12116)
			(xy 182.954712 -151.098224) (xy 182.902806 -151.068257) (xy 182.855256 -151.03177) (xy 182.812876 -150.98939)
			(xy 182.776389 -150.94184) (xy 182.746422 -150.889934) (xy 182.723486 -150.834561) (xy 182.707973 -150.776668)
			(xy 182.70015 -150.717246) (xy 182.69966 -150.687278) (xy 171.832524 -150.687278) (xy 171.832524 -152.487376)
			(xy 180.84546 -152.487376) (xy 180.84546 -151.623776) (xy 180.84595 -151.593808) (xy 180.853773 -151.534386)
			(xy 180.869286 -151.476493) (xy 180.892222 -151.42112) (xy 180.922189 -151.369214) (xy 180.958676 -151.321664)
			(xy 181.001056 -151.279284) (xy 181.048606 -151.242797) (xy 181.100512 -151.21283) (xy 181.155885 -151.189894)
			(xy 181.213778 -151.174381) (xy 181.2732 -151.166558) (xy 181.333136 -151.166558) (xy 181.392558 -151.174381)
			(xy 181.450451 -151.189894) (xy 181.505824 -151.21283) (xy 181.55773 -151.242797) (xy 181.60528 -151.279284)
			(xy 181.64766 -151.321664) (xy 181.684147 -151.369214) (xy 181.714114 -151.42112) (xy 181.73705 -151.476493)
			(xy 181.752563 -151.534386) (xy 181.760386 -151.593808) (xy 181.760876 -151.623776) (xy 181.760876 -152.487376)
			(xy 181.760386 -152.517344) (xy 181.752563 -152.576766) (xy 181.73705 -152.634659) (xy 181.714114 -152.690032)
			(xy 181.684147 -152.741938) (xy 181.64766 -152.789488) (xy 181.60528 -152.831868) (xy 181.55773 -152.868355)
			(xy 181.505824 -152.898322) (xy 181.450451 -152.921258) (xy 181.392558 -152.936771) (xy 181.333136 -152.944594)
			(xy 181.2732 -152.944594) (xy 181.213778 -152.936771) (xy 181.155885 -152.921258) (xy 181.100512 -152.898322)
			(xy 181.048606 -152.868355) (xy 181.001056 -152.831868) (xy 180.958676 -152.789488) (xy 180.922189 -152.741938)
			(xy 180.892222 -152.690032) (xy 180.869286 -152.634659) (xy 180.853773 -152.576766) (xy 180.84595 -152.517344)
			(xy 180.84546 -152.487376) (xy 171.832524 -152.487376) (xy 171.832524 -154.28722) (xy 182.69966 -154.28722)
			(xy 182.69966 -153.42362) (xy 182.70015 -153.393652) (xy 182.707973 -153.33423) (xy 182.723486 -153.276337)
			(xy 182.746422 -153.220964) (xy 182.776389 -153.169058) (xy 182.812876 -153.121508) (xy 182.855256 -153.079128)
			(xy 182.902806 -153.042641) (xy 182.954712 -153.012674) (xy 183.010085 -152.989738) (xy 183.067978 -152.974225)
			(xy 183.1274 -152.966402) (xy 183.187336 -152.966402) (xy 183.246758 -152.974225) (xy 183.304651 -152.989738)
			(xy 183.360024 -153.012674) (xy 183.41193 -153.042641) (xy 183.45948 -153.079128) (xy 183.50186 -153.121508)
			(xy 183.538347 -153.169058) (xy 183.568314 -153.220964) (xy 183.59125 -153.276337) (xy 183.606763 -153.33423)
			(xy 183.614586 -153.393652) (xy 183.615076 -153.42362) (xy 183.615076 -154.28722) (xy 183.614586 -154.317188)
			(xy 183.606763 -154.37661) (xy 183.59125 -154.434503) (xy 183.568314 -154.489876) (xy 183.538347 -154.541782)
			(xy 183.50186 -154.589332) (xy 183.45948 -154.631712) (xy 183.41193 -154.668199) (xy 183.360024 -154.698166)
			(xy 183.304651 -154.721102) (xy 183.246758 -154.736615) (xy 183.187336 -154.744438) (xy 183.1274 -154.744438)
			(xy 183.067978 -154.736615) (xy 183.010085 -154.721102) (xy 182.954712 -154.698166) (xy 182.902806 -154.668199)
			(xy 182.855256 -154.631712) (xy 182.812876 -154.589332) (xy 182.776389 -154.541782) (xy 182.746422 -154.489876)
			(xy 182.723486 -154.434503) (xy 182.707973 -154.37661) (xy 182.70015 -154.317188) (xy 182.69966 -154.28722)
			(xy 171.832524 -154.28722) (xy 171.832524 -156.087318) (xy 180.84546 -156.087318) (xy 180.84546 -155.223718)
			(xy 180.84595 -155.19375) (xy 180.853773 -155.134328) (xy 180.869286 -155.076435) (xy 180.892222 -155.021062)
			(xy 180.922189 -154.969156) (xy 180.958676 -154.921606) (xy 181.001056 -154.879226) (xy 181.048606 -154.842739)
			(xy 181.100512 -154.812772) (xy 181.155885 -154.789836) (xy 181.213778 -154.774323) (xy 181.2732 -154.7665)
			(xy 181.333136 -154.7665) (xy 181.392558 -154.774323) (xy 181.450451 -154.789836) (xy 181.505824 -154.812772)
			(xy 181.55773 -154.842739) (xy 181.60528 -154.879226) (xy 181.64766 -154.921606) (xy 181.684147 -154.969156)
			(xy 181.714114 -155.021062) (xy 181.73705 -155.076435) (xy 181.752563 -155.134328) (xy 181.760386 -155.19375)
			(xy 181.760876 -155.223718) (xy 181.760876 -156.087318) (xy 181.760386 -156.117286) (xy 181.752563 -156.176708)
			(xy 181.73705 -156.234601) (xy 181.714114 -156.289974) (xy 181.684147 -156.34188) (xy 181.64766 -156.38943)
			(xy 181.60528 -156.43181) (xy 181.55773 -156.468297) (xy 181.505824 -156.498264) (xy 181.450451 -156.5212)
			(xy 181.392558 -156.536713) (xy 181.333136 -156.544536) (xy 181.2732 -156.544536) (xy 181.213778 -156.536713)
			(xy 181.155885 -156.5212) (xy 181.100512 -156.498264) (xy 181.048606 -156.468297) (xy 181.001056 -156.43181)
			(xy 180.958676 -156.38943) (xy 180.922189 -156.34188) (xy 180.892222 -156.289974) (xy 180.869286 -156.234601)
			(xy 180.853773 -156.176708) (xy 180.84595 -156.117286) (xy 180.84546 -156.087318) (xy 171.832524 -156.087318)
			(xy 171.832524 -157.045152) (xy 178.526438 -157.045152) (xy 178.530509 -156.98953) (xy 178.542635 -156.935093)
			(xy 178.562558 -156.883002) (xy 178.589854 -156.834367) (xy 178.62394 -156.790224) (xy 178.664089 -156.751515)
			(xy 178.709447 -156.719064) (xy 178.759047 -156.693563) (xy 178.811831 -156.675556) (xy 178.866674 -156.665426)
			(xy 178.922408 -156.663389) (xy 178.977845 -156.669489) (xy 179.031802 -156.683595) (xy 179.083131 -156.705407)
			(xy 179.130737 -156.734461) (xy 179.173605 -156.770136) (xy 179.210822 -156.811673) (xy 179.241595 -156.858186)
			(xy 179.265267 -156.908683) (xy 179.281335 -156.96209) (xy 179.289455 -157.017266) (xy 179.289964 -157.045152)
			(xy 179.289455 -157.073038) (xy 179.281335 -157.128214) (xy 179.265267 -157.181621) (xy 179.241595 -157.232118)
			(xy 179.210822 -157.278631) (xy 179.173605 -157.320168) (xy 179.130737 -157.355843) (xy 179.083131 -157.384897)
			(xy 179.031802 -157.406709) (xy 178.977845 -157.420815) (xy 178.922408 -157.426915) (xy 178.866674 -157.424878)
			(xy 178.811831 -157.414748) (xy 178.759047 -157.396741) (xy 178.709447 -157.37124) (xy 178.664089 -157.338789)
			(xy 178.62394 -157.30008) (xy 178.589854 -157.255937) (xy 178.562558 -157.207302) (xy 178.542635 -157.155211)
			(xy 178.530509 -157.100774) (xy 178.526438 -157.045152) (xy 171.832524 -157.045152) (xy 171.832524 -158.219648)
			(xy 197.282052 -158.219648) (xy 197.286123 -158.164026) (xy 197.298249 -158.109589) (xy 197.318172 -158.057498)
			(xy 197.345468 -158.008863) (xy 197.379554 -157.96472) (xy 197.419703 -157.926011) (xy 197.465061 -157.89356)
			(xy 197.514661 -157.868059) (xy 197.567445 -157.850052) (xy 197.622288 -157.839922) (xy 197.678022 -157.837885)
			(xy 197.733459 -157.843985) (xy 197.787416 -157.858091) (xy 197.838745 -157.879903) (xy 197.886351 -157.908957)
			(xy 197.929219 -157.944632) (xy 197.966436 -157.986169) (xy 197.997209 -158.032682) (xy 198.020881 -158.083179)
			(xy 198.036949 -158.136586) (xy 198.045069 -158.191762) (xy 198.045578 -158.219648) (xy 198.045069 -158.247534)
			(xy 198.036949 -158.30271) (xy 198.020881 -158.356117) (xy 197.997209 -158.406614) (xy 197.966436 -158.453127)
			(xy 197.929219 -158.494664) (xy 197.886351 -158.530339) (xy 197.838745 -158.559393) (xy 197.787416 -158.581205)
			(xy 197.733459 -158.595311) (xy 197.678022 -158.601411) (xy 197.622288 -158.599374) (xy 197.567445 -158.589244)
			(xy 197.514661 -158.571237) (xy 197.465061 -158.545736) (xy 197.419703 -158.513285) (xy 197.379554 -158.474576)
			(xy 197.345468 -158.430433) (xy 197.318172 -158.381798) (xy 197.298249 -158.329707) (xy 197.286123 -158.27527)
			(xy 197.282052 -158.219648) (xy 171.832524 -158.219648) (xy 171.832524 -159.438086) (xy 171.83295 -159.448155)
			(xy 171.84067 -159.466753) (xy 171.84751 -159.474154) (xy 172.558483 -160.1851) (xy 185.988719 -160.1851)
			(xy 185.992676 -160.093219) (xy 186.004516 -160.002019) (xy 186.024153 -159.912174) (xy 186.05144 -159.824349)
			(xy 186.086176 -159.739196) (xy 186.128104 -159.657343) (xy 186.176913 -159.579398) (xy 186.232242 -159.505938)
			(xy 186.293682 -159.437506) (xy 186.360776 -159.374608) (xy 186.433029 -159.317712) (xy 186.509906 -159.267237)
			(xy 186.590837 -159.223557) (xy 186.675223 -159.186997) (xy 186.76244 -159.157826) (xy 186.851842 -159.136261)
			(xy 186.942767 -159.122461) (xy 187.034541 -159.116528) (xy 187.126486 -159.118507) (xy 187.21792 -159.128383)
			(xy 187.308167 -159.146082) (xy 187.396558 -159.171473) (xy 187.482439 -159.204369) (xy 187.546884 -159.235648)
			(xy 197.448422 -159.235648) (xy 197.452493 -159.180026) (xy 197.464619 -159.125589) (xy 197.484542 -159.073498)
			(xy 197.511838 -159.024863) (xy 197.545924 -158.98072) (xy 197.586073 -158.942011) (xy 197.631431 -158.90956)
			(xy 197.681031 -158.884059) (xy 197.733815 -158.866052) (xy 197.788658 -158.855922) (xy 197.844392 -158.853885)
			(xy 197.899829 -158.859985) (xy 197.953786 -158.874091) (xy 198.005115 -158.895903) (xy 198.052721 -158.924957)
			(xy 198.095589 -158.960632) (xy 198.132806 -159.002169) (xy 198.163579 -159.048682) (xy 198.187251 -159.099179)
			(xy 198.203319 -159.152586) (xy 198.211439 -159.207762) (xy 198.211948 -159.235648) (xy 198.211439 -159.263534)
			(xy 198.203319 -159.31871) (xy 198.187251 -159.372117) (xy 198.163579 -159.422614) (xy 198.132806 -159.469127)
			(xy 198.095589 -159.510664) (xy 198.052721 -159.546339) (xy 198.005115 -159.575393) (xy 197.953786 -159.597205)
			(xy 197.899829 -159.611311) (xy 197.844392 -159.617411) (xy 197.788658 -159.615374) (xy 197.733815 -159.605244)
			(xy 197.681031 -159.587237) (xy 197.631431 -159.561736) (xy 197.586073 -159.529285) (xy 197.545924 -159.490576)
			(xy 197.511838 -159.446433) (xy 197.484542 -159.397798) (xy 197.464619 -159.345707) (xy 197.452493 -159.29127)
			(xy 197.448422 -159.235648) (xy 187.546884 -159.235648) (xy 187.565175 -159.244526) (xy 187.644152 -159.291647)
			(xy 187.718786 -159.345383) (xy 187.788524 -159.405335) (xy 187.85285 -159.471061) (xy 187.911289 -159.542073)
			(xy 187.963406 -159.617846) (xy 188.008816 -159.697818) (xy 188.047184 -159.781399) (xy 188.078225 -159.867968)
			(xy 188.101708 -159.956885) (xy 188.117462 -160.047492) (xy 188.125367 -160.139117) (xy 188.125862 -160.1851)
			(xy 188.125367 -160.231083) (xy 188.117462 -160.322708) (xy 188.101708 -160.413315) (xy 188.078225 -160.502232)
			(xy 188.047184 -160.588801) (xy 188.008816 -160.672382) (xy 187.963406 -160.752354) (xy 187.911289 -160.828127)
			(xy 187.85285 -160.899139) (xy 187.788524 -160.964865) (xy 187.718786 -161.024817) (xy 187.644152 -161.078553)
			(xy 187.565175 -161.125674) (xy 187.482439 -161.165831) (xy 187.396558 -161.198727) (xy 187.308167 -161.224118)
			(xy 187.21792 -161.241817) (xy 187.126486 -161.251693) (xy 187.034541 -161.253672) (xy 186.942767 -161.247739)
			(xy 186.851842 -161.233939) (xy 186.76244 -161.212374) (xy 186.675223 -161.183203) (xy 186.590837 -161.146643)
			(xy 186.509906 -161.102963) (xy 186.433029 -161.052488) (xy 186.360776 -160.995592) (xy 186.293682 -160.932694)
			(xy 186.232242 -160.864262) (xy 186.176913 -160.790802) (xy 186.128104 -160.712857) (xy 186.086176 -160.631004)
			(xy 186.05144 -160.545851) (xy 186.024153 -160.458026) (xy 186.004516 -160.368181) (xy 185.992676 -160.276981)
			(xy 185.988719 -160.1851) (xy 172.558483 -160.1851) (xy 178.444138 -166.070534) (xy 180.295294 -166.070534)
			(xy 180.299365 -166.014912) (xy 180.311491 -165.960475) (xy 180.331414 -165.908384) (xy 180.35871 -165.859749)
			(xy 180.392796 -165.815606) (xy 180.432945 -165.776897) (xy 180.478303 -165.744446) (xy 180.527903 -165.718945)
			(xy 180.580687 -165.700938) (xy 180.63553 -165.690808) (xy 180.691264 -165.688771) (xy 180.746701 -165.694871)
			(xy 180.800658 -165.708977) (xy 180.851987 -165.730789) (xy 180.899593 -165.759843) (xy 180.942461 -165.795518)
			(xy 180.979678 -165.837055) (xy 181.010451 -165.883568) (xy 181.034123 -165.934065) (xy 181.050191 -165.987472)
			(xy 181.058311 -166.042648) (xy 181.05882 -166.070534) (xy 181.058311 -166.09842) (xy 181.050191 -166.153596)
			(xy 181.034123 -166.207003) (xy 181.010451 -166.2575) (xy 180.979678 -166.304013) (xy 180.942461 -166.34555)
			(xy 180.899593 -166.381225) (xy 180.851987 -166.410279) (xy 180.800658 -166.432091) (xy 180.746701 -166.446197)
			(xy 180.691264 -166.452297) (xy 180.63553 -166.45026) (xy 180.580687 -166.44013) (xy 180.527903 -166.422123)
			(xy 180.478303 -166.396622) (xy 180.432945 -166.364171) (xy 180.392796 -166.325462) (xy 180.35871 -166.281319)
			(xy 180.331414 -166.232684) (xy 180.311491 -166.180593) (xy 180.299365 -166.126156) (xy 180.295294 -166.070534)
			(xy 178.444138 -166.070534) (xy 178.597052 -166.223442) (xy 178.604509 -166.230201) (xy 178.623069 -166.237922)
			(xy 178.63312 -166.238428) (xy 178.974496 -166.238428) (xy 178.985672 -166.235888) (xy 178.991006 -166.233094)
			(xy 178.992022 -166.232586) (xy 179.019494 -166.218858) (xy 179.077743 -166.199405) (xy 179.138355 -166.189532)
			(xy 179.16906 -166.188898) (xy 179.196315 -166.189347) (xy 179.250271 -166.197099) (xy 179.302575 -166.212452)
			(xy 179.352161 -166.235092) (xy 179.39802 -166.26456) (xy 179.439218 -166.300254) (xy 179.474916 -166.341448)
			(xy 179.504388 -166.387304) (xy 179.527034 -166.436888) (xy 179.542392 -166.48919) (xy 179.550151 -166.543145)
			(xy 179.550151 -166.597655) (xy 179.542392 -166.65161) (xy 179.527034 -166.703912) (xy 179.504388 -166.753496)
			(xy 179.474916 -166.799352) (xy 179.439218 -166.840546) (xy 179.39802 -166.87624) (xy 179.352161 -166.905708)
			(xy 179.302575 -166.928348) (xy 179.250271 -166.943701) (xy 179.196315 -166.951453) (xy 179.16906 -166.951914)
			(xy 179.138257 -166.951313) (xy 179.077456 -166.941384) (xy 179.019042 -166.921807) (xy 178.991514 -166.907972)
			(xy 178.991006 -166.907718) (xy 178.985695 -166.905216) (xy 178.974269 -166.90253) (xy 178.9684 -166.902384)
			(xy 178.474624 -166.902384) (xy 178.448536 -166.901901) (xy 178.397004 -166.893736) (xy 178.347386 -166.877604)
			(xy 178.300905 -166.853902) (xy 178.258708 -166.823216) (xy 178.239928 -166.805102) (xy 178.1429 -166.708074)
			(xy 178.135953 -166.70177) (xy 178.11884 -166.694132) (xy 178.100127 -166.693137) (xy 178.091084 -166.695628)
			(xy 177.991516 -166.72814) (xy 177.972974 -166.749984) (xy 177.970688 -166.764208) (xy 177.966093 -166.790849)
			(xy 177.950327 -166.84256) (xy 177.927418 -166.891526) (xy 177.897825 -166.936768) (xy 177.86214 -166.977378)
			(xy 177.821079 -167.012543) (xy 177.775464 -167.041558) (xy 177.72621 -167.063842) (xy 177.674303 -167.078948)
			(xy 177.620782 -167.086575) (xy 177.593752 -167.087042) (xy 177.566501 -167.086567) (xy 177.512555 -167.078805)
			(xy 177.460262 -167.063445) (xy 177.410687 -167.040801) (xy 177.364838 -167.011333) (xy 177.323649 -166.975641)
			(xy 177.287959 -166.934451) (xy 177.258492 -166.888601) (xy 177.23585 -166.839025) (xy 177.220492 -166.786732)
			(xy 177.212732 -166.732785) (xy 177.212244 -166.705534) (xy 177.212727 -166.678507) (xy 177.220365 -166.624994)
			(xy 177.23548 -166.573095) (xy 177.257768 -166.523849) (xy 177.286783 -166.478242) (xy 177.321946 -166.437186)
			(xy 177.36255 -166.401504) (xy 177.407784 -166.37191) (xy 177.456743 -166.348996) (xy 177.508445 -166.333222)
			(xy 177.535078 -166.328598) (xy 177.549302 -166.326312) (xy 177.571146 -166.30777) (xy 177.603658 -166.208202)
			(xy 177.60621 -166.199158) (xy 177.605268 -166.180406) (xy 177.597614 -166.163262) (xy 177.591212 -166.156386)
			(xy 171.654216 -160.21939) (xy 171.624244 -160.213294) (xy 171.61002 -160.21939) (xy 171.600903 -160.223625)
			(xy 171.586665 -160.237792) (xy 171.578953 -160.256338) (xy 171.578524 -160.26638) (xy 171.578524 -172.329348)
			(xy 177.947826 -172.329348) (xy 177.951897 -172.273726) (xy 177.964023 -172.219289) (xy 177.983946 -172.167198)
			(xy 178.011242 -172.118563) (xy 178.045328 -172.07442) (xy 178.085477 -172.035711) (xy 178.130835 -172.00326)
			(xy 178.180435 -171.977759) (xy 178.233219 -171.959752) (xy 178.288062 -171.949622) (xy 178.343796 -171.947585)
			(xy 178.399233 -171.953685) (xy 178.45319 -171.967791) (xy 178.504519 -171.989603) (xy 178.552125 -172.018657)
			(xy 178.594993 -172.054332) (xy 178.63221 -172.095869) (xy 178.662983 -172.142382) (xy 178.686655 -172.192879)
			(xy 178.702723 -172.246286) (xy 178.710843 -172.301462) (xy 178.711352 -172.329348) (xy 178.711088 -172.343826)
			(xy 178.885086 -172.343826) (xy 178.889157 -172.288204) (xy 178.901283 -172.233767) (xy 178.921206 -172.181676)
			(xy 178.948502 -172.133041) (xy 178.982588 -172.088898) (xy 179.022737 -172.050189) (xy 179.068095 -172.017738)
			(xy 179.117695 -171.992237) (xy 179.170479 -171.97423) (xy 179.225322 -171.9641) (xy 179.281056 -171.962063)
			(xy 179.336493 -171.968163) (xy 179.39045 -171.982269) (xy 179.441779 -172.004081) (xy 179.489385 -172.033135)
			(xy 179.532253 -172.06881) (xy 179.56947 -172.110347) (xy 179.600243 -172.15686) (xy 179.623915 -172.207357)
			(xy 179.639983 -172.260764) (xy 179.648103 -172.31594) (xy 179.648612 -172.343826) (xy 179.648103 -172.371712)
			(xy 179.639983 -172.426888) (xy 179.623915 -172.480295) (xy 179.600243 -172.530792) (xy 179.56947 -172.577305)
			(xy 179.532253 -172.618842) (xy 179.489385 -172.654517) (xy 179.441779 -172.683571) (xy 179.39045 -172.705383)
			(xy 179.336493 -172.719489) (xy 179.281056 -172.725589) (xy 179.225322 -172.723552) (xy 179.170479 -172.713422)
			(xy 179.117695 -172.695415) (xy 179.068095 -172.669914) (xy 179.022737 -172.637463) (xy 178.982588 -172.598754)
			(xy 178.948502 -172.554611) (xy 178.921206 -172.505976) (xy 178.901283 -172.453885) (xy 178.889157 -172.399448)
			(xy 178.885086 -172.343826) (xy 178.711088 -172.343826) (xy 178.710843 -172.357234) (xy 178.702723 -172.41241)
			(xy 178.686655 -172.465817) (xy 178.662983 -172.516314) (xy 178.63221 -172.562827) (xy 178.594993 -172.604364)
			(xy 178.552125 -172.640039) (xy 178.504519 -172.669093) (xy 178.45319 -172.690905) (xy 178.399233 -172.705011)
			(xy 178.343796 -172.711111) (xy 178.288062 -172.709074) (xy 178.233219 -172.698944) (xy 178.180435 -172.680937)
			(xy 178.130835 -172.655436) (xy 178.085477 -172.622985) (xy 178.045328 -172.584276) (xy 178.011242 -172.540133)
			(xy 177.983946 -172.491498) (xy 177.964023 -172.439407) (xy 177.951897 -172.38497) (xy 177.947826 -172.329348)
			(xy 171.578524 -172.329348) (xy 171.578524 -176.204372) (xy 183.126124 -176.204372) (xy 183.130195 -176.14875)
			(xy 183.142321 -176.094313) (xy 183.162244 -176.042222) (xy 183.18954 -175.993587) (xy 183.223626 -175.949444)
			(xy 183.263775 -175.910735) (xy 183.309133 -175.878284) (xy 183.358733 -175.852783) (xy 183.411517 -175.834776)
			(xy 183.46636 -175.824646) (xy 183.522094 -175.822609) (xy 183.577531 -175.828709) (xy 183.631488 -175.842815)
			(xy 183.682817 -175.864627) (xy 183.730423 -175.893681) (xy 183.773291 -175.929356) (xy 183.810508 -175.970893)
			(xy 183.841281 -176.017406) (xy 183.864953 -176.067903) (xy 183.881021 -176.12131) (xy 183.889141 -176.176486)
			(xy 183.88965 -176.204372) (xy 183.889141 -176.232258) (xy 183.881021 -176.287434) (xy 183.864953 -176.340841)
			(xy 183.841281 -176.391338) (xy 183.810508 -176.437851) (xy 183.773291 -176.479388) (xy 183.730423 -176.515063)
			(xy 183.682817 -176.544117) (xy 183.631488 -176.565929) (xy 183.577531 -176.580035) (xy 183.522094 -176.586135)
			(xy 183.46636 -176.584098) (xy 183.411517 -176.573968) (xy 183.358733 -176.555961) (xy 183.309133 -176.53046)
			(xy 183.263775 -176.498009) (xy 183.223626 -176.4593) (xy 183.18954 -176.415157) (xy 183.162244 -176.366522)
			(xy 183.142321 -176.314431) (xy 183.130195 -176.259994) (xy 183.126124 -176.204372) (xy 171.578524 -176.204372)
			(xy 171.578524 -177.061876) (xy 178.352702 -177.061876) (xy 178.356773 -177.006254) (xy 178.368899 -176.951817)
			(xy 178.388822 -176.899726) (xy 178.416118 -176.851091) (xy 178.450204 -176.806948) (xy 178.490353 -176.768239)
			(xy 178.535711 -176.735788) (xy 178.585311 -176.710287) (xy 178.638095 -176.69228) (xy 178.692938 -176.68215)
			(xy 178.748672 -176.680113) (xy 178.804109 -176.686213) (xy 178.858066 -176.700319) (xy 178.909395 -176.722131)
			(xy 178.957001 -176.751185) (xy 178.999869 -176.78686) (xy 179.037086 -176.828397) (xy 179.067859 -176.87491)
			(xy 179.091531 -176.925407) (xy 179.107599 -176.978814) (xy 179.115719 -177.03399) (xy 179.116228 -177.061876)
			(xy 179.115719 -177.089762) (xy 179.107599 -177.144938) (xy 179.091531 -177.198345) (xy 179.067859 -177.248842)
			(xy 179.037086 -177.295355) (xy 178.999869 -177.336892) (xy 178.957001 -177.372567) (xy 178.909395 -177.401621)
			(xy 178.858066 -177.423433) (xy 178.804109 -177.437539) (xy 178.748672 -177.443639) (xy 178.692938 -177.441602)
			(xy 178.638095 -177.431472) (xy 178.585311 -177.413465) (xy 178.535711 -177.387964) (xy 178.490353 -177.355513)
			(xy 178.450204 -177.316804) (xy 178.416118 -177.272661) (xy 178.388822 -177.224026) (xy 178.368899 -177.171935)
			(xy 178.356773 -177.117498) (xy 178.352702 -177.061876) (xy 171.578524 -177.061876) (xy 171.578524 -177.115724)
			(xy 171.578931 -177.125795) (xy 171.586664 -177.144393) (xy 171.59351 -177.151792) (xy 172.159433 -177.717704)
			(xy 180.770782 -177.717704) (xy 180.774853 -177.662082) (xy 180.786979 -177.607645) (xy 180.806902 -177.555554)
			(xy 180.834198 -177.506919) (xy 180.868284 -177.462776) (xy 180.908433 -177.424067) (xy 180.953791 -177.391616)
			(xy 181.003391 -177.366115) (xy 181.056175 -177.348108) (xy 181.111018 -177.337978) (xy 181.166752 -177.335941)
			(xy 181.222189 -177.342041) (xy 181.276146 -177.356147) (xy 181.327475 -177.377959) (xy 181.375081 -177.407013)
			(xy 181.417949 -177.442688) (xy 181.455166 -177.484225) (xy 181.485939 -177.530738) (xy 181.509611 -177.581235)
			(xy 181.525679 -177.634642) (xy 181.533799 -177.689818) (xy 181.534308 -177.717704) (xy 181.533799 -177.74559)
			(xy 181.525679 -177.800766) (xy 181.509611 -177.854173) (xy 181.485939 -177.90467) (xy 181.455166 -177.951183)
			(xy 181.417949 -177.99272) (xy 181.375081 -178.028395) (xy 181.327475 -178.057449) (xy 181.276146 -178.079261)
			(xy 181.222189 -178.093367) (xy 181.166752 -178.099467) (xy 181.111018 -178.09743) (xy 181.056175 -178.0873)
			(xy 181.003391 -178.069293) (xy 180.953791 -178.043792) (xy 180.908433 -178.011341) (xy 180.868284 -177.972632)
			(xy 180.834198 -177.928489) (xy 180.806902 -177.879854) (xy 180.786979 -177.827763) (xy 180.774853 -177.773326)
			(xy 180.770782 -177.717704) (xy 172.159433 -177.717704) (xy 172.803589 -178.361848) (xy 178.332382 -178.361848)
			(xy 178.336453 -178.306226) (xy 178.348579 -178.251789) (xy 178.368502 -178.199698) (xy 178.395798 -178.151063)
			(xy 178.429884 -178.10692) (xy 178.470033 -178.068211) (xy 178.515391 -178.03576) (xy 178.564991 -178.010259)
			(xy 178.617775 -177.992252) (xy 178.672618 -177.982122) (xy 178.728352 -177.980085) (xy 178.783789 -177.986185)
			(xy 178.837746 -178.000291) (xy 178.889075 -178.022103) (xy 178.936681 -178.051157) (xy 178.979549 -178.086832)
			(xy 179.016766 -178.128369) (xy 179.047539 -178.174882) (xy 179.071211 -178.225379) (xy 179.087279 -178.278786)
			(xy 179.095399 -178.333962) (xy 179.095908 -178.361848) (xy 179.095399 -178.389734) (xy 179.09012 -178.425602)
			(xy 181.640224 -178.425602) (xy 181.644295 -178.36998) (xy 181.656421 -178.315543) (xy 181.676344 -178.263452)
			(xy 181.70364 -178.214817) (xy 181.737726 -178.170674) (xy 181.777875 -178.131965) (xy 181.823233 -178.099514)
			(xy 181.872833 -178.074013) (xy 181.925617 -178.056006) (xy 181.98046 -178.045876) (xy 182.036194 -178.043839)
			(xy 182.091631 -178.049939) (xy 182.145588 -178.064045) (xy 182.196917 -178.085857) (xy 182.244523 -178.114911)
			(xy 182.287391 -178.150586) (xy 182.324608 -178.192123) (xy 182.355381 -178.238636) (xy 182.379053 -178.289133)
			(xy 182.395121 -178.34254) (xy 182.403241 -178.397716) (xy 182.40375 -178.425602) (xy 182.403241 -178.453488)
			(xy 182.395121 -178.508664) (xy 182.379053 -178.562071) (xy 182.355381 -178.612568) (xy 182.324608 -178.659081)
			(xy 182.287391 -178.700618) (xy 182.244523 -178.736293) (xy 182.196917 -178.765347) (xy 182.145588 -178.787159)
			(xy 182.091631 -178.801265) (xy 182.036194 -178.807365) (xy 181.98046 -178.805328) (xy 181.925617 -178.795198)
			(xy 181.872833 -178.777191) (xy 181.823233 -178.75169) (xy 181.777875 -178.719239) (xy 181.737726 -178.68053)
			(xy 181.70364 -178.636387) (xy 181.676344 -178.587752) (xy 181.656421 -178.535661) (xy 181.644295 -178.481224)
			(xy 181.640224 -178.425602) (xy 179.09012 -178.425602) (xy 179.087279 -178.44491) (xy 179.071211 -178.498317)
			(xy 179.047539 -178.548814) (xy 179.016766 -178.595327) (xy 178.979549 -178.636864) (xy 178.936681 -178.672539)
			(xy 178.889075 -178.701593) (xy 178.837746 -178.723405) (xy 178.783789 -178.737511) (xy 178.728352 -178.743611)
			(xy 178.672618 -178.741574) (xy 178.617775 -178.731444) (xy 178.564991 -178.713437) (xy 178.515391 -178.687936)
			(xy 178.470033 -178.655485) (xy 178.429884 -178.616776) (xy 178.395798 -178.572633) (xy 178.368502 -178.523998)
			(xy 178.348579 -178.471907) (xy 178.336453 -178.41747) (xy 178.332382 -178.361848) (xy 172.803589 -178.361848)
			(xy 174.162515 -179.720748) (xy 180.007766 -179.720748) (xy 180.011837 -179.665126) (xy 180.023963 -179.610689)
			(xy 180.043886 -179.558598) (xy 180.071182 -179.509963) (xy 180.105268 -179.46582) (xy 180.145417 -179.427111)
			(xy 180.190775 -179.39466) (xy 180.240375 -179.369159) (xy 180.293159 -179.351152) (xy 180.348002 -179.341022)
			(xy 180.403736 -179.338985) (xy 180.459173 -179.345085) (xy 180.51313 -179.359191) (xy 180.564459 -179.381003)
			(xy 180.612065 -179.410057) (xy 180.644782 -179.437284) (xy 181.43169 -179.437284) (xy 181.435761 -179.381662)
			(xy 181.447887 -179.327225) (xy 181.46781 -179.275134) (xy 181.495106 -179.226499) (xy 181.529192 -179.182356)
			(xy 181.569341 -179.143647) (xy 181.614699 -179.111196) (xy 181.664299 -179.085695) (xy 181.717083 -179.067688)
			(xy 181.771926 -179.057558) (xy 181.82766 -179.055521) (xy 181.883097 -179.061621) (xy 181.937054 -179.075727)
			(xy 181.988383 -179.097539) (xy 182.035989 -179.126593) (xy 182.078857 -179.162268) (xy 182.116074 -179.203805)
			(xy 182.146847 -179.250318) (xy 182.16448 -179.287932) (xy 183.426606 -179.287932) (xy 183.430677 -179.23231)
			(xy 183.442803 -179.177873) (xy 183.462726 -179.125782) (xy 183.490022 -179.077147) (xy 183.524108 -179.033004)
			(xy 183.564257 -178.994295) (xy 183.609615 -178.961844) (xy 183.659215 -178.936343) (xy 183.711999 -178.918336)
			(xy 183.766842 -178.908206) (xy 183.822576 -178.906169) (xy 183.878013 -178.912269) (xy 183.93197 -178.926375)
			(xy 183.983299 -178.948187) (xy 184.030905 -178.977241) (xy 184.073773 -179.012916) (xy 184.11099 -179.054453)
			(xy 184.141763 -179.100966) (xy 184.165435 -179.151463) (xy 184.181503 -179.20487) (xy 184.189623 -179.260046)
			(xy 184.190132 -179.287932) (xy 184.189623 -179.315818) (xy 184.181503 -179.370994) (xy 184.165435 -179.424401)
			(xy 184.141763 -179.474898) (xy 184.11099 -179.521411) (xy 184.073773 -179.562948) (xy 184.030905 -179.598623)
			(xy 183.983299 -179.627677) (xy 183.93197 -179.649489) (xy 183.878013 -179.663595) (xy 183.822576 -179.669695)
			(xy 183.766842 -179.667658) (xy 183.711999 -179.657528) (xy 183.659215 -179.639521) (xy 183.609615 -179.61402)
			(xy 183.564257 -179.581569) (xy 183.524108 -179.54286) (xy 183.490022 -179.498717) (xy 183.462726 -179.450082)
			(xy 183.442803 -179.397991) (xy 183.430677 -179.343554) (xy 183.426606 -179.287932) (xy 182.16448 -179.287932)
			(xy 182.170519 -179.300815) (xy 182.186587 -179.354222) (xy 182.194707 -179.409398) (xy 182.195216 -179.437284)
			(xy 182.194707 -179.46517) (xy 182.186587 -179.520346) (xy 182.170519 -179.573753) (xy 182.146847 -179.62425)
			(xy 182.116074 -179.670763) (xy 182.078857 -179.7123) (xy 182.035989 -179.747975) (xy 181.988383 -179.777029)
			(xy 181.937054 -179.798841) (xy 181.883097 -179.812947) (xy 181.82766 -179.819047) (xy 181.771926 -179.81701)
			(xy 181.717083 -179.80688) (xy 181.664299 -179.788873) (xy 181.614699 -179.763372) (xy 181.569341 -179.730921)
			(xy 181.529192 -179.692212) (xy 181.495106 -179.648069) (xy 181.46781 -179.599434) (xy 181.447887 -179.547343)
			(xy 181.435761 -179.492906) (xy 181.43169 -179.437284) (xy 180.644782 -179.437284) (xy 180.654933 -179.445732)
			(xy 180.69215 -179.487269) (xy 180.722923 -179.533782) (xy 180.746595 -179.584279) (xy 180.762663 -179.637686)
			(xy 180.770783 -179.692862) (xy 180.771292 -179.720748) (xy 180.770783 -179.748634) (xy 180.762663 -179.80381)
			(xy 180.746595 -179.857217) (xy 180.722923 -179.907714) (xy 180.69215 -179.954227) (xy 180.654933 -179.995764)
			(xy 180.612065 -180.031439) (xy 180.564459 -180.060493) (xy 180.51313 -180.082305) (xy 180.459173 -180.096411)
			(xy 180.403736 -180.102511) (xy 180.348002 -180.100474) (xy 180.293159 -180.090344) (xy 180.240375 -180.072337)
			(xy 180.190775 -180.046836) (xy 180.145417 -180.014385) (xy 180.105268 -179.975676) (xy 180.071182 -179.931533)
			(xy 180.043886 -179.882898) (xy 180.023963 -179.830807) (xy 180.011837 -179.77637) (xy 180.007766 -179.720748)
			(xy 174.162515 -179.720748) (xy 175.202919 -180.761132) (xy 182.748172 -180.761132) (xy 182.752243 -180.70551)
			(xy 182.764369 -180.651073) (xy 182.784292 -180.598982) (xy 182.811588 -180.550347) (xy 182.845674 -180.506204)
			(xy 182.885823 -180.467495) (xy 182.931181 -180.435044) (xy 182.980781 -180.409543) (xy 183.033565 -180.391536)
			(xy 183.088408 -180.381406) (xy 183.144142 -180.379369) (xy 183.199579 -180.385469) (xy 183.253536 -180.399575)
			(xy 183.304865 -180.421387) (xy 183.352471 -180.450441) (xy 183.395339 -180.486116) (xy 183.432556 -180.527653)
			(xy 183.463329 -180.574166) (xy 183.487001 -180.624663) (xy 183.503069 -180.67807) (xy 183.511189 -180.733246)
			(xy 183.511698 -180.761132) (xy 183.511189 -180.789018) (xy 183.503069 -180.844194) (xy 183.487001 -180.897601)
			(xy 183.463329 -180.948098) (xy 183.432556 -180.994611) (xy 183.395339 -181.036148) (xy 183.352471 -181.071823)
			(xy 183.304865 -181.100877) (xy 183.253536 -181.122689) (xy 183.199579 -181.136795) (xy 183.144142 -181.142895)
			(xy 183.088408 -181.140858) (xy 183.033565 -181.130728) (xy 182.980781 -181.112721) (xy 182.931181 -181.08722)
			(xy 182.885823 -181.054769) (xy 182.845674 -181.01606) (xy 182.811588 -180.971917) (xy 182.784292 -180.923282)
			(xy 182.764369 -180.871191) (xy 182.752243 -180.816754) (xy 182.748172 -180.761132) (xy 175.202919 -180.761132)
			(xy 179.409492 -184.967626) (xy 183.30494 -184.967626) (xy 183.309011 -184.912004) (xy 183.321137 -184.857567)
			(xy 183.34106 -184.805476) (xy 183.368356 -184.756841) (xy 183.402442 -184.712698) (xy 183.442591 -184.673989)
			(xy 183.487949 -184.641538) (xy 183.537549 -184.616037) (xy 183.590333 -184.59803) (xy 183.645176 -184.5879)
			(xy 183.70091 -184.585863) (xy 183.756347 -184.591963) (xy 183.810304 -184.606069) (xy 183.861633 -184.627881)
			(xy 183.909239 -184.656935) (xy 183.952107 -184.69261) (xy 183.989324 -184.734147) (xy 184.020097 -184.78066)
			(xy 184.043769 -184.831157) (xy 184.059837 -184.884564) (xy 184.067957 -184.93974) (xy 184.068466 -184.967626)
			(xy 184.067957 -184.995512) (xy 184.059837 -185.050688) (xy 184.043769 -185.104095) (xy 184.020097 -185.154592)
			(xy 183.989324 -185.201105) (xy 183.952107 -185.242642) (xy 183.909239 -185.278317) (xy 183.861633 -185.307371)
			(xy 183.810304 -185.329183) (xy 183.756347 -185.343289) (xy 183.70091 -185.349389) (xy 183.645176 -185.347352)
			(xy 183.590333 -185.337222) (xy 183.537549 -185.319215) (xy 183.487949 -185.293714) (xy 183.442591 -185.261263)
			(xy 183.402442 -185.222554) (xy 183.368356 -185.178411) (xy 183.34106 -185.129776) (xy 183.321137 -185.077685)
			(xy 183.309011 -185.023248) (xy 183.30494 -184.967626) (xy 179.409492 -184.967626) (xy 180.410779 -185.968894)
			(xy 183.9374 -185.968894) (xy 183.941471 -185.913272) (xy 183.953597 -185.858835) (xy 183.97352 -185.806744)
			(xy 184.000816 -185.758109) (xy 184.034902 -185.713966) (xy 184.075051 -185.675257) (xy 184.120409 -185.642806)
			(xy 184.170009 -185.617305) (xy 184.222793 -185.599298) (xy 184.277636 -185.589168) (xy 184.33337 -185.587131)
			(xy 184.388807 -185.593231) (xy 184.442764 -185.607337) (xy 184.494093 -185.629149) (xy 184.541699 -185.658203)
			(xy 184.584567 -185.693878) (xy 184.621784 -185.735415) (xy 184.652557 -185.781928) (xy 184.676229 -185.832425)
			(xy 184.692297 -185.885832) (xy 184.700417 -185.941008) (xy 184.700926 -185.968894) (xy 184.700417 -185.99678)
			(xy 184.692297 -186.051956) (xy 184.676229 -186.105363) (xy 184.652557 -186.15586) (xy 184.621784 -186.202373)
			(xy 184.584567 -186.24391) (xy 184.541699 -186.279585) (xy 184.494093 -186.308639) (xy 184.442764 -186.330451)
			(xy 184.388807 -186.344557) (xy 184.33337 -186.350657) (xy 184.277636 -186.34862) (xy 184.222793 -186.33849)
			(xy 184.170009 -186.320483) (xy 184.120409 -186.294982) (xy 184.075051 -186.262531) (xy 184.034902 -186.223822)
			(xy 184.000816 -186.179679) (xy 183.97352 -186.131044) (xy 183.953597 -186.078953) (xy 183.941471 -186.024516)
			(xy 183.9374 -185.968894) (xy 180.410779 -185.968894) (xy 182.143092 -187.701174) (xy 182.793384 -187.701174)
			(xy 182.797455 -187.645552) (xy 182.809581 -187.591115) (xy 182.829504 -187.539024) (xy 182.8568 -187.490389)
			(xy 182.890886 -187.446246) (xy 182.931035 -187.407537) (xy 182.976393 -187.375086) (xy 183.025993 -187.349585)
			(xy 183.078777 -187.331578) (xy 183.13362 -187.321448) (xy 183.189354 -187.319411) (xy 183.244791 -187.325511)
			(xy 183.298748 -187.339617) (xy 183.350077 -187.361429) (xy 183.397683 -187.390483) (xy 183.440551 -187.426158)
			(xy 183.477768 -187.467695) (xy 183.508541 -187.514208) (xy 183.532213 -187.564705) (xy 183.548281 -187.618112)
			(xy 183.556401 -187.673288) (xy 183.55691 -187.701174) (xy 183.556401 -187.72906) (xy 183.548281 -187.784236)
			(xy 183.532213 -187.837643) (xy 183.508541 -187.88814) (xy 183.477768 -187.934653) (xy 183.440551 -187.97619)
			(xy 183.397683 -188.011865) (xy 183.350077 -188.040919) (xy 183.298748 -188.062731) (xy 183.244791 -188.076837)
			(xy 183.189354 -188.082937) (xy 183.13362 -188.0809) (xy 183.078777 -188.07077) (xy 183.025993 -188.052763)
			(xy 182.976393 -188.027262) (xy 182.931035 -187.994811) (xy 182.890886 -187.956102) (xy 182.8568 -187.911959)
			(xy 182.829504 -187.863324) (xy 182.809581 -187.811233) (xy 182.797455 -187.756796) (xy 182.793384 -187.701174)
			(xy 182.143092 -187.701174) (xy 184.967626 -190.525654) (xy 184.990551 -190.549195) (xy 185.031516 -190.600574)
			(xy 185.066471 -190.656218) (xy 185.094976 -190.715425) (xy 185.116672 -190.777452) (xy 185.131287 -190.841518)
			(xy 185.138636 -190.906818) (xy 185.139076 -190.939674) (xy 185.139076 -207.264) (xy 185.799982 -207.264)
			(xy 185.804053 -207.208378) (xy 185.816179 -207.153941) (xy 185.836102 -207.10185) (xy 185.863398 -207.053215)
			(xy 185.897484 -207.009072) (xy 185.937633 -206.970363) (xy 185.982991 -206.937912) (xy 186.032591 -206.912411)
			(xy 186.085375 -206.894404) (xy 186.140218 -206.884274) (xy 186.195952 -206.882237) (xy 186.251389 -206.888337)
			(xy 186.305346 -206.902443) (xy 186.356675 -206.924255) (xy 186.404281 -206.953309) (xy 186.447149 -206.988984)
			(xy 186.484366 -207.030521) (xy 186.515139 -207.077034) (xy 186.538811 -207.127531) (xy 186.554879 -207.180938)
			(xy 186.562999 -207.236114) (xy 186.563508 -207.264) (xy 186.562999 -207.291886) (xy 186.554879 -207.347062)
			(xy 186.538811 -207.400469) (xy 186.515139 -207.450966) (xy 186.484366 -207.497479) (xy 186.447149 -207.539016)
			(xy 186.404281 -207.574691) (xy 186.356675 -207.603745) (xy 186.305346 -207.625557) (xy 186.251389 -207.639663)
			(xy 186.195952 -207.645763) (xy 186.140218 -207.643726) (xy 186.085375 -207.633596) (xy 186.032591 -207.615589)
			(xy 185.982991 -207.590088) (xy 185.937633 -207.557637) (xy 185.897484 -207.518928) (xy 185.863398 -207.474785)
			(xy 185.836102 -207.42615) (xy 185.816179 -207.374059) (xy 185.804053 -207.319622) (xy 185.799982 -207.264)
			(xy 185.139076 -207.264) (xy 185.139076 -210.573954) (xy 185.262451 -210.573954) (xy 185.262451 -210.519446)
			(xy 185.270209 -210.465493) (xy 185.285566 -210.413193) (xy 185.30821 -210.363611) (xy 185.337681 -210.317756)
			(xy 185.373377 -210.276563) (xy 185.414572 -210.240869) (xy 185.460428 -210.211401) (xy 185.510011 -210.188759)
			(xy 185.562312 -210.173405) (xy 185.616266 -210.16565) (xy 185.64352 -210.165188) (xy 185.670448 -210.165634)
			(xy 185.723767 -210.173222) (xy 185.775489 -210.188231) (xy 185.824588 -210.210363) (xy 185.870087 -210.239177)
			(xy 185.911084 -210.274102) (xy 185.92927 -210.293966) (xy 185.936382 -210.30184) (xy 185.955432 -210.31073)
			(xy 186.051952 -210.312508) (xy 186.071256 -210.304634) (xy 186.078622 -210.297014) (xy 186.078876 -210.29676)
			(xy 186.096939 -210.278457) (xy 186.137103 -210.246347) (xy 186.181221 -210.21993) (xy 186.228491 -210.199687)
			(xy 186.278054 -210.185984) (xy 186.329009 -210.179071) (xy 186.35472 -210.17865) (xy 186.381967 -210.179222)
			(xy 186.435907 -210.186979) (xy 186.488193 -210.202335) (xy 186.537763 -210.224974) (xy 186.583605 -210.254438)
			(xy 186.624789 -210.290126) (xy 186.660474 -210.331311) (xy 186.689935 -210.377155) (xy 186.712572 -210.426725)
			(xy 186.727925 -210.479013) (xy 186.73568 -210.532953) (xy 186.73568 -210.587447) (xy 186.727925 -210.641387)
			(xy 186.712572 -210.693675) (xy 186.689935 -210.743245) (xy 186.660474 -210.789089) (xy 186.624789 -210.830274)
			(xy 186.583605 -210.865962) (xy 186.537763 -210.895426) (xy 186.488193 -210.918065) (xy 186.435907 -210.933421)
			(xy 186.381967 -210.941178) (xy 186.35472 -210.941666) (xy 186.327794 -210.941175) (xy 186.274478 -210.933593)
			(xy 186.222757 -210.918592) (xy 186.173659 -210.896469) (xy 186.128158 -210.867664) (xy 186.087158 -210.832748)
			(xy 186.06897 -210.812888) (xy 186.061858 -210.805014) (xy 186.042808 -210.796124) (xy 185.946288 -210.794346)
			(xy 185.926984 -210.80222) (xy 185.919618 -210.80984) (xy 185.919364 -210.810094) (xy 185.90134 -210.828436)
			(xy 185.861166 -210.860541) (xy 185.81704 -210.886951) (xy 185.769763 -210.907188) (xy 185.720194 -210.920883)
			(xy 185.669233 -210.927787) (xy 185.64352 -210.928204) (xy 185.616266 -210.92775) (xy 185.562312 -210.919995)
			(xy 185.510011 -210.904641) (xy 185.460428 -210.881999) (xy 185.414572 -210.852531) (xy 185.373377 -210.816837)
			(xy 185.337681 -210.775644) (xy 185.30821 -210.729789) (xy 185.285566 -210.680207) (xy 185.270209 -210.627907)
			(xy 185.262451 -210.573954) (xy 185.139076 -210.573954) (xy 185.139076 -216.88806) (xy 185.727084 -216.88806)
			(xy 185.731155 -216.832438) (xy 185.743281 -216.778001) (xy 185.763204 -216.72591) (xy 185.7905 -216.677275)
			(xy 185.824586 -216.633132) (xy 185.864735 -216.594423) (xy 185.910093 -216.561972) (xy 185.959693 -216.536471)
			(xy 186.012477 -216.518464) (xy 186.06732 -216.508334) (xy 186.123054 -216.506297) (xy 186.178491 -216.512397)
			(xy 186.232448 -216.526503) (xy 186.283777 -216.548315) (xy 186.331383 -216.577369) (xy 186.374251 -216.613044)
			(xy 186.411468 -216.654581) (xy 186.442241 -216.701094) (xy 186.465913 -216.751591) (xy 186.481981 -216.804998)
			(xy 186.490101 -216.860174) (xy 186.49061 -216.88806) (xy 186.490101 -216.915946) (xy 186.481981 -216.971122)
			(xy 186.465913 -217.024529) (xy 186.442241 -217.075026) (xy 186.411468 -217.121539) (xy 186.374251 -217.163076)
			(xy 186.331383 -217.198751) (xy 186.283777 -217.227805) (xy 186.232448 -217.249617) (xy 186.178491 -217.263723)
			(xy 186.123054 -217.269823) (xy 186.06732 -217.267786) (xy 186.012477 -217.257656) (xy 185.959693 -217.239649)
			(xy 185.910093 -217.214148) (xy 185.864735 -217.181697) (xy 185.824586 -217.142988) (xy 185.7905 -217.098845)
			(xy 185.763204 -217.05021) (xy 185.743281 -216.998119) (xy 185.731155 -216.943682) (xy 185.727084 -216.88806)
			(xy 185.139076 -216.88806) (xy 185.139076 -224.411794) (xy 185.139484 -224.421866) (xy 185.147215 -224.440464)
			(xy 185.154062 -224.447862) (xy 185.502042 -224.795588) (xy 185.524925 -224.819167) (xy 185.565891 -224.870541)
			(xy 185.600848 -224.926178) (xy 185.629356 -224.985379) (xy 185.651056 -225.047399) (xy 185.665676 -225.11146)
			(xy 185.673032 -225.176754) (xy 185.673492 -225.209608) (xy 185.673492 -225.209862) (xy 185.673087 -225.241633)
			(xy 185.666215 -225.304803) (xy 185.652548 -225.366858) (xy 185.632246 -225.42707) (xy 185.605548 -225.484731)
			(xy 185.572766 -225.539165) (xy 185.553858 -225.5647) (xy 185.548245 -225.572834) (xy 185.543132 -225.591907)
			(xy 185.545605 -225.611497) (xy 185.550048 -225.620326) (xy 185.568051 -225.653367) (xy 185.59635 -225.723089)
			(xy 185.615487 -225.795861) (xy 185.625148 -225.870485) (xy 185.62574 -225.908108) (xy 185.62574 -226.489768)
			(xy 185.62518 -226.525175) (xy 185.616646 -226.595473) (xy 185.599698 -226.66423) (xy 185.574583 -226.730441)
			(xy 185.541669 -226.793141) (xy 185.501434 -226.851415) (xy 185.454467 -226.904413) (xy 185.401453 -226.951362)
			(xy 185.343165 -226.991575) (xy 185.280453 -227.024468) (xy 185.214233 -227.049559) (xy 185.145471 -227.066483)
			(xy 185.075169 -227.074993) (xy 185.039762 -227.075492) (xy 185.006217 -227.075081) (xy 184.939564 -227.067454)
			(xy 184.874218 -227.052259) (xy 184.811038 -227.029695) (xy 184.75085 -227.000058) (xy 184.694444 -226.963736)
			(xy 184.64256 -226.921206) (xy 184.618884 -226.897438) (xy 184.609232 -226.887532) (xy 184.582308 -226.880166)
			(xy 184.469532 -226.911408) (xy 184.450482 -226.93122) (xy 184.44718 -226.944936) (xy 184.440167 -226.972516)
			(xy 184.41915 -227.025397) (xy 184.390514 -227.07457) (xy 184.354894 -227.118947) (xy 184.31308 -227.157542)
			(xy 184.265998 -227.189501) (xy 184.214693 -227.214115) (xy 184.160301 -227.230838) (xy 184.10403 -227.239299)
			(xy 184.075578 -227.23983) (xy 184.048669 -227.239329) (xy 183.995387 -227.23175) (xy 183.943699 -227.21676)
			(xy 183.894629 -227.194657) (xy 183.849152 -227.165878) (xy 183.808169 -227.130995) (xy 183.772494 -227.0907)
			(xy 183.742835 -227.045792) (xy 183.719779 -226.997162) (xy 183.711342 -226.971606) (xy 183.711342 -226.971352)
			(xy 183.709366 -226.965658) (xy 183.703067 -226.955383) (xy 183.698896 -226.951032) (xy 183.318404 -226.57054)
			(xy 183.300375 -226.551766) (xy 183.269795 -226.50965) (xy 183.246167 -226.463274) (xy 183.230071 -226.413778)
			(xy 183.221904 -226.362375) (xy 183.221376 -226.336352) (xy 183.221376 -221.917006) (xy 183.220954 -221.906936)
			(xy 183.213232 -221.888338) (xy 183.20639 -221.880938) (xy 182.77205 -221.446852) (xy 182.753967 -221.428044)
			(xy 182.723279 -221.385853) (xy 182.699573 -221.339379) (xy 182.683433 -221.289768) (xy 182.675258 -221.238241)
			(xy 182.674768 -221.212156) (xy 182.674768 -220.500448) (xy 182.67528 -220.474362) (xy 182.68344 -220.422831)
			(xy 182.699566 -220.373214) (xy 182.723261 -220.326733) (xy 182.75394 -220.284534) (xy 182.77205 -220.265752)
			(xy 183.119014 -219.919042) (xy 183.12583 -219.911623) (xy 183.133563 -219.893038) (xy 183.134 -219.882974)
			(xy 183.134 -209.014568) (xy 183.133618 -209.004493) (xy 183.12587 -208.985894) (xy 183.119014 -208.9785)
			(xy 173.498764 -199.358504) (xy 173.483656 -199.342884) (xy 173.45721 -199.308401) (xy 173.435499 -199.270757)
			(xy 173.426882 -199.250808) (xy 162.122612 -171.960286) (xy 162.116574 -171.945164) (xy 162.107159 -171.913992)
			(xy 162.103816 -171.898056) (xy 159.76473 -160.139126) (xy 159.761748 -160.123164) (xy 159.758569 -160.090847)
			(xy 159.75838 -160.07461) (xy 159.75838 -150.337012) (xy 159.757954 -150.326943) (xy 159.750234 -150.308345)
			(xy 159.743394 -150.300944) (xy 158.082742 -148.640546) (xy 158.064655 -148.621742) (xy 158.033968 -148.57955)
			(xy 158.010262 -148.533075) (xy 157.994124 -148.483463) (xy 157.98595 -148.431936) (xy 157.98546 -148.40585)
			(xy 157.98546 -121.96318) (xy 157.985056 -121.953108) (xy 157.977321 -121.93451) (xy 157.970474 -121.927112)
			(xy 154.02306 -117.979444) (xy 154.015027 -117.97217) (xy 153.994777 -117.96452) (xy 153.983944 -117.964712)
			(xy 153.896822 -117.970046) (xy 153.877518 -117.980206) (xy 153.870914 -117.988842) (xy 153.852726 -118.011328)
			(xy 153.810704 -118.051061) (xy 153.763168 -118.083998) (xy 153.711207 -118.109386) (xy 153.656009 -118.126642)
			(xy 153.59884 -118.135372) (xy 153.569924 -118.135908) (xy 153.542672 -118.135422) (xy 153.488722 -118.127669)
			(xy 153.436424 -118.112316) (xy 153.386844 -118.089676) (xy 153.340991 -118.06021) (xy 153.299798 -118.024519)
			(xy 153.264104 -117.983328) (xy 153.234636 -117.937477) (xy 153.211993 -117.887898) (xy 153.196636 -117.835602)
			(xy 153.188879 -117.781652) (xy 153.188416 -117.7544) (xy 153.188928 -117.725483) (xy 153.197658 -117.668311)
			(xy 153.214917 -117.613112) (xy 153.240309 -117.56115) (xy 153.273254 -117.513616) (xy 153.312996 -117.4716)
			(xy 153.335482 -117.45341) (xy 153.344118 -117.446806) (xy 153.354278 -117.427502) (xy 153.359612 -117.34038)
			(xy 153.359804 -117.329543) (xy 153.352176 -117.309279) (xy 153.34488 -117.301264) (xy 152.932638 -116.889276)
			(xy 152.928253 -116.885151) (xy 152.917983 -116.878871) (xy 152.912318 -116.87683) (xy 152.91181 -116.87683)
			(xy 152.886257 -116.868408) (xy 152.837653 -116.845333) (xy 152.792773 -116.815659) (xy 152.752506 -116.779975)
			(xy 152.717652 -116.738988) (xy 152.688901 -116.69351) (xy 152.666824 -116.644445) (xy 152.651858 -116.592765)
			(xy 152.6443 -116.539496) (xy 152.64384 -116.512594) (xy 149.792246 -116.512594) (xy 149.76855 -116.549652)
			(xy 149.714755 -116.619361) (xy 149.685248 -116.65204) (xy 149.67945 -116.658919) (xy 149.672686 -116.675578)
			(xy 149.67204 -116.684552) (xy 149.669753 -116.72836) (xy 149.65845 -116.81536) (xy 149.639555 -116.901033)
			(xy 149.613216 -116.984717) (xy 149.596856 -117.02542) (xy 149.407372 -117.483382) (xy 149.390095 -117.52388)
			(xy 149.349389 -117.601959) (xy 149.301954 -117.676143) (xy 149.248159 -117.745853) (xy 149.21865 -117.77853)
			(xy 149.21285 -117.785409) (xy 149.206083 -117.802067) (xy 149.205442 -117.811042) (xy 149.203155 -117.854851)
			(xy 149.191853 -117.941851) (xy 149.172959 -118.027524) (xy 149.146621 -118.111208) (xy 149.130258 -118.15191)
			(xy 148.940774 -118.609872) (xy 148.923497 -118.65037) (xy 148.882792 -118.72845) (xy 148.835358 -118.802635)
			(xy 148.781564 -118.872345) (xy 148.752052 -118.90502) (xy 148.74625 -118.911898) (xy 148.73948 -118.928557)
			(xy 148.738844 -118.937532) (xy 148.736558 -118.981341) (xy 148.725256 -119.068341) (xy 148.706364 -119.154014)
			(xy 148.680026 -119.237699) (xy 148.66366 -119.2784) (xy 148.522436 -119.62003) (xy 148.518447 -119.631086)
			(xy 148.519952 -119.654515) (xy 148.531745 -119.674816) (xy 148.541232 -119.681752) (xy 148.556218 -119.691912)
			(xy 148.592286 -119.688356) (xy 149.460712 -118.81993) (xy 149.499477 -118.782186) (xy 149.583869 -118.714471)
			(xy 149.629114 -118.684802) (xy 149.63013 -118.684294) (xy 149.665135 -118.661584) (xy 149.738277 -118.621411)
			(xy 149.814519 -118.587489) (xy 149.893329 -118.560056) (xy 149.974155 -118.539303) (xy 150.056433 -118.525375)
			(xy 150.139586 -118.518371) (xy 150.18131 -118.517924) (xy 150.501096 -118.517924) (xy 150.510818 -118.517442)
			(xy 150.528839 -118.510128) (xy 150.536148 -118.5037) (xy 150.567016 -118.474783) (xy 150.632868 -118.421689)
			(xy 150.702978 -118.374362) (xy 150.776843 -118.33314) (xy 150.853934 -118.29832) (xy 150.933696 -118.270153)
			(xy 151.015556 -118.24884) (xy 151.098927 -118.234534) (xy 151.18321 -118.227339) (xy 151.225504 -118.22684)
			(xy 151.272193 -118.22739) (xy 151.365161 -118.236131) (xy 151.456904 -118.253527) (xy 151.546618 -118.279426)
			(xy 151.633518 -118.313601) (xy 151.716841 -118.355751) (xy 151.795858 -118.405509) (xy 151.869876 -118.462437)
			(xy 151.938246 -118.526037) (xy 152.00037 -118.595751) (xy 152.055702 -118.670969) (xy 152.080214 -118.71071)
			(xy 152.082809 -118.714689) (xy 152.0892 -118.721717) (xy 152.092914 -118.72468) (xy 152.115541 -118.742864)
			(xy 152.155549 -118.784919) (xy 152.188725 -118.83255) (xy 152.214305 -118.884655) (xy 152.231696 -118.940035)
			(xy 152.240499 -118.997409) (xy 152.240996 -119.026432) (xy 152.240996 -119.027194) (xy 152.240492 -119.056559)
			(xy 152.231555 -119.114603) (xy 152.223216 -119.142764) (xy 152.221871 -119.147272) (xy 152.220714 -119.156607)
			(xy 152.22093 -119.161306) (xy 152.221812 -119.177039) (xy 152.222702 -119.208541) (xy 152.222708 -119.224298)
			(xy 152.222274 -119.266666) (xy 152.215087 -119.351095) (xy 152.200757 -119.43461) (xy 152.179387 -119.516606)
			(xy 152.151131 -119.596491) (xy 152.134062 -119.63527) (xy 152.130091 -119.645311) (xy 152.130091 -119.666885)
			(xy 152.134062 -119.676926) (xy 152.151105 -119.715715) (xy 152.179339 -119.795604) (xy 152.200701 -119.877598)
			(xy 152.215037 -119.961108) (xy 152.222244 -120.045532) (xy 152.222708 -120.087898) (xy 152.222701 -120.103719)
			(xy 152.221812 -120.135348) (xy 152.22093 -120.151144) (xy 152.220764 -120.155841) (xy 152.22192 -120.165168)
			(xy 152.223216 -120.169686) (xy 152.230081 -120.192512) (xy 152.238736 -120.239386) (xy 152.240488 -120.263158)
			(xy 152.240488 -120.264174) (xy 152.240742 -120.271794) (xy 152.24125 -120.280938) (xy 152.247346 -120.296686)
			(xy 152.25268 -120.303036) (xy 152.262586 -120.314212) (xy 152.263348 -120.314974) (xy 152.266142 -120.318276)
			(xy 152.271984 -120.324372) (xy 153.143204 -120.324372) (xy 153.152926 -120.323889) (xy 153.170949 -120.316579)
			(xy 153.178256 -120.310148) (xy 153.209123 -120.281227) (xy 153.274971 -120.228125) (xy 153.34508 -120.180788)
			(xy 153.418944 -120.139558) (xy 153.496034 -120.104729) (xy 153.575796 -120.076553) (xy 153.657658 -120.055231)
			(xy 153.741031 -120.040917) (xy 153.825316 -120.033714) (xy 153.867612 -120.033288) (xy 153.914303 -120.033833)
			(xy 154.007275 -120.042567) (xy 154.099022 -120.059957) (xy 154.188742 -120.085851) (xy 154.275646 -120.120021)
			(xy 154.358975 -120.162169) (xy 154.437997 -120.211924) (xy 154.512019 -120.268852) (xy 154.580394 -120.332452)
			(xy 154.642521 -120.402167) (xy 154.697856 -120.477387) (xy 154.722322 -120.517158) (xy 154.72492 -120.521135)
			(xy 154.731315 -120.528157) (xy 154.735022 -120.531128) (xy 154.757646 -120.549313) (xy 154.797648 -120.59137)
			(xy 154.830818 -120.639002) (xy 154.85639 -120.691108) (xy 154.873774 -120.746486) (xy 154.882569 -120.803859)
			(xy 154.883104 -120.83288) (xy 154.883104 -120.833642) (xy 154.882604 -120.863008) (xy 154.873675 -120.921054)
			(xy 154.865324 -120.949212) (xy 154.863983 -120.95372) (xy 154.862836 -120.963055) (xy 154.863038 -120.967754)
			(xy 154.86392 -120.983487) (xy 154.864808 -121.014989) (xy 154.864816 -121.030746) (xy 154.86438 -121.073113)
			(xy 154.857189 -121.157542) (xy 154.842855 -121.241055) (xy 154.821482 -121.323049) (xy 154.793223 -121.402932)
			(xy 154.77617 -121.441718) (xy 154.772214 -121.45176) (xy 154.772232 -121.473323) (xy 154.77617 -121.483374)
			(xy 154.793212 -121.522163) (xy 154.821445 -121.602052) (xy 154.842805 -121.684046) (xy 154.857139 -121.767556)
			(xy 154.864342 -121.851981) (xy 154.864816 -121.894346) (xy 154.864817 -121.910294) (xy 154.863928 -121.942177)
			(xy 154.863038 -121.9581) (xy 154.862843 -121.962661) (xy 154.863859 -121.971733) (xy 154.86507 -121.976134)
			(xy 154.869896 -121.992644) (xy 154.869896 -121.993152) (xy 154.873414 -122.006496) (xy 154.878753 -122.033573)
			(xy 154.880564 -122.047254) (xy 154.881834 -122.059446) (xy 154.883358 -122.091958) (xy 154.882797 -122.121158)
			(xy 154.873884 -122.178873) (xy 154.856276 -122.234555) (xy 154.830385 -122.286901) (xy 154.796816 -122.334688)
			(xy 154.756353 -122.376798) (xy 154.733498 -122.39498) (xy 154.73299 -122.395488) (xy 154.727656 -122.399298)
			(xy 154.705382 -122.436343) (xy 154.655339 -122.506834) (xy 154.599382 -122.572729) (xy 154.537931 -122.633532)
			(xy 154.471447 -122.688787) (xy 154.40043 -122.738079) (xy 154.325412 -122.781038) (xy 154.246956 -122.817342)
			(xy 154.165652 -122.846718) (xy 154.082111 -122.868945) (xy 153.996959 -122.883857) (xy 153.910836 -122.891342)
			(xy 153.867612 -122.891804) (xy 153.825301 -122.891356) (xy 153.740984 -122.884187) (xy 153.657577 -122.869899)
			(xy 153.575682 -122.848594) (xy 153.495886 -122.820427) (xy 153.418763 -122.785599) (xy 153.34487 -122.744362)
			(xy 153.274736 -122.697011) (xy 153.208867 -122.643888) (xy 153.178002 -122.614944) (xy 153.170636 -122.607832)
			(xy 153.152856 -122.60072) (xy 153.123392 -122.60072) (xy 153.11374 -122.605038) (xy 153.075711 -122.621318)
			(xy 152.997493 -122.648262) (xy 152.917312 -122.668638) (xy 152.83572 -122.682306) (xy 152.753276 -122.689173)
			(xy 152.711912 -122.68962) (xy 152.280874 -122.68962) (xy 152.277826 -122.692668) (xy 152.225502 -122.747786)
			(xy 152.222708 -122.752358) (xy 152.220676 -122.75566) (xy 152.220676 -122.755914) (xy 152.221692 -122.77471)
			(xy 152.222708 -122.82424) (xy 152.222272 -122.866607) (xy 152.215082 -122.951036) (xy 152.200748 -123.034549)
			(xy 152.179375 -123.116543) (xy 152.151117 -123.196427) (xy 152.134062 -123.235212) (xy 152.130101 -123.245253)
			(xy 152.130116 -123.266819) (xy 152.134062 -123.276868) (xy 152.151103 -123.315657) (xy 152.179334 -123.395547)
			(xy 152.200693 -123.477541) (xy 152.215025 -123.561051) (xy 152.222228 -123.645475) (xy 152.222708 -123.68784)
			(xy 152.222702 -123.703661) (xy 152.221814 -123.73529) (xy 152.22093 -123.751086) (xy 152.220758 -123.755784)
			(xy 152.221905 -123.765114) (xy 152.223216 -123.769628) (xy 152.231554 -123.797788) (xy 152.24048 -123.855834)
			(xy 152.240996 -123.885198) (xy 152.240996 -123.886976) (xy 152.240664 -123.90792) (xy 152.235949 -123.949544)
			(xy 152.231598 -123.970034) (xy 152.230628 -123.974734) (xy 152.230244 -123.984322) (xy 152.230836 -123.989084)
			(xy 152.23194 -123.995028) (xy 152.236558 -124.006198) (xy 152.23998 -124.011182) (xy 152.24506 -124.017786)
			(xy 152.272238 -124.039376) (xy 152.281646 -124.046168) (xy 152.304273 -124.051197) (xy 152.315672 -124.049028)
			(xy 152.328372 -124.04598) (xy 152.333706 -124.043186) (xy 152.376194 -124.022371) (xy 152.464356 -123.988017)
			(xy 152.509728 -123.974606) (xy 152.561592 -123.960688) (xy 152.667493 -123.942869) (xy 152.721056 -123.939046)
			(xy 152.726644 -123.938284) (xy 152.767804 -123.931825) (xy 152.850844 -123.92496) (xy 152.892506 -123.924568)
			(xy 153.152856 -123.924568) (xy 153.170636 -123.917456) (xy 153.178002 -123.910344) (xy 153.208875 -123.88141)
			(xy 153.274741 -123.828285) (xy 153.344873 -123.780933) (xy 153.418766 -123.739696) (xy 153.495887 -123.70487)
			(xy 153.575683 -123.676705) (xy 153.657579 -123.655405) (xy 153.740985 -123.641122) (xy 153.825302 -123.63396)
			(xy 153.867612 -123.633484) (xy 153.914303 -123.634029) (xy 154.007275 -123.642763) (xy 154.099022 -123.660153)
			(xy 154.188742 -123.686047) (xy 154.275647 -123.720217) (xy 154.358975 -123.762364) (xy 154.437997 -123.81212)
			(xy 154.51202 -123.869047) (xy 154.580395 -123.932647) (xy 154.642522 -124.002363) (xy 154.697858 -124.077582)
			(xy 154.722322 -124.117354) (xy 154.72492 -124.121331) (xy 154.731315 -124.128353) (xy 154.735022 -124.131324)
			(xy 154.757646 -124.149509) (xy 154.797649 -124.191566) (xy 154.830819 -124.239197) (xy 154.856392 -124.291303)
			(xy 154.873776 -124.346682) (xy 154.882572 -124.404054) (xy 154.883104 -124.433076) (xy 154.883104 -124.433838)
			(xy 154.882604 -124.463204) (xy 154.873676 -124.521251) (xy 154.865324 -124.549408) (xy 154.863983 -124.553916)
			(xy 154.862834 -124.563251) (xy 154.863038 -124.56795) (xy 154.86392 -124.583683) (xy 154.864808 -124.615185)
			(xy 154.864816 -124.630942) (xy 154.86438 -124.673309) (xy 154.85719 -124.757738) (xy 154.842856 -124.841251)
			(xy 154.821483 -124.923245) (xy 154.793225 -125.003128) (xy 154.77617 -125.041914) (xy 154.772213 -125.051956)
			(xy 154.77223 -125.07352) (xy 154.77617 -125.08357) (xy 154.793213 -125.122359) (xy 154.821446 -125.202248)
			(xy 154.842806 -125.284242) (xy 154.85714 -125.367752) (xy 154.864343 -125.452177) (xy 154.864816 -125.494542)
			(xy 154.864817 -125.51049) (xy 154.863929 -125.542373) (xy 154.863038 -125.558296) (xy 154.862843 -125.562857)
			(xy 154.863858 -125.571929) (xy 154.86507 -125.57633) (xy 154.869896 -125.59284) (xy 154.869896 -125.593348)
			(xy 154.873415 -125.606692) (xy 154.878753 -125.633769) (xy 154.880564 -125.64745) (xy 154.881834 -125.659642)
			(xy 154.883358 -125.692154) (xy 154.882797 -125.721354) (xy 154.873885 -125.779069) (xy 154.856278 -125.834751)
			(xy 154.830387 -125.887098) (xy 154.796818 -125.934885) (xy 154.756355 -125.976996) (xy 154.733498 -125.995176)
			(xy 154.73299 -125.995684) (xy 154.727656 -125.999494) (xy 154.705382 -126.03654) (xy 154.655339 -126.107031)
			(xy 154.599383 -126.172925) (xy 154.537932 -126.233729) (xy 154.471448 -126.288984) (xy 154.40043 -126.338276)
			(xy 154.325412 -126.381236) (xy 154.246957 -126.41754) (xy 154.165653 -126.446916) (xy 154.082111 -126.469143)
			(xy 153.996959 -126.484055) (xy 153.910836 -126.49154) (xy 153.867612 -126.492) (xy 153.823398 -126.491488)
			(xy 153.735322 -126.48359) (xy 153.648291 -126.467925) (xy 153.562989 -126.444618) (xy 153.480085 -126.413851)
			(xy 153.40023 -126.375865) (xy 153.361898 -126.353824) (xy 153.36139 -126.353824) (xy 153.346658 -126.345188)
			(xy 153.334212 -126.34595) (xy 153.308812 -126.351792) (xy 153.299632 -126.354143) (xy 153.283838 -126.364587)
			(xy 153.278078 -126.372112) (xy 153.261822 -126.394464) (xy 153.240669 -126.422135) (xy 153.195033 -126.474762)
			(xy 153.170636 -126.49962) (xy 152.857962 -126.812294) (xy 152.841464 -126.828611) (xy 152.80716 -126.859866)
			(xy 152.789382 -126.874778) (xy 152.783794 -126.87935) (xy 152.38857 -127.470662) (xy 152.386792 -127.48133)
			(xy 152.379208 -127.522011) (xy 152.358167 -127.602049) (xy 152.33057 -127.680071) (xy 152.296605 -127.755539)
			(xy 152.256508 -127.827934) (xy 152.233884 -127.862584) (xy 152.225248 -127.875284) (xy 152.246781 -127.890597)
			(xy 152.285811 -127.926212) (xy 152.319547 -127.966877) (xy 152.347342 -128.011813) (xy 152.368664 -128.060157)
			(xy 152.383103 -128.110984) (xy 152.390383 -128.163317) (xy 152.390856 -128.189736) (xy 152.390368 -128.216987)
			(xy 152.382607 -128.270933) (xy 152.36725 -128.323226) (xy 152.344607 -128.372802) (xy 152.315141 -128.418651)
			(xy 152.27945 -128.459841) (xy 152.238261 -128.495533) (xy 152.192413 -128.525001) (xy 152.142838 -128.547645)
			(xy 152.090545 -128.563005) (xy 152.036599 -128.570767) (xy 152.009348 -128.571244) (xy 152.009094 -128.571244)
			(xy 151.981879 -128.570765) (xy 151.928007 -128.562981) (xy 151.875794 -128.5476) (xy 151.850852 -128.5367)
			(xy 151.850344 -128.5367) (xy 151.846534 -128.534922) (xy 151.82596 -128.534668) (xy 151.748998 -128.565656)
			(xy 151.739722 -128.569906) (xy 151.725307 -128.58432) (xy 151.721058 -128.593596) (xy 151.701502 -128.639778)
			(xy 151.654422 -128.728338) (xy 151.627078 -128.77038) (xy 151.386794 -129.12979) (xy 151.36109 -129.167327)
			(xy 151.303847 -129.238048) (xy 151.272494 -129.271014) (xy 151.26611 -129.278063) (xy 151.258664 -129.295546)
			(xy 151.258149 -129.314542) (xy 151.261064 -129.323592) (xy 151.292052 -129.409698) (xy 151.295636 -129.418468)
			(xy 151.308089 -129.43273) (xy 151.324853 -129.441529) (xy 151.334216 -129.442972) (xy 151.379789 -129.44851)
			(xy 151.46974 -129.466887) (xy 151.557622 -129.493453) (xy 151.642692 -129.527982) (xy 151.724228 -129.570182)
			(xy 151.801541 -129.619696) (xy 151.873977 -129.676105) (xy 151.940923 -129.738932) (xy 152.001813 -129.807645)
			(xy 152.056131 -129.881663) (xy 152.080214 -129.920746) (xy 152.082811 -129.924723) (xy 152.089205 -129.931748)
			(xy 152.092914 -129.934716) (xy 152.115539 -129.952901) (xy 152.155543 -129.994957) (xy 152.188715 -130.042588)
			(xy 152.214289 -130.094694) (xy 152.231676 -130.150073) (xy 152.240473 -130.207446) (xy 152.240996 -130.236468)
			(xy 152.240996 -130.23723) (xy 152.240497 -130.266596) (xy 152.231569 -130.324643) (xy 152.223216 -130.3528)
			(xy 152.221875 -130.357308) (xy 152.220725 -130.366643) (xy 152.22093 -130.371342) (xy 152.221812 -130.387075)
			(xy 152.2227 -130.418577) (xy 152.222708 -130.434334) (xy 152.222272 -130.476701) (xy 152.215083 -130.56113)
			(xy 152.20075 -130.644643) (xy 152.179377 -130.726638) (xy 152.151119 -130.806521) (xy 152.134062 -130.845306)
			(xy 152.130099 -130.855347) (xy 152.130112 -130.876914) (xy 152.134062 -130.886962) (xy 152.151103 -130.925751)
			(xy 152.179335 -131.005641) (xy 152.200694 -131.087635) (xy 152.215027 -131.171145) (xy 152.22223 -131.255569)
			(xy 152.222708 -131.297934) (xy 152.222702 -131.313755) (xy 152.221815 -131.345384) (xy 152.22093 -131.36118)
			(xy 152.220758 -131.365878) (xy 152.221903 -131.375208) (xy 152.223216 -131.379722) (xy 152.229312 -131.401058)
			(xy 152.234266 -131.42168) (xy 152.240117 -131.463688) (xy 152.240996 -131.484878) (xy 152.2417 -131.494716)
			(xy 152.249583 -131.512777) (xy 152.263691 -131.526535) (xy 152.281943 -131.533963) (xy 152.291796 -131.534408)
			(xy 153.143204 -131.534408) (xy 153.152925 -131.533923) (xy 153.170942 -131.526606) (xy 153.178256 -131.520184)
			(xy 153.209124 -131.491265) (xy 153.274974 -131.438165) (xy 153.345083 -131.390832) (xy 153.418947 -131.349604)
			(xy 153.496037 -131.314778) (xy 153.575799 -131.286604) (xy 153.65766 -131.265283) (xy 153.741032 -131.25097)
			(xy 153.825316 -131.243767) (xy 153.867612 -131.243324) (xy 153.914302 -131.243869) (xy 154.007274 -131.252603)
			(xy 154.099021 -131.269994) (xy 154.188739 -131.295888) (xy 154.275643 -131.330059) (xy 154.358971 -131.372208)
			(xy 154.437991 -131.421964) (xy 154.512012 -131.478893) (xy 154.580385 -131.542494) (xy 154.64251 -131.612211)
			(xy 154.697843 -131.687432) (xy 154.722322 -131.727194) (xy 154.724917 -131.731174) (xy 154.731307 -131.738203)
			(xy 154.735022 -131.741164) (xy 154.757644 -131.75935) (xy 154.797642 -131.801408) (xy 154.830807 -131.84904)
			(xy 154.856375 -131.901146) (xy 154.873754 -131.956524) (xy 154.882543 -132.013896) (xy 154.883104 -132.042916)
			(xy 154.883104 -132.043678) (xy 154.882601 -132.073043) (xy 154.873667 -132.131088) (xy 154.865324 -132.159248)
			(xy 154.863987 -132.163757) (xy 154.862846 -132.173091) (xy 154.863038 -132.17779) (xy 154.863921 -132.193523)
			(xy 154.864811 -132.225025) (xy 154.864816 -132.240782) (xy 154.864382 -132.28315) (xy 154.857197 -132.36758)
			(xy 154.842868 -132.451095) (xy 154.8215 -132.533091) (xy 154.793245 -132.612977) (xy 154.77617 -132.651754)
			(xy 154.772201 -132.661796) (xy 154.772194 -132.683371) (xy 154.77617 -132.69341) (xy 154.793215 -132.732199)
			(xy 154.821453 -132.812087) (xy 154.842818 -132.894081) (xy 154.857157 -132.977591) (xy 154.864366 -133.062016)
			(xy 154.864816 -133.104382) (xy 154.864817 -133.12033) (xy 154.863927 -133.152213) (xy 154.863038 -133.168136)
			(xy 154.862846 -133.172697) (xy 154.863869 -133.181766) (xy 154.86507 -133.18617) (xy 154.869896 -133.20268)
			(xy 154.869896 -133.203188) (xy 154.873414 -133.216532) (xy 154.878755 -133.243609) (xy 154.880564 -133.25729)
			(xy 154.881834 -133.269482) (xy 154.883358 -133.301994) (xy 154.882801 -133.331196) (xy 154.873897 -133.388917)
			(xy 154.856296 -133.444605) (xy 154.83041 -133.496958) (xy 154.796844 -133.544753) (xy 154.756384 -133.58687)
			(xy 154.733498 -133.605016) (xy 154.73299 -133.605524) (xy 154.727656 -133.609334) (xy 154.705381 -133.646378)
			(xy 154.655337 -133.716867) (xy 154.599379 -133.782759) (xy 154.537927 -133.84356) (xy 154.471443 -133.898813)
			(xy 154.400425 -133.948103) (xy 154.325407 -133.991061) (xy 154.246952 -134.027363) (xy 154.165649 -134.056738)
			(xy 154.082109 -134.078965) (xy 153.996958 -134.093876) (xy 153.910835 -134.10136) (xy 153.867612 -134.10184)
			(xy 153.825301 -134.101393) (xy 153.740983 -134.094223) (xy 153.657577 -134.079935) (xy 153.57568 -134.058631)
			(xy 153.495884 -134.030465) (xy 153.418761 -133.995638) (xy 153.344866 -133.954402) (xy 153.274731 -133.907052)
			(xy 153.208861 -133.853931) (xy 153.178002 -133.82498) (xy 153.170636 -133.817868) (xy 153.152856 -133.810756)
			(xy 153.022554 -133.810756) (xy 153.016544 -133.810923) (xy 153.00486 -133.813743) (xy 152.99944 -133.816344)
			(xy 152.959345 -133.836239) (xy 152.876273 -133.869582) (xy 152.790544 -133.895338) (xy 152.70285 -133.913298)
			(xy 152.613899 -133.923319) (xy 152.569164 -133.924802) (xy 152.559766 -133.925056) (xy 152.401524 -133.990842)
			(xy 152.375646 -134.001412) (xy 152.322909 -134.019964) (xy 152.296114 -134.027926) (xy 152.267158 -134.0358)
			(xy 152.259284 -134.037832) (xy 152.252934 -134.041896) (xy 152.249454 -134.044101) (xy 152.243194 -134.049457)
			(xy 152.240488 -134.052564) (xy 152.233884 -134.060692) (xy 152.232614 -134.062216) (xy 152.227793 -134.068592)
			(xy 152.22198 -134.083472) (xy 152.221184 -134.091426) (xy 152.218031 -134.137135) (xy 152.204386 -134.227743)
			(xy 152.182477 -134.316715) (xy 152.152489 -134.403299) (xy 152.134062 -134.445248) (xy 152.130087 -134.45529)
			(xy 152.130078 -134.476867) (xy 152.134062 -134.486904) (xy 152.151106 -134.525693) (xy 152.179342 -134.605582)
			(xy 152.200705 -134.687576) (xy 152.215043 -134.771086) (xy 152.222252 -134.85551) (xy 152.222708 -134.897876)
			(xy 152.22093 -134.960868) (xy 152.220757 -134.965566) (xy 152.2219 -134.974897) (xy 152.223216 -134.97941)
			(xy 152.231556 -135.00757) (xy 152.240485 -135.065615) (xy 152.240996 -135.09498) (xy 152.240996 -135.095488)
			(xy 152.240735 -135.114478) (xy 152.236918 -135.152267) (xy 152.233376 -135.170926) (xy 152.232107 -135.178272)
			(xy 152.233405 -135.193116) (xy 152.235916 -135.200136) (xy 152.238456 -135.206232) (xy 152.247092 -135.217408)
			(xy 152.315926 -135.267446) (xy 152.316434 -135.267954) (xy 152.326594 -135.275066) (xy 152.331928 -135.278368)
			(xy 152.332182 -135.278368) (xy 152.332944 -135.278622) (xy 152.36063 -135.263128) (xy 152.398043 -135.242505)
			(xy 152.475748 -135.206989) (xy 152.556207 -135.178253) (xy 152.63883 -135.156506) (xy 152.723011 -135.141909)
			(xy 152.808132 -135.134568) (xy 152.85085 -135.134096) (xy 153.143204 -135.134096) (xy 153.152898 -135.133658)
			(xy 153.170905 -135.126464) (xy 153.178256 -135.120126) (xy 153.209114 -135.091224) (xy 153.274942 -135.038159)
			(xy 153.345028 -134.990859) (xy 153.418868 -134.949665) (xy 153.495931 -134.914872) (xy 153.575664 -134.88673)
			(xy 153.657494 -134.865442) (xy 153.740833 -134.85116) (xy 153.825081 -134.843987) (xy 153.867358 -134.84352)
			(xy 153.867612 -134.84352) (xy 153.914311 -134.844065) (xy 154.007301 -134.852799) (xy 154.099067 -134.870189)
			(xy 154.188804 -134.896083) (xy 154.275728 -134.930254) (xy 154.359076 -134.972403) (xy 154.438117 -135.02216)
			(xy 154.512161 -135.079089) (xy 154.580557 -135.142692) (xy 154.642706 -135.212412) (xy 154.698065 -135.287636)
			(xy 154.722576 -135.32739) (xy 154.72509 -135.331373) (xy 154.731349 -135.338412) (xy 154.735022 -135.34136)
			(xy 154.757644 -135.359546) (xy 154.797643 -135.401604) (xy 154.830809 -135.449236) (xy 154.856376 -135.501342)
			(xy 154.873756 -135.55672) (xy 154.882546 -135.614091) (xy 154.883104 -135.643112) (xy 154.883104 -135.64362)
			(xy 154.882606 -135.672986) (xy 154.87368 -135.731034) (xy 154.865324 -135.75919) (xy 154.863981 -135.763698)
			(xy 154.862829 -135.773033) (xy 154.863038 -135.777732) (xy 154.86392 -135.793465) (xy 154.864809 -135.824967)
			(xy 154.864816 -135.840724) (xy 154.864381 -135.883091) (xy 154.857192 -135.96752) (xy 154.84286 -136.051034)
			(xy 154.821488 -136.133029) (xy 154.793231 -136.212913) (xy 154.77617 -136.251696) (xy 154.77221 -136.261738)
			(xy 154.772219 -136.283305) (xy 154.77617 -136.293352) (xy 154.793213 -136.332141) (xy 154.821448 -136.41203)
			(xy 154.84281 -136.494024) (xy 154.857145 -136.577534) (xy 154.86435 -136.661958) (xy 154.864816 -136.704324)
			(xy 154.864818 -136.720272) (xy 154.86393 -136.752155) (xy 154.863038 -136.768078) (xy 154.86285 -136.772638)
			(xy 154.863879 -136.781706) (xy 154.86507 -136.786112) (xy 154.869896 -136.802622) (xy 154.869896 -136.80313)
			(xy 154.873412 -136.816474) (xy 154.878751 -136.843552) (xy 154.880564 -136.857232) (xy 154.881834 -136.869424)
			(xy 154.883358 -136.901936) (xy 154.882798 -136.931136) (xy 154.873889 -136.988854) (xy 154.856283 -137.044537)
			(xy 154.830394 -137.096886) (xy 154.796826 -137.144676) (xy 154.756364 -137.186788) (xy 154.733498 -137.204958)
			(xy 154.73299 -137.205466) (xy 154.727656 -137.209276) (xy 154.706915 -137.243837) (xy 154.660645 -137.309846)
			(xy 154.609203 -137.371908) (xy 154.581352 -137.401046) (xy 154.57464 -137.408496) (xy 154.567174 -137.427091)
			(xy 154.566874 -137.437114) (xy 154.567128 -137.508234) (xy 154.567699 -137.518157) (xy 154.575408 -137.536458)
			(xy 154.582114 -137.543794) (xy 154.640026 -137.60196) (xy 154.67423 -137.63697) (xy 154.736343 -137.712622)
			(xy 154.79074 -137.793998) (xy 154.836899 -137.880314) (xy 154.85618 -137.925302) (xy 155.31211 -139.02563)
			(xy 155.330371 -139.071239) (xy 155.358869 -139.165265) (xy 155.369006 -139.213336) (xy 155.405836 -139.397486)
			(xy 155.410154 -139.407646) (xy 155.41371 -139.412218) (xy 155.439785 -139.448074) (xy 155.486192 -139.523624)
			(xy 155.525717 -139.602992) (xy 155.558049 -139.685551) (xy 155.582934 -139.770652) (xy 155.592018 -139.814046)
			(xy 155.685998 -140.287756) (xy 155.69491 -140.33571) (xy 155.704452 -140.432786) (xy 155.705048 -140.481558)
			(xy 155.705048 -140.481812) (xy 155.704776 -140.514676) (xy 155.700454 -140.580261) (xy 155.696412 -140.612876)
			(xy 155.69565 -140.621688) (xy 155.699432 -140.638953) (xy 155.703778 -140.646658) (xy 155.727486 -140.685404)
			(xy 155.768554 -140.766434) (xy 155.802084 -140.850863) (xy 155.827797 -140.937991) (xy 155.837128 -140.982446)
			(xy 155.933648 -141.468602) (xy 155.942639 -141.516677) (xy 155.952307 -141.614008) (xy 155.952952 -141.662912)
			(xy 155.952567 -141.701875) (xy 155.946464 -141.779561) (xy 155.94076 -141.818106) (xy 155.939716 -141.827072)
			(xy 155.943218 -141.844769) (xy 155.947618 -141.85265) (xy 155.970143 -141.890411) (xy 156.009225 -141.969181)
			(xy 156.041209 -142.05109) (xy 156.065847 -142.135499) (xy 156.074872 -142.178532) (xy 156.112972 -142.369794)
			(xy 156.128974 -142.389098) (xy 156.136086 -142.392146) (xy 156.162837 -142.402868) (xy 156.213023 -142.431197)
			(xy 156.258378 -142.466749) (xy 156.297873 -142.508717) (xy 156.330608 -142.556147) (xy 156.355839 -142.607959)
			(xy 156.372992 -142.662977) (xy 156.381678 -142.719948) (xy 156.382212 -142.748762) (xy 156.381682 -142.777647)
			(xy 156.372973 -142.834758) (xy 156.355749 -142.889901) (xy 156.330403 -142.941815) (xy 156.297516 -142.989311)
			(xy 156.257841 -143.031303) (xy 156.2354 -143.049498) (xy 156.226477 -143.057206) (xy 156.216278 -143.078433)
			(xy 156.21661 -143.101981) (xy 156.22143 -143.112744) (xy 156.242144 -143.154238) (xy 156.276677 -143.240319)
			(xy 156.303077 -143.329232) (xy 156.312616 -143.374618) (xy 156.409136 -143.860774) (xy 156.418128 -143.908849)
			(xy 156.4278 -144.00618) (xy 156.42844 -144.055084) (xy 156.428003 -144.094115) (xy 156.421775 -144.171929)
			(xy 156.415994 -144.210532) (xy 156.414954 -144.219497) (xy 156.418466 -144.237188) (xy 156.422852 -144.245076)
			(xy 156.445358 -144.282812) (xy 156.484414 -144.361526) (xy 156.516394 -144.443369) (xy 156.541051 -144.527709)
			(xy 156.550106 -144.570704) (xy 156.646626 -145.05686) (xy 156.655575 -145.104937) (xy 156.665117 -145.20227)
			(xy 156.665676 -145.25117) (xy 156.665298 -145.290196) (xy 156.659196 -145.36801) (xy 156.653484 -145.406618)
			(xy 156.652442 -145.415584) (xy 156.655949 -145.433278) (xy 156.660342 -145.441162) (xy 156.682848 -145.478898)
			(xy 156.721906 -145.557611) (xy 156.753888 -145.639455) (xy 156.778546 -145.723794) (xy 156.787596 -145.76679)
			(xy 156.884116 -146.252946) (xy 156.893109 -146.301021) (xy 156.902782 -146.398352) (xy 156.90342 -146.447256)
			(xy 156.902981 -146.486287) (xy 156.896748 -146.5641) (xy 156.890974 -146.602704) (xy 156.88993 -146.61167)
			(xy 156.893432 -146.629367) (xy 156.897832 -146.637248) (xy 156.920339 -146.674984) (xy 156.959398 -146.753696)
			(xy 156.991381 -146.83554) (xy 157.016041 -146.919879) (xy 157.025086 -146.962876) (xy 157.121606 -147.449032)
			(xy 157.130556 -147.497109) (xy 157.140101 -147.594442) (xy 157.140656 -147.643342) (xy 157.140033 -147.693149)
			(xy 157.130113 -147.792267) (xy 157.120844 -147.841208) (xy 157.119548 -147.849481) (xy 157.121756 -147.86607)
			(xy 157.125162 -147.87372) (xy 157.144425 -147.913544) (xy 157.176641 -147.995941) (xy 157.201444 -148.080864)
			(xy 157.210506 -148.124164) (xy 157.324298 -148.697696) (xy 157.333216 -148.745713) (xy 157.342754 -148.842917)
			(xy 157.343348 -148.891752) (xy 157.342909 -148.934383) (xy 157.335661 -149.019335) (xy 157.32887 -149.061424)
			(xy 157.327346 -149.070822) (xy 164.462206 -184.999122) (xy 164.463984 -185.005472) (xy 171.861789 -206.859124)
			(xy 174.992028 -206.859124) (xy 174.996099 -206.803502) (xy 175.008225 -206.749065) (xy 175.028148 -206.696974)
			(xy 175.055444 -206.648339) (xy 175.08953 -206.604196) (xy 175.129679 -206.565487) (xy 175.175037 -206.533036)
			(xy 175.224637 -206.507535) (xy 175.277421 -206.489528) (xy 175.332264 -206.479398) (xy 175.387998 -206.477361)
			(xy 175.443435 -206.483461) (xy 175.497392 -206.497567) (xy 175.548721 -206.519379) (xy 175.596327 -206.548433)
			(xy 175.639195 -206.584108) (xy 175.676412 -206.625645) (xy 175.707185 -206.672158) (xy 175.730857 -206.722655)
			(xy 175.746925 -206.776062) (xy 175.755045 -206.831238) (xy 175.755554 -206.859124) (xy 175.755045 -206.88701)
			(xy 175.746925 -206.942186) (xy 175.730857 -206.995593) (xy 175.707185 -207.04609) (xy 175.676412 -207.092603)
			(xy 175.639195 -207.13414) (xy 175.596327 -207.169815) (xy 175.548721 -207.198869) (xy 175.497392 -207.220681)
			(xy 175.443435 -207.234787) (xy 175.387998 -207.240887) (xy 175.332264 -207.23885) (xy 175.277421 -207.22872)
			(xy 175.224637 -207.210713) (xy 175.175037 -207.185212) (xy 175.129679 -207.152761) (xy 175.08953 -207.114052)
			(xy 175.055444 -207.069909) (xy 175.028148 -207.021274) (xy 175.008225 -206.969183) (xy 174.996099 -206.914746)
			(xy 174.992028 -206.859124) (xy 171.861789 -206.859124) (xy 172.480351 -208.6864) (xy 180.694836 -208.6864)
			(xy 180.698907 -208.630778) (xy 180.711033 -208.576341) (xy 180.730956 -208.52425) (xy 180.758252 -208.475615)
			(xy 180.792338 -208.431472) (xy 180.832487 -208.392763) (xy 180.877845 -208.360312) (xy 180.927445 -208.334811)
			(xy 180.980229 -208.316804) (xy 181.035072 -208.306674) (xy 181.090806 -208.304637) (xy 181.146243 -208.310737)
			(xy 181.2002 -208.324843) (xy 181.251529 -208.346655) (xy 181.299135 -208.375709) (xy 181.342003 -208.411384)
			(xy 181.37922 -208.452921) (xy 181.409993 -208.499434) (xy 181.433665 -208.549931) (xy 181.449733 -208.603338)
			(xy 181.457853 -208.658514) (xy 181.458362 -208.6864) (xy 181.457853 -208.714286) (xy 181.449733 -208.769462)
			(xy 181.433665 -208.822869) (xy 181.409993 -208.873366) (xy 181.37922 -208.919879) (xy 181.342003 -208.961416)
			(xy 181.299135 -208.997091) (xy 181.251529 -209.026145) (xy 181.2002 -209.047957) (xy 181.146243 -209.062063)
			(xy 181.090806 -209.068163) (xy 181.035072 -209.066126) (xy 180.980229 -209.055996) (xy 180.927445 -209.037989)
			(xy 180.877845 -209.012488) (xy 180.832487 -208.980037) (xy 180.792338 -208.941328) (xy 180.758252 -208.897185)
			(xy 180.730956 -208.84855) (xy 180.711033 -208.796459) (xy 180.698907 -208.742022) (xy 180.694836 -208.6864)
			(xy 172.480351 -208.6864) (xy 179.642734 -229.8446) (xy 182.411876 -229.8446) (xy 182.415947 -229.788978)
			(xy 182.428073 -229.734541) (xy 182.447996 -229.68245) (xy 182.475292 -229.633815) (xy 182.509378 -229.589672)
			(xy 182.549527 -229.550963) (xy 182.594885 -229.518512) (xy 182.644485 -229.493011) (xy 182.697269 -229.475004)
			(xy 182.752112 -229.464874) (xy 182.807846 -229.462837) (xy 182.863283 -229.468937) (xy 182.91724 -229.483043)
			(xy 182.968569 -229.504855) (xy 183.016175 -229.533909) (xy 183.059043 -229.569584) (xy 183.09626 -229.611121)
			(xy 183.127033 -229.657634) (xy 183.150705 -229.708131) (xy 183.166773 -229.761538) (xy 183.174893 -229.816714)
			(xy 183.175402 -229.8446) (xy 183.174893 -229.872486) (xy 183.166773 -229.927662) (xy 183.150705 -229.981069)
			(xy 183.127033 -230.031566) (xy 183.09626 -230.078079) (xy 183.059043 -230.119616) (xy 183.016175 -230.155291)
			(xy 182.968569 -230.184345) (xy 182.91724 -230.206157) (xy 182.863283 -230.220263) (xy 182.807846 -230.226363)
			(xy 182.752112 -230.224326) (xy 182.697269 -230.214196) (xy 182.644485 -230.196189) (xy 182.594885 -230.170688)
			(xy 182.549527 -230.138237) (xy 182.509378 -230.099528) (xy 182.475292 -230.055385) (xy 182.447996 -230.00675)
			(xy 182.428073 -229.954659) (xy 182.415947 -229.900222) (xy 182.411876 -229.8446) (xy 179.642734 -229.8446)
			(xy 181.551126 -235.48213) (xy 183.206388 -235.48213) (xy 183.210459 -235.426508) (xy 183.222585 -235.372071)
			(xy 183.242508 -235.31998) (xy 183.269804 -235.271345) (xy 183.30389 -235.227202) (xy 183.344039 -235.188493)
			(xy 183.389397 -235.156042) (xy 183.438997 -235.130541) (xy 183.491781 -235.112534) (xy 183.546624 -235.102404)
			(xy 183.602358 -235.100367) (xy 183.657795 -235.106467) (xy 183.711752 -235.120573) (xy 183.763081 -235.142385)
			(xy 183.810687 -235.171439) (xy 183.853555 -235.207114) (xy 183.890772 -235.248651) (xy 183.921545 -235.295164)
			(xy 183.945217 -235.345661) (xy 183.961285 -235.399068) (xy 183.969405 -235.454244) (xy 183.969914 -235.48213)
			(xy 183.969405 -235.510016) (xy 183.961285 -235.565192) (xy 183.945217 -235.618599) (xy 183.921545 -235.669096)
			(xy 183.890772 -235.715609) (xy 183.853555 -235.757146) (xy 183.810687 -235.792821) (xy 183.763081 -235.821875)
			(xy 183.711752 -235.843687) (xy 183.657795 -235.857793) (xy 183.602358 -235.863893) (xy 183.546624 -235.861856)
			(xy 183.491781 -235.851726) (xy 183.438997 -235.833719) (xy 183.389397 -235.808218) (xy 183.344039 -235.775767)
			(xy 183.30389 -235.737058) (xy 183.269804 -235.692915) (xy 183.242508 -235.64428) (xy 183.222585 -235.592189)
			(xy 183.210459 -235.537752) (xy 183.206388 -235.48213) (xy 181.551126 -235.48213) (xy 181.949657 -236.65942)
			(xy 182.566816 -236.65942) (xy 182.570887 -236.603798) (xy 182.583013 -236.549361) (xy 182.602936 -236.49727)
			(xy 182.630232 -236.448635) (xy 182.664318 -236.404492) (xy 182.704467 -236.365783) (xy 182.749825 -236.333332)
			(xy 182.799425 -236.307831) (xy 182.852209 -236.289824) (xy 182.907052 -236.279694) (xy 182.962786 -236.277657)
			(xy 183.018223 -236.283757) (xy 183.07218 -236.297863) (xy 183.123509 -236.319675) (xy 183.171115 -236.348729)
			(xy 183.213983 -236.384404) (xy 183.2512 -236.425941) (xy 183.281973 -236.472454) (xy 183.305645 -236.522951)
			(xy 183.321713 -236.576358) (xy 183.329833 -236.631534) (xy 183.330342 -236.65942) (xy 183.329833 -236.687306)
			(xy 183.321713 -236.742482) (xy 183.305645 -236.795889) (xy 183.281973 -236.846386) (xy 183.2512 -236.892899)
			(xy 183.213983 -236.934436) (xy 183.171115 -236.970111) (xy 183.123509 -236.999165) (xy 183.07218 -237.020977)
			(xy 183.018223 -237.035083) (xy 182.962786 -237.041183) (xy 182.907052 -237.039146) (xy 182.852209 -237.029016)
			(xy 182.799425 -237.011009) (xy 182.749825 -236.985508) (xy 182.704467 -236.953057) (xy 182.664318 -236.914348)
			(xy 182.630232 -236.870205) (xy 182.602936 -236.82157) (xy 182.583013 -236.769479) (xy 182.570887 -236.715042)
			(xy 182.566816 -236.65942) (xy 181.949657 -236.65942) (xy 182.884919 -239.422251) (xy 183.108578 -239.422251)
			(xy 183.108578 -239.367749) (xy 183.116334 -239.313801) (xy 183.131689 -239.261506) (xy 183.154331 -239.211929)
			(xy 183.183797 -239.166079) (xy 183.219488 -239.124888) (xy 183.260679 -239.089197) (xy 183.306529 -239.059731)
			(xy 183.356106 -239.037089) (xy 183.408401 -239.021734) (xy 183.462349 -239.013978) (xy 183.4896 -239.013492)
			(xy 183.515775 -239.013916) (xy 183.567631 -239.021092) (xy 183.618017 -239.035297) (xy 183.665986 -239.056263)
			(xy 183.710635 -239.083595) (xy 183.731154 -239.099852) (xy 183.739771 -239.106192) (xy 183.760385 -239.11183)
			(xy 183.771032 -239.110774) (xy 183.85663 -239.097566) (xy 183.87441 -239.086136) (xy 183.880506 -239.076992)
			(xy 183.895682 -239.054692) (xy 183.93136 -239.014235) (xy 183.972383 -238.97921) (xy 184.017932 -238.950314)
			(xy 184.067098 -238.928125) (xy 184.118901 -238.913085) (xy 184.172305 -238.905495) (xy 184.199276 -238.905034)
			(xy 184.226533 -238.905411) (xy 184.280493 -238.913166) (xy 184.332799 -238.928522) (xy 184.382388 -238.951166)
			(xy 184.428249 -238.980636) (xy 184.469449 -239.016334) (xy 184.505149 -239.057532) (xy 184.534623 -239.103391)
			(xy 184.55727 -239.152978) (xy 184.572629 -239.205284) (xy 184.580387 -239.259243) (xy 184.580387 -239.313757)
			(xy 184.572629 -239.367716) (xy 184.55727 -239.420022) (xy 184.547585 -239.441228) (xy 185.623706 -239.441228)
			(xy 185.627777 -239.385606) (xy 185.639903 -239.331169) (xy 185.659826 -239.279078) (xy 185.687122 -239.230443)
			(xy 185.721208 -239.1863) (xy 185.761357 -239.147591) (xy 185.806715 -239.11514) (xy 185.856315 -239.089639)
			(xy 185.909099 -239.071632) (xy 185.963942 -239.061502) (xy 186.019676 -239.059465) (xy 186.075113 -239.065565)
			(xy 186.12907 -239.079671) (xy 186.180399 -239.101483) (xy 186.228005 -239.130537) (xy 186.270873 -239.166212)
			(xy 186.30809 -239.207749) (xy 186.338863 -239.254262) (xy 186.362535 -239.304759) (xy 186.378603 -239.358166)
			(xy 186.386723 -239.413342) (xy 186.387232 -239.441228) (xy 186.386723 -239.469114) (xy 186.378603 -239.52429)
			(xy 186.362535 -239.577697) (xy 186.338863 -239.628194) (xy 186.30809 -239.674707) (xy 186.270873 -239.716244)
			(xy 186.228005 -239.751919) (xy 186.180399 -239.780973) (xy 186.12907 -239.802785) (xy 186.075113 -239.816891)
			(xy 186.019676 -239.822991) (xy 185.963942 -239.820954) (xy 185.909099 -239.810824) (xy 185.856315 -239.792817)
			(xy 185.806715 -239.767316) (xy 185.761357 -239.734865) (xy 185.721208 -239.696156) (xy 185.687122 -239.652013)
			(xy 185.659826 -239.603378) (xy 185.639903 -239.551287) (xy 185.627777 -239.49685) (xy 185.623706 -239.441228)
			(xy 184.547585 -239.441228) (xy 184.534623 -239.469609) (xy 184.505149 -239.515468) (xy 184.469449 -239.556666)
			(xy 184.428249 -239.592364) (xy 184.382388 -239.621834) (xy 184.332799 -239.644478) (xy 184.280493 -239.659834)
			(xy 184.226533 -239.667589) (xy 184.199276 -239.66805) (xy 184.173102 -239.667596) (xy 184.121247 -239.660429)
			(xy 184.07086 -239.646232) (xy 184.022891 -239.625272) (xy 183.978241 -239.597945) (xy 183.957722 -239.58169)
			(xy 183.94911 -239.575341) (xy 183.928492 -239.569707) (xy 183.917844 -239.570768) (xy 183.832246 -239.583976)
			(xy 183.814466 -239.595406) (xy 183.80837 -239.60455) (xy 183.793158 -239.626824) (xy 183.757485 -239.667279)
			(xy 183.716467 -239.702305) (xy 183.670924 -239.731203) (xy 183.621764 -239.753397) (xy 183.569968 -239.768443)
			(xy 183.516569 -239.776042) (xy 183.4896 -239.776508) (xy 183.462349 -239.776022) (xy 183.408401 -239.768266)
			(xy 183.356106 -239.752911) (xy 183.306529 -239.730269) (xy 183.260679 -239.700803) (xy 183.219488 -239.665112)
			(xy 183.183797 -239.623921) (xy 183.154331 -239.578071) (xy 183.131689 -239.528494) (xy 183.116334 -239.476199)
			(xy 183.108578 -239.422251) (xy 182.884919 -239.422251) (xy 183.377061 -240.876074) (xy 184.744866 -240.876074)
			(xy 184.748937 -240.820452) (xy 184.761063 -240.766015) (xy 184.780986 -240.713924) (xy 184.808282 -240.665289)
			(xy 184.842368 -240.621146) (xy 184.882517 -240.582437) (xy 184.927875 -240.549986) (xy 184.977475 -240.524485)
			(xy 185.030259 -240.506478) (xy 185.085102 -240.496348) (xy 185.140836 -240.494311) (xy 185.196273 -240.500411)
			(xy 185.25023 -240.514517) (xy 185.301559 -240.536329) (xy 185.349165 -240.565383) (xy 185.392033 -240.601058)
			(xy 185.42925 -240.642595) (xy 185.460023 -240.689108) (xy 185.483695 -240.739605) (xy 185.499763 -240.793012)
			(xy 185.507883 -240.848188) (xy 185.508392 -240.876074) (xy 185.507883 -240.90396) (xy 185.499763 -240.959136)
			(xy 185.483695 -241.012543) (xy 185.460023 -241.06304) (xy 185.42925 -241.109553) (xy 185.392033 -241.15109)
			(xy 185.349165 -241.186765) (xy 185.301559 -241.215819) (xy 185.25023 -241.237631) (xy 185.196273 -241.251737)
			(xy 185.140836 -241.257837) (xy 185.085102 -241.2558) (xy 185.030259 -241.24567) (xy 184.977475 -241.227663)
			(xy 184.927875 -241.202162) (xy 184.882517 -241.169711) (xy 184.842368 -241.131002) (xy 184.808282 -241.086859)
			(xy 184.780986 -241.038224) (xy 184.761063 -240.986133) (xy 184.748937 -240.931696) (xy 184.744866 -240.876074)
			(xy 183.377061 -240.876074) (xy 183.536559 -241.347244) (xy 186.002674 -241.347244) (xy 186.006745 -241.291622)
			(xy 186.018871 -241.237185) (xy 186.038794 -241.185094) (xy 186.06609 -241.136459) (xy 186.100176 -241.092316)
			(xy 186.140325 -241.053607) (xy 186.185683 -241.021156) (xy 186.235283 -240.995655) (xy 186.288067 -240.977648)
			(xy 186.34291 -240.967518) (xy 186.398644 -240.965481) (xy 186.454081 -240.971581) (xy 186.508038 -240.985687)
			(xy 186.559367 -241.007499) (xy 186.606973 -241.036553) (xy 186.649841 -241.072228) (xy 186.687058 -241.113765)
			(xy 186.717831 -241.160278) (xy 186.741503 -241.210775) (xy 186.757571 -241.264182) (xy 186.765691 -241.319358)
			(xy 186.7662 -241.347244) (xy 186.765691 -241.37513) (xy 186.757571 -241.430306) (xy 186.741503 -241.483713)
			(xy 186.717831 -241.53421) (xy 186.687058 -241.580723) (xy 186.649841 -241.62226) (xy 186.606973 -241.657935)
			(xy 186.559367 -241.686989) (xy 186.508038 -241.708801) (xy 186.454081 -241.722907) (xy 186.398644 -241.729007)
			(xy 186.34291 -241.72697) (xy 186.288067 -241.71684) (xy 186.235283 -241.698833) (xy 186.185683 -241.673332)
			(xy 186.140325 -241.640881) (xy 186.100176 -241.602172) (xy 186.06609 -241.558029) (xy 186.038794 -241.509394)
			(xy 186.018871 -241.457303) (xy 186.006745 -241.402866) (xy 186.002674 -241.347244) (xy 183.536559 -241.347244)
			(xy 184.097168 -243.003324) (xy 184.101922 -243.015039) (xy 184.12044 -243.032208) (xy 184.132474 -243.03609)
			(xy 184.160723 -243.04413) (xy 184.214525 -243.067685) (xy 184.264086 -243.099201) (xy 184.308237 -243.137934)
			(xy 184.345935 -243.182971) (xy 184.376294 -243.233249) (xy 184.398595 -243.287583) (xy 184.406032 -243.315998)
			(xy 184.408753 -243.325305) (xy 184.420001 -243.34108) (xy 184.436279 -243.351589) (xy 184.455286 -243.355346)
			(xy 184.474337 -243.351821) (xy 184.48274 -243.346986) (xy 184.505788 -243.332859) (xy 184.555024 -243.310542)
			(xy 184.606921 -243.29541) (xy 184.660435 -243.287764) (xy 184.687464 -243.287296) (xy 184.714718 -243.287757)
			(xy 184.768672 -243.29551) (xy 184.820974 -243.310862) (xy 184.870558 -243.333503) (xy 184.916415 -243.362969)
			(xy 184.957612 -243.398663) (xy 184.993309 -243.439856) (xy 185.02278 -243.48571) (xy 185.045425 -243.535292)
			(xy 185.060783 -243.587592) (xy 185.068541 -243.641546) (xy 185.068541 -243.696054) (xy 185.060783 -243.750008)
			(xy 185.045425 -243.802308) (xy 185.02278 -243.85189) (xy 184.993309 -243.897744) (xy 184.957612 -243.938937)
			(xy 184.916415 -243.974631) (xy 184.870558 -244.004097) (xy 184.820974 -244.026738) (xy 184.768672 -244.04209)
			(xy 184.714718 -244.049843) (xy 184.687464 -244.050312) (xy 184.668086 -244.050052) (xy 184.629531 -244.04611)
			(xy 184.610502 -244.042438) (xy 184.610248 -244.042438) (xy 184.601499 -244.040989) (xy 184.583967 -244.043593)
			(xy 184.56839 -244.052047) (xy 184.562242 -244.05844) (xy 184.503822 -244.12448) (xy 184.498137 -244.131399)
			(xy 184.491564 -244.148046) (xy 184.491101 -244.165938) (xy 184.493662 -244.174518) (xy 186.826783 -251.066808)
			(xy 188.18936 -251.066808) (xy 188.193431 -251.011186) (xy 188.205557 -250.956749) (xy 188.22548 -250.904658)
			(xy 188.252776 -250.856023) (xy 188.286862 -250.81188) (xy 188.327011 -250.773171) (xy 188.372369 -250.74072)
			(xy 188.421969 -250.715219) (xy 188.474753 -250.697212) (xy 188.529596 -250.687082) (xy 188.58533 -250.685045)
			(xy 188.640767 -250.691145) (xy 188.694724 -250.705251) (xy 188.746053 -250.727063) (xy 188.793659 -250.756117)
			(xy 188.836527 -250.791792) (xy 188.873744 -250.833329) (xy 188.904517 -250.879842) (xy 188.928189 -250.930339)
			(xy 188.944257 -250.983746) (xy 188.952377 -251.038922) (xy 188.952886 -251.066808) (xy 188.952377 -251.094694)
			(xy 188.944257 -251.14987) (xy 188.928189 -251.203277) (xy 188.904517 -251.253774) (xy 188.873744 -251.300287)
			(xy 188.836527 -251.341824) (xy 188.793659 -251.377499) (xy 188.746053 -251.406553) (xy 188.694724 -251.428365)
			(xy 188.640767 -251.442471) (xy 188.58533 -251.448571) (xy 188.529596 -251.446534) (xy 188.474753 -251.436404)
			(xy 188.421969 -251.418397) (xy 188.372369 -251.392896) (xy 188.327011 -251.360445) (xy 188.286862 -251.321736)
			(xy 188.252776 -251.277593) (xy 188.22548 -251.228958) (xy 188.205557 -251.176867) (xy 188.193431 -251.12243)
			(xy 188.18936 -251.066808) (xy 186.826783 -251.066808) (xy 188.203182 -255.13284) (xy 188.35573 -255.13284)
			(xy 188.359801 -255.077218) (xy 188.371927 -255.022781) (xy 188.39185 -254.97069) (xy 188.419146 -254.922055)
			(xy 188.453232 -254.877912) (xy 188.493381 -254.839203) (xy 188.538739 -254.806752) (xy 188.588339 -254.781251)
			(xy 188.641123 -254.763244) (xy 188.695966 -254.753114) (xy 188.7517 -254.751077) (xy 188.807137 -254.757177)
			(xy 188.861094 -254.771283) (xy 188.912423 -254.793095) (xy 188.960029 -254.822149) (xy 189.002897 -254.857824)
			(xy 189.040114 -254.899361) (xy 189.070887 -254.945874) (xy 189.094559 -254.996371) (xy 189.110627 -255.049778)
			(xy 189.118747 -255.104954) (xy 189.119256 -255.13284) (xy 189.118747 -255.160726) (xy 189.110627 -255.215902)
			(xy 189.094559 -255.269309) (xy 189.070887 -255.319806) (xy 189.040114 -255.366319) (xy 189.002897 -255.407856)
			(xy 188.960029 -255.443531) (xy 188.912423 -255.472585) (xy 188.861094 -255.494397) (xy 188.807137 -255.508503)
			(xy 188.7517 -255.514603) (xy 188.695966 -255.512566) (xy 188.641123 -255.502436) (xy 188.588339 -255.484429)
			(xy 188.538739 -255.458928) (xy 188.493381 -255.426477) (xy 188.453232 -255.387768) (xy 188.419146 -255.343625)
			(xy 188.39185 -255.29499) (xy 188.371927 -255.242899) (xy 188.359801 -255.188462) (xy 188.35573 -255.13284)
			(xy 188.203182 -255.13284) (xy 189.29223 -258.350004) (xy 189.296124 -258.359835) (xy 189.310372 -258.37543)
			(xy 189.329677 -258.384002) (xy 189.340236 -258.384548) (xy 189.945518 -258.384548) (xy 189.956057 -258.383971)
			(xy 189.975344 -258.375452) (xy 189.982856 -258.368038) (xy 189.98311 -258.368038) (xy 189.989812 -258.359834)
			(xy 189.996508 -258.33976) (xy 189.996064 -258.329176) (xy 188.96076 -246.4943) (xy 188.960252 -246.490744)
			(xy 188.235844 -241.942874) (xy 188.235102 -241.9387) (xy 188.232416 -241.930659) (xy 188.23051 -241.926872)
			(xy 188.228478 -241.923062) (xy 188.225895 -241.917635) (xy 188.223072 -241.905955) (xy 188.22289 -241.899948)
			(xy 188.22289 -241.863372) (xy 188.222382 -241.855244) (xy 187.663074 -238.346488) (xy 186.505088 -231.075738)
			(xy 186.456574 -230.771446) (xy 186.449208 -230.725726) (xy 186.449208 -230.724456) (xy 186.447938 -230.717344)
			(xy 186.440823 -230.674646) (xy 186.433194 -230.588416) (xy 186.432698 -230.545132) (xy 186.432698 -230.544878)
			(xy 186.432818 -230.528926) (xy 186.43396 -230.497043) (xy 186.434984 -230.481124) (xy 186.701938 -226.349052)
			(xy 186.702446 -226.34194) (xy 186.699652 -226.328732) (xy 186.698382 -226.325176) (xy 186.691203 -226.303711)
			(xy 186.681395 -226.259525) (xy 186.678824 -226.237038) (xy 186.677554 -226.220528) (xy 186.677554 -226.216464)
			(xy 186.6773 -226.214178) (xy 186.6773 -226.208336) (xy 186.677046 -226.199446) (xy 186.677046 -226.198938)
			(xy 186.677671 -226.168996) (xy 186.687095 -226.109855) (xy 186.705624 -226.052907) (xy 186.718702 -226.025964)
			(xy 186.723528 -226.016566) (xy 186.912758 -223.092518) (xy 186.912758 -223.084898) (xy 186.68619 -220.497146)
			(xy 186.684407 -220.475473) (xy 186.682501 -220.432024) (xy 186.68238 -220.410278) (xy 186.682505 -220.388532)
			(xy 186.684412 -220.345083) (xy 186.68619 -220.32341) (xy 186.727338 -219.854018) (xy 186.717178 -219.83065)
			(xy 186.707272 -219.822776) (xy 186.6851 -219.804581) (xy 186.645949 -219.762667) (xy 186.613514 -219.715363)
			(xy 186.588528 -219.663737) (xy 186.571552 -219.608951) (xy 186.56297 -219.552242) (xy 186.562492 -219.523564)
			(xy 186.562492 -219.52331) (xy 186.562902 -219.497925) (xy 186.569623 -219.447603) (xy 186.582961 -219.398617)
			(xy 186.602679 -219.351834) (xy 186.62843 -219.30808) (xy 186.643772 -219.287852) (xy 186.649898 -219.279141)
			(xy 186.655108 -219.258516) (xy 186.65153 -219.237547) (xy 186.639774 -219.219818) (xy 186.631072 -219.213684)
			(xy 186.608281 -219.198581) (xy 186.566864 -219.162888) (xy 186.530965 -219.121651) (xy 186.501318 -219.075712)
			(xy 186.47853 -219.026012) (xy 186.463068 -218.97357) (xy 186.455249 -218.919457) (xy 186.454796 -218.89212)
			(xy 186.455258 -218.864866) (xy 186.463013 -218.810913) (xy 186.478367 -218.758613) (xy 186.501008 -218.709031)
			(xy 186.530476 -218.663176) (xy 186.56617 -218.621981) (xy 186.607363 -218.586286) (xy 186.653217 -218.556816)
			(xy 186.702798 -218.534173) (xy 186.755098 -218.518816) (xy 186.80905 -218.511059) (xy 186.836304 -218.510612)
			(xy 186.84494 -218.510612) (xy 188.24702 -202.484228) (xy 188.24702 -202.483212) (xy 188.25083 -202.425554)
			(xy 188.391546 -200.249028) (xy 188.426852 -199.702674) (xy 188.56452 -197.570598) (xy 188.564715 -197.56031)
			(xy 188.55789 -197.54092) (xy 188.551312 -197.533006) (xy 188.518038 -197.496684) (xy 188.517784 -197.49643)
			(xy 188.501782 -197.479158) (xy 188.501274 -197.47865) (xy 188.500258 -197.477634) (xy 188.496658 -197.474081)
			(xy 188.48834 -197.468325) (xy 188.483748 -197.466204) (xy 188.474604 -197.462394) (xy 188.46419 -197.462394)
			(xy 188.437033 -197.461771) (xy 188.383304 -197.453783) (xy 188.33125 -197.438254) (xy 188.281926 -197.415499)
			(xy 188.236329 -197.385978) (xy 188.195379 -197.350288) (xy 188.159907 -197.30915) (xy 188.130628 -197.263396)
			(xy 188.108135 -197.213952) (xy 188.092882 -197.161817) (xy 188.085179 -197.108046) (xy 188.084714 -197.080886)
			(xy 188.085178 -197.053634) (xy 188.092937 -196.999686) (xy 188.108294 -196.947391) (xy 188.130938 -196.897814)
			(xy 188.160407 -196.851964) (xy 188.196101 -196.810775) (xy 188.237293 -196.775085) (xy 188.283146 -196.745621)
			(xy 188.332725 -196.722982) (xy 188.385021 -196.707629) (xy 188.43897 -196.699876) (xy 188.466222 -196.699378)
			(xy 188.477169 -196.699462) (xy 188.499027 -196.70073) (xy 188.50991 -196.701918) (xy 188.512958 -196.702172)
			(xy 188.520832 -196.702172) (xy 188.528833 -196.701777) (xy 188.543987 -196.696605) (xy 188.55055 -196.692012)
			(xy 188.608716 -196.644006) (xy 188.609224 -196.643498) (xy 188.617352 -196.63664) (xy 188.626496 -196.618352)
			(xy 188.627258 -196.605652) (xy 188.627512 -196.602096) (xy 188.627766 -196.595238) (xy 188.627766 -196.591682)
			(xy 188.627063 -196.583591) (xy 188.621237 -196.56844) (xy 188.616336 -196.561964) (xy 188.609732 -196.55409)
			(xy 188.602874 -196.549772) (xy 188.5777 -196.533052) (xy 188.531962 -196.493556) (xy 188.492325 -196.447939)
			(xy 188.459601 -196.397134) (xy 188.434458 -196.342182) (xy 188.417411 -196.284204) (xy 188.408809 -196.224388)
			(xy 188.40831 -196.194172) (xy 188.40879 -196.165529) (xy 188.416536 -196.10877) (xy 188.431882 -196.053578)
			(xy 188.454547 -196.000967) (xy 188.484114 -195.951902) (xy 188.520041 -195.907283) (xy 188.561669 -195.867929)
			(xy 188.608235 -195.834562) (xy 188.633354 -195.820792) (xy 188.640212 -195.817236) (xy 188.6458 -195.814188)
			(xy 188.64961 -195.811394) (xy 188.652752 -195.808814) (xy 188.658236 -195.802812) (xy 188.660532 -195.799456)
			(xy 188.673994 -195.779136) (xy 188.67882 -195.769738) (xy 188.681868 -195.762118) (xy 188.686186 -195.694046)
			(xy 188.696854 -195.529962) (xy 188.696854 -195.529708) (xy 188.69787 -195.515738) (xy 188.69152 -195.503292)
			(xy 188.688091 -195.497219) (xy 188.678561 -195.487043) (xy 188.672724 -195.483226) (xy 188.641482 -195.463922)
			(xy 188.637672 -195.461636) (xy 188.614304 -195.45935) (xy 188.603128 -195.463668) (xy 188.570542 -195.475189)
			(xy 188.502555 -195.487594) (xy 188.468 -195.488306) (xy 188.437266 -195.487036) (xy 188.423804 -195.487798)
			(xy 188.405815 -195.49101) (xy 188.369432 -195.494445) (xy 188.35116 -195.494656) (xy 188.350906 -195.494656)
			(xy 188.323199 -195.494185) (xy 188.26835 -195.4863) (xy 188.215181 -195.470689) (xy 188.164776 -195.44767)
			(xy 188.118159 -195.417712) (xy 188.07628 -195.381424) (xy 188.039992 -195.339546) (xy 188.010033 -195.29293)
			(xy 187.987013 -195.242524) (xy 187.971401 -195.189356) (xy 187.963515 -195.134507) (xy 187.963515 -195.079093)
			(xy 187.971401 -195.024244) (xy 187.987013 -194.971076) (xy 188.010033 -194.92067) (xy 188.039992 -194.874054)
			(xy 188.07628 -194.832176) (xy 188.118159 -194.795888) (xy 188.164776 -194.76593) (xy 188.215181 -194.742911)
			(xy 188.26835 -194.7273) (xy 188.323199 -194.719415) (xy 188.350906 -194.71894) (xy 188.369242 -194.719144)
			(xy 188.405751 -194.722582) (xy 188.423804 -194.725798) (xy 188.437266 -194.72656) (xy 188.468 -194.72529)
			(xy 188.493203 -194.725692) (xy 188.543171 -194.732332) (xy 188.591824 -194.74551) (xy 188.638312 -194.764995)
			(xy 188.660278 -194.77736) (xy 188.671258 -194.783149) (xy 188.696023 -194.784327) (xy 188.707522 -194.779646)
			(xy 188.719206 -194.774058) (xy 188.72725 -194.769924) (xy 188.739974 -194.757091) (xy 188.747435 -194.74063)
			(xy 188.748416 -194.73164) (xy 188.750194 -194.706748) (xy 188.750194 -194.70624) (xy 188.753496 -194.654678)
			(xy 188.771784 -194.365626) (xy 188.771784 -194.358768) (xy 188.77153 -194.358006) (xy 188.769865 -194.346812)
			(xy 188.758261 -194.327418) (xy 188.749178 -194.320668) (xy 188.702442 -194.28968) (xy 188.701934 -194.28968)
			(xy 188.685424 -194.278504) (xy 188.684916 -194.278504) (xy 188.680344 -194.275202) (xy 188.66739 -194.27063)
			(xy 188.660532 -194.270122) (xy 188.653688 -194.269935) (xy 188.640301 -194.272773) (xy 188.634116 -194.27571)
			(xy 188.622178 -194.281806) (xy 188.594804 -194.294939) (xy 188.537001 -194.31351) (xy 188.47702 -194.322906)
			(xy 188.446664 -194.323462) (xy 188.44641 -194.323462) (xy 188.418446 -194.322987) (xy 188.363086 -194.315029)
			(xy 188.309422 -194.299273) (xy 188.258547 -194.276041) (xy 188.211497 -194.245804) (xy 188.169228 -194.209179)
			(xy 188.132602 -194.166911) (xy 188.102364 -194.119861) (xy 188.07913 -194.068987) (xy 188.063373 -194.015324)
			(xy 188.055413 -193.959964) (xy 188.055413 -193.904036) (xy 188.063373 -193.848676) (xy 188.07913 -193.795013)
			(xy 188.102364 -193.744139) (xy 188.132602 -193.697089) (xy 188.169228 -193.654821) (xy 188.211497 -193.618196)
			(xy 188.258547 -193.587959) (xy 188.309422 -193.564727) (xy 188.363086 -193.548971) (xy 188.418446 -193.541013)
			(xy 188.44641 -193.540634) (xy 188.446664 -193.540634) (xy 188.458377 -193.540722) (xy 188.48176 -193.54212)
			(xy 188.4934 -193.543428) (xy 188.495686 -193.543682) (xy 188.520901 -193.54605) (xy 188.570431 -193.556616)
			(xy 188.618124 -193.573652) (xy 188.663138 -193.596859) (xy 188.684154 -193.610992) (xy 188.688218 -193.613786)
			(xy 188.694747 -193.618082) (xy 188.709619 -193.622861) (xy 188.717428 -193.623184) (xy 188.718444 -193.623184)
			(xy 188.74486 -193.610484) (xy 188.745368 -193.610484) (xy 188.796422 -193.5861) (xy 188.804296 -193.581782)
			(xy 188.813186 -193.574666) (xy 188.824156 -193.554747) (xy 188.825378 -193.543428) (xy 188.872622 -192.814702)
			(xy 188.881512 -192.67678) (xy 188.949838 -191.622172) (xy 189.787784 -178.67757) (xy 189.790546 -178.639723)
			(xy 189.80116 -178.564578) (xy 189.817516 -178.490471) (xy 189.82817 -178.45405) (xy 191.48933 -172.983652)
			(xy 191.489838 -172.982128) (xy 192.04813 -170.898058) (xy 192.059824 -170.856136) (xy 192.089571 -170.774336)
			(xy 192.126344 -170.695444) (xy 192.147698 -170.65752) (xy 199.054212 -158.694374) (xy 199.055482 -158.68396)
			(xy 199.060374 -158.642795) (xy 199.076124 -158.561399) (xy 199.098573 -158.48159) (xy 199.127566 -158.403919)
			(xy 199.162903 -158.328922) (xy 199.183244 -158.2928) (xy 199.431148 -157.86354) (xy 199.451864 -157.828445)
			(xy 199.498219 -157.761411) (xy 199.549895 -157.698386) (xy 199.606544 -157.639792) (xy 199.636888 -157.612588)
			(xy 199.64297 -157.606877) (xy 199.651406 -157.592495) (xy 199.653398 -157.584394) (xy 199.661746 -157.544496)
			(xy 199.684122 -157.466108) (xy 199.712828 -157.389811) (xy 199.747673 -157.316114) (xy 199.767698 -157.28061)
			(xy 199.863202 -157.11551) (xy 199.867945 -157.106355) (xy 199.870443 -157.085909) (xy 199.868028 -157.075886)
			(xy 199.846946 -157.005274) (xy 199.843571 -156.995437) (xy 199.83033 -156.979428) (xy 199.821292 -156.974286)
			(xy 199.780202 -156.952746) (xy 199.701811 -156.903115) (xy 199.628368 -156.846419) (xy 199.560507 -156.783148)
			(xy 199.498814 -156.713849) (xy 199.443824 -156.63912) (xy 199.419464 -156.599636) (xy 199.416943 -156.595659)
			(xy 199.410674 -156.588634) (xy 199.407018 -156.585666) (xy 199.384367 -156.567497) (xy 199.344311 -156.52546)
			(xy 199.311091 -156.477837) (xy 199.285475 -156.425728) (xy 199.268055 -156.370338) (xy 199.259235 -156.312946)
			(xy 199.258682 -156.283914) (xy 199.258682 -156.276802) (xy 199.259444 -156.258006) (xy 199.259698 -156.256228)
			(xy 199.259698 -156.254196) (xy 199.260968 -156.236162) (xy 199.261222 -156.233368) (xy 199.26173 -156.230574)
			(xy 199.26427 -156.21762) (xy 199.264524 -156.216096) (xy 199.266818 -156.20387) (xy 199.272793 -156.179722)
			(xy 199.276462 -156.167836) (xy 199.277828 -156.163267) (xy 199.278987 -156.153803) (xy 199.278748 -156.14904)
			(xy 199.277798 -156.133246) (xy 199.276781 -156.101617) (xy 199.276716 -156.085794) (xy 199.277151 -156.043427)
			(xy 199.284339 -155.958997) (xy 199.29867 -155.875483) (xy 199.320041 -155.793488) (xy 199.348298 -155.713603)
			(xy 199.365362 -155.674822) (xy 199.36934 -155.664782) (xy 199.369338 -155.643207) (xy 199.365362 -155.633166)
			(xy 199.348329 -155.5944) (xy 199.320107 -155.514561) (xy 199.29875 -155.432618) (xy 199.28441 -155.34916)
			(xy 199.277191 -155.264788) (xy 199.276716 -155.222448) (xy 199.276716 -155.22194) (xy 199.277224 -155.195524)
			(xy 199.277224 -155.195016) (xy 199.277732 -155.175204) (xy 199.27316 -155.169362) (xy 199.238362 -155.133548)
			(xy 199.237854 -155.13304) (xy 199.219566 -155.114752) (xy 199.215834 -155.111234) (xy 199.207257 -155.105611)
			(xy 199.202548 -155.103576) (xy 199.193912 -155.10002) (xy 198.935848 -155.10002) (xy 198.89547 -155.099622)
			(xy 198.814984 -155.093037) (xy 198.735305 -155.079898) (xy 198.656966 -155.060294) (xy 198.618602 -155.047696)
			(xy 198.617586 -155.047442) (xy 198.613268 -155.046172) (xy 198.610728 -155.04541) (xy 198.608188 -155.044902)
			(xy 198.601838 -155.043632) (xy 198.596504 -155.042362) (xy 198.595742 -155.042108) (xy 198.593202 -155.0416)
			(xy 198.592948 -155.0416) (xy 198.569399 -155.03663) (xy 198.522769 -155.024686) (xy 198.49973 -155.017724)
			(xy 198.479405 -155.011434) (xy 198.439259 -154.997333) (xy 198.419466 -154.98953) (xy 198.416418 -154.98826)
			(xy 198.410322 -154.98572) (xy 198.346822 -154.98572) (xy 198.329042 -154.992832) (xy 198.321676 -154.999944)
			(xy 198.290804 -155.028881) (xy 198.224939 -155.082012) (xy 198.154809 -155.12937) (xy 198.080917 -155.170613)
			(xy 198.003796 -155.205446) (xy 197.924 -155.233617) (xy 197.842104 -155.254924) (xy 197.758696 -155.269213)
			(xy 197.674377 -155.276382) (xy 197.632066 -155.276804) (xy 197.585383 -155.276263) (xy 197.492425 -155.26754)
			(xy 197.40069 -155.250164) (xy 197.310981 -155.224288) (xy 197.224084 -155.190138) (xy 197.14076 -155.148013)
			(xy 197.06174 -155.098283) (xy 196.987716 -155.041383) (xy 196.919335 -154.977811) (xy 196.857198 -154.908125)
			(xy 196.801847 -154.832934) (xy 196.777356 -154.793188) (xy 196.774759 -154.78921) (xy 196.768366 -154.782185)
			(xy 196.764656 -154.779218) (xy 196.742051 -154.761017) (xy 196.702081 -154.718941) (xy 196.668932 -154.671306)
			(xy 196.643364 -154.619207) (xy 196.625966 -154.563842) (xy 196.617138 -154.506483) (xy 196.616574 -154.477466)
			(xy 196.616574 -154.470354) (xy 196.617336 -154.451558) (xy 196.61759 -154.44978) (xy 196.61759 -154.447748)
			(xy 196.61886 -154.429714) (xy 196.619114 -154.42692) (xy 196.619622 -154.424126) (xy 196.622162 -154.411172)
			(xy 196.622416 -154.409648) (xy 196.624708 -154.397422) (xy 196.63068 -154.373272) (xy 196.634354 -154.361388)
			(xy 196.635716 -154.356819) (xy 196.636865 -154.347355) (xy 196.63664 -154.342592) (xy 196.63569 -154.326798)
			(xy 196.634675 -154.295169) (xy 196.634608 -154.279346) (xy 196.635041 -154.236978) (xy 196.642224 -154.152547)
			(xy 196.656551 -154.069032) (xy 196.677918 -153.987034) (xy 196.706171 -153.907148) (xy 196.723254 -153.868374)
			(xy 196.727244 -153.858334) (xy 196.727262 -153.836749) (xy 196.723254 -153.826718) (xy 196.706219 -153.787953)
			(xy 196.677993 -153.708114) (xy 196.656632 -153.626171) (xy 196.642288 -153.542713) (xy 196.635065 -153.45834)
			(xy 196.634608 -153.416) (xy 196.634608 -153.415492) (xy 196.63537 -153.38044) (xy 196.635476 -153.375594)
			(xy 196.634061 -153.366005) (xy 196.632576 -153.36139) (xy 196.624105 -153.336158) (xy 196.613487 -153.284005)
			(xy 196.610234 -153.23088) (xy 196.614411 -153.177821) (xy 196.625936 -153.12586) (xy 196.634862 -153.100786)
			(xy 196.635878 -153.097738) (xy 196.639942 -153.085292) (xy 196.64299 -153.078688) (xy 196.643244 -153.07818)
			(xy 196.647054 -153.068782) (xy 196.64807 -153.065734) (xy 196.650102 -153.06167) (xy 196.660574 -153.039258)
			(xy 196.686461 -152.997101) (xy 196.717567 -152.958633) (xy 196.735192 -152.941274) (xy 196.764656 -152.915874)
			(xy 196.768403 -152.912947) (xy 196.774804 -152.905916) (xy 196.777356 -152.901904) (xy 196.801869 -152.862175)
			(xy 196.857231 -152.787001) (xy 196.919376 -152.71733) (xy 196.98776 -152.653771) (xy 197.061784 -152.596881)
			(xy 197.140801 -152.547157) (xy 197.224119 -152.505036) (xy 197.311008 -152.470885) (xy 197.400709 -152.445004)
			(xy 197.492436 -152.427619) (xy 197.585386 -152.418881) (xy 197.632066 -152.418288) (xy 197.674363 -152.418743)
			(xy 197.758652 -152.425924) (xy 197.842029 -152.440221) (xy 197.923895 -152.46153) (xy 198.003662 -152.489699)
			(xy 198.080755 -152.524525) (xy 198.15462 -152.565757) (xy 198.224726 -152.613099) (xy 198.290569 -152.666211)
			(xy 198.321422 -152.695148) (xy 198.328719 -152.701598) (xy 198.346746 -152.708919) (xy 198.356474 -152.709372)
			(xy 199.225916 -152.709372) (xy 199.228456 -152.707086) (xy 199.230996 -152.704546) (xy 199.24268 -152.691338)
			(xy 199.246744 -152.686766) (xy 199.252332 -152.680416) (xy 199.25919 -152.66416) (xy 199.259698 -152.65527)
			(xy 199.2609 -152.640402) (xy 199.265348 -152.610903) (xy 199.268588 -152.596342) (xy 199.276716 -152.566624)
			(xy 199.277979 -152.562102) (xy 199.278994 -152.552771) (xy 199.278748 -152.548082) (xy 199.276716 -152.485852)
			(xy 199.277149 -152.443484) (xy 199.284331 -152.359053) (xy 199.298658 -152.275537) (xy 199.320025 -152.19354)
			(xy 199.348278 -152.113653) (xy 199.365362 -152.07488) (xy 199.369331 -152.064841) (xy 199.369313 -152.043273)
			(xy 199.365362 -152.033224) (xy 199.348321 -151.994435) (xy 199.32009 -151.914545) (xy 199.298731 -151.832551)
			(xy 199.284399 -151.749041) (xy 199.277197 -151.664617) (xy 199.276716 -151.622252) (xy 199.278748 -151.560022)
			(xy 199.27892 -151.555324) (xy 199.277775 -151.545994) (xy 199.276462 -151.54148) (xy 199.273078 -151.530395)
			(xy 199.267488 -151.507901) (xy 199.265286 -151.496522) (xy 199.265286 -151.496268) (xy 199.263 -151.484584)
			(xy 199.256142 -151.47544) (xy 199.252666 -151.470943) (xy 199.244071 -151.463507) (xy 199.239124 -151.460708)
			(xy 199.236076 -151.45893) (xy 199.231504 -151.456644) (xy 199.226932 -151.45512) (xy 199.210051 -151.449807)
			(xy 199.176642 -151.438121) (xy 199.16013 -151.431752) (xy 199.159622 -151.431752) (xy 199.147938 -151.426926)
			(xy 199.128766 -151.418988) (xy 199.091035 -151.401711) (xy 199.0725 -151.392382) (xy 199.06996 -151.391112)
			(xy 199.064533 -151.388528) (xy 199.052854 -151.385703) (xy 199.046846 -151.385524) (xy 198.356474 -151.385524)
			(xy 198.346754 -151.38601) (xy 198.328736 -151.393326) (xy 198.321422 -151.399748) (xy 198.290555 -151.428668)
			(xy 198.224706 -151.48177) (xy 198.154598 -151.529105) (xy 198.080733 -151.570334) (xy 198.003643 -151.605161)
			(xy 197.923881 -151.633335) (xy 197.842019 -151.654655) (xy 197.758647 -151.668967) (xy 197.674362 -151.676169)
			(xy 197.632066 -151.676608) (xy 197.585383 -151.676067) (xy 197.492425 -151.667344) (xy 197.400689 -151.649968)
			(xy 197.31098 -151.624092) (xy 197.224083 -151.589942) (xy 197.14076 -151.547818) (xy 197.06174 -151.498088)
			(xy 196.987715 -151.441188) (xy 196.919334 -151.377616) (xy 196.857196 -151.30793) (xy 196.801846 -151.232739)
			(xy 196.777356 -151.192992) (xy 196.77476 -151.189014) (xy 196.768367 -151.181988) (xy 196.764656 -151.179022)
			(xy 196.74205 -151.160821) (xy 196.70208 -151.118745) (xy 196.66893 -151.07111) (xy 196.643362 -151.019011)
			(xy 196.625964 -150.963646) (xy 196.617135 -150.906287) (xy 196.616574 -150.87727) (xy 196.616574 -150.870158)
			(xy 196.617336 -150.851362) (xy 196.61759 -150.849584) (xy 196.61759 -150.847552) (xy 196.61886 -150.829518)
			(xy 196.619114 -150.826724) (xy 196.619622 -150.82393) (xy 196.622162 -150.810976) (xy 196.622416 -150.809452)
			(xy 196.624708 -150.797226) (xy 196.63068 -150.773076) (xy 196.634354 -150.761192) (xy 196.635716 -150.756623)
			(xy 196.636867 -150.747159) (xy 196.63664 -150.742396) (xy 196.63569 -150.726602) (xy 196.634675 -150.694973)
			(xy 196.634608 -150.67915) (xy 196.635041 -150.636782) (xy 196.642224 -150.552351) (xy 196.65655 -150.468836)
			(xy 196.677917 -150.386838) (xy 196.70617 -150.306951) (xy 196.723254 -150.268178) (xy 196.727245 -150.258138)
			(xy 196.727264 -150.236552) (xy 196.723254 -150.226522) (xy 196.706219 -150.187757) (xy 196.677993 -150.107918)
			(xy 196.656631 -150.025975) (xy 196.642287 -149.942517) (xy 196.635063 -149.858144) (xy 196.634608 -149.815804)
			(xy 196.634608 -149.815296) (xy 196.63537 -149.780244) (xy 196.635476 -149.775398) (xy 196.634062 -149.765808)
			(xy 196.632576 -149.761194) (xy 196.624105 -149.735962) (xy 196.613486 -149.683809) (xy 196.610233 -149.630684)
			(xy 196.614409 -149.577624) (xy 196.625934 -149.525663) (xy 196.634862 -149.50059) (xy 196.635878 -149.497542)
			(xy 196.639942 -149.485096) (xy 196.64299 -149.478492) (xy 196.643244 -149.477984) (xy 196.647054 -149.468586)
			(xy 196.64807 -149.465538) (xy 196.650102 -149.461474) (xy 196.660574 -149.439062) (xy 196.68646 -149.396904)
			(xy 196.717566 -149.358436) (xy 196.735192 -149.341078) (xy 196.764656 -149.315678) (xy 196.768403 -149.312751)
			(xy 196.774804 -149.30572) (xy 196.777356 -149.301708) (xy 196.801869 -149.261979) (xy 196.857231 -149.186804)
			(xy 196.919376 -149.117133) (xy 196.98776 -149.053574) (xy 197.061784 -148.996684) (xy 197.140801 -148.94696)
			(xy 197.224118 -148.904839) (xy 197.311008 -148.870688) (xy 197.400709 -148.844806) (xy 197.492436 -148.827421)
			(xy 197.585386 -148.818683) (xy 197.632066 -148.818092) (xy 197.674363 -148.818547) (xy 197.758652 -148.825728)
			(xy 197.842029 -148.840025) (xy 197.923895 -148.861334) (xy 198.003662 -148.889503) (xy 198.080754 -148.924329)
			(xy 198.15462 -148.965562) (xy 198.224726 -149.012904) (xy 198.290569 -149.066016) (xy 198.321422 -149.094952)
			(xy 198.328719 -149.101402) (xy 198.346746 -149.108722) (xy 198.356474 -149.109176) (xy 199.22617 -149.109176)
			(xy 199.230742 -149.104604) (xy 199.241664 -149.092158) (xy 199.247252 -149.085808) (xy 199.259444 -149.056598)
			(xy 199.260206 -149.048724) (xy 199.260206 -149.04847) (xy 199.262315 -149.027806) (xy 199.270457 -148.987074)
			(xy 199.276462 -148.96719) (xy 199.277803 -148.962682) (xy 199.278952 -148.953347) (xy 199.278748 -148.948648)
			(xy 199.276716 -148.88591) (xy 199.27715 -148.843542) (xy 199.284337 -148.759113) (xy 199.298666 -148.675598)
			(xy 199.320036 -148.593602) (xy 199.348292 -148.513717) (xy 199.365362 -148.474938) (xy 199.369344 -148.464898)
			(xy 199.369348 -148.44332) (xy 199.365362 -148.433282) (xy 199.348319 -148.394493) (xy 199.320083 -148.314604)
			(xy 199.29872 -148.23261) (xy 199.284383 -148.1491) (xy 199.277175 -148.064676) (xy 199.276716 -148.02231)
			(xy 199.277224 -147.992846) (xy 199.277732 -147.978622) (xy 199.271128 -147.964398) (xy 199.265794 -147.95881)
			(xy 199.264778 -147.957794) (xy 199.24141 -147.933918) (xy 199.219312 -147.911312) (xy 199.213199 -147.90603)
			(xy 199.198579 -147.89918) (xy 199.19061 -147.89785) (xy 199.184514 -147.897596) (xy 198.836788 -147.897596)
			(xy 198.788656 -147.896997) (xy 198.692853 -147.887586) (xy 198.645526 -147.8788) (xy 198.63308 -147.87626)
			(xy 198.61716 -147.872842) (xy 198.585531 -147.865093) (xy 198.569834 -147.860766) (xy 198.523729 -147.847282)
			(xy 198.434161 -147.812548) (xy 198.391018 -147.791424) (xy 198.39051 -147.790916) (xy 198.385231 -147.788542)
			(xy 198.373945 -147.785981) (xy 198.368158 -147.785836) (xy 198.356728 -147.785836) (xy 198.347032 -147.78627)
			(xy 198.32902 -147.793459) (xy 198.321676 -147.799806) (xy 198.290798 -147.828729) (xy 198.224925 -147.881832)
			(xy 198.154788 -147.929161) (xy 198.080893 -147.970375) (xy 198.00377 -148.005179) (xy 197.923976 -148.033322)
			(xy 197.842083 -148.0546) (xy 197.758682 -148.068862) (xy 197.674372 -148.076005) (xy 197.632066 -148.076412)
			(xy 197.585372 -148.07588) (xy 197.492392 -148.067171) (xy 197.400633 -148.049807) (xy 197.310901 -148.023937)
			(xy 197.223981 -147.98979) (xy 197.140634 -147.947665) (xy 197.061593 -147.89793) (xy 196.987548 -147.841021)
			(xy 196.91915 -147.777438) (xy 196.856997 -147.707737) (xy 196.801635 -147.63253) (xy 196.777102 -147.592796)
			(xy 196.774586 -147.588814) (xy 196.768325 -147.581779) (xy 196.764656 -147.578826) (xy 196.742272 -147.560851)
			(xy 196.702643 -147.519316) (xy 196.669683 -147.472314) (xy 196.644135 -147.420905) (xy 196.626575 -147.36625)
			(xy 196.617399 -147.309581) (xy 196.616574 -147.280884) (xy 196.616574 -147.27174) (xy 196.617388 -147.243465)
			(xy 196.626311 -147.187608) (xy 196.634354 -147.160488) (xy 196.635702 -147.155981) (xy 196.63685 -147.146646)
			(xy 196.63664 -147.141946) (xy 196.634608 -147.079208) (xy 196.635043 -147.03684) (xy 196.642229 -146.952411)
			(xy 196.656559 -146.868896) (xy 196.677929 -146.7869) (xy 196.706184 -146.707015) (xy 196.723254 -146.668236)
			(xy 196.727236 -146.658196) (xy 196.727239 -146.636618) (xy 196.723254 -146.62658) (xy 196.706211 -146.587791)
			(xy 196.677976 -146.507902) (xy 196.656613 -146.425908) (xy 196.642276 -146.342398) (xy 196.635069 -146.257974)
			(xy 196.634608 -146.215608) (xy 196.634677 -146.199722) (xy 196.635694 -146.167966) (xy 196.63664 -146.152108)
			(xy 196.636884 -146.14742) (xy 196.635863 -146.138089) (xy 196.634608 -146.133566) (xy 196.62902 -146.114516)
			(xy 196.624109 -146.094776) (xy 196.617995 -146.05456) (xy 196.616828 -146.034252) (xy 196.616574 -146.028156)
			(xy 196.616574 -146.01571) (xy 196.617276 -145.986832) (xy 196.626309 -145.92978) (xy 196.643824 -145.874736)
			(xy 196.669422 -145.822955) (xy 196.70252 -145.775615) (xy 196.742365 -145.733794) (xy 196.76491 -145.715736)
			(xy 196.768573 -145.712776) (xy 196.774834 -145.705743) (xy 196.777356 -145.701766) (xy 196.80188 -145.662051)
			(xy 196.85726 -145.586906) (xy 196.919418 -145.517264) (xy 196.987809 -145.453733) (xy 197.061837 -145.396868)
			(xy 197.140853 -145.347168) (xy 197.224167 -145.305067) (xy 197.311049 -145.270933) (xy 197.40074 -145.245064)
			(xy 197.492455 -145.227687) (xy 197.585393 -145.218955) (xy 197.632066 -145.218404) (xy 197.63232 -145.218404)
			(xy 197.674596 -145.218864) (xy 197.758842 -145.226049) (xy 197.842177 -145.24034) (xy 197.924003 -145.261635)
			(xy 198.003733 -145.289781) (xy 198.080793 -145.324576) (xy 198.154632 -145.36577) (xy 198.224718 -145.413066)
			(xy 198.290548 -145.466126) (xy 198.321422 -145.49501) (xy 198.328745 -145.501387) (xy 198.346772 -145.508563)
			(xy 198.356474 -145.50898) (xy 199.226424 -145.50898) (xy 199.230488 -145.504916) (xy 199.248522 -145.485104)
			(xy 199.251824 -145.474944) (xy 199.259698 -145.45564) (xy 199.260206 -145.44802) (xy 199.260968 -145.440654)
			(xy 199.26324 -145.421938) (xy 199.271002 -145.38504) (xy 199.276462 -145.366994) (xy 199.277803 -145.362486)
			(xy 199.278953 -145.353151) (xy 199.278748 -145.348452) (xy 199.276716 -145.285714) (xy 199.27715 -145.243346)
			(xy 199.284336 -145.158917) (xy 199.298666 -145.075402) (xy 199.320035 -144.993406) (xy 199.348291 -144.91352)
			(xy 199.365362 -144.874742) (xy 199.369345 -144.864702) (xy 199.36935 -144.843123) (xy 199.365362 -144.833086)
			(xy 199.348318 -144.794297) (xy 199.320082 -144.714408) (xy 199.298719 -144.632414) (xy 199.284382 -144.548904)
			(xy 199.277174 -144.46448) (xy 199.276716 -144.422114) (xy 199.278748 -144.359376) (xy 199.278916 -144.354679)
			(xy 199.277763 -144.345351) (xy 199.276462 -144.340834) (xy 199.268125 -144.312673) (xy 199.259191 -144.254628)
			(xy 199.258682 -144.225264) (xy 199.258682 -144.222978) (xy 199.259227 -144.195401) (xy 199.267262 -144.140832)
			(xy 199.274684 -144.114266) (xy 199.2757 -144.110964) (xy 199.278494 -144.0942) (xy 199.27697 -144.085564)
			(xy 199.272906 -144.062196) (xy 199.271637 -144.055846) (xy 199.266356 -144.044026) (xy 199.262492 -144.038828)
			(xy 199.24014 -144.007332) (xy 199.222614 -143.98244) (xy 199.215756 -143.975836) (xy 199.215248 -143.975328)
			(xy 199.213216 -143.973804) (xy 199.118474 -143.973804) (xy 199.113454 -143.973894) (xy 199.103601 -143.97581)
			(xy 199.098916 -143.977614) (xy 198.779892 -144.109948) (xy 198.734524 -144.128061) (xy 198.641028 -144.156383)
			(xy 198.545211 -144.175434) (xy 198.447992 -144.185033) (xy 198.399146 -144.18564) (xy 198.346822 -144.18564)
			(xy 198.329042 -144.192752) (xy 198.321676 -144.199864) (xy 198.290804 -144.228801) (xy 198.224939 -144.281931)
			(xy 198.154808 -144.329287) (xy 198.080916 -144.37053) (xy 198.003795 -144.405362) (xy 197.923999 -144.433532)
			(xy 197.842103 -144.454839) (xy 197.758695 -144.469128) (xy 197.674377 -144.476297) (xy 197.632066 -144.476724)
			(xy 197.585383 -144.476183) (xy 197.492424 -144.46746) (xy 197.400689 -144.450084) (xy 197.310979 -144.424209)
			(xy 197.224082 -144.390059) (xy 197.140758 -144.347935) (xy 197.061737 -144.298205) (xy 196.987712 -144.241306)
			(xy 196.91933 -144.177735) (xy 196.857191 -144.108049) (xy 196.80184 -144.032859) (xy 196.777356 -143.993108)
			(xy 196.774761 -143.989129) (xy 196.768369 -143.982102) (xy 196.764656 -143.979138) (xy 196.74205 -143.960937)
			(xy 196.702078 -143.918862) (xy 196.668926 -143.871227) (xy 196.643356 -143.819128) (xy 196.625955 -143.763763)
			(xy 196.617124 -143.706403) (xy 196.616574 -143.677386) (xy 196.616574 -143.670274) (xy 196.617336 -143.651478)
			(xy 196.61759 -143.6497) (xy 196.61759 -143.647668) (xy 196.61886 -143.629634) (xy 196.619114 -143.62684)
			(xy 196.619622 -143.624046) (xy 196.622162 -143.611092) (xy 196.622416 -143.609568) (xy 196.624708 -143.597342)
			(xy 196.630679 -143.573192) (xy 196.634354 -143.561308) (xy 196.635718 -143.556739) (xy 196.636871 -143.547275)
			(xy 196.63664 -143.542512) (xy 196.63569 -143.526718) (xy 196.634674 -143.495089) (xy 196.634608 -143.479266)
			(xy 196.635044 -143.436899) (xy 196.642234 -143.35247) (xy 196.656567 -143.268957) (xy 196.67794 -143.186963)
			(xy 196.706199 -143.107079) (xy 196.723254 -143.068294) (xy 196.727227 -143.058255) (xy 196.727213 -143.036684)
			(xy 196.723254 -143.026638) (xy 196.706222 -142.987872) (xy 196.678003 -142.908032) (xy 196.656648 -142.826089)
			(xy 196.642311 -142.742632) (xy 196.635094 -142.65826) (xy 196.634608 -142.61592) (xy 196.634608 -142.615412)
			(xy 196.63537 -142.58036) (xy 196.635478 -142.575513) (xy 196.634067 -142.565923) (xy 196.632576 -142.56131)
			(xy 196.624104 -142.536078) (xy 196.613483 -142.483924) (xy 196.610228 -142.430799) (xy 196.614402 -142.377738)
			(xy 196.625924 -142.325776) (xy 196.634862 -142.300706) (xy 196.635878 -142.297658) (xy 196.639942 -142.285212)
			(xy 196.641974 -142.280386) (xy 196.644006 -142.276068) (xy 196.647054 -142.268448) (xy 196.64807 -142.265654)
			(xy 196.649848 -142.262352) (xy 196.650356 -142.260828) (xy 196.662817 -142.234644) (xy 196.694446 -142.186044)
			(xy 196.713348 -142.164054) (xy 196.725129 -142.151106) (xy 196.750696 -142.127191) (xy 196.764402 -142.116302)
			(xy 196.768143 -142.113369) (xy 196.77453 -142.10633) (xy 196.777102 -142.102332) (xy 196.799517 -142.065851)
			(xy 196.849698 -141.996468) (xy 196.905645 -141.931644) (xy 196.966947 -141.871859) (xy 197.033151 -141.817552)
			(xy 197.10377 -141.769124) (xy 197.178282 -141.726932) (xy 197.256139 -141.691287) (xy 197.336766 -141.662451)
			(xy 197.419569 -141.640638) (xy 197.503938 -141.626008) (xy 197.589252 -141.618669) (xy 197.632066 -141.618208)
			(xy 197.673998 -141.618647) (xy 197.757565 -141.625708) (xy 197.840244 -141.639765) (xy 197.921449 -141.660719)
			(xy 198.000606 -141.688422) (xy 198.077155 -141.722678) (xy 198.150556 -141.763245) (xy 198.220288 -141.809836)
			(xy 198.25335 -141.835632) (xy 198.264272 -141.844268) (xy 198.29145 -141.848078) (xy 198.472552 -141.773148)
			(xy 198.51792 -141.755037) (xy 198.611417 -141.726719) (xy 198.707234 -141.707672) (xy 198.804453 -141.698078)
			(xy 198.853298 -141.697456) (xy 199.74433 -141.697456) (xy 199.793145 -141.698068) (xy 199.890305 -141.707653)
			(xy 199.986061 -141.726698) (xy 200.079493 -141.75502) (xy 200.124822 -141.773148) (xy 200.998074 -142.134844)
			(xy 201.001884 -142.136114) (xy 201.441304 -142.2781) (xy 201.483712 -142.292279) (xy 201.56601 -142.327264)
			(xy 201.644811 -142.369539) (xy 201.719472 -142.418759) (xy 201.75474 -142.446248) (xy 201.754994 -142.446502)
			(xy 201.760582 -142.45082) (xy 201.901298 -142.508986) (xy 201.946294 -142.528292) (xy 202.032617 -142.574515)
			(xy 202.11399 -142.628981) (xy 202.189631 -142.691163) (xy 202.22464 -142.725394) (xy 202.632564 -143.133064)
			(xy 202.63739 -143.137128) (xy 203.204826 -143.581374) (xy 203.277724 -143.638778) (xy 203.286898 -143.645261)
			(xy 203.308753 -143.650335) (xy 203.330693 -143.645641) (xy 203.339954 -143.639286) (xy 203.339954 -143.639032)
			(xy 203.348463 -143.63183) (xy 203.358809 -143.612114) (xy 203.359869 -143.589873) (xy 203.35621 -143.579342)
			(xy 203.245466 -143.312388) (xy 203.243177 -143.307315) (xy 203.236779 -143.29821) (xy 203.232766 -143.294354)
			(xy 203.215576 -143.278472) (xy 203.182544 -143.245309) (xy 203.166726 -143.22806) (xy 203.165964 -143.227044)
			(xy 203.134978 -143.193587) (xy 203.078571 -143.121926) (xy 203.028942 -143.045416) (xy 202.986503 -142.964695)
			(xy 202.968606 -142.922752) (xy 202.7936 -142.500096) (xy 202.778479 -142.462531) (xy 202.753652 -142.385447)
			(xy 202.735153 -142.306604) (xy 202.723103 -142.226522) (xy 202.71994 -142.186152) (xy 202.719072 -142.177851)
			(xy 202.71273 -142.162424) (xy 202.707494 -142.155926) (xy 202.681051 -142.125047) (xy 202.632702 -142.05968)
			(xy 202.589834 -141.990594) (xy 202.552731 -141.918249) (xy 202.536806 -141.880844) (xy 202.3618 -141.458188)
			(xy 202.346656 -141.420565) (xy 202.321801 -141.343357) (xy 202.303303 -141.264385) (xy 202.291283 -141.184171)
			(xy 202.28814 -141.143736) (xy 202.28727 -141.135436) (xy 202.280924 -141.120012) (xy 202.275694 -141.11351)
			(xy 202.243449 -141.075648) (xy 202.1858 -140.994604) (xy 202.136489 -140.908233) (xy 202.115674 -140.863066)
			(xy 202.11542 -140.862812) (xy 202.113388 -140.862558) (xy 202.087503 -140.857227) (xy 202.037415 -140.840372)
			(xy 201.990132 -140.816766) (xy 201.946559 -140.786861) (xy 201.90753 -140.751228) (xy 201.873792 -140.71055)
			(xy 201.845991 -140.665605) (xy 201.82466 -140.617253) (xy 201.810205 -140.56642) (xy 201.802904 -140.514078)
			(xy 201.802492 -140.487654) (xy 201.802492 -140.476224) (xy 201.803931 -140.446985) (xy 201.814599 -140.389427)
			(xy 201.833927 -140.334171) (xy 201.847196 -140.308076) (xy 201.855324 -140.29309) (xy 201.857864 -140.289026)
			(xy 201.858372 -140.288518) (xy 201.86015 -140.285724) (xy 201.878184 -140.259308) (xy 201.879708 -140.257276)
			(xy 201.871242 -140.218796) (xy 201.859671 -140.140854) (xy 201.856594 -140.101574) (xy 201.855662 -140.093406)
			(xy 201.849316 -140.078249) (xy 201.844148 -140.071856) (xy 201.81639 -140.039379) (xy 201.765903 -139.970449)
			(xy 201.74331 -139.934188) (xy 201.742802 -139.933172) (xy 201.74204 -139.931902) (xy 201.741024 -139.930378)
			(xy 201.73696 -139.923774) (xy 201.736706 -139.92352) (xy 201.715233 -139.888615) (xy 201.677467 -139.815876)
			(xy 201.661268 -139.778232) (xy 201.606658 -139.647676) (xy 201.49058 -139.370562) (xy 201.490326 -139.370054)
			(xy 201.487024 -139.362434) (xy 201.487024 -139.36218) (xy 201.483214 -139.352782) (xy 201.481182 -139.347702)
			(xy 201.474832 -139.331192) (xy 201.474832 -139.330938) (xy 201.467974 -139.31265) (xy 201.46772 -139.311888)
			(xy 201.467466 -139.310364) (xy 201.459846 -139.287504) (xy 201.446798 -139.244646) (xy 201.42759 -139.157135)
			(xy 201.421492 -139.112752) (xy 201.41692 -139.069826) (xy 201.41565 -139.0523) (xy 201.415142 -139.043918)
			(xy 201.405744 -139.021566) (xy 201.400918 -139.015978) (xy 201.38922 -139.001992) (xy 201.366734 -138.973283)
			(xy 201.35596 -138.958574) (xy 201.354944 -138.95705) (xy 201.328265 -138.922123) (xy 201.280517 -138.848328)
			(xy 201.239512 -138.770583) (xy 201.222102 -138.730228) (xy 201.2188 -138.723624) (xy 201.093578 -138.424158)
			(xy 201.067416 -138.361674) (xy 201.050652 -138.321796) (xy 201.050652 -138.321542) (xy 201.046588 -138.31189)
			(xy 201.044556 -138.307064) (xy 201.044556 -138.30681) (xy 201.040492 -138.297158) (xy 201.038968 -138.292586)
			(xy 201.03846 -138.291316) (xy 201.030332 -138.269218) (xy 201.029824 -138.268456) (xy 201.026522 -138.25855)
			(xy 201.026522 -138.257788) (xy 201.023728 -138.249406) (xy 201.010938 -138.209401) (xy 200.991398 -138.127709)
			(xy 200.978863 -138.044654) (xy 200.975722 -138.002772) (xy 200.975214 -137.994136) (xy 200.96226 -137.963402)
			(xy 200.956418 -137.957052) (xy 200.939532 -137.93797) (xy 200.90751 -137.898328) (xy 200.89241 -137.877804)
			(xy 200.891902 -137.877042) (xy 200.889362 -137.873486) (xy 200.860914 -137.831576) (xy 200.838264 -137.79535)
			(xy 200.798582 -137.719679) (xy 200.781666 -137.680446) (xy 200.610724 -137.272776) (xy 200.603004 -137.254174)
			(xy 200.588904 -137.216443) (xy 200.58253 -137.197338) (xy 200.579482 -137.18794) (xy 200.561448 -137.165842)
			(xy 200.558908 -137.163131) (xy 200.55317 -137.158411) (xy 200.550018 -137.156444) (xy 200.52792 -137.144252)
			(xy 200.522586 -137.141966) (xy 200.504298 -137.146284) (xy 200.466548 -137.154847) (xy 200.390063 -137.166815)
			(xy 200.312882 -137.172824) (xy 200.274174 -137.173208) (xy 200.227491 -137.172667) (xy 200.134532 -137.163945)
			(xy 200.042796 -137.14657) (xy 199.953087 -137.120694) (xy 199.866189 -137.086545) (xy 199.782865 -137.044421)
			(xy 199.703844 -136.994691) (xy 199.629819 -136.937791) (xy 199.561438 -136.87422) (xy 199.499299 -136.804533)
			(xy 199.443948 -136.729343) (xy 199.419464 -136.689592) (xy 199.416868 -136.685613) (xy 199.410476 -136.678587)
			(xy 199.406764 -136.675622) (xy 199.384158 -136.657421) (xy 199.344187 -136.615345) (xy 199.311036 -136.567711)
			(xy 199.285468 -136.515612) (xy 199.268069 -136.460246) (xy 199.25924 -136.402887) (xy 199.258682 -136.37387)
			(xy 199.258682 -136.366758) (xy 199.259444 -136.347962) (xy 199.259698 -136.346184) (xy 199.259698 -136.344152)
			(xy 199.260968 -136.326118) (xy 199.261222 -136.323324) (xy 199.26173 -136.32053) (xy 199.26427 -136.307576)
			(xy 199.264524 -136.306052) (xy 199.266816 -136.293826) (xy 199.272788 -136.269676) (xy 199.276462 -136.257792)
			(xy 199.277824 -136.253223) (xy 199.278974 -136.243759) (xy 199.278748 -136.238996) (xy 199.277798 -136.223202)
			(xy 199.276783 -136.191573) (xy 199.276716 -136.17575) (xy 199.277149 -136.133382) (xy 199.284332 -136.048951)
			(xy 199.298658 -135.965436) (xy 199.320025 -135.883438) (xy 199.348278 -135.803551) (xy 199.365362 -135.764778)
			(xy 199.369352 -135.754738) (xy 199.369371 -135.733152) (xy 199.365362 -135.723122) (xy 199.348326 -135.684357)
			(xy 199.320101 -135.604518) (xy 199.298739 -135.522575) (xy 199.284394 -135.439117) (xy 199.27717 -135.354744)
			(xy 199.276716 -135.312404) (xy 199.276716 -135.311896) (xy 199.277224 -135.28548) (xy 199.277224 -135.284972)
			(xy 199.277732 -135.26516) (xy 199.27316 -135.259318) (xy 199.238362 -135.223504) (xy 199.237854 -135.222996)
			(xy 199.219566 -135.204708) (xy 199.215836 -135.201187) (xy 199.207261 -135.195558) (xy 199.202548 -135.193532)
			(xy 199.193912 -135.189976) (xy 198.921624 -135.189976) (xy 198.891062 -135.189729) (xy 198.830058 -135.185919)
			(xy 198.799704 -135.182356) (xy 198.799196 -135.182356) (xy 198.752634 -135.181818) (xy 198.659915 -135.173138)
			(xy 198.568408 -135.155853) (xy 198.478911 -135.130114) (xy 198.392203 -135.096145) (xy 198.350378 -135.075676)
			(xy 198.3359 -135.075676) (xy 198.304818 -135.106002) (xy 198.238219 -135.161742) (xy 198.167026 -135.211479)
			(xy 198.091778 -135.254837) (xy 198.013045 -135.291489) (xy 197.931423 -135.321155) (xy 197.847531 -135.343612)
			(xy 197.762003 -135.358689) (xy 197.675489 -135.366272) (xy 197.632066 -135.36676) (xy 197.585383 -135.366219)
			(xy 197.492426 -135.357495) (xy 197.400691 -135.340119) (xy 197.310983 -135.314242) (xy 197.224088 -135.280092)
			(xy 197.140766 -135.237966) (xy 197.061747 -135.188234) (xy 196.987724 -135.131333) (xy 196.919346 -135.06776)
			(xy 196.857211 -134.998072) (xy 196.801864 -134.92288) (xy 196.777356 -134.883144) (xy 196.774757 -134.879168)
			(xy 196.76836 -134.872148) (xy 196.764656 -134.869174) (xy 196.742053 -134.850972) (xy 196.702088 -134.808894)
			(xy 196.668944 -134.761259) (xy 196.643383 -134.70916) (xy 196.625991 -134.653795) (xy 196.61717 -134.596437)
			(xy 196.616574 -134.567422) (xy 196.616574 -134.56031) (xy 196.617336 -134.541514) (xy 196.61759 -134.539736)
			(xy 196.61759 -134.537704) (xy 196.61886 -134.51967) (xy 196.619114 -134.516876) (xy 196.619622 -134.514082)
			(xy 196.622162 -134.501128) (xy 196.622416 -134.499604) (xy 196.62471 -134.487378) (xy 196.630684 -134.463229)
			(xy 196.634354 -134.451344) (xy 196.635721 -134.446775) (xy 196.636881 -134.43731) (xy 196.63664 -134.432548)
			(xy 196.63569 -134.416754) (xy 196.634673 -134.385125) (xy 196.634608 -134.369302) (xy 196.635043 -134.326935)
			(xy 196.64223 -134.242505) (xy 196.65656 -134.158991) (xy 196.67793 -134.076995) (xy 196.706186 -133.99711)
			(xy 196.723254 -133.95833) (xy 196.727235 -133.94829) (xy 196.727235 -133.926713) (xy 196.723254 -133.916674)
			(xy 196.70622 -133.877909) (xy 196.677999 -133.798069) (xy 196.656641 -133.716126) (xy 196.6423 -133.632668)
			(xy 196.635081 -133.548296) (xy 196.634608 -133.505956) (xy 196.634608 -133.505448) (xy 196.63537 -133.470396)
			(xy 196.635481 -133.465549) (xy 196.634076 -133.455956) (xy 196.632576 -133.451346) (xy 196.624108 -133.426115)
			(xy 196.613496 -133.373962) (xy 196.610249 -133.320839) (xy 196.614432 -133.267782) (xy 196.625962 -133.215825)
			(xy 196.634862 -133.190742) (xy 196.635878 -133.187694) (xy 196.639942 -133.175248) (xy 196.64299 -133.168644)
			(xy 196.643244 -133.168136) (xy 196.647054 -133.158738) (xy 196.64807 -133.15569) (xy 196.650102 -133.151626)
			(xy 196.660572 -133.129212) (xy 196.686453 -133.08705) (xy 196.717556 -133.048579) (xy 196.735192 -133.03123)
			(xy 196.742267 -133.02455) (xy 196.757007 -133.011844) (xy 196.764656 -133.00583) (xy 196.768401 -133.002901)
			(xy 196.774796 -132.995867) (xy 196.777356 -132.99186) (xy 196.801868 -132.952129) (xy 196.857228 -132.876951)
			(xy 196.919371 -132.807276) (xy 196.987754 -132.743714) (xy 197.061777 -132.686821) (xy 197.140794 -132.637094)
			(xy 197.224113 -132.59497) (xy 197.311003 -132.560817) (xy 197.400705 -132.534934) (xy 197.492434 -132.517548)
			(xy 197.585385 -132.50881) (xy 197.632066 -132.508244) (xy 197.674363 -132.508699) (xy 197.758652 -132.51588)
			(xy 197.84203 -132.530176) (xy 197.923897 -132.551485) (xy 198.003664 -132.579653) (xy 198.080758 -132.614477)
			(xy 198.154624 -132.655708) (xy 198.224732 -132.703049) (xy 198.290577 -132.756159) (xy 198.321422 -132.785104)
			(xy 198.328721 -132.791548) (xy 198.346748 -132.798861) (xy 198.356474 -132.799328) (xy 199.225916 -132.799328)
			(xy 199.228456 -132.797042) (xy 199.230996 -132.794502) (xy 199.24268 -132.781294) (xy 199.246744 -132.776722)
			(xy 199.252332 -132.770372) (xy 199.25919 -132.754116) (xy 199.259698 -132.74421) (xy 199.261619 -132.721865)
			(xy 199.270026 -132.67781) (xy 199.276462 -132.656326) (xy 199.277806 -132.651818) (xy 199.278962 -132.642483)
			(xy 199.278748 -132.637784) (xy 199.276716 -132.575808) (xy 199.277151 -132.53344) (xy 199.284337 -132.449011)
			(xy 199.298667 -132.365496) (xy 199.320037 -132.2835) (xy 199.348293 -132.203615) (xy 199.365362 -132.164836)
			(xy 199.369343 -132.154796) (xy 199.369346 -132.133218) (xy 199.365362 -132.12318) (xy 199.348328 -132.084415)
			(xy 199.320106 -132.004575) (xy 199.298747 -131.922632) (xy 199.284406 -131.839175) (xy 199.277186 -131.754802)
			(xy 199.276716 -131.712462) (xy 199.276716 -131.711954) (xy 199.277224 -131.685538) (xy 199.277224 -131.68503)
			(xy 199.277732 -131.665726) (xy 199.271382 -131.657344) (xy 199.238362 -131.623308) (xy 199.237854 -131.6228)
			(xy 199.219566 -131.604512) (xy 199.215836 -131.60099) (xy 199.207261 -131.595361) (xy 199.202548 -131.593336)
			(xy 199.193912 -131.58978) (xy 198.92645 -131.58978) (xy 198.879704 -131.589213) (xy 198.786633 -131.580336)
			(xy 198.694818 -131.562705) (xy 198.605079 -131.536477) (xy 198.51822 -131.501887) (xy 198.476362 -131.481068)
			(xy 198.470935 -131.478486) (xy 198.459255 -131.475663) (xy 198.453248 -131.47548) (xy 198.346822 -131.47548)
			(xy 198.329042 -131.482592) (xy 198.321676 -131.489704) (xy 198.290804 -131.518642) (xy 198.224941 -131.571775)
			(xy 198.154811 -131.619135) (xy 198.080919 -131.66038) (xy 198.003798 -131.695214) (xy 197.924002 -131.723386)
			(xy 197.842105 -131.744694) (xy 197.758697 -131.758984) (xy 197.674378 -131.766153) (xy 197.632066 -131.766564)
			(xy 197.585383 -131.766023) (xy 197.492426 -131.757299) (xy 197.400691 -131.739923) (xy 197.310983 -131.714047)
			(xy 197.224087 -131.679896) (xy 197.140765 -131.63777) (xy 197.061747 -131.588039) (xy 196.987724 -131.531137)
			(xy 196.919345 -131.467564) (xy 196.85721 -131.397877) (xy 196.801862 -131.322685) (xy 196.777356 -131.282948)
			(xy 196.774836 -131.27897) (xy 196.768567 -131.271945) (xy 196.76491 -131.268978) (xy 196.742415 -131.250923)
			(xy 196.702605 -131.209187) (xy 196.669522 -131.161939) (xy 196.643921 -131.110254) (xy 196.626382 -131.055307)
			(xy 196.617304 -130.998347) (xy 196.616574 -130.969512) (xy 196.616574 -130.965956) (xy 196.616574 -130.965448)
			(xy 196.617178 -130.936404) (xy 196.626114 -130.879005) (xy 196.634354 -130.851148) (xy 196.635701 -130.84664)
			(xy 196.63686 -130.837305) (xy 196.63664 -130.832606) (xy 196.635686 -130.816748) (xy 196.634671 -130.784992)
			(xy 196.634608 -130.769106) (xy 196.635043 -130.726738) (xy 196.642229 -130.642309) (xy 196.656559 -130.558794)
			(xy 196.677929 -130.476798) (xy 196.706185 -130.396913) (xy 196.723254 -130.358134) (xy 196.727235 -130.348094)
			(xy 196.727238 -130.326516) (xy 196.723254 -130.316478) (xy 196.706211 -130.277689) (xy 196.677976 -130.1978)
			(xy 196.656613 -130.115806) (xy 196.642277 -130.032296) (xy 196.63507 -129.947872) (xy 196.634608 -129.905506)
			(xy 196.634677 -129.88962) (xy 196.635694 -129.857864) (xy 196.63664 -129.842006) (xy 196.636884 -129.837318)
			(xy 196.635862 -129.827988) (xy 196.634608 -129.823464) (xy 196.630544 -129.810002) (xy 196.624984 -129.788933)
			(xy 196.618107 -129.745903) (xy 196.616828 -129.72415) (xy 196.616574 -129.718054) (xy 196.616574 -129.705608)
			(xy 196.617276 -129.67673) (xy 196.626309 -129.619678) (xy 196.643825 -129.564635) (xy 196.669423 -129.512854)
			(xy 196.702521 -129.465514) (xy 196.742366 -129.423693) (xy 196.76491 -129.405634) (xy 196.768573 -129.402674)
			(xy 196.774834 -129.395641) (xy 196.777356 -129.391664) (xy 196.801868 -129.351933) (xy 196.857227 -129.276755)
			(xy 196.91937 -129.20708) (xy 196.987753 -129.143517) (xy 197.061777 -129.086624) (xy 197.140794 -129.036897)
			(xy 197.224112 -128.994773) (xy 197.311003 -128.96062) (xy 197.400705 -128.934737) (xy 197.492433 -128.91735)
			(xy 197.585385 -128.908612) (xy 197.632066 -128.908048) (xy 197.674363 -128.908503) (xy 197.758652 -128.915684)
			(xy 197.84203 -128.92998) (xy 197.923897 -128.951289) (xy 198.003664 -128.979457) (xy 198.080758 -129.014282)
			(xy 198.154624 -129.055513) (xy 198.224731 -129.102854) (xy 198.290576 -129.155964) (xy 198.321422 -129.184908)
			(xy 198.328721 -129.191352) (xy 198.346748 -129.198664) (xy 198.356474 -129.199132) (xy 200.36028 -129.199132)
			(xy 200.40926 -129.199713) (xy 200.50675 -129.209314) (xy 200.602828 -129.228426) (xy 200.69657 -129.256864)
			(xy 200.742042 -129.275078) (xy 201.771758 -129.701544) (xy 201.781149 -129.70489) (xy 201.801065 -129.704888)
			(xy 201.819483 -129.697309) (xy 201.826876 -129.690622) (xy 201.837798 -129.6797) (xy 201.843894 -129.649474)
			(xy 201.832464 -129.62255) (xy 201.81737 -129.585643) (xy 201.792429 -129.5099) (xy 201.773617 -129.432407)
			(xy 201.761054 -129.353658) (xy 201.757534 -129.31394) (xy 201.75658 -129.305836) (xy 201.750226 -129.290816)
			(xy 201.745088 -129.284476) (xy 201.718957 -129.254124) (xy 201.671098 -129.189896) (xy 201.628554 -129.122031)
			(xy 201.591602 -129.050966) (xy 201.57567 -129.01422) (xy 201.398124 -128.59258) (xy 201.38303 -128.555673)
			(xy 201.358087 -128.47993) (xy 201.339273 -128.402437) (xy 201.326709 -128.323689) (xy 201.323194 -128.28397)
			(xy 201.322244 -128.275865) (xy 201.315892 -128.260842) (xy 201.310748 -128.254506) (xy 201.284615 -128.224155)
			(xy 201.236751 -128.15993) (xy 201.194204 -128.092066) (xy 201.157247 -128.021002) (xy 201.14133 -127.98425)
			(xy 200.963784 -127.56261) (xy 200.946783 -127.520864) (xy 200.919506 -127.434944) (xy 200.900105 -127.346911)
			(xy 200.893934 -127.30226) (xy 200.891394 -127.292354) (xy 200.878766 -127.253968) (xy 200.85908 -127.175588)
			(xy 200.84586 -127.095862) (xy 200.842118 -127.055626) (xy 200.839578 -127.014732) (xy 200.839331 -127.010368)
			(xy 200.837538 -127.001814) (xy 200.836022 -126.997714) (xy 200.818582 -126.953471) (xy 200.791227 -126.862383)
			(xy 200.781412 -126.81585) (xy 200.613518 -125.971046) (xy 200.613264 -125.970792) (xy 200.551542 -125.931676)
			(xy 200.541382 -125.92685) (xy 200.522078 -125.931676) (xy 200.52157 -125.931676) (xy 200.481098 -125.941649)
			(xy 200.398916 -125.955621) (xy 200.315854 -125.96268) (xy 200.274174 -125.963172) (xy 200.227491 -125.962631)
			(xy 200.134533 -125.953909) (xy 200.042798 -125.936533) (xy 199.953089 -125.910657) (xy 199.866193 -125.876507)
			(xy 199.782869 -125.834382) (xy 199.70385 -125.784651) (xy 199.629826 -125.72775) (xy 199.561447 -125.664177)
			(xy 199.49931 -125.59449) (xy 199.443962 -125.519298) (xy 199.419464 -125.479556) (xy 199.416944 -125.475578)
			(xy 199.410677 -125.468551) (xy 199.407018 -125.465586) (xy 199.384523 -125.447532) (xy 199.34471 -125.405796)
			(xy 199.311626 -125.358548) (xy 199.286023 -125.306863) (xy 199.268482 -125.251915) (xy 199.259403 -125.194955)
			(xy 199.258682 -125.16612) (xy 199.258682 -125.162564) (xy 199.258682 -125.162056) (xy 199.259286 -125.133012)
			(xy 199.26822 -125.075613) (xy 199.276462 -125.047756) (xy 199.277807 -125.043249) (xy 199.278949 -125.033914)
			(xy 199.278748 -125.029214) (xy 199.277794 -125.013356) (xy 199.276778 -124.9816) (xy 199.276716 -124.965714)
			(xy 199.27715 -124.923346) (xy 199.284336 -124.838917) (xy 199.298666 -124.755402) (xy 199.320035 -124.673406)
			(xy 199.348291 -124.59352) (xy 199.365362 -124.554742) (xy 199.369345 -124.544702) (xy 199.36935 -124.523123)
			(xy 199.365362 -124.513086) (xy 199.348318 -124.474297) (xy 199.320082 -124.394408) (xy 199.298719 -124.312414)
			(xy 199.284382 -124.228904) (xy 199.277174 -124.14448) (xy 199.276716 -124.102114) (xy 199.278748 -124.039122)
			(xy 199.27892 -124.034424) (xy 199.277775 -124.025094) (xy 199.276462 -124.02058) (xy 199.271727 -124.004992)
			(xy 199.264609 -123.973198) (xy 199.262238 -123.95708) (xy 199.261984 -123.955556) (xy 199.260328 -123.946289)
			(xy 199.25131 -123.929785) (xy 199.236945 -123.917644) (xy 199.228202 -123.914154) (xy 199.200803 -123.904606)
			(xy 199.147048 -123.882747) (xy 199.12076 -123.870466) (xy 199.115586 -123.868204) (xy 199.104562 -123.865766)
			(xy 199.098916 -123.86564) (xy 198.356474 -123.86564) (xy 198.346754 -123.866127) (xy 198.328737 -123.873445)
			(xy 198.321422 -123.879864) (xy 198.290555 -123.908784) (xy 198.224706 -123.961884) (xy 198.154597 -124.009219)
			(xy 198.080732 -124.050447) (xy 198.003642 -124.085273) (xy 197.92388 -124.113447) (xy 197.842019 -124.134767)
			(xy 197.758646 -124.149079) (xy 197.674362 -124.156281) (xy 197.632066 -124.156724) (xy 197.585383 -124.156183)
			(xy 197.492424 -124.14746) (xy 197.400689 -124.130084) (xy 197.310979 -124.104209) (xy 197.224082 -124.070059)
			(xy 197.140758 -124.027935) (xy 197.061737 -123.978205) (xy 196.987712 -123.921306) (xy 196.91933 -123.857735)
			(xy 196.857191 -123.788049) (xy 196.80184 -123.712859) (xy 196.777356 -123.673108) (xy 196.774839 -123.669127)
			(xy 196.768575 -123.662096) (xy 196.76491 -123.659138) (xy 196.742417 -123.641083) (xy 196.702611 -123.599345)
			(xy 196.669534 -123.552096) (xy 196.643937 -123.500411) (xy 196.626404 -123.445464) (xy 196.617333 -123.388506)
			(xy 196.616574 -123.359672) (xy 196.616574 -123.356116) (xy 196.616574 -123.355608) (xy 196.617174 -123.326563)
			(xy 196.626101 -123.269162) (xy 196.634354 -123.241308) (xy 196.635704 -123.236801) (xy 196.636856 -123.227465)
			(xy 196.63664 -123.222766) (xy 196.635685 -123.206908) (xy 196.634668 -123.175152) (xy 196.634608 -123.159266)
			(xy 196.635044 -123.116899) (xy 196.642234 -123.03247) (xy 196.656567 -122.948957) (xy 196.67794 -122.866963)
			(xy 196.706199 -122.787079) (xy 196.723254 -122.748294) (xy 196.727227 -122.738255) (xy 196.727213 -122.716684)
			(xy 196.723254 -122.706638) (xy 196.706212 -122.667849) (xy 196.677981 -122.58796) (xy 196.656621 -122.505965)
			(xy 196.642288 -122.422455) (xy 196.635084 -122.338031) (xy 196.634608 -122.295666) (xy 196.634676 -122.27978)
			(xy 196.635691 -122.248024) (xy 196.63664 -122.232166) (xy 196.63688 -122.227479) (xy 196.635852 -122.21815)
			(xy 196.634608 -122.213624) (xy 196.630544 -122.200162) (xy 196.624986 -122.179093) (xy 196.618114 -122.136062)
			(xy 196.616828 -122.11431) (xy 196.616574 -122.108214) (xy 196.616574 -122.095768) (xy 196.617279 -122.066892)
			(xy 196.626318 -122.009843) (xy 196.643837 -121.954804) (xy 196.669439 -121.903027) (xy 196.702539 -121.855692)
			(xy 196.742385 -121.813875) (xy 196.76491 -121.795794) (xy 196.768575 -121.792836) (xy 196.774844 -121.785808)
			(xy 196.777356 -121.781824) (xy 196.801869 -121.742094) (xy 196.85723 -121.666919) (xy 196.919374 -121.597246)
			(xy 196.987758 -121.533686) (xy 197.061782 -121.476795) (xy 197.140799 -121.427071) (xy 197.224117 -121.384948)
			(xy 197.311007 -121.350797) (xy 197.400708 -121.324915) (xy 197.492435 -121.307529) (xy 197.585386 -121.298792)
			(xy 197.632066 -121.298208) (xy 197.674363 -121.298663) (xy 197.758652 -121.305844) (xy 197.842029 -121.320141)
			(xy 197.923895 -121.341451) (xy 198.003661 -121.36962) (xy 198.080753 -121.404447) (xy 198.154618 -121.445679)
			(xy 198.224724 -121.493022) (xy 198.290566 -121.546135) (xy 198.321422 -121.575068) (xy 198.32872 -121.581516)
			(xy 198.346747 -121.588834) (xy 198.356474 -121.589292) (xy 199.225916 -121.589292) (xy 199.228456 -121.587006)
			(xy 199.230996 -121.584466) (xy 199.24268 -121.571258) (xy 199.246744 -121.566686) (xy 199.252332 -121.560336)
			(xy 199.25919 -121.54408) (xy 199.259698 -121.534174) (xy 199.261616 -121.511828) (xy 199.270015 -121.467771)
			(xy 199.276462 -121.44629) (xy 199.277803 -121.441782) (xy 199.278952 -121.432447) (xy 199.278748 -121.427748)
			(xy 199.276716 -121.365772) (xy 199.277152 -121.323405) (xy 199.284341 -121.238976) (xy 199.298674 -121.155463)
			(xy 199.320047 -121.073468) (xy 199.348305 -120.993585) (xy 199.365362 -120.9548) (xy 199.369335 -120.944761)
			(xy 199.369324 -120.923189) (xy 199.365362 -120.913144) (xy 199.34832 -120.874355) (xy 199.320087 -120.794466)
			(xy 199.298727 -120.712471) (xy 199.284394 -120.628961) (xy 199.277189 -120.544537) (xy 199.276716 -120.502172)
			(xy 199.277224 -120.472962) (xy 199.277732 -120.458738) (xy 199.272144 -120.446038) (xy 199.266302 -120.439688)
			(xy 199.231504 -120.40235) (xy 199.229726 -120.400318) (xy 199.2269 -120.397773) (xy 199.220651 -120.393441)
			(xy 199.21728 -120.391682) (xy 199.19061 -120.37822) (xy 199.177656 -120.377458) (xy 199.176894 -120.377458)
			(xy 199.133968 -120.373394) (xy 199.111607 -120.370663) (xy 199.06714 -120.36342) (xy 199.045068 -120.358916)
			(xy 198.995981 -120.347908) (xy 198.900164 -120.317238) (xy 198.853806 -120.297702) (xy 198.852282 -120.297194)
			(xy 198.837043 -120.29103) (xy 198.806937 -120.27782) (xy 198.792084 -120.270778) (xy 198.791576 -120.270778)
			(xy 198.781416 -120.265952) (xy 198.356474 -120.265952) (xy 198.346773 -120.266375) (xy 198.328742 -120.273544)
			(xy 198.321422 -120.279922) (xy 198.290565 -120.308825) (xy 198.224737 -120.361891) (xy 198.154651 -120.409192)
			(xy 198.080812 -120.450387) (xy 198.003748 -120.48518) (xy 197.924015 -120.513321) (xy 197.842185 -120.534609)
			(xy 197.758846 -120.54889) (xy 197.674597 -120.556061) (xy 197.63232 -120.556528) (xy 197.632066 -120.556528)
			(xy 197.585374 -120.555983) (xy 197.4924 -120.547253) (xy 197.400648 -120.529872) (xy 197.310921 -120.503993)
			(xy 197.224006 -120.469843) (xy 197.140663 -120.427719) (xy 197.061621 -120.377991) (xy 196.987572 -120.321095)
			(xy 196.919164 -120.257527) (xy 196.856996 -120.187844) (xy 196.801612 -120.112657) (xy 196.777102 -120.072912)
			(xy 196.774582 -120.068934) (xy 196.768313 -120.061909) (xy 196.764656 -120.058942) (xy 196.742271 -120.040967)
			(xy 196.702641 -119.999433) (xy 196.669679 -119.952431) (xy 196.644128 -119.901022) (xy 196.626566 -119.846367)
			(xy 196.617388 -119.789697) (xy 196.616574 -119.761) (xy 196.616574 -119.751856) (xy 196.617387 -119.72358)
			(xy 196.626308 -119.667723) (xy 196.634354 -119.640604) (xy 196.635703 -119.636097) (xy 196.636855 -119.626761)
			(xy 196.63664 -119.622062) (xy 196.634608 -119.559324) (xy 196.635042 -119.516956) (xy 196.642227 -119.432526)
			(xy 196.656556 -119.349011) (xy 196.677924 -119.267015) (xy 196.706179 -119.187129) (xy 196.723254 -119.148352)
			(xy 196.727239 -119.138312) (xy 196.727248 -119.116731) (xy 196.723254 -119.106696) (xy 196.70621 -119.067907)
			(xy 196.677974 -118.988019) (xy 196.65661 -118.906024) (xy 196.642272 -118.822514) (xy 196.635063 -118.73809)
			(xy 196.634608 -118.695724) (xy 196.634672 -118.679774) (xy 196.635687 -118.647891) (xy 196.63664 -118.63197)
			(xy 196.636808 -118.627273) (xy 196.635653 -118.617945) (xy 196.634354 -118.613428) (xy 196.627117 -118.589252)
			(xy 196.618324 -118.539559) (xy 196.616828 -118.514368) (xy 196.616574 -118.508272) (xy 196.616574 -118.495826)
			(xy 196.617282 -118.466951) (xy 196.626326 -118.409906) (xy 196.64385 -118.354871) (xy 196.669455 -118.303099)
			(xy 196.702558 -118.255768) (xy 196.742405 -118.213957) (xy 196.76491 -118.195852) (xy 196.768573 -118.192893)
			(xy 196.774837 -118.185861) (xy 196.777356 -118.181882) (xy 196.80188 -118.142167) (xy 196.857259 -118.067021)
			(xy 196.919416 -117.997377) (xy 196.987808 -117.933845) (xy 197.061835 -117.87698) (xy 197.140851 -117.827279)
			(xy 197.224165 -117.785177) (xy 197.311047 -117.751042) (xy 197.400739 -117.725173) (xy 197.492454 -117.707796)
			(xy 197.585392 -117.699063) (xy 197.632066 -117.69852) (xy 197.63232 -117.69852) (xy 197.674596 -117.69898)
			(xy 197.758842 -117.706165) (xy 197.842177 -117.720457) (xy 197.924003 -117.741752) (xy 198.003732 -117.769898)
			(xy 198.080792 -117.804693) (xy 198.15463 -117.845887) (xy 198.224716 -117.893185) (xy 198.290545 -117.946245)
			(xy 198.321422 -117.975126) (xy 198.328742 -117.981511) (xy 198.346769 -117.9887) (xy 198.356474 -117.989096)
			(xy 200.321926 -117.989096) (xy 200.363889 -117.989538) (xy 200.447516 -117.996609) (xy 200.530253 -118.010681)
			(xy 200.611516 -118.031655) (xy 200.690728 -118.059384) (xy 200.767331 -118.093669) (xy 200.840782 -118.13427)
			(xy 200.8759 -118.157244) (xy 203.81976 -120.123966) (xy 203.854435 -120.147629) (xy 203.9201 -120.199941)
			(xy 203.981132 -120.257592) (xy 204.037097 -120.320173) (xy 204.0876 -120.387239) (xy 204.132282 -120.458317)
			(xy 204.170827 -120.532901) (xy 204.187298 -120.571514) (xy 204.332485 -120.922034) (xy 205.550516 -120.922034)
			(xy 205.550998 -120.894664) (xy 205.558811 -120.840486) (xy 205.574297 -120.787983) (xy 205.597135 -120.738236)
			(xy 205.626856 -120.692268) (xy 205.644496 -120.671336) (xy 205.64475 -120.671082) (xy 205.650356 -120.664009)
			(xy 205.65659 -120.647082) (xy 205.656942 -120.638062) (xy 205.656942 -120.571006) (xy 205.656595 -120.561988)
			(xy 205.650342 -120.54507) (xy 205.64475 -120.537986) (xy 205.644496 -120.537986) (xy 205.644496 -120.537732)
			(xy 205.62689 -120.516772) (xy 205.597166 -120.470808) (xy 205.574321 -120.421066) (xy 205.558823 -120.368568)
			(xy 205.550992 -120.314394) (xy 205.550988 -120.259657) (xy 205.558812 -120.205482) (xy 205.574303 -120.152982)
			(xy 205.597141 -120.103237) (xy 205.626859 -120.057269) (xy 205.644496 -120.036336) (xy 205.64475 -120.036082)
			(xy 205.650356 -120.029009) (xy 205.65659 -120.012082) (xy 205.656942 -120.003062) (xy 205.656942 -119.936006)
			(xy 205.656595 -119.926988) (xy 205.650342 -119.91007) (xy 205.64475 -119.902986) (xy 205.644496 -119.902986)
			(xy 205.644496 -119.902732) (xy 205.62689 -119.881772) (xy 205.597166 -119.835808) (xy 205.574321 -119.786066)
			(xy 205.558823 -119.733568) (xy 205.550992 -119.679394) (xy 205.550988 -119.624657) (xy 205.558812 -119.570482)
			(xy 205.574303 -119.517982) (xy 205.597141 -119.468237) (xy 205.626859 -119.422269) (xy 205.644496 -119.401336)
			(xy 205.64475 -119.401082) (xy 205.650356 -119.394009) (xy 205.65659 -119.377082) (xy 205.656942 -119.368062)
			(xy 205.656942 -119.301006) (xy 205.656595 -119.291988) (xy 205.650342 -119.27507) (xy 205.64475 -119.267986)
			(xy 205.644496 -119.267986) (xy 205.644496 -119.267732) (xy 205.626858 -119.246799) (xy 205.597146 -119.200827)
			(xy 205.57431 -119.151079) (xy 205.558819 -119.098579) (xy 205.55099 -119.044403) (xy 205.550516 -119.017034)
			(xy 205.551002 -118.989783) (xy 205.558758 -118.935835) (xy 205.574113 -118.88354) (xy 205.596755 -118.833963)
			(xy 205.626221 -118.788113) (xy 205.661912 -118.746922) (xy 205.703103 -118.711231) (xy 205.748953 -118.681765)
			(xy 205.79853 -118.659123) (xy 205.850825 -118.643768) (xy 205.904773 -118.636012) (xy 205.959275 -118.636012)
			(xy 206.013223 -118.643768) (xy 206.065518 -118.659123) (xy 206.115095 -118.681765) (xy 206.160945 -118.711231)
			(xy 206.202136 -118.746922) (xy 206.237827 -118.788113) (xy 206.267293 -118.833963) (xy 206.289935 -118.88354)
			(xy 206.30529 -118.935835) (xy 206.313046 -118.989783) (xy 206.313532 -119.017034) (xy 206.313102 -119.044406)
			(xy 206.308435 -119.076724) (xy 206.521812 -119.076724) (xy 206.522278 -119.049471) (xy 206.530032 -118.995519)
			(xy 206.545386 -118.94322) (xy 206.568027 -118.893639) (xy 206.597494 -118.847784) (xy 206.633188 -118.806591)
			(xy 206.674381 -118.770897) (xy 206.720235 -118.741429) (xy 206.769816 -118.718787) (xy 206.822115 -118.703433)
			(xy 206.876067 -118.695678) (xy 206.90332 -118.695216) (xy 206.929635 -118.695665) (xy 206.981764 -118.702903)
			(xy 207.032407 -118.717225) (xy 207.080606 -118.738361) (xy 207.125449 -118.765911) (xy 207.166088 -118.799353)
			(xy 207.184244 -118.818406) (xy 207.191747 -118.82583) (xy 207.211041 -118.834341) (xy 207.221582 -118.834916)
			(xy 207.296258 -118.834916) (xy 207.306806 -118.834373) (xy 207.326101 -118.825847) (xy 207.333596 -118.818406)
			(xy 207.351762 -118.799361) (xy 207.392389 -118.765902) (xy 207.437227 -118.738342) (xy 207.485426 -118.717201)
			(xy 207.536072 -118.702882) (xy 207.588204 -118.695656) (xy 207.61452 -118.695216) (xy 207.641774 -118.695636)
			(xy 207.695728 -118.703397) (xy 207.748028 -118.718756) (xy 207.79761 -118.741403) (xy 207.843464 -118.770875)
			(xy 207.884658 -118.806574) (xy 207.920351 -118.847771) (xy 207.949818 -118.893628) (xy 207.972459 -118.943213)
			(xy 207.987813 -118.995515) (xy 207.995567 -119.049469) (xy 207.996028 -119.076724) (xy 207.995484 -119.105052)
			(xy 207.987121 -119.161088) (xy 207.970565 -119.215272) (xy 207.946183 -119.266414) (xy 207.914508 -119.31339)
			(xy 207.876238 -119.355167) (xy 207.832213 -119.390828) (xy 207.808068 -119.405654) (xy 207.800771 -119.410375)
			(xy 207.789587 -119.423659) (xy 207.783456 -119.439907) (xy 207.782922 -119.44858) (xy 207.781652 -119.535194)
			(xy 207.781921 -119.543867) (xy 207.787448 -119.560299) (xy 207.798142 -119.573943) (xy 207.805274 -119.578882)
			(xy 207.828199 -119.593999) (xy 207.869907 -119.629718) (xy 207.906067 -119.671043) (xy 207.935935 -119.717122)
			(xy 207.958893 -119.767004) (xy 207.974469 -119.819661) (xy 207.982341 -119.874006) (xy 207.98282 -119.901462)
			(xy 207.982309 -119.928713) (xy 207.974558 -119.982662) (xy 207.959207 -120.034958) (xy 207.93657 -120.084537)
			(xy 207.907107 -120.13039) (xy 207.871418 -120.171583) (xy 207.83023 -120.207277) (xy 207.784381 -120.236746)
			(xy 207.734805 -120.25939) (xy 207.682511 -120.274747) (xy 207.628563 -120.282506) (xy 207.601312 -120.28297)
			(xy 207.573942 -120.282504) (xy 207.519762 -120.274687) (xy 207.467259 -120.259199) (xy 207.417512 -120.236357)
			(xy 207.371545 -120.206632) (xy 207.350614 -120.18899) (xy 207.35036 -120.188736) (xy 207.343266 -120.183161)
			(xy 207.326355 -120.176909) (xy 207.31734 -120.176544) (xy 207.250284 -120.176544) (xy 207.241265 -120.176884)
			(xy 207.224348 -120.183142) (xy 207.217264 -120.188736) (xy 207.217264 -120.18899) (xy 207.21701 -120.18899)
			(xy 207.196084 -120.206636) (xy 207.150109 -120.236347) (xy 207.100361 -120.259182) (xy 207.047858 -120.274671)
			(xy 206.993682 -120.282497) (xy 206.966312 -120.28297) (xy 206.939058 -120.282533) (xy 206.885104 -120.274777)
			(xy 206.832803 -120.259421) (xy 206.783221 -120.236777) (xy 206.737366 -120.207306) (xy 206.696172 -120.17161)
			(xy 206.660478 -120.130414) (xy 206.631011 -120.084557) (xy 206.60837 -120.034972) (xy 206.593017 -119.982671)
			(xy 206.585265 -119.928716) (xy 206.584804 -119.901462) (xy 206.585272 -119.875526) (xy 206.592293 -119.824132)
			(xy 206.606213 -119.774163) (xy 206.626776 -119.726542) (xy 206.653603 -119.682146) (xy 206.686198 -119.641795)
			(xy 206.723961 -119.606233) (xy 206.744824 -119.59082) (xy 206.755746 -119.5832) (xy 206.766922 -119.55907)
			(xy 206.759556 -119.458994) (xy 206.758535 -119.450283) (xy 206.751384 -119.43428) (xy 206.739282 -119.421601)
			(xy 206.731616 -119.417338) (xy 206.708293 -119.405108) (xy 206.664963 -119.375173) (xy 206.626166 -119.339561)
			(xy 206.592639 -119.298948) (xy 206.56502 -119.254107) (xy 206.543835 -119.205892) (xy 206.529488 -119.15522)
			(xy 206.52225 -119.103056) (xy 206.521812 -119.076724) (xy 206.308435 -119.076724) (xy 206.305278 -119.098587)
			(xy 206.289782 -119.151091) (xy 206.266931 -119.200838) (xy 206.237198 -119.246802) (xy 206.219552 -119.267732)
			(xy 206.219298 -119.267986) (xy 206.213711 -119.275072) (xy 206.207465 -119.291989) (xy 206.207106 -119.301006)
			(xy 206.207106 -119.368062) (xy 206.20748 -119.377077) (xy 206.213716 -119.393994) (xy 206.219298 -119.401082)
			(xy 206.219552 -119.401082) (xy 206.219552 -119.401336) (xy 206.237227 -119.422241) (xy 206.266952 -119.468213)
			(xy 206.289797 -119.517964) (xy 206.305291 -119.57047) (xy 206.313117 -119.624653) (xy 206.313113 -119.679398)
			(xy 206.30528 -119.73358) (xy 206.289779 -119.786084) (xy 206.266927 -119.835832) (xy 206.237196 -119.8818)
			(xy 206.219552 -119.902732) (xy 206.219298 -119.902986) (xy 206.213711 -119.910072) (xy 206.207465 -119.926989)
			(xy 206.207106 -119.936006) (xy 206.207106 -120.003062) (xy 206.20748 -120.012077) (xy 206.213716 -120.028994)
			(xy 206.219298 -120.036082) (xy 206.219552 -120.036082) (xy 206.219552 -120.036336) (xy 206.237227 -120.057241)
			(xy 206.266952 -120.103213) (xy 206.289797 -120.152964) (xy 206.305291 -120.20547) (xy 206.313117 -120.259653)
			(xy 206.313113 -120.314398) (xy 206.310753 -120.330722) (xy 208.104232 -120.330722) (xy 208.104703 -120.303352)
			(xy 208.112519 -120.249173) (xy 208.128006 -120.196669) (xy 208.150847 -120.146922) (xy 208.180571 -120.100956)
			(xy 208.198212 -120.080024) (xy 208.198466 -120.07977) (xy 208.204037 -120.072673) (xy 208.210291 -120.055764)
			(xy 208.210658 -120.04675) (xy 208.210658 -119.979694) (xy 208.210313 -119.970676) (xy 208.204058 -119.953759)
			(xy 208.198466 -119.946674) (xy 208.198212 -119.946674) (xy 208.198212 -119.94642) (xy 208.180571 -119.92549)
			(xy 208.150859 -119.879517) (xy 208.128023 -119.829769) (xy 208.112533 -119.777268) (xy 208.104705 -119.723091)
			(xy 208.104232 -119.695722) (xy 208.104676 -119.668468) (xy 208.112431 -119.614514) (xy 208.127786 -119.562214)
			(xy 208.150429 -119.512631) (xy 208.179898 -119.466776) (xy 208.215594 -119.425582) (xy 208.25679 -119.389888)
			(xy 208.302647 -119.36042) (xy 208.35223 -119.33778) (xy 208.404532 -119.322427) (xy 208.458486 -119.314675)
			(xy 208.48574 -119.314214) (xy 208.514863 -119.314748) (xy 208.572435 -119.32358) (xy 208.627995 -119.341064)
			(xy 208.680251 -119.366792) (xy 208.727987 -119.400166) (xy 208.770093 -119.440411) (xy 208.80559 -119.48659)
			(xy 208.833653 -119.53763) (xy 208.853629 -119.592343) (xy 208.859882 -119.620792) (xy 208.862168 -119.632476)
			(xy 208.876646 -119.651272) (xy 208.96072 -119.691658) (xy 208.971533 -119.696221) (xy 208.994973 -119.69596)
			(xy 209.005678 -119.69115) (xy 209.006186 -119.69115) (xy 209.033242 -119.677863) (xy 209.090519 -119.659086)
			(xy 209.150038 -119.649569) (xy 209.180176 -119.648986) (xy 209.207428 -119.649478) (xy 209.261378 -119.657231)
			(xy 209.313675 -119.672584) (xy 209.363254 -119.695223) (xy 209.409107 -119.724688) (xy 209.4503 -119.760379)
			(xy 209.485994 -119.801569) (xy 209.515462 -119.847419) (xy 209.538106 -119.896997) (xy 209.553462 -119.949293)
			(xy 209.56122 -120.003242) (xy 209.561684 -120.030494) (xy 209.561218 -120.057864) (xy 209.553401 -120.112044)
			(xy 209.537912 -120.164547) (xy 209.51507 -120.214294) (xy 209.485345 -120.26026) (xy 209.467704 -120.281192)
			(xy 209.46745 -120.281446) (xy 209.461874 -120.28854) (xy 209.455622 -120.305451) (xy 209.455258 -120.314466)
			(xy 209.455258 -120.381522) (xy 209.455592 -120.390541) (xy 209.461854 -120.407459) (xy 209.46745 -120.414542)
			(xy 209.467704 -120.414542) (xy 209.467704 -120.414796) (xy 209.485355 -120.435718) (xy 209.515065 -120.481694)
			(xy 209.537899 -120.531444) (xy 209.553387 -120.583947) (xy 209.561212 -120.638124) (xy 209.561684 -120.665494)
			(xy 209.561239 -120.692748) (xy 209.553482 -120.746701) (xy 209.538126 -120.799) (xy 209.515482 -120.848582)
			(xy 209.486013 -120.894436) (xy 209.450317 -120.93563) (xy 209.409122 -120.971323) (xy 209.363266 -121.000791)
			(xy 209.313683 -121.023432) (xy 209.261383 -121.038786) (xy 209.20743 -121.04654) (xy 209.180176 -121.047002)
			(xy 209.151054 -121.046441) (xy 209.093484 -121.037611) (xy 209.037925 -121.020131) (xy 208.98567 -120.994406)
			(xy 208.937935 -120.961035) (xy 208.895828 -120.920794) (xy 208.86033 -120.874618) (xy 208.832266 -120.823582)
			(xy 208.812288 -120.768872) (xy 208.806034 -120.740424) (xy 208.803748 -120.72874) (xy 208.78927 -120.709944)
			(xy 208.705196 -120.669558) (xy 208.694379 -120.665004) (xy 208.670943 -120.665258) (xy 208.660238 -120.670066)
			(xy 208.65973 -120.670066) (xy 208.632671 -120.683349) (xy 208.575396 -120.702127) (xy 208.515877 -120.711646)
			(xy 208.48574 -120.71223) (xy 208.458489 -120.711708) (xy 208.404541 -120.703957) (xy 208.352246 -120.688607)
			(xy 208.302668 -120.665971) (xy 208.256815 -120.636509) (xy 208.215623 -120.600821) (xy 208.179928 -120.559634)
			(xy 208.150459 -120.513787) (xy 208.127815 -120.464212) (xy 208.112457 -120.411919) (xy 208.104697 -120.357973)
			(xy 208.104232 -120.330722) (xy 206.310753 -120.330722) (xy 206.30528 -120.36858) (xy 206.289779 -120.421084)
			(xy 206.266927 -120.470832) (xy 206.237196 -120.5168) (xy 206.219552 -120.537732) (xy 206.219298 -120.537986)
			(xy 206.213711 -120.545072) (xy 206.207465 -120.561989) (xy 206.207106 -120.571006) (xy 206.207106 -120.638062)
			(xy 206.20748 -120.647077) (xy 206.213716 -120.663994) (xy 206.219298 -120.671082) (xy 206.219552 -120.671082)
			(xy 206.219552 -120.671336) (xy 206.237167 -120.692288) (xy 206.266884 -120.738254) (xy 206.289726 -120.787997)
			(xy 206.305222 -120.840493) (xy 206.313055 -120.894666) (xy 206.313532 -120.922034) (xy 206.313046 -120.949285)
			(xy 206.30529 -121.003233) (xy 206.289935 -121.055528) (xy 206.267293 -121.105105) (xy 206.237827 -121.150955)
			(xy 206.202136 -121.192146) (xy 206.160945 -121.227837) (xy 206.115095 -121.257303) (xy 206.065518 -121.279945)
			(xy 206.013223 -121.2953) (xy 205.959275 -121.303056) (xy 205.904773 -121.303056) (xy 205.850825 -121.2953)
			(xy 205.79853 -121.279945) (xy 205.748953 -121.257303) (xy 205.703103 -121.227837) (xy 205.661912 -121.192146)
			(xy 205.626221 -121.150955) (xy 205.596755 -121.105105) (xy 205.574113 -121.055528) (xy 205.558758 -121.003233)
			(xy 205.551002 -120.949285) (xy 205.550516 -120.922034) (xy 204.332485 -120.922034) (xy 204.818147 -122.094549)
			(xy 210.164198 -122.094549) (xy 210.164198 -122.040051) (xy 210.171954 -121.986109) (xy 210.187306 -121.933819)
			(xy 210.209944 -121.884247) (xy 210.239406 -121.8384) (xy 210.275093 -121.797213) (xy 210.316278 -121.761523)
			(xy 210.362122 -121.732058) (xy 210.411693 -121.709416) (xy 210.463982 -121.694059) (xy 210.517924 -121.6863)
			(xy 210.545172 -121.685812) (xy 210.572542 -121.686292) (xy 210.62672 -121.694106) (xy 210.679223 -121.709591)
			(xy 210.728971 -121.73243) (xy 210.774938 -121.762152) (xy 210.79587 -121.779792) (xy 210.796124 -121.780046)
			(xy 210.803196 -121.785654) (xy 210.820124 -121.791887) (xy 210.829144 -121.792238) (xy 210.8962 -121.792238)
			(xy 210.905216 -121.791873) (xy 210.922132 -121.78563) (xy 210.92922 -121.780046) (xy 210.92922 -121.779792)
			(xy 210.929474 -121.779792) (xy 210.950407 -121.762151) (xy 210.996375 -121.732427) (xy 211.046121 -121.709581)
			(xy 211.098623 -121.694085) (xy 211.152801 -121.686256) (xy 211.207543 -121.686256) (xy 211.261721 -121.694085)
			(xy 211.314223 -121.709581) (xy 211.363969 -121.732427) (xy 211.409937 -121.762151) (xy 211.43087 -121.779792)
			(xy 211.431124 -121.780046) (xy 211.438196 -121.785654) (xy 211.455124 -121.791887) (xy 211.464144 -121.792238)
			(xy 211.5312 -121.792238) (xy 211.540216 -121.791873) (xy 211.557132 -121.78563) (xy 211.56422 -121.780046)
			(xy 211.56422 -121.779792) (xy 211.564474 -121.779792) (xy 211.585404 -121.76215) (xy 211.631378 -121.732439)
			(xy 211.681126 -121.709604) (xy 211.733627 -121.694113) (xy 211.787803 -121.686286) (xy 211.815172 -121.685812)
			(xy 211.842428 -121.686233) (xy 211.896384 -121.693987) (xy 211.948688 -121.709342) (xy 211.998275 -121.731984)
			(xy 212.044134 -121.761452) (xy 212.085332 -121.797148) (xy 212.121031 -121.838344) (xy 212.150503 -121.884201)
			(xy 212.173149 -121.933785) (xy 212.188507 -121.986088) (xy 212.196265 -122.040044) (xy 212.196265 -122.094556)
			(xy 212.188507 -122.148512) (xy 212.173149 -122.200815) (xy 212.150503 -122.250399) (xy 212.121031 -122.296256)
			(xy 212.085332 -122.337452) (xy 212.044134 -122.373148) (xy 211.998275 -122.402616) (xy 211.948688 -122.425258)
			(xy 211.896384 -122.440613) (xy 211.842428 -122.448367) (xy 211.815172 -122.448828) (xy 211.7878 -122.448396)
			(xy 211.733619 -122.440573) (xy 211.681115 -122.425077) (xy 211.631369 -122.402227) (xy 211.585404 -122.372494)
			(xy 211.564474 -122.354848) (xy 211.56422 -122.354594) (xy 211.557132 -122.349009) (xy 211.540216 -122.342762)
			(xy 211.5312 -122.342402) (xy 211.464144 -122.342402) (xy 211.455129 -122.34278) (xy 211.438212 -122.349013)
			(xy 211.431124 -122.354594) (xy 211.431124 -122.354848) (xy 211.43087 -122.354848) (xy 211.409937 -122.372489)
			(xy 211.363969 -122.402213) (xy 211.314223 -122.425059) (xy 211.261721 -122.440555) (xy 211.207543 -122.448384)
			(xy 211.152801 -122.448384) (xy 211.098623 -122.440555) (xy 211.046121 -122.425059) (xy 210.996375 -122.402213)
			(xy 210.950407 -122.372489) (xy 210.929474 -122.354848) (xy 210.92922 -122.354594) (xy 210.922132 -122.349009)
			(xy 210.905216 -122.342762) (xy 210.8962 -122.342402) (xy 210.829144 -122.342402) (xy 210.820129 -122.34278)
			(xy 210.803212 -122.349013) (xy 210.796124 -122.354594) (xy 210.796124 -122.354848) (xy 210.79587 -122.354848)
			(xy 210.774916 -122.37246) (xy 210.72895 -122.402177) (xy 210.679208 -122.425019) (xy 210.626712 -122.440517)
			(xy 210.57254 -122.448351) (xy 210.545172 -122.448828) (xy 210.517924 -122.4483) (xy 210.463982 -122.440541)
			(xy 210.411693 -122.425184) (xy 210.362122 -122.402542) (xy 210.316278 -122.373077) (xy 210.275093 -122.337387)
			(xy 210.239406 -122.2962) (xy 210.209944 -122.250353) (xy 210.187306 -122.200781) (xy 210.171954 -122.148491)
			(xy 210.164198 -122.094549) (xy 204.818147 -122.094549) (xy 205.181736 -122.972347) (xy 210.707522 -122.972347)
			(xy 210.707522 -122.917853) (xy 210.715277 -122.863913) (xy 210.730629 -122.811626) (xy 210.753266 -122.762057)
			(xy 210.782727 -122.716213) (xy 210.818412 -122.675028) (xy 210.859595 -122.63934) (xy 210.905437 -122.609877)
			(xy 210.955006 -122.587237) (xy 211.007292 -122.571882) (xy 211.061231 -122.564124) (xy 211.088478 -122.563636)
			(xy 211.116082 -122.564094) (xy 211.170715 -122.572036) (xy 211.223632 -122.587773) (xy 211.273727 -122.610975)
			(xy 211.319953 -122.641157) (xy 211.361345 -122.677689) (xy 211.397036 -122.719807) (xy 211.412074 -122.74296)
			(xy 211.420048 -122.754782) (xy 211.441213 -122.773872) (xy 211.466832 -122.786362) (xy 211.494906 -122.791279)
			(xy 211.523245 -122.78824) (xy 211.549637 -122.77748) (xy 211.572024 -122.759841) (xy 211.58073 -122.748548)
			(xy 211.596147 -122.7278) (xy 211.631687 -122.690264) (xy 211.67197 -122.657871) (xy 211.716258 -122.631215)
			(xy 211.76374 -122.610784) (xy 211.813546 -122.596953) (xy 211.864764 -122.589973) (xy 211.89061 -122.589544)
			(xy 211.917857 -122.590127) (xy 211.971797 -122.597884) (xy 212.024084 -122.613238) (xy 212.073654 -122.635876)
			(xy 212.119497 -122.665339) (xy 212.160681 -122.701026) (xy 212.196367 -122.742211) (xy 212.225828 -122.788055)
			(xy 212.248466 -122.837625) (xy 212.263819 -122.889913) (xy 212.271574 -122.943853) (xy 212.271574 -122.998347)
			(xy 212.263819 -123.052287) (xy 212.248466 -123.104575) (xy 212.225828 -123.154145) (xy 212.196367 -123.199989)
			(xy 212.160681 -123.241174) (xy 212.119497 -123.276861) (xy 212.073654 -123.306324) (xy 212.024084 -123.328962)
			(xy 211.971797 -123.344316) (xy 211.917857 -123.352073) (xy 211.89061 -123.35256) (xy 211.863008 -123.352036)
			(xy 211.808378 -123.344106) (xy 211.755463 -123.328381) (xy 211.705368 -123.30519) (xy 211.659141 -123.275018)
			(xy 211.617747 -123.238495) (xy 211.582053 -123.196385) (xy 211.567014 -123.173236) (xy 211.559055 -123.161403)
			(xy 211.537887 -123.142314) (xy 211.512265 -123.129824) (xy 211.484188 -123.124908) (xy 211.455847 -123.12795)
			(xy 211.429452 -123.138712) (xy 211.407064 -123.156354) (xy 211.398358 -123.167648) (xy 211.382947 -123.188401)
			(xy 211.347407 -123.225937) (xy 211.307123 -123.258329) (xy 211.262833 -123.284985) (xy 211.21535 -123.305415)
			(xy 211.165543 -123.319246) (xy 211.114324 -123.326223) (xy 211.088478 -123.326652) (xy 211.061231 -123.326076)
			(xy 211.007292 -123.318318) (xy 210.955006 -123.302963) (xy 210.905437 -123.280323) (xy 210.859595 -123.25086)
			(xy 210.818412 -123.215172) (xy 210.782727 -123.173987) (xy 210.753266 -123.128143) (xy 210.730629 -123.078574)
			(xy 210.715277 -123.026287) (xy 210.707522 -122.972347) (xy 205.181736 -122.972347) (xy 205.864842 -124.621544)
			(xy 211.274914 -124.621544) (xy 211.27534 -124.595229) (xy 211.282582 -124.543098) (xy 211.296909 -124.492454)
			(xy 211.31805 -124.444255) (xy 211.345603 -124.399413) (xy 211.379049 -124.358775) (xy 211.398104 -124.34062)
			(xy 211.405499 -124.333093) (xy 211.414027 -124.313817) (xy 211.414614 -124.303282) (xy 211.414614 -124.228606)
			(xy 211.414091 -124.218056) (xy 211.405551 -124.198761) (xy 211.398104 -124.191268) (xy 211.379041 -124.17312)
			(xy 211.345584 -124.132489) (xy 211.318026 -124.087647) (xy 211.296889 -124.039445) (xy 211.282573 -123.988796)
			(xy 211.275351 -123.936661) (xy 211.274914 -123.910344) (xy 211.2754 -123.883093) (xy 211.283156 -123.829145)
			(xy 211.298511 -123.77685) (xy 211.321153 -123.727273) (xy 211.350619 -123.681423) (xy 211.38631 -123.640232)
			(xy 211.427501 -123.604541) (xy 211.473351 -123.575075) (xy 211.522928 -123.552433) (xy 211.575223 -123.537078)
			(xy 211.629171 -123.529322) (xy 211.683673 -123.529322) (xy 211.737621 -123.537078) (xy 211.789916 -123.552433)
			(xy 211.839493 -123.575075) (xy 211.885343 -123.604541) (xy 211.926534 -123.640232) (xy 211.962225 -123.681423)
			(xy 211.991691 -123.727273) (xy 212.014333 -123.77685) (xy 212.029688 -123.829145) (xy 212.037444 -123.883093)
			(xy 212.03793 -123.910344) (xy 212.037482 -123.936659) (xy 212.030242 -123.988788) (xy 212.015918 -124.03943)
			(xy 211.994782 -124.087629) (xy 211.967233 -124.132472) (xy 211.933792 -124.173111) (xy 211.91474 -124.191268)
			(xy 211.907357 -124.198805) (xy 211.898821 -124.218073) (xy 211.89823 -124.228606) (xy 211.89823 -124.303282)
			(xy 211.898746 -124.313833) (xy 211.90729 -124.333129) (xy 211.91474 -124.34062) (xy 211.933806 -124.358765)
			(xy 211.967261 -124.399398) (xy 211.994817 -124.444241) (xy 212.015954 -124.492443) (xy 212.030269 -124.543092)
			(xy 212.037492 -124.595227) (xy 212.03793 -124.621544) (xy 212.037444 -124.648795) (xy 212.029688 -124.702743)
			(xy 212.014333 -124.755038) (xy 211.991691 -124.804615) (xy 211.962225 -124.850465) (xy 211.926534 -124.891656)
			(xy 211.885343 -124.927347) (xy 211.839493 -124.956813) (xy 211.789916 -124.979455) (xy 211.737621 -124.99481)
			(xy 211.683673 -125.002566) (xy 211.629171 -125.002566) (xy 211.575223 -124.99481) (xy 211.522928 -124.979455)
			(xy 211.473351 -124.956813) (xy 211.427501 -124.927347) (xy 211.38631 -124.891656) (xy 211.350619 -124.850465)
			(xy 211.321153 -124.804615) (xy 211.298511 -124.755038) (xy 211.283156 -124.702743) (xy 211.2754 -124.648795)
			(xy 211.274914 -124.621544) (xy 205.864842 -124.621544) (xy 207.553118 -128.697482) (xy 211.268308 -128.697482)
			(xy 211.272379 -128.64186) (xy 211.284505 -128.587423) (xy 211.304428 -128.535332) (xy 211.331724 -128.486697)
			(xy 211.36581 -128.442554) (xy 211.405959 -128.403845) (xy 211.451317 -128.371394) (xy 211.500917 -128.345893)
			(xy 211.553701 -128.327886) (xy 211.608544 -128.317756) (xy 211.664278 -128.315719) (xy 211.719715 -128.321819)
			(xy 211.773672 -128.335925) (xy 211.825001 -128.357737) (xy 211.872607 -128.386791) (xy 211.915475 -128.422466)
			(xy 211.952692 -128.464003) (xy 211.983465 -128.510516) (xy 212.007137 -128.561013) (xy 212.023205 -128.61442)
			(xy 212.031325 -128.669596) (xy 212.031834 -128.697482) (xy 212.031325 -128.725368) (xy 212.023205 -128.780544)
			(xy 212.007137 -128.833951) (xy 211.983465 -128.884448) (xy 211.952692 -128.930961) (xy 211.915475 -128.972498)
			(xy 211.872607 -129.008173) (xy 211.825001 -129.037227) (xy 211.773672 -129.059039) (xy 211.719715 -129.073145)
			(xy 211.664278 -129.079245) (xy 211.608544 -129.077208) (xy 211.553701 -129.067078) (xy 211.500917 -129.049071)
			(xy 211.451317 -129.02357) (xy 211.405959 -128.991119) (xy 211.36581 -128.95241) (xy 211.331724 -128.908267)
			(xy 211.304428 -128.859632) (xy 211.284505 -128.807541) (xy 211.272379 -128.753104) (xy 211.268308 -128.697482)
			(xy 207.553118 -128.697482) (xy 208.17332 -130.194812) (xy 208.175324 -130.199378) (xy 208.180817 -130.207699)
			(xy 208.184242 -130.211322) (xy 208.352136 -130.37947) (xy 208.386356 -130.414489) (xy 208.44853 -130.490134)
			(xy 208.502995 -130.571506) (xy 208.549225 -130.657822) (xy 208.568544 -130.702812) (xy 210.25631 -134.777734)
			(xy 211.442044 -134.777734) (xy 211.446115 -134.722112) (xy 211.458241 -134.667675) (xy 211.478164 -134.615584)
			(xy 211.50546 -134.566949) (xy 211.539546 -134.522806) (xy 211.579695 -134.484097) (xy 211.625053 -134.451646)
			(xy 211.674653 -134.426145) (xy 211.727437 -134.408138) (xy 211.78228 -134.398008) (xy 211.838014 -134.395971)
			(xy 211.893451 -134.402071) (xy 211.947408 -134.416177) (xy 211.998737 -134.437989) (xy 212.046343 -134.467043)
			(xy 212.089211 -134.502718) (xy 212.126428 -134.544255) (xy 212.157201 -134.590768) (xy 212.180873 -134.641265)
			(xy 212.196941 -134.694672) (xy 212.205061 -134.749848) (xy 212.20557 -134.777734) (xy 212.205061 -134.80562)
			(xy 212.204231 -134.811262) (xy 228.099112 -134.811262) (xy 228.099598 -134.784011) (xy 228.107354 -134.730063)
			(xy 228.122709 -134.677768) (xy 228.145351 -134.628191) (xy 228.174817 -134.582341) (xy 228.210508 -134.54115)
			(xy 228.251699 -134.505459) (xy 228.297549 -134.475993) (xy 228.347126 -134.453351) (xy 228.399421 -134.437996)
			(xy 228.453369 -134.43024) (xy 228.507871 -134.43024) (xy 228.561819 -134.437996) (xy 228.614114 -134.453351)
			(xy 228.663691 -134.475993) (xy 228.709541 -134.505459) (xy 228.750732 -134.54115) (xy 228.786423 -134.582341)
			(xy 228.815889 -134.628191) (xy 228.838531 -134.677768) (xy 228.853886 -134.730063) (xy 228.861642 -134.784011)
			(xy 228.862128 -134.811262) (xy 228.861712 -134.837579) (xy 228.854481 -134.889714) (xy 228.840151 -134.940359)
			(xy 228.818993 -134.988553) (xy 228.791411 -135.033381) (xy 228.757927 -135.073991) (xy 228.719178 -135.109611)
			(xy 228.69779 -135.124952) (xy 228.68662 -135.133118) (xy 228.668872 -135.154336) (xy 228.657474 -135.17954)
			(xy 228.653263 -135.206879) (xy 228.65655 -135.234345) (xy 228.667091 -135.25992) (xy 228.684114 -135.281723)
			(xy 228.706367 -135.298155) (xy 228.719126 -135.303514) (xy 228.745788 -135.314237) (xy 228.795756 -135.342623)
			(xy 228.840898 -135.378186) (xy 228.880192 -135.420121) (xy 228.912748 -135.467477) (xy 228.937827 -135.519184)
			(xy 228.954863 -135.574068) (xy 228.96347 -135.630888) (xy 228.963982 -135.659622) (xy 228.963496 -135.686873)
			(xy 228.95574 -135.740821) (xy 228.940385 -135.793116) (xy 228.917743 -135.842693) (xy 228.888277 -135.888543)
			(xy 228.852586 -135.929734) (xy 228.811395 -135.965425) (xy 228.765545 -135.994891) (xy 228.715968 -136.017533)
			(xy 228.663673 -136.032888) (xy 228.609725 -136.040644) (xy 228.555223 -136.040644) (xy 228.501275 -136.032888)
			(xy 228.44898 -136.017533) (xy 228.399403 -135.994891) (xy 228.353553 -135.965425) (xy 228.312362 -135.929734)
			(xy 228.276671 -135.888543) (xy 228.247205 -135.842693) (xy 228.224563 -135.793116) (xy 228.209208 -135.740821)
			(xy 228.201452 -135.686873) (xy 228.200966 -135.659622) (xy 228.201372 -135.633305) (xy 228.208605 -135.58117)
			(xy 228.222937 -135.530524) (xy 228.244096 -135.48233) (xy 228.27168 -135.437502) (xy 228.305165 -135.396893)
			(xy 228.343916 -135.361273) (xy 228.365304 -135.345932) (xy 228.376388 -135.337656) (xy 228.394134 -135.316461)
			(xy 228.405536 -135.291279) (xy 228.409755 -135.263959) (xy 228.406481 -135.236511) (xy 228.395955 -135.21095)
			(xy 228.37895 -135.189155) (xy 228.356717 -135.172729) (xy 228.343968 -135.16737) (xy 228.317335 -135.15658)
			(xy 228.26737 -135.128202) (xy 228.222229 -135.092648) (xy 228.182935 -135.050723) (xy 228.150376 -135.003376)
			(xy 228.125291 -134.951679) (xy 228.108247 -134.896804) (xy 228.099631 -134.839993) (xy 228.099112 -134.811262)
			(xy 212.204231 -134.811262) (xy 212.196941 -134.860796) (xy 212.180873 -134.914203) (xy 212.157201 -134.9647)
			(xy 212.126428 -135.011213) (xy 212.089211 -135.05275) (xy 212.046343 -135.088425) (xy 211.998737 -135.117479)
			(xy 211.947408 -135.139291) (xy 211.893451 -135.153397) (xy 211.838014 -135.159497) (xy 211.78228 -135.15746)
			(xy 211.727437 -135.14733) (xy 211.674653 -135.129323) (xy 211.625053 -135.103822) (xy 211.579695 -135.071371)
			(xy 211.539546 -135.032662) (xy 211.50546 -134.988519) (xy 211.478164 -134.939884) (xy 211.458241 -134.887793)
			(xy 211.446115 -134.833356) (xy 211.442044 -134.777734) (xy 210.25631 -134.777734) (xy 210.408012 -135.144002)
			(xy 210.414108 -135.150606) (xy 210.431513 -135.170422) (xy 210.461269 -135.213968) (xy 210.484746 -135.261196)
			(xy 210.501498 -135.311206) (xy 210.511205 -135.363047) (xy 210.512914 -135.389366) (xy 210.513422 -135.398256)
			(xy 210.621746 -135.659622) (xy 224.644456 -135.659622) (xy 224.648527 -135.604) (xy 224.660653 -135.549563)
			(xy 224.680576 -135.497472) (xy 224.707872 -135.448837) (xy 224.741958 -135.404694) (xy 224.782107 -135.365985)
			(xy 224.827465 -135.333534) (xy 224.877065 -135.308033) (xy 224.929849 -135.290026) (xy 224.984692 -135.279896)
			(xy 225.040426 -135.277859) (xy 225.095863 -135.283959) (xy 225.14982 -135.298065) (xy 225.201149 -135.319877)
			(xy 225.248755 -135.348931) (xy 225.291623 -135.384606) (xy 225.32884 -135.426143) (xy 225.359613 -135.472656)
			(xy 225.383285 -135.523153) (xy 225.399353 -135.57656) (xy 225.407473 -135.631736) (xy 225.407982 -135.659622)
			(xy 226.422456 -135.659622) (xy 226.426527 -135.604) (xy 226.438653 -135.549563) (xy 226.458576 -135.497472)
			(xy 226.485872 -135.448837) (xy 226.519958 -135.404694) (xy 226.560107 -135.365985) (xy 226.605465 -135.333534)
			(xy 226.655065 -135.308033) (xy 226.707849 -135.290026) (xy 226.762692 -135.279896) (xy 226.818426 -135.277859)
			(xy 226.873863 -135.283959) (xy 226.92782 -135.298065) (xy 226.979149 -135.319877) (xy 227.026755 -135.348931)
			(xy 227.069623 -135.384606) (xy 227.10684 -135.426143) (xy 227.137613 -135.472656) (xy 227.161285 -135.523153)
			(xy 227.177353 -135.57656) (xy 227.185473 -135.631736) (xy 227.185982 -135.659622) (xy 227.185473 -135.687508)
			(xy 227.177353 -135.742684) (xy 227.161285 -135.796091) (xy 227.137613 -135.846588) (xy 227.10684 -135.893101)
			(xy 227.069623 -135.934638) (xy 227.026755 -135.970313) (xy 226.979149 -135.999367) (xy 226.92782 -136.021179)
			(xy 226.873863 -136.035285) (xy 226.818426 -136.041385) (xy 226.762692 -136.039348) (xy 226.707849 -136.029218)
			(xy 226.655065 -136.011211) (xy 226.605465 -135.98571) (xy 226.560107 -135.953259) (xy 226.519958 -135.91455)
			(xy 226.485872 -135.870407) (xy 226.458576 -135.821772) (xy 226.438653 -135.769681) (xy 226.426527 -135.715244)
			(xy 226.422456 -135.659622) (xy 225.407982 -135.659622) (xy 225.407473 -135.687508) (xy 225.399353 -135.742684)
			(xy 225.383285 -135.796091) (xy 225.359613 -135.846588) (xy 225.32884 -135.893101) (xy 225.291623 -135.934638)
			(xy 225.248755 -135.970313) (xy 225.201149 -135.999367) (xy 225.14982 -136.021179) (xy 225.095863 -136.035285)
			(xy 225.040426 -136.041385) (xy 224.984692 -136.039348) (xy 224.929849 -136.029218) (xy 224.877065 -136.011211)
			(xy 224.827465 -135.98571) (xy 224.782107 -135.953259) (xy 224.741958 -135.91455) (xy 224.707872 -135.870407)
			(xy 224.680576 -135.821772) (xy 224.660653 -135.769681) (xy 224.648527 -135.715244) (xy 224.644456 -135.659622)
			(xy 210.621746 -135.659622) (xy 210.65617 -135.74268) (xy 210.662266 -135.749284) (xy 210.680011 -135.769273)
			(xy 210.710308 -135.813308) (xy 210.734157 -135.861144) (xy 210.751089 -135.911842) (xy 210.760772 -135.964409)
			(xy 210.762342 -135.991092) (xy 210.762596 -135.999982) (xy 210.831197 -136.16559) (xy 211.52561 -136.16559)
			(xy 211.529681 -136.109968) (xy 211.541807 -136.055531) (xy 211.56173 -136.00344) (xy 211.589026 -135.954805)
			(xy 211.623112 -135.910662) (xy 211.663261 -135.871953) (xy 211.708619 -135.839502) (xy 211.758219 -135.814001)
			(xy 211.811003 -135.795994) (xy 211.865846 -135.785864) (xy 211.92158 -135.783827) (xy 211.977017 -135.789927)
			(xy 212.030974 -135.804033) (xy 212.082303 -135.825845) (xy 212.129909 -135.854899) (xy 212.172777 -135.890574)
			(xy 212.209994 -135.932111) (xy 212.240767 -135.978624) (xy 212.264439 -136.029121) (xy 212.280507 -136.082528)
			(xy 212.288627 -136.137704) (xy 212.289136 -136.16559) (xy 212.288627 -136.193476) (xy 212.280507 -136.248652)
			(xy 212.264439 -136.302059) (xy 212.240767 -136.352556) (xy 212.209994 -136.399069) (xy 212.172777 -136.440606)
			(xy 212.129909 -136.476281) (xy 212.082303 -136.505335) (xy 212.030974 -136.527147) (xy 211.977017 -136.541253)
			(xy 211.92158 -136.547353) (xy 211.865846 -136.545316) (xy 211.811003 -136.535186) (xy 211.758219 -136.517179)
			(xy 211.708619 -136.491678) (xy 211.663261 -136.459227) (xy 211.623112 -136.420518) (xy 211.589026 -136.376375)
			(xy 211.56173 -136.32774) (xy 211.541807 -136.275649) (xy 211.529681 -136.221212) (xy 211.52561 -136.16559)
			(xy 210.831197 -136.16559) (xy 211.159367 -136.957816) (xy 223.695512 -136.957816) (xy 223.699583 -136.902194)
			(xy 223.711709 -136.847757) (xy 223.731632 -136.795666) (xy 223.758928 -136.747031) (xy 223.793014 -136.702888)
			(xy 223.833163 -136.664179) (xy 223.878521 -136.631728) (xy 223.928121 -136.606227) (xy 223.980905 -136.58822)
			(xy 224.035748 -136.57809) (xy 224.091482 -136.576053) (xy 224.146919 -136.582153) (xy 224.200876 -136.596259)
			(xy 224.252205 -136.618071) (xy 224.299811 -136.647125) (xy 224.342679 -136.6828) (xy 224.379896 -136.724337)
			(xy 224.410669 -136.77085) (xy 224.434341 -136.821347) (xy 224.450409 -136.874754) (xy 224.458529 -136.92993)
			(xy 224.459038 -136.957816) (xy 224.458529 -136.985702) (xy 224.450409 -137.040878) (xy 224.434341 -137.094285)
			(xy 224.410669 -137.144782) (xy 224.379896 -137.191295) (xy 224.342679 -137.232832) (xy 224.299811 -137.268507)
			(xy 224.252205 -137.297561) (xy 224.200876 -137.319373) (xy 224.146919 -137.333479) (xy 224.091482 -137.339579)
			(xy 224.035748 -137.337542) (xy 223.980905 -137.327412) (xy 223.928121 -137.309405) (xy 223.878521 -137.283904)
			(xy 223.833163 -137.251453) (xy 223.793014 -137.212744) (xy 223.758928 -137.168601) (xy 223.731632 -137.119966)
			(xy 223.711709 -137.067875) (xy 223.699583 -137.013438) (xy 223.695512 -136.957816) (xy 211.159367 -136.957816)
			(xy 211.628633 -138.090656) (xy 224.549206 -138.090656) (xy 224.553277 -138.035034) (xy 224.565403 -137.980597)
			(xy 224.585326 -137.928506) (xy 224.612622 -137.879871) (xy 224.646708 -137.835728) (xy 224.686857 -137.797019)
			(xy 224.732215 -137.764568) (xy 224.781815 -137.739067) (xy 224.834599 -137.72106) (xy 224.889442 -137.71093)
			(xy 224.945176 -137.708893) (xy 225.000613 -137.714993) (xy 225.05457 -137.729099) (xy 225.105899 -137.750911)
			(xy 225.153505 -137.779965) (xy 225.196373 -137.81564) (xy 225.23359 -137.857177) (xy 225.264363 -137.90369)
			(xy 225.288035 -137.954187) (xy 225.304103 -138.007594) (xy 225.312223 -138.06277) (xy 225.312732 -138.090656)
			(xy 225.312223 -138.118542) (xy 225.304103 -138.173718) (xy 225.288035 -138.227125) (xy 225.273304 -138.25855)
			(xy 232.741976 -138.25855) (xy 232.746047 -138.202928) (xy 232.758173 -138.148491) (xy 232.778096 -138.0964)
			(xy 232.805392 -138.047765) (xy 232.839478 -138.003622) (xy 232.879627 -137.964913) (xy 232.924985 -137.932462)
			(xy 232.974585 -137.906961) (xy 233.027369 -137.888954) (xy 233.082212 -137.878824) (xy 233.137946 -137.876787)
			(xy 233.193383 -137.882887) (xy 233.24734 -137.896993) (xy 233.298669 -137.918805) (xy 233.346275 -137.947859)
			(xy 233.389143 -137.983534) (xy 233.42636 -138.025071) (xy 233.457133 -138.071584) (xy 233.480805 -138.122081)
			(xy 233.496873 -138.175488) (xy 233.504993 -138.230664) (xy 233.505502 -138.25855) (xy 233.504993 -138.286436)
			(xy 233.496873 -138.341612) (xy 233.480805 -138.395019) (xy 233.457133 -138.445516) (xy 233.42636 -138.492029)
			(xy 233.389143 -138.533566) (xy 233.346275 -138.569241) (xy 233.298669 -138.598295) (xy 233.24734 -138.620107)
			(xy 233.193383 -138.634213) (xy 233.137946 -138.640313) (xy 233.082212 -138.638276) (xy 233.027369 -138.628146)
			(xy 232.974585 -138.610139) (xy 232.924985 -138.584638) (xy 232.879627 -138.552187) (xy 232.839478 -138.513478)
			(xy 232.805392 -138.469335) (xy 232.778096 -138.4207) (xy 232.758173 -138.368609) (xy 232.746047 -138.314172)
			(xy 232.741976 -138.25855) (xy 225.273304 -138.25855) (xy 225.264363 -138.277622) (xy 225.23359 -138.324135)
			(xy 225.196373 -138.365672) (xy 225.153505 -138.401347) (xy 225.105899 -138.430401) (xy 225.05457 -138.452213)
			(xy 225.000613 -138.466319) (xy 224.945176 -138.472419) (xy 224.889442 -138.470382) (xy 224.834599 -138.460252)
			(xy 224.781815 -138.442245) (xy 224.732215 -138.416744) (xy 224.686857 -138.384293) (xy 224.646708 -138.345584)
			(xy 224.612622 -138.301441) (xy 224.585326 -138.252806) (xy 224.565403 -138.200715) (xy 224.553277 -138.146278)
			(xy 224.549206 -138.090656) (xy 211.628633 -138.090656) (xy 211.800346 -138.505184) (xy 221.778828 -138.505184)
			(xy 221.782899 -138.449562) (xy 221.795025 -138.395125) (xy 221.814948 -138.343034) (xy 221.842244 -138.294399)
			(xy 221.87633 -138.250256) (xy 221.916479 -138.211547) (xy 221.961837 -138.179096) (xy 222.011437 -138.153595)
			(xy 222.064221 -138.135588) (xy 222.119064 -138.125458) (xy 222.174798 -138.123421) (xy 222.230235 -138.129521)
			(xy 222.284192 -138.143627) (xy 222.335521 -138.165439) (xy 222.383127 -138.194493) (xy 222.425995 -138.230168)
			(xy 222.463212 -138.271705) (xy 222.493985 -138.318218) (xy 222.517657 -138.368715) (xy 222.533725 -138.422122)
			(xy 222.541845 -138.477298) (xy 222.542354 -138.505184) (xy 222.541845 -138.53307) (xy 222.533725 -138.588246)
			(xy 222.517657 -138.641653) (xy 222.493985 -138.69215) (xy 222.463212 -138.738663) (xy 222.425995 -138.7802)
			(xy 222.383127 -138.815875) (xy 222.335521 -138.844929) (xy 222.284192 -138.866741) (xy 222.230235 -138.880847)
			(xy 222.174798 -138.886947) (xy 222.119064 -138.88491) (xy 222.064221 -138.87478) (xy 222.011437 -138.856773)
			(xy 221.961837 -138.831272) (xy 221.916479 -138.798821) (xy 221.87633 -138.760112) (xy 221.842244 -138.715969)
			(xy 221.814948 -138.667334) (xy 221.795025 -138.615243) (xy 221.782899 -138.560806) (xy 221.778828 -138.505184)
			(xy 211.800346 -138.505184) (xy 212.029118 -139.057455) (xy 226.046957 -139.057455) (xy 226.046957 -139.002945)
			(xy 226.054716 -138.948991) (xy 226.070074 -138.896689) (xy 226.09272 -138.847106) (xy 226.122192 -138.801251)
			(xy 226.15789 -138.760058) (xy 226.199088 -138.724364) (xy 226.244947 -138.694898) (xy 226.294532 -138.672258)
			(xy 226.346836 -138.656906) (xy 226.400791 -138.649154) (xy 226.428046 -138.648694) (xy 226.455415 -138.649193)
			(xy 226.509593 -138.657003) (xy 226.562095 -138.672485) (xy 226.611843 -138.695319) (xy 226.657811 -138.725036)
			(xy 226.678744 -138.742674) (xy 226.678998 -138.742928) (xy 226.686079 -138.748523) (xy 226.703 -138.754764)
			(xy 226.712018 -138.75512) (xy 226.779074 -138.75512) (xy 226.788089 -138.754746) (xy 226.805006 -138.74851)
			(xy 226.812094 -138.742928) (xy 226.812094 -138.742674) (xy 226.812348 -138.742674) (xy 226.833286 -138.725042)
			(xy 226.879257 -138.69533) (xy 226.929003 -138.672493) (xy 226.981503 -138.657) (xy 227.035677 -138.64917)
			(xy 227.063046 -138.648694) (xy 227.090295 -138.649179) (xy 227.144238 -138.656941) (xy 227.196528 -138.6723)
			(xy 227.246099 -138.694944) (xy 227.291944 -138.724412) (xy 227.333129 -138.760103) (xy 227.368816 -138.801293)
			(xy 227.398278 -138.847141) (xy 227.420916 -138.896715) (xy 227.436269 -138.949007) (xy 227.444024 -139.002951)
			(xy 227.444024 -139.057449) (xy 227.436269 -139.111393) (xy 227.420916 -139.163685) (xy 227.398278 -139.213259)
			(xy 227.368816 -139.259107) (xy 227.333129 -139.300297) (xy 227.291944 -139.335988) (xy 227.246099 -139.365456)
			(xy 227.196528 -139.3881) (xy 227.144238 -139.403459) (xy 227.090295 -139.411221) (xy 227.063046 -139.41171)
			(xy 227.035677 -139.411215) (xy 226.981499 -139.403403) (xy 226.928996 -139.387921) (xy 226.879249 -139.365086)
			(xy 226.833281 -139.335368) (xy 226.812348 -139.31773) (xy 226.812094 -139.317476) (xy 226.805015 -139.311878)
			(xy 226.788092 -139.305639) (xy 226.779074 -139.305284) (xy 226.712018 -139.305284) (xy 226.703002 -139.305653)
			(xy 226.686086 -139.311893) (xy 226.678998 -139.317476) (xy 226.678998 -139.31773) (xy 226.678744 -139.31773)
			(xy 226.65781 -139.335367) (xy 226.611837 -139.365078) (xy 226.56209 -139.387914) (xy 226.50959 -139.403405)
			(xy 226.455415 -139.411235) (xy 226.428046 -139.41171) (xy 226.400791 -139.411246) (xy 226.346836 -139.403494)
			(xy 226.294532 -139.388142) (xy 226.244947 -139.365502) (xy 226.199088 -139.336036) (xy 226.15789 -139.300342)
			(xy 226.122192 -139.259149) (xy 226.09272 -139.213294) (xy 226.070074 -139.163711) (xy 226.054716 -139.111409)
			(xy 226.046957 -139.057455) (xy 212.029118 -139.057455) (xy 212.27119 -139.641834) (xy 219.820234 -139.641834)
			(xy 219.824305 -139.586212) (xy 219.836431 -139.531775) (xy 219.856354 -139.479684) (xy 219.88365 -139.431049)
			(xy 219.917736 -139.386906) (xy 219.957885 -139.348197) (xy 220.003243 -139.315746) (xy 220.052843 -139.290245)
			(xy 220.105627 -139.272238) (xy 220.16047 -139.262108) (xy 220.216204 -139.260071) (xy 220.271641 -139.266171)
			(xy 220.325598 -139.280277) (xy 220.376927 -139.302089) (xy 220.424533 -139.331143) (xy 220.467401 -139.366818)
			(xy 220.504618 -139.408355) (xy 220.535391 -139.454868) (xy 220.559063 -139.505365) (xy 220.575131 -139.558772)
			(xy 220.583251 -139.613948) (xy 220.58376 -139.641834) (xy 220.583251 -139.66972) (xy 220.575131 -139.724896)
			(xy 220.559063 -139.778303) (xy 220.53683 -139.82573) (xy 231.704894 -139.82573) (xy 231.708965 -139.770108)
			(xy 231.721091 -139.715671) (xy 231.741014 -139.66358) (xy 231.76831 -139.614945) (xy 231.802396 -139.570802)
			(xy 231.842545 -139.532093) (xy 231.887903 -139.499642) (xy 231.937503 -139.474141) (xy 231.990287 -139.456134)
			(xy 232.04513 -139.446004) (xy 232.100864 -139.443967) (xy 232.156301 -139.450067) (xy 232.210258 -139.464173)
			(xy 232.261587 -139.485985) (xy 232.309193 -139.515039) (xy 232.352061 -139.550714) (xy 232.389278 -139.592251)
			(xy 232.420051 -139.638764) (xy 232.443723 -139.689261) (xy 232.459791 -139.742668) (xy 232.467911 -139.797844)
			(xy 232.46842 -139.82573) (xy 232.467911 -139.853616) (xy 232.459791 -139.908792) (xy 232.443723 -139.962199)
			(xy 232.420051 -140.012696) (xy 232.389278 -140.059209) (xy 232.352061 -140.100746) (xy 232.309193 -140.136421)
			(xy 232.261587 -140.165475) (xy 232.210258 -140.187287) (xy 232.156301 -140.201393) (xy 232.100864 -140.207493)
			(xy 232.04513 -140.205456) (xy 231.990287 -140.195326) (xy 231.937503 -140.177319) (xy 231.887903 -140.151818)
			(xy 231.842545 -140.119367) (xy 231.802396 -140.080658) (xy 231.76831 -140.036515) (xy 231.741014 -139.98788)
			(xy 231.721091 -139.935789) (xy 231.708965 -139.881352) (xy 231.704894 -139.82573) (xy 220.53683 -139.82573)
			(xy 220.535391 -139.8288) (xy 220.504618 -139.875313) (xy 220.467401 -139.91685) (xy 220.424533 -139.952525)
			(xy 220.376927 -139.981579) (xy 220.325598 -140.003391) (xy 220.271641 -140.017497) (xy 220.216204 -140.023597)
			(xy 220.16047 -140.02156) (xy 220.105627 -140.01143) (xy 220.052843 -139.993423) (xy 220.003243 -139.967922)
			(xy 219.957885 -139.935471) (xy 219.917736 -139.896762) (xy 219.88365 -139.852619) (xy 219.856354 -139.803984)
			(xy 219.836431 -139.751893) (xy 219.824305 -139.697456) (xy 219.820234 -139.641834) (xy 212.27119 -139.641834)
			(xy 212.790118 -140.894562) (xy 219.859604 -140.894562) (xy 219.863675 -140.83894) (xy 219.875801 -140.784503)
			(xy 219.895724 -140.732412) (xy 219.92302 -140.683777) (xy 219.957106 -140.639634) (xy 219.997255 -140.600925)
			(xy 220.042613 -140.568474) (xy 220.092213 -140.542973) (xy 220.144997 -140.524966) (xy 220.19984 -140.514836)
			(xy 220.255574 -140.512799) (xy 220.311011 -140.518899) (xy 220.364968 -140.533005) (xy 220.416297 -140.554817)
			(xy 220.463903 -140.583871) (xy 220.506771 -140.619546) (xy 220.543988 -140.661083) (xy 220.574761 -140.707596)
			(xy 220.598433 -140.758093) (xy 220.614501 -140.8115) (xy 220.622621 -140.866676) (xy 220.62313 -140.894562)
			(xy 220.622621 -140.922448) (xy 220.617791 -140.955268) (xy 222.72701 -140.955268) (xy 222.731081 -140.899646)
			(xy 222.743207 -140.845209) (xy 222.76313 -140.793118) (xy 222.790426 -140.744483) (xy 222.824512 -140.70034)
			(xy 222.864661 -140.661631) (xy 222.910019 -140.62918) (xy 222.959619 -140.603679) (xy 223.012403 -140.585672)
			(xy 223.067246 -140.575542) (xy 223.12298 -140.573505) (xy 223.178417 -140.579605) (xy 223.232374 -140.593711)
			(xy 223.283703 -140.615523) (xy 223.331309 -140.644577) (xy 223.374177 -140.680252) (xy 223.397787 -140.706602)
			(xy 224.801428 -140.706602) (xy 224.805499 -140.65098) (xy 224.817625 -140.596543) (xy 224.837548 -140.544452)
			(xy 224.864844 -140.495817) (xy 224.89893 -140.451674) (xy 224.939079 -140.412965) (xy 224.984437 -140.380514)
			(xy 225.034037 -140.355013) (xy 225.086821 -140.337006) (xy 225.141664 -140.326876) (xy 225.197398 -140.324839)
			(xy 225.252835 -140.330939) (xy 225.306792 -140.345045) (xy 225.358121 -140.366857) (xy 225.405727 -140.395911)
			(xy 225.448595 -140.431586) (xy 225.485812 -140.473123) (xy 225.516585 -140.519636) (xy 225.540257 -140.570133)
			(xy 225.556325 -140.62354) (xy 225.564445 -140.678716) (xy 225.564954 -140.706602) (xy 225.564445 -140.734488)
			(xy 225.556325 -140.789664) (xy 225.540257 -140.843071) (xy 225.516585 -140.893568) (xy 225.485812 -140.940081)
			(xy 225.448595 -140.981618) (xy 225.405727 -141.017293) (xy 225.358121 -141.046347) (xy 225.306792 -141.068159)
			(xy 225.252835 -141.082265) (xy 225.197398 -141.088365) (xy 225.141664 -141.086328) (xy 225.086821 -141.076198)
			(xy 225.034037 -141.058191) (xy 224.984437 -141.03269) (xy 224.939079 -141.000239) (xy 224.89893 -140.96153)
			(xy 224.864844 -140.917387) (xy 224.837548 -140.868752) (xy 224.817625 -140.816661) (xy 224.805499 -140.762224)
			(xy 224.801428 -140.706602) (xy 223.397787 -140.706602) (xy 223.411394 -140.721789) (xy 223.442167 -140.768302)
			(xy 223.465839 -140.818799) (xy 223.481907 -140.872206) (xy 223.490027 -140.927382) (xy 223.490536 -140.955268)
			(xy 223.490027 -140.983154) (xy 223.481907 -141.03833) (xy 223.465839 -141.091737) (xy 223.442167 -141.142234)
			(xy 223.411394 -141.188747) (xy 223.374177 -141.230284) (xy 223.331309 -141.265959) (xy 223.283703 -141.295013)
			(xy 223.232374 -141.316825) (xy 223.178417 -141.330931) (xy 223.12298 -141.337031) (xy 223.067246 -141.334994)
			(xy 223.012403 -141.324864) (xy 222.959619 -141.306857) (xy 222.910019 -141.281356) (xy 222.864661 -141.248905)
			(xy 222.824512 -141.210196) (xy 222.790426 -141.166053) (xy 222.76313 -141.117418) (xy 222.743207 -141.065327)
			(xy 222.731081 -141.01089) (xy 222.72701 -140.955268) (xy 220.617791 -140.955268) (xy 220.614501 -140.977624)
			(xy 220.598433 -141.031031) (xy 220.574761 -141.081528) (xy 220.543988 -141.128041) (xy 220.506771 -141.169578)
			(xy 220.463903 -141.205253) (xy 220.416297 -141.234307) (xy 220.364968 -141.256119) (xy 220.311011 -141.270225)
			(xy 220.255574 -141.276325) (xy 220.19984 -141.274288) (xy 220.144997 -141.264158) (xy 220.092213 -141.246151)
			(xy 220.042613 -141.22065) (xy 219.997255 -141.188199) (xy 219.957106 -141.14949) (xy 219.92302 -141.105347)
			(xy 219.895724 -141.056712) (xy 219.875801 -141.004621) (xy 219.863675 -140.950184) (xy 219.859604 -140.894562)
			(xy 212.790118 -140.894562) (xy 213.152063 -141.768322) (xy 231.849166 -141.768322) (xy 231.853237 -141.7127)
			(xy 231.865363 -141.658263) (xy 231.885286 -141.606172) (xy 231.912582 -141.557537) (xy 231.946668 -141.513394)
			(xy 231.986817 -141.474685) (xy 232.032175 -141.442234) (xy 232.081775 -141.416733) (xy 232.134559 -141.398726)
			(xy 232.189402 -141.388596) (xy 232.245136 -141.386559) (xy 232.300573 -141.392659) (xy 232.35453 -141.406765)
			(xy 232.405859 -141.428577) (xy 232.453465 -141.457631) (xy 232.496333 -141.493306) (xy 232.53355 -141.534843)
			(xy 232.564323 -141.581356) (xy 232.587995 -141.631853) (xy 232.604063 -141.68526) (xy 232.612183 -141.740436)
			(xy 232.612692 -141.768322) (xy 232.612183 -141.796208) (xy 232.604063 -141.851384) (xy 232.587995 -141.904791)
			(xy 232.564323 -141.955288) (xy 232.53355 -142.001801) (xy 232.496333 -142.043338) (xy 232.453465 -142.079013)
			(xy 232.405859 -142.108067) (xy 232.35453 -142.129879) (xy 232.300573 -142.143985) (xy 232.245136 -142.150085)
			(xy 232.189402 -142.148048) (xy 232.134559 -142.137918) (xy 232.081775 -142.119911) (xy 232.032175 -142.09441)
			(xy 231.986817 -142.061959) (xy 231.946668 -142.02325) (xy 231.912582 -141.979107) (xy 231.885286 -141.930472)
			(xy 231.865363 -141.878381) (xy 231.853237 -141.823944) (xy 231.849166 -141.768322) (xy 213.152063 -141.768322)
			(xy 213.349449 -142.244826) (xy 228.06736 -142.244826) (xy 228.071431 -142.189204) (xy 228.083557 -142.134767)
			(xy 228.10348 -142.082676) (xy 228.130776 -142.034041) (xy 228.164862 -141.989898) (xy 228.205011 -141.951189)
			(xy 228.250369 -141.918738) (xy 228.299969 -141.893237) (xy 228.352753 -141.87523) (xy 228.407596 -141.8651)
			(xy 228.46333 -141.863063) (xy 228.518767 -141.869163) (xy 228.572724 -141.883269) (xy 228.624053 -141.905081)
			(xy 228.671659 -141.934135) (xy 228.714527 -141.96981) (xy 228.751744 -142.011347) (xy 228.782517 -142.05786)
			(xy 228.806189 -142.108357) (xy 228.822257 -142.161764) (xy 228.830377 -142.21694) (xy 228.830886 -142.244826)
			(xy 228.830399 -142.271496) (xy 230.464866 -142.271496) (xy 230.468937 -142.215874) (xy 230.481063 -142.161437)
			(xy 230.500986 -142.109346) (xy 230.528282 -142.060711) (xy 230.562368 -142.016568) (xy 230.602517 -141.977859)
			(xy 230.647875 -141.945408) (xy 230.697475 -141.919907) (xy 230.750259 -141.9019) (xy 230.805102 -141.89177)
			(xy 230.860836 -141.889733) (xy 230.916273 -141.895833) (xy 230.97023 -141.909939) (xy 231.021559 -141.931751)
			(xy 231.069165 -141.960805) (xy 231.112033 -141.99648) (xy 231.14925 -142.038017) (xy 231.180023 -142.08453)
			(xy 231.203695 -142.135027) (xy 231.219763 -142.188434) (xy 231.227883 -142.24361) (xy 231.228392 -142.271496)
			(xy 231.227883 -142.299382) (xy 231.219763 -142.354558) (xy 231.203695 -142.407965) (xy 231.180023 -142.458462)
			(xy 231.14925 -142.504975) (xy 231.112033 -142.546512) (xy 231.069165 -142.582187) (xy 231.021559 -142.611241)
			(xy 230.97023 -142.633053) (xy 230.940551 -142.640812) (xy 234.22305 -142.640812) (xy 234.227121 -142.58519)
			(xy 234.239247 -142.530753) (xy 234.25917 -142.478662) (xy 234.286466 -142.430027) (xy 234.320552 -142.385884)
			(xy 234.360701 -142.347175) (xy 234.406059 -142.314724) (xy 234.455659 -142.289223) (xy 234.508443 -142.271216)
			(xy 234.563286 -142.261086) (xy 234.61902 -142.259049) (xy 234.674457 -142.265149) (xy 234.728414 -142.279255)
			(xy 234.779743 -142.301067) (xy 234.827349 -142.330121) (xy 234.870217 -142.365796) (xy 234.907434 -142.407333)
			(xy 234.938207 -142.453846) (xy 234.961879 -142.504343) (xy 234.977947 -142.55775) (xy 234.986067 -142.612926)
			(xy 234.986576 -142.640812) (xy 234.986067 -142.668698) (xy 234.977947 -142.723874) (xy 234.961879 -142.777281)
			(xy 234.938207 -142.827778) (xy 234.907434 -142.874291) (xy 234.870217 -142.915828) (xy 234.827349 -142.951503)
			(xy 234.779743 -142.980557) (xy 234.728414 -143.002369) (xy 234.674457 -143.016475) (xy 234.61902 -143.022575)
			(xy 234.563286 -143.020538) (xy 234.508443 -143.010408) (xy 234.455659 -142.992401) (xy 234.406059 -142.9669)
			(xy 234.360701 -142.934449) (xy 234.320552 -142.89574) (xy 234.286466 -142.851597) (xy 234.25917 -142.802962)
			(xy 234.239247 -142.750871) (xy 234.227121 -142.696434) (xy 234.22305 -142.640812) (xy 230.940551 -142.640812)
			(xy 230.916273 -142.647159) (xy 230.860836 -142.653259) (xy 230.805102 -142.651222) (xy 230.750259 -142.641092)
			(xy 230.697475 -142.623085) (xy 230.647875 -142.597584) (xy 230.602517 -142.565133) (xy 230.562368 -142.526424)
			(xy 230.528282 -142.482281) (xy 230.500986 -142.433646) (xy 230.481063 -142.381555) (xy 230.468937 -142.327118)
			(xy 230.464866 -142.271496) (xy 228.830399 -142.271496) (xy 228.830377 -142.272712) (xy 228.822257 -142.327888)
			(xy 228.806189 -142.381295) (xy 228.782517 -142.431792) (xy 228.751744 -142.478305) (xy 228.714527 -142.519842)
			(xy 228.671659 -142.555517) (xy 228.624053 -142.584571) (xy 228.572724 -142.606383) (xy 228.518767 -142.620489)
			(xy 228.46333 -142.626589) (xy 228.407596 -142.624552) (xy 228.352753 -142.614422) (xy 228.299969 -142.596415)
			(xy 228.250369 -142.570914) (xy 228.205011 -142.538463) (xy 228.164862 -142.499754) (xy 228.130776 -142.455611)
			(xy 228.10348 -142.406976) (xy 228.083557 -142.354885) (xy 228.071431 -142.300448) (xy 228.06736 -142.244826)
			(xy 213.349449 -142.244826) (xy 214.053769 -143.945102) (xy 225.0219 -143.945102) (xy 225.025971 -143.88948)
			(xy 225.038097 -143.835043) (xy 225.05802 -143.782952) (xy 225.085316 -143.734317) (xy 225.119402 -143.690174)
			(xy 225.159551 -143.651465) (xy 225.204909 -143.619014) (xy 225.254509 -143.593513) (xy 225.307293 -143.575506)
			(xy 225.362136 -143.565376) (xy 225.41787 -143.563339) (xy 225.473307 -143.569439) (xy 225.527264 -143.583545)
			(xy 225.578593 -143.605357) (xy 225.626199 -143.634411) (xy 225.669067 -143.670086) (xy 225.706284 -143.711623)
			(xy 225.737057 -143.758136) (xy 225.760729 -143.808633) (xy 225.776797 -143.86204) (xy 225.784917 -143.917216)
			(xy 225.785426 -143.945102) (xy 225.784917 -143.972988) (xy 225.776797 -144.028164) (xy 225.760729 -144.081571)
			(xy 225.737057 -144.132068) (xy 225.706284 -144.178581) (xy 225.669067 -144.220118) (xy 225.626199 -144.255793)
			(xy 225.578593 -144.284847) (xy 225.527264 -144.306659) (xy 225.473307 -144.320765) (xy 225.41787 -144.326865)
			(xy 225.362136 -144.324828) (xy 225.307293 -144.314698) (xy 225.254509 -144.296691) (xy 225.204909 -144.27119)
			(xy 225.159551 -144.238739) (xy 225.119402 -144.20003) (xy 225.085316 -144.155887) (xy 225.05802 -144.107252)
			(xy 225.038097 -144.055161) (xy 225.025971 -144.000724) (xy 225.0219 -143.945102) (xy 214.053769 -143.945102)
			(xy 214.355214 -144.672812) (xy 234.175044 -144.672812) (xy 234.179115 -144.61719) (xy 234.191241 -144.562753)
			(xy 234.211164 -144.510662) (xy 234.23846 -144.462027) (xy 234.272546 -144.417884) (xy 234.312695 -144.379175)
			(xy 234.358053 -144.346724) (xy 234.407653 -144.321223) (xy 234.460437 -144.303216) (xy 234.51528 -144.293086)
			(xy 234.571014 -144.291049) (xy 234.626451 -144.297149) (xy 234.680408 -144.311255) (xy 234.731737 -144.333067)
			(xy 234.779343 -144.362121) (xy 234.822211 -144.397796) (xy 234.859428 -144.439333) (xy 234.890201 -144.485846)
			(xy 234.913873 -144.536343) (xy 234.929941 -144.58975) (xy 234.938061 -144.644926) (xy 234.93857 -144.672812)
			(xy 236.25124 -144.672812) (xy 236.255311 -144.61719) (xy 236.267437 -144.562753) (xy 236.28736 -144.510662)
			(xy 236.314656 -144.462027) (xy 236.348742 -144.417884) (xy 236.388891 -144.379175) (xy 236.434249 -144.346724)
			(xy 236.483849 -144.321223) (xy 236.536633 -144.303216) (xy 236.591476 -144.293086) (xy 236.64721 -144.291049)
			(xy 236.702647 -144.297149) (xy 236.756604 -144.311255) (xy 236.807933 -144.333067) (xy 236.855539 -144.362121)
			(xy 236.898407 -144.397796) (xy 236.935624 -144.439333) (xy 236.966397 -144.485846) (xy 236.990069 -144.536343)
			(xy 237.006137 -144.58975) (xy 237.014257 -144.644926) (xy 237.014766 -144.672812) (xy 237.014257 -144.700698)
			(xy 237.006137 -144.755874) (xy 236.990069 -144.809281) (xy 236.966397 -144.859778) (xy 236.935624 -144.906291)
			(xy 236.898407 -144.947828) (xy 236.855539 -144.983503) (xy 236.807933 -145.012557) (xy 236.756604 -145.034369)
			(xy 236.702647 -145.048475) (xy 236.64721 -145.054575) (xy 236.591476 -145.052538) (xy 236.536633 -145.042408)
			(xy 236.483849 -145.024401) (xy 236.434249 -144.9989) (xy 236.388891 -144.966449) (xy 236.348742 -144.92774)
			(xy 236.314656 -144.883597) (xy 236.28736 -144.834962) (xy 236.267437 -144.782871) (xy 236.255311 -144.728434)
			(xy 236.25124 -144.672812) (xy 234.93857 -144.672812) (xy 234.938061 -144.700698) (xy 234.929941 -144.755874)
			(xy 234.913873 -144.809281) (xy 234.890201 -144.859778) (xy 234.859428 -144.906291) (xy 234.822211 -144.947828)
			(xy 234.779343 -144.983503) (xy 234.731737 -145.012557) (xy 234.680408 -145.034369) (xy 234.626451 -145.048475)
			(xy 234.571014 -145.054575) (xy 234.51528 -145.052538) (xy 234.460437 -145.042408) (xy 234.407653 -145.024401)
			(xy 234.358053 -144.9989) (xy 234.312695 -144.966449) (xy 234.272546 -144.92774) (xy 234.23846 -144.883597)
			(xy 234.211164 -144.834962) (xy 234.191241 -144.782871) (xy 234.179115 -144.728434) (xy 234.175044 -144.672812)
			(xy 214.355214 -144.672812) (xy 214.548918 -145.140426) (xy 222.363028 -145.140426) (xy 222.367099 -145.084804)
			(xy 222.379225 -145.030367) (xy 222.399148 -144.978276) (xy 222.426444 -144.929641) (xy 222.46053 -144.885498)
			(xy 222.500679 -144.846789) (xy 222.546037 -144.814338) (xy 222.595637 -144.788837) (xy 222.648421 -144.77083)
			(xy 222.703264 -144.7607) (xy 222.758998 -144.758663) (xy 222.814435 -144.764763) (xy 222.868392 -144.778869)
			(xy 222.919721 -144.800681) (xy 222.967327 -144.829735) (xy 223.010195 -144.86541) (xy 223.047412 -144.906947)
			(xy 223.078185 -144.95346) (xy 223.101857 -145.003957) (xy 223.117925 -145.057364) (xy 223.126045 -145.11254)
			(xy 223.126554 -145.140426) (xy 223.126045 -145.168312) (xy 223.117925 -145.223488) (xy 223.101857 -145.276895)
			(xy 223.078185 -145.327392) (xy 223.047412 -145.373905) (xy 223.010195 -145.415442) (xy 222.967327 -145.451117)
			(xy 222.919721 -145.480171) (xy 222.868392 -145.501983) (xy 222.814435 -145.516089) (xy 222.758998 -145.522189)
			(xy 222.703264 -145.520152) (xy 222.648421 -145.510022) (xy 222.595637 -145.492015) (xy 222.546037 -145.466514)
			(xy 222.500679 -145.434063) (xy 222.46053 -145.395354) (xy 222.426444 -145.351211) (xy 222.399148 -145.302576)
			(xy 222.379225 -145.250485) (xy 222.367099 -145.196048) (xy 222.363028 -145.140426) (xy 214.548918 -145.140426)
			(xy 214.894449 -145.974562) (xy 219.859604 -145.974562) (xy 219.863675 -145.91894) (xy 219.875801 -145.864503)
			(xy 219.895724 -145.812412) (xy 219.92302 -145.763777) (xy 219.957106 -145.719634) (xy 219.997255 -145.680925)
			(xy 220.042613 -145.648474) (xy 220.092213 -145.622973) (xy 220.144997 -145.604966) (xy 220.19984 -145.594836)
			(xy 220.255574 -145.592799) (xy 220.311011 -145.598899) (xy 220.364968 -145.613005) (xy 220.416297 -145.634817)
			(xy 220.463903 -145.663871) (xy 220.493873 -145.688812) (xy 236.25124 -145.688812) (xy 236.255311 -145.63319)
			(xy 236.267437 -145.578753) (xy 236.28736 -145.526662) (xy 236.314656 -145.478027) (xy 236.348742 -145.433884)
			(xy 236.388891 -145.395175) (xy 236.434249 -145.362724) (xy 236.483849 -145.337223) (xy 236.536633 -145.319216)
			(xy 236.591476 -145.309086) (xy 236.64721 -145.307049) (xy 236.702647 -145.313149) (xy 236.756604 -145.327255)
			(xy 236.807933 -145.349067) (xy 236.855539 -145.378121) (xy 236.898407 -145.413796) (xy 236.935624 -145.455333)
			(xy 236.966397 -145.501846) (xy 236.990069 -145.552343) (xy 237.006137 -145.60575) (xy 237.014257 -145.660926)
			(xy 237.014766 -145.688812) (xy 237.014257 -145.716698) (xy 237.006137 -145.771874) (xy 236.990069 -145.825281)
			(xy 236.966397 -145.875778) (xy 236.935624 -145.922291) (xy 236.898407 -145.963828) (xy 236.855539 -145.999503)
			(xy 236.807933 -146.028557) (xy 236.756604 -146.050369) (xy 236.702647 -146.064475) (xy 236.64721 -146.070575)
			(xy 236.591476 -146.068538) (xy 236.536633 -146.058408) (xy 236.483849 -146.040401) (xy 236.434249 -146.0149)
			(xy 236.388891 -145.982449) (xy 236.348742 -145.94374) (xy 236.314656 -145.899597) (xy 236.28736 -145.850962)
			(xy 236.267437 -145.798871) (xy 236.255311 -145.744434) (xy 236.25124 -145.688812) (xy 220.493873 -145.688812)
			(xy 220.506771 -145.699546) (xy 220.543988 -145.741083) (xy 220.574761 -145.787596) (xy 220.598433 -145.838093)
			(xy 220.614501 -145.8915) (xy 220.622621 -145.946676) (xy 220.62313 -145.974562) (xy 220.622621 -146.002448)
			(xy 220.614501 -146.057624) (xy 220.598433 -146.111031) (xy 220.574761 -146.161528) (xy 220.543988 -146.208041)
			(xy 220.506771 -146.249578) (xy 220.463903 -146.285253) (xy 220.416297 -146.314307) (xy 220.364968 -146.336119)
			(xy 220.311011 -146.350225) (xy 220.255574 -146.356325) (xy 220.19984 -146.354288) (xy 220.144997 -146.344158)
			(xy 220.092213 -146.326151) (xy 220.042613 -146.30065) (xy 219.997255 -146.268199) (xy 219.957106 -146.22949)
			(xy 219.92302 -146.185347) (xy 219.895724 -146.136712) (xy 219.875801 -146.084621) (xy 219.863675 -146.030184)
			(xy 219.859604 -145.974562) (xy 214.894449 -145.974562) (xy 215.315315 -146.990562) (xy 221.941642 -146.990562)
			(xy 221.945713 -146.93494) (xy 221.957839 -146.880503) (xy 221.977762 -146.828412) (xy 222.005058 -146.779777)
			(xy 222.039144 -146.735634) (xy 222.079293 -146.696925) (xy 222.124651 -146.664474) (xy 222.174251 -146.638973)
			(xy 222.227035 -146.620966) (xy 222.281878 -146.610836) (xy 222.337612 -146.608799) (xy 222.393049 -146.614899)
			(xy 222.447006 -146.629005) (xy 222.48852 -146.646646) (xy 223.425256 -146.646646) (xy 223.429327 -146.591024)
			(xy 223.441453 -146.536587) (xy 223.461376 -146.484496) (xy 223.488672 -146.435861) (xy 223.522758 -146.391718)
			(xy 223.562907 -146.353009) (xy 223.608265 -146.320558) (xy 223.657865 -146.295057) (xy 223.710649 -146.27705)
			(xy 223.765492 -146.26692) (xy 223.821226 -146.264883) (xy 223.876663 -146.270983) (xy 223.93062 -146.285089)
			(xy 223.981949 -146.306901) (xy 224.029555 -146.335955) (xy 224.072423 -146.37163) (xy 224.10964 -146.413167)
			(xy 224.140413 -146.45968) (xy 224.164085 -146.510177) (xy 224.180153 -146.563584) (xy 224.188273 -146.61876)
			(xy 224.188782 -146.646646) (xy 224.188273 -146.674532) (xy 224.180153 -146.729708) (xy 224.164085 -146.783115)
			(xy 224.140413 -146.833612) (xy 224.10964 -146.880125) (xy 224.072423 -146.921662) (xy 224.029555 -146.957337)
			(xy 223.981949 -146.986391) (xy 223.93062 -147.008203) (xy 223.876663 -147.022309) (xy 223.821226 -147.028409)
			(xy 223.765492 -147.026372) (xy 223.710649 -147.016242) (xy 223.657865 -146.998235) (xy 223.608265 -146.972734)
			(xy 223.562907 -146.940283) (xy 223.522758 -146.901574) (xy 223.488672 -146.857431) (xy 223.461376 -146.808796)
			(xy 223.441453 -146.756705) (xy 223.429327 -146.702268) (xy 223.425256 -146.646646) (xy 222.48852 -146.646646)
			(xy 222.498335 -146.650817) (xy 222.545941 -146.679871) (xy 222.588809 -146.715546) (xy 222.626026 -146.757083)
			(xy 222.656799 -146.803596) (xy 222.680471 -146.854093) (xy 222.696539 -146.9075) (xy 222.704659 -146.962676)
			(xy 222.705168 -146.990562) (xy 222.704659 -147.018448) (xy 222.696539 -147.073624) (xy 222.680471 -147.127031)
			(xy 222.656799 -147.177528) (xy 222.649045 -147.189248) (xy 233.05469 -147.189248) (xy 233.05469 -147.134752)
			(xy 233.062445 -147.08081) (xy 233.077797 -147.028521) (xy 233.100434 -146.978948) (xy 233.129895 -146.933102)
			(xy 233.16558 -146.891914) (xy 233.206763 -146.856224) (xy 233.252606 -146.826757) (xy 233.302176 -146.804114)
			(xy 233.354463 -146.788755) (xy 233.408404 -146.780994) (xy 233.435652 -146.780504) (xy 233.467273 -146.781113)
			(xy 233.529646 -146.791567) (xy 233.589436 -146.812179) (xy 233.617516 -146.826732) (xy 233.625869 -146.830746)
			(xy 233.644237 -146.833091) (xy 233.65333 -146.831304) (xy 233.728514 -146.813524) (xy 233.744262 -146.802856)
			(xy 233.749342 -146.795236) (xy 233.764731 -146.773932) (xy 233.80036 -146.735302) (xy 233.840952 -146.701925)
			(xy 233.885739 -146.674433) (xy 233.933874 -146.653344) (xy 233.984447 -146.639058) (xy 234.036502 -146.631846)
			(xy 234.062778 -146.631406) (xy 234.090033 -146.631839) (xy 234.143988 -146.639594) (xy 234.196291 -146.654949)
			(xy 234.245876 -146.677591) (xy 234.288236 -146.704812) (xy 236.25124 -146.704812) (xy 236.255311 -146.64919)
			(xy 236.267437 -146.594753) (xy 236.28736 -146.542662) (xy 236.314656 -146.494027) (xy 236.348742 -146.449884)
			(xy 236.388891 -146.411175) (xy 236.434249 -146.378724) (xy 236.483849 -146.353223) (xy 236.536633 -146.335216)
			(xy 236.591476 -146.325086) (xy 236.64721 -146.323049) (xy 236.702647 -146.329149) (xy 236.756604 -146.343255)
			(xy 236.807933 -146.365067) (xy 236.855539 -146.394121) (xy 236.898407 -146.429796) (xy 236.935624 -146.471333)
			(xy 236.966397 -146.517846) (xy 236.990069 -146.568343) (xy 237.006137 -146.62175) (xy 237.014257 -146.676926)
			(xy 237.014766 -146.704812) (xy 237.014257 -146.732698) (xy 237.006137 -146.787874) (xy 236.990069 -146.841281)
			(xy 236.966397 -146.891778) (xy 236.935624 -146.938291) (xy 236.898407 -146.979828) (xy 236.855539 -147.015503)
			(xy 236.807933 -147.044557) (xy 236.756604 -147.066369) (xy 236.702647 -147.080475) (xy 236.64721 -147.086575)
			(xy 236.591476 -147.084538) (xy 236.536633 -147.074408) (xy 236.483849 -147.056401) (xy 236.434249 -147.0309)
			(xy 236.388891 -146.998449) (xy 236.348742 -146.95974) (xy 236.314656 -146.915597) (xy 236.28736 -146.866962)
			(xy 236.267437 -146.814871) (xy 236.255311 -146.760434) (xy 236.25124 -146.704812) (xy 234.288236 -146.704812)
			(xy 234.291733 -146.707059) (xy 234.33293 -146.742754) (xy 234.368627 -146.783949) (xy 234.398099 -146.829805)
			(xy 234.420743 -146.879389) (xy 234.436101 -146.93169) (xy 234.443859 -146.985645) (xy 234.443859 -147.040155)
			(xy 234.436101 -147.09411) (xy 234.420743 -147.146411) (xy 234.398099 -147.195995) (xy 234.368627 -147.241851)
			(xy 234.33293 -147.283046) (xy 234.291733 -147.318741) (xy 234.245876 -147.348209) (xy 234.196291 -147.370851)
			(xy 234.143988 -147.386206) (xy 234.090033 -147.393961) (xy 234.062778 -147.394422) (xy 234.031157 -147.393809)
			(xy 233.968784 -147.383359) (xy 233.908994 -147.362748) (xy 233.880914 -147.348194) (xy 233.872555 -147.344195)
			(xy 233.854192 -147.34184) (xy 233.8451 -147.343622) (xy 233.769916 -147.361402) (xy 233.754168 -147.37207)
			(xy 233.749088 -147.37969) (xy 233.733751 -147.401032) (xy 233.698112 -147.43966) (xy 233.657511 -147.473033)
			(xy 233.612715 -147.500521) (xy 233.564572 -147.521603) (xy 233.513991 -147.535881) (xy 233.461931 -147.543085)
			(xy 233.435652 -147.54352) (xy 233.408404 -147.543006) (xy 233.354463 -147.535245) (xy 233.302176 -147.519886)
			(xy 233.252606 -147.497243) (xy 233.206763 -147.467776) (xy 233.16558 -147.432086) (xy 233.129895 -147.390898)
			(xy 233.100434 -147.345052) (xy 233.077797 -147.295479) (xy 233.062445 -147.24319) (xy 233.05469 -147.189248)
			(xy 222.649045 -147.189248) (xy 222.626026 -147.224041) (xy 222.588809 -147.265578) (xy 222.545941 -147.301253)
			(xy 222.498335 -147.330307) (xy 222.447006 -147.352119) (xy 222.393049 -147.366225) (xy 222.337612 -147.372325)
			(xy 222.281878 -147.370288) (xy 222.227035 -147.360158) (xy 222.174251 -147.342151) (xy 222.124651 -147.31665)
			(xy 222.079293 -147.284199) (xy 222.039144 -147.24549) (xy 222.005058 -147.201347) (xy 221.977762 -147.152712)
			(xy 221.957839 -147.100621) (xy 221.945713 -147.046184) (xy 221.941642 -146.990562) (xy 215.315315 -146.990562)
			(xy 215.617812 -147.720812) (xy 234.212128 -147.720812) (xy 234.216199 -147.66519) (xy 234.228325 -147.610753)
			(xy 234.248248 -147.558662) (xy 234.275544 -147.510027) (xy 234.30963 -147.465884) (xy 234.349779 -147.427175)
			(xy 234.395137 -147.394724) (xy 234.444737 -147.369223) (xy 234.497521 -147.351216) (xy 234.552364 -147.341086)
			(xy 234.608098 -147.339049) (xy 234.663535 -147.345149) (xy 234.717492 -147.359255) (xy 234.768821 -147.381067)
			(xy 234.816427 -147.410121) (xy 234.859295 -147.445796) (xy 234.896512 -147.487333) (xy 234.927285 -147.533846)
			(xy 234.950957 -147.584343) (xy 234.967025 -147.63775) (xy 234.975145 -147.692926) (xy 234.975654 -147.720812)
			(xy 236.25124 -147.720812) (xy 236.255311 -147.66519) (xy 236.267437 -147.610753) (xy 236.28736 -147.558662)
			(xy 236.314656 -147.510027) (xy 236.348742 -147.465884) (xy 236.388891 -147.427175) (xy 236.434249 -147.394724)
			(xy 236.483849 -147.369223) (xy 236.536633 -147.351216) (xy 236.591476 -147.341086) (xy 236.64721 -147.339049)
			(xy 236.702647 -147.345149) (xy 236.756604 -147.359255) (xy 236.807933 -147.381067) (xy 236.855539 -147.410121)
			(xy 236.898407 -147.445796) (xy 236.935624 -147.487333) (xy 236.966397 -147.533846) (xy 236.990069 -147.584343)
			(xy 237.006137 -147.63775) (xy 237.014257 -147.692926) (xy 237.014766 -147.720812) (xy 237.014257 -147.748698)
			(xy 237.006137 -147.803874) (xy 236.990069 -147.857281) (xy 236.966397 -147.907778) (xy 236.935624 -147.954291)
			(xy 236.898407 -147.995828) (xy 236.855539 -148.031503) (xy 236.807933 -148.060557) (xy 236.756604 -148.082369)
			(xy 236.702647 -148.096475) (xy 236.64721 -148.102575) (xy 236.591476 -148.100538) (xy 236.536633 -148.090408)
			(xy 236.483849 -148.072401) (xy 236.434249 -148.0469) (xy 236.388891 -148.014449) (xy 236.348742 -147.97574)
			(xy 236.314656 -147.931597) (xy 236.28736 -147.882962) (xy 236.267437 -147.830871) (xy 236.255311 -147.776434)
			(xy 236.25124 -147.720812) (xy 234.975654 -147.720812) (xy 234.975145 -147.748698) (xy 234.967025 -147.803874)
			(xy 234.950957 -147.857281) (xy 234.927285 -147.907778) (xy 234.896512 -147.954291) (xy 234.859295 -147.995828)
			(xy 234.816427 -148.031503) (xy 234.768821 -148.060557) (xy 234.717492 -148.082369) (xy 234.663535 -148.096475)
			(xy 234.608098 -148.102575) (xy 234.552364 -148.100538) (xy 234.497521 -148.090408) (xy 234.444737 -148.072401)
			(xy 234.395137 -148.0469) (xy 234.349779 -148.014449) (xy 234.30963 -147.97574) (xy 234.275544 -147.931597)
			(xy 234.248248 -147.882962) (xy 234.228325 -147.830871) (xy 234.216199 -147.776434) (xy 234.212128 -147.720812)
			(xy 215.617812 -147.720812) (xy 216.170199 -149.054312) (xy 219.859604 -149.054312) (xy 219.863675 -148.99869)
			(xy 219.875801 -148.944253) (xy 219.895724 -148.892162) (xy 219.92302 -148.843527) (xy 219.957106 -148.799384)
			(xy 219.997255 -148.760675) (xy 220.042613 -148.728224) (xy 220.092213 -148.702723) (xy 220.144997 -148.684716)
			(xy 220.19984 -148.674586) (xy 220.255574 -148.672549) (xy 220.311011 -148.678649) (xy 220.364968 -148.692755)
			(xy 220.416297 -148.714567) (xy 220.463903 -148.743621) (xy 220.506771 -148.779296) (xy 220.543988 -148.820833)
			(xy 220.574761 -148.867346) (xy 220.598433 -148.917843) (xy 220.614501 -148.97125) (xy 220.622621 -149.026426)
			(xy 220.62313 -149.054312) (xy 220.622621 -149.082198) (xy 220.614501 -149.137374) (xy 220.598433 -149.190781)
			(xy 220.574761 -149.241278) (xy 220.543988 -149.287791) (xy 220.506771 -149.329328) (xy 220.463903 -149.365003)
			(xy 220.416297 -149.394057) (xy 220.394527 -149.403308) (xy 223.512886 -149.403308) (xy 223.516957 -149.347686)
			(xy 223.529083 -149.293249) (xy 223.549006 -149.241158) (xy 223.576302 -149.192523) (xy 223.610388 -149.14838)
			(xy 223.650537 -149.109671) (xy 223.695895 -149.07722) (xy 223.745495 -149.051719) (xy 223.798279 -149.033712)
			(xy 223.853122 -149.023582) (xy 223.908856 -149.021545) (xy 223.964293 -149.027645) (xy 224.01825 -149.041751)
			(xy 224.069579 -149.063563) (xy 224.117185 -149.092617) (xy 224.160053 -149.128292) (xy 224.19727 -149.169829)
			(xy 224.228043 -149.216342) (xy 224.251715 -149.266839) (xy 224.258038 -149.287857) (xy 233.065215 -149.287857)
			(xy 233.065215 -149.233343) (xy 233.072973 -149.179385) (xy 233.088332 -149.12708) (xy 233.110978 -149.077493)
			(xy 233.140451 -149.031634) (xy 233.176151 -148.990437) (xy 233.21735 -148.954739) (xy 233.263211 -148.925269)
			(xy 233.312799 -148.902625) (xy 233.365105 -148.887269) (xy 233.419063 -148.879514) (xy 233.44632 -148.879052)
			(xy 233.473193 -148.879488) (xy 233.526406 -148.887047) (xy 233.578032 -148.901998) (xy 233.627049 -148.924046)
			(xy 233.672487 -148.952753) (xy 233.713447 -148.987553) (xy 233.749118 -149.027757) (xy 233.778795 -149.072568)
			(xy 233.80189 -149.1211) (xy 233.817946 -149.172393) (xy 233.822748 -149.198838) (xy 233.824272 -149.208744)
			(xy 233.834686 -149.225508) (xy 233.899964 -149.273514) (xy 233.908092 -149.278969) (xy 233.927045 -149.283799)
			(xy 233.936794 -149.282912) (xy 233.937048 -149.282912) (xy 233.949938 -149.281253) (xy 233.975868 -149.279475)
			(xy 233.988864 -149.279356) (xy 233.989118 -149.279356) (xy 234.016366 -149.279915) (xy 234.070306 -149.287673)
			(xy 234.122594 -149.303028) (xy 234.172164 -149.325668) (xy 234.218008 -149.355132) (xy 234.259192 -149.390821)
			(xy 234.294878 -149.432006) (xy 234.32434 -149.477852) (xy 234.346978 -149.527423) (xy 234.362331 -149.579711)
			(xy 234.370086 -149.633652) (xy 234.370086 -149.688148) (xy 234.362331 -149.742089) (xy 234.346978 -149.794377)
			(xy 234.32434 -149.843948) (xy 234.294878 -149.889794) (xy 234.259192 -149.930979) (xy 234.218008 -149.966668)
			(xy 234.172164 -149.996131) (xy 234.122594 -150.018772) (xy 234.070306 -150.034127) (xy 234.016366 -150.041885)
			(xy 233.989118 -150.042372) (xy 233.962247 -150.041881) (xy 233.909037 -150.034328) (xy 233.857413 -150.019383)
			(xy 233.808398 -149.997342) (xy 233.762961 -149.96864) (xy 233.722001 -149.933846) (xy 233.686329 -149.893649)
			(xy 233.65665 -149.848843) (xy 233.633553 -149.800316) (xy 233.617494 -149.749029) (xy 233.61269 -149.722586)
			(xy 233.611166 -149.71268) (xy 233.600752 -149.695916) (xy 233.535474 -149.64791) (xy 233.527334 -149.642476)
			(xy 233.508391 -149.637632) (xy 233.498644 -149.638512) (xy 233.49839 -149.638512) (xy 233.4855 -149.640167)
			(xy 233.45957 -149.641948) (xy 233.446574 -149.642068) (xy 233.44632 -149.642068) (xy 233.419063 -149.641686)
			(xy 233.365105 -149.633931) (xy 233.312799 -149.618575) (xy 233.263211 -149.595931) (xy 233.21735 -149.566461)
			(xy 233.176151 -149.530763) (xy 233.140451 -149.489566) (xy 233.110978 -149.443707) (xy 233.088332 -149.39412)
			(xy 233.072973 -149.341815) (xy 233.065215 -149.287857) (xy 224.258038 -149.287857) (xy 224.267783 -149.320246)
			(xy 224.275903 -149.375422) (xy 224.276412 -149.403308) (xy 224.275903 -149.431194) (xy 224.267783 -149.48637)
			(xy 224.251715 -149.539777) (xy 224.228043 -149.590274) (xy 224.19727 -149.636787) (xy 224.160053 -149.678324)
			(xy 224.117185 -149.713999) (xy 224.069579 -149.743053) (xy 224.01825 -149.764865) (xy 223.964293 -149.778971)
			(xy 223.908856 -149.785071) (xy 223.853122 -149.783034) (xy 223.798279 -149.772904) (xy 223.745495 -149.754897)
			(xy 223.695895 -149.729396) (xy 223.650537 -149.696945) (xy 223.610388 -149.658236) (xy 223.576302 -149.614093)
			(xy 223.549006 -149.565458) (xy 223.529083 -149.513367) (xy 223.516957 -149.45893) (xy 223.512886 -149.403308)
			(xy 220.394527 -149.403308) (xy 220.364968 -149.415869) (xy 220.311011 -149.429975) (xy 220.255574 -149.436075)
			(xy 220.19984 -149.434038) (xy 220.144997 -149.423908) (xy 220.092213 -149.405901) (xy 220.042613 -149.3804)
			(xy 219.997255 -149.347949) (xy 219.957106 -149.30924) (xy 219.92302 -149.265097) (xy 219.895724 -149.216462)
			(xy 219.875801 -149.164371) (xy 219.863675 -149.109934) (xy 219.859604 -149.054312) (xy 216.170199 -149.054312)
			(xy 217.193114 -151.5237) (xy 217.211322 -151.569174) (xy 217.239759 -151.662915) (xy 217.240007 -151.664162)
			(xy 231.773474 -151.664162) (xy 231.777545 -151.60854) (xy 231.789671 -151.554103) (xy 231.809594 -151.502012)
			(xy 231.83689 -151.453377) (xy 231.870976 -151.409234) (xy 231.911125 -151.370525) (xy 231.956483 -151.338074)
			(xy 232.006083 -151.312573) (xy 232.058867 -151.294566) (xy 232.11371 -151.284436) (xy 232.169444 -151.282399)
			(xy 232.224881 -151.288499) (xy 232.278838 -151.302605) (xy 232.330167 -151.324417) (xy 232.377773 -151.353471)
			(xy 232.420641 -151.389146) (xy 232.457858 -151.430683) (xy 232.488631 -151.477196) (xy 232.512303 -151.527693)
			(xy 232.528371 -151.5811) (xy 232.536491 -151.636276) (xy 232.537 -151.664162) (xy 232.536491 -151.692048)
			(xy 232.528371 -151.747224) (xy 232.512303 -151.800631) (xy 232.488631 -151.851128) (xy 232.457858 -151.897641)
			(xy 232.420641 -151.939178) (xy 232.377773 -151.974853) (xy 232.330167 -152.003907) (xy 232.278838 -152.025719)
			(xy 232.224881 -152.039825) (xy 232.169444 -152.045925) (xy 232.11371 -152.043888) (xy 232.058867 -152.033758)
			(xy 232.006083 -152.015751) (xy 231.956483 -151.99025) (xy 231.911125 -151.957799) (xy 231.870976 -151.91909)
			(xy 231.83689 -151.874947) (xy 231.809594 -151.826312) (xy 231.789671 -151.774221) (xy 231.777545 -151.719784)
			(xy 231.773474 -151.664162) (xy 217.240007 -151.664162) (xy 217.258869 -151.758993) (xy 217.268467 -151.856482)
			(xy 217.26906 -151.905462) (xy 217.26906 -152.412446) (xy 226.102924 -152.412446) (xy 226.106995 -152.356824)
			(xy 226.119121 -152.302387) (xy 226.139044 -152.250296) (xy 226.16634 -152.201661) (xy 226.200426 -152.157518)
			(xy 226.240575 -152.118809) (xy 226.285933 -152.086358) (xy 226.335533 -152.060857) (xy 226.388317 -152.04285)
			(xy 226.44316 -152.03272) (xy 226.498894 -152.030683) (xy 226.554331 -152.036783) (xy 226.608288 -152.050889)
			(xy 226.659617 -152.072701) (xy 226.707223 -152.101755) (xy 226.750091 -152.13743) (xy 226.787308 -152.178967)
			(xy 226.818081 -152.22548) (xy 226.841753 -152.275977) (xy 226.857821 -152.329384) (xy 226.864139 -152.372314)
			(xy 227.76256 -152.372314) (xy 227.766631 -152.316692) (xy 227.778757 -152.262255) (xy 227.79868 -152.210164)
			(xy 227.825976 -152.161529) (xy 227.860062 -152.117386) (xy 227.900211 -152.078677) (xy 227.945569 -152.046226)
			(xy 227.995169 -152.020725) (xy 228.047953 -152.002718) (xy 228.102796 -151.992588) (xy 228.15853 -151.990551)
			(xy 228.213967 -151.996651) (xy 228.267924 -152.010757) (xy 228.319253 -152.032569) (xy 228.366859 -152.061623)
			(xy 228.38462 -152.076404) (xy 230.958388 -152.076404) (xy 230.962459 -152.020782) (xy 230.974585 -151.966345)
			(xy 230.994508 -151.914254) (xy 231.021804 -151.865619) (xy 231.05589 -151.821476) (xy 231.096039 -151.782767)
			(xy 231.141397 -151.750316) (xy 231.190997 -151.724815) (xy 231.243781 -151.706808) (xy 231.298624 -151.696678)
			(xy 231.354358 -151.694641) (xy 231.409795 -151.700741) (xy 231.463752 -151.714847) (xy 231.515081 -151.736659)
			(xy 231.562687 -151.765713) (xy 231.605555 -151.801388) (xy 231.642772 -151.842925) (xy 231.673545 -151.889438)
			(xy 231.697217 -151.939935) (xy 231.713285 -151.993342) (xy 231.721405 -152.048518) (xy 231.721914 -152.076404)
			(xy 231.721405 -152.10429) (xy 231.713285 -152.159466) (xy 231.697217 -152.212873) (xy 231.673545 -152.26337)
			(xy 231.642772 -152.309883) (xy 231.605555 -152.35142) (xy 231.562687 -152.387095) (xy 231.515081 -152.416149)
			(xy 231.463752 -152.437961) (xy 231.409795 -152.452067) (xy 231.354358 -152.458167) (xy 231.298624 -152.45613)
			(xy 231.243781 -152.446) (xy 231.190997 -152.427993) (xy 231.141397 -152.402492) (xy 231.096039 -152.370041)
			(xy 231.05589 -152.331332) (xy 231.021804 -152.287189) (xy 230.994508 -152.238554) (xy 230.974585 -152.186463)
			(xy 230.962459 -152.132026) (xy 230.958388 -152.076404) (xy 228.38462 -152.076404) (xy 228.409727 -152.097298)
			(xy 228.446944 -152.138835) (xy 228.477717 -152.185348) (xy 228.501389 -152.235845) (xy 228.517457 -152.289252)
			(xy 228.525577 -152.344428) (xy 228.526086 -152.372314) (xy 228.525577 -152.4002) (xy 228.517457 -152.455376)
			(xy 228.501389 -152.508783) (xy 228.477717 -152.55928) (xy 228.446944 -152.605793) (xy 228.409727 -152.64733)
			(xy 228.366859 -152.683005) (xy 228.319253 -152.712059) (xy 228.267924 -152.733871) (xy 228.213967 -152.747977)
			(xy 228.15853 -152.754077) (xy 228.102796 -152.75204) (xy 228.047953 -152.74191) (xy 227.995169 -152.723903)
			(xy 227.945569 -152.698402) (xy 227.900211 -152.665951) (xy 227.860062 -152.627242) (xy 227.825976 -152.583099)
			(xy 227.79868 -152.534464) (xy 227.778757 -152.482373) (xy 227.766631 -152.427936) (xy 227.76256 -152.372314)
			(xy 226.864139 -152.372314) (xy 226.865941 -152.38456) (xy 226.86645 -152.412446) (xy 226.865941 -152.440332)
			(xy 226.857821 -152.495508) (xy 226.841753 -152.548915) (xy 226.818081 -152.599412) (xy 226.787308 -152.645925)
			(xy 226.750091 -152.687462) (xy 226.707223 -152.723137) (xy 226.659617 -152.752191) (xy 226.608288 -152.774003)
			(xy 226.554331 -152.788109) (xy 226.498894 -152.794209) (xy 226.44316 -152.792172) (xy 226.388317 -152.782042)
			(xy 226.335533 -152.764035) (xy 226.285933 -152.738534) (xy 226.240575 -152.706083) (xy 226.200426 -152.667374)
			(xy 226.16634 -152.623231) (xy 226.139044 -152.574596) (xy 226.119121 -152.522505) (xy 226.106995 -152.468068)
			(xy 226.102924 -152.412446) (xy 217.26906 -152.412446) (xy 217.26906 -153.675842) (xy 222.211136 -153.675842)
			(xy 222.215207 -153.62022) (xy 222.227333 -153.565783) (xy 222.247256 -153.513692) (xy 222.274552 -153.465057)
			(xy 222.308638 -153.420914) (xy 222.348787 -153.382205) (xy 222.394145 -153.349754) (xy 222.443745 -153.324253)
			(xy 222.496529 -153.306246) (xy 222.551372 -153.296116) (xy 222.607106 -153.294079) (xy 222.662543 -153.300179)
			(xy 222.7165 -153.314285) (xy 222.767829 -153.336097) (xy 222.815435 -153.365151) (xy 222.858303 -153.400826)
			(xy 222.89552 -153.442363) (xy 222.926293 -153.488876) (xy 222.949965 -153.539373) (xy 222.966033 -153.59278)
			(xy 222.974153 -153.647956) (xy 222.974662 -153.675842) (xy 222.974153 -153.703728) (xy 222.966033 -153.758904)
			(xy 222.949965 -153.812311) (xy 222.926293 -153.862808) (xy 222.89552 -153.909321) (xy 222.858303 -153.950858)
			(xy 222.815435 -153.986533) (xy 222.767829 -154.015587) (xy 222.7165 -154.037399) (xy 222.662543 -154.051505)
			(xy 222.607106 -154.057605) (xy 222.551372 -154.055568) (xy 222.496529 -154.045438) (xy 222.443745 -154.027431)
			(xy 222.394145 -154.00193) (xy 222.348787 -153.969479) (xy 222.308638 -153.93077) (xy 222.274552 -153.886627)
			(xy 222.247256 -153.837992) (xy 222.227333 -153.785901) (xy 222.215207 -153.731464) (xy 222.211136 -153.675842)
			(xy 217.26906 -153.675842) (xy 217.26906 -154.564842) (xy 222.211136 -154.564842) (xy 222.215207 -154.50922)
			(xy 222.227333 -154.454783) (xy 222.247256 -154.402692) (xy 222.274552 -154.354057) (xy 222.308638 -154.309914)
			(xy 222.348787 -154.271205) (xy 222.394145 -154.238754) (xy 222.443745 -154.213253) (xy 222.496529 -154.195246)
			(xy 222.551372 -154.185116) (xy 222.607106 -154.183079) (xy 222.662543 -154.189179) (xy 222.7165 -154.203285)
			(xy 222.767829 -154.225097) (xy 222.815435 -154.254151) (xy 222.858303 -154.289826) (xy 222.89552 -154.331363)
			(xy 222.926293 -154.377876) (xy 222.949965 -154.428373) (xy 222.966033 -154.48178) (xy 222.974153 -154.536956)
			(xy 222.974662 -154.564842) (xy 222.974153 -154.592728) (xy 222.966033 -154.647904) (xy 222.949965 -154.701311)
			(xy 222.926293 -154.751808) (xy 222.89552 -154.798321) (xy 222.858303 -154.839858) (xy 222.830755 -154.862784)
			(xy 227.184964 -154.862784) (xy 227.189035 -154.807162) (xy 227.201161 -154.752725) (xy 227.221084 -154.700634)
			(xy 227.24838 -154.651999) (xy 227.282466 -154.607856) (xy 227.322615 -154.569147) (xy 227.367973 -154.536696)
			(xy 227.417573 -154.511195) (xy 227.470357 -154.493188) (xy 227.5252 -154.483058) (xy 227.580934 -154.481021)
			(xy 227.636371 -154.487121) (xy 227.690328 -154.501227) (xy 227.741657 -154.523039) (xy 227.789263 -154.552093)
			(xy 227.832131 -154.587768) (xy 227.869348 -154.629305) (xy 227.883835 -154.651202) (xy 234.809028 -154.651202)
			(xy 234.813099 -154.59558) (xy 234.825225 -154.541143) (xy 234.845148 -154.489052) (xy 234.872444 -154.440417)
			(xy 234.90653 -154.396274) (xy 234.946679 -154.357565) (xy 234.992037 -154.325114) (xy 235.041637 -154.299613)
			(xy 235.094421 -154.281606) (xy 235.149264 -154.271476) (xy 235.204998 -154.269439) (xy 235.260435 -154.275539)
			(xy 235.314392 -154.289645) (xy 235.365721 -154.311457) (xy 235.413327 -154.340511) (xy 235.456195 -154.376186)
			(xy 235.493412 -154.417723) (xy 235.524185 -154.464236) (xy 235.547857 -154.514733) (xy 235.563925 -154.56814)
			(xy 235.572045 -154.623316) (xy 235.572554 -154.651202) (xy 235.572045 -154.679088) (xy 235.563925 -154.734264)
			(xy 235.547857 -154.787671) (xy 235.524185 -154.838168) (xy 235.493412 -154.884681) (xy 235.456195 -154.926218)
			(xy 235.413327 -154.961893) (xy 235.365721 -154.990947) (xy 235.314392 -155.012759) (xy 235.260435 -155.026865)
			(xy 235.204998 -155.032965) (xy 235.149264 -155.030928) (xy 235.094421 -155.020798) (xy 235.041637 -155.002791)
			(xy 234.992037 -154.97729) (xy 234.946679 -154.944839) (xy 234.90653 -154.90613) (xy 234.872444 -154.861987)
			(xy 234.845148 -154.813352) (xy 234.825225 -154.761261) (xy 234.813099 -154.706824) (xy 234.809028 -154.651202)
			(xy 227.883835 -154.651202) (xy 227.900121 -154.675818) (xy 227.923793 -154.726315) (xy 227.939861 -154.779722)
			(xy 227.947981 -154.834898) (xy 227.94849 -154.862784) (xy 227.947981 -154.89067) (xy 227.939861 -154.945846)
			(xy 227.923793 -154.999253) (xy 227.900121 -155.04975) (xy 227.869348 -155.096263) (xy 227.832131 -155.1378)
			(xy 227.789263 -155.173475) (xy 227.741657 -155.202529) (xy 227.690328 -155.224341) (xy 227.636371 -155.238447)
			(xy 227.580934 -155.244547) (xy 227.5252 -155.24251) (xy 227.470357 -155.23238) (xy 227.417573 -155.214373)
			(xy 227.367973 -155.188872) (xy 227.322615 -155.156421) (xy 227.282466 -155.117712) (xy 227.24838 -155.073569)
			(xy 227.221084 -155.024934) (xy 227.201161 -154.972843) (xy 227.189035 -154.918406) (xy 227.184964 -154.862784)
			(xy 222.830755 -154.862784) (xy 222.815435 -154.875533) (xy 222.767829 -154.904587) (xy 222.7165 -154.926399)
			(xy 222.662543 -154.940505) (xy 222.607106 -154.946605) (xy 222.551372 -154.944568) (xy 222.496529 -154.934438)
			(xy 222.443745 -154.916431) (xy 222.394145 -154.89093) (xy 222.348787 -154.858479) (xy 222.308638 -154.81977)
			(xy 222.274552 -154.775627) (xy 222.247256 -154.726992) (xy 222.227333 -154.674901) (xy 222.215207 -154.620464)
			(xy 222.211136 -154.564842) (xy 217.26906 -154.564842) (xy 217.26906 -155.540202) (xy 234.809028 -155.540202)
			(xy 234.813099 -155.48458) (xy 234.825225 -155.430143) (xy 234.845148 -155.378052) (xy 234.872444 -155.329417)
			(xy 234.90653 -155.285274) (xy 234.946679 -155.246565) (xy 234.992037 -155.214114) (xy 235.041637 -155.188613)
			(xy 235.094421 -155.170606) (xy 235.149264 -155.160476) (xy 235.204998 -155.158439) (xy 235.260435 -155.164539)
			(xy 235.314392 -155.178645) (xy 235.365721 -155.200457) (xy 235.38469 -155.212034) (xy 239.469166 -155.212034)
			(xy 239.473237 -155.156412) (xy 239.485363 -155.101975) (xy 239.505286 -155.049884) (xy 239.532582 -155.001249)
			(xy 239.566668 -154.957106) (xy 239.606817 -154.918397) (xy 239.652175 -154.885946) (xy 239.701775 -154.860445)
			(xy 239.754559 -154.842438) (xy 239.809402 -154.832308) (xy 239.865136 -154.830271) (xy 239.920573 -154.836371)
			(xy 239.97453 -154.850477) (xy 240.025859 -154.872289) (xy 240.073465 -154.901343) (xy 240.116333 -154.937018)
			(xy 240.15355 -154.978555) (xy 240.184323 -155.025068) (xy 240.207995 -155.075565) (xy 240.224063 -155.128972)
			(xy 240.232183 -155.184148) (xy 240.232692 -155.212034) (xy 240.232183 -155.23992) (xy 240.224063 -155.295096)
			(xy 240.207995 -155.348503) (xy 240.184323 -155.399) (xy 240.15355 -155.445513) (xy 240.116333 -155.48705)
			(xy 240.073465 -155.522725) (xy 240.025859 -155.551779) (xy 239.97453 -155.573591) (xy 239.920573 -155.587697)
			(xy 239.865136 -155.593797) (xy 239.809402 -155.59176) (xy 239.754559 -155.58163) (xy 239.701775 -155.563623)
			(xy 239.652175 -155.538122) (xy 239.606817 -155.505671) (xy 239.566668 -155.466962) (xy 239.532582 -155.422819)
			(xy 239.505286 -155.374184) (xy 239.485363 -155.322093) (xy 239.473237 -155.267656) (xy 239.469166 -155.212034)
			(xy 235.38469 -155.212034) (xy 235.413327 -155.229511) (xy 235.456195 -155.265186) (xy 235.493412 -155.306723)
			(xy 235.524185 -155.353236) (xy 235.547857 -155.403733) (xy 235.563925 -155.45714) (xy 235.572045 -155.512316)
			(xy 235.572554 -155.540202) (xy 235.572045 -155.568088) (xy 235.563925 -155.623264) (xy 235.547857 -155.676671)
			(xy 235.524185 -155.727168) (xy 235.493412 -155.773681) (xy 235.456195 -155.815218) (xy 235.413327 -155.850893)
			(xy 235.365721 -155.879947) (xy 235.314392 -155.901759) (xy 235.260435 -155.915865) (xy 235.204998 -155.921965)
			(xy 235.149264 -155.919928) (xy 235.094421 -155.909798) (xy 235.041637 -155.891791) (xy 234.992037 -155.86629)
			(xy 234.946679 -155.833839) (xy 234.90653 -155.79513) (xy 234.872444 -155.750987) (xy 234.845148 -155.702352)
			(xy 234.825225 -155.650261) (xy 234.813099 -155.595824) (xy 234.809028 -155.540202) (xy 217.26906 -155.540202)
			(xy 217.26906 -157.008322) (xy 226.168964 -157.008322) (xy 226.173035 -156.9527) (xy 226.185161 -156.898263)
			(xy 226.205084 -156.846172) (xy 226.23238 -156.797537) (xy 226.266466 -156.753394) (xy 226.306615 -156.714685)
			(xy 226.351973 -156.682234) (xy 226.401573 -156.656733) (xy 226.454357 -156.638726) (xy 226.5092 -156.628596)
			(xy 226.564934 -156.626559) (xy 226.620371 -156.632659) (xy 226.674328 -156.646765) (xy 226.725657 -156.668577)
			(xy 226.7671 -156.69387) (xy 241.0874 -156.69387) (xy 241.091471 -156.638248) (xy 241.103597 -156.583811)
			(xy 241.12352 -156.53172) (xy 241.150816 -156.483085) (xy 241.184902 -156.438942) (xy 241.225051 -156.400233)
			(xy 241.270409 -156.367782) (xy 241.320009 -156.342281) (xy 241.372793 -156.324274) (xy 241.427636 -156.314144)
			(xy 241.48337 -156.312107) (xy 241.538807 -156.318207) (xy 241.592764 -156.332313) (xy 241.644093 -156.354125)
			(xy 241.691699 -156.383179) (xy 241.734567 -156.418854) (xy 241.771784 -156.460391) (xy 241.802557 -156.506904)
			(xy 241.826229 -156.557401) (xy 241.842297 -156.610808) (xy 241.850417 -156.665984) (xy 241.850926 -156.69387)
			(xy 241.850417 -156.721756) (xy 241.842297 -156.776932) (xy 241.826229 -156.830339) (xy 241.802557 -156.880836)
			(xy 241.771784 -156.927349) (xy 241.734567 -156.968886) (xy 241.691699 -157.004561) (xy 241.644093 -157.033615)
			(xy 241.592764 -157.055427) (xy 241.538807 -157.069533) (xy 241.48337 -157.075633) (xy 241.427636 -157.073596)
			(xy 241.372793 -157.063466) (xy 241.320009 -157.045459) (xy 241.270409 -157.019958) (xy 241.225051 -156.987507)
			(xy 241.184902 -156.948798) (xy 241.150816 -156.904655) (xy 241.12352 -156.85602) (xy 241.103597 -156.803929)
			(xy 241.091471 -156.749492) (xy 241.0874 -156.69387) (xy 226.7671 -156.69387) (xy 226.773263 -156.697631)
			(xy 226.816131 -156.733306) (xy 226.853348 -156.774843) (xy 226.884121 -156.821356) (xy 226.907793 -156.871853)
			(xy 226.923861 -156.92526) (xy 226.931981 -156.980436) (xy 226.93249 -157.008322) (xy 226.931981 -157.036208)
			(xy 226.923861 -157.091384) (xy 226.907793 -157.144791) (xy 226.884121 -157.195288) (xy 226.853348 -157.241801)
			(xy 226.816131 -157.283338) (xy 226.773263 -157.319013) (xy 226.725657 -157.348067) (xy 226.674328 -157.369879)
			(xy 226.620371 -157.383985) (xy 226.564934 -157.390085) (xy 226.5092 -157.388048) (xy 226.454357 -157.377918)
			(xy 226.401573 -157.359911) (xy 226.351973 -157.33441) (xy 226.306615 -157.301959) (xy 226.266466 -157.26325)
			(xy 226.23238 -157.219107) (xy 226.205084 -157.170472) (xy 226.185161 -157.118381) (xy 226.173035 -157.063944)
			(xy 226.168964 -157.008322) (xy 217.26906 -157.008322) (xy 217.26906 -157.900066) (xy 228.314505 -157.900066)
			(xy 228.314505 -157.840134) (xy 228.322328 -157.780714) (xy 228.33784 -157.722823) (xy 228.360775 -157.667453)
			(xy 228.390741 -157.61555) (xy 228.427226 -157.568002) (xy 228.469605 -157.525624) (xy 228.517153 -157.489139)
			(xy 228.569056 -157.459173) (xy 228.624427 -157.436238) (xy 228.682318 -157.420727) (xy 228.741738 -157.412905)
			(xy 228.771704 -157.412436) (xy 229.635304 -157.412436) (xy 229.665274 -157.412838) (xy 229.724702 -157.420663)
			(xy 229.7826 -157.436177) (xy 229.837978 -157.459116) (xy 229.889888 -157.489086) (xy 229.937442 -157.525576)
			(xy 229.979827 -157.567961) (xy 230.016316 -157.615515) (xy 230.046286 -157.667425) (xy 230.069224 -157.722803)
			(xy 230.084738 -157.780702) (xy 230.092562 -157.84013) (xy 230.092562 -157.90007) (xy 230.089876 -157.920473)
			(xy 230.557725 -157.920473) (xy 230.557725 -157.860527) (xy 230.56555 -157.801095) (xy 230.581066 -157.743192)
			(xy 230.604007 -157.68781) (xy 230.633981 -157.635897) (xy 230.670475 -157.58834) (xy 230.712864 -157.545953)
			(xy 230.760423 -157.509463) (xy 230.812339 -157.479493) (xy 230.867722 -157.456555) (xy 230.925626 -157.441044)
			(xy 230.985059 -157.433223) (xy 231.015032 -157.432756) (xy 231.878632 -157.432756) (xy 231.908596 -157.43332)
			(xy 231.968011 -157.441146) (xy 232.025896 -157.45666) (xy 232.081261 -157.479596) (xy 232.133158 -157.509563)
			(xy 232.180701 -157.546046) (xy 232.223075 -157.588423) (xy 232.259555 -157.635968) (xy 232.289518 -157.687868)
			(xy 232.31245 -157.743235) (xy 232.32796 -157.801121) (xy 232.329523 -157.812994) (xy 238.850168 -157.812994)
			(xy 238.854239 -157.757372) (xy 238.866365 -157.702935) (xy 238.886288 -157.650844) (xy 238.913584 -157.602209)
			(xy 238.94767 -157.558066) (xy 238.987819 -157.519357) (xy 239.033177 -157.486906) (xy 239.082777 -157.461405)
			(xy 239.135561 -157.443398) (xy 239.190404 -157.433268) (xy 239.246138 -157.431231) (xy 239.301575 -157.437331)
			(xy 239.355532 -157.451437) (xy 239.406861 -157.473249) (xy 239.454467 -157.502303) (xy 239.497335 -157.537978)
			(xy 239.534552 -157.579515) (xy 239.565325 -157.626028) (xy 239.575575 -157.647894) (xy 243.21389 -157.647894)
			(xy 243.214426 -157.621251) (xy 243.222949 -157.568653) (xy 243.239806 -157.518105) (xy 243.264559 -157.470919)
			(xy 243.296567 -157.428318) (xy 243.334998 -157.391409) (xy 243.356638 -157.37586) (xy 243.367927 -157.367502)
			(xy 243.385779 -157.345826) (xy 243.397058 -157.320111) (xy 243.400914 -157.292297) (xy 243.397056 -157.264483)
			(xy 243.385775 -157.238768) (xy 243.367922 -157.217094) (xy 243.356638 -157.208728) (xy 243.335036 -157.193131)
			(xy 243.296621 -157.156218) (xy 243.264621 -157.113623) (xy 243.239863 -157.066449) (xy 243.222988 -157.015916)
			(xy 243.214432 -156.963332) (xy 243.21389 -156.936694) (xy 243.2144 -156.910707) (xy 243.22253 -156.859372)
			(xy 243.238591 -156.809942) (xy 243.262187 -156.763632) (xy 243.292737 -156.721584) (xy 243.329488 -156.684833)
			(xy 243.371536 -156.654283) (xy 243.417846 -156.630687) (xy 243.467276 -156.614626) (xy 243.518611 -156.606496)
			(xy 243.570585 -156.606496) (xy 243.62192 -156.614626) (xy 243.67135 -156.630687) (xy 243.71766 -156.654283)
			(xy 243.759708 -156.684833) (xy 243.796459 -156.721584) (xy 243.827009 -156.763632) (xy 243.850605 -156.809942)
			(xy 243.866666 -156.859372) (xy 243.874796 -156.910707) (xy 243.875306 -156.936694) (xy 243.874763 -156.963336)
			(xy 243.866242 -157.015935) (xy 243.849386 -157.066483) (xy 243.824634 -157.113669) (xy 243.792628 -157.156269)
			(xy 243.754198 -157.193179) (xy 243.732558 -157.208728) (xy 243.721281 -157.217101) (xy 243.70343 -157.238774)
			(xy 243.692151 -157.264486) (xy 243.688293 -157.292297) (xy 243.692149 -157.320108) (xy 243.703427 -157.34582)
			(xy 243.721276 -157.367494) (xy 243.732558 -157.37586) (xy 243.754153 -157.391465) (xy 243.792569 -157.428377)
			(xy 243.82457 -157.47097) (xy 243.849329 -157.518142) (xy 243.866205 -157.568673) (xy 243.874763 -157.621257)
			(xy 243.875306 -157.647894) (xy 244.113812 -157.647894) (xy 244.114338 -157.621251) (xy 244.122862 -157.568651)
			(xy 244.13972 -157.518103) (xy 244.164475 -157.470916) (xy 244.196485 -157.428316) (xy 244.234919 -157.391408)
			(xy 244.25656 -157.37586) (xy 244.267847 -157.3675) (xy 244.285695 -157.345824) (xy 244.296971 -157.320109)
			(xy 244.300827 -157.292297) (xy 244.29697 -157.264484) (xy 244.285691 -157.23877) (xy 244.267842 -157.217095)
			(xy 244.25656 -157.208728) (xy 244.234963 -157.193125) (xy 244.196547 -157.156213) (xy 244.164545 -157.11362)
			(xy 244.139786 -157.066447) (xy 244.122911 -157.015915) (xy 244.114354 -156.963332) (xy 244.113812 -156.936694)
			(xy 244.114322 -156.910707) (xy 244.122452 -156.859372) (xy 244.138513 -156.809942) (xy 244.162109 -156.763632)
			(xy 244.192659 -156.721584) (xy 244.22941 -156.684833) (xy 244.271458 -156.654283) (xy 244.317768 -156.630687)
			(xy 244.367198 -156.614626) (xy 244.418533 -156.606496) (xy 244.470507 -156.606496) (xy 244.521842 -156.614626)
			(xy 244.571272 -156.630687) (xy 244.617582 -156.654283) (xy 244.65963 -156.684833) (xy 244.696381 -156.721584)
			(xy 244.726931 -156.763632) (xy 244.750527 -156.809942) (xy 244.766588 -156.859372) (xy 244.774718 -156.910707)
			(xy 244.775228 -156.936694) (xy 244.774719 -156.963338) (xy 244.766195 -157.01594) (xy 244.749335 -157.06649)
			(xy 244.724577 -157.113677) (xy 244.692563 -157.156276) (xy 244.654124 -157.193182) (xy 244.63248 -157.208728)
			(xy 244.621201 -157.2171) (xy 244.603346 -157.238771) (xy 244.592064 -157.264484) (xy 244.588206 -157.292297)
			(xy 244.592063 -157.320109) (xy 244.603343 -157.345823) (xy 244.621196 -157.367495) (xy 244.63248 -157.37586)
			(xy 244.65408 -157.391459) (xy 244.692494 -157.428373) (xy 244.724494 -157.470967) (xy 244.749252 -157.518141)
			(xy 244.766128 -157.568673) (xy 244.774685 -157.621256) (xy 244.775228 -157.647894) (xy 245.013734 -157.647894)
			(xy 245.014251 -157.62125) (xy 245.022775 -157.56865) (xy 245.039635 -157.518101) (xy 245.064392 -157.470914)
			(xy 245.096403 -157.428315) (xy 245.134839 -157.391407) (xy 245.156482 -157.37586) (xy 245.167776 -157.367505)
			(xy 245.185637 -157.345832) (xy 245.196923 -157.320115) (xy 245.200782 -157.292297) (xy 245.196921 -157.264479)
			(xy 245.185634 -157.238763) (xy 245.167771 -157.217091) (xy 245.156482 -157.208728) (xy 245.13489 -157.193118)
			(xy 245.096472 -157.156209) (xy 245.06447 -157.113617) (xy 245.03971 -157.066446) (xy 245.022833 -157.015915)
			(xy 245.014276 -156.963331) (xy 245.013734 -156.936694) (xy 245.014244 -156.910707) (xy 245.022374 -156.859372)
			(xy 245.038435 -156.809942) (xy 245.062031 -156.763632) (xy 245.092581 -156.721584) (xy 245.129332 -156.684833)
			(xy 245.17138 -156.654283) (xy 245.21769 -156.630687) (xy 245.26712 -156.614626) (xy 245.318455 -156.606496)
			(xy 245.370429 -156.606496) (xy 245.421764 -156.614626) (xy 245.471194 -156.630687) (xy 245.517504 -156.654283)
			(xy 245.559552 -156.684833) (xy 245.596303 -156.721584) (xy 245.626853 -156.763632) (xy 245.650449 -156.809942)
			(xy 245.66651 -156.859372) (xy 245.67464 -156.910707) (xy 245.67515 -156.936694) (xy 245.674631 -156.963338)
			(xy 245.666108 -157.015938) (xy 245.649249 -157.066488) (xy 245.624493 -157.113675) (xy 245.592481 -157.156274)
			(xy 245.554045 -157.193181) (xy 245.532402 -157.208728) (xy 245.521121 -157.217099) (xy 245.503263 -157.238769)
			(xy 245.491978 -157.264483) (xy 245.488119 -157.292297) (xy 245.491976 -157.320111) (xy 245.503259 -157.345825)
			(xy 245.521116 -157.367496) (xy 245.532402 -157.37586) (xy 245.553985 -157.391482) (xy 245.592404 -157.428388)
			(xy 245.624408 -157.470977) (xy 245.64917 -157.518146) (xy 245.666048 -157.568676) (xy 245.674607 -157.621257)
			(xy 245.67515 -157.647894) (xy 245.91391 -157.647894) (xy 245.914437 -157.621251) (xy 245.922961 -157.568652)
			(xy 245.939819 -157.518103) (xy 245.964574 -157.470917) (xy 245.996583 -157.428317) (xy 246.035017 -157.391408)
			(xy 246.056658 -157.37586) (xy 246.067946 -157.3675) (xy 246.085793 -157.345824) (xy 246.09707 -157.320109)
			(xy 246.100926 -157.292297) (xy 246.097068 -157.264484) (xy 246.08579 -157.23877) (xy 246.067941 -157.217095)
			(xy 246.056658 -157.208728) (xy 246.035061 -157.193125) (xy 245.996645 -157.156214) (xy 245.964643 -157.11362)
			(xy 245.939884 -157.066447) (xy 245.923009 -157.015915) (xy 245.914452 -156.963332) (xy 245.91391 -156.936694)
			(xy 245.91442 -156.910707) (xy 245.92255 -156.859372) (xy 245.938611 -156.809942) (xy 245.962207 -156.763632)
			(xy 245.992757 -156.721584) (xy 246.029508 -156.684833) (xy 246.071556 -156.654283) (xy 246.117866 -156.630687)
			(xy 246.167296 -156.614626) (xy 246.218631 -156.606496) (xy 246.270605 -156.606496) (xy 246.32194 -156.614626)
			(xy 246.37137 -156.630687) (xy 246.41768 -156.654283) (xy 246.459728 -156.684833) (xy 246.496479 -156.721584)
			(xy 246.527029 -156.763632) (xy 246.550625 -156.809942) (xy 246.566686 -156.859372) (xy 246.574816 -156.910707)
			(xy 246.575326 -156.936694) (xy 246.574817 -156.963338) (xy 246.566294 -157.01594) (xy 246.549434 -157.06649)
			(xy 246.524675 -157.113677) (xy 246.492661 -157.156276) (xy 246.454222 -157.193182) (xy 246.432578 -157.208728)
			(xy 246.421299 -157.2171) (xy 246.403445 -157.238772) (xy 246.392163 -157.264484) (xy 246.388305 -157.292297)
			(xy 246.392161 -157.320109) (xy 246.403441 -157.345823) (xy 246.421294 -157.367495) (xy 246.432578 -157.37586)
			(xy 246.454178 -157.391459) (xy 246.492592 -157.428373) (xy 246.524592 -157.470967) (xy 246.54935 -157.518141)
			(xy 246.566226 -157.568673) (xy 246.574783 -157.621256) (xy 246.575285 -157.645862) (xy 247.52935 -157.645862)
			(xy 247.529776 -157.619546) (xy 247.537017 -157.567416) (xy 247.551343 -157.516771) (xy 247.572483 -157.468572)
			(xy 247.600038 -157.42373) (xy 247.633484 -157.383093) (xy 247.65254 -157.364938) (xy 247.659918 -157.357396)
			(xy 247.668458 -157.338132) (xy 247.66905 -157.3276) (xy 247.66905 -157.252924) (xy 247.668507 -157.242376)
			(xy 247.65998 -157.223082) (xy 247.65254 -157.215586) (xy 247.633473 -157.197442) (xy 247.600019 -157.156808)
			(xy 247.572463 -157.111965) (xy 247.551327 -157.063763) (xy 247.537012 -157.013114) (xy 247.529788 -156.960979)
			(xy 247.52935 -156.934662) (xy 247.529836 -156.907411) (xy 247.537592 -156.853463) (xy 247.552947 -156.801168)
			(xy 247.575589 -156.751591) (xy 247.605055 -156.705741) (xy 247.640746 -156.66455) (xy 247.681937 -156.628859)
			(xy 247.727787 -156.599393) (xy 247.777364 -156.576751) (xy 247.829659 -156.561396) (xy 247.883607 -156.55364)
			(xy 247.938109 -156.55364) (xy 247.992057 -156.561396) (xy 248.044352 -156.576751) (xy 248.093929 -156.599393)
			(xy 248.139779 -156.628859) (xy 248.158524 -156.645101) (xy 249.513918 -156.645101) (xy 249.518234 -156.587828)
			(xy 249.531084 -156.531849) (xy 249.552177 -156.478427) (xy 249.581038 -156.428769) (xy 249.617015 -156.383997)
			(xy 249.637804 -156.364178) (xy 249.645218 -156.356667) (xy 249.653735 -156.337379) (xy 249.654314 -156.32684)
			(xy 249.654314 -156.252164) (xy 249.65376 -156.241617) (xy 249.645242 -156.222322) (xy 249.637804 -156.214826)
			(xy 249.618769 -156.19665) (xy 249.58531 -156.156025) (xy 249.557748 -156.111189) (xy 249.536606 -156.062992)
			(xy 249.522284 -156.012348) (xy 249.515055 -155.960217) (xy 249.514614 -155.933902) (xy 249.5151 -155.906651)
			(xy 249.522856 -155.852703) (xy 249.538211 -155.800408) (xy 249.560853 -155.750831) (xy 249.590319 -155.704981)
			(xy 249.62601 -155.66379) (xy 249.667201 -155.628099) (xy 249.713051 -155.598633) (xy 249.762628 -155.575991)
			(xy 249.814923 -155.560636) (xy 249.868871 -155.55288) (xy 249.923373 -155.55288) (xy 249.977321 -155.560636)
			(xy 250.029616 -155.575991) (xy 250.079193 -155.598633) (xy 250.125043 -155.628099) (xy 250.166234 -155.66379)
			(xy 250.201925 -155.704981) (xy 250.231391 -155.750831) (xy 250.254033 -155.800408) (xy 250.269388 -155.852703)
			(xy 250.277144 -155.906651) (xy 250.27763 -155.933902) (xy 250.277154 -155.960216) (xy 250.26992 -156.012343)
			(xy 250.255602 -156.062986) (xy 250.234471 -156.111184) (xy 250.206927 -156.156028) (xy 250.17349 -156.196669)
			(xy 250.15444 -156.214826) (xy 250.147031 -156.222341) (xy 250.13851 -156.241626) (xy 250.13793 -156.252164)
			(xy 250.13793 -156.32684) (xy 250.138469 -156.337389) (xy 250.146996 -156.356685) (xy 250.15444 -156.364178)
			(xy 250.175229 -156.383997) (xy 250.211202 -156.42877) (xy 250.24006 -156.478428) (xy 250.261151 -156.53185)
			(xy 250.273999 -156.587829) (xy 250.278314 -156.645101) (xy 250.273999 -156.702374) (xy 250.272863 -156.707322)
			(xy 252.579727 -156.707322) (xy 252.584039 -156.650052) (xy 252.596884 -156.594076) (xy 252.617973 -156.540656)
			(xy 252.646828 -156.491) (xy 252.682798 -156.446228) (xy 252.703584 -156.426408) (xy 252.710982 -156.418883)
			(xy 252.719509 -156.399606) (xy 252.720094 -156.38907) (xy 252.720094 -156.314394) (xy 252.719584 -156.303842)
			(xy 252.711036 -156.284547) (xy 252.703584 -156.277056) (xy 252.684511 -156.258918) (xy 252.651056 -156.218284)
			(xy 252.6235 -156.17344) (xy 252.602364 -156.125236) (xy 252.588051 -156.074586) (xy 252.58083 -156.022449)
			(xy 252.580394 -155.996132) (xy 252.58088 -155.968881) (xy 252.588636 -155.914933) (xy 252.603991 -155.862638)
			(xy 252.626633 -155.813061) (xy 252.656099 -155.767211) (xy 252.69179 -155.72602) (xy 252.732981 -155.690329)
			(xy 252.778831 -155.660863) (xy 252.828408 -155.638221) (xy 252.880703 -155.622866) (xy 252.934651 -155.61511)
			(xy 252.989153 -155.61511) (xy 253.043101 -155.622866) (xy 253.095396 -155.638221) (xy 253.144973 -155.660863)
			(xy 253.190823 -155.690329) (xy 253.232014 -155.72602) (xy 253.267705 -155.767211) (xy 253.297171 -155.813061)
			(xy 253.319813 -155.862638) (xy 253.335168 -155.914933) (xy 253.342924 -155.968881) (xy 253.34341 -155.996132)
			(xy 253.342961 -156.022447) (xy 253.335722 -156.074576) (xy 253.321399 -156.125219) (xy 253.300263 -156.173417)
			(xy 253.272714 -156.218261) (xy 253.239273 -156.2589) (xy 253.22022 -156.277056) (xy 253.212839 -156.284595)
			(xy 253.204302 -156.303862) (xy 253.20371 -156.314394) (xy 253.20371 -156.38907) (xy 253.204239 -156.39962)
			(xy 253.212774 -156.418915) (xy 253.22022 -156.426408) (xy 253.24104 -156.446196) (xy 253.277014 -156.490973)
			(xy 253.305873 -156.540636) (xy 253.326964 -156.594062) (xy 253.33981 -156.650045) (xy 253.344123 -156.707322)
			(xy 253.339804 -156.764598) (xy 253.326951 -156.82058) (xy 253.305854 -156.874003) (xy 253.27699 -156.923663)
			(xy 253.24101 -156.968436) (xy 253.22022 -156.988256) (xy 253.212839 -156.995795) (xy 253.204302 -157.015062)
			(xy 253.20371 -157.025594) (xy 253.20371 -157.10027) (xy 253.204239 -157.11082) (xy 253.212774 -157.130115)
			(xy 253.22022 -157.137608) (xy 253.239276 -157.155763) (xy 253.272733 -157.196393) (xy 253.300291 -157.241234)
			(xy 253.321429 -157.289435) (xy 253.335746 -157.340082) (xy 253.342971 -157.392216) (xy 253.34341 -157.418532)
			(xy 253.342924 -157.445783) (xy 253.335168 -157.499731) (xy 253.319813 -157.552026) (xy 253.297171 -157.601603)
			(xy 253.267705 -157.647453) (xy 253.232014 -157.688644) (xy 253.190823 -157.724335) (xy 253.144973 -157.753801)
			(xy 253.095396 -157.776443) (xy 253.043101 -157.791798) (xy 252.989153 -157.799554) (xy 252.934651 -157.799554)
			(xy 252.880703 -157.791798) (xy 252.828408 -157.776443) (xy 252.778831 -157.753801) (xy 252.732981 -157.724335)
			(xy 252.69179 -157.688644) (xy 252.656099 -157.647453) (xy 252.626633 -157.601603) (xy 252.603991 -157.552026)
			(xy 252.588636 -157.499731) (xy 252.58088 -157.445783) (xy 252.580394 -157.418532) (xy 252.580818 -157.392217)
			(xy 252.588062 -157.340086) (xy 252.60239 -157.289443) (xy 252.62353 -157.241244) (xy 252.651084 -157.196402)
			(xy 252.684529 -157.155764) (xy 252.703584 -157.137608) (xy 252.710982 -157.130083) (xy 252.719509 -157.110806)
			(xy 252.720094 -157.10027) (xy 252.720094 -157.025594) (xy 252.719584 -157.015042) (xy 252.711036 -156.995747)
			(xy 252.703584 -156.988256) (xy 252.682828 -156.968404) (xy 252.646852 -156.923636) (xy 252.617991 -156.873983)
			(xy 252.596897 -156.820566) (xy 252.584045 -156.764591) (xy 252.579727 -156.707322) (xy 250.272863 -156.707322)
			(xy 250.26115 -156.758353) (xy 250.240059 -156.811774) (xy 250.2112 -156.861432) (xy 250.175227 -156.906205)
			(xy 250.15444 -156.926026) (xy 250.147031 -156.933541) (xy 250.13851 -156.952826) (xy 250.13793 -156.963364)
			(xy 250.13793 -157.03804) (xy 250.138469 -157.048589) (xy 250.146996 -157.067885) (xy 250.15444 -157.075378)
			(xy 250.173486 -157.093543) (xy 250.206942 -157.134172) (xy 250.234501 -157.17901) (xy 250.255641 -157.227209)
			(xy 250.269961 -157.277854) (xy 250.277189 -157.329987) (xy 250.27763 -157.356302) (xy 250.277144 -157.383553)
			(xy 250.269388 -157.437501) (xy 250.254033 -157.489796) (xy 250.231391 -157.539373) (xy 250.201925 -157.585223)
			(xy 250.166234 -157.626414) (xy 250.125043 -157.662105) (xy 250.079193 -157.691571) (xy 250.029616 -157.714213)
			(xy 249.977321 -157.729568) (xy 249.923373 -157.737324) (xy 249.868871 -157.737324) (xy 249.814923 -157.729568)
			(xy 249.762628 -157.714213) (xy 249.713051 -157.691571) (xy 249.667201 -157.662105) (xy 249.62601 -157.626414)
			(xy 249.590319 -157.585223) (xy 249.560853 -157.539373) (xy 249.538211 -157.489796) (xy 249.522856 -157.437501)
			(xy 249.5151 -157.383553) (xy 249.514614 -157.356302) (xy 249.515078 -157.329988) (xy 249.522313 -157.277859)
			(xy 249.536633 -157.227216) (xy 249.557766 -157.179017) (xy 249.585312 -157.134174) (xy 249.618752 -157.093534)
			(xy 249.637804 -157.075378) (xy 249.645218 -157.067867) (xy 249.653735 -157.048579) (xy 249.654314 -157.03804)
			(xy 249.654314 -156.963364) (xy 249.65376 -156.952817) (xy 249.645242 -156.933522) (xy 249.637804 -156.926026)
			(xy 249.617017 -156.906205) (xy 249.58104 -156.861433) (xy 249.552178 -156.811776) (xy 249.531084 -156.758354)
			(xy 249.518234 -156.702374) (xy 249.513918 -156.645101) (xy 248.158524 -156.645101) (xy 248.18097 -156.66455)
			(xy 248.216661 -156.705741) (xy 248.246127 -156.751591) (xy 248.268769 -156.801168) (xy 248.284124 -156.853463)
			(xy 248.29188 -156.907411) (xy 248.292366 -156.934662) (xy 248.291951 -156.960978) (xy 248.284707 -157.013109)
			(xy 248.270378 -157.063753) (xy 248.249236 -157.111952) (xy 248.22168 -157.156794) (xy 248.188232 -157.197431)
			(xy 248.169176 -157.215586) (xy 248.16179 -157.223121) (xy 248.153254 -157.24239) (xy 248.152666 -157.252924)
			(xy 248.152666 -157.3276) (xy 248.153192 -157.33815) (xy 248.16173 -157.357444) (xy 248.169176 -157.364938)
			(xy 248.188238 -157.383087) (xy 248.221696 -157.423717) (xy 248.249255 -157.468559) (xy 248.270392 -157.516761)
			(xy 248.284707 -157.56741) (xy 248.291929 -157.619545) (xy 248.292366 -157.645862) (xy 248.29188 -157.673113)
			(xy 248.284124 -157.727061) (xy 248.268769 -157.779356) (xy 248.246127 -157.828933) (xy 248.216661 -157.874783)
			(xy 248.18097 -157.915974) (xy 248.139779 -157.951665) (xy 248.093929 -157.981131) (xy 248.044352 -158.003773)
			(xy 247.992057 -158.019128) (xy 247.938109 -158.026884) (xy 247.883607 -158.026884) (xy 247.829659 -158.019128)
			(xy 247.777364 -158.003773) (xy 247.727787 -157.981131) (xy 247.681937 -157.951665) (xy 247.640746 -157.915974)
			(xy 247.605055 -157.874783) (xy 247.575589 -157.828933) (xy 247.552947 -157.779356) (xy 247.537592 -157.727061)
			(xy 247.529836 -157.673113) (xy 247.52935 -157.645862) (xy 246.575285 -157.645862) (xy 246.575326 -157.647894)
			(xy 246.574816 -157.673881) (xy 246.566686 -157.725216) (xy 246.550625 -157.774646) (xy 246.527029 -157.820956)
			(xy 246.496479 -157.863004) (xy 246.459728 -157.899755) (xy 246.41768 -157.930305) (xy 246.37137 -157.953901)
			(xy 246.32194 -157.969962) (xy 246.270605 -157.978092) (xy 246.218631 -157.978092) (xy 246.167296 -157.969962)
			(xy 246.117866 -157.953901) (xy 246.071556 -157.930305) (xy 246.029508 -157.899755) (xy 245.992757 -157.863004)
			(xy 245.962207 -157.820956) (xy 245.938611 -157.774646) (xy 245.92255 -157.725216) (xy 245.91442 -157.673881)
			(xy 245.91391 -157.647894) (xy 245.67515 -157.647894) (xy 245.67464 -157.673881) (xy 245.66651 -157.725216)
			(xy 245.650449 -157.774646) (xy 245.626853 -157.820956) (xy 245.596303 -157.863004) (xy 245.559552 -157.899755)
			(xy 245.517504 -157.930305) (xy 245.471194 -157.953901) (xy 245.421764 -157.969962) (xy 245.370429 -157.978092)
			(xy 245.318455 -157.978092) (xy 245.26712 -157.969962) (xy 245.21769 -157.953901) (xy 245.17138 -157.930305)
			(xy 245.129332 -157.899755) (xy 245.092581 -157.863004) (xy 245.062031 -157.820956) (xy 245.038435 -157.774646)
			(xy 245.022374 -157.725216) (xy 245.014244 -157.673881) (xy 245.013734 -157.647894) (xy 244.775228 -157.647894)
			(xy 244.774718 -157.673881) (xy 244.766588 -157.725216) (xy 244.750527 -157.774646) (xy 244.726931 -157.820956)
			(xy 244.696381 -157.863004) (xy 244.65963 -157.899755) (xy 244.617582 -157.930305) (xy 244.571272 -157.953901)
			(xy 244.521842 -157.969962) (xy 244.470507 -157.978092) (xy 244.418533 -157.978092) (xy 244.367198 -157.969962)
			(xy 244.317768 -157.953901) (xy 244.271458 -157.930305) (xy 244.22941 -157.899755) (xy 244.192659 -157.863004)
			(xy 244.162109 -157.820956) (xy 244.138513 -157.774646) (xy 244.122452 -157.725216) (xy 244.114322 -157.673881)
			(xy 244.113812 -157.647894) (xy 243.875306 -157.647894) (xy 243.874796 -157.673881) (xy 243.866666 -157.725216)
			(xy 243.850605 -157.774646) (xy 243.827009 -157.820956) (xy 243.796459 -157.863004) (xy 243.759708 -157.899755)
			(xy 243.71766 -157.930305) (xy 243.67135 -157.953901) (xy 243.62192 -157.969962) (xy 243.570585 -157.978092)
			(xy 243.518611 -157.978092) (xy 243.467276 -157.969962) (xy 243.417846 -157.953901) (xy 243.371536 -157.930305)
			(xy 243.329488 -157.899755) (xy 243.292737 -157.863004) (xy 243.262187 -157.820956) (xy 243.238591 -157.774646)
			(xy 243.22253 -157.725216) (xy 243.2144 -157.673881) (xy 243.21389 -157.647894) (xy 239.575575 -157.647894)
			(xy 239.588997 -157.676525) (xy 239.605065 -157.729932) (xy 239.613185 -157.785108) (xy 239.613694 -157.812994)
			(xy 239.613185 -157.84088) (xy 239.605065 -157.896056) (xy 239.588997 -157.949463) (xy 239.565325 -157.99996)
			(xy 239.534552 -158.046473) (xy 239.522082 -158.06039) (xy 241.039648 -158.06039) (xy 241.043719 -158.004768)
			(xy 241.055845 -157.950331) (xy 241.075768 -157.89824) (xy 241.103064 -157.849605) (xy 241.13715 -157.805462)
			(xy 241.177299 -157.766753) (xy 241.222657 -157.734302) (xy 241.272257 -157.708801) (xy 241.325041 -157.690794)
			(xy 241.379884 -157.680664) (xy 241.435618 -157.678627) (xy 241.491055 -157.684727) (xy 241.545012 -157.698833)
			(xy 241.596341 -157.720645) (xy 241.643947 -157.749699) (xy 241.686815 -157.785374) (xy 241.724032 -157.826911)
			(xy 241.754805 -157.873424) (xy 241.778477 -157.923921) (xy 241.794545 -157.977328) (xy 241.802665 -158.032504)
			(xy 241.803174 -158.06039) (xy 241.802665 -158.088276) (xy 241.794545 -158.143452) (xy 241.778477 -158.196859)
			(xy 241.754805 -158.247356) (xy 241.724032 -158.293869) (xy 241.686815 -158.335406) (xy 241.643947 -158.371081)
			(xy 241.596341 -158.400135) (xy 241.545012 -158.421947) (xy 241.491055 -158.436053) (xy 241.435618 -158.442153)
			(xy 241.379884 -158.440116) (xy 241.325041 -158.429986) (xy 241.272257 -158.411979) (xy 241.222657 -158.386478)
			(xy 241.177299 -158.354027) (xy 241.13715 -158.315318) (xy 241.103064 -158.271175) (xy 241.075768 -158.22254)
			(xy 241.055845 -158.170449) (xy 241.043719 -158.116012) (xy 241.039648 -158.06039) (xy 239.522082 -158.06039)
			(xy 239.497335 -158.08801) (xy 239.454467 -158.123685) (xy 239.406861 -158.152739) (xy 239.355532 -158.174551)
			(xy 239.301575 -158.188657) (xy 239.246138 -158.194757) (xy 239.190404 -158.19272) (xy 239.135561 -158.18259)
			(xy 239.082777 -158.164583) (xy 239.033177 -158.139082) (xy 238.987819 -158.106631) (xy 238.94767 -158.067922)
			(xy 238.913584 -158.023779) (xy 238.886288 -157.975144) (xy 238.866365 -157.923053) (xy 238.854239 -157.868616)
			(xy 238.850168 -157.812994) (xy 232.329523 -157.812994) (xy 232.335782 -157.860536) (xy 232.335782 -157.920464)
			(xy 232.32796 -157.979879) (xy 232.31245 -158.037765) (xy 232.289518 -158.093132) (xy 232.259555 -158.145032)
			(xy 232.223075 -158.192577) (xy 232.180701 -158.234954) (xy 232.133158 -158.271437) (xy 232.081261 -158.301404)
			(xy 232.025896 -158.32434) (xy 231.968011 -158.339854) (xy 231.908596 -158.34768) (xy 231.878632 -158.348172)
			(xy 231.015032 -158.348172) (xy 230.985059 -158.347777) (xy 230.925626 -158.339956) (xy 230.867722 -158.324445)
			(xy 230.812339 -158.301507) (xy 230.760423 -158.271537) (xy 230.712864 -158.235047) (xy 230.670475 -158.19266)
			(xy 230.633981 -158.145103) (xy 230.604007 -158.09319) (xy 230.581066 -158.037808) (xy 230.56555 -157.979905)
			(xy 230.557725 -157.920473) (xy 230.089876 -157.920473) (xy 230.084738 -157.959498) (xy 230.069224 -158.017397)
			(xy 230.046286 -158.072775) (xy 230.016316 -158.124685) (xy 229.979827 -158.172239) (xy 229.937442 -158.214624)
			(xy 229.889888 -158.251114) (xy 229.837978 -158.281084) (xy 229.7826 -158.304023) (xy 229.724702 -158.319537)
			(xy 229.665274 -158.327362) (xy 229.635304 -158.327852) (xy 228.771704 -158.327852) (xy 228.741738 -158.327295)
			(xy 228.682318 -158.319473) (xy 228.624427 -158.303962) (xy 228.569056 -158.281027) (xy 228.517153 -158.251061)
			(xy 228.469605 -158.214576) (xy 228.427226 -158.172198) (xy 228.390741 -158.12465) (xy 228.360775 -158.072747)
			(xy 228.33784 -158.017377) (xy 228.322328 -157.959486) (xy 228.314505 -157.900066) (xy 217.26906 -157.900066)
			(xy 217.26906 -158.828994) (xy 238.850168 -158.828994) (xy 238.854239 -158.773372) (xy 238.866365 -158.718935)
			(xy 238.886288 -158.666844) (xy 238.913584 -158.618209) (xy 238.94767 -158.574066) (xy 238.987819 -158.535357)
			(xy 239.033177 -158.502906) (xy 239.082777 -158.477405) (xy 239.135561 -158.459398) (xy 239.190404 -158.449268)
			(xy 239.246138 -158.447231) (xy 239.301575 -158.453331) (xy 239.355532 -158.467437) (xy 239.406861 -158.489249)
			(xy 239.454467 -158.518303) (xy 239.497335 -158.553978) (xy 239.534552 -158.595515) (xy 239.565325 -158.642028)
			(xy 239.588997 -158.692525) (xy 239.605065 -158.745932) (xy 239.60615 -158.753302) (xy 248.716544 -158.753302)
			(xy 248.720615 -158.69768) (xy 248.732741 -158.643243) (xy 248.752664 -158.591152) (xy 248.77996 -158.542517)
			(xy 248.814046 -158.498374) (xy 248.854195 -158.459665) (xy 248.899553 -158.427214) (xy 248.949153 -158.401713)
			(xy 249.001937 -158.383706) (xy 249.05678 -158.373576) (xy 249.112514 -158.371539) (xy 249.167951 -158.377639)
			(xy 249.221908 -158.391745) (xy 249.273237 -158.413557) (xy 249.320843 -158.442611) (xy 249.363711 -158.478286)
			(xy 249.400928 -158.519823) (xy 249.431701 -158.566336) (xy 249.455373 -158.616833) (xy 249.471441 -158.67024)
			(xy 249.479561 -158.725416) (xy 249.48007 -158.753302) (xy 249.479561 -158.781188) (xy 249.471441 -158.836364)
			(xy 249.455373 -158.889771) (xy 249.431701 -158.940268) (xy 249.400928 -158.986781) (xy 249.363711 -159.028318)
			(xy 249.320843 -159.063993) (xy 249.273237 -159.093047) (xy 249.221908 -159.114859) (xy 249.167951 -159.128965)
			(xy 249.112514 -159.135065) (xy 249.05678 -159.133028) (xy 249.001937 -159.122898) (xy 248.949153 -159.104891)
			(xy 248.899553 -159.07939) (xy 248.854195 -159.046939) (xy 248.814046 -159.00823) (xy 248.77996 -158.964087)
			(xy 248.752664 -158.915452) (xy 248.732741 -158.863361) (xy 248.720615 -158.808924) (xy 248.716544 -158.753302)
			(xy 239.60615 -158.753302) (xy 239.613185 -158.801108) (xy 239.613694 -158.828994) (xy 239.613185 -158.85688)
			(xy 239.605065 -158.912056) (xy 239.588997 -158.965463) (xy 239.565325 -159.01596) (xy 239.534552 -159.062473)
			(xy 239.497335 -159.10401) (xy 239.454467 -159.139685) (xy 239.406861 -159.168739) (xy 239.355532 -159.190551)
			(xy 239.301575 -159.204657) (xy 239.246138 -159.210757) (xy 239.190404 -159.20872) (xy 239.135561 -159.19859)
			(xy 239.082777 -159.180583) (xy 239.033177 -159.155082) (xy 238.987819 -159.122631) (xy 238.94767 -159.083922)
			(xy 238.913584 -159.039779) (xy 238.886288 -158.991144) (xy 238.866365 -158.939053) (xy 238.854239 -158.884616)
			(xy 238.850168 -158.828994) (xy 217.26906 -158.828994) (xy 217.26906 -159.386524) (xy 217.269314 -159.389572)
			(xy 217.270621 -159.401084) (xy 217.272019 -159.424214) (xy 217.272108 -159.4358) (xy 217.272086 -159.439102)
			(xy 241.107974 -159.439102) (xy 241.112045 -159.38348) (xy 241.124171 -159.329043) (xy 241.144094 -159.276952)
			(xy 241.17139 -159.228317) (xy 241.205476 -159.184174) (xy 241.245625 -159.145465) (xy 241.290983 -159.113014)
			(xy 241.340583 -159.087513) (xy 241.393367 -159.069506) (xy 241.44821 -159.059376) (xy 241.503944 -159.057339)
			(xy 241.559381 -159.063439) (xy 241.613338 -159.077545) (xy 241.664667 -159.099357) (xy 241.712273 -159.128411)
			(xy 241.755141 -159.164086) (xy 241.792358 -159.205623) (xy 241.823131 -159.252136) (xy 241.846803 -159.302633)
			(xy 241.862871 -159.35604) (xy 241.870991 -159.411216) (xy 241.8715 -159.439102) (xy 241.870991 -159.466988)
			(xy 241.862871 -159.522164) (xy 241.859968 -159.531812) (xy 244.312692 -159.531812) (xy 244.316763 -159.47619)
			(xy 244.328889 -159.421753) (xy 244.348812 -159.369662) (xy 244.376108 -159.321027) (xy 244.410194 -159.276884)
			(xy 244.450343 -159.238175) (xy 244.495701 -159.205724) (xy 244.545301 -159.180223) (xy 244.598085 -159.162216)
			(xy 244.652928 -159.152086) (xy 244.708662 -159.150049) (xy 244.764099 -159.156149) (xy 244.818056 -159.170255)
			(xy 244.869385 -159.192067) (xy 244.916991 -159.221121) (xy 244.959859 -159.256796) (xy 244.997076 -159.298333)
			(xy 245.027849 -159.344846) (xy 245.051521 -159.395343) (xy 245.067589 -159.44875) (xy 245.073458 -159.488632)
			(xy 246.595898 -159.488632) (xy 246.599969 -159.43301) (xy 246.612095 -159.378573) (xy 246.632018 -159.326482)
			(xy 246.659314 -159.277847) (xy 246.6934 -159.233704) (xy 246.733549 -159.194995) (xy 246.778907 -159.162544)
			(xy 246.828507 -159.137043) (xy 246.881291 -159.119036) (xy 246.936134 -159.108906) (xy 246.991868 -159.106869)
			(xy 247.047305 -159.112969) (xy 247.101262 -159.127075) (xy 247.152591 -159.148887) (xy 247.200197 -159.177941)
			(xy 247.243065 -159.213616) (xy 247.280282 -159.255153) (xy 247.311055 -159.301666) (xy 247.334727 -159.352163)
			(xy 247.350795 -159.40557) (xy 247.358915 -159.460746) (xy 247.359424 -159.488632) (xy 247.358915 -159.516518)
			(xy 247.350795 -159.571694) (xy 247.334727 -159.625101) (xy 247.311055 -159.675598) (xy 247.280282 -159.722111)
			(xy 247.243065 -159.763648) (xy 247.200197 -159.799323) (xy 247.152591 -159.828377) (xy 247.101262 -159.850189)
			(xy 247.047305 -159.864295) (xy 246.991868 -159.870395) (xy 246.936134 -159.868358) (xy 246.881291 -159.858228)
			(xy 246.828507 -159.840221) (xy 246.778907 -159.81472) (xy 246.733549 -159.782269) (xy 246.6934 -159.74356)
			(xy 246.659314 -159.699417) (xy 246.632018 -159.650782) (xy 246.612095 -159.598691) (xy 246.599969 -159.544254)
			(xy 246.595898 -159.488632) (xy 245.073458 -159.488632) (xy 245.075709 -159.503926) (xy 245.076218 -159.531812)
			(xy 245.075709 -159.559698) (xy 245.067589 -159.614874) (xy 245.051521 -159.668281) (xy 245.027849 -159.718778)
			(xy 244.997076 -159.765291) (xy 244.959859 -159.806828) (xy 244.916991 -159.842503) (xy 244.869385 -159.871557)
			(xy 244.818056 -159.893369) (xy 244.764099 -159.907475) (xy 244.708662 -159.913575) (xy 244.652928 -159.911538)
			(xy 244.598085 -159.901408) (xy 244.545301 -159.883401) (xy 244.495701 -159.8579) (xy 244.450343 -159.825449)
			(xy 244.410194 -159.78674) (xy 244.376108 -159.742597) (xy 244.348812 -159.693962) (xy 244.328889 -159.641871)
			(xy 244.316763 -159.587434) (xy 244.312692 -159.531812) (xy 241.859968 -159.531812) (xy 241.846803 -159.575571)
			(xy 241.823131 -159.626068) (xy 241.792358 -159.672581) (xy 241.755141 -159.714118) (xy 241.712273 -159.749793)
			(xy 241.664667 -159.778847) (xy 241.613338 -159.800659) (xy 241.559381 -159.814765) (xy 241.503944 -159.820865)
			(xy 241.44821 -159.818828) (xy 241.393367 -159.808698) (xy 241.340583 -159.790691) (xy 241.290983 -159.76519)
			(xy 241.245625 -159.732739) (xy 241.205476 -159.69403) (xy 241.17139 -159.649887) (xy 241.144094 -159.601252)
			(xy 241.124171 -159.549161) (xy 241.112045 -159.494724) (xy 241.107974 -159.439102) (xy 217.272086 -159.439102)
			(xy 217.272032 -159.447386) (xy 217.270636 -159.470517) (xy 217.269314 -159.482028) (xy 217.26906 -159.485076)
			(xy 217.26906 -159.966914) (xy 217.269006 -159.971051) (xy 232.232178 -159.971051) (xy 232.232178 -159.916549)
			(xy 232.239934 -159.862601) (xy 232.255289 -159.810306) (xy 232.277931 -159.760729) (xy 232.307397 -159.714879)
			(xy 232.343088 -159.673688) (xy 232.384279 -159.637997) (xy 232.430129 -159.608531) (xy 232.479706 -159.585889)
			(xy 232.532001 -159.570534) (xy 232.585949 -159.562778) (xy 232.6132 -159.562292) (xy 232.64057 -159.56276)
			(xy 232.694749 -159.570578) (xy 232.747252 -159.586066) (xy 232.796999 -159.608908) (xy 232.842966 -159.638631)
			(xy 232.863898 -159.656272) (xy 232.864152 -159.656526) (xy 232.871246 -159.662102) (xy 232.888157 -159.668354)
			(xy 232.897172 -159.668718) (xy 232.964228 -159.668718) (xy 232.973246 -159.668371) (xy 232.990163 -159.662116)
			(xy 232.997248 -159.656526) (xy 232.997248 -159.656272) (xy 232.997502 -159.656272) (xy 233.018419 -159.638614)
			(xy 233.064396 -159.608906) (xy 233.114148 -159.586074) (xy 233.166652 -159.570587) (xy 233.22083 -159.562764)
			(xy 233.2482 -159.562292) (xy 233.275451 -159.562778) (xy 233.329399 -159.570534) (xy 233.381694 -159.585889)
			(xy 233.431271 -159.608531) (xy 233.477121 -159.637997) (xy 233.518312 -159.673688) (xy 233.554003 -159.714879)
			(xy 233.583469 -159.760729) (xy 233.606111 -159.810306) (xy 233.616296 -159.844994) (xy 238.850168 -159.844994)
			(xy 238.854239 -159.789372) (xy 238.866365 -159.734935) (xy 238.886288 -159.682844) (xy 238.913584 -159.634209)
			(xy 238.94767 -159.590066) (xy 238.987819 -159.551357) (xy 239.033177 -159.518906) (xy 239.082777 -159.493405)
			(xy 239.135561 -159.475398) (xy 239.190404 -159.465268) (xy 239.246138 -159.463231) (xy 239.301575 -159.469331)
			(xy 239.355532 -159.483437) (xy 239.406861 -159.505249) (xy 239.454467 -159.534303) (xy 239.497335 -159.569978)
			(xy 239.534552 -159.611515) (xy 239.565325 -159.658028) (xy 239.588997 -159.708525) (xy 239.605065 -159.761932)
			(xy 239.613185 -159.817108) (xy 239.613694 -159.844994) (xy 239.613185 -159.87288) (xy 239.605065 -159.928056)
			(xy 239.588997 -159.981463) (xy 239.565325 -160.03196) (xy 239.534552 -160.078473) (xy 239.497335 -160.12001)
			(xy 239.454467 -160.155685) (xy 239.406861 -160.184739) (xy 239.355532 -160.206551) (xy 239.301575 -160.220657)
			(xy 239.246138 -160.226757) (xy 239.190404 -160.22472) (xy 239.135561 -160.21459) (xy 239.082777 -160.196583)
			(xy 239.033177 -160.171082) (xy 238.987819 -160.138631) (xy 238.94767 -160.099922) (xy 238.913584 -160.055779)
			(xy 238.886288 -160.007144) (xy 238.866365 -159.955053) (xy 238.854239 -159.900616) (xy 238.850168 -159.844994)
			(xy 233.616296 -159.844994) (xy 233.621466 -159.862601) (xy 233.629222 -159.916549) (xy 233.629222 -159.971051)
			(xy 233.621466 -160.024999) (xy 233.606111 -160.077294) (xy 233.583469 -160.126871) (xy 233.554003 -160.172721)
			(xy 233.518312 -160.213912) (xy 233.477121 -160.249603) (xy 233.431271 -160.279069) (xy 233.381694 -160.301711)
			(xy 233.329399 -160.317066) (xy 233.275451 -160.324822) (xy 233.2482 -160.325308) (xy 233.22083 -160.32484)
			(xy 233.166651 -160.317022) (xy 233.114148 -160.301534) (xy 233.064401 -160.278692) (xy 233.018434 -160.248969)
			(xy 232.997502 -160.231328) (xy 232.997248 -160.231074) (xy 232.990154 -160.225498) (xy 232.973243 -160.219246)
			(xy 232.964228 -160.218882) (xy 232.897172 -160.218882) (xy 232.888154 -160.219229) (xy 232.871237 -160.225484)
			(xy 232.864152 -160.231074) (xy 232.864152 -160.231328) (xy 232.863898 -160.231328) (xy 232.842981 -160.248986)
			(xy 232.797004 -160.278694) (xy 232.747252 -160.301526) (xy 232.694748 -160.317013) (xy 232.64057 -160.324836)
			(xy 232.6132 -160.325308) (xy 232.585949 -160.324822) (xy 232.532001 -160.317066) (xy 232.479706 -160.301711)
			(xy 232.430129 -160.279069) (xy 232.384279 -160.249603) (xy 232.343088 -160.213912) (xy 232.307397 -160.172721)
			(xy 232.277931 -160.126871) (xy 232.255289 -160.077294) (xy 232.239934 -160.024999) (xy 232.232178 -159.971051)
			(xy 217.269006 -159.971051) (xy 217.268806 -159.986472) (xy 217.268814 -159.991138) (xy 217.270358 -160.00034)
			(xy 217.271854 -160.00476) (xy 217.282496 -160.03628) (xy 217.293981 -160.101802) (xy 217.294714 -160.135062)
			(xy 217.294105 -160.165865) (xy 217.284172 -160.226664) (xy 217.264607 -160.285081) (xy 217.250772 -160.312608)
			(xy 217.243709 -160.325773) (xy 217.227817 -160.351076) (xy 217.219022 -160.363154) (xy 217.218514 -160.363662)
			(xy 217.21826 -160.36417) (xy 217.217752 -160.364932) (xy 217.213942 -160.370266) (xy 217.209878 -160.377124)
			(xy 217.204544 -160.3883) (xy 217.20277 -160.392928) (xy 217.200851 -160.402649) (xy 217.200734 -160.407604)
			(xy 217.200734 -160.421066) (xy 217.200393 -160.429195) (xy 217.195212 -160.444608) (xy 217.190574 -160.451292)
			(xy 217.189558 -160.45307) (xy 217.187526 -160.459674) (xy 217.186344 -160.463569) (xy 217.185062 -160.471607)
			(xy 217.184986 -160.475676) (xy 217.18524 -160.484058) (xy 217.187526 -160.490662) (xy 217.188288 -160.49244)
			(xy 217.195908 -160.513776) (xy 217.202258 -160.521142) (xy 217.219613 -160.542006) (xy 217.24886 -160.587719)
			(xy 217.271326 -160.637119) (xy 217.280417 -160.668208) (xy 222.918272 -160.668208) (xy 222.922343 -160.612586)
			(xy 222.934469 -160.558149) (xy 222.954392 -160.506058) (xy 222.981688 -160.457423) (xy 223.015774 -160.41328)
			(xy 223.055923 -160.374571) (xy 223.101281 -160.34212) (xy 223.150881 -160.316619) (xy 223.203665 -160.298612)
			(xy 223.258508 -160.288482) (xy 223.314242 -160.286445) (xy 223.369679 -160.292545) (xy 223.423636 -160.306651)
			(xy 223.474965 -160.328463) (xy 223.522571 -160.357517) (xy 223.565439 -160.393192) (xy 223.602656 -160.434729)
			(xy 223.633429 -160.481242) (xy 223.657101 -160.531739) (xy 223.673169 -160.585146) (xy 223.681289 -160.640322)
			(xy 223.681798 -160.668208) (xy 223.681289 -160.696094) (xy 223.673169 -160.75127) (xy 223.657101 -160.804677)
			(xy 223.633429 -160.855174) (xy 223.602656 -160.901687) (xy 223.565439 -160.943224) (xy 223.523546 -160.978088)
			(xy 233.964986 -160.978088) (xy 233.969057 -160.922466) (xy 233.981183 -160.868029) (xy 234.001106 -160.815938)
			(xy 234.028402 -160.767303) (xy 234.062488 -160.72316) (xy 234.102637 -160.684451) (xy 234.147995 -160.652)
			(xy 234.197595 -160.626499) (xy 234.250379 -160.608492) (xy 234.305222 -160.598362) (xy 234.360956 -160.596325)
			(xy 234.416393 -160.602425) (xy 234.47035 -160.616531) (xy 234.521679 -160.638343) (xy 234.569285 -160.667397)
			(xy 234.598064 -160.691347) (xy 239.187022 -160.691347) (xy 239.187022 -160.636853) (xy 239.194777 -160.582914)
			(xy 239.210129 -160.530627) (xy 239.232766 -160.481058) (xy 239.262226 -160.435214) (xy 239.297911 -160.394029)
			(xy 239.339093 -160.358342) (xy 239.384935 -160.328878) (xy 239.434503 -160.306238) (xy 239.486789 -160.290883)
			(xy 239.540727 -160.283124) (xy 239.567974 -160.282636) (xy 239.594502 -160.283086) (xy 239.647047 -160.290421)
			(xy 239.698069 -160.304967) (xy 239.746583 -160.326443) (xy 239.791653 -160.354435) (xy 239.832409 -160.388402)
			(xy 239.868064 -160.427689) (xy 239.897931 -160.471539) (xy 239.921434 -160.519104) (xy 239.938118 -160.569467)
			(xy 239.947662 -160.621657) (xy 239.949228 -160.648142) (xy 239.950231 -160.662657) (xy 239.959576 -160.690203)
			(xy 239.976316 -160.713991) (xy 239.999091 -160.732086) (xy 240.026047 -160.743015) (xy 240.054993 -160.745891)
			(xy 240.06937 -160.743646) (xy 240.086858 -160.740549) (xy 240.122223 -160.737244) (xy 240.139982 -160.737042)
			(xy 240.140236 -160.737042) (xy 240.167489 -160.73743) (xy 240.22144 -160.745192) (xy 240.273737 -160.760552)
			(xy 240.323316 -160.783198) (xy 240.369168 -160.81267) (xy 240.41036 -160.848366) (xy 240.446052 -160.88956)
			(xy 240.475519 -160.935415) (xy 240.489438 -160.965896) (xy 241.137692 -160.965896) (xy 241.141763 -160.910274)
			(xy 241.153889 -160.855837) (xy 241.173812 -160.803746) (xy 241.201108 -160.755111) (xy 241.235194 -160.710968)
			(xy 241.275343 -160.672259) (xy 241.320701 -160.639808) (xy 241.370301 -160.614307) (xy 241.423085 -160.5963)
			(xy 241.477928 -160.58617) (xy 241.533662 -160.584133) (xy 241.589099 -160.590233) (xy 241.643056 -160.604339)
			(xy 241.694385 -160.626151) (xy 241.741991 -160.655205) (xy 241.784859 -160.69088) (xy 241.822076 -160.732417)
			(xy 241.852849 -160.77893) (xy 241.876521 -160.829427) (xy 241.892589 -160.882834) (xy 241.900709 -160.93801)
			(xy 241.901181 -160.963864) (xy 242.529612 -160.963864) (xy 242.533683 -160.908242) (xy 242.545809 -160.853805)
			(xy 242.565732 -160.801714) (xy 242.593028 -160.753079) (xy 242.627114 -160.708936) (xy 242.667263 -160.670227)
			(xy 242.712621 -160.637776) (xy 242.762221 -160.612275) (xy 242.815005 -160.594268) (xy 242.869848 -160.584138)
			(xy 242.925582 -160.582101) (xy 242.981019 -160.588201) (xy 243.034976 -160.602307) (xy 243.086305 -160.624119)
			(xy 243.133911 -160.653173) (xy 243.176779 -160.688848) (xy 243.213996 -160.730385) (xy 243.244769 -160.776898)
			(xy 243.268441 -160.827395) (xy 243.284509 -160.880802) (xy 243.292629 -160.935978) (xy 243.293138 -160.963864)
			(xy 243.293045 -160.968944) (xy 243.80139 -160.968944) (xy 243.805461 -160.913322) (xy 243.817587 -160.858885)
			(xy 243.83751 -160.806794) (xy 243.864806 -160.758159) (xy 243.898892 -160.714016) (xy 243.939041 -160.675307)
			(xy 243.984399 -160.642856) (xy 244.033999 -160.617355) (xy 244.086783 -160.599348) (xy 244.141626 -160.589218)
			(xy 244.19736 -160.587181) (xy 244.252797 -160.593281) (xy 244.306754 -160.607387) (xy 244.358083 -160.629199)
			(xy 244.405689 -160.658253) (xy 244.448557 -160.693928) (xy 244.485774 -160.735465) (xy 244.516547 -160.781978)
			(xy 244.540219 -160.832475) (xy 244.556287 -160.885882) (xy 244.55868 -160.902142) (xy 245.582692 -160.902142)
			(xy 245.586763 -160.84652) (xy 245.598889 -160.792083) (xy 245.618812 -160.739992) (xy 245.646108 -160.691357)
			(xy 245.680194 -160.647214) (xy 245.720343 -160.608505) (xy 245.765701 -160.576054) (xy 245.815301 -160.550553)
			(xy 245.868085 -160.532546) (xy 245.922928 -160.522416) (xy 245.978662 -160.520379) (xy 246.034099 -160.526479)
			(xy 246.088056 -160.540585) (xy 246.139385 -160.562397) (xy 246.186991 -160.591451) (xy 246.229859 -160.627126)
			(xy 246.267076 -160.668663) (xy 246.297849 -160.715176) (xy 246.321521 -160.765673) (xy 246.337589 -160.81908)
			(xy 246.345709 -160.874256) (xy 246.346218 -160.902142) (xy 246.345709 -160.930028) (xy 246.337589 -160.985204)
			(xy 246.321521 -161.038611) (xy 246.297849 -161.089108) (xy 246.267076 -161.135621) (xy 246.229859 -161.177158)
			(xy 246.186991 -161.212833) (xy 246.139385 -161.241887) (xy 246.088056 -161.263699) (xy 246.034099 -161.277805)
			(xy 245.978662 -161.283905) (xy 245.922928 -161.281868) (xy 245.868085 -161.271738) (xy 245.815301 -161.253731)
			(xy 245.765701 -161.22823) (xy 245.720343 -161.195779) (xy 245.680194 -161.15707) (xy 245.646108 -161.112927)
			(xy 245.618812 -161.064292) (xy 245.598889 -161.012201) (xy 245.586763 -160.957764) (xy 245.582692 -160.902142)
			(xy 244.55868 -160.902142) (xy 244.564407 -160.941058) (xy 244.564916 -160.968944) (xy 244.564407 -160.99683)
			(xy 244.556287 -161.052006) (xy 244.540219 -161.105413) (xy 244.516547 -161.15591) (xy 244.485774 -161.202423)
			(xy 244.448557 -161.24396) (xy 244.405689 -161.279635) (xy 244.358083 -161.308689) (xy 244.306754 -161.330501)
			(xy 244.252797 -161.344607) (xy 244.19736 -161.350707) (xy 244.141626 -161.34867) (xy 244.086783 -161.33854)
			(xy 244.033999 -161.320533) (xy 243.984399 -161.295032) (xy 243.939041 -161.262581) (xy 243.898892 -161.223872)
			(xy 243.864806 -161.179729) (xy 243.83751 -161.131094) (xy 243.817587 -161.079003) (xy 243.805461 -161.024566)
			(xy 243.80139 -160.968944) (xy 243.293045 -160.968944) (xy 243.292629 -160.99175) (xy 243.284509 -161.046926)
			(xy 243.268441 -161.100333) (xy 243.244769 -161.15083) (xy 243.213996 -161.197343) (xy 243.176779 -161.23888)
			(xy 243.133911 -161.274555) (xy 243.086305 -161.303609) (xy 243.034976 -161.325421) (xy 242.981019 -161.339527)
			(xy 242.925582 -161.345627) (xy 242.869848 -161.34359) (xy 242.815005 -161.33346) (xy 242.762221 -161.315453)
			(xy 242.712621 -161.289952) (xy 242.667263 -161.257501) (xy 242.627114 -161.218792) (xy 242.593028 -161.174649)
			(xy 242.565732 -161.126014) (xy 242.545809 -161.073923) (xy 242.533683 -161.019486) (xy 242.529612 -160.963864)
			(xy 241.901181 -160.963864) (xy 241.901218 -160.965896) (xy 241.900709 -160.993782) (xy 241.892589 -161.048958)
			(xy 241.876521 -161.102365) (xy 241.852849 -161.152862) (xy 241.822076 -161.199375) (xy 241.784859 -161.240912)
			(xy 241.741991 -161.276587) (xy 241.694385 -161.305641) (xy 241.643056 -161.327453) (xy 241.589099 -161.341559)
			(xy 241.533662 -161.347659) (xy 241.477928 -161.345622) (xy 241.423085 -161.335492) (xy 241.370301 -161.317485)
			(xy 241.320701 -161.291984) (xy 241.275343 -161.259533) (xy 241.235194 -161.220824) (xy 241.201108 -161.176681)
			(xy 241.173812 -161.128046) (xy 241.153889 -161.075955) (xy 241.141763 -161.021518) (xy 241.137692 -160.965896)
			(xy 240.489438 -160.965896) (xy 240.49816 -160.984996) (xy 240.513516 -161.037295) (xy 240.521272 -161.091247)
			(xy 240.521272 -161.145753) (xy 240.513516 -161.199705) (xy 240.49816 -161.252004) (xy 240.475519 -161.301585)
			(xy 240.446052 -161.34744) (xy 240.41036 -161.388634) (xy 240.369168 -161.42433) (xy 240.323316 -161.453802)
			(xy 240.273737 -161.476448) (xy 240.22144 -161.491808) (xy 240.167489 -161.49957) (xy 240.140236 -161.500058)
			(xy 240.113708 -161.499604) (xy 240.061163 -161.492271) (xy 240.010141 -161.477726) (xy 239.961626 -161.456251)
			(xy 239.916556 -161.428259) (xy 239.8758 -161.394292) (xy 239.840144 -161.355005) (xy 239.810277 -161.311156)
			(xy 239.786775 -161.26359) (xy 239.770091 -161.213227) (xy 239.760548 -161.161037) (xy 239.758982 -161.134552)
			(xy 239.757972 -161.120038) (xy 239.748627 -161.092494) (xy 239.731888 -161.068707) (xy 239.709115 -161.050613)
			(xy 239.68216 -161.039682) (xy 239.653217 -161.036805) (xy 239.63884 -161.039048) (xy 239.621351 -161.042143)
			(xy 239.585987 -161.04545) (xy 239.568228 -161.045652) (xy 239.567974 -161.045652) (xy 239.540727 -161.045076)
			(xy 239.486789 -161.037317) (xy 239.434503 -161.021962) (xy 239.384935 -160.999322) (xy 239.339093 -160.969858)
			(xy 239.297911 -160.934171) (xy 239.262226 -160.892986) (xy 239.232766 -160.847142) (xy 239.210129 -160.797573)
			(xy 239.194777 -160.745286) (xy 239.187022 -160.691347) (xy 234.598064 -160.691347) (xy 234.612153 -160.703072)
			(xy 234.64937 -160.744609) (xy 234.680143 -160.791122) (xy 234.703815 -160.841619) (xy 234.719883 -160.895026)
			(xy 234.728003 -160.950202) (xy 234.728512 -160.978088) (xy 234.728003 -161.005974) (xy 234.719883 -161.06115)
			(xy 234.703815 -161.114557) (xy 234.680143 -161.165054) (xy 234.64937 -161.211567) (xy 234.612153 -161.253104)
			(xy 234.569285 -161.288779) (xy 234.521679 -161.317833) (xy 234.47035 -161.339645) (xy 234.416393 -161.353751)
			(xy 234.360956 -161.359851) (xy 234.305222 -161.357814) (xy 234.250379 -161.347684) (xy 234.197595 -161.329677)
			(xy 234.147995 -161.304176) (xy 234.102637 -161.271725) (xy 234.062488 -161.233016) (xy 234.028402 -161.188873)
			(xy 234.001106 -161.140238) (xy 233.981183 -161.088147) (xy 233.969057 -161.03371) (xy 233.964986 -160.978088)
			(xy 223.523546 -160.978088) (xy 223.522571 -160.978899) (xy 223.474965 -161.007953) (xy 223.423636 -161.029765)
			(xy 223.369679 -161.043871) (xy 223.314242 -161.049971) (xy 223.258508 -161.047934) (xy 223.203665 -161.037804)
			(xy 223.150881 -161.019797) (xy 223.101281 -160.994296) (xy 223.055923 -160.961845) (xy 223.015774 -160.923136)
			(xy 222.981688 -160.878993) (xy 222.954392 -160.830358) (xy 222.934469 -160.778267) (xy 222.922343 -160.72383)
			(xy 222.918272 -160.668208) (xy 217.280417 -160.668208) (xy 217.286558 -160.689206) (xy 217.294247 -160.742928)
			(xy 217.294714 -160.770062) (xy 217.294211 -160.79791) (xy 217.286123 -160.853017) (xy 217.270111 -160.906362)
			(xy 217.246517 -160.956814) (xy 217.21584 -161.003302) (xy 217.178734 -161.044838) (xy 217.135985 -161.08054)
			(xy 217.088501 -161.109651) (xy 217.037291 -161.131552) (xy 217.010488 -161.139124) (xy 217.00998 -161.139124)
			(xy 217.004138 -161.140902) (xy 216.985088 -161.159952) (xy 216.884758 -161.535364) (xy 216.873072 -161.57737)
			(xy 216.843332 -161.65934) (xy 216.806557 -161.738403) (xy 216.78519 -161.77641) (xy 216.012959 -163.114736)
			(xy 248.249692 -163.114736) (xy 248.253763 -163.059114) (xy 248.265889 -163.004677) (xy 248.285812 -162.952586)
			(xy 248.313108 -162.903951) (xy 248.347194 -162.859808) (xy 248.387343 -162.821099) (xy 248.432701 -162.788648)
			(xy 248.482301 -162.763147) (xy 248.535085 -162.74514) (xy 248.589928 -162.73501) (xy 248.645662 -162.732973)
			(xy 248.701099 -162.739073) (xy 248.755056 -162.753179) (xy 248.806385 -162.774991) (xy 248.853991 -162.804045)
			(xy 248.896859 -162.83972) (xy 248.934076 -162.881257) (xy 248.964849 -162.92777) (xy 248.988521 -162.978267)
			(xy 249.004589 -163.031674) (xy 249.012709 -163.08685) (xy 249.013218 -163.114736) (xy 249.012709 -163.142622)
			(xy 249.004589 -163.197798) (xy 248.988521 -163.251205) (xy 248.964849 -163.301702) (xy 248.934076 -163.348215)
			(xy 248.896859 -163.389752) (xy 248.853991 -163.425427) (xy 248.806385 -163.454481) (xy 248.755056 -163.476293)
			(xy 248.701099 -163.490399) (xy 248.645662 -163.496499) (xy 248.589928 -163.494462) (xy 248.535085 -163.484332)
			(xy 248.482301 -163.466325) (xy 248.432701 -163.440824) (xy 248.387343 -163.408373) (xy 248.347194 -163.369664)
			(xy 248.313108 -163.325521) (xy 248.285812 -163.276886) (xy 248.265889 -163.224795) (xy 248.253763 -163.170358)
			(xy 248.249692 -163.114736) (xy 216.012959 -163.114736) (xy 215.333648 -164.292026) (xy 216.864182 -164.292026)
			(xy 216.868253 -164.236404) (xy 216.880379 -164.181967) (xy 216.900302 -164.129876) (xy 216.927598 -164.081241)
			(xy 216.961684 -164.037098) (xy 217.001833 -163.998389) (xy 217.047191 -163.965938) (xy 217.096791 -163.940437)
			(xy 217.149575 -163.92243) (xy 217.204418 -163.9123) (xy 217.260152 -163.910263) (xy 217.315589 -163.916363)
			(xy 217.369546 -163.930469) (xy 217.420875 -163.952281) (xy 217.468481 -163.981335) (xy 217.511349 -164.01701)
			(xy 217.548566 -164.058547) (xy 217.579339 -164.10506) (xy 217.603011 -164.155557) (xy 217.619079 -164.208964)
			(xy 217.625098 -164.249862) (xy 218.480384 -164.249862) (xy 218.484455 -164.19424) (xy 218.496581 -164.139803)
			(xy 218.516504 -164.087712) (xy 218.5438 -164.039077) (xy 218.577886 -163.994934) (xy 218.618035 -163.956225)
			(xy 218.663393 -163.923774) (xy 218.712993 -163.898273) (xy 218.765777 -163.880266) (xy 218.82062 -163.870136)
			(xy 218.876354 -163.868099) (xy 218.931791 -163.874199) (xy 218.985748 -163.888305) (xy 219.037077 -163.910117)
			(xy 219.084683 -163.939171) (xy 219.127551 -163.974846) (xy 219.164768 -164.016383) (xy 219.195541 -164.062896)
			(xy 219.219213 -164.113393) (xy 219.235281 -164.1668) (xy 219.243401 -164.221976) (xy 219.24391 -164.249862)
			(xy 219.243401 -164.277748) (xy 219.235281 -164.332924) (xy 219.219213 -164.386331) (xy 219.195541 -164.436828)
			(xy 219.164768 -164.483341) (xy 219.127551 -164.524878) (xy 219.084683 -164.560553) (xy 219.037077 -164.589607)
			(xy 218.985748 -164.611419) (xy 218.931791 -164.625525) (xy 218.876354 -164.631625) (xy 218.82062 -164.629588)
			(xy 218.765777 -164.619458) (xy 218.712993 -164.601451) (xy 218.663393 -164.57595) (xy 218.618035 -164.543499)
			(xy 218.577886 -164.50479) (xy 218.5438 -164.460647) (xy 218.516504 -164.412012) (xy 218.496581 -164.359921)
			(xy 218.484455 -164.305484) (xy 218.480384 -164.249862) (xy 217.625098 -164.249862) (xy 217.627199 -164.26414)
			(xy 217.627708 -164.292026) (xy 217.627199 -164.319912) (xy 217.619079 -164.375088) (xy 217.603011 -164.428495)
			(xy 217.579339 -164.478992) (xy 217.548566 -164.525505) (xy 217.511349 -164.567042) (xy 217.468481 -164.602717)
			(xy 217.420875 -164.631771) (xy 217.369546 -164.653583) (xy 217.315589 -164.667689) (xy 217.260152 -164.673789)
			(xy 217.204418 -164.671752) (xy 217.149575 -164.661622) (xy 217.096791 -164.643615) (xy 217.047191 -164.618114)
			(xy 217.001833 -164.585663) (xy 216.961684 -164.546954) (xy 216.927598 -164.502811) (xy 216.900302 -164.454176)
			(xy 216.880379 -164.402085) (xy 216.868253 -164.347648) (xy 216.864182 -164.292026) (xy 215.333648 -164.292026)
			(xy 213.819232 -166.916608) (xy 213.814858 -166.924889) (xy 213.811951 -166.943379) (xy 213.815927 -166.961668)
			(xy 213.820756 -166.969694) (xy 213.877652 -167.057578) (xy 213.90356 -167.06977) (xy 213.917784 -167.068246)
			(xy 213.927535 -167.067296) (xy 213.947103 -167.066279) (xy 213.9569 -167.066214) (xy 213.957408 -167.066214)
			(xy 213.984657 -167.066701) (xy 214.007766 -167.070024) (xy 215.122758 -167.070024) (xy 215.126829 -167.014402)
			(xy 215.138955 -166.959965) (xy 215.158878 -166.907874) (xy 215.186174 -166.859239) (xy 215.22026 -166.815096)
			(xy 215.260409 -166.776387) (xy 215.305767 -166.743936) (xy 215.355367 -166.718435) (xy 215.408151 -166.700428)
			(xy 215.462994 -166.690298) (xy 215.518728 -166.688261) (xy 215.574165 -166.694361) (xy 215.628122 -166.708467)
			(xy 215.679451 -166.730279) (xy 215.727057 -166.759333) (xy 215.769925 -166.795008) (xy 215.807142 -166.836545)
			(xy 215.837915 -166.883058) (xy 215.861587 -166.933555) (xy 215.877655 -166.986962) (xy 215.880534 -167.006524)
			(xy 216.52941 -167.006524) (xy 216.533481 -166.950902) (xy 216.545607 -166.896465) (xy 216.56553 -166.844374)
			(xy 216.592826 -166.795739) (xy 216.626912 -166.751596) (xy 216.667061 -166.712887) (xy 216.712419 -166.680436)
			(xy 216.762019 -166.654935) (xy 216.814803 -166.636928) (xy 216.869646 -166.626798) (xy 216.92538 -166.624761)
			(xy 216.980817 -166.630861) (xy 217.034774 -166.644967) (xy 217.086103 -166.666779) (xy 217.133709 -166.695833)
			(xy 217.176577 -166.731508) (xy 217.213794 -166.773045) (xy 217.244567 -166.819558) (xy 217.268239 -166.870055)
			(xy 217.284307 -166.923462) (xy 217.292427 -166.978638) (xy 217.292936 -167.006524) (xy 217.292427 -167.03441)
			(xy 217.284307 -167.089586) (xy 217.268239 -167.142993) (xy 217.244567 -167.19349) (xy 217.213794 -167.240003)
			(xy 217.176577 -167.28154) (xy 217.133709 -167.317215) (xy 217.086103 -167.346269) (xy 217.034774 -167.368081)
			(xy 216.980817 -167.382187) (xy 216.92538 -167.388287) (xy 216.869646 -167.38625) (xy 216.814803 -167.37612)
			(xy 216.762019 -167.358113) (xy 216.712419 -167.332612) (xy 216.667061 -167.300161) (xy 216.626912 -167.261452)
			(xy 216.592826 -167.217309) (xy 216.56553 -167.168674) (xy 216.545607 -167.116583) (xy 216.533481 -167.062146)
			(xy 216.52941 -167.006524) (xy 215.880534 -167.006524) (xy 215.885775 -167.042138) (xy 215.886284 -167.070024)
			(xy 215.885775 -167.09791) (xy 215.877655 -167.153086) (xy 215.861587 -167.206493) (xy 215.837915 -167.25699)
			(xy 215.807142 -167.303503) (xy 215.769925 -167.34504) (xy 215.727057 -167.380715) (xy 215.679451 -167.409769)
			(xy 215.628122 -167.431581) (xy 215.574165 -167.445687) (xy 215.518728 -167.451787) (xy 215.462994 -167.44975)
			(xy 215.408151 -167.43962) (xy 215.355367 -167.421613) (xy 215.305767 -167.396112) (xy 215.260409 -167.363661)
			(xy 215.22026 -167.324952) (xy 215.186174 -167.280809) (xy 215.158878 -167.232174) (xy 215.138955 -167.180083)
			(xy 215.126829 -167.125646) (xy 215.122758 -167.070024) (xy 214.007766 -167.070024) (xy 214.038601 -167.074458)
			(xy 214.090892 -167.089813) (xy 214.140465 -167.112453) (xy 214.186312 -167.141918) (xy 214.227499 -167.177607)
			(xy 214.263187 -167.218795) (xy 214.292651 -167.264642) (xy 214.31529 -167.314216) (xy 214.330644 -167.366507)
			(xy 214.3384 -167.420451) (xy 214.3384 -167.474949) (xy 214.330644 -167.528893) (xy 214.31529 -167.581184)
			(xy 214.292651 -167.630758) (xy 214.263187 -167.676605) (xy 214.227499 -167.717793) (xy 214.186312 -167.753482)
			(xy 214.140465 -167.782947) (xy 214.090892 -167.805587) (xy 214.038601 -167.820942) (xy 213.984657 -167.828699)
			(xy 213.957408 -167.82923) (xy 213.929955 -167.828752) (xy 213.875618 -167.820877) (xy 213.822972 -167.805288)
			(xy 213.773107 -167.782308) (xy 213.727055 -167.752412) (xy 213.685767 -167.716218) (xy 213.650099 -167.674477)
			(xy 213.620788 -167.62805) (xy 213.609174 -167.60317) (xy 213.603332 -167.589962) (xy 213.579964 -167.574214)
			(xy 213.474808 -167.568626) (xy 213.465478 -167.568566) (xy 213.44776 -167.574362) (xy 213.43331 -167.586139)
			(xy 213.428326 -167.594026) (xy 212.989055 -168.354756) (xy 213.648542 -168.354756) (xy 213.652613 -168.299134)
			(xy 213.664739 -168.244697) (xy 213.684662 -168.192606) (xy 213.711958 -168.143971) (xy 213.746044 -168.099828)
			(xy 213.786193 -168.061119) (xy 213.831551 -168.028668) (xy 213.881151 -168.003167) (xy 213.933935 -167.98516)
			(xy 213.988778 -167.97503) (xy 214.044512 -167.972993) (xy 214.099949 -167.979093) (xy 214.153906 -167.993199)
			(xy 214.205235 -168.015011) (xy 214.252841 -168.044065) (xy 214.295709 -168.07974) (xy 214.332926 -168.121277)
			(xy 214.363699 -168.16779) (xy 214.387371 -168.218287) (xy 214.403439 -168.271694) (xy 214.411559 -168.32687)
			(xy 214.412068 -168.354756) (xy 214.411559 -168.382642) (xy 214.403439 -168.437818) (xy 214.387371 -168.491225)
			(xy 214.363699 -168.541722) (xy 214.332926 -168.588235) (xy 214.295709 -168.629772) (xy 214.252841 -168.665447)
			(xy 214.205235 -168.694501) (xy 214.153906 -168.716313) (xy 214.099949 -168.730419) (xy 214.044512 -168.736519)
			(xy 213.988778 -168.734482) (xy 213.933935 -168.724352) (xy 213.881151 -168.706345) (xy 213.831551 -168.680844)
			(xy 213.786193 -168.648393) (xy 213.746044 -168.609684) (xy 213.711958 -168.565541) (xy 213.684662 -168.516906)
			(xy 213.664739 -168.464815) (xy 213.652613 -168.410378) (xy 213.648542 -168.354756) (xy 212.989055 -168.354756)
			(xy 212.974682 -168.379648) (xy 212.975952 -168.40835) (xy 212.983064 -168.419018) (xy 212.998522 -168.442799)
			(xy 213.022994 -168.493964) (xy 213.039629 -168.548187) (xy 213.048059 -168.604274) (xy 213.048596 -168.632632)
			(xy 213.048596 -168.63314) (xy 213.048107 -168.660389) (xy 213.040346 -168.714332) (xy 213.024987 -168.766621)
			(xy 213.002344 -168.816192) (xy 212.972876 -168.862037) (xy 212.937184 -168.903221) (xy 212.895995 -168.938907)
			(xy 212.850147 -168.968368) (xy 212.800572 -168.991005) (xy 212.748281 -169.006357) (xy 212.694337 -169.014111)
			(xy 212.667088 -169.014648) (xy 212.659976 -169.014648) (xy 212.640672 -169.013886) (xy 212.62721 -169.01287)
			(xy 212.60181 -169.026586) (xy 212.444378 -169.299382) (xy 212.885526 -169.299382) (xy 212.889597 -169.24376)
			(xy 212.901723 -169.189323) (xy 212.921646 -169.137232) (xy 212.948942 -169.088597) (xy 212.983028 -169.044454)
			(xy 213.023177 -169.005745) (xy 213.068535 -168.973294) (xy 213.118135 -168.947793) (xy 213.170919 -168.929786)
			(xy 213.225762 -168.919656) (xy 213.281496 -168.917619) (xy 213.336933 -168.923719) (xy 213.39089 -168.937825)
			(xy 213.442219 -168.959637) (xy 213.489825 -168.988691) (xy 213.532693 -169.024366) (xy 213.56991 -169.065903)
			(xy 213.600683 -169.112416) (xy 213.624355 -169.162913) (xy 213.640423 -169.21632) (xy 213.648543 -169.271496)
			(xy 213.649052 -169.299382) (xy 213.648543 -169.327268) (xy 213.640461 -169.382186) (xy 221.32493 -169.382186)
			(xy 221.329001 -169.326564) (xy 221.341127 -169.272127) (xy 221.36105 -169.220036) (xy 221.388346 -169.171401)
			(xy 221.422432 -169.127258) (xy 221.462581 -169.088549) (xy 221.507939 -169.056098) (xy 221.557539 -169.030597)
			(xy 221.610323 -169.01259) (xy 221.665166 -169.00246) (xy 221.7209 -169.000423) (xy 221.776337 -169.006523)
			(xy 221.830294 -169.020629) (xy 221.881623 -169.042441) (xy 221.929229 -169.071495) (xy 221.972097 -169.10717)
			(xy 222.009314 -169.148707) (xy 222.040087 -169.19522) (xy 222.063759 -169.245717) (xy 222.079827 -169.299124)
			(xy 222.087947 -169.3543) (xy 222.088456 -169.382186) (xy 222.087947 -169.410072) (xy 222.080949 -169.457624)
			(xy 222.853756 -169.457624) (xy 222.857827 -169.402002) (xy 222.869953 -169.347565) (xy 222.889876 -169.295474)
			(xy 222.917172 -169.246839) (xy 222.951258 -169.202696) (xy 222.991407 -169.163987) (xy 223.036765 -169.131536)
			(xy 223.086365 -169.106035) (xy 223.139149 -169.088028) (xy 223.193992 -169.077898) (xy 223.249726 -169.075861)
			(xy 223.305163 -169.081961) (xy 223.35912 -169.096067) (xy 223.410449 -169.117879) (xy 223.458055 -169.146933)
			(xy 223.500923 -169.182608) (xy 223.53814 -169.224145) (xy 223.568913 -169.270658) (xy 223.592585 -169.321155)
			(xy 223.608653 -169.374562) (xy 223.616773 -169.429738) (xy 223.617282 -169.457624) (xy 223.616773 -169.48551)
			(xy 223.608653 -169.540686) (xy 223.592585 -169.594093) (xy 223.568913 -169.64459) (xy 223.53814 -169.691103)
			(xy 223.500923 -169.73264) (xy 223.458055 -169.768315) (xy 223.410449 -169.797369) (xy 223.35912 -169.819181)
			(xy 223.305163 -169.833287) (xy 223.249726 -169.839387) (xy 223.193992 -169.83735) (xy 223.139149 -169.82722)
			(xy 223.086365 -169.809213) (xy 223.036765 -169.783712) (xy 222.991407 -169.751261) (xy 222.951258 -169.712552)
			(xy 222.917172 -169.668409) (xy 222.889876 -169.619774) (xy 222.869953 -169.567683) (xy 222.857827 -169.513246)
			(xy 222.853756 -169.457624) (xy 222.080949 -169.457624) (xy 222.079827 -169.465248) (xy 222.063759 -169.518655)
			(xy 222.040087 -169.569152) (xy 222.009314 -169.615665) (xy 221.972097 -169.657202) (xy 221.929229 -169.692877)
			(xy 221.881623 -169.721931) (xy 221.830294 -169.743743) (xy 221.776337 -169.757849) (xy 221.7209 -169.763949)
			(xy 221.665166 -169.761912) (xy 221.610323 -169.751782) (xy 221.557539 -169.733775) (xy 221.507939 -169.708274)
			(xy 221.462581 -169.675823) (xy 221.422432 -169.637114) (xy 221.388346 -169.592971) (xy 221.36105 -169.544336)
			(xy 221.341127 -169.492245) (xy 221.329001 -169.437808) (xy 221.32493 -169.382186) (xy 213.640461 -169.382186)
			(xy 213.640423 -169.382444) (xy 213.624355 -169.435851) (xy 213.600683 -169.486348) (xy 213.56991 -169.532861)
			(xy 213.532693 -169.574398) (xy 213.489825 -169.610073) (xy 213.442219 -169.639127) (xy 213.39089 -169.660939)
			(xy 213.336933 -169.675045) (xy 213.281496 -169.681145) (xy 213.225762 -169.679108) (xy 213.170919 -169.668978)
			(xy 213.118135 -169.650971) (xy 213.068535 -169.62547) (xy 213.023177 -169.593019) (xy 212.983028 -169.55431)
			(xy 212.948942 -169.510167) (xy 212.921646 -169.461532) (xy 212.901723 -169.409441) (xy 212.889597 -169.355004)
			(xy 212.885526 -169.299382) (xy 212.444378 -169.299382) (xy 211.270088 -171.334176) (xy 211.26831 -171.340526)
			(xy 211.2591 -171.371046) (xy 211.231962 -171.428725) (xy 211.195627 -171.481101) (xy 211.173822 -171.504356)
			(xy 211.16925 -171.508928) (xy 211.042758 -171.727876) (xy 211.041234 -171.75099) (xy 211.042504 -171.754292)
			(xy 211.052204 -171.777901) (xy 211.065922 -171.827064) (xy 211.072961 -171.877618) (xy 211.073492 -171.903136)
			(xy 211.073492 -171.906692) (xy 211.072908 -171.933941) (xy 211.06496 -171.987861) (xy 211.049426 -172.040102)
			(xy 211.026621 -172.089603) (xy 210.997007 -172.135359) (xy 210.961188 -172.176438) (xy 210.919892 -172.212005)
			(xy 210.913934 -172.21581) (xy 217.915996 -172.21581) (xy 217.920067 -172.160188) (xy 217.932193 -172.105751)
			(xy 217.952116 -172.05366) (xy 217.979412 -172.005025) (xy 218.013498 -171.960882) (xy 218.053647 -171.922173)
			(xy 218.099005 -171.889722) (xy 218.148605 -171.864221) (xy 218.201389 -171.846214) (xy 218.256232 -171.836084)
			(xy 218.311966 -171.834047) (xy 218.367403 -171.840147) (xy 218.42136 -171.854253) (xy 218.472689 -171.876065)
			(xy 218.520295 -171.905119) (xy 218.563163 -171.940794) (xy 218.60038 -171.982331) (xy 218.631153 -172.028844)
			(xy 218.654825 -172.079341) (xy 218.670893 -172.132748) (xy 218.679013 -172.187924) (xy 218.679522 -172.21581)
			(xy 218.679013 -172.243696) (xy 218.670893 -172.298872) (xy 218.654825 -172.352279) (xy 218.631153 -172.402776)
			(xy 218.60038 -172.449289) (xy 218.563163 -172.490826) (xy 218.520295 -172.526501) (xy 218.472689 -172.555555)
			(xy 218.42136 -172.577367) (xy 218.367403 -172.591473) (xy 218.311966 -172.597573) (xy 218.256232 -172.595536)
			(xy 218.201389 -172.585406) (xy 218.148605 -172.567399) (xy 218.099005 -172.541898) (xy 218.053647 -172.509447)
			(xy 218.013498 -172.470738) (xy 217.979412 -172.426595) (xy 217.952116 -172.37796) (xy 217.932193 -172.325869)
			(xy 217.920067 -172.271432) (xy 217.915996 -172.21581) (xy 210.913934 -172.21581) (xy 210.873957 -172.241339)
			(xy 210.824317 -172.263842) (xy 210.771982 -172.279057) (xy 210.74507 -172.283374) (xy 210.733386 -172.284898)
			(xy 210.714082 -172.297852) (xy 209.155679 -174.99838) (xy 219.081348 -174.99838) (xy 219.085419 -174.942758)
			(xy 219.097545 -174.888321) (xy 219.117468 -174.83623) (xy 219.144764 -174.787595) (xy 219.17885 -174.743452)
			(xy 219.218999 -174.704743) (xy 219.264357 -174.672292) (xy 219.313957 -174.646791) (xy 219.366741 -174.628784)
			(xy 219.421584 -174.618654) (xy 219.477318 -174.616617) (xy 219.532755 -174.622717) (xy 219.586712 -174.636823)
			(xy 219.638041 -174.658635) (xy 219.685647 -174.687689) (xy 219.728515 -174.723364) (xy 219.765732 -174.764901)
			(xy 219.796505 -174.811414) (xy 219.820177 -174.861911) (xy 219.836245 -174.915318) (xy 219.844365 -174.970494)
			(xy 219.844874 -174.99838) (xy 219.844365 -175.026266) (xy 219.836245 -175.081442) (xy 219.820177 -175.134849)
			(xy 219.796505 -175.185346) (xy 219.765732 -175.231859) (xy 219.728515 -175.273396) (xy 219.685647 -175.309071)
			(xy 219.638041 -175.338125) (xy 219.586712 -175.359937) (xy 219.532755 -175.374043) (xy 219.477318 -175.380143)
			(xy 219.421584 -175.378106) (xy 219.366741 -175.367976) (xy 219.313957 -175.349969) (xy 219.264357 -175.324468)
			(xy 219.218999 -175.292017) (xy 219.17885 -175.253308) (xy 219.144764 -175.209165) (xy 219.117468 -175.16053)
			(xy 219.097545 -175.108439) (xy 219.085419 -175.054002) (xy 219.081348 -174.99838) (xy 209.155679 -174.99838)
			(xy 208.862526 -175.50638) (xy 222.194626 -175.50638) (xy 222.198697 -175.450758) (xy 222.210823 -175.396321)
			(xy 222.230746 -175.34423) (xy 222.258042 -175.295595) (xy 222.292128 -175.251452) (xy 222.332277 -175.212743)
			(xy 222.377635 -175.180292) (xy 222.427235 -175.154791) (xy 222.480019 -175.136784) (xy 222.534862 -175.126654)
			(xy 222.590596 -175.124617) (xy 222.646033 -175.130717) (xy 222.69999 -175.144823) (xy 222.751319 -175.166635)
			(xy 222.798925 -175.195689) (xy 222.841793 -175.231364) (xy 222.87901 -175.272901) (xy 222.909783 -175.319414)
			(xy 222.915151 -175.330866) (xy 224.385376 -175.330866) (xy 224.389447 -175.275244) (xy 224.401573 -175.220807)
			(xy 224.421496 -175.168716) (xy 224.448792 -175.120081) (xy 224.482878 -175.075938) (xy 224.523027 -175.037229)
			(xy 224.568385 -175.004778) (xy 224.617985 -174.979277) (xy 224.670769 -174.96127) (xy 224.725612 -174.95114)
			(xy 224.781346 -174.949103) (xy 224.836783 -174.955203) (xy 224.89074 -174.969309) (xy 224.942069 -174.991121)
			(xy 224.989675 -175.020175) (xy 225.032543 -175.05585) (xy 225.06976 -175.097387) (xy 225.100533 -175.1439)
			(xy 225.124205 -175.194397) (xy 225.140273 -175.247804) (xy 225.148393 -175.30298) (xy 225.148902 -175.330866)
			(xy 225.148393 -175.358752) (xy 225.140273 -175.413928) (xy 225.124205 -175.467335) (xy 225.100533 -175.517832)
			(xy 225.06976 -175.564345) (xy 225.032543 -175.605882) (xy 224.989675 -175.641557) (xy 224.942069 -175.670611)
			(xy 224.89074 -175.692423) (xy 224.836783 -175.706529) (xy 224.781346 -175.712629) (xy 224.725612 -175.710592)
			(xy 224.670769 -175.700462) (xy 224.617985 -175.682455) (xy 224.568385 -175.656954) (xy 224.523027 -175.624503)
			(xy 224.482878 -175.585794) (xy 224.448792 -175.541651) (xy 224.421496 -175.493016) (xy 224.401573 -175.440925)
			(xy 224.389447 -175.386488) (xy 224.385376 -175.330866) (xy 222.915151 -175.330866) (xy 222.933455 -175.369911)
			(xy 222.949523 -175.423318) (xy 222.957643 -175.478494) (xy 222.958152 -175.50638) (xy 222.957643 -175.534266)
			(xy 222.949523 -175.589442) (xy 222.933455 -175.642849) (xy 222.909783 -175.693346) (xy 222.87901 -175.739859)
			(xy 222.841793 -175.781396) (xy 222.798925 -175.817071) (xy 222.751319 -175.846125) (xy 222.69999 -175.867937)
			(xy 222.646033 -175.882043) (xy 222.590596 -175.888143) (xy 222.534862 -175.886106) (xy 222.480019 -175.875976)
			(xy 222.427235 -175.857969) (xy 222.377635 -175.832468) (xy 222.332277 -175.800017) (xy 222.292128 -175.761308)
			(xy 222.258042 -175.717165) (xy 222.230746 -175.66853) (xy 222.210823 -175.616439) (xy 222.198697 -175.562002)
			(xy 222.194626 -175.50638) (xy 208.862526 -175.50638) (xy 208.607482 -175.94834) (xy 216.952066 -175.94834)
			(xy 216.956137 -175.892718) (xy 216.968263 -175.838281) (xy 216.988186 -175.78619) (xy 217.015482 -175.737555)
			(xy 217.049568 -175.693412) (xy 217.089717 -175.654703) (xy 217.135075 -175.622252) (xy 217.184675 -175.596751)
			(xy 217.237459 -175.578744) (xy 217.292302 -175.568614) (xy 217.348036 -175.566577) (xy 217.403473 -175.572677)
			(xy 217.45743 -175.586783) (xy 217.508759 -175.608595) (xy 217.556365 -175.637649) (xy 217.599233 -175.673324)
			(xy 217.63645 -175.714861) (xy 217.667223 -175.761374) (xy 217.690895 -175.811871) (xy 217.706963 -175.865278)
			(xy 217.715083 -175.920454) (xy 217.715592 -175.94834) (xy 217.715083 -175.976226) (xy 217.706963 -176.031402)
			(xy 217.690895 -176.084809) (xy 217.667223 -176.135306) (xy 217.63645 -176.181819) (xy 217.599233 -176.223356)
			(xy 217.556365 -176.259031) (xy 217.508759 -176.288085) (xy 217.45743 -176.309897) (xy 217.403473 -176.324003)
			(xy 217.348036 -176.330103) (xy 217.292302 -176.328066) (xy 217.237459 -176.317936) (xy 217.184675 -176.299929)
			(xy 217.135075 -176.274428) (xy 217.089717 -176.241977) (xy 217.049568 -176.203268) (xy 217.015482 -176.159125)
			(xy 216.988186 -176.11049) (xy 216.968263 -176.058399) (xy 216.956137 -176.003962) (xy 216.952066 -175.94834)
			(xy 208.607482 -175.94834) (xy 208.302749 -176.476406) (xy 215.436702 -176.476406) (xy 215.440773 -176.420784)
			(xy 215.452899 -176.366347) (xy 215.472822 -176.314256) (xy 215.500118 -176.265621) (xy 215.534204 -176.221478)
			(xy 215.574353 -176.182769) (xy 215.619711 -176.150318) (xy 215.669311 -176.124817) (xy 215.722095 -176.10681)
			(xy 215.776938 -176.09668) (xy 215.832672 -176.094643) (xy 215.888109 -176.100743) (xy 215.942066 -176.114849)
			(xy 215.993395 -176.136661) (xy 216.041001 -176.165715) (xy 216.083869 -176.20139) (xy 216.121086 -176.242927)
			(xy 216.151859 -176.28944) (xy 216.175531 -176.339937) (xy 216.191599 -176.393344) (xy 216.199719 -176.44852)
			(xy 216.200228 -176.476406) (xy 216.199719 -176.504292) (xy 216.197057 -176.52238) (xy 222.194626 -176.52238)
			(xy 222.198697 -176.466758) (xy 222.210823 -176.412321) (xy 222.230746 -176.36023) (xy 222.258042 -176.311595)
			(xy 222.292128 -176.267452) (xy 222.332277 -176.228743) (xy 222.377635 -176.196292) (xy 222.427235 -176.170791)
			(xy 222.480019 -176.152784) (xy 222.534862 -176.142654) (xy 222.590596 -176.140617) (xy 222.646033 -176.146717)
			(xy 222.69999 -176.160823) (xy 222.751319 -176.182635) (xy 222.798925 -176.211689) (xy 222.841793 -176.247364)
			(xy 222.87901 -176.288901) (xy 222.909783 -176.335414) (xy 222.933455 -176.385911) (xy 222.949523 -176.439318)
			(xy 222.957643 -176.494494) (xy 222.958152 -176.52238) (xy 222.957643 -176.550266) (xy 222.949523 -176.605442)
			(xy 222.933455 -176.658849) (xy 222.909783 -176.709346) (xy 222.87901 -176.755859) (xy 222.841793 -176.797396)
			(xy 222.798925 -176.833071) (xy 222.751319 -176.862125) (xy 222.69999 -176.883937) (xy 222.646033 -176.898043)
			(xy 222.590596 -176.904143) (xy 222.534862 -176.902106) (xy 222.480019 -176.891976) (xy 222.427235 -176.873969)
			(xy 222.377635 -176.848468) (xy 222.332277 -176.816017) (xy 222.292128 -176.777308) (xy 222.258042 -176.733165)
			(xy 222.230746 -176.68453) (xy 222.210823 -176.632439) (xy 222.198697 -176.578002) (xy 222.194626 -176.52238)
			(xy 216.197057 -176.52238) (xy 216.191599 -176.559468) (xy 216.175531 -176.612875) (xy 216.151859 -176.663372)
			(xy 216.121086 -176.709885) (xy 216.083869 -176.751422) (xy 216.041001 -176.787097) (xy 215.993395 -176.816151)
			(xy 215.942066 -176.837963) (xy 215.888109 -176.852069) (xy 215.832672 -176.858169) (xy 215.776938 -176.856132)
			(xy 215.722095 -176.846002) (xy 215.669311 -176.827995) (xy 215.619711 -176.802494) (xy 215.574353 -176.770043)
			(xy 215.534204 -176.731334) (xy 215.500118 -176.687191) (xy 215.472822 -176.638556) (xy 215.452899 -176.586465)
			(xy 215.440773 -176.532028) (xy 215.436702 -176.476406) (xy 208.302749 -176.476406) (xy 208.280762 -176.514506)
			(xy 208.275682 -176.526444) (xy 207.91338 -177.85461) (xy 212.50859 -177.85461) (xy 212.512661 -177.798988)
			(xy 212.524787 -177.744551) (xy 212.54471 -177.69246) (xy 212.572006 -177.643825) (xy 212.606092 -177.599682)
			(xy 212.646241 -177.560973) (xy 212.691599 -177.528522) (xy 212.741199 -177.503021) (xy 212.793983 -177.485014)
			(xy 212.848826 -177.474884) (xy 212.90456 -177.472847) (xy 212.959997 -177.478947) (xy 213.013954 -177.493053)
			(xy 213.065283 -177.514865) (xy 213.103813 -177.53838) (xy 222.194626 -177.53838) (xy 222.198697 -177.482758)
			(xy 222.210823 -177.428321) (xy 222.230746 -177.37623) (xy 222.258042 -177.327595) (xy 222.292128 -177.283452)
			(xy 222.332277 -177.244743) (xy 222.377635 -177.212292) (xy 222.427235 -177.186791) (xy 222.480019 -177.168784)
			(xy 222.534862 -177.158654) (xy 222.590596 -177.156617) (xy 222.646033 -177.162717) (xy 222.69999 -177.176823)
			(xy 222.751319 -177.198635) (xy 222.798925 -177.227689) (xy 222.841793 -177.263364) (xy 222.87901 -177.304901)
			(xy 222.909783 -177.351414) (xy 222.933455 -177.401911) (xy 222.949523 -177.455318) (xy 222.957643 -177.510494)
			(xy 222.958152 -177.53838) (xy 222.957643 -177.566266) (xy 222.949523 -177.621442) (xy 222.933455 -177.674849)
			(xy 222.909783 -177.725346) (xy 222.87901 -177.771859) (xy 222.841793 -177.813396) (xy 222.798925 -177.849071)
			(xy 222.751319 -177.878125) (xy 222.69999 -177.899937) (xy 222.646033 -177.914043) (xy 222.590596 -177.920143)
			(xy 222.534862 -177.918106) (xy 222.480019 -177.907976) (xy 222.427235 -177.889969) (xy 222.377635 -177.864468)
			(xy 222.332277 -177.832017) (xy 222.292128 -177.793308) (xy 222.258042 -177.749165) (xy 222.230746 -177.70053)
			(xy 222.210823 -177.648439) (xy 222.198697 -177.594002) (xy 222.194626 -177.53838) (xy 213.103813 -177.53838)
			(xy 213.112889 -177.543919) (xy 213.155757 -177.579594) (xy 213.192974 -177.621131) (xy 213.223747 -177.667644)
			(xy 213.247419 -177.718141) (xy 213.263487 -177.771548) (xy 213.271607 -177.826724) (xy 213.272116 -177.85461)
			(xy 213.271607 -177.882496) (xy 213.263487 -177.937672) (xy 213.247419 -177.991079) (xy 213.223747 -178.041576)
			(xy 213.192974 -178.088089) (xy 213.184828 -178.09718) (xy 217.597226 -178.09718) (xy 217.601297 -178.041558)
			(xy 217.613423 -177.987121) (xy 217.633346 -177.93503) (xy 217.660642 -177.886395) (xy 217.694728 -177.842252)
			(xy 217.734877 -177.803543) (xy 217.780235 -177.771092) (xy 217.829835 -177.745591) (xy 217.882619 -177.727584)
			(xy 217.937462 -177.717454) (xy 217.993196 -177.715417) (xy 218.048633 -177.721517) (xy 218.10259 -177.735623)
			(xy 218.153919 -177.757435) (xy 218.201525 -177.786489) (xy 218.244393 -177.822164) (xy 218.28161 -177.863701)
			(xy 218.312383 -177.910214) (xy 218.336055 -177.960711) (xy 218.352123 -178.014118) (xy 218.35403 -178.027076)
			(xy 220.323408 -178.027076) (xy 220.327479 -177.971454) (xy 220.339605 -177.917017) (xy 220.359528 -177.864926)
			(xy 220.386824 -177.816291) (xy 220.42091 -177.772148) (xy 220.461059 -177.733439) (xy 220.506417 -177.700988)
			(xy 220.556017 -177.675487) (xy 220.608801 -177.65748) (xy 220.663644 -177.64735) (xy 220.719378 -177.645313)
			(xy 220.774815 -177.651413) (xy 220.828772 -177.665519) (xy 220.880101 -177.687331) (xy 220.927707 -177.716385)
			(xy 220.970575 -177.75206) (xy 221.007792 -177.793597) (xy 221.038565 -177.84011) (xy 221.062237 -177.890607)
			(xy 221.078305 -177.944014) (xy 221.086425 -177.99919) (xy 221.086934 -178.027076) (xy 221.086425 -178.054962)
			(xy 221.078305 -178.110138) (xy 221.062237 -178.163545) (xy 221.038565 -178.214042) (xy 221.007792 -178.260555)
			(xy 220.970575 -178.302092) (xy 220.927707 -178.337767) (xy 220.880101 -178.366821) (xy 220.828772 -178.388633)
			(xy 220.774815 -178.402739) (xy 220.719378 -178.408839) (xy 220.663644 -178.406802) (xy 220.608801 -178.396672)
			(xy 220.556017 -178.378665) (xy 220.506417 -178.353164) (xy 220.461059 -178.320713) (xy 220.42091 -178.282004)
			(xy 220.386824 -178.237861) (xy 220.359528 -178.189226) (xy 220.339605 -178.137135) (xy 220.327479 -178.082698)
			(xy 220.323408 -178.027076) (xy 218.35403 -178.027076) (xy 218.360243 -178.069294) (xy 218.360752 -178.09718)
			(xy 218.360243 -178.125066) (xy 218.352123 -178.180242) (xy 218.336055 -178.233649) (xy 218.312383 -178.284146)
			(xy 218.28161 -178.330659) (xy 218.244393 -178.372196) (xy 218.201525 -178.407871) (xy 218.153919 -178.436925)
			(xy 218.10259 -178.458737) (xy 218.048633 -178.472843) (xy 217.993196 -178.478943) (xy 217.937462 -178.476906)
			(xy 217.882619 -178.466776) (xy 217.829835 -178.448769) (xy 217.780235 -178.423268) (xy 217.734877 -178.390817)
			(xy 217.694728 -178.352108) (xy 217.660642 -178.307965) (xy 217.633346 -178.25933) (xy 217.613423 -178.207239)
			(xy 217.601297 -178.152802) (xy 217.597226 -178.09718) (xy 213.184828 -178.09718) (xy 213.155757 -178.129626)
			(xy 213.112889 -178.165301) (xy 213.065283 -178.194355) (xy 213.013954 -178.216167) (xy 212.959997 -178.230273)
			(xy 212.90456 -178.236373) (xy 212.848826 -178.234336) (xy 212.793983 -178.224206) (xy 212.741199 -178.206199)
			(xy 212.691599 -178.180698) (xy 212.646241 -178.148247) (xy 212.606092 -178.109538) (xy 212.572006 -178.065395)
			(xy 212.54471 -178.01676) (xy 212.524787 -177.964669) (xy 212.512661 -177.910232) (xy 212.50859 -177.85461)
			(xy 207.91338 -177.85461) (xy 207.691662 -178.66741) (xy 208.886042 -178.66741) (xy 208.890113 -178.611788)
			(xy 208.902239 -178.557351) (xy 208.922162 -178.50526) (xy 208.949458 -178.456625) (xy 208.983544 -178.412482)
			(xy 209.023693 -178.373773) (xy 209.069051 -178.341322) (xy 209.118651 -178.315821) (xy 209.171435 -178.297814)
			(xy 209.226278 -178.287684) (xy 209.282012 -178.285647) (xy 209.337449 -178.291747) (xy 209.391406 -178.305853)
			(xy 209.442735 -178.327665) (xy 209.490341 -178.356719) (xy 209.533209 -178.392394) (xy 209.570426 -178.433931)
			(xy 209.601199 -178.480444) (xy 209.624871 -178.530941) (xy 209.640939 -178.584348) (xy 209.649059 -178.639524)
			(xy 209.649568 -178.66741) (xy 209.649059 -178.695296) (xy 209.640939 -178.750472) (xy 209.624871 -178.803879)
			(xy 209.601199 -178.854376) (xy 209.570426 -178.900889) (xy 209.533209 -178.942426) (xy 209.490341 -178.978101)
			(xy 209.442735 -179.007155) (xy 209.391406 -179.028967) (xy 209.337449 -179.043073) (xy 209.282012 -179.049173)
			(xy 209.226278 -179.047136) (xy 209.171435 -179.037006) (xy 209.118651 -179.018999) (xy 209.069051 -178.993498)
			(xy 209.023693 -178.961047) (xy 208.983544 -178.922338) (xy 208.949458 -178.878195) (xy 208.922162 -178.82956)
			(xy 208.902239 -178.777469) (xy 208.890113 -178.723032) (xy 208.886042 -178.66741) (xy 207.691662 -178.66741)
			(xy 207.547961 -179.194206) (xy 210.383118 -179.194206) (xy 210.387189 -179.138584) (xy 210.399315 -179.084147)
			(xy 210.419238 -179.032056) (xy 210.446534 -178.983421) (xy 210.48062 -178.939278) (xy 210.520769 -178.900569)
			(xy 210.566127 -178.868118) (xy 210.615727 -178.842617) (xy 210.668511 -178.82461) (xy 210.723354 -178.81448)
			(xy 210.779088 -178.812443) (xy 210.834525 -178.818543) (xy 210.888482 -178.832649) (xy 210.939811 -178.854461)
			(xy 210.987417 -178.883515) (xy 211.030285 -178.91919) (xy 211.067502 -178.960727) (xy 211.098275 -179.00724)
			(xy 211.121947 -179.057737) (xy 211.138015 -179.111144) (xy 211.146135 -179.16632) (xy 211.146644 -179.194206)
			(xy 211.146135 -179.222092) (xy 211.138015 -179.277268) (xy 211.121947 -179.330675) (xy 211.098275 -179.381172)
			(xy 211.067502 -179.427685) (xy 211.030285 -179.469222) (xy 210.987417 -179.504897) (xy 210.939811 -179.533951)
			(xy 210.888482 -179.555763) (xy 210.834525 -179.569869) (xy 210.779088 -179.575969) (xy 210.723354 -179.573932)
			(xy 210.668511 -179.563802) (xy 210.615727 -179.545795) (xy 210.566127 -179.520294) (xy 210.520769 -179.487843)
			(xy 210.48062 -179.449134) (xy 210.446534 -179.404991) (xy 210.419238 -179.356356) (xy 210.399315 -179.304265)
			(xy 210.387189 -179.249828) (xy 210.383118 -179.194206) (xy 207.547961 -179.194206) (xy 207.488028 -179.413916)
			(xy 207.48625 -179.422806) (xy 207.448455 -179.85486) (xy 214.447628 -179.85486) (xy 214.447628 -179.854606)
			(xy 214.448175 -179.825868) (xy 214.456795 -179.769043) (xy 214.47384 -179.714153) (xy 214.498926 -179.662441)
			(xy 214.531485 -179.615077) (xy 214.550752 -179.593748) (xy 214.557356 -179.58689) (xy 214.564468 -179.568856)
			(xy 214.564468 -179.479956) (xy 214.557356 -179.461922) (xy 214.550752 -179.455064) (xy 214.531486 -179.433732)
			(xy 214.498919 -179.386372) (xy 214.473825 -179.334661) (xy 214.456773 -179.279772) (xy 214.448149 -179.222945)
			(xy 214.447628 -179.194206) (xy 214.448114 -179.166955) (xy 214.45587 -179.113007) (xy 214.471225 -179.060712)
			(xy 214.493867 -179.011135) (xy 214.523333 -178.965285) (xy 214.559024 -178.924094) (xy 214.600215 -178.888403)
			(xy 214.646065 -178.858937) (xy 214.695642 -178.836295) (xy 214.747937 -178.82094) (xy 214.801885 -178.813184)
			(xy 214.856387 -178.813184) (xy 214.910335 -178.82094) (xy 214.96263 -178.836295) (xy 215.012207 -178.858937)
			(xy 215.058057 -178.888403) (xy 215.099248 -178.924094) (xy 215.134939 -178.965285) (xy 215.164405 -179.011135)
			(xy 215.187047 -179.060712) (xy 215.202402 -179.113007) (xy 215.210158 -179.166955) (xy 215.210644 -179.194206)
			(xy 215.210112 -179.222944) (xy 215.20149 -179.279771) (xy 215.184441 -179.334661) (xy 215.159351 -179.386373)
			(xy 215.126789 -179.433736) (xy 215.10752 -179.455064) (xy 215.100916 -179.461922) (xy 215.093804 -179.479956)
			(xy 215.093804 -179.568856) (xy 215.100916 -179.58689) (xy 215.10752 -179.593748) (xy 215.126787 -179.615079)
			(xy 215.143908 -179.639976) (xy 217.55049 -179.639976) (xy 217.554561 -179.584354) (xy 217.566687 -179.529917)
			(xy 217.58661 -179.477826) (xy 217.613906 -179.429191) (xy 217.647992 -179.385048) (xy 217.688141 -179.346339)
			(xy 217.733499 -179.313888) (xy 217.783099 -179.288387) (xy 217.835883 -179.27038) (xy 217.890726 -179.26025)
			(xy 217.94646 -179.258213) (xy 218.001897 -179.264313) (xy 218.055854 -179.278419) (xy 218.107183 -179.300231)
			(xy 218.154789 -179.329285) (xy 218.197657 -179.36496) (xy 218.234874 -179.406497) (xy 218.265647 -179.45301)
			(xy 218.289319 -179.503507) (xy 218.305387 -179.556914) (xy 218.313507 -179.61209) (xy 218.314016 -179.639976)
			(xy 218.313507 -179.667862) (xy 218.305387 -179.723038) (xy 218.289319 -179.776445) (xy 218.265647 -179.826942)
			(xy 218.234874 -179.873455) (xy 218.197657 -179.914992) (xy 218.154789 -179.950667) (xy 218.107183 -179.979721)
			(xy 218.055854 -180.001533) (xy 218.001897 -180.015639) (xy 217.94646 -180.021739) (xy 217.890726 -180.019702)
			(xy 217.835883 -180.009572) (xy 217.783099 -179.991565) (xy 217.733499 -179.966064) (xy 217.688141 -179.933613)
			(xy 217.647992 -179.894904) (xy 217.613906 -179.850761) (xy 217.58661 -179.802126) (xy 217.566687 -179.750035)
			(xy 217.554561 -179.695598) (xy 217.55049 -179.639976) (xy 215.143908 -179.639976) (xy 215.159355 -179.662439)
			(xy 215.184449 -179.71415) (xy 215.2015 -179.76904) (xy 215.210123 -179.825867) (xy 215.210644 -179.854606)
			(xy 215.210182 -179.881207) (xy 215.202806 -179.933894) (xy 215.188183 -179.985045) (xy 215.166598 -180.03367)
			(xy 215.138468 -180.078826) (xy 215.104338 -180.119637) (xy 215.084914 -180.137816) (xy 215.076786 -180.145182)
			(xy 215.067896 -180.165502) (xy 215.070182 -180.264562) (xy 215.079834 -180.284374) (xy 215.08847 -180.291486)
			(xy 215.109808 -180.309687) (xy 215.147418 -180.35129) (xy 215.178527 -180.397954) (xy 215.202463 -180.448673)
			(xy 215.216544 -180.495194) (xy 219.951552 -180.495194) (xy 219.955623 -180.439572) (xy 219.967749 -180.385135)
			(xy 219.987672 -180.333044) (xy 220.014968 -180.284409) (xy 220.049054 -180.240266) (xy 220.089203 -180.201557)
			(xy 220.134561 -180.169106) (xy 220.184161 -180.143605) (xy 220.236945 -180.125598) (xy 220.291788 -180.115468)
			(xy 220.347522 -180.113431) (xy 220.402959 -180.119531) (xy 220.456916 -180.133637) (xy 220.508245 -180.155449)
			(xy 220.555851 -180.184503) (xy 220.598719 -180.220178) (xy 220.635936 -180.261715) (xy 220.666709 -180.308228)
			(xy 220.690381 -180.358725) (xy 220.706449 -180.412132) (xy 220.714569 -180.467308) (xy 220.715078 -180.495194)
			(xy 220.714569 -180.52308) (xy 220.706449 -180.578256) (xy 220.690381 -180.631663) (xy 220.666709 -180.68216)
			(xy 220.635936 -180.728673) (xy 220.598719 -180.77021) (xy 220.555851 -180.805885) (xy 220.508245 -180.834939)
			(xy 220.456916 -180.856751) (xy 220.402959 -180.870857) (xy 220.347522 -180.876957) (xy 220.291788 -180.87492)
			(xy 220.236945 -180.86479) (xy 220.184161 -180.846783) (xy 220.134561 -180.821282) (xy 220.089203 -180.788831)
			(xy 220.049054 -180.750122) (xy 220.014968 -180.705979) (xy 219.987672 -180.657344) (xy 219.967749 -180.605253)
			(xy 219.955623 -180.550816) (xy 219.951552 -180.495194) (xy 215.216544 -180.495194) (xy 215.21871 -180.502351)
			(xy 215.226916 -180.55783) (xy 215.227408 -180.585872) (xy 215.227408 -180.586126) (xy 215.226922 -180.613377)
			(xy 215.219166 -180.667325) (xy 215.203811 -180.71962) (xy 215.181169 -180.769197) (xy 215.151703 -180.815047)
			(xy 215.116012 -180.856238) (xy 215.074821 -180.891929) (xy 215.028971 -180.921395) (xy 214.979394 -180.944037)
			(xy 214.927099 -180.959392) (xy 214.873151 -180.967148) (xy 214.818649 -180.967148) (xy 214.764701 -180.959392)
			(xy 214.712406 -180.944037) (xy 214.662829 -180.921395) (xy 214.616979 -180.891929) (xy 214.575788 -180.856238)
			(xy 214.540097 -180.815047) (xy 214.510631 -180.769197) (xy 214.487989 -180.71962) (xy 214.472634 -180.667325)
			(xy 214.464878 -180.613377) (xy 214.464392 -180.586126) (xy 214.464863 -180.559526) (xy 214.472236 -180.506839)
			(xy 214.486856 -180.455687) (xy 214.50844 -180.407061) (xy 214.536569 -180.361906) (xy 214.570698 -180.321095)
			(xy 214.590122 -180.302916) (xy 214.59825 -180.29555) (xy 214.60714 -180.27523) (xy 214.604854 -180.17617)
			(xy 214.595202 -180.156358) (xy 214.586566 -180.149246) (xy 214.565251 -180.131019) (xy 214.527638 -180.089423)
			(xy 214.496525 -180.042764) (xy 214.472584 -179.992051) (xy 214.456333 -179.938376) (xy 214.448122 -179.8829)
			(xy 214.447628 -179.85486) (xy 207.448455 -179.85486) (xy 207.393974 -180.477668) (xy 208.830162 -180.477668)
			(xy 208.834233 -180.422046) (xy 208.846359 -180.367609) (xy 208.866282 -180.315518) (xy 208.893578 -180.266883)
			(xy 208.927664 -180.22274) (xy 208.967813 -180.184031) (xy 209.013171 -180.15158) (xy 209.062771 -180.126079)
			(xy 209.115555 -180.108072) (xy 209.170398 -180.097942) (xy 209.226132 -180.095905) (xy 209.281569 -180.102005)
			(xy 209.335526 -180.116111) (xy 209.386855 -180.137923) (xy 209.434461 -180.166977) (xy 209.477329 -180.202652)
			(xy 209.513683 -180.243226) (xy 211.981794 -180.243226) (xy 211.985865 -180.187604) (xy 211.997991 -180.133167)
			(xy 212.017914 -180.081076) (xy 212.04521 -180.032441) (xy 212.079296 -179.988298) (xy 212.119445 -179.949589)
			(xy 212.164803 -179.917138) (xy 212.214403 -179.891637) (xy 212.267187 -179.87363) (xy 212.32203 -179.8635)
			(xy 212.377764 -179.861463) (xy 212.433201 -179.867563) (xy 212.487158 -179.881669) (xy 212.538487 -179.903481)
			(xy 212.586093 -179.932535) (xy 212.628961 -179.96821) (xy 212.666178 -180.009747) (xy 212.696951 -180.05626)
			(xy 212.720623 -180.106757) (xy 212.736691 -180.160164) (xy 212.744811 -180.21534) (xy 212.74532 -180.243226)
			(xy 212.744811 -180.271112) (xy 212.736691 -180.326288) (xy 212.720623 -180.379695) (xy 212.696951 -180.430192)
			(xy 212.666178 -180.476705) (xy 212.628961 -180.518242) (xy 212.586093 -180.553917) (xy 212.538487 -180.582971)
			(xy 212.487158 -180.604783) (xy 212.433201 -180.618889) (xy 212.377764 -180.624989) (xy 212.32203 -180.622952)
			(xy 212.267187 -180.612822) (xy 212.214403 -180.594815) (xy 212.164803 -180.569314) (xy 212.119445 -180.536863)
			(xy 212.079296 -180.498154) (xy 212.04521 -180.454011) (xy 212.017914 -180.405376) (xy 211.997991 -180.353285)
			(xy 211.985865 -180.298848) (xy 211.981794 -180.243226) (xy 209.513683 -180.243226) (xy 209.514546 -180.244189)
			(xy 209.545319 -180.290702) (xy 209.568991 -180.341199) (xy 209.585059 -180.394606) (xy 209.593179 -180.449782)
			(xy 209.593688 -180.477668) (xy 209.593179 -180.505554) (xy 209.585059 -180.56073) (xy 209.568991 -180.614137)
			(xy 209.545319 -180.664634) (xy 209.514546 -180.711147) (xy 209.477329 -180.752684) (xy 209.434461 -180.788359)
			(xy 209.386855 -180.817413) (xy 209.335526 -180.839225) (xy 209.281569 -180.853331) (xy 209.226132 -180.859431)
			(xy 209.170398 -180.857394) (xy 209.115555 -180.847264) (xy 209.062771 -180.829257) (xy 209.013171 -180.803756)
			(xy 208.967813 -180.771305) (xy 208.927664 -180.732596) (xy 208.893578 -180.688453) (xy 208.866282 -180.639818)
			(xy 208.846359 -180.587727) (xy 208.834233 -180.53329) (xy 208.830162 -180.477668) (xy 207.393974 -180.477668)
			(xy 207.322806 -181.29123) (xy 211.95868 -181.29123) (xy 211.962751 -181.235608) (xy 211.974877 -181.181171)
			(xy 211.9948 -181.12908) (xy 212.022096 -181.080445) (xy 212.056182 -181.036302) (xy 212.096331 -180.997593)
			(xy 212.141689 -180.965142) (xy 212.191289 -180.939641) (xy 212.244073 -180.921634) (xy 212.298916 -180.911504)
			(xy 212.35465 -180.909467) (xy 212.410087 -180.915567) (xy 212.464044 -180.929673) (xy 212.515373 -180.951485)
			(xy 212.562979 -180.980539) (xy 212.605847 -181.016214) (xy 212.643064 -181.057751) (xy 212.673837 -181.104264)
			(xy 212.697509 -181.154761) (xy 212.713577 -181.208168) (xy 212.721697 -181.263344) (xy 212.722206 -181.29123)
			(xy 212.721697 -181.319116) (xy 212.713577 -181.374292) (xy 212.697509 -181.427699) (xy 212.673837 -181.478196)
			(xy 212.643064 -181.524709) (xy 212.605847 -181.566246) (xy 212.562979 -181.601921) (xy 212.515373 -181.630975)
			(xy 212.464044 -181.652787) (xy 212.410087 -181.666893) (xy 212.35465 -181.672993) (xy 212.298916 -181.670956)
			(xy 212.244073 -181.660826) (xy 212.191289 -181.642819) (xy 212.141689 -181.617318) (xy 212.096331 -181.584867)
			(xy 212.056182 -181.546158) (xy 212.022096 -181.502015) (xy 211.9948 -181.45338) (xy 211.974877 -181.401289)
			(xy 211.962751 -181.346852) (xy 211.95868 -181.29123) (xy 207.322806 -181.29123) (xy 207.259614 -182.013606)
			(xy 210.383118 -182.013606) (xy 210.387189 -181.957984) (xy 210.399315 -181.903547) (xy 210.419238 -181.851456)
			(xy 210.446534 -181.802821) (xy 210.48062 -181.758678) (xy 210.520769 -181.719969) (xy 210.566127 -181.687518)
			(xy 210.615727 -181.662017) (xy 210.668511 -181.64401) (xy 210.723354 -181.63388) (xy 210.779088 -181.631843)
			(xy 210.834525 -181.637943) (xy 210.888482 -181.652049) (xy 210.939811 -181.673861) (xy 210.987417 -181.702915)
			(xy 211.030285 -181.73859) (xy 211.067502 -181.780127) (xy 211.098275 -181.82664) (xy 211.121947 -181.877137)
			(xy 211.138015 -181.930544) (xy 211.146135 -181.98572) (xy 211.146644 -182.013606) (xy 214.447118 -182.013606)
			(xy 214.451189 -181.957984) (xy 214.463315 -181.903547) (xy 214.483238 -181.851456) (xy 214.510534 -181.802821)
			(xy 214.54462 -181.758678) (xy 214.584769 -181.719969) (xy 214.630127 -181.687518) (xy 214.679727 -181.662017)
			(xy 214.732511 -181.64401) (xy 214.787354 -181.63388) (xy 214.843088 -181.631843) (xy 214.898525 -181.637943)
			(xy 214.952482 -181.652049) (xy 215.003811 -181.673861) (xy 215.051417 -181.702915) (xy 215.094285 -181.73859)
			(xy 215.131502 -181.780127) (xy 215.162275 -181.82664) (xy 215.185947 -181.877137) (xy 215.202015 -181.930544)
			(xy 215.210135 -181.98572) (xy 215.210644 -182.013606) (xy 215.210135 -182.041492) (xy 215.202015 -182.096668)
			(xy 215.185947 -182.150075) (xy 215.162275 -182.200572) (xy 215.131502 -182.247085) (xy 215.094285 -182.288622)
			(xy 215.051417 -182.324297) (xy 215.003811 -182.353351) (xy 214.952482 -182.375163) (xy 214.898525 -182.389269)
			(xy 214.843088 -182.395369) (xy 214.787354 -182.393332) (xy 214.732511 -182.383202) (xy 214.679727 -182.365195)
			(xy 214.630127 -182.339694) (xy 214.584769 -182.307243) (xy 214.54462 -182.268534) (xy 214.510534 -182.224391)
			(xy 214.483238 -182.175756) (xy 214.463315 -182.123665) (xy 214.451189 -182.069228) (xy 214.447118 -182.013606)
			(xy 211.146644 -182.013606) (xy 211.146135 -182.041492) (xy 211.138015 -182.096668) (xy 211.121947 -182.150075)
			(xy 211.098275 -182.200572) (xy 211.067502 -182.247085) (xy 211.030285 -182.288622) (xy 210.987417 -182.324297)
			(xy 210.939811 -182.353351) (xy 210.888482 -182.375163) (xy 210.834525 -182.389269) (xy 210.779088 -182.395369)
			(xy 210.723354 -182.393332) (xy 210.668511 -182.383202) (xy 210.615727 -182.365195) (xy 210.566127 -182.339694)
			(xy 210.520769 -182.307243) (xy 210.48062 -182.268534) (xy 210.446534 -182.224391) (xy 210.419238 -182.175756)
			(xy 210.399315 -182.123665) (xy 210.387189 -182.069228) (xy 210.383118 -182.013606) (xy 207.259614 -182.013606)
			(xy 207.091748 -183.932576) (xy 207.46796 -183.932576) (xy 207.472031 -183.876954) (xy 207.484157 -183.822517)
			(xy 207.50408 -183.770426) (xy 207.531376 -183.721791) (xy 207.565462 -183.677648) (xy 207.605611 -183.638939)
			(xy 207.650969 -183.606488) (xy 207.700569 -183.580987) (xy 207.753353 -183.56298) (xy 207.808196 -183.55285)
			(xy 207.86393 -183.550813) (xy 207.919367 -183.556913) (xy 207.924213 -183.55818) (xy 217.546426 -183.55818)
			(xy 217.550497 -183.502558) (xy 217.562623 -183.448121) (xy 217.582546 -183.39603) (xy 217.609842 -183.347395)
			(xy 217.643928 -183.303252) (xy 217.684077 -183.264543) (xy 217.729435 -183.232092) (xy 217.779035 -183.206591)
			(xy 217.831819 -183.188584) (xy 217.886662 -183.178454) (xy 217.942396 -183.176417) (xy 217.997833 -183.182517)
			(xy 218.05179 -183.196623) (xy 218.103119 -183.218435) (xy 218.150725 -183.247489) (xy 218.193593 -183.283164)
			(xy 218.23081 -183.324701) (xy 218.261583 -183.371214) (xy 218.285255 -183.421711) (xy 218.301323 -183.475118)
			(xy 218.309443 -183.530294) (xy 218.309952 -183.55818) (xy 218.309443 -183.586066) (xy 218.301323 -183.641242)
			(xy 218.285255 -183.694649) (xy 218.261583 -183.745146) (xy 218.23081 -183.791659) (xy 218.193593 -183.833196)
			(xy 218.150725 -183.868871) (xy 218.103119 -183.897925) (xy 218.05179 -183.919737) (xy 217.997833 -183.933843)
			(xy 217.942396 -183.939943) (xy 217.886662 -183.937906) (xy 217.831819 -183.927776) (xy 217.779035 -183.909769)
			(xy 217.729435 -183.884268) (xy 217.684077 -183.851817) (xy 217.643928 -183.813108) (xy 217.609842 -183.768965)
			(xy 217.582546 -183.72033) (xy 217.562623 -183.668239) (xy 217.550497 -183.613802) (xy 217.546426 -183.55818)
			(xy 207.924213 -183.55818) (xy 207.973324 -183.571019) (xy 208.024653 -183.592831) (xy 208.072259 -183.621885)
			(xy 208.115127 -183.65756) (xy 208.152344 -183.699097) (xy 208.183117 -183.74561) (xy 208.206789 -183.796107)
			(xy 208.222857 -183.849514) (xy 208.230977 -183.90469) (xy 208.231486 -183.932576) (xy 208.230977 -183.960462)
			(xy 208.222857 -184.015638) (xy 208.206789 -184.069045) (xy 208.183117 -184.119542) (xy 208.152344 -184.166055)
			(xy 208.115127 -184.207592) (xy 208.072259 -184.243267) (xy 208.024653 -184.272321) (xy 207.973324 -184.294133)
			(xy 207.919367 -184.308239) (xy 207.86393 -184.314339) (xy 207.808196 -184.312302) (xy 207.753353 -184.302172)
			(xy 207.700569 -184.284165) (xy 207.650969 -184.258664) (xy 207.605611 -184.226213) (xy 207.565462 -184.187504)
			(xy 207.531376 -184.143361) (xy 207.50408 -184.094726) (xy 207.484157 -184.042635) (xy 207.472031 -183.988198)
			(xy 207.46796 -183.932576) (xy 207.091748 -183.932576) (xy 207.022791 -184.720857) (xy 208.300715 -184.720857)
			(xy 208.300715 -184.666343) (xy 208.308474 -184.612384) (xy 208.323833 -184.560078) (xy 208.34648 -184.510491)
			(xy 208.375953 -184.464632) (xy 208.411654 -184.423434) (xy 208.452854 -184.387736) (xy 208.498716 -184.358266)
			(xy 208.548305 -184.335623) (xy 208.600611 -184.320268) (xy 208.654571 -184.312513) (xy 208.681828 -184.312052)
			(xy 208.709343 -184.312556) (xy 208.763802 -184.320465) (xy 208.816561 -184.336113) (xy 208.866525 -184.359177)
			(xy 208.889854 -184.373774) (xy 208.899506 -184.37987) (xy 208.921858 -184.382918) (xy 209.018886 -184.352184)
			(xy 209.035396 -184.33669) (xy 209.039714 -184.326022) (xy 209.050628 -184.29972) (xy 209.079229 -184.250476)
			(xy 209.114833 -184.206033) (xy 209.15665 -184.167377) (xy 209.203748 -184.135367) (xy 209.255083 -184.110716)
			(xy 209.309511 -184.093971) (xy 209.365825 -184.085504) (xy 209.394298 -184.084976) (xy 209.42155 -184.085471)
			(xy 209.475499 -184.093228) (xy 209.527795 -184.108583) (xy 209.577373 -184.131224) (xy 209.623224 -184.160691)
			(xy 209.664415 -184.196383) (xy 209.700108 -184.237574) (xy 209.729575 -184.283425) (xy 209.752217 -184.333004)
			(xy 209.767572 -184.385299) (xy 209.775329 -184.439248) (xy 209.775329 -184.493752) (xy 209.767572 -184.547701)
			(xy 209.752217 -184.599996) (xy 209.729575 -184.649575) (xy 209.700108 -184.695426) (xy 209.664415 -184.736617)
			(xy 209.623224 -184.772309) (xy 209.577373 -184.801776) (xy 209.527795 -184.824417) (xy 209.475499 -184.839772)
			(xy 209.42155 -184.847529) (xy 209.394298 -184.847992) (xy 209.366782 -184.847516) (xy 209.312322 -184.839598)
			(xy 209.259563 -184.823941) (xy 209.2096 -184.80087) (xy 209.186272 -184.78627) (xy 209.17662 -184.780174)
			(xy 209.154268 -184.777126) (xy 209.05724 -184.80786) (xy 209.04073 -184.823354) (xy 209.036412 -184.834022)
			(xy 209.025447 -184.860302) (xy 208.996855 -184.909546) (xy 208.96126 -184.953992) (xy 208.919451 -184.99265)
			(xy 208.87236 -185.024663) (xy 208.821032 -185.049318) (xy 208.766608 -185.066067) (xy 208.710299 -185.074538)
			(xy 208.681828 -185.075068) (xy 208.654571 -185.074687) (xy 208.600611 -185.066932) (xy 208.548305 -185.051577)
			(xy 208.498716 -185.028934) (xy 208.452854 -184.999464) (xy 208.411654 -184.963766) (xy 208.375953 -184.922568)
			(xy 208.34648 -184.876709) (xy 208.323833 -184.827122) (xy 208.308474 -184.774816) (xy 208.300715 -184.720857)
			(xy 207.022791 -184.720857) (xy 206.972408 -185.29681) (xy 206.981044 -185.318908) (xy 206.98968 -185.326782)
			(xy 207.008706 -185.344924) (xy 207.042095 -185.385531) (xy 207.069594 -185.430337) (xy 207.090681 -185.478494)
			(xy 207.104958 -185.52909) (xy 207.112154 -185.581166) (xy 207.112616 -185.607452) (xy 207.112147 -185.63475)
			(xy 207.104359 -185.688787) (xy 207.08895 -185.741162) (xy 207.066235 -185.790807) (xy 207.036676 -185.836709)
			(xy 207.000878 -185.87793) (xy 206.959572 -185.913628) (xy 206.936848 -185.928762) (xy 206.926942 -185.935112)
			(xy 206.915004 -185.955178) (xy 206.752444 -187.809886) (xy 206.772256 -187.839604) (xy 206.789274 -187.844938)
			(xy 206.814699 -187.853458) (xy 206.843035 -187.867036) (xy 207.844134 -187.867036) (xy 207.848205 -187.811414)
			(xy 207.860331 -187.756977) (xy 207.880254 -187.704886) (xy 207.90755 -187.656251) (xy 207.941636 -187.612108)
			(xy 207.981785 -187.573399) (xy 208.027143 -187.540948) (xy 208.076743 -187.515447) (xy 208.129527 -187.49744)
			(xy 208.18437 -187.48731) (xy 208.240104 -187.485273) (xy 208.295541 -187.491373) (xy 208.349498 -187.505479)
			(xy 208.400827 -187.527291) (xy 208.448433 -187.556345) (xy 208.491301 -187.59202) (xy 208.528518 -187.633557)
			(xy 208.534435 -187.6425) (xy 210.560918 -187.6425) (xy 210.564989 -187.586878) (xy 210.577115 -187.532441)
			(xy 210.597038 -187.48035) (xy 210.624334 -187.431715) (xy 210.65842 -187.387572) (xy 210.698569 -187.348863)
			(xy 210.743927 -187.316412) (xy 210.793527 -187.290911) (xy 210.846311 -187.272904) (xy 210.901154 -187.262774)
			(xy 210.956888 -187.260737) (xy 211.012325 -187.266837) (xy 211.066282 -187.280943) (xy 211.117611 -187.302755)
			(xy 211.165217 -187.331809) (xy 211.208085 -187.367484) (xy 211.245302 -187.409021) (xy 211.276075 -187.455534)
			(xy 211.299747 -187.506031) (xy 211.315815 -187.559438) (xy 211.323935 -187.614614) (xy 211.324444 -187.6425)
			(xy 211.324439 -187.642754) (xy 212.143084 -187.642754) (xy 212.147155 -187.587132) (xy 212.159281 -187.532695)
			(xy 212.179204 -187.480604) (xy 212.2065 -187.431969) (xy 212.240586 -187.387826) (xy 212.280735 -187.349117)
			(xy 212.326093 -187.316666) (xy 212.375693 -187.291165) (xy 212.428477 -187.273158) (xy 212.48332 -187.263028)
			(xy 212.539054 -187.260991) (xy 212.594491 -187.267091) (xy 212.648448 -187.281197) (xy 212.699777 -187.303009)
			(xy 212.747383 -187.332063) (xy 212.790251 -187.367738) (xy 212.827468 -187.409275) (xy 212.858241 -187.455788)
			(xy 212.881913 -187.506285) (xy 212.897981 -187.559692) (xy 212.906101 -187.614868) (xy 212.906605 -187.6425)
			(xy 214.624918 -187.6425) (xy 214.628989 -187.586878) (xy 214.641115 -187.532441) (xy 214.661038 -187.48035)
			(xy 214.688334 -187.431715) (xy 214.72242 -187.387572) (xy 214.762569 -187.348863) (xy 214.807927 -187.316412)
			(xy 214.857527 -187.290911) (xy 214.910311 -187.272904) (xy 214.965154 -187.262774) (xy 215.020888 -187.260737)
			(xy 215.076325 -187.266837) (xy 215.130282 -187.280943) (xy 215.181611 -187.302755) (xy 215.229217 -187.331809)
			(xy 215.272085 -187.367484) (xy 215.309302 -187.409021) (xy 215.340075 -187.455534) (xy 215.363747 -187.506031)
			(xy 215.379815 -187.559438) (xy 215.387665 -187.612782) (xy 216.656918 -187.612782) (xy 216.660989 -187.55716)
			(xy 216.673115 -187.502723) (xy 216.693038 -187.450632) (xy 216.720334 -187.401997) (xy 216.75442 -187.357854)
			(xy 216.794569 -187.319145) (xy 216.839927 -187.286694) (xy 216.889527 -187.261193) (xy 216.942311 -187.243186)
			(xy 216.997154 -187.233056) (xy 217.052888 -187.231019) (xy 217.108325 -187.237119) (xy 217.162282 -187.251225)
			(xy 217.213611 -187.273037) (xy 217.261217 -187.302091) (xy 217.304085 -187.337766) (xy 217.341302 -187.379303)
			(xy 217.372075 -187.425816) (xy 217.395747 -187.476313) (xy 217.411815 -187.52972) (xy 217.419935 -187.584896)
			(xy 217.420444 -187.612782) (xy 217.419935 -187.640668) (xy 217.411815 -187.695844) (xy 217.395747 -187.749251)
			(xy 217.372075 -187.799748) (xy 217.341302 -187.846261) (xy 217.304085 -187.887798) (xy 217.261217 -187.923473)
			(xy 217.213611 -187.952527) (xy 217.162282 -187.974339) (xy 217.108325 -187.988445) (xy 217.052888 -187.994545)
			(xy 216.997154 -187.992508) (xy 216.942311 -187.982378) (xy 216.889527 -187.964371) (xy 216.839927 -187.93887)
			(xy 216.794569 -187.906419) (xy 216.75442 -187.86771) (xy 216.720334 -187.823567) (xy 216.693038 -187.774932)
			(xy 216.673115 -187.722841) (xy 216.660989 -187.668404) (xy 216.656918 -187.612782) (xy 215.387665 -187.612782)
			(xy 215.387935 -187.614614) (xy 215.388444 -187.6425) (xy 215.387935 -187.670386) (xy 215.379815 -187.725562)
			(xy 215.363747 -187.778969) (xy 215.340075 -187.829466) (xy 215.309302 -187.875979) (xy 215.272085 -187.917516)
			(xy 215.229217 -187.953191) (xy 215.181611 -187.982245) (xy 215.130282 -188.004057) (xy 215.076325 -188.018163)
			(xy 215.020888 -188.024263) (xy 214.965154 -188.022226) (xy 214.910311 -188.012096) (xy 214.857527 -187.994089)
			(xy 214.807927 -187.968588) (xy 214.762569 -187.936137) (xy 214.72242 -187.897428) (xy 214.688334 -187.853285)
			(xy 214.661038 -187.80465) (xy 214.641115 -187.752559) (xy 214.628989 -187.698122) (xy 214.624918 -187.6425)
			(xy 212.906605 -187.6425) (xy 212.90661 -187.642754) (xy 212.906101 -187.67064) (xy 212.897981 -187.725816)
			(xy 212.881913 -187.779223) (xy 212.858241 -187.82972) (xy 212.827468 -187.876233) (xy 212.790251 -187.91777)
			(xy 212.747383 -187.953445) (xy 212.699777 -187.982499) (xy 212.648448 -188.004311) (xy 212.594491 -188.018417)
			(xy 212.539054 -188.024517) (xy 212.48332 -188.02248) (xy 212.428477 -188.01235) (xy 212.375693 -187.994343)
			(xy 212.326093 -187.968842) (xy 212.280735 -187.936391) (xy 212.240586 -187.897682) (xy 212.2065 -187.853539)
			(xy 212.179204 -187.804904) (xy 212.159281 -187.752813) (xy 212.147155 -187.698376) (xy 212.143084 -187.642754)
			(xy 211.324439 -187.642754) (xy 211.323935 -187.670386) (xy 211.315815 -187.725562) (xy 211.299747 -187.778969)
			(xy 211.276075 -187.829466) (xy 211.245302 -187.875979) (xy 211.208085 -187.917516) (xy 211.165217 -187.953191)
			(xy 211.117611 -187.982245) (xy 211.066282 -188.004057) (xy 211.012325 -188.018163) (xy 210.956888 -188.024263)
			(xy 210.901154 -188.022226) (xy 210.846311 -188.012096) (xy 210.793527 -187.994089) (xy 210.743927 -187.968588)
			(xy 210.698569 -187.936137) (xy 210.65842 -187.897428) (xy 210.624334 -187.853285) (xy 210.597038 -187.80465)
			(xy 210.577115 -187.752559) (xy 210.564989 -187.698122) (xy 210.560918 -187.6425) (xy 208.534435 -187.6425)
			(xy 208.559291 -187.68007) (xy 208.582963 -187.730567) (xy 208.599031 -187.783974) (xy 208.607151 -187.83915)
			(xy 208.60766 -187.867036) (xy 208.607151 -187.894922) (xy 208.599031 -187.950098) (xy 208.582963 -188.003505)
			(xy 208.559291 -188.054002) (xy 208.528518 -188.100515) (xy 208.491301 -188.142052) (xy 208.448433 -188.177727)
			(xy 208.400827 -188.206781) (xy 208.349498 -188.228593) (xy 208.295541 -188.242699) (xy 208.240104 -188.248799)
			(xy 208.18437 -188.246762) (xy 208.129527 -188.236632) (xy 208.076743 -188.218625) (xy 208.027143 -188.193124)
			(xy 207.981785 -188.160673) (xy 207.941636 -188.121964) (xy 207.90755 -188.077821) (xy 207.880254 -188.029186)
			(xy 207.860331 -187.977095) (xy 207.848205 -187.922658) (xy 207.844134 -187.867036) (xy 206.843035 -187.867036)
			(xy 206.863056 -187.87663) (xy 206.907691 -187.906345) (xy 206.947727 -187.942016) (xy 206.982373 -187.982942)
			(xy 207.010947 -188.028316) (xy 207.032887 -188.077244) (xy 207.04776 -188.128762) (xy 207.055273 -188.181855)
			(xy 207.05572 -188.208666) (xy 207.055238 -188.236118) (xy 207.047358 -188.290454) (xy 207.031771 -188.3431)
			(xy 207.008798 -188.392967) (xy 206.978915 -188.439026) (xy 206.942737 -188.480326) (xy 206.901013 -188.516014)
			(xy 206.854604 -188.545352) (xy 206.804469 -188.567734) (xy 206.751643 -188.582699) (xy 206.724504 -188.586872)
			(xy 206.713141 -188.588914) (xy 206.693872 -188.601589) (xy 206.682065 -188.621401) (xy 206.680562 -188.632846)
			(xy 206.679546 -188.643514) (xy 206.70767 -188.646534) (xy 206.762651 -188.659816) (xy 206.815069 -188.681071)
			(xy 206.863773 -188.709832) (xy 206.907697 -188.745469) (xy 206.945877 -188.787202) (xy 206.977478 -188.834114)
			(xy 207.001804 -188.885178) (xy 207.018325 -188.939274) (xy 207.026677 -188.995217) (xy 207.027272 -189.023498)
			(xy 207.026779 -189.051145) (xy 207.018788 -189.105858) (xy 207.018352 -189.107318) (xy 217.854528 -189.107318)
			(xy 217.858599 -189.051696) (xy 217.870725 -188.997259) (xy 217.890648 -188.945168) (xy 217.917944 -188.896533)
			(xy 217.95203 -188.85239) (xy 217.992179 -188.813681) (xy 218.037537 -188.78123) (xy 218.087137 -188.755729)
			(xy 218.139921 -188.737722) (xy 218.194764 -188.727592) (xy 218.250498 -188.725555) (xy 218.305935 -188.731655)
			(xy 218.359892 -188.745761) (xy 218.411221 -188.767573) (xy 218.458827 -188.796627) (xy 218.501695 -188.832302)
			(xy 218.538912 -188.873839) (xy 218.569685 -188.920352) (xy 218.593357 -188.970849) (xy 218.609425 -189.024256)
			(xy 218.617545 -189.079432) (xy 218.618054 -189.107318) (xy 218.617545 -189.135204) (xy 218.609425 -189.19038)
			(xy 218.593357 -189.243787) (xy 218.569685 -189.294284) (xy 218.538912 -189.340797) (xy 218.501695 -189.382334)
			(xy 218.458827 -189.418009) (xy 218.411221 -189.447063) (xy 218.359892 -189.468875) (xy 218.305935 -189.482981)
			(xy 218.250498 -189.489081) (xy 218.194764 -189.487044) (xy 218.139921 -189.476914) (xy 218.087137 -189.458907)
			(xy 218.037537 -189.433406) (xy 217.992179 -189.400955) (xy 217.95203 -189.362246) (xy 217.917944 -189.318103)
			(xy 217.890648 -189.269468) (xy 217.870725 -189.217377) (xy 217.858599 -189.16294) (xy 217.854528 -189.107318)
			(xy 207.018352 -189.107318) (xy 207.002973 -189.158841) (xy 206.979667 -189.208983) (xy 206.94936 -189.25523)
			(xy 206.912686 -189.296611) (xy 206.89189 -189.314836) (xy 206.888334 -189.318138) (xy 206.881058 -189.32631)
			(xy 206.87364 -189.346873) (xy 206.875457 -189.368657) (xy 206.886177 -189.387707) (xy 206.894684 -189.394592)
			(xy 206.918237 -189.412725) (xy 206.959962 -189.455056) (xy 206.994625 -189.50334) (xy 207.02139 -189.556412)
			(xy 207.03961 -189.612989) (xy 207.048845 -189.671705) (xy 207.04937 -189.701424) (xy 207.048883 -189.728662)
			(xy 207.042902 -189.770258) (xy 209.545428 -189.770258) (xy 209.545914 -189.743007) (xy 209.55367 -189.689059)
			(xy 209.569025 -189.636764) (xy 209.591667 -189.587187) (xy 209.621133 -189.541337) (xy 209.656824 -189.500146)
			(xy 209.698015 -189.464455) (xy 209.743865 -189.434989) (xy 209.793442 -189.412347) (xy 209.845737 -189.396992)
			(xy 209.899685 -189.389236) (xy 209.954187 -189.389236) (xy 210.008135 -189.396992) (xy 210.06043 -189.412347)
			(xy 210.110007 -189.434989) (xy 210.155857 -189.464455) (xy 210.197048 -189.500146) (xy 210.232739 -189.541337)
			(xy 210.262205 -189.587187) (xy 210.284847 -189.636764) (xy 210.292273 -189.662054) (xy 212.592918 -189.662054)
			(xy 212.596989 -189.606432) (xy 212.609115 -189.551995) (xy 212.629038 -189.499904) (xy 212.656334 -189.451269)
			(xy 212.69042 -189.407126) (xy 212.730569 -189.368417) (xy 212.775927 -189.335966) (xy 212.825527 -189.310465)
			(xy 212.878311 -189.292458) (xy 212.933154 -189.282328) (xy 212.988888 -189.280291) (xy 213.044325 -189.286391)
			(xy 213.098282 -189.300497) (xy 213.149611 -189.322309) (xy 213.197217 -189.351363) (xy 213.240085 -189.387038)
			(xy 213.277302 -189.428575) (xy 213.308075 -189.475088) (xy 213.331747 -189.525585) (xy 213.347815 -189.578992)
			(xy 213.355935 -189.634168) (xy 213.356444 -189.662054) (xy 216.656918 -189.662054) (xy 216.660989 -189.606432)
			(xy 216.673115 -189.551995) (xy 216.693038 -189.499904) (xy 216.720334 -189.451269) (xy 216.75442 -189.407126)
			(xy 216.794569 -189.368417) (xy 216.839927 -189.335966) (xy 216.889527 -189.310465) (xy 216.942311 -189.292458)
			(xy 216.997154 -189.282328) (xy 217.052888 -189.280291) (xy 217.108325 -189.286391) (xy 217.162282 -189.300497)
			(xy 217.213611 -189.322309) (xy 217.261217 -189.351363) (xy 217.304085 -189.387038) (xy 217.341302 -189.428575)
			(xy 217.372075 -189.475088) (xy 217.395747 -189.525585) (xy 217.411815 -189.578992) (xy 217.419935 -189.634168)
			(xy 217.420444 -189.662054) (xy 217.419935 -189.68994) (xy 217.411815 -189.745116) (xy 217.395747 -189.798523)
			(xy 217.372075 -189.84902) (xy 217.341302 -189.895533) (xy 217.304085 -189.93707) (xy 217.261217 -189.972745)
			(xy 217.213611 -190.001799) (xy 217.162282 -190.023611) (xy 217.108325 -190.037717) (xy 217.052888 -190.043817)
			(xy 216.997154 -190.04178) (xy 216.942311 -190.03165) (xy 216.889527 -190.013643) (xy 216.839927 -189.988142)
			(xy 216.794569 -189.955691) (xy 216.75442 -189.916982) (xy 216.720334 -189.872839) (xy 216.693038 -189.824204)
			(xy 216.673115 -189.772113) (xy 216.660989 -189.717676) (xy 216.656918 -189.662054) (xy 213.356444 -189.662054)
			(xy 213.355935 -189.68994) (xy 213.347815 -189.745116) (xy 213.331747 -189.798523) (xy 213.308075 -189.84902)
			(xy 213.277302 -189.895533) (xy 213.240085 -189.93707) (xy 213.197217 -189.972745) (xy 213.149611 -190.001799)
			(xy 213.098282 -190.023611) (xy 213.044325 -190.037717) (xy 212.988888 -190.043817) (xy 212.933154 -190.04178)
			(xy 212.878311 -190.03165) (xy 212.825527 -190.013643) (xy 212.775927 -189.988142) (xy 212.730569 -189.955691)
			(xy 212.69042 -189.916982) (xy 212.656334 -189.872839) (xy 212.629038 -189.824204) (xy 212.609115 -189.772113)
			(xy 212.596989 -189.717676) (xy 212.592918 -189.662054) (xy 210.292273 -189.662054) (xy 210.300202 -189.689059)
			(xy 210.307958 -189.743007) (xy 210.308444 -189.770258) (xy 210.308444 -189.770512) (xy 210.307938 -189.7986)
			(xy 210.299678 -189.854166) (xy 210.283369 -189.907922) (xy 210.259362 -189.95871) (xy 210.244182 -189.982348)
			(xy 210.236955 -189.993771) (xy 210.228304 -190.019373) (xy 210.226688 -190.046349) (xy 210.232221 -190.072801)
			(xy 210.244513 -190.096868) (xy 210.2627 -190.116856) (xy 210.285503 -190.13136) (xy 210.298284 -190.135764)
			(xy 210.323855 -190.144172) (xy 210.372506 -190.167208) (xy 210.417433 -190.196857) (xy 210.457744 -190.232529)
			(xy 210.492638 -190.273517) (xy 210.52142 -190.319004) (xy 210.543519 -190.368087) (xy 210.558496 -190.41979)
			(xy 210.566052 -190.473086) (xy 210.566508 -190.5) (xy 210.566022 -190.527251) (xy 210.558266 -190.581199)
			(xy 210.542911 -190.633494) (xy 210.520269 -190.683071) (xy 210.490803 -190.728921) (xy 210.455112 -190.770112)
			(xy 210.413921 -190.805803) (xy 210.368071 -190.835269) (xy 210.318494 -190.857911) (xy 210.266199 -190.873266)
			(xy 210.212251 -190.881022) (xy 210.157749 -190.881022) (xy 210.103801 -190.873266) (xy 210.051506 -190.857911)
			(xy 210.001929 -190.835269) (xy 209.956079 -190.805803) (xy 209.914888 -190.770112) (xy 209.879197 -190.728921)
			(xy 209.849731 -190.683071) (xy 209.827089 -190.633494) (xy 209.811734 -190.581199) (xy 209.803978 -190.527251)
			(xy 209.803492 -190.5) (xy 209.803492 -190.499746) (xy 209.80402 -190.471659) (xy 209.812272 -190.416094)
			(xy 209.828574 -190.362337) (xy 209.852576 -190.311548) (xy 209.867754 -190.28791) (xy 209.874891 -190.276436)
			(xy 209.883546 -190.250851) (xy 209.88517 -190.223891) (xy 209.87965 -190.197452) (xy 209.867375 -190.173393)
			(xy 209.849207 -190.153408) (xy 209.826424 -190.138902) (xy 209.813652 -190.134494) (xy 209.788086 -190.126073)
			(xy 209.739439 -190.103035) (xy 209.694516 -190.073385) (xy 209.654207 -190.037713) (xy 209.619315 -189.996727)
			(xy 209.590532 -189.951243) (xy 209.568431 -189.902163) (xy 209.55345 -189.850464) (xy 209.545888 -189.797171)
			(xy 209.545428 -189.770258) (xy 207.042902 -189.770258) (xy 207.04113 -189.782582) (xy 207.025785 -189.834852)
			(xy 207.003161 -189.884406) (xy 206.973717 -189.930239) (xy 206.938052 -189.971416) (xy 206.896893 -190.007102)
			(xy 206.851075 -190.036569) (xy 206.801532 -190.059218) (xy 206.74927 -190.074589) (xy 206.695353 -190.082369)
			(xy 206.668116 -190.082932) (xy 206.667608 -190.082932) (xy 206.651098 -190.082678) (xy 206.641192 -190.08217)
			(xy 206.622904 -190.08852) (xy 206.562452 -190.141352) (xy 206.555435 -190.148103) (xy 206.546676 -190.165476)
			(xy 206.545434 -190.175134) (xy 206.285846 -193.142616) (xy 206.285393 -193.152269) (xy 206.290887 -193.170779)
			(xy 206.302839 -193.185944) (xy 206.310992 -193.19113) (xy 206.403702 -193.244724) (xy 206.432912 -193.243454)
			(xy 206.445104 -193.235072) (xy 206.469239 -193.218892) (xy 206.521379 -193.193253) (xy 206.576807 -193.175827)
			(xy 206.634238 -193.167019) (xy 206.66329 -193.166492) (xy 206.690543 -193.166955) (xy 206.744495 -193.17471)
			(xy 206.796794 -193.190066) (xy 206.846376 -193.212708) (xy 206.89223 -193.242175) (xy 206.933424 -193.277869)
			(xy 206.969119 -193.319062) (xy 206.998588 -193.364915) (xy 207.021231 -193.414496) (xy 207.036587 -193.466795)
			(xy 207.044345 -193.520747) (xy 207.044345 -193.575253) (xy 207.036587 -193.629205) (xy 207.021231 -193.681504)
			(xy 206.998588 -193.731085) (xy 206.969119 -193.776938) (xy 206.933424 -193.818131) (xy 206.89223 -193.853825)
			(xy 206.846376 -193.883292) (xy 206.796794 -193.905934) (xy 206.744495 -193.92129) (xy 206.690543 -193.929045)
			(xy 206.66329 -193.929508) (xy 206.633385 -193.928924) (xy 206.574307 -193.919584) (xy 206.517413 -193.901134)
			(xy 206.464097 -193.874028) (xy 206.415667 -193.83893) (xy 206.39405 -193.818256) (xy 206.383382 -193.807842)
			(xy 206.354934 -193.801492) (xy 206.254604 -193.838068) (xy 206.245654 -193.841752) (xy 206.231204 -193.854604)
			(xy 206.22256 -193.871902) (xy 206.22133 -193.881502) (xy 205.294862 -204.47) (xy 206.119982 -204.47)
			(xy 206.124053 -204.414378) (xy 206.136179 -204.359941) (xy 206.156102 -204.30785) (xy 206.183398 -204.259215)
			(xy 206.217484 -204.215072) (xy 206.257633 -204.176363) (xy 206.302991 -204.143912) (xy 206.352591 -204.118411)
			(xy 206.405375 -204.100404) (xy 206.460218 -204.090274) (xy 206.515952 -204.088237) (xy 206.571389 -204.094337)
			(xy 206.625346 -204.108443) (xy 206.676675 -204.130255) (xy 206.724281 -204.159309) (xy 206.767149 -204.194984)
			(xy 206.804366 -204.236521) (xy 206.835139 -204.283034) (xy 206.858811 -204.333531) (xy 206.874879 -204.386938)
			(xy 206.882999 -204.442114) (xy 206.883508 -204.47) (xy 206.882999 -204.497886) (xy 206.874879 -204.553062)
			(xy 206.858811 -204.606469) (xy 206.835139 -204.656966) (xy 206.804366 -204.703479) (xy 206.767149 -204.745016)
			(xy 206.724281 -204.780691) (xy 206.676675 -204.809745) (xy 206.625346 -204.831557) (xy 206.571389 -204.845663)
			(xy 206.515952 -204.851763) (xy 206.460218 -204.849726) (xy 206.405375 -204.839596) (xy 206.352591 -204.821589)
			(xy 206.302991 -204.796088) (xy 206.257633 -204.763637) (xy 206.217484 -204.724928) (xy 206.183398 -204.680785)
			(xy 206.156102 -204.63215) (xy 206.136179 -204.580059) (xy 206.124053 -204.525622) (xy 206.119982 -204.47)
			(xy 205.294862 -204.47) (xy 204.967408 -208.212436) (xy 206.122268 -208.212436) (xy 206.126339 -208.156814)
			(xy 206.138465 -208.102377) (xy 206.158388 -208.050286) (xy 206.185684 -208.001651) (xy 206.21977 -207.957508)
			(xy 206.259919 -207.918799) (xy 206.305277 -207.886348) (xy 206.354877 -207.860847) (xy 206.407661 -207.84284)
			(xy 206.462504 -207.83271) (xy 206.518238 -207.830673) (xy 206.573675 -207.836773) (xy 206.627632 -207.850879)
			(xy 206.678961 -207.872691) (xy 206.726567 -207.901745) (xy 206.769435 -207.93742) (xy 206.806652 -207.978957)
			(xy 206.837425 -208.02547) (xy 206.861097 -208.075967) (xy 206.877165 -208.129374) (xy 206.885285 -208.18455)
			(xy 206.885794 -208.212436) (xy 206.885285 -208.240322) (xy 206.877165 -208.295498) (xy 206.861097 -208.348905)
			(xy 206.837425 -208.399402) (xy 206.806652 -208.445915) (xy 206.769435 -208.487452) (xy 206.726567 -208.523127)
			(xy 206.678961 -208.552181) (xy 206.627632 -208.573993) (xy 206.573675 -208.588099) (xy 206.518238 -208.594199)
			(xy 206.462504 -208.592162) (xy 206.407661 -208.582032) (xy 206.354877 -208.564025) (xy 206.305277 -208.538524)
			(xy 206.259919 -208.506073) (xy 206.21977 -208.467364) (xy 206.185684 -208.423221) (xy 206.158388 -208.374586)
			(xy 206.138465 -208.322495) (xy 206.126339 -208.268058) (xy 206.122268 -208.212436) (xy 204.967408 -208.212436)
			(xy 203.780136 -221.781624) (xy 203.780136 -221.79026) (xy 204.010568 -224.430844) (xy 205.922118 -224.430844)
			(xy 205.922586 -224.405054) (xy 205.929546 -224.353946) (xy 205.943331 -224.304243) (xy 205.96369 -224.256851)
			(xy 205.990251 -224.212636) (xy 206.02253 -224.172405) (xy 206.059937 -224.136892) (xy 206.080614 -224.121472)
			(xy 206.080868 -224.121472) (xy 206.088946 -224.114985) (xy 206.099432 -224.097139) (xy 206.101188 -224.086928)
			(xy 206.11211 -224.002854) (xy 206.106268 -223.982534) (xy 206.099664 -223.974406) (xy 206.083285 -223.953821)
			(xy 206.05571 -223.909022) (xy 206.034555 -223.860858) (xy 206.020223 -223.810243) (xy 206.012986 -223.758138)
			(xy 206.012542 -223.731836) (xy 206.013028 -223.704585) (xy 206.020784 -223.650637) (xy 206.036139 -223.598342)
			(xy 206.058781 -223.548765) (xy 206.088247 -223.502915) (xy 206.123938 -223.461724) (xy 206.165129 -223.426033)
			(xy 206.210979 -223.396567) (xy 206.260556 -223.373925) (xy 206.312851 -223.35857) (xy 206.366799 -223.350814)
			(xy 206.421301 -223.350814) (xy 206.475249 -223.35857) (xy 206.527544 -223.373925) (xy 206.577121 -223.396567)
			(xy 206.622971 -223.426033) (xy 206.664162 -223.461724) (xy 206.699853 -223.502915) (xy 206.729319 -223.548765)
			(xy 206.751961 -223.598342) (xy 206.767316 -223.650637) (xy 206.775072 -223.704585) (xy 206.775558 -223.731836)
			(xy 206.77516 -223.757628) (xy 206.768189 -223.80874) (xy 206.754392 -223.858445) (xy 206.734022 -223.905837)
			(xy 206.70745 -223.950051) (xy 206.67516 -223.990281) (xy 206.637744 -224.025791) (xy 206.617062 -224.041208)
			(xy 206.616808 -224.041208) (xy 206.608733 -224.047699) (xy 206.598246 -224.065542) (xy 206.596488 -224.075752)
			(xy 206.585566 -224.159826) (xy 206.591408 -224.180146) (xy 206.598012 -224.188274) (xy 206.614425 -224.208834)
			(xy 206.641995 -224.253639) (xy 206.663144 -224.301809) (xy 206.677468 -224.35243) (xy 206.684695 -224.40454)
			(xy 206.685134 -224.430844) (xy 206.684648 -224.458095) (xy 206.676892 -224.512043) (xy 206.661537 -224.564338)
			(xy 206.638895 -224.613915) (xy 206.609429 -224.659765) (xy 206.574604 -224.699957) (xy 211.573007 -224.699957)
			(xy 211.573007 -224.645443) (xy 211.580765 -224.591485) (xy 211.596124 -224.539179) (xy 211.61877 -224.489592)
			(xy 211.648242 -224.443733) (xy 211.683942 -224.402535) (xy 211.725141 -224.366836) (xy 211.771001 -224.337365)
			(xy 211.820589 -224.31472) (xy 211.872894 -224.299363) (xy 211.926853 -224.291606) (xy 211.95411 -224.291144)
			(xy 211.980199 -224.291554) (xy 212.03189 -224.298667) (xy 212.082129 -224.312759) (xy 212.129979 -224.333566)
			(xy 212.152484 -224.34677) (xy 212.166008 -224.354346) (xy 212.196096 -224.361741) (xy 212.227018 -224.359795)
			(xy 212.255941 -224.348684) (xy 212.280213 -224.329427) (xy 212.297611 -224.303789) (xy 212.302598 -224.289112)
			(xy 212.310807 -224.263241) (xy 212.333605 -224.213983) (xy 212.363152 -224.168452) (xy 212.398852 -224.127567)
			(xy 212.439985 -224.092153) (xy 212.48572 -224.062924) (xy 212.535136 -224.040471) (xy 212.587235 -224.025245)
			(xy 212.640965 -224.017555) (xy 212.668104 -224.017078) (xy 212.695354 -224.017593) (xy 212.749299 -224.025349)
			(xy 212.801592 -224.040704) (xy 212.851166 -224.063345) (xy 212.897015 -224.09281) (xy 212.938203 -224.1285)
			(xy 212.973893 -224.169689) (xy 213.003357 -224.215537) (xy 213.025997 -224.265112) (xy 213.041352 -224.317405)
			(xy 213.049108 -224.37135) (xy 213.049108 -224.42585) (xy 213.0479 -224.434253) (xy 214.409746 -224.434253)
			(xy 214.409746 -224.379747) (xy 214.417503 -224.325797) (xy 214.432858 -224.273499) (xy 214.4555 -224.223919)
			(xy 214.484967 -224.178065) (xy 214.520659 -224.136872) (xy 214.561851 -224.101178) (xy 214.607703 -224.071708)
			(xy 214.657282 -224.049064) (xy 214.709579 -224.033706) (xy 214.763529 -224.025947) (xy 214.790782 -224.02546)
			(xy 214.817717 -224.025911) (xy 214.871049 -224.033503) (xy 214.922782 -224.048525) (xy 214.971886 -224.070678)
			(xy 215.017384 -224.09952) (xy 215.038178 -224.116646) (xy 215.04529 -224.122742) (xy 215.063324 -224.129092)
			(xy 215.141302 -224.126298) (xy 215.150724 -224.125603) (xy 215.168076 -224.118157) (xy 215.175084 -224.11182)
			(xy 215.175338 -224.111566) (xy 215.196887 -224.091184) (xy 215.2451 -224.056641) (xy 215.29808 -224.029977)
			(xy 215.354549 -224.011836) (xy 215.413145 -224.002655) (xy 215.4428 -224.002092) (xy 215.473032 -224.002653)
			(xy 215.532738 -224.012203) (xy 215.59019 -224.031048) (xy 215.643953 -224.058717) (xy 215.69268 -224.094517)
			(xy 215.714326 -224.11563) (xy 215.72093 -224.122488) (xy 215.73871 -224.130362) (xy 215.827864 -224.133664)
			(xy 215.845644 -224.127314) (xy 215.85301 -224.120964) (xy 215.873922 -224.10341) (xy 215.919829 -224.073854)
			(xy 215.969479 -224.051143) (xy 216.02186 -224.035739) (xy 216.075901 -224.027958) (xy 216.1032 -224.027492)
			(xy 216.130451 -224.027978) (xy 216.184399 -224.035734) (xy 216.236694 -224.051089) (xy 216.286271 -224.073731)
			(xy 216.332121 -224.103197) (xy 216.373312 -224.138888) (xy 216.409003 -224.180079) (xy 216.438469 -224.225929)
			(xy 216.461111 -224.275506) (xy 216.476466 -224.327801) (xy 216.484222 -224.381749) (xy 216.484222 -224.436251)
			(xy 216.477185 -224.4852) (xy 217.959938 -224.4852) (xy 217.964009 -224.429578) (xy 217.976135 -224.375141)
			(xy 217.996058 -224.32305) (xy 218.023354 -224.274415) (xy 218.05744 -224.230272) (xy 218.097589 -224.191563)
			(xy 218.142947 -224.159112) (xy 218.192547 -224.133611) (xy 218.245331 -224.115604) (xy 218.300174 -224.105474)
			(xy 218.355908 -224.103437) (xy 218.411345 -224.109537) (xy 218.465302 -224.123643) (xy 218.516631 -224.145455)
			(xy 218.564237 -224.174509) (xy 218.607105 -224.210184) (xy 218.644322 -224.251721) (xy 218.675095 -224.298234)
			(xy 218.698767 -224.348731) (xy 218.714835 -224.402138) (xy 218.722955 -224.457314) (xy 218.723464 -224.4852)
			(xy 218.722955 -224.513086) (xy 218.714835 -224.568262) (xy 218.698767 -224.621669) (xy 218.675095 -224.672166)
			(xy 218.644322 -224.718679) (xy 218.607105 -224.760216) (xy 218.564237 -224.795891) (xy 218.516631 -224.824945)
			(xy 218.465302 -224.846757) (xy 218.411345 -224.860863) (xy 218.355908 -224.866963) (xy 218.300174 -224.864926)
			(xy 218.245331 -224.854796) (xy 218.192547 -224.836789) (xy 218.142947 -224.811288) (xy 218.097589 -224.778837)
			(xy 218.05744 -224.740128) (xy 218.023354 -224.695985) (xy 217.996058 -224.64735) (xy 217.976135 -224.595259)
			(xy 217.964009 -224.540822) (xy 217.959938 -224.4852) (xy 216.477185 -224.4852) (xy 216.476466 -224.490199)
			(xy 216.461111 -224.542494) (xy 216.438469 -224.592071) (xy 216.409003 -224.637921) (xy 216.373312 -224.679112)
			(xy 216.332121 -224.714803) (xy 216.286271 -224.744269) (xy 216.236694 -224.766911) (xy 216.184399 -224.782266)
			(xy 216.130451 -224.790022) (xy 216.1032 -224.790508) (xy 216.072968 -224.789947) (xy 216.013262 -224.780397)
			(xy 215.95581 -224.761552) (xy 215.902047 -224.733883) (xy 215.85332 -224.698083) (xy 215.831674 -224.67697)
			(xy 215.82507 -224.670112) (xy 215.80729 -224.662238) (xy 215.718136 -224.658936) (xy 215.700356 -224.665286)
			(xy 215.69299 -224.671636) (xy 215.672078 -224.68919) (xy 215.626171 -224.718746) (xy 215.576521 -224.741457)
			(xy 215.52414 -224.756861) (xy 215.470099 -224.764642) (xy 215.4428 -224.765108) (xy 215.415865 -224.764675)
			(xy 215.362531 -224.75708) (xy 215.310798 -224.742054) (xy 215.261694 -224.719897) (xy 215.216197 -224.69105)
			(xy 215.195404 -224.673922) (xy 215.188292 -224.667826) (xy 215.170258 -224.661476) (xy 215.09228 -224.66427)
			(xy 215.082871 -224.665021) (xy 215.065539 -224.672459) (xy 215.058498 -224.678748) (xy 215.058244 -224.679002)
			(xy 215.036698 -224.699387) (xy 214.988484 -224.733931) (xy 214.935504 -224.760595) (xy 214.879035 -224.778735)
			(xy 214.820438 -224.787914) (xy 214.790782 -224.788476) (xy 214.763529 -224.788053) (xy 214.709579 -224.780294)
			(xy 214.657282 -224.764936) (xy 214.607703 -224.742292) (xy 214.561851 -224.712822) (xy 214.520659 -224.677128)
			(xy 214.484967 -224.635935) (xy 214.4555 -224.590081) (xy 214.432858 -224.540501) (xy 214.417503 -224.488203)
			(xy 214.409746 -224.434253) (xy 213.0479 -224.434253) (xy 213.041352 -224.479795) (xy 213.025997 -224.532088)
			(xy 213.003357 -224.581663) (xy 212.973893 -224.627511) (xy 212.938203 -224.6687) (xy 212.897015 -224.70439)
			(xy 212.851166 -224.733855) (xy 212.801592 -224.756496) (xy 212.749299 -224.771851) (xy 212.695354 -224.779607)
			(xy 212.668104 -224.780094) (xy 212.642015 -224.779672) (xy 212.590325 -224.772562) (xy 212.540086 -224.758473)
			(xy 212.492236 -224.73767) (xy 212.46973 -224.724468) (xy 212.456208 -224.716887) (xy 212.426118 -224.709484)
			(xy 212.395192 -224.711428) (xy 212.366266 -224.72254) (xy 212.341993 -224.741802) (xy 212.324599 -224.767446)
			(xy 212.319616 -224.782126) (xy 212.311418 -224.808001) (xy 212.288617 -224.857257) (xy 212.259067 -224.902786)
			(xy 212.223365 -224.94367) (xy 212.182231 -224.979083) (xy 212.136494 -225.008311) (xy 212.087078 -225.030765)
			(xy 212.034979 -225.045991) (xy 211.981249 -225.053682) (xy 211.95411 -225.05416) (xy 211.926853 -225.053794)
			(xy 211.872894 -225.046037) (xy 211.820589 -225.03068) (xy 211.771001 -225.008035) (xy 211.725141 -224.978564)
			(xy 211.683942 -224.942865) (xy 211.648242 -224.901667) (xy 211.61877 -224.855808) (xy 211.596124 -224.806221)
			(xy 211.580765 -224.753915) (xy 211.573007 -224.699957) (xy 206.574604 -224.699957) (xy 206.573738 -224.700956)
			(xy 206.532547 -224.736647) (xy 206.486697 -224.766113) (xy 206.43712 -224.788755) (xy 206.384825 -224.80411)
			(xy 206.330877 -224.811866) (xy 206.276375 -224.811866) (xy 206.222427 -224.80411) (xy 206.170132 -224.788755)
			(xy 206.120555 -224.766113) (xy 206.074705 -224.736647) (xy 206.033514 -224.700956) (xy 205.997823 -224.659765)
			(xy 205.968357 -224.613915) (xy 205.945715 -224.564338) (xy 205.93036 -224.512043) (xy 205.922604 -224.458095)
			(xy 205.922118 -224.430844) (xy 204.010568 -224.430844) (xy 204.097102 -225.42246) (xy 212.289642 -225.42246)
			(xy 212.293713 -225.366838) (xy 212.305839 -225.312401) (xy 212.325762 -225.26031) (xy 212.353058 -225.211675)
			(xy 212.387144 -225.167532) (xy 212.427293 -225.128823) (xy 212.472651 -225.096372) (xy 212.522251 -225.070871)
			(xy 212.575035 -225.052864) (xy 212.629878 -225.042734) (xy 212.685612 -225.040697) (xy 212.741049 -225.046797)
			(xy 212.795006 -225.060903) (xy 212.846335 -225.082715) (xy 212.893941 -225.111769) (xy 212.936809 -225.147444)
			(xy 212.974026 -225.188981) (xy 213.004799 -225.235494) (xy 213.028471 -225.285991) (xy 213.044539 -225.339398)
			(xy 213.052659 -225.394574) (xy 213.053168 -225.42246) (xy 213.05267 -225.449752) (xy 214.493838 -225.449752)
			(xy 214.493838 -225.395248) (xy 214.501594 -225.341298) (xy 214.516948 -225.289002) (xy 214.539589 -225.239422)
			(xy 214.569054 -225.193569) (xy 214.604745 -225.152376) (xy 214.645934 -225.11668) (xy 214.691784 -225.08721)
			(xy 214.74136 -225.064564) (xy 214.793655 -225.049203) (xy 214.847604 -225.041441) (xy 214.874856 -225.040952)
			(xy 214.90122 -225.04141) (xy 214.953443 -225.04869) (xy 215.004167 -225.06309) (xy 215.052425 -225.084335)
			(xy 215.0973 -225.112022) (xy 215.137935 -225.145622) (xy 215.173558 -225.184497) (xy 215.203491 -225.227906)
			(xy 215.215724 -225.251264) (xy 215.215978 -225.251518) (xy 215.220476 -225.259522) (xy 215.234014 -225.2719)
			(xy 215.242394 -225.275648) (xy 215.31453 -225.304096) (xy 215.333072 -225.30435) (xy 215.341708 -225.301048)
			(xy 215.37361 -225.290027) (xy 215.440044 -225.278145) (xy 215.473788 -225.277426) (xy 215.501297 -225.277929)
			(xy 215.555741 -225.285849) (xy 215.608481 -225.301513) (xy 215.658423 -225.324595) (xy 215.704528 -225.354616)
			(xy 215.725502 -225.372422) (xy 215.725756 -225.372676) (xy 215.73313 -225.37841) (xy 215.750708 -225.384678)
			(xy 215.760046 -225.384868) (xy 215.829388 -225.383344) (xy 215.838755 -225.382712) (xy 215.856086 -225.375536)
			(xy 215.86317 -225.369374) (xy 215.863678 -225.368866) (xy 215.885128 -225.348887) (xy 215.933016 -225.315083)
			(xy 215.985508 -225.288997) (xy 216.041371 -225.271242) (xy 216.099292 -225.262236) (xy 216.1286 -225.261678)
			(xy 216.15585 -225.262192) (xy 216.209796 -225.269948) (xy 216.262089 -225.285303) (xy 216.311664 -225.307943)
			(xy 216.357513 -225.337408) (xy 216.398701 -225.373099) (xy 216.434392 -225.414287) (xy 216.463857 -225.460136)
			(xy 216.486497 -225.509711) (xy 216.487429 -225.512884) (xy 217.959938 -225.512884) (xy 217.964009 -225.457262)
			(xy 217.976135 -225.402825) (xy 217.996058 -225.350734) (xy 218.023354 -225.302099) (xy 218.05744 -225.257956)
			(xy 218.097589 -225.219247) (xy 218.142947 -225.186796) (xy 218.192547 -225.161295) (xy 218.245331 -225.143288)
			(xy 218.300174 -225.133158) (xy 218.355908 -225.131121) (xy 218.411345 -225.137221) (xy 218.465302 -225.151327)
			(xy 218.516631 -225.173139) (xy 218.564237 -225.202193) (xy 218.607105 -225.237868) (xy 218.644322 -225.279405)
			(xy 218.675095 -225.325918) (xy 218.698767 -225.376415) (xy 218.714835 -225.429822) (xy 218.722955 -225.484998)
			(xy 218.723464 -225.512884) (xy 218.722955 -225.54077) (xy 218.714835 -225.595946) (xy 218.698767 -225.649353)
			(xy 218.675095 -225.69985) (xy 218.644322 -225.746363) (xy 218.607105 -225.7879) (xy 218.564237 -225.823575)
			(xy 218.516631 -225.852629) (xy 218.465302 -225.874441) (xy 218.411345 -225.888547) (xy 218.355908 -225.894647)
			(xy 218.300174 -225.89261) (xy 218.245331 -225.88248) (xy 218.192547 -225.864473) (xy 218.142947 -225.838972)
			(xy 218.097589 -225.806521) (xy 218.05744 -225.767812) (xy 218.023354 -225.723669) (xy 217.996058 -225.675034)
			(xy 217.976135 -225.622943) (xy 217.964009 -225.568506) (xy 217.959938 -225.512884) (xy 216.487429 -225.512884)
			(xy 216.501852 -225.562004) (xy 216.509608 -225.61595) (xy 216.509608 -225.67045) (xy 216.501852 -225.724396)
			(xy 216.486497 -225.776689) (xy 216.463857 -225.826264) (xy 216.434392 -225.872113) (xy 216.398701 -225.913301)
			(xy 216.357513 -225.948992) (xy 216.311664 -225.978457) (xy 216.262089 -226.001097) (xy 216.209796 -226.016452)
			(xy 216.15585 -226.024208) (xy 216.1286 -226.024694) (xy 216.101091 -226.024194) (xy 216.046647 -226.016272)
			(xy 215.993907 -226.000607) (xy 215.943965 -225.977524) (xy 215.89786 -225.947504) (xy 215.876886 -225.929698)
			(xy 215.876632 -225.929444) (xy 215.869268 -225.923695) (xy 215.851682 -225.917439) (xy 215.842342 -225.917252)
			(xy 215.773 -225.918776) (xy 215.763632 -225.919398) (xy 215.7463 -225.92658) (xy 215.739218 -225.932746)
			(xy 215.73871 -225.933254) (xy 215.719892 -225.950861) (xy 215.678342 -225.98135) (xy 215.633069 -226.005975)
			(xy 215.584897 -226.024289) (xy 215.559894 -226.030536) (xy 215.54821 -226.03333) (xy 215.529922 -226.04857)
			(xy 215.487504 -226.145344) (xy 215.488774 -226.168966) (xy 215.494616 -226.179634) (xy 215.505645 -226.199793)
			(xy 215.523351 -226.242197) (xy 215.529922 -226.264216) (xy 215.532886 -226.273198) (xy 215.544231 -226.288313)
			(xy 215.55202 -226.29368) (xy 215.617806 -226.334828) (xy 215.636348 -226.338384) (xy 215.645746 -226.336606)
			(xy 215.662553 -226.333738) (xy 215.696515 -226.33069) (xy 215.713564 -226.33051) (xy 215.713818 -226.33051)
			(xy 215.74107 -226.330961) (xy 215.795018 -226.33872) (xy 215.847313 -226.354077) (xy 215.89689 -226.376721)
			(xy 215.942741 -226.406189) (xy 215.983931 -226.441882) (xy 216.019622 -226.483074) (xy 216.049088 -226.528925)
			(xy 216.071729 -226.578504) (xy 216.087084 -226.6308) (xy 216.09484 -226.684748) (xy 216.09484 -226.739252)
			(xy 216.087084 -226.7932) (xy 216.071729 -226.845496) (xy 216.049088 -226.895075) (xy 216.019622 -226.940926)
			(xy 215.983931 -226.982118) (xy 215.942741 -227.017811) (xy 215.89689 -227.047279) (xy 215.847313 -227.069923)
			(xy 215.795018 -227.08528) (xy 215.74107 -227.093039) (xy 215.713818 -227.093526) (xy 215.686364 -227.092977)
			(xy 215.632025 -227.085095) (xy 215.579377 -227.069505) (xy 215.529508 -227.04653) (xy 215.483446 -227.016644)
			(xy 215.442144 -226.980464) (xy 215.406455 -226.938737) (xy 215.377115 -226.892326) (xy 215.35473 -226.842188)
			(xy 215.346788 -226.815904) (xy 215.343813 -226.806926) (xy 215.332476 -226.791809) (xy 215.32469 -226.78644)
			(xy 215.258904 -226.745292) (xy 215.240362 -226.741736) (xy 215.230964 -226.743514) (xy 215.214157 -226.746381)
			(xy 215.180195 -226.74943) (xy 215.163146 -226.74961) (xy 215.162892 -226.74961) (xy 215.135641 -226.74913)
			(xy 215.081693 -226.741372) (xy 215.029398 -226.726016) (xy 214.979821 -226.703374) (xy 214.933971 -226.673907)
			(xy 214.892781 -226.638215) (xy 214.857089 -226.597024) (xy 214.827623 -226.551174) (xy 214.804982 -226.501596)
			(xy 214.789627 -226.449301) (xy 214.78187 -226.395353) (xy 214.781384 -226.368102) (xy 214.781967 -226.339627)
			(xy 214.790446 -226.283313) (xy 214.807201 -226.228884) (xy 214.831859 -226.177549) (xy 214.863872 -226.13045)
			(xy 214.902531 -226.088632) (xy 214.946976 -226.053024) (xy 214.996219 -226.024418) (xy 215.049167 -226.003448)
			(xy 215.076786 -225.9965) (xy 215.08847 -225.993706) (xy 215.106758 -225.978466) (xy 215.14435 -225.892614)
			(xy 215.148508 -225.881554) (xy 215.147318 -225.857985) (xy 215.142064 -225.847402) (xy 215.13292 -225.83013)
			(xy 215.132666 -225.829876) (xy 215.128154 -225.821881) (xy 215.114626 -225.809499) (xy 215.10625 -225.805746)
			(xy 215.034114 -225.777298) (xy 215.015572 -225.777044) (xy 215.006936 -225.780346) (xy 214.975031 -225.791356)
			(xy 214.908599 -225.803245) (xy 214.874856 -225.803968) (xy 214.847604 -225.803559) (xy 214.793655 -225.795797)
			(xy 214.74136 -225.780436) (xy 214.691784 -225.75779) (xy 214.645934 -225.72832) (xy 214.604745 -225.692624)
			(xy 214.569054 -225.651431) (xy 214.539589 -225.605578) (xy 214.516948 -225.555998) (xy 214.501594 -225.503702)
			(xy 214.493838 -225.449752) (xy 213.05267 -225.449752) (xy 213.052659 -225.450346) (xy 213.044539 -225.505522)
			(xy 213.028471 -225.558929) (xy 213.004799 -225.609426) (xy 212.974026 -225.655939) (xy 212.936809 -225.697476)
			(xy 212.893941 -225.733151) (xy 212.846335 -225.762205) (xy 212.795006 -225.784017) (xy 212.741049 -225.798123)
			(xy 212.685612 -225.804223) (xy 212.629878 -225.802186) (xy 212.575035 -225.792056) (xy 212.522251 -225.774049)
			(xy 212.472651 -225.748548) (xy 212.427293 -225.716097) (xy 212.387144 -225.677388) (xy 212.353058 -225.633245)
			(xy 212.325762 -225.58461) (xy 212.305839 -225.532519) (xy 212.293713 -225.478082) (xy 212.289642 -225.42246)
			(xy 204.097102 -225.42246) (xy 204.162429 -226.171052) (xy 207.172275 -226.171052) (xy 207.172275 -226.116548)
			(xy 207.180032 -226.0626) (xy 207.195388 -226.010304) (xy 207.218029 -225.960726) (xy 207.247496 -225.914875)
			(xy 207.283189 -225.873684) (xy 207.32438 -225.837993) (xy 207.370231 -225.808526) (xy 207.41981 -225.785885)
			(xy 207.472106 -225.770531) (xy 207.526054 -225.762775) (xy 207.553306 -225.762312) (xy 207.55356 -225.762312)
			(xy 207.57976 -225.76276) (xy 207.631666 -225.769947) (xy 207.682102 -225.784163) (xy 207.730121 -225.805141)
			(xy 207.752696 -225.818446) (xy 207.76261 -225.824049) (xy 207.785224 -225.826554) (xy 207.79613 -225.823272)
			(xy 207.880966 -225.793554) (xy 207.897222 -225.777552) (xy 207.901032 -225.766884) (xy 207.911588 -225.739799)
			(xy 207.939722 -225.688934) (xy 207.975246 -225.642924) (xy 208.017336 -225.602834) (xy 208.06502 -225.569591)
			(xy 208.117194 -225.543964) (xy 208.172651 -225.526547) (xy 208.230108 -225.517742) (xy 208.259172 -225.517202)
			(xy 208.286427 -225.517643) (xy 208.340382 -225.525397) (xy 208.392685 -225.540751) (xy 208.44227 -225.563392)
			(xy 208.488128 -225.592861) (xy 208.529325 -225.628555) (xy 208.565023 -225.66975) (xy 208.594494 -225.715605)
			(xy 208.617139 -225.765189) (xy 208.632497 -225.81749) (xy 208.640255 -225.871445) (xy 208.640255 -225.925955)
			(xy 208.632497 -225.97991) (xy 208.617139 -226.032211) (xy 208.594494 -226.081795) (xy 208.565023 -226.12765)
			(xy 208.529325 -226.168845) (xy 208.488128 -226.204539) (xy 208.44227 -226.234008) (xy 208.392685 -226.256649)
			(xy 208.340382 -226.272003) (xy 208.286427 -226.279757) (xy 208.259172 -226.280218) (xy 208.258918 -226.280218)
			(xy 208.232717 -226.279775) (xy 208.180811 -226.272586) (xy 208.130376 -226.258369) (xy 208.082357 -226.237389)
			(xy 208.059782 -226.224084) (xy 208.04984 -226.218567) (xy 208.027267 -226.216079) (xy 208.016348 -226.219258)
			(xy 207.931512 -226.248976) (xy 207.915256 -226.264978) (xy 207.911446 -226.275646) (xy 207.900841 -226.30271)
			(xy 207.87271 -226.353571) (xy 207.837192 -226.399579) (xy 207.834772 -226.401884) (xy 211.795866 -226.401884)
			(xy 211.799937 -226.346262) (xy 211.812063 -226.291825) (xy 211.831986 -226.239734) (xy 211.859282 -226.191099)
			(xy 211.893368 -226.146956) (xy 211.933517 -226.108247) (xy 211.978875 -226.075796) (xy 212.028475 -226.050295)
			(xy 212.081259 -226.032288) (xy 212.136102 -226.022158) (xy 212.191836 -226.020121) (xy 212.247273 -226.026221)
			(xy 212.30123 -226.040327) (xy 212.352559 -226.062139) (xy 212.400165 -226.091193) (xy 212.443033 -226.126868)
			(xy 212.48025 -226.168405) (xy 212.511023 -226.214918) (xy 212.534695 -226.265415) (xy 212.550763 -226.318822)
			(xy 212.558883 -226.373998) (xy 212.559392 -226.401884) (xy 212.558883 -226.42977) (xy 212.550763 -226.484946)
			(xy 212.534695 -226.538353) (xy 212.511023 -226.58885) (xy 212.48025 -226.635363) (xy 212.443033 -226.6769)
			(xy 212.400165 -226.712575) (xy 212.352559 -226.741629) (xy 212.30123 -226.763441) (xy 212.247273 -226.777547)
			(xy 212.191836 -226.783647) (xy 212.136102 -226.78161) (xy 212.081259 -226.77148) (xy 212.028475 -226.753473)
			(xy 211.978875 -226.727972) (xy 211.933517 -226.695521) (xy 211.893368 -226.656812) (xy 211.859282 -226.612669)
			(xy 211.831986 -226.564034) (xy 211.812063 -226.511943) (xy 211.799937 -226.457506) (xy 211.795866 -226.401884)
			(xy 207.834772 -226.401884) (xy 207.795109 -226.439668) (xy 207.747433 -226.472913) (xy 207.695267 -226.498544)
			(xy 207.639817 -226.515968) (xy 207.582367 -226.524783) (xy 207.553306 -226.525328) (xy 207.526054 -226.524825)
			(xy 207.472106 -226.517069) (xy 207.41981 -226.501715) (xy 207.370231 -226.479074) (xy 207.32438 -226.449607)
			(xy 207.283189 -226.413916) (xy 207.247496 -226.372725) (xy 207.218029 -226.326874) (xy 207.195388 -226.277296)
			(xy 207.180032 -226.225) (xy 207.172275 -226.171052) (xy 204.162429 -226.171052) (xy 204.219545 -226.825556)
			(xy 209.439762 -226.825556) (xy 209.443833 -226.769934) (xy 209.455959 -226.715497) (xy 209.475882 -226.663406)
			(xy 209.503178 -226.614771) (xy 209.537264 -226.570628) (xy 209.577413 -226.531919) (xy 209.622771 -226.499468)
			(xy 209.672371 -226.473967) (xy 209.725155 -226.45596) (xy 209.779998 -226.44583) (xy 209.835732 -226.443793)
			(xy 209.891169 -226.449893) (xy 209.945126 -226.463999) (xy 209.996455 -226.485811) (xy 210.044061 -226.514865)
			(xy 210.086929 -226.55054) (xy 210.124146 -226.592077) (xy 210.154919 -226.63859) (xy 210.178591 -226.689087)
			(xy 210.194659 -226.742494) (xy 210.202779 -226.79767) (xy 210.203288 -226.825556) (xy 210.202779 -226.853442)
			(xy 210.194659 -226.908618) (xy 210.178591 -226.962025) (xy 210.154919 -227.012522) (xy 210.124146 -227.059035)
			(xy 210.086929 -227.100572) (xy 210.044061 -227.136247) (xy 209.996455 -227.165301) (xy 209.945126 -227.187113)
			(xy 209.891169 -227.201219) (xy 209.835732 -227.207319) (xy 209.779998 -227.205282) (xy 209.725155 -227.195152)
			(xy 209.672371 -227.177145) (xy 209.622771 -227.151644) (xy 209.577413 -227.119193) (xy 209.537264 -227.080484)
			(xy 209.503178 -227.036341) (xy 209.475882 -226.987706) (xy 209.455959 -226.935615) (xy 209.443833 -226.881178)
			(xy 209.439762 -226.825556) (xy 204.219545 -226.825556) (xy 204.294154 -227.68052) (xy 207.17459 -227.68052)
			(xy 207.178661 -227.624898) (xy 207.190787 -227.570461) (xy 207.21071 -227.51837) (xy 207.238006 -227.469735)
			(xy 207.272092 -227.425592) (xy 207.312241 -227.386883) (xy 207.357599 -227.354432) (xy 207.407199 -227.328931)
			(xy 207.459983 -227.310924) (xy 207.514826 -227.300794) (xy 207.57056 -227.298757) (xy 207.625997 -227.304857)
			(xy 207.678451 -227.31857) (xy 211.978746 -227.31857) (xy 211.982817 -227.262948) (xy 211.994943 -227.208511)
			(xy 212.014866 -227.15642) (xy 212.042162 -227.107785) (xy 212.076248 -227.063642) (xy 212.116397 -227.024933)
			(xy 212.161755 -226.992482) (xy 212.211355 -226.966981) (xy 212.264139 -226.948974) (xy 212.318982 -226.938844)
			(xy 212.374716 -226.936807) (xy 212.430153 -226.942907) (xy 212.48411 -226.957013) (xy 212.535439 -226.978825)
			(xy 212.583045 -227.007879) (xy 212.625913 -227.043554) (xy 212.66313 -227.085091) (xy 212.693903 -227.131604)
			(xy 212.717575 -227.182101) (xy 212.733643 -227.235508) (xy 212.741763 -227.290684) (xy 212.742272 -227.31857)
			(xy 212.741763 -227.346456) (xy 212.733643 -227.401632) (xy 212.721341 -227.442522) (xy 213.69604 -227.442522)
			(xy 213.700111 -227.3869) (xy 213.712237 -227.332463) (xy 213.73216 -227.280372) (xy 213.759456 -227.231737)
			(xy 213.793542 -227.187594) (xy 213.833691 -227.148885) (xy 213.879049 -227.116434) (xy 213.928649 -227.090933)
			(xy 213.981433 -227.072926) (xy 214.036276 -227.062796) (xy 214.09201 -227.060759) (xy 214.147447 -227.066859)
			(xy 214.201404 -227.080965) (xy 214.252733 -227.102777) (xy 214.300339 -227.131831) (xy 214.343207 -227.167506)
			(xy 214.380424 -227.209043) (xy 214.411197 -227.255556) (xy 214.434869 -227.306053) (xy 214.450937 -227.35946)
			(xy 214.459057 -227.414636) (xy 214.459566 -227.442522) (xy 214.459057 -227.470408) (xy 214.450937 -227.525584)
			(xy 214.434869 -227.578991) (xy 214.411197 -227.629488) (xy 214.380424 -227.676001) (xy 214.355437 -227.703888)
			(xy 215.21115 -227.703888) (xy 215.215221 -227.648266) (xy 215.227347 -227.593829) (xy 215.24727 -227.541738)
			(xy 215.274566 -227.493103) (xy 215.308652 -227.44896) (xy 215.348801 -227.410251) (xy 215.394159 -227.3778)
			(xy 215.443759 -227.352299) (xy 215.496543 -227.334292) (xy 215.551386 -227.324162) (xy 215.60712 -227.322125)
			(xy 215.662557 -227.328225) (xy 215.716514 -227.342331) (xy 215.767843 -227.364143) (xy 215.815449 -227.393197)
			(xy 215.858317 -227.428872) (xy 215.895534 -227.470409) (xy 215.926307 -227.516922) (xy 215.949979 -227.567419)
			(xy 215.966047 -227.620826) (xy 215.974167 -227.676002) (xy 215.974676 -227.703888) (xy 215.974167 -227.731774)
			(xy 215.966047 -227.78695) (xy 215.949979 -227.840357) (xy 215.926307 -227.890854) (xy 215.895534 -227.937367)
			(xy 215.858317 -227.978904) (xy 215.815449 -228.014579) (xy 215.767843 -228.043633) (xy 215.716514 -228.065445)
			(xy 215.662557 -228.079551) (xy 215.60712 -228.085651) (xy 215.551386 -228.083614) (xy 215.496543 -228.073484)
			(xy 215.443759 -228.055477) (xy 215.394159 -228.029976) (xy 215.348801 -227.997525) (xy 215.308652 -227.958816)
			(xy 215.274566 -227.914673) (xy 215.24727 -227.866038) (xy 215.227347 -227.813947) (xy 215.215221 -227.75951)
			(xy 215.21115 -227.703888) (xy 214.355437 -227.703888) (xy 214.343207 -227.717538) (xy 214.300339 -227.753213)
			(xy 214.252733 -227.782267) (xy 214.201404 -227.804079) (xy 214.147447 -227.818185) (xy 214.09201 -227.824285)
			(xy 214.036276 -227.822248) (xy 213.981433 -227.812118) (xy 213.928649 -227.794111) (xy 213.879049 -227.76861)
			(xy 213.833691 -227.736159) (xy 213.793542 -227.69745) (xy 213.759456 -227.653307) (xy 213.73216 -227.604672)
			(xy 213.712237 -227.552581) (xy 213.700111 -227.498144) (xy 213.69604 -227.442522) (xy 212.721341 -227.442522)
			(xy 212.717575 -227.455039) (xy 212.693903 -227.505536) (xy 212.66313 -227.552049) (xy 212.625913 -227.593586)
			(xy 212.583045 -227.629261) (xy 212.535439 -227.658315) (xy 212.48411 -227.680127) (xy 212.430153 -227.694233)
			(xy 212.374716 -227.700333) (xy 212.318982 -227.698296) (xy 212.264139 -227.688166) (xy 212.211355 -227.670159)
			(xy 212.161755 -227.644658) (xy 212.116397 -227.612207) (xy 212.076248 -227.573498) (xy 212.042162 -227.529355)
			(xy 212.014866 -227.48072) (xy 211.994943 -227.428629) (xy 211.982817 -227.374192) (xy 211.978746 -227.31857)
			(xy 207.678451 -227.31857) (xy 207.679954 -227.318963) (xy 207.731283 -227.340775) (xy 207.778889 -227.369829)
			(xy 207.821757 -227.405504) (xy 207.858974 -227.447041) (xy 207.889747 -227.493554) (xy 207.913419 -227.544051)
			(xy 207.929487 -227.597458) (xy 207.937607 -227.652634) (xy 207.938116 -227.68052) (xy 207.937607 -227.708406)
			(xy 207.929487 -227.763582) (xy 207.913419 -227.816989) (xy 207.889747 -227.867486) (xy 207.858974 -227.913999)
			(xy 207.821757 -227.955536) (xy 207.778889 -227.991211) (xy 207.731283 -228.020265) (xy 207.679954 -228.042077)
			(xy 207.625997 -228.056183) (xy 207.57056 -228.062283) (xy 207.514826 -228.060246) (xy 207.459983 -228.050116)
			(xy 207.407199 -228.032109) (xy 207.357599 -228.006608) (xy 207.312241 -227.974157) (xy 207.272092 -227.935448)
			(xy 207.238006 -227.891305) (xy 207.21071 -227.84267) (xy 207.190787 -227.790579) (xy 207.178661 -227.736142)
			(xy 207.17459 -227.68052) (xy 204.294154 -227.68052) (xy 204.338817 -228.19233) (xy 209.118198 -228.19233)
			(xy 209.122269 -228.136708) (xy 209.134395 -228.082271) (xy 209.154318 -228.03018) (xy 209.181614 -227.981545)
			(xy 209.2157 -227.937402) (xy 209.255849 -227.898693) (xy 209.301207 -227.866242) (xy 209.350807 -227.840741)
			(xy 209.403591 -227.822734) (xy 209.458434 -227.812604) (xy 209.514168 -227.810567) (xy 209.569605 -227.816667)
			(xy 209.623562 -227.830773) (xy 209.674891 -227.852585) (xy 209.722497 -227.881639) (xy 209.765365 -227.917314)
			(xy 209.802582 -227.958851) (xy 209.833355 -228.005364) (xy 209.857027 -228.055861) (xy 209.873095 -228.109268)
			(xy 209.881215 -228.164444) (xy 209.881724 -228.19233) (xy 209.881215 -228.220216) (xy 209.873095 -228.275392)
			(xy 209.857027 -228.328799) (xy 209.833355 -228.379296) (xy 209.802582 -228.425809) (xy 209.765365 -228.467346)
			(xy 209.722497 -228.503021) (xy 209.674891 -228.532075) (xy 209.623562 -228.553887) (xy 209.569605 -228.567993)
			(xy 209.514168 -228.574093) (xy 209.458434 -228.572056) (xy 209.403591 -228.561926) (xy 209.350807 -228.543919)
			(xy 209.301207 -228.518418) (xy 209.255849 -228.485967) (xy 209.2157 -228.447258) (xy 209.181614 -228.403115)
			(xy 209.154318 -228.35448) (xy 209.134395 -228.302389) (xy 209.122269 -228.247952) (xy 209.118198 -228.19233)
			(xy 204.338817 -228.19233) (xy 204.546109 -230.567738) (xy 207.397856 -230.567738) (xy 207.401927 -230.512116)
			(xy 207.414053 -230.457679) (xy 207.433976 -230.405588) (xy 207.461272 -230.356953) (xy 207.495358 -230.31281)
			(xy 207.535507 -230.274101) (xy 207.580865 -230.24165) (xy 207.630465 -230.216149) (xy 207.683249 -230.198142)
			(xy 207.738092 -230.188012) (xy 207.793826 -230.185975) (xy 207.849263 -230.192075) (xy 207.90322 -230.206181)
			(xy 207.954549 -230.227993) (xy 208.002155 -230.257047) (xy 208.045023 -230.292722) (xy 208.08224 -230.334259)
			(xy 208.113013 -230.380772) (xy 208.136685 -230.431269) (xy 208.152753 -230.484676) (xy 208.160873 -230.539852)
			(xy 208.161382 -230.567738) (xy 208.160873 -230.595624) (xy 208.152753 -230.6508) (xy 208.136685 -230.704207)
			(xy 208.113013 -230.754704) (xy 208.08224 -230.801217) (xy 208.045023 -230.842754) (xy 208.002155 -230.878429)
			(xy 207.954549 -230.907483) (xy 207.90322 -230.929295) (xy 207.849263 -230.943401) (xy 207.793826 -230.949501)
			(xy 207.738092 -230.947464) (xy 207.683249 -230.937334) (xy 207.630465 -230.919327) (xy 207.580865 -230.893826)
			(xy 207.535507 -230.861375) (xy 207.495358 -230.822666) (xy 207.461272 -230.778523) (xy 207.433976 -230.729888)
			(xy 207.414053 -230.677797) (xy 207.401927 -230.62336) (xy 207.397856 -230.567738) (xy 204.546109 -230.567738)
			(xy 204.716295 -232.51795) (xy 207.360518 -232.51795) (xy 207.364589 -232.462328) (xy 207.376715 -232.407891)
			(xy 207.396638 -232.3558) (xy 207.423934 -232.307165) (xy 207.45802 -232.263022) (xy 207.498169 -232.224313)
			(xy 207.543527 -232.191862) (xy 207.593127 -232.166361) (xy 207.645911 -232.148354) (xy 207.700754 -232.138224)
			(xy 207.756488 -232.136187) (xy 207.811925 -232.142287) (xy 207.865882 -232.156393) (xy 207.917211 -232.178205)
			(xy 207.964817 -232.207259) (xy 207.967623 -232.209594) (xy 210.399884 -232.209594) (xy 210.40037 -232.182343)
			(xy 210.408126 -232.128395) (xy 210.423481 -232.0761) (xy 210.446123 -232.026523) (xy 210.475589 -231.980673)
			(xy 210.51128 -231.939482) (xy 210.552471 -231.903791) (xy 210.598321 -231.874325) (xy 210.647898 -231.851683)
			(xy 210.700193 -231.836328) (xy 210.754141 -231.828572) (xy 210.808643 -231.828572) (xy 210.862591 -231.836328)
			(xy 210.914886 -231.851683) (xy 210.964463 -231.874325) (xy 211.010313 -231.903791) (xy 211.051504 -231.939482)
			(xy 211.087195 -231.980673) (xy 211.116661 -232.026523) (xy 211.139303 -232.0761) (xy 211.154658 -232.128395)
			(xy 211.162414 -232.182343) (xy 211.1629 -232.209594) (xy 211.162516 -232.23408) (xy 211.156246 -232.282649)
			(xy 211.14381 -232.330016) (xy 211.13496 -232.35285) (xy 211.131536 -232.362859) (xy 211.132173 -232.383977)
			(xy 211.13623 -232.393744) (xy 211.173314 -232.471214) (xy 211.189062 -232.48493) (xy 211.199476 -232.488232)
			(xy 211.225223 -232.496534) (xy 211.274237 -232.519426) (xy 211.319526 -232.549012) (xy 211.360182 -232.5847)
			(xy 211.395388 -232.625773) (xy 211.424439 -232.671407) (xy 211.446751 -232.720688) (xy 211.461878 -232.772627)
			(xy 211.468773 -232.820972) (xy 212.193378 -232.820972) (xy 212.193891 -232.792233) (xy 212.202517 -232.735405)
			(xy 212.21957 -232.680515) (xy 212.244664 -232.628803) (xy 212.277231 -232.581441) (xy 212.296502 -232.560114)
			(xy 212.303106 -232.553256) (xy 212.310218 -232.535222) (xy 212.310218 -232.446322) (xy 212.303106 -232.428288)
			(xy 212.296502 -232.42143) (xy 212.277229 -232.400105) (xy 212.244661 -232.352743) (xy 212.219568 -232.301031)
			(xy 212.202518 -232.24614) (xy 212.193898 -232.189311) (xy 212.193378 -232.160572) (xy 212.193864 -232.133321)
			(xy 212.20162 -232.079373) (xy 212.216975 -232.027078) (xy 212.239617 -231.977501) (xy 212.269083 -231.931651)
			(xy 212.304774 -231.89046) (xy 212.345965 -231.854769) (xy 212.391815 -231.825303) (xy 212.441392 -231.802661)
			(xy 212.493687 -231.787306) (xy 212.547635 -231.77955) (xy 212.602137 -231.77955) (xy 212.656085 -231.787306)
			(xy 212.70838 -231.802661) (xy 212.757957 -231.825303) (xy 212.803807 -231.854769) (xy 212.844998 -231.89046)
			(xy 212.880689 -231.931651) (xy 212.910155 -231.977501) (xy 212.932797 -232.027078) (xy 212.948152 -232.079373)
			(xy 212.955908 -232.133321) (xy 212.956394 -232.160572) (xy 212.955855 -232.18931) (xy 212.954471 -232.198437)
			(xy 213.302558 -232.198437) (xy 213.302561 -232.143931) (xy 213.31032 -232.08998) (xy 213.325679 -232.037682)
			(xy 213.348324 -231.988103) (xy 213.377795 -231.942251) (xy 213.413491 -231.90106) (xy 213.454686 -231.865368)
			(xy 213.500541 -231.835903) (xy 213.550124 -231.813263) (xy 213.602423 -231.797911) (xy 213.656375 -231.790157)
			(xy 213.710881 -231.790161) (xy 213.764832 -231.797923) (xy 213.817129 -231.813283) (xy 213.866708 -231.83593)
			(xy 213.912559 -231.865402) (xy 213.953749 -231.901099) (xy 213.989439 -231.942296) (xy 214.018903 -231.988152)
			(xy 214.041541 -232.037735) (xy 214.056892 -232.090035) (xy 214.064643 -232.143987) (xy 214.065104 -232.17124)
			(xy 214.064302 -232.20546) (xy 214.052034 -232.272793) (xy 214.04072 -232.305098) (xy 214.036027 -232.319393)
			(xy 214.034154 -232.349401) (xy 214.041085 -232.378658) (xy 214.056221 -232.404637) (xy 214.078255 -232.425095)
			(xy 214.105284 -232.438265) (xy 214.134973 -232.44301) (xy 214.14994 -232.441496) (xy 214.16283 -232.439838)
			(xy 214.18876 -232.438059) (xy 214.201756 -232.43794) (xy 214.20201 -232.43794) (xy 214.22926 -232.438389)
			(xy 214.283204 -232.446146) (xy 214.335495 -232.461501) (xy 214.385069 -232.484142) (xy 214.430917 -232.513607)
			(xy 214.472104 -232.549296) (xy 214.507794 -232.590484) (xy 214.537259 -232.636331) (xy 214.559899 -232.685905)
			(xy 214.575254 -232.738197) (xy 214.583011 -232.792141) (xy 214.583012 -232.84664) (xy 214.575258 -232.900585)
			(xy 214.559906 -232.952877) (xy 214.537268 -233.002452) (xy 214.507805 -233.048301) (xy 214.472118 -233.089491)
			(xy 214.430932 -233.125182) (xy 214.385086 -233.154649) (xy 214.335513 -233.177292) (xy 214.329316 -233.179112)
			(xy 215.416382 -233.179112) (xy 215.420453 -233.12349) (xy 215.432579 -233.069053) (xy 215.452502 -233.016962)
			(xy 215.479798 -232.968327) (xy 215.513884 -232.924184) (xy 215.554033 -232.885475) (xy 215.599391 -232.853024)
			(xy 215.648991 -232.827523) (xy 215.701775 -232.809516) (xy 215.756618 -232.799386) (xy 215.812352 -232.797349)
			(xy 215.867789 -232.803449) (xy 215.921746 -232.817555) (xy 215.973075 -232.839367) (xy 216.020681 -232.868421)
			(xy 216.063549 -232.904096) (xy 216.100766 -232.945633) (xy 216.131539 -232.992146) (xy 216.155211 -233.042643)
			(xy 216.171279 -233.09605) (xy 216.179399 -233.151226) (xy 216.179908 -233.179112) (xy 216.179399 -233.206998)
			(xy 216.171279 -233.262174) (xy 216.155211 -233.315581) (xy 216.131539 -233.366078) (xy 216.100766 -233.412591)
			(xy 216.063549 -233.454128) (xy 216.020681 -233.489803) (xy 215.973075 -233.518857) (xy 215.921746 -233.540669)
			(xy 215.867789 -233.554775) (xy 215.812352 -233.560875) (xy 215.756618 -233.558838) (xy 215.701775 -233.548708)
			(xy 215.648991 -233.530701) (xy 215.599391 -233.5052) (xy 215.554033 -233.472749) (xy 215.513884 -233.43404)
			(xy 215.479798 -233.389897) (xy 215.452502 -233.341262) (xy 215.432579 -233.289171) (xy 215.420453 -233.234734)
			(xy 215.416382 -233.179112) (xy 214.329316 -233.179112) (xy 214.283222 -233.19265) (xy 214.229278 -233.20041)
			(xy 214.174779 -233.200414) (xy 214.120834 -233.192662) (xy 214.068541 -233.177312) (xy 214.018965 -233.154677)
			(xy 213.973114 -233.125217) (xy 213.931923 -233.089531) (xy 213.896229 -233.048347) (xy 213.86676 -233.002503)
			(xy 213.844115 -232.952931) (xy 213.828754 -232.900641) (xy 213.820992 -232.846698) (xy 213.820502 -232.819448)
			(xy 213.8213 -232.785228) (xy 213.83357 -232.717895) (xy 213.844886 -232.68559) (xy 213.849586 -232.671298)
			(xy 213.851456 -232.641289) (xy 213.844523 -232.612032) (xy 213.829386 -232.586054) (xy 213.807352 -232.565596)
			(xy 213.780323 -232.552425) (xy 213.750633 -232.547679) (xy 213.735666 -232.549192) (xy 213.722776 -232.550849)
			(xy 213.696846 -232.552629) (xy 213.68385 -232.552748) (xy 213.683596 -232.552748) (xy 213.656343 -232.55224)
			(xy 213.602392 -232.544483) (xy 213.550093 -232.529126) (xy 213.500513 -232.506482) (xy 213.45466 -232.477013)
			(xy 213.413468 -232.441318) (xy 213.377775 -232.400124) (xy 213.348308 -232.354269) (xy 213.325667 -232.304688)
			(xy 213.310313 -232.252389) (xy 213.302558 -232.198437) (xy 212.954471 -232.198437) (xy 212.947236 -232.246137)
			(xy 212.93019 -232.301028) (xy 212.905102 -232.35274) (xy 212.872539 -232.400103) (xy 212.85327 -232.42143)
			(xy 212.846666 -232.428288) (xy 212.839554 -232.446322) (xy 212.839554 -232.535222) (xy 212.846666 -232.553256)
			(xy 212.85327 -232.560114) (xy 212.872529 -232.581451) (xy 212.905096 -232.628811) (xy 212.930191 -232.68052)
			(xy 212.947245 -232.735408) (xy 212.955871 -232.792234) (xy 212.956394 -232.820972) (xy 212.955908 -232.848223)
			(xy 212.948152 -232.902171) (xy 212.932797 -232.954466) (xy 212.910155 -233.004043) (xy 212.880689 -233.049893)
			(xy 212.844998 -233.091084) (xy 212.803807 -233.126775) (xy 212.757957 -233.156241) (xy 212.70838 -233.178883)
			(xy 212.656085 -233.194238) (xy 212.602137 -233.201994) (xy 212.547635 -233.201994) (xy 212.493687 -233.194238)
			(xy 212.441392 -233.178883) (xy 212.391815 -233.156241) (xy 212.345965 -233.126775) (xy 212.304774 -233.091084)
			(xy 212.269083 -233.049893) (xy 212.239617 -233.004043) (xy 212.216975 -232.954466) (xy 212.20162 -232.902171)
			(xy 212.193864 -232.848223) (xy 212.193378 -232.820972) (xy 211.468773 -232.820972) (xy 211.469516 -232.826182)
			(xy 211.469986 -232.85323) (xy 211.4695 -232.880481) (xy 211.461744 -232.934429) (xy 211.446389 -232.986724)
			(xy 211.423747 -233.036301) (xy 211.394281 -233.082151) (xy 211.35859 -233.123342) (xy 211.317399 -233.159033)
			(xy 211.271549 -233.188499) (xy 211.221972 -233.211141) (xy 211.169677 -233.226496) (xy 211.115729 -233.234252)
			(xy 211.061227 -233.234252) (xy 211.007279 -233.226496) (xy 210.954984 -233.211141) (xy 210.905407 -233.188499)
			(xy 210.859557 -233.159033) (xy 210.818366 -233.123342) (xy 210.782675 -233.082151) (xy 210.753209 -233.036301)
			(xy 210.730567 -232.986724) (xy 210.715212 -232.934429) (xy 210.707456 -232.880481) (xy 210.70697 -232.85323)
			(xy 210.707364 -232.828744) (xy 210.71363 -232.780175) (xy 210.726062 -232.732808) (xy 210.73491 -232.709974)
			(xy 210.738381 -232.699977) (xy 210.737715 -232.678847) (xy 210.73364 -232.66908) (xy 210.696556 -232.59161)
			(xy 210.680808 -232.577894) (xy 210.670394 -232.574592) (xy 210.644649 -232.566287) (xy 210.595636 -232.543394)
			(xy 210.550348 -232.513807) (xy 210.509694 -232.478119) (xy 210.474488 -232.437046) (xy 210.445438 -232.391413)
			(xy 210.423124 -232.342133) (xy 210.407995 -232.290196) (xy 210.400355 -232.236642) (xy 210.399884 -232.209594)
			(xy 207.967623 -232.209594) (xy 208.007685 -232.242934) (xy 208.044902 -232.284471) (xy 208.075675 -232.330984)
			(xy 208.099347 -232.381481) (xy 208.115415 -232.434888) (xy 208.123535 -232.490064) (xy 208.124044 -232.51795)
			(xy 208.123535 -232.545836) (xy 208.115415 -232.601012) (xy 208.099347 -232.654419) (xy 208.075675 -232.704916)
			(xy 208.044902 -232.751429) (xy 208.007685 -232.792966) (xy 207.964817 -232.828641) (xy 207.917211 -232.857695)
			(xy 207.910384 -232.860596) (xy 209.253326 -232.860596) (xy 209.257397 -232.804974) (xy 209.269523 -232.750537)
			(xy 209.289446 -232.698446) (xy 209.316742 -232.649811) (xy 209.350828 -232.605668) (xy 209.390977 -232.566959)
			(xy 209.436335 -232.534508) (xy 209.485935 -232.509007) (xy 209.538719 -232.491) (xy 209.593562 -232.48087)
			(xy 209.649296 -232.478833) (xy 209.704733 -232.484933) (xy 209.75869 -232.499039) (xy 209.810019 -232.520851)
			(xy 209.857625 -232.549905) (xy 209.900493 -232.58558) (xy 209.93771 -232.627117) (xy 209.968483 -232.67363)
			(xy 209.992155 -232.724127) (xy 210.008223 -232.777534) (xy 210.016343 -232.83271) (xy 210.016852 -232.860596)
			(xy 210.016343 -232.888482) (xy 210.008223 -232.943658) (xy 209.992155 -232.997065) (xy 209.968483 -233.047562)
			(xy 209.93771 -233.094075) (xy 209.900493 -233.135612) (xy 209.857625 -233.171287) (xy 209.810019 -233.200341)
			(xy 209.75869 -233.222153) (xy 209.704733 -233.236259) (xy 209.649296 -233.242359) (xy 209.593562 -233.240322)
			(xy 209.538719 -233.230192) (xy 209.485935 -233.212185) (xy 209.436335 -233.186684) (xy 209.390977 -233.154233)
			(xy 209.350828 -233.115524) (xy 209.316742 -233.071381) (xy 209.289446 -233.022746) (xy 209.269523 -232.970655)
			(xy 209.257397 -232.916218) (xy 209.253326 -232.860596) (xy 207.910384 -232.860596) (xy 207.865882 -232.879507)
			(xy 207.811925 -232.893613) (xy 207.756488 -232.899713) (xy 207.700754 -232.897676) (xy 207.645911 -232.887546)
			(xy 207.593127 -232.869539) (xy 207.543527 -232.844038) (xy 207.498169 -232.811587) (xy 207.45802 -232.772878)
			(xy 207.423934 -232.728735) (xy 207.396638 -232.6801) (xy 207.376715 -232.628009) (xy 207.364589 -232.573572)
			(xy 207.360518 -232.51795) (xy 204.716295 -232.51795) (xy 204.87019 -234.281472) (xy 211.644736 -234.281472)
			(xy 211.648807 -234.22585) (xy 211.660933 -234.171413) (xy 211.680856 -234.119322) (xy 211.708152 -234.070687)
			(xy 211.742238 -234.026544) (xy 211.782387 -233.987835) (xy 211.827745 -233.955384) (xy 211.877345 -233.929883)
			(xy 211.930129 -233.911876) (xy 211.984972 -233.901746) (xy 212.040706 -233.899709) (xy 212.096143 -233.905809)
			(xy 212.1501 -233.919915) (xy 212.201429 -233.941727) (xy 212.249035 -233.970781) (xy 212.291903 -234.006456)
			(xy 212.32912 -234.047993) (xy 212.359893 -234.094506) (xy 212.383565 -234.145003) (xy 212.399633 -234.19841)
			(xy 212.407753 -234.253586) (xy 212.408262 -234.281472) (xy 212.407753 -234.309358) (xy 212.399633 -234.364534)
			(xy 212.383565 -234.417941) (xy 212.359893 -234.468438) (xy 212.32912 -234.514951) (xy 212.291903 -234.556488)
			(xy 212.249035 -234.592163) (xy 212.201429 -234.621217) (xy 212.1501 -234.643029) (xy 212.096143 -234.657135)
			(xy 212.040706 -234.663235) (xy 211.984972 -234.661198) (xy 211.930129 -234.651068) (xy 211.877345 -234.633061)
			(xy 211.827745 -234.60756) (xy 211.782387 -234.575109) (xy 211.742238 -234.5364) (xy 211.708152 -234.492257)
			(xy 211.680856 -234.443622) (xy 211.660933 -234.391531) (xy 211.648807 -234.337094) (xy 211.644736 -234.281472)
			(xy 204.87019 -234.281472) (xy 204.909224 -234.728766) (xy 215.316052 -234.728766) (xy 215.320123 -234.673144)
			(xy 215.332249 -234.618707) (xy 215.352172 -234.566616) (xy 215.379468 -234.517981) (xy 215.413554 -234.473838)
			(xy 215.453703 -234.435129) (xy 215.499061 -234.402678) (xy 215.548661 -234.377177) (xy 215.601445 -234.35917)
			(xy 215.656288 -234.34904) (xy 215.712022 -234.347003) (xy 215.767459 -234.353103) (xy 215.821416 -234.367209)
			(xy 215.872745 -234.389021) (xy 215.920351 -234.418075) (xy 215.963219 -234.45375) (xy 216.000436 -234.495287)
			(xy 216.031209 -234.5418) (xy 216.054881 -234.592297) (xy 216.070949 -234.645704) (xy 216.079069 -234.70088)
			(xy 216.079578 -234.728766) (xy 216.079069 -234.756652) (xy 216.070949 -234.811828) (xy 216.054881 -234.865235)
			(xy 216.031209 -234.915732) (xy 216.000436 -234.962245) (xy 215.963219 -235.003782) (xy 215.920351 -235.039457)
			(xy 215.872745 -235.068511) (xy 215.821416 -235.090323) (xy 215.767459 -235.104429) (xy 215.712022 -235.110529)
			(xy 215.656288 -235.108492) (xy 215.601445 -235.098362) (xy 215.548661 -235.080355) (xy 215.499061 -235.054854)
			(xy 215.453703 -235.022403) (xy 215.413554 -234.983694) (xy 215.379468 -234.939551) (xy 215.352172 -234.890916)
			(xy 215.332249 -234.838825) (xy 215.320123 -234.784388) (xy 215.316052 -234.728766) (xy 204.909224 -234.728766)
			(xy 204.964039 -235.356908) (xy 213.315548 -235.356908) (xy 213.319619 -235.301286) (xy 213.331745 -235.246849)
			(xy 213.351668 -235.194758) (xy 213.378964 -235.146123) (xy 213.41305 -235.10198) (xy 213.453199 -235.063271)
			(xy 213.498557 -235.03082) (xy 213.548157 -235.005319) (xy 213.600941 -234.987312) (xy 213.655784 -234.977182)
			(xy 213.711518 -234.975145) (xy 213.766955 -234.981245) (xy 213.820912 -234.995351) (xy 213.872241 -235.017163)
			(xy 213.919847 -235.046217) (xy 213.962715 -235.081892) (xy 213.999932 -235.123429) (xy 214.030705 -235.169942)
			(xy 214.054377 -235.220439) (xy 214.070445 -235.273846) (xy 214.078565 -235.329022) (xy 214.079074 -235.356908)
			(xy 214.078565 -235.384794) (xy 214.070445 -235.43997) (xy 214.054377 -235.493377) (xy 214.030705 -235.543874)
			(xy 213.999932 -235.590387) (xy 213.962715 -235.631924) (xy 213.919847 -235.667599) (xy 213.872241 -235.696653)
			(xy 213.820912 -235.718465) (xy 213.766955 -235.732571) (xy 213.711518 -235.738671) (xy 213.655784 -235.736634)
			(xy 213.600941 -235.726504) (xy 213.548157 -235.708497) (xy 213.498557 -235.682996) (xy 213.453199 -235.650545)
			(xy 213.41305 -235.611836) (xy 213.378964 -235.567693) (xy 213.351668 -235.519058) (xy 213.331745 -235.466967)
			(xy 213.319619 -235.41253) (xy 213.315548 -235.356908) (xy 204.964039 -235.356908) (xy 205.064781 -236.511338)
			(xy 207.013808 -236.511338) (xy 207.017879 -236.455716) (xy 207.030005 -236.401279) (xy 207.049928 -236.349188)
			(xy 207.077224 -236.300553) (xy 207.11131 -236.25641) (xy 207.151459 -236.217701) (xy 207.196817 -236.18525)
			(xy 207.246417 -236.159749) (xy 207.299201 -236.141742) (xy 207.354044 -236.131612) (xy 207.409778 -236.129575)
			(xy 207.465215 -236.135675) (xy 207.519172 -236.149781) (xy 207.570501 -236.171593) (xy 207.618107 -236.200647)
			(xy 207.660975 -236.236322) (xy 207.698192 -236.277859) (xy 207.728965 -236.324372) (xy 207.752637 -236.374869)
			(xy 207.759536 -236.3978) (xy 208.80019 -236.3978) (xy 208.804261 -236.342178) (xy 208.816387 -236.287741)
			(xy 208.83631 -236.23565) (xy 208.863606 -236.187015) (xy 208.897692 -236.142872) (xy 208.937841 -236.104163)
			(xy 208.983199 -236.071712) (xy 209.032799 -236.046211) (xy 209.085583 -236.028204) (xy 209.140426 -236.018074)
			(xy 209.19616 -236.016037) (xy 209.251597 -236.022137) (xy 209.305554 -236.036243) (xy 209.356883 -236.058055)
			(xy 209.404489 -236.087109) (xy 209.447357 -236.122784) (xy 209.484574 -236.164321) (xy 209.515347 -236.210834)
			(xy 209.539019 -236.261331) (xy 209.555087 -236.314738) (xy 209.563207 -236.369914) (xy 209.563716 -236.3978)
			(xy 209.563207 -236.425686) (xy 209.555087 -236.480862) (xy 209.539019 -236.534269) (xy 209.515347 -236.584766)
			(xy 209.484574 -236.631279) (xy 209.447357 -236.672816) (xy 209.404489 -236.708491) (xy 209.356883 -236.737545)
			(xy 209.305554 -236.759357) (xy 209.251597 -236.773463) (xy 209.19616 -236.779563) (xy 209.140426 -236.777526)
			(xy 209.085583 -236.767396) (xy 209.032799 -236.749389) (xy 208.983199 -236.723888) (xy 208.937841 -236.691437)
			(xy 208.897692 -236.652728) (xy 208.863606 -236.608585) (xy 208.83631 -236.55995) (xy 208.816387 -236.507859)
			(xy 208.804261 -236.453422) (xy 208.80019 -236.3978) (xy 207.759536 -236.3978) (xy 207.768705 -236.428276)
			(xy 207.776825 -236.483452) (xy 207.777334 -236.511338) (xy 207.776825 -236.539224) (xy 207.768705 -236.5944)
			(xy 207.752637 -236.647807) (xy 207.728965 -236.698304) (xy 207.698192 -236.744817) (xy 207.660975 -236.786354)
			(xy 207.618107 -236.822029) (xy 207.570501 -236.851083) (xy 207.519172 -236.872895) (xy 207.465215 -236.887001)
			(xy 207.409778 -236.893101) (xy 207.354044 -236.891064) (xy 207.299201 -236.880934) (xy 207.246417 -236.862927)
			(xy 207.196817 -236.837426) (xy 207.151459 -236.804975) (xy 207.11131 -236.766266) (xy 207.077224 -236.722123)
			(xy 207.049928 -236.673488) (xy 207.030005 -236.621397) (xy 207.017879 -236.56696) (xy 207.013808 -236.511338)
			(xy 205.064781 -236.511338) (xy 205.143313 -237.41126) (xy 216.287602 -237.41126) (xy 216.291673 -237.355638)
			(xy 216.303799 -237.301201) (xy 216.323722 -237.24911) (xy 216.351018 -237.200475) (xy 216.385104 -237.156332)
			(xy 216.425253 -237.117623) (xy 216.470611 -237.085172) (xy 216.520211 -237.059671) (xy 216.572995 -237.041664)
			(xy 216.627838 -237.031534) (xy 216.683572 -237.029497) (xy 216.739009 -237.035597) (xy 216.792966 -237.049703)
			(xy 216.844295 -237.071515) (xy 216.891901 -237.100569) (xy 216.934769 -237.136244) (xy 216.971986 -237.177781)
			(xy 217.002759 -237.224294) (xy 217.026431 -237.274791) (xy 217.042499 -237.328198) (xy 217.047808 -237.36427)
			(xy 217.702636 -237.36427) (xy 217.706707 -237.308648) (xy 217.718833 -237.254211) (xy 217.738756 -237.20212)
			(xy 217.766052 -237.153485) (xy 217.800138 -237.109342) (xy 217.840287 -237.070633) (xy 217.885645 -237.038182)
			(xy 217.935245 -237.012681) (xy 217.988029 -236.994674) (xy 218.042872 -236.984544) (xy 218.098606 -236.982507)
			(xy 218.154043 -236.988607) (xy 218.208 -237.002713) (xy 218.259329 -237.024525) (xy 218.306935 -237.053579)
			(xy 218.349803 -237.089254) (xy 218.38702 -237.130791) (xy 218.417793 -237.177304) (xy 218.441465 -237.227801)
			(xy 218.457533 -237.281208) (xy 218.465653 -237.336384) (xy 218.466162 -237.36427) (xy 218.465653 -237.392156)
			(xy 218.457533 -237.447332) (xy 218.441465 -237.500739) (xy 218.417793 -237.551236) (xy 218.38702 -237.597749)
			(xy 218.349803 -237.639286) (xy 218.306935 -237.674961) (xy 218.259329 -237.704015) (xy 218.208 -237.725827)
			(xy 218.154043 -237.739933) (xy 218.098606 -237.746033) (xy 218.042872 -237.743996) (xy 217.988029 -237.733866)
			(xy 217.935245 -237.715859) (xy 217.885645 -237.690358) (xy 217.840287 -237.657907) (xy 217.800138 -237.619198)
			(xy 217.766052 -237.575055) (xy 217.738756 -237.52642) (xy 217.718833 -237.474329) (xy 217.706707 -237.419892)
			(xy 217.702636 -237.36427) (xy 217.047808 -237.36427) (xy 217.050619 -237.383374) (xy 217.051128 -237.41126)
			(xy 217.050619 -237.439146) (xy 217.042499 -237.494322) (xy 217.026431 -237.547729) (xy 217.002759 -237.598226)
			(xy 216.971986 -237.644739) (xy 216.934769 -237.686276) (xy 216.891901 -237.721951) (xy 216.844295 -237.751005)
			(xy 216.792966 -237.772817) (xy 216.739009 -237.786923) (xy 216.683572 -237.793023) (xy 216.627838 -237.790986)
			(xy 216.572995 -237.780856) (xy 216.520211 -237.762849) (xy 216.470611 -237.737348) (xy 216.425253 -237.704897)
			(xy 216.385104 -237.666188) (xy 216.351018 -237.622045) (xy 216.323722 -237.57341) (xy 216.303799 -237.521319)
			(xy 216.291673 -237.466882) (xy 216.287602 -237.41126) (xy 205.143313 -237.41126) (xy 205.253365 -238.67237)
			(xy 209.019138 -238.67237) (xy 209.023209 -238.616748) (xy 209.035335 -238.562311) (xy 209.055258 -238.51022)
			(xy 209.082554 -238.461585) (xy 209.11664 -238.417442) (xy 209.156789 -238.378733) (xy 209.202147 -238.346282)
			(xy 209.251747 -238.320781) (xy 209.304531 -238.302774) (xy 209.359374 -238.292644) (xy 209.415108 -238.290607)
			(xy 209.470545 -238.296707) (xy 209.524502 -238.310813) (xy 209.575831 -238.332625) (xy 209.623437 -238.361679)
			(xy 209.666305 -238.397354) (xy 209.703522 -238.438891) (xy 209.734295 -238.485404) (xy 209.757967 -238.535901)
			(xy 209.774035 -238.589308) (xy 209.782155 -238.644484) (xy 209.78233 -238.654082) (xy 210.3407 -238.654082)
			(xy 210.344771 -238.59846) (xy 210.356897 -238.544023) (xy 210.37682 -238.491932) (xy 210.404116 -238.443297)
			(xy 210.438202 -238.399154) (xy 210.478351 -238.360445) (xy 210.523709 -238.327994) (xy 210.573309 -238.302493)
			(xy 210.626093 -238.284486) (xy 210.680936 -238.274356) (xy 210.73667 -238.272319) (xy 210.792107 -238.278419)
			(xy 210.846064 -238.292525) (xy 210.897393 -238.314337) (xy 210.944999 -238.343391) (xy 210.987867 -238.379066)
			(xy 211.025084 -238.420603) (xy 211.055857 -238.467116) (xy 211.079529 -238.517613) (xy 211.095597 -238.57102)
			(xy 211.103717 -238.626196) (xy 211.104226 -238.654082) (xy 211.103746 -238.680353) (xy 211.374444 -238.680353)
			(xy 211.374444 -238.625847) (xy 211.382201 -238.571896) (xy 211.397556 -238.519598) (xy 211.420198 -238.470018)
			(xy 211.449665 -238.424164) (xy 211.485358 -238.382971) (xy 211.52655 -238.347276) (xy 211.572402 -238.317807)
			(xy 211.621981 -238.295162) (xy 211.674279 -238.279804) (xy 211.728229 -238.272045) (xy 211.755482 -238.271558)
			(xy 211.783662 -238.272089) (xy 211.839409 -238.280384) (xy 211.893331 -238.296781) (xy 211.944258 -238.320925)
			(xy 211.991083 -238.352291) (xy 212.012276 -238.370872) (xy 212.019134 -238.377222) (xy 212.036914 -238.38408)
			(xy 212.12429 -238.38408) (xy 212.14207 -238.377222) (xy 212.148928 -238.370872) (xy 212.170123 -238.352291)
			(xy 212.21694 -238.320907) (xy 212.267865 -238.296751) (xy 212.32179 -238.280351) (xy 212.37754 -238.272062)
			(xy 212.405722 -238.271558) (xy 212.43297 -238.272114) (xy 212.48691 -238.279872) (xy 212.539198 -238.295228)
			(xy 212.588768 -238.317868) (xy 212.634611 -238.347332) (xy 212.675795 -238.383021) (xy 212.711481 -238.424207)
			(xy 212.740943 -238.470052) (xy 212.76358 -238.519623) (xy 212.778933 -238.571911) (xy 212.786688 -238.625852)
			(xy 212.786688 -238.680348) (xy 212.778933 -238.734289) (xy 212.76358 -238.786577) (xy 212.740943 -238.836148)
			(xy 212.711481 -238.881993) (xy 212.675795 -238.923179) (xy 212.634611 -238.958868) (xy 212.588768 -238.988332)
			(xy 212.539198 -239.010972) (xy 212.48691 -239.026328) (xy 212.43297 -239.034086) (xy 212.405722 -239.034574)
			(xy 212.377542 -239.034033) (xy 212.321797 -239.025739) (xy 212.267875 -239.009344) (xy 212.216948 -238.985202)
			(xy 212.170122 -238.953839) (xy 212.148928 -238.93526) (xy 212.14207 -238.92891) (xy 212.12429 -238.922052)
			(xy 212.036914 -238.922052) (xy 212.019134 -238.92891) (xy 212.012276 -238.93526) (xy 211.991084 -238.953844)
			(xy 211.944265 -238.985227) (xy 211.89334 -239.009381) (xy 211.839415 -239.025781) (xy 211.783664 -239.03407)
			(xy 211.755482 -239.034574) (xy 211.728229 -239.034155) (xy 211.674279 -239.026396) (xy 211.621981 -239.011038)
			(xy 211.572402 -238.988393) (xy 211.52655 -238.958924) (xy 211.485358 -238.923229) (xy 211.449665 -238.882036)
			(xy 211.420198 -238.836182) (xy 211.397556 -238.786602) (xy 211.382201 -238.734304) (xy 211.374444 -238.680353)
			(xy 211.103746 -238.680353) (xy 211.103717 -238.681968) (xy 211.095597 -238.737144) (xy 211.079529 -238.790551)
			(xy 211.055857 -238.841048) (xy 211.025084 -238.887561) (xy 210.987867 -238.929098) (xy 210.944999 -238.964773)
			(xy 210.897393 -238.993827) (xy 210.846064 -239.015639) (xy 210.792107 -239.029745) (xy 210.73667 -239.035845)
			(xy 210.680936 -239.033808) (xy 210.626093 -239.023678) (xy 210.573309 -239.005671) (xy 210.523709 -238.98017)
			(xy 210.478351 -238.947719) (xy 210.438202 -238.90901) (xy 210.404116 -238.864867) (xy 210.37682 -238.816232)
			(xy 210.356897 -238.764141) (xy 210.344771 -238.709704) (xy 210.3407 -238.654082) (xy 209.78233 -238.654082)
			(xy 209.782664 -238.67237) (xy 209.782155 -238.700256) (xy 209.774035 -238.755432) (xy 209.757967 -238.808839)
			(xy 209.734295 -238.859336) (xy 209.703522 -238.905849) (xy 209.666305 -238.947386) (xy 209.623437 -238.983061)
			(xy 209.575831 -239.012115) (xy 209.524502 -239.033927) (xy 209.470545 -239.048033) (xy 209.415108 -239.054133)
			(xy 209.359374 -239.052096) (xy 209.304531 -239.041966) (xy 209.251747 -239.023959) (xy 209.202147 -238.998458)
			(xy 209.156789 -238.966007) (xy 209.11664 -238.927298) (xy 209.082554 -238.883155) (xy 209.055258 -238.83452)
			(xy 209.035335 -238.782429) (xy 209.023209 -238.727992) (xy 209.019138 -238.67237) (xy 205.253365 -238.67237)
			(xy 205.472427 -241.182652) (xy 208.956654 -241.182652) (xy 208.960725 -241.12703) (xy 208.972851 -241.072593)
			(xy 208.992774 -241.020502) (xy 209.02007 -240.971867) (xy 209.054156 -240.927724) (xy 209.094305 -240.889015)
			(xy 209.139663 -240.856564) (xy 209.189263 -240.831063) (xy 209.242047 -240.813056) (xy 209.29689 -240.802926)
			(xy 209.352624 -240.800889) (xy 209.408061 -240.806989) (xy 209.462018 -240.821095) (xy 209.513347 -240.842907)
			(xy 209.560953 -240.871961) (xy 209.603821 -240.907636) (xy 209.641038 -240.949173) (xy 209.671811 -240.995686)
			(xy 209.695483 -241.046183) (xy 209.711551 -241.09959) (xy 209.711604 -241.099953) (xy 211.374448 -241.099953)
			(xy 211.374448 -241.045447) (xy 211.382204 -240.991497) (xy 211.39756 -240.9392) (xy 211.420201 -240.88962)
			(xy 211.449668 -240.843767) (xy 211.485361 -240.802574) (xy 211.526552 -240.766879) (xy 211.572404 -240.73741)
			(xy 211.621983 -240.714766) (xy 211.674279 -240.699408) (xy 211.728229 -240.691649) (xy 211.755482 -240.691162)
			(xy 211.783662 -240.691692) (xy 211.839409 -240.699987) (xy 211.893331 -240.716384) (xy 211.944258 -240.740529)
			(xy 211.991083 -240.771895) (xy 212.012276 -240.790476) (xy 212.019134 -240.796826) (xy 212.036914 -240.803684)
			(xy 212.12429 -240.803684) (xy 212.14207 -240.796826) (xy 212.148928 -240.790476) (xy 212.170123 -240.771895)
			(xy 212.21694 -240.740511) (xy 212.267865 -240.716356) (xy 212.32179 -240.699955) (xy 212.37754 -240.691666)
			(xy 212.405722 -240.691162) (xy 212.43297 -240.69171) (xy 212.486911 -240.699468) (xy 212.539199 -240.714824)
			(xy 212.58877 -240.737465) (xy 212.634614 -240.766929) (xy 212.675798 -240.802618) (xy 212.711484 -240.843804)
			(xy 212.740946 -240.88965) (xy 212.763584 -240.939222) (xy 212.778937 -240.99151) (xy 212.786692 -241.045452)
			(xy 212.786692 -241.083084) (xy 213.703406 -241.083084) (xy 213.707477 -241.027462) (xy 213.719603 -240.973025)
			(xy 213.739526 -240.920934) (xy 213.766822 -240.872299) (xy 213.800908 -240.828156) (xy 213.841057 -240.789447)
			(xy 213.886415 -240.756996) (xy 213.936015 -240.731495) (xy 213.988799 -240.713488) (xy 214.043642 -240.703358)
			(xy 214.099376 -240.701321) (xy 214.154813 -240.707421) (xy 214.20877 -240.721527) (xy 214.260099 -240.743339)
			(xy 214.307705 -240.772393) (xy 214.350573 -240.808068) (xy 214.38779 -240.849605) (xy 214.418563 -240.896118)
			(xy 214.442235 -240.946615) (xy 214.458303 -241.000022) (xy 214.466423 -241.055198) (xy 214.466932 -241.083084)
			(xy 214.466423 -241.11097) (xy 214.458303 -241.166146) (xy 214.442235 -241.219553) (xy 214.418563 -241.27005)
			(xy 214.38779 -241.316563) (xy 214.350573 -241.3581) (xy 214.307705 -241.393775) (xy 214.260099 -241.422829)
			(xy 214.20877 -241.444641) (xy 214.154813 -241.458747) (xy 214.099376 -241.464847) (xy 214.043642 -241.46281)
			(xy 213.988799 -241.45268) (xy 213.936015 -241.434673) (xy 213.886415 -241.409172) (xy 213.841057 -241.376721)
			(xy 213.800908 -241.338012) (xy 213.766822 -241.293869) (xy 213.739526 -241.245234) (xy 213.719603 -241.193143)
			(xy 213.707477 -241.138706) (xy 213.703406 -241.083084) (xy 212.786692 -241.083084) (xy 212.786692 -241.099948)
			(xy 212.778937 -241.15389) (xy 212.763584 -241.206178) (xy 212.740946 -241.25575) (xy 212.711484 -241.301596)
			(xy 212.675798 -241.342782) (xy 212.634614 -241.378471) (xy 212.58877 -241.407935) (xy 212.539199 -241.430576)
			(xy 212.486911 -241.445932) (xy 212.43297 -241.45369) (xy 212.405722 -241.454178) (xy 212.377543 -241.453635)
			(xy 212.321797 -241.445342) (xy 212.267875 -241.428947) (xy 212.216948 -241.404806) (xy 212.170122 -241.373443)
			(xy 212.148928 -241.354864) (xy 212.14207 -241.348514) (xy 212.12429 -241.341656) (xy 212.036914 -241.341656)
			(xy 212.019134 -241.348514) (xy 212.012276 -241.354864) (xy 211.991085 -241.373449) (xy 211.944266 -241.404832)
			(xy 211.89334 -241.428985) (xy 211.839415 -241.445385) (xy 211.783664 -241.453674) (xy 211.755482 -241.454178)
			(xy 211.728229 -241.453751) (xy 211.674279 -241.445992) (xy 211.621983 -241.430634) (xy 211.572404 -241.40799)
			(xy 211.526552 -241.378521) (xy 211.485361 -241.342826) (xy 211.449668 -241.301633) (xy 211.420201 -241.25578)
			(xy 211.39756 -241.2062) (xy 211.382204 -241.153903) (xy 211.374448 -241.099953) (xy 209.711604 -241.099953)
			(xy 209.719671 -241.154766) (xy 209.72018 -241.182652) (xy 209.719671 -241.210538) (xy 209.711551 -241.265714)
			(xy 209.695483 -241.319121) (xy 209.671811 -241.369618) (xy 209.641038 -241.416131) (xy 209.603821 -241.457668)
			(xy 209.560953 -241.493343) (xy 209.513347 -241.522397) (xy 209.462018 -241.544209) (xy 209.408061 -241.558315)
			(xy 209.352624 -241.564415) (xy 209.29689 -241.562378) (xy 209.242047 -241.552248) (xy 209.189263 -241.534241)
			(xy 209.139663 -241.50874) (xy 209.094305 -241.476289) (xy 209.054156 -241.43758) (xy 209.02007 -241.393437)
			(xy 208.992774 -241.344802) (xy 208.972851 -241.292711) (xy 208.960725 -241.238274) (xy 208.956654 -241.182652)
			(xy 205.472427 -241.182652) (xy 205.512591 -241.6429) (xy 216.006932 -241.6429) (xy 216.011003 -241.587278)
			(xy 216.023129 -241.532841) (xy 216.043052 -241.48075) (xy 216.070348 -241.432115) (xy 216.104434 -241.387972)
			(xy 216.144583 -241.349263) (xy 216.189941 -241.316812) (xy 216.239541 -241.291311) (xy 216.292325 -241.273304)
			(xy 216.347168 -241.263174) (xy 216.402902 -241.261137) (xy 216.458339 -241.267237) (xy 216.512296 -241.281343)
			(xy 216.563625 -241.303155) (xy 216.611231 -241.332209) (xy 216.654099 -241.367884) (xy 216.691316 -241.409421)
			(xy 216.722089 -241.455934) (xy 216.745761 -241.506431) (xy 216.761829 -241.559838) (xy 216.769949 -241.615014)
			(xy 216.770458 -241.6429) (xy 216.769949 -241.670786) (xy 216.761829 -241.725962) (xy 216.745761 -241.779369)
			(xy 216.722089 -241.829866) (xy 216.691316 -241.876379) (xy 216.654099 -241.917916) (xy 216.611231 -241.953591)
			(xy 216.563625 -241.982645) (xy 216.512296 -242.004457) (xy 216.458339 -242.018563) (xy 216.402902 -242.024663)
			(xy 216.347168 -242.022626) (xy 216.292325 -242.012496) (xy 216.239541 -241.994489) (xy 216.189941 -241.968988)
			(xy 216.144583 -241.936537) (xy 216.104434 -241.897828) (xy 216.070348 -241.853685) (xy 216.043052 -241.80505)
			(xy 216.023129 -241.752959) (xy 216.011003 -241.698522) (xy 216.006932 -241.6429) (xy 205.512591 -241.6429)
			(xy 205.739787 -244.2464) (xy 219.538802 -244.2464) (xy 219.542873 -244.190778) (xy 219.554999 -244.136341)
			(xy 219.574922 -244.08425) (xy 219.602218 -244.035615) (xy 219.636304 -243.991472) (xy 219.676453 -243.952763)
			(xy 219.721811 -243.920312) (xy 219.771411 -243.894811) (xy 219.824195 -243.876804) (xy 219.879038 -243.866674)
			(xy 219.934772 -243.864637) (xy 219.990209 -243.870737) (xy 220.044166 -243.884843) (xy 220.095495 -243.906655)
			(xy 220.143101 -243.935709) (xy 220.185969 -243.971384) (xy 220.223186 -244.012921) (xy 220.253959 -244.059434)
			(xy 220.277631 -244.109931) (xy 220.293699 -244.163338) (xy 220.301819 -244.218514) (xy 220.302328 -244.2464)
			(xy 220.301819 -244.274286) (xy 220.293699 -244.329462) (xy 220.277631 -244.382869) (xy 220.253959 -244.433366)
			(xy 220.223186 -244.479879) (xy 220.185969 -244.521416) (xy 220.143101 -244.557091) (xy 220.095495 -244.586145)
			(xy 220.044166 -244.607957) (xy 219.990209 -244.622063) (xy 219.934772 -244.628163) (xy 219.879038 -244.626126)
			(xy 219.824195 -244.615996) (xy 219.771411 -244.597989) (xy 219.721811 -244.572488) (xy 219.676453 -244.540037)
			(xy 219.636304 -244.501328) (xy 219.602218 -244.457185) (xy 219.574922 -244.40855) (xy 219.554999 -244.356459)
			(xy 219.542873 -244.302022) (xy 219.538802 -244.2464) (xy 205.739787 -244.2464) (xy 205.807857 -245.026434)
			(xy 209.338162 -245.026434) (xy 209.342233 -244.970812) (xy 209.354359 -244.916375) (xy 209.374282 -244.864284)
			(xy 209.401578 -244.815649) (xy 209.435664 -244.771506) (xy 209.475813 -244.732797) (xy 209.521171 -244.700346)
			(xy 209.570771 -244.674845) (xy 209.623555 -244.656838) (xy 209.678398 -244.646708) (xy 209.734132 -244.644671)
			(xy 209.789569 -244.650771) (xy 209.843526 -244.664877) (xy 209.894855 -244.686689) (xy 209.942461 -244.715743)
			(xy 209.985329 -244.751418) (xy 210.022546 -244.792955) (xy 210.053319 -244.839468) (xy 210.076991 -244.889965)
			(xy 210.093059 -244.943372) (xy 210.101179 -244.998548) (xy 210.101679 -245.025926) (xy 211.053424 -245.025926)
			(xy 211.057495 -244.970304) (xy 211.069621 -244.915867) (xy 211.089544 -244.863776) (xy 211.11684 -244.815141)
			(xy 211.150926 -244.770998) (xy 211.191075 -244.732289) (xy 211.236433 -244.699838) (xy 211.286033 -244.674337)
			(xy 211.338817 -244.65633) (xy 211.39366 -244.6462) (xy 211.449394 -244.644163) (xy 211.504831 -244.650263)
			(xy 211.558788 -244.664369) (xy 211.610117 -244.686181) (xy 211.657723 -244.715235) (xy 211.700591 -244.75091)
			(xy 211.737808 -244.792447) (xy 211.768581 -244.83896) (xy 211.792253 -244.889457) (xy 211.808321 -244.942864)
			(xy 211.816441 -244.99804) (xy 211.81695 -245.025926) (xy 212.069424 -245.025926) (xy 212.073495 -244.970304)
			(xy 212.085621 -244.915867) (xy 212.105544 -244.863776) (xy 212.13284 -244.815141) (xy 212.166926 -244.770998)
			(xy 212.207075 -244.732289) (xy 212.252433 -244.699838) (xy 212.302033 -244.674337) (xy 212.354817 -244.65633)
			(xy 212.40966 -244.6462) (xy 212.465394 -244.644163) (xy 212.520831 -244.650263) (xy 212.574788 -244.664369)
			(xy 212.626117 -244.686181) (xy 212.673723 -244.715235) (xy 212.716591 -244.75091) (xy 212.753808 -244.792447)
			(xy 212.784581 -244.83896) (xy 212.808253 -244.889457) (xy 212.824321 -244.942864) (xy 212.832441 -244.99804)
			(xy 212.83295 -245.025926) (xy 212.832441 -245.053812) (xy 212.824321 -245.108988) (xy 212.808253 -245.162395)
			(xy 212.784581 -245.212892) (xy 212.753808 -245.259405) (xy 212.716591 -245.300942) (xy 212.673723 -245.336617)
			(xy 212.626117 -245.365671) (xy 212.574788 -245.387483) (xy 212.520831 -245.401589) (xy 212.465394 -245.407689)
			(xy 212.40966 -245.405652) (xy 212.354817 -245.395522) (xy 212.302033 -245.377515) (xy 212.252433 -245.352014)
			(xy 212.207075 -245.319563) (xy 212.166926 -245.280854) (xy 212.13284 -245.236711) (xy 212.105544 -245.188076)
			(xy 212.085621 -245.135985) (xy 212.073495 -245.081548) (xy 212.069424 -245.025926) (xy 211.81695 -245.025926)
			(xy 211.816441 -245.053812) (xy 211.808321 -245.108988) (xy 211.792253 -245.162395) (xy 211.768581 -245.212892)
			(xy 211.737808 -245.259405) (xy 211.700591 -245.300942) (xy 211.657723 -245.336617) (xy 211.610117 -245.365671)
			(xy 211.558788 -245.387483) (xy 211.504831 -245.401589) (xy 211.449394 -245.407689) (xy 211.39366 -245.405652)
			(xy 211.338817 -245.395522) (xy 211.286033 -245.377515) (xy 211.236433 -245.352014) (xy 211.191075 -245.319563)
			(xy 211.150926 -245.280854) (xy 211.11684 -245.236711) (xy 211.089544 -245.188076) (xy 211.069621 -245.135985)
			(xy 211.057495 -245.081548) (xy 211.053424 -245.025926) (xy 210.101679 -245.025926) (xy 210.101688 -245.026434)
			(xy 210.101179 -245.05432) (xy 210.093059 -245.109496) (xy 210.076991 -245.162903) (xy 210.053319 -245.2134)
			(xy 210.022546 -245.259913) (xy 209.985329 -245.30145) (xy 209.942461 -245.337125) (xy 209.894855 -245.366179)
			(xy 209.843526 -245.387991) (xy 209.789569 -245.402097) (xy 209.734132 -245.408197) (xy 209.678398 -245.40616)
			(xy 209.623555 -245.39603) (xy 209.570771 -245.378023) (xy 209.521171 -245.352522) (xy 209.475813 -245.320071)
			(xy 209.435664 -245.281362) (xy 209.401578 -245.237219) (xy 209.374282 -245.188584) (xy 209.354359 -245.136493)
			(xy 209.342233 -245.082056) (xy 209.338162 -245.026434) (xy 205.807857 -245.026434) (xy 206.098424 -248.35612)
			(xy 210.174838 -248.35612) (xy 210.178909 -248.300498) (xy 210.191035 -248.246061) (xy 210.210958 -248.19397)
			(xy 210.238254 -248.145335) (xy 210.27234 -248.101192) (xy 210.312489 -248.062483) (xy 210.357847 -248.030032)
			(xy 210.407447 -248.004531) (xy 210.460231 -247.986524) (xy 210.515074 -247.976394) (xy 210.570808 -247.974357)
			(xy 210.626245 -247.980457) (xy 210.680202 -247.994563) (xy 210.731531 -248.016375) (xy 210.779137 -248.045429)
			(xy 210.822005 -248.081104) (xy 210.859222 -248.122641) (xy 210.889995 -248.169154) (xy 210.913667 -248.219651)
			(xy 210.929735 -248.273058) (xy 210.937855 -248.328234) (xy 210.938341 -248.35485) (xy 211.817456 -248.35485)
			(xy 211.821527 -248.299228) (xy 211.833653 -248.244791) (xy 211.853576 -248.1927) (xy 211.880872 -248.144065)
			(xy 211.914958 -248.099922) (xy 211.955107 -248.061213) (xy 212.000465 -248.028762) (xy 212.050065 -248.003261)
			(xy 212.102849 -247.985254) (xy 212.157692 -247.975124) (xy 212.213426 -247.973087) (xy 212.268863 -247.979187)
			(xy 212.32282 -247.993293) (xy 212.374149 -248.015105) (xy 212.421755 -248.044159) (xy 212.464623 -248.079834)
			(xy 212.50184 -248.121371) (xy 212.532613 -248.167884) (xy 212.556285 -248.218381) (xy 212.572353 -248.271788)
			(xy 212.580473 -248.326964) (xy 212.580982 -248.35485) (xy 212.580473 -248.382736) (xy 212.572353 -248.437912)
			(xy 212.565859 -248.459498) (xy 219.575124 -248.459498) (xy 219.579195 -248.403876) (xy 219.591321 -248.349439)
			(xy 219.611244 -248.297348) (xy 219.63854 -248.248713) (xy 219.672626 -248.20457) (xy 219.712775 -248.165861)
			(xy 219.758133 -248.13341) (xy 219.807733 -248.107909) (xy 219.860517 -248.089902) (xy 219.91536 -248.079772)
			(xy 219.971094 -248.077735) (xy 220.026531 -248.083835) (xy 220.080488 -248.097941) (xy 220.131817 -248.119753)
			(xy 220.179423 -248.148807) (xy 220.222291 -248.184482) (xy 220.259508 -248.226019) (xy 220.290281 -248.272532)
			(xy 220.313953 -248.323029) (xy 220.330021 -248.376436) (xy 220.332563 -248.393712) (xy 221.630746 -248.393712)
			(xy 221.634817 -248.33809) (xy 221.646943 -248.283653) (xy 221.666866 -248.231562) (xy 221.694162 -248.182927)
			(xy 221.728248 -248.138784) (xy 221.768397 -248.100075) (xy 221.813755 -248.067624) (xy 221.863355 -248.042123)
			(xy 221.916139 -248.024116) (xy 221.970982 -248.013986) (xy 222.026716 -248.011949) (xy 222.082153 -248.018049)
			(xy 222.13611 -248.032155) (xy 222.187439 -248.053967) (xy 222.235045 -248.083021) (xy 222.277913 -248.118696)
			(xy 222.31513 -248.160233) (xy 222.345903 -248.206746) (xy 222.369575 -248.257243) (xy 222.385643 -248.31065)
			(xy 222.393763 -248.365826) (xy 222.394272 -248.393712) (xy 222.393763 -248.421598) (xy 222.385643 -248.476774)
			(xy 222.369575 -248.530181) (xy 222.345903 -248.580678) (xy 222.31513 -248.627191) (xy 222.277913 -248.668728)
			(xy 222.235045 -248.704403) (xy 222.187439 -248.733457) (xy 222.13611 -248.755269) (xy 222.082153 -248.769375)
			(xy 222.026716 -248.775475) (xy 221.970982 -248.773438) (xy 221.916139 -248.763308) (xy 221.863355 -248.745301)
			(xy 221.813755 -248.7198) (xy 221.768397 -248.687349) (xy 221.728248 -248.64864) (xy 221.694162 -248.604497)
			(xy 221.666866 -248.555862) (xy 221.646943 -248.503771) (xy 221.634817 -248.449334) (xy 221.630746 -248.393712)
			(xy 220.332563 -248.393712) (xy 220.338141 -248.431612) (xy 220.33865 -248.459498) (xy 220.338141 -248.487384)
			(xy 220.330021 -248.54256) (xy 220.313953 -248.595967) (xy 220.290281 -248.646464) (xy 220.259508 -248.692977)
			(xy 220.222291 -248.734514) (xy 220.179423 -248.770189) (xy 220.131817 -248.799243) (xy 220.080488 -248.821055)
			(xy 220.026531 -248.835161) (xy 219.971094 -248.841261) (xy 219.91536 -248.839224) (xy 219.860517 -248.829094)
			(xy 219.807733 -248.811087) (xy 219.758133 -248.785586) (xy 219.712775 -248.753135) (xy 219.672626 -248.714426)
			(xy 219.63854 -248.670283) (xy 219.611244 -248.621648) (xy 219.591321 -248.569557) (xy 219.579195 -248.51512)
			(xy 219.575124 -248.459498) (xy 212.565859 -248.459498) (xy 212.556285 -248.491319) (xy 212.532613 -248.541816)
			(xy 212.50184 -248.588329) (xy 212.464623 -248.629866) (xy 212.421755 -248.665541) (xy 212.374149 -248.694595)
			(xy 212.32282 -248.716407) (xy 212.268863 -248.730513) (xy 212.213426 -248.736613) (xy 212.157692 -248.734576)
			(xy 212.102849 -248.724446) (xy 212.050065 -248.706439) (xy 212.000465 -248.680938) (xy 211.955107 -248.648487)
			(xy 211.914958 -248.609778) (xy 211.880872 -248.565635) (xy 211.853576 -248.517) (xy 211.833653 -248.464909)
			(xy 211.821527 -248.410472) (xy 211.817456 -248.35485) (xy 210.938341 -248.35485) (xy 210.938364 -248.35612)
			(xy 210.937855 -248.384006) (xy 210.929735 -248.439182) (xy 210.913667 -248.492589) (xy 210.889995 -248.543086)
			(xy 210.859222 -248.589599) (xy 210.822005 -248.631136) (xy 210.779137 -248.666811) (xy 210.731531 -248.695865)
			(xy 210.680202 -248.717677) (xy 210.626245 -248.731783) (xy 210.570808 -248.737883) (xy 210.515074 -248.735846)
			(xy 210.460231 -248.725716) (xy 210.407447 -248.707709) (xy 210.357847 -248.682208) (xy 210.312489 -248.649757)
			(xy 210.27234 -248.611048) (xy 210.238254 -248.566905) (xy 210.210958 -248.51827) (xy 210.191035 -248.466179)
			(xy 210.178909 -248.411742) (xy 210.174838 -248.35612) (xy 206.098424 -248.35612) (xy 206.142844 -248.865136)
			(xy 206.143594 -248.871349) (xy 206.147706 -248.883166) (xy 206.150972 -248.888504) (xy 208.531086 -252.498149)
			(xy 221.153498 -252.498149) (xy 221.153498 -252.443651) (xy 221.161254 -252.389708) (xy 221.176607 -252.337417)
			(xy 221.199246 -252.287844) (xy 221.228709 -252.241997) (xy 221.264397 -252.200809) (xy 221.305582 -252.16512)
			(xy 221.351428 -252.135654) (xy 221.401 -252.113013) (xy 221.45329 -252.097658) (xy 221.507233 -252.089899)
			(xy 221.534482 -252.089412) (xy 221.560355 -252.089843) (xy 221.611628 -252.096824) (xy 221.661487 -252.110673)
			(xy 221.709014 -252.131137) (xy 221.753339 -252.157838) (xy 221.793646 -252.190288) (xy 221.829195 -252.22789)
			(xy 221.844616 -252.24867) (xy 221.853584 -252.260214) (xy 221.876666 -252.278124) (xy 221.903874 -252.288768)
			(xy 221.932982 -252.291274) (xy 221.961609 -252.285438) (xy 221.987412 -252.271736) (xy 222.008282 -252.251291)
			(xy 222.015812 -252.238764) (xy 222.03042 -252.213713) (xy 222.065944 -252.167882) (xy 222.107994 -252.127955)
			(xy 222.155602 -252.094851) (xy 222.207671 -252.069333) (xy 222.263002 -252.051988) (xy 222.320321 -252.043215)
			(xy 222.349314 -252.042676) (xy 222.376563 -252.043195) (xy 222.430507 -252.050953) (xy 222.482798 -252.066309)
			(xy 222.532371 -252.08895) (xy 222.578218 -252.118415) (xy 222.619405 -252.154105) (xy 222.655093 -252.195293)
			(xy 222.684557 -252.241141) (xy 222.707196 -252.290715) (xy 222.72255 -252.343006) (xy 222.730306 -252.396951)
			(xy 222.730306 -252.451449) (xy 222.726046 -252.48108) (xy 222.877886 -252.48108) (xy 222.881957 -252.425458)
			(xy 222.894083 -252.371021) (xy 222.914006 -252.31893) (xy 222.941302 -252.270295) (xy 222.975388 -252.226152)
			(xy 223.015537 -252.187443) (xy 223.060895 -252.154992) (xy 223.110495 -252.129491) (xy 223.163279 -252.111484)
			(xy 223.218122 -252.101354) (xy 223.273856 -252.099317) (xy 223.329293 -252.105417) (xy 223.38325 -252.119523)
			(xy 223.434579 -252.141335) (xy 223.482185 -252.170389) (xy 223.525053 -252.206064) (xy 223.56227 -252.247601)
			(xy 223.593043 -252.294114) (xy 223.616715 -252.344611) (xy 223.632783 -252.398018) (xy 223.640903 -252.453194)
			(xy 223.641412 -252.48108) (xy 223.640903 -252.508966) (xy 223.632783 -252.564142) (xy 223.616715 -252.617549)
			(xy 223.593043 -252.668046) (xy 223.56227 -252.714559) (xy 223.525053 -252.756096) (xy 223.482185 -252.791771)
			(xy 223.434579 -252.820825) (xy 223.38325 -252.842637) (xy 223.329293 -252.856743) (xy 223.273856 -252.862843)
			(xy 223.218122 -252.860806) (xy 223.163279 -252.850676) (xy 223.110495 -252.832669) (xy 223.060895 -252.807168)
			(xy 223.015537 -252.774717) (xy 222.975388 -252.736008) (xy 222.941302 -252.691865) (xy 222.914006 -252.64323)
			(xy 222.894083 -252.591139) (xy 222.881957 -252.536702) (xy 222.877886 -252.48108) (xy 222.726046 -252.48108)
			(xy 222.72255 -252.505394) (xy 222.707196 -252.557685) (xy 222.684557 -252.607259) (xy 222.655093 -252.653107)
			(xy 222.619405 -252.694295) (xy 222.578218 -252.729985) (xy 222.532371 -252.75945) (xy 222.482798 -252.782091)
			(xy 222.430507 -252.797447) (xy 222.376563 -252.805205) (xy 222.349314 -252.805692) (xy 222.323441 -252.805262)
			(xy 222.272168 -252.798281) (xy 222.22231 -252.784432) (xy 222.174782 -252.763968) (xy 222.130457 -252.737266)
			(xy 222.09015 -252.704816) (xy 222.054601 -252.667214) (xy 222.03918 -252.646434) (xy 222.030217 -252.634886)
			(xy 222.007135 -252.616974) (xy 221.979925 -252.60633) (xy 221.950816 -252.603824) (xy 221.922188 -252.609662)
			(xy 221.896383 -252.623365) (xy 221.875514 -252.643812) (xy 221.867984 -252.65634) (xy 221.85338 -252.681394)
			(xy 221.817856 -252.727224) (xy 221.775805 -252.767151) (xy 221.728196 -252.800254) (xy 221.676126 -252.825772)
			(xy 221.620794 -252.843117) (xy 221.563475 -252.851889) (xy 221.534482 -252.852428) (xy 221.507233 -252.851901)
			(xy 221.45329 -252.844142) (xy 221.401 -252.828787) (xy 221.351428 -252.806146) (xy 221.305582 -252.77668)
			(xy 221.264397 -252.740991) (xy 221.228709 -252.699803) (xy 221.199246 -252.653956) (xy 221.176607 -252.604383)
			(xy 221.161254 -252.552092) (xy 221.153498 -252.498149) (xy 208.531086 -252.498149) (xy 209.152744 -253.440946)
			(xy 209.152744 -253.441454) (xy 210.418172 -255.33477) (xy 210.429348 -255.33604) (xy 224.314512 -255.33604)
			(xy 224.324521 -255.33555) (xy 224.343016 -255.32789) (xy 224.357174 -255.313739) (xy 224.364845 -255.295249)
			(xy 224.365312 -255.28524) (xy 224.365312 -253.533656) (xy 224.365143 -253.526924) (xy 224.361669 -253.513919)
			(xy 224.358454 -253.508002) (xy 224.345988 -253.485932) (xy 224.326345 -253.439205) (xy 224.313046 -253.390292)
			(xy 224.306324 -253.340052) (xy 224.305876 -253.314708) (xy 224.305876 -252.953266) (xy 224.296224 -252.932946)
			(xy 224.288858 -252.926596) (xy 224.28835 -252.926088) (xy 224.288096 -252.925834) (xy 224.281133 -252.92063)
			(xy 224.264776 -252.914783) (xy 224.256092 -252.914404) (xy 224.246694 -252.914404) (xy 224.24263 -252.915166)
			(xy 224.229945 -252.917059) (xy 224.204396 -252.919348) (xy 224.191576 -252.919738) (xy 224.181924 -252.919738)
			(xy 224.154862 -252.919211) (xy 224.101296 -252.911453) (xy 224.049364 -252.896202) (xy 224.000108 -252.873766)
			(xy 223.954518 -252.844593) (xy 223.913507 -252.809271) (xy 223.877901 -252.768507) (xy 223.848412 -252.723121)
			(xy 223.825634 -252.674022) (xy 223.810022 -252.622197) (xy 223.801892 -252.568686) (xy 223.801406 -252.514563)
			(xy 223.808573 -252.460915) (xy 223.82325 -252.408818) (xy 223.845142 -252.359318) (xy 223.87381 -252.313408)
			(xy 223.908679 -252.272011) (xy 223.949047 -252.235957) (xy 223.994106 -252.20597) (xy 224.042951 -252.182652)
			(xy 224.094601 -252.166471) (xy 224.148019 -252.157751) (xy 224.175066 -252.156722) (xy 224.18421 -252.156722)
			(xy 224.19978 -252.156938) (xy 224.230808 -252.159607) (xy 224.246186 -252.162056) (xy 224.257362 -252.163834)
			(xy 224.267522 -252.16104) (xy 224.272838 -252.159512) (xy 224.282701 -252.154512) (xy 224.28708 -252.151134)
			(xy 224.287588 -252.150626) (xy 224.295836 -252.143018) (xy 224.305326 -252.122717) (xy 224.305876 -252.11151)
			(xy 224.305876 -243.969032) (xy 224.30544 -243.958968) (xy 224.297705 -243.940384) (xy 224.29089 -243.932964)
			(xy 221.567756 -241.20983) (xy 221.561296 -241.203933) (xy 221.545467 -241.196522) (xy 221.528067 -241.19487)
			(xy 221.519496 -241.196622) (xy 221.434914 -241.217958) (xy 221.426517 -241.220461) (xy 221.411966 -241.230201)
			(xy 221.401497 -241.244237) (xy 221.398592 -241.252502) (xy 221.398592 -241.252756) (xy 221.39036 -241.278631)
			(xy 221.367594 -241.327927) (xy 221.33807 -241.373497) (xy 221.302385 -241.414422) (xy 221.261257 -241.449874)
			(xy 221.21552 -241.479138) (xy 221.166096 -241.501623) (xy 221.113983 -241.516874) (xy 221.060235 -241.524584)
			(xy 221.033086 -241.525044) (xy 221.005834 -241.524557) (xy 220.951886 -241.516799) (xy 220.899591 -241.501443)
			(xy 220.850013 -241.478802) (xy 220.804162 -241.449336) (xy 220.762971 -241.413645) (xy 220.727277 -241.372455)
			(xy 220.697809 -241.326606) (xy 220.675164 -241.277029) (xy 220.659805 -241.224735) (xy 220.652044 -241.170788)
			(xy 220.651578 -241.143536) (xy 220.652055 -241.116386) (xy 220.659751 -241.062634) (xy 220.674992 -241.010517)
			(xy 220.69747 -240.961088) (xy 220.726732 -240.915346) (xy 220.762184 -240.874217) (xy 220.803111 -240.838532)
			(xy 220.848686 -240.809011) (xy 220.897987 -240.786252) (xy 220.923866 -240.77803) (xy 220.92412 -240.77803)
			(xy 220.932404 -240.775153) (xy 220.946478 -240.764715) (xy 220.956174 -240.750119) (xy 220.958664 -240.741708)
			(xy 220.98 -240.657126) (xy 220.981788 -240.648562) (xy 220.980112 -240.63116) (xy 220.972683 -240.615335)
			(xy 220.966792 -240.608866) (xy 218.697556 -238.33963) (xy 218.676702 -238.317959) (xy 218.64133 -238.269324)
			(xy 218.613993 -238.215758) (xy 218.595364 -238.158577) (xy 218.5859 -238.099189) (xy 218.585288 -238.06912)
			(xy 218.585288 -236.907324) (xy 218.584851 -236.89726) (xy 218.577116 -236.878677) (xy 218.570302 -236.871256)
			(xy 218.006676 -236.307376) (xy 217.985825 -236.285705) (xy 217.950457 -236.237068) (xy 217.923127 -236.183501)
			(xy 217.904504 -236.126321) (xy 217.895048 -236.066933) (xy 217.894408 -236.036866) (xy 217.894408 -233.533696)
			(xy 217.889836 -233.526076) (xy 217.886174 -233.52036) (xy 217.876399 -233.510948) (xy 217.870532 -233.507534)
			(xy 217.850212 -233.496358) (xy 217.847926 -233.495088) (xy 217.834464 -233.49077) (xy 217.824766 -233.489598)
			(xy 217.805702 -233.493782) (xy 217.79738 -233.498898) (xy 217.773615 -233.514302) (xy 217.722499 -233.538681)
			(xy 217.668344 -233.555243) (xy 217.612336 -233.563625) (xy 217.58402 -233.564176) (xy 217.583512 -233.564176)
			(xy 217.568272 -233.563922) (xy 217.541753 -233.562403) (xy 217.489486 -233.552939) (xy 217.439038 -233.536314)
			(xy 217.391385 -233.51285) (xy 217.347449 -233.483001) (xy 217.308078 -233.447345) (xy 217.274036 -233.406571)
			(xy 217.245981 -233.361468) (xy 217.224455 -233.312908) (xy 217.209876 -233.261832) (xy 217.202524 -233.209227)
			(xy 217.202004 -233.182668) (xy 217.202492 -233.155419) (xy 217.210253 -233.101475) (xy 217.225611 -233.049185)
			(xy 217.248254 -232.999613) (xy 217.277721 -232.953767) (xy 217.313413 -232.912582) (xy 217.354602 -232.876895)
			(xy 217.400451 -232.847433) (xy 217.450026 -232.824795) (xy 217.502318 -232.809443) (xy 217.556263 -232.801689)
			(xy 217.583512 -232.80116) (xy 217.583766 -232.80116) (xy 217.612084 -232.801675) (xy 217.668097 -232.810051)
			(xy 217.722254 -232.826623) (xy 217.773363 -232.851027) (xy 217.797126 -232.866438) (xy 217.802937 -232.870094)
			(xy 217.815941 -232.874482) (xy 217.82278 -232.875074) (xy 217.83675 -232.875836) (xy 217.882978 -232.851198)
			(xy 217.883994 -232.85069) (xy 217.894408 -232.833164) (xy 217.894408 -230.242364) (xy 217.893979 -230.232296)
			(xy 217.886256 -230.213701) (xy 217.879422 -230.206296) (xy 217.073988 -229.400862) (xy 217.066592 -229.394011)
			(xy 217.047993 -229.386271) (xy 217.03792 -229.385876) (xy 212.782658 -229.385876) (xy 212.752587 -229.385297)
			(xy 212.69319 -229.375846) (xy 212.636005 -229.357216) (xy 212.58244 -229.329866) (xy 212.533816 -229.294469)
			(xy 212.512148 -229.273608) (xy 211.85505 -228.61651) (xy 211.847649 -228.60967) (xy 211.829051 -228.601952)
			(xy 211.818982 -228.601524) (xy 210.836002 -228.601524) (xy 210.808676 -228.60106) (xy 210.754582 -228.593282)
			(xy 210.702144 -228.577886) (xy 210.652432 -228.555183) (xy 210.606456 -228.525636) (xy 210.565154 -228.489848)
			(xy 210.529365 -228.448545) (xy 210.499818 -228.40257) (xy 210.477115 -228.352858) (xy 210.461718 -228.30042)
			(xy 210.45394 -228.246326) (xy 210.45394 -228.191674) (xy 210.461718 -228.13758) (xy 210.477115 -228.085142)
			(xy 210.499818 -228.03543) (xy 210.529365 -227.989455) (xy 210.565154 -227.948152) (xy 210.606456 -227.912364)
			(xy 210.652432 -227.882817) (xy 210.702144 -227.860114) (xy 210.754582 -227.844718) (xy 210.808676 -227.83694)
			(xy 210.836002 -227.836476) (xy 211.99856 -227.836476) (xy 212.028619 -227.83707) (xy 212.087995 -227.846478)
			(xy 212.14517 -227.865055) (xy 212.198738 -227.892343) (xy 212.24738 -227.927671) (xy 212.26907 -227.94849)
			(xy 212.926168 -228.605334) (xy 212.933567 -228.612177) (xy 212.952166 -228.619897) (xy 212.962236 -228.62032)
			(xy 216.683844 -228.62032) (xy 216.692454 -228.619982) (xy 216.708706 -228.614293) (xy 216.722176 -228.603566)
			(xy 216.727024 -228.596444) (xy 216.779602 -228.512624) (xy 216.780872 -228.486462) (xy 216.775284 -228.474778)
			(xy 216.761474 -228.445039) (xy 216.739811 -228.38315) (xy 216.725203 -228.319227) (xy 216.71783 -228.254071)
			(xy 216.717372 -228.221286) (xy 216.717372 -228.22027) (xy 216.717908 -228.184867) (xy 216.726443 -228.114577)
			(xy 216.743385 -228.045828) (xy 216.768488 -227.979622) (xy 216.801386 -227.916922) (xy 216.841598 -227.858643)
			(xy 216.88854 -227.805634) (xy 216.941527 -227.758667) (xy 216.999787 -227.718428) (xy 217.062471 -227.685501)
			(xy 217.128666 -227.660367) (xy 217.197408 -227.643392) (xy 217.267693 -227.634824) (xy 217.303096 -227.634292)
			(xy 217.335972 -227.634774) (xy 217.401308 -227.642172) (xy 217.465406 -227.656831) (xy 217.527463 -227.678568)
			(xy 217.586699 -227.707109) (xy 217.642371 -227.742096) (xy 217.693781 -227.783091) (xy 217.71737 -227.805996)
			(xy 217.791284 -227.87991) (xy 217.798373 -227.886386) (xy 217.815997 -227.89397) (xy 217.825574 -227.894642)
			(xy 217.904822 -227.897182) (xy 217.92311 -227.890578) (xy 217.928444 -227.885752) (xy 217.953336 -227.865432)
			(xy 217.973635 -227.850617) (xy 218.017373 -227.825869) (xy 218.063978 -227.807067) (xy 218.08821 -227.800408)
			(xy 218.094306 -227.798884) (xy 218.106752 -227.792026) (xy 218.10853 -227.79101) (xy 218.115677 -227.786265)
			(xy 218.126565 -227.773021) (xy 218.129866 -227.765102) (xy 218.130628 -227.76307) (xy 218.147646 -227.702872)
			(xy 218.1479 -227.701856) (xy 218.154504 -227.675948) (xy 218.156198 -227.667622) (xy 218.154565 -227.650719)
			(xy 218.147465 -227.635294) (xy 218.141804 -227.628958) (xy 217.957654 -227.445062) (xy 217.935158 -227.421921)
			(xy 217.894921 -227.371458) (xy 217.860587 -227.316807) (xy 217.832587 -227.258656) (xy 217.811273 -227.197736)
			(xy 217.796913 -227.134813) (xy 217.789686 -227.070678) (xy 217.789252 -227.038408) (xy 217.789252 -227.0379)
			(xy 217.789756 -227.003116) (xy 217.798142 -226.934054) (xy 217.814791 -226.866507) (xy 217.839461 -226.801459)
			(xy 217.871792 -226.73986) (xy 217.911312 -226.682606) (xy 217.957445 -226.630534) (xy 218.009519 -226.584402)
			(xy 218.066773 -226.544883) (xy 218.128374 -226.512554) (xy 218.193422 -226.487886) (xy 218.26097 -226.471239)
			(xy 218.330032 -226.462855) (xy 218.364816 -226.462336) (xy 218.365324 -226.462336) (xy 218.397592 -226.462804)
			(xy 218.461719 -226.470053) (xy 218.524635 -226.484424) (xy 218.58555 -226.505736) (xy 218.643702 -226.533723)
			(xy 218.698361 -226.568035) (xy 218.748843 -226.60824) (xy 218.771978 -226.630738) (xy 219.547186 -227.405946)
			(xy 219.552936 -227.411143) (xy 219.566769 -227.418115) (xy 219.574364 -227.419662) (xy 219.582746 -227.420424)
			(xy 219.62491 -227.420424) (xy 219.630244 -227.418138) (xy 219.635578 -227.417122) (xy 219.65031 -227.407978)
			(xy 219.65666 -227.400104) (xy 219.65666 -224.364296) (xy 219.656235 -224.354227) (xy 219.648515 -224.335627)
			(xy 219.641674 -224.328228) (xy 219.194126 -223.880934) (xy 219.186725 -223.874095) (xy 219.168126 -223.866383)
			(xy 219.158058 -223.865948) (xy 218.827096 -223.865948) (xy 218.817698 -223.866456) (xy 216.665556 -223.866456)
			(xy 216.656158 -223.865948) (xy 215.034114 -223.865948) (xy 215.024716 -223.866456) (xy 213.884256 -223.866456)
			(xy 213.874858 -223.865948) (xy 212.255608 -223.865948) (xy 212.24621 -223.866456) (xy 211.814918 -223.866456)
			(xy 211.808314 -223.866202) (xy 211.797646 -223.866202) (xy 211.791042 -223.866456) (xy 210.143852 -223.866456)
			(xy 210.137842 -223.866623) (xy 210.126159 -223.869444) (xy 210.120738 -223.872044) (xy 210.117263 -223.873882)
			(xy 210.110881 -223.878473) (xy 210.108038 -223.881188) (xy 210.104736 -223.88449) (xy 210.054952 -223.943164)
			(xy 210.051801 -223.947026) (xy 210.046946 -223.95573) (xy 210.0453 -223.960436) (xy 210.044792 -223.962214)
			(xy 210.044792 -223.962468) (xy 210.043302 -223.968257) (xy 210.042785 -223.980196) (xy 210.043776 -223.98609)
			(xy 210.044284 -223.988376) (xy 210.046531 -224.003324) (xy 210.048944 -224.033459) (xy 210.04911 -224.048574)
			(xy 210.04911 -224.049082) (xy 210.048648 -224.076336) (xy 210.040893 -224.130289) (xy 210.025539 -224.182589)
			(xy 210.002897 -224.232171) (xy 209.97343 -224.278027) (xy 209.937736 -224.319222) (xy 209.896543 -224.354918)
			(xy 209.850689 -224.384388) (xy 209.801108 -224.407032) (xy 209.748808 -224.422389) (xy 209.694856 -224.430146)
			(xy 209.667602 -224.43059) (xy 209.667348 -224.43059) (xy 209.637983 -224.430043) (xy 209.579947 -224.421042)
			(xy 209.523969 -224.403276) (xy 209.497422 -224.390712) (xy 209.492342 -224.388172) (xy 209.48269 -224.385632)
			(xy 209.476052 -224.38403) (xy 209.462404 -224.38403) (xy 209.455766 -224.385632) (xy 209.446114 -224.388172)
			(xy 209.441034 -224.390712) (xy 209.4145 -224.403311) (xy 209.358522 -224.421096) (xy 209.300476 -224.430073)
			(xy 209.271108 -224.43059) (xy 209.2706 -224.43059) (xy 209.243348 -224.430127) (xy 209.189398 -224.42237)
			(xy 209.137101 -224.407013) (xy 209.087522 -224.384371) (xy 209.04167 -224.354902) (xy 209.000479 -224.319208)
			(xy 208.964787 -224.278016) (xy 208.935321 -224.232162) (xy 208.91268 -224.182582) (xy 208.897327 -224.130285)
			(xy 208.889572 -224.076334) (xy 208.889092 -224.049082) (xy 208.889632 -224.020108) (xy 208.898398 -223.962828)
			(xy 208.915726 -223.907531) (xy 208.941217 -223.855492) (xy 208.974285 -223.807906) (xy 209.014169 -223.765868)
			(xy 209.059952 -223.730345) (xy 209.11058 -223.702155) (xy 209.16489 -223.681945) (xy 209.221631 -223.670182)
			(xy 209.250534 -223.668082) (xy 209.250788 -223.668082) (xy 209.258083 -223.667411) (xy 209.271879 -223.662507)
			(xy 209.277966 -223.65843) (xy 209.284062 -223.654112) (xy 209.292698 -223.642936) (xy 209.312256 -223.59239)
			(xy 209.312256 -223.591882) (xy 209.328512 -223.549718) (xy 209.332242 -223.538072) (xy 209.329595 -223.513798)
			(xy 209.323432 -223.503236) (xy 209.317082 -223.495616) (xy 207.277462 -221.455996) (xy 207.264 -221.441518)
			(xy 207.26273 -221.439994) (xy 207.204818 -221.382082) (xy 207.197972 -221.374683) (xy 207.190242 -221.356085)
			(xy 207.189832 -221.346014) (xy 207.189832 -221.266004) (xy 207.189578 -221.262194) (xy 207.188816 -221.240858)
			(xy 207.188816 -219.833698) (xy 207.188562 -219.828364) (xy 207.187225 -219.81935) (xy 207.179104 -219.803049)
			(xy 207.165818 -219.790595) (xy 207.157574 -219.786708) (xy 207.125824 -219.775786) (xy 207.094074 -219.785438)
			(xy 207.084168 -219.799154) (xy 207.066062 -219.822917) (xy 207.023703 -219.865042) (xy 206.975297 -219.900051)
			(xy 206.922028 -219.92709) (xy 206.865196 -219.945498) (xy 206.806189 -219.954825) (xy 206.77632 -219.955364)
			(xy 206.746799 -219.954784) (xy 206.688469 -219.945638) (xy 206.632241 -219.927623) (xy 206.579457 -219.901169)
			(xy 206.555086 -219.884498) (xy 206.546958 -219.879672) (xy 206.522713 -219.86779) (xy 206.477546 -219.838207)
			(xy 206.437004 -219.802549) (xy 206.401897 -219.761529) (xy 206.372927 -219.715966) (xy 206.350674 -219.666773)
			(xy 206.335582 -219.614933) (xy 206.327954 -219.561482) (xy 206.327502 -219.534486) (xy 206.329026 -219.499688)
			(xy 206.329788 -219.490798) (xy 206.32547 -219.47378) (xy 206.283814 -219.41282) (xy 206.27851 -219.405797)
			(xy 206.264223 -219.395541) (xy 206.255874 -219.392754) (xy 206.25562 -219.392754) (xy 206.229342 -219.384807)
			(xy 206.179217 -219.362415) (xy 206.132819 -219.333069) (xy 206.091106 -219.297377) (xy 206.05494 -219.256074)
			(xy 206.025067 -219.210014) (xy 206.002104 -219.160148) (xy 205.986526 -219.107505) (xy 205.978654 -219.053174)
			(xy 205.978252 -219.025724) (xy 205.978738 -218.998473) (xy 205.986494 -218.944525) (xy 206.001849 -218.89223)
			(xy 206.024491 -218.842653) (xy 206.053957 -218.796803) (xy 206.089648 -218.755612) (xy 206.130839 -218.719921)
			(xy 206.176689 -218.690455) (xy 206.226266 -218.667813) (xy 206.278561 -218.652458) (xy 206.332509 -218.644702)
			(xy 206.387011 -218.644702) (xy 206.440959 -218.652458) (xy 206.493254 -218.667813) (xy 206.542831 -218.690455)
			(xy 206.588681 -218.719921) (xy 206.629872 -218.755612) (xy 206.665563 -218.796803) (xy 206.695029 -218.842653)
			(xy 206.717671 -218.89223) (xy 206.733026 -218.944525) (xy 206.740782 -218.998473) (xy 206.741268 -219.025724)
			(xy 206.739744 -219.060522) (xy 206.738982 -219.069412) (xy 206.7433 -219.08643) (xy 206.784956 -219.14739)
			(xy 206.790258 -219.154416) (xy 206.804544 -219.164677) (xy 206.812896 -219.167456) (xy 206.81315 -219.167456)
			(xy 206.826991 -219.171501) (xy 206.854072 -219.181417) (xy 206.867252 -219.187268) (xy 206.883803 -219.195069)
			(xy 206.915478 -219.213394) (xy 206.930498 -219.223844) (xy 206.938626 -219.22867) (xy 206.965446 -219.241905)
			(xy 207.01495 -219.275461) (xy 207.037178 -219.295472) (xy 207.059276 -219.316046) (xy 207.065372 -219.314268)
			(xy 207.127602 -219.292678) (xy 207.130904 -219.295218) (xy 207.15986 -219.281502) (xy 207.168316 -219.277046)
			(xy 207.181363 -219.263098) (xy 207.188373 -219.245332) (xy 207.188816 -219.235782) (xy 207.188816 -215.741504)
			(xy 207.188329 -215.731495) (xy 207.180671 -215.712999) (xy 207.166518 -215.69884) (xy 207.148025 -215.691175)
			(xy 207.138016 -215.690704) (xy 207.111092 -215.690704) (xy 207.101085 -215.690214) (xy 207.082595 -215.682554)
			(xy 207.068444 -215.668401) (xy 207.060785 -215.649911) (xy 207.060292 -215.639904) (xy 207.060292 -215.435688)
			(xy 207.060038 -215.431878) (xy 207.059276 -215.410542) (xy 207.059276 -215.118442) (xy 207.059107 -215.11171)
			(xy 207.055633 -215.098705) (xy 207.052418 -215.092788) (xy 207.0501 -215.088999) (xy 207.044348 -215.082231)
			(xy 207.040988 -215.079326) (xy 207.019949 -215.062583) (xy 206.982333 -215.024164) (xy 206.950483 -214.980844)
			(xy 206.925032 -214.933481) (xy 206.906483 -214.883014) (xy 206.895205 -214.830442) (xy 206.891419 -214.776807)
			(xy 206.895203 -214.723173) (xy 206.906479 -214.6706) (xy 206.925026 -214.620132) (xy 206.950476 -214.572768)
			(xy 206.982323 -214.529447) (xy 207.019938 -214.491027) (xy 207.040988 -214.474298) (xy 207.04434 -214.471385)
			(xy 207.050088 -214.464616) (xy 207.052418 -214.460836) (xy 207.055584 -214.4549) (xy 207.059056 -214.441906)
			(xy 207.059276 -214.435182) (xy 207.059276 -214.04834) (xy 207.058646 -214.03721) (xy 207.04916 -214.017062)
			(xy 207.040988 -214.009478) (xy 206.976726 -213.960202) (xy 206.970198 -213.955901) (xy 206.955327 -213.95111)
			(xy 206.947516 -213.950804) (xy 206.93253 -213.950804) (xy 206.926434 -213.952328) (xy 206.90321 -213.957902)
			(xy 206.855826 -213.963894) (xy 206.831946 -213.964266) (xy 206.804692 -213.963806) (xy 206.750738 -213.956054)
			(xy 206.698437 -213.940701) (xy 206.648854 -213.918061) (xy 206.602998 -213.888594) (xy 206.561804 -213.852899)
			(xy 206.526109 -213.811705) (xy 206.496641 -213.765849) (xy 206.474 -213.716266) (xy 206.458647 -213.663965)
			(xy 206.450895 -213.610012) (xy 206.450438 -213.582758) (xy 206.450926 -213.555521) (xy 206.458681 -213.501603)
			(xy 206.474028 -213.449336) (xy 206.496653 -213.399784) (xy 206.526098 -213.353955) (xy 206.561763 -213.31278)
			(xy 206.602922 -213.277098) (xy 206.648738 -213.247633) (xy 206.698281 -213.224986) (xy 206.750541 -213.209617)
			(xy 206.804456 -213.201838) (xy 206.831692 -213.20125) (xy 206.8322 -213.20125) (xy 206.844646 -213.201504)
			(xy 206.84617 -213.201504) (xy 206.856235 -213.201068) (xy 206.874821 -213.193336) (xy 206.882238 -213.186518)
			(xy 206.88681 -213.1822) (xy 206.935578 -213.10092) (xy 206.941205 -213.090275) (xy 206.942918 -213.066291)
			(xy 206.93888 -213.054946) (xy 206.938372 -213.05393) (xy 206.936086 -213.05012) (xy 206.92428 -213.028488)
			(xy 206.905721 -212.982836) (xy 206.893198 -212.935172) (xy 206.88692 -212.886293) (xy 206.886556 -212.861652)
			(xy 206.886556 -212.86089) (xy 206.887064 -212.842602) (xy 206.887064 -212.839554) (xy 206.887318 -212.83549)
			(xy 206.88808 -212.82533) (xy 206.890985 -212.799176) (xy 206.90307 -212.747959) (xy 206.922078 -212.698889)
			(xy 206.947647 -212.652896) (xy 206.979294 -212.610853) (xy 206.997554 -212.591904) (xy 207.020414 -212.570822)
			(xy 207.020668 -212.570568) (xy 207.024678 -212.566959) (xy 207.031213 -212.558377) (xy 207.033622 -212.55355)
			(xy 207.038448 -212.54339) (xy 207.038448 -212.511132) (xy 207.038448 -212.510624) (xy 207.038702 -212.472524)
			(xy 207.038315 -212.462441) (xy 207.030638 -212.443799) (xy 207.016378 -212.429546) (xy 206.997731 -212.421879)
			(xy 206.987648 -212.42147) (xy 206.976218 -212.421978) (xy 206.963772 -212.426804) (xy 206.957168 -212.43163)
			(xy 206.932176 -212.449734) (xy 206.877573 -212.47848) (xy 206.819057 -212.49807) (xy 206.758152 -212.507994)
			(xy 206.727298 -212.508592) (xy 206.700048 -212.508106) (xy 206.646103 -212.500349) (xy 206.593811 -212.484995)
			(xy 206.544236 -212.462354) (xy 206.498388 -212.432889) (xy 206.457199 -212.397199) (xy 206.42151 -212.356011)
			(xy 206.392045 -212.310162) (xy 206.369405 -212.260588) (xy 206.35405 -212.208295) (xy 206.346294 -212.15435)
			(xy 206.346294 -212.09985) (xy 206.35405 -212.045905) (xy 206.369405 -211.993612) (xy 206.392045 -211.944038)
			(xy 206.42151 -211.898189) (xy 206.457199 -211.857001) (xy 206.498388 -211.821311) (xy 206.544236 -211.791846)
			(xy 206.593811 -211.769205) (xy 206.646103 -211.753851) (xy 206.700048 -211.746094) (xy 206.727298 -211.745576)
			(xy 206.758321 -211.746207) (xy 206.819543 -211.756293) (xy 206.878327 -211.776149) (xy 206.933125 -211.805254)
			(xy 206.958184 -211.823554) (xy 206.958692 -211.823554) (xy 206.9592 -211.824062) (xy 206.965411 -211.82837)
			(xy 206.979612 -211.833528) (xy 206.98714 -211.834222) (xy 206.994252 -211.834476) (xy 207.009238 -211.830666)
			(xy 207.020414 -211.823554) (xy 207.022954 -211.821522) (xy 207.038448 -211.809584) (xy 207.047705 -211.801978)
			(xy 207.058557 -211.780651) (xy 207.059276 -211.76869) (xy 207.059276 -211.240878) (xy 207.05826 -211.230972)
			(xy 207.057585 -211.226806) (xy 207.055026 -211.218765) (xy 207.05318 -211.21497) (xy 207.05191 -211.21243)
			(xy 207.040226 -211.192364) (xy 207.03286 -211.182458) (xy 207.028542 -211.17814) (xy 207.023208 -211.174838)
			(xy 206.999565 -211.159502) (xy 206.956553 -211.123094) (xy 206.91924 -211.080863) (xy 206.888408 -211.033692)
			(xy 206.8647 -210.982569) (xy 206.848614 -210.92856) (xy 206.840484 -210.872797) (xy 206.840481 -210.816444)
			(xy 206.848605 -210.760679) (xy 206.864686 -210.706669) (xy 206.888388 -210.655543) (xy 206.919216 -210.608369)
			(xy 206.956524 -210.566135) (xy 206.999533 -210.529722) (xy 207.023208 -210.514438) (xy 207.028542 -210.511136)
			(xy 207.032606 -210.506818) (xy 207.04048 -210.496658) (xy 207.052418 -210.475576) (xy 207.053942 -210.472782)
			(xy 207.056382 -210.467516) (xy 207.059076 -210.45623) (xy 207.059276 -210.45043) (xy 207.059276 -209.708496)
			(xy 207.059276 -209.708242) (xy 207.058693 -209.69729) (xy 207.049473 -209.677416) (xy 207.041496 -209.669888)
			(xy 207.03413 -209.663538) (xy 207.023462 -209.660236) (xy 206.997454 -209.651634) (xy 206.948025 -209.62802)
			(xy 206.902482 -209.597579) (xy 206.861761 -209.560938) (xy 206.826699 -209.518849) (xy 206.798017 -209.472178)
			(xy 206.776304 -209.421885) (xy 206.7687 -209.395568) (xy 206.762205 -209.369779) (xy 206.755591 -209.317012)
			(xy 206.756369 -209.263837) (xy 206.764525 -209.211286) (xy 206.779899 -209.160377) (xy 206.802196 -209.112096)
			(xy 206.830981 -209.06738) (xy 206.865698 -209.027095) (xy 206.905674 -208.992022) (xy 206.950133 -208.962841)
			(xy 206.998214 -208.940117) (xy 207.023462 -208.931764) (xy 207.026256 -208.931002) (xy 207.035208 -208.927214)
			(xy 207.049597 -208.914167) (xy 207.058117 -208.896712) (xy 207.059276 -208.88706) (xy 207.059276 -208.106264)
			(xy 207.060038 -208.084674) (xy 207.060292 -208.080864) (xy 207.060292 -207.401668) (xy 207.060038 -207.397858)
			(xy 207.059276 -207.376268) (xy 207.059276 -207.120998) (xy 207.058847 -207.111282) (xy 207.05163 -207.093242)
			(xy 207.038228 -207.079172) (xy 207.029558 -207.07477) (xy 206.945484 -207.036416) (xy 206.936473 -207.03277)
			(xy 206.917073 -207.031853) (xy 206.898728 -207.03823) (xy 206.891128 -207.04429) (xy 206.870203 -207.061771)
			(xy 206.824331 -207.091242) (xy 206.774734 -207.113889) (xy 206.72242 -207.129252) (xy 206.668453 -207.137019)
			(xy 206.641192 -207.137508) (xy 206.613941 -207.137022) (xy 206.559994 -207.129264) (xy 206.5077 -207.113908)
			(xy 206.458124 -207.091267) (xy 206.412275 -207.0618) (xy 206.371086 -207.026109) (xy 206.335395 -206.984919)
			(xy 206.305929 -206.939069) (xy 206.283289 -206.889492) (xy 206.267934 -206.837198) (xy 206.260178 -206.783251)
			(xy 206.260178 -206.728749) (xy 206.267934 -206.674802) (xy 206.283289 -206.622508) (xy 206.305929 -206.572931)
			(xy 206.335395 -206.527081) (xy 206.371086 -206.485891) (xy 206.412275 -206.4502) (xy 206.458124 -206.420733)
			(xy 206.5077 -206.398092) (xy 206.559994 -206.382736) (xy 206.613941 -206.374978) (xy 206.641192 -206.374492)
			(xy 206.668456 -206.374955) (xy 206.722428 -206.382715) (xy 206.774746 -206.398078) (xy 206.824345 -206.420731)
			(xy 206.870214 -206.450213) (xy 206.891128 -206.46771) (xy 206.898741 -206.473739) (xy 206.917077 -206.48009)
			(xy 206.93646 -206.479178) (xy 206.945484 -206.475584) (xy 207.029558 -206.43723) (xy 207.038221 -206.43281)
			(xy 207.05164 -206.418756) (xy 207.058869 -206.400718) (xy 207.059276 -206.391002) (xy 207.059276 -202.944476)
			(xy 207.060038 -202.92314) (xy 207.060292 -202.91933) (xy 207.060292 -202.83932) (xy 207.060729 -202.829256)
			(xy 207.068463 -202.810672) (xy 207.075278 -202.803252) (xy 207.132428 -202.746102) (xy 207.133698 -202.744578)
			(xy 207.149192 -202.728068) (xy 207.174338 -202.702922) (xy 207.179328 -202.697424) (xy 207.186179 -202.684259)
			(xy 207.1878 -202.677014) (xy 207.188816 -202.667362) (xy 207.188816 -194.53479) (xy 207.189578 -194.5132)
			(xy 207.189832 -194.50939) (xy 207.189832 -193.279776) (xy 207.19026 -193.269708) (xy 207.197984 -193.251113)
			(xy 207.204818 -193.243708) (xy 207.26273 -193.185796) (xy 207.263238 -193.185288) (xy 207.27125 -193.175989)
			(xy 207.278261 -193.152507) (xy 207.2767 -193.14033) (xy 207.270565 -193.116154) (xy 207.263939 -193.066717)
			(xy 207.263492 -193.041778) (xy 207.263492 -193.04) (xy 207.263917 -193.014218) (xy 207.27086 -192.963125)
			(xy 207.28462 -192.913432) (xy 207.304946 -192.866044) (xy 207.331468 -192.821825) (xy 207.363703 -192.78158)
			(xy 207.401064 -192.746042) (xy 207.421734 -192.730628) (xy 207.421988 -192.730628) (xy 207.422242 -192.730374)
			(xy 207.427039 -192.726595) (xy 207.43486 -192.71722) (xy 207.437736 -192.711832) (xy 207.440276 -192.706244)
			(xy 207.44307 -192.693798) (xy 207.440784 -192.644776) (xy 207.439006 -192.602612) (xy 207.438605 -192.596255)
			(xy 207.435004 -192.584041) (xy 207.431894 -192.578482) (xy 207.428592 -192.573402) (xy 207.420464 -192.564766)
			(xy 207.414368 -192.56121) (xy 207.390539 -192.546327) (xy 207.347128 -192.510665) (xy 207.309418 -192.469019)
			(xy 207.278227 -192.422292) (xy 207.254228 -192.371494) (xy 207.237942 -192.317725) (xy 207.22972 -192.262149)
			(xy 207.229202 -192.234058) (xy 207.229691 -192.206809) (xy 207.237453 -192.152866) (xy 207.252811 -192.100577)
			(xy 207.275455 -192.051006) (xy 207.304923 -192.005162) (xy 207.340614 -191.963977) (xy 207.381803 -191.928291)
			(xy 207.427652 -191.89883) (xy 207.477226 -191.876193) (xy 207.529517 -191.860841) (xy 207.583461 -191.853087)
			(xy 207.61071 -191.85255) (xy 207.621594 -191.852642) (xy 207.643324 -191.853913) (xy 207.654144 -191.85509)
			(xy 207.660494 -191.855852) (xy 207.677512 -191.853312) (xy 207.681068 -191.852296) (xy 207.707864 -191.844713)
			(xy 207.762952 -191.836557) (xy 207.790796 -191.83604) (xy 207.791304 -191.83604) (xy 207.820528 -191.836598)
			(xy 207.878291 -191.845515) (xy 207.934017 -191.863138) (xy 207.986404 -191.889057) (xy 208.034223 -191.922663)
			(xy 208.076356 -191.96317) (xy 208.111817 -192.009631) (xy 208.139775 -192.060958) (xy 208.150206 -192.088262)
			(xy 208.151222 -192.091056) (xy 208.155286 -192.099184) (xy 208.157064 -192.101978) (xy 208.159895 -192.106182)
			(xy 208.166935 -192.113473) (xy 208.171034 -192.116456) (xy 208.178908 -192.12179) (xy 208.188814 -192.124076)
			(xy 208.270094 -192.142364) (xy 208.273728 -192.143103) (xy 208.281125 -192.143611) (xy 208.284826 -192.14338)
			(xy 208.298288 -192.142618) (xy 208.313528 -192.132458) (xy 208.321148 -192.126108) (xy 208.687924 -191.759332)
			(xy 208.700878 -191.74714) (xy 208.703418 -191.744854) (xy 208.81975 -191.628522) (xy 208.825198 -191.622745)
			(xy 208.832455 -191.60863) (xy 208.833974 -191.600836) (xy 208.835752 -191.590168) (xy 208.835752 -191.573404)
			(xy 208.83455 -191.567217) (xy 208.829532 -191.555658) (xy 208.825846 -191.550544) (xy 208.822544 -191.54648)
			(xy 208.822036 -191.544702) (xy 208.804764 -191.491362) (xy 208.802448 -191.484724) (xy 208.794714 -191.47299)
			(xy 208.789524 -191.468248) (xy 208.784444 -191.46393) (xy 208.771998 -191.458342) (xy 208.764632 -191.457072)
			(xy 208.738129 -191.452267) (xy 208.686721 -191.436189) (xy 208.63808 -191.413055) (xy 208.593167 -191.383322)
			(xy 208.552872 -191.347579) (xy 208.517993 -191.306535) (xy 208.489221 -191.261) (xy 208.467125 -191.211878)
			(xy 208.452143 -191.160141) (xy 208.444571 -191.106813) (xy 208.444084 -191.079882) (xy 208.444572 -191.052576)
			(xy 208.452346 -190.99852) (xy 208.467733 -190.94612) (xy 208.490419 -190.896443) (xy 208.519944 -190.8505)
			(xy 208.555706 -190.809226) (xy 208.596978 -190.773461) (xy 208.642919 -190.743933) (xy 208.692594 -190.721242)
			(xy 208.744993 -190.705852) (xy 208.799048 -190.698074) (xy 208.826354 -190.697612) (xy 208.853651 -190.698095)
			(xy 208.90769 -190.705855) (xy 208.960075 -190.721224) (xy 209.009742 -190.743889) (xy 209.055678 -190.773389)
			(xy 209.096951 -190.809124) (xy 209.132721 -190.850367) (xy 209.162259 -190.896279) (xy 209.184965 -190.945926)
			(xy 209.200377 -190.998299) (xy 209.208182 -191.052332) (xy 209.208624 -191.079628) (xy 209.208624 -191.079882)
			(xy 209.207862 -191.09944) (xy 209.207608 -191.101218) (xy 209.207608 -191.105028) (xy 209.206846 -191.115696)
			(xy 209.210402 -191.125602) (xy 209.212313 -191.130445) (xy 209.217817 -191.13928) (xy 209.221324 -191.143128)
			(xy 209.271108 -191.196214) (xy 209.27314 -191.198246) (xy 209.278641 -191.203229) (xy 209.29181 -191.210063)
			(xy 209.299048 -191.211708) (xy 209.3087 -191.212724) (xy 209.351372 -191.212724) (xy 209.36077 -191.212216)
			(xy 211.5058 -191.212216) (xy 211.507324 -191.212724) (xy 211.551012 -191.212724) (xy 211.556109 -191.212838)
			(xy 211.566094 -191.214887) (xy 211.570824 -191.216788) (xy 211.579968 -191.220598) (xy 211.582762 -191.223392)
			(xy 211.584286 -191.224662) (xy 211.616798 -191.257174) (xy 211.620862 -191.258698) (xy 211.663788 -191.303148)
			(xy 211.664296 -191.303656) (xy 212.974682 -192.614042) (xy 212.987382 -192.627504) (xy 212.989668 -192.630044)
			(xy 213.018624 -192.659) (xy 215.390982 -192.659) (xy 215.395053 -192.603378) (xy 215.407179 -192.548941)
			(xy 215.427102 -192.49685) (xy 215.454398 -192.448215) (xy 215.488484 -192.404072) (xy 215.528633 -192.365363)
			(xy 215.573991 -192.332912) (xy 215.623591 -192.307411) (xy 215.676375 -192.289404) (xy 215.731218 -192.279274)
			(xy 215.786952 -192.277237) (xy 215.842389 -192.283337) (xy 215.896346 -192.297443) (xy 215.947675 -192.319255)
			(xy 215.995281 -192.348309) (xy 216.038149 -192.383984) (xy 216.075366 -192.425521) (xy 216.106139 -192.472034)
			(xy 216.129811 -192.522531) (xy 216.145879 -192.575938) (xy 216.153999 -192.631114) (xy 216.154508 -192.659)
			(xy 216.153999 -192.686886) (xy 216.145879 -192.742062) (xy 216.129811 -192.795469) (xy 216.106139 -192.845966)
			(xy 216.075366 -192.892479) (xy 216.038149 -192.934016) (xy 215.995281 -192.969691) (xy 215.947675 -192.998745)
			(xy 215.896346 -193.020557) (xy 215.842389 -193.034663) (xy 215.786952 -193.040763) (xy 215.731218 -193.038726)
			(xy 215.676375 -193.028596) (xy 215.623591 -193.010589) (xy 215.573991 -192.985088) (xy 215.528633 -192.952637)
			(xy 215.488484 -192.913928) (xy 215.454398 -192.869785) (xy 215.427102 -192.82115) (xy 215.407179 -192.769059)
			(xy 215.395053 -192.714622) (xy 215.390982 -192.659) (xy 213.018624 -192.659) (xy 213.051898 -192.692274)
			(xy 213.053168 -192.693798) (xy 213.055962 -192.696592) (xy 213.059772 -192.705736) (xy 213.06164 -192.710476)
			(xy 213.06368 -192.720456) (xy 213.063836 -192.725548) (xy 213.063836 -192.820036) (xy 213.064344 -192.830196)
			(xy 213.064344 -193.929) (xy 215.390982 -193.929) (xy 215.395053 -193.873378) (xy 215.407179 -193.818941)
			(xy 215.427102 -193.76685) (xy 215.454398 -193.718215) (xy 215.488484 -193.674072) (xy 215.528633 -193.635363)
			(xy 215.573991 -193.602912) (xy 215.623591 -193.577411) (xy 215.676375 -193.559404) (xy 215.731218 -193.549274)
			(xy 215.786952 -193.547237) (xy 215.842389 -193.553337) (xy 215.896346 -193.567443) (xy 215.947675 -193.589255)
			(xy 215.995281 -193.618309) (xy 216.038149 -193.653984) (xy 216.075366 -193.695521) (xy 216.106139 -193.742034)
			(xy 216.129811 -193.792531) (xy 216.145879 -193.845938) (xy 216.153999 -193.901114) (xy 216.154508 -193.929)
			(xy 216.153999 -193.956886) (xy 216.145879 -194.012062) (xy 216.129811 -194.065469) (xy 216.106139 -194.115966)
			(xy 216.075366 -194.162479) (xy 216.038149 -194.204016) (xy 215.995281 -194.239691) (xy 215.947675 -194.268745)
			(xy 215.896346 -194.290557) (xy 215.842389 -194.304663) (xy 215.786952 -194.310763) (xy 215.731218 -194.308726)
			(xy 215.676375 -194.298596) (xy 215.623591 -194.280589) (xy 215.573991 -194.255088) (xy 215.528633 -194.222637)
			(xy 215.488484 -194.183928) (xy 215.454398 -194.139785) (xy 215.427102 -194.09115) (xy 215.407179 -194.039059)
			(xy 215.395053 -193.984622) (xy 215.390982 -193.929) (xy 213.064344 -193.929) (xy 213.064344 -195.458334)
			(xy 213.653876 -195.458334) (xy 213.657947 -195.402712) (xy 213.670073 -195.348275) (xy 213.689996 -195.296184)
			(xy 213.717292 -195.247549) (xy 213.751378 -195.203406) (xy 213.791527 -195.164697) (xy 213.836885 -195.132246)
			(xy 213.886485 -195.106745) (xy 213.939269 -195.088738) (xy 213.994112 -195.078608) (xy 214.049846 -195.076571)
			(xy 214.105283 -195.082671) (xy 214.15924 -195.096777) (xy 214.210569 -195.118589) (xy 214.258175 -195.147643)
			(xy 214.301043 -195.183318) (xy 214.33826 -195.224855) (xy 214.369033 -195.271368) (xy 214.392705 -195.321865)
			(xy 214.408773 -195.375272) (xy 214.416893 -195.430448) (xy 214.417402 -195.458334) (xy 214.416893 -195.48622)
			(xy 214.408773 -195.541396) (xy 214.392705 -195.594803) (xy 214.369033 -195.6453) (xy 214.33826 -195.691813)
			(xy 214.301043 -195.73335) (xy 214.258175 -195.769025) (xy 214.210569 -195.798079) (xy 214.15924 -195.819891)
			(xy 214.105283 -195.833997) (xy 214.049846 -195.840097) (xy 213.994112 -195.83806) (xy 213.939269 -195.82793)
			(xy 213.886485 -195.809923) (xy 213.836885 -195.784422) (xy 213.791527 -195.751971) (xy 213.751378 -195.713262)
			(xy 213.717292 -195.669119) (xy 213.689996 -195.620484) (xy 213.670073 -195.568393) (xy 213.657947 -195.513956)
			(xy 213.653876 -195.458334) (xy 213.064344 -195.458334) (xy 213.064344 -196.108066) (xy 214.501982 -196.108066)
			(xy 214.506053 -196.052444) (xy 214.518179 -195.998007) (xy 214.538102 -195.945916) (xy 214.565398 -195.897281)
			(xy 214.599484 -195.853138) (xy 214.639633 -195.814429) (xy 214.684991 -195.781978) (xy 214.734591 -195.756477)
			(xy 214.787375 -195.73847) (xy 214.842218 -195.72834) (xy 214.897952 -195.726303) (xy 214.953389 -195.732403)
			(xy 215.007346 -195.746509) (xy 215.058675 -195.768321) (xy 215.106281 -195.797375) (xy 215.149149 -195.83305)
			(xy 215.186366 -195.874587) (xy 215.217139 -195.9211) (xy 215.240811 -195.971597) (xy 215.256879 -196.025004)
			(xy 215.264999 -196.08018) (xy 215.265508 -196.108066) (xy 215.264999 -196.135952) (xy 215.256879 -196.191128)
			(xy 215.240811 -196.244535) (xy 215.217139 -196.295032) (xy 215.186366 -196.341545) (xy 215.149149 -196.383082)
			(xy 215.106281 -196.418757) (xy 215.058675 -196.447811) (xy 215.007346 -196.469623) (xy 214.953389 -196.483729)
			(xy 214.897952 -196.489829) (xy 214.842218 -196.487792) (xy 214.787375 -196.477662) (xy 214.734591 -196.459655)
			(xy 214.684991 -196.434154) (xy 214.639633 -196.401703) (xy 214.599484 -196.362994) (xy 214.565398 -196.318851)
			(xy 214.538102 -196.270216) (xy 214.518179 -196.218125) (xy 214.506053 -196.163688) (xy 214.501982 -196.108066)
			(xy 213.064344 -196.108066) (xy 213.064344 -196.114162) (xy 213.066376 -196.12102) (xy 213.073587 -196.14723)
			(xy 213.081363 -196.201029) (xy 213.08187 -196.228208) (xy 213.08187 -196.228716) (xy 213.081349 -196.255893)
			(xy 213.073569 -196.30969) (xy 213.066376 -196.335904) (xy 213.064344 -196.342762) (xy 213.064344 -196.596)
			(xy 217.803982 -196.596) (xy 217.808053 -196.540378) (xy 217.820179 -196.485941) (xy 217.840102 -196.43385)
			(xy 217.867398 -196.385215) (xy 217.901484 -196.341072) (xy 217.941633 -196.302363) (xy 217.986991 -196.269912)
			(xy 218.036591 -196.244411) (xy 218.089375 -196.226404) (xy 218.144218 -196.216274) (xy 218.199952 -196.214237)
			(xy 218.255389 -196.220337) (xy 218.309346 -196.234443) (xy 218.360675 -196.256255) (xy 218.408281 -196.285309)
			(xy 218.451149 -196.320984) (xy 218.488366 -196.362521) (xy 218.519139 -196.409034) (xy 218.542811 -196.459531)
			(xy 218.558879 -196.512938) (xy 218.566999 -196.568114) (xy 218.567508 -196.596) (xy 218.566999 -196.623886)
			(xy 218.558879 -196.679062) (xy 218.542811 -196.732469) (xy 218.519139 -196.782966) (xy 218.488366 -196.829479)
			(xy 218.451149 -196.871016) (xy 218.408281 -196.906691) (xy 218.360675 -196.935745) (xy 218.309346 -196.957557)
			(xy 218.255389 -196.971663) (xy 218.199952 -196.977763) (xy 218.144218 -196.975726) (xy 218.089375 -196.965596)
			(xy 218.036591 -196.947589) (xy 217.986991 -196.922088) (xy 217.941633 -196.889637) (xy 217.901484 -196.850928)
			(xy 217.867398 -196.806785) (xy 217.840102 -196.75815) (xy 217.820179 -196.706059) (xy 217.808053 -196.651622)
			(xy 217.803982 -196.596) (xy 213.064344 -196.596) (xy 213.064344 -197.231) (xy 215.390982 -197.231)
			(xy 215.395053 -197.175378) (xy 215.407179 -197.120941) (xy 215.427102 -197.06885) (xy 215.454398 -197.020215)
			(xy 215.488484 -196.976072) (xy 215.528633 -196.937363) (xy 215.573991 -196.904912) (xy 215.623591 -196.879411)
			(xy 215.676375 -196.861404) (xy 215.731218 -196.851274) (xy 215.786952 -196.849237) (xy 215.842389 -196.855337)
			(xy 215.896346 -196.869443) (xy 215.947675 -196.891255) (xy 215.995281 -196.920309) (xy 216.038149 -196.955984)
			(xy 216.075366 -196.997521) (xy 216.106139 -197.044034) (xy 216.129811 -197.094531) (xy 216.145879 -197.147938)
			(xy 216.153999 -197.203114) (xy 216.154508 -197.231) (xy 216.153999 -197.258886) (xy 216.145879 -197.314062)
			(xy 216.129811 -197.367469) (xy 216.106139 -197.417966) (xy 216.075366 -197.464479) (xy 216.038149 -197.506016)
			(xy 215.995281 -197.541691) (xy 215.947675 -197.570745) (xy 215.896346 -197.592557) (xy 215.842389 -197.606663)
			(xy 215.786952 -197.612763) (xy 215.731218 -197.610726) (xy 215.676375 -197.600596) (xy 215.623591 -197.582589)
			(xy 215.573991 -197.557088) (xy 215.528633 -197.524637) (xy 215.488484 -197.485928) (xy 215.454398 -197.441785)
			(xy 215.427102 -197.39315) (xy 215.407179 -197.341059) (xy 215.395053 -197.286622) (xy 215.390982 -197.231)
			(xy 213.064344 -197.231) (xy 213.064344 -198.501) (xy 215.390982 -198.501) (xy 215.395053 -198.445378)
			(xy 215.407179 -198.390941) (xy 215.427102 -198.33885) (xy 215.454398 -198.290215) (xy 215.488484 -198.246072)
			(xy 215.528633 -198.207363) (xy 215.573991 -198.174912) (xy 215.623591 -198.149411) (xy 215.676375 -198.131404)
			(xy 215.731218 -198.121274) (xy 215.786952 -198.119237) (xy 215.842389 -198.125337) (xy 215.896346 -198.139443)
			(xy 215.947675 -198.161255) (xy 215.995281 -198.190309) (xy 216.038149 -198.225984) (xy 216.075366 -198.267521)
			(xy 216.106139 -198.314034) (xy 216.129811 -198.364531) (xy 216.13266 -198.374) (xy 217.804492 -198.374)
			(xy 217.804975 -198.345081) (xy 217.813707 -198.287907) (xy 217.830969 -198.232706) (xy 217.856367 -198.180744)
			(xy 217.889319 -198.133211) (xy 217.929068 -198.091197) (xy 217.951558 -198.07301) (xy 217.96036 -198.065399)
			(xy 217.970544 -198.044501) (xy 217.971116 -198.032878) (xy 217.971116 -197.953122) (xy 217.970544 -197.941494)
			(xy 217.960378 -197.920585) (xy 217.951558 -197.91299) (xy 217.929061 -197.894815) (xy 217.889329 -197.852791)
			(xy 217.856392 -197.805252) (xy 217.831007 -197.753288) (xy 217.813753 -197.698088) (xy 217.805026 -197.640917)
			(xy 217.804492 -197.612) (xy 217.804978 -197.584749) (xy 217.812734 -197.530801) (xy 217.828089 -197.478506)
			(xy 217.850731 -197.428929) (xy 217.880197 -197.383079) (xy 217.915888 -197.341888) (xy 217.957079 -197.306197)
			(xy 218.002929 -197.276731) (xy 218.052506 -197.254089) (xy 218.104801 -197.238734) (xy 218.158749 -197.230978)
			(xy 218.213251 -197.230978) (xy 218.267199 -197.238734) (xy 218.319494 -197.254089) (xy 218.369071 -197.276731)
			(xy 218.414921 -197.306197) (xy 218.456112 -197.341888) (xy 218.491803 -197.383079) (xy 218.521269 -197.428929)
			(xy 218.543911 -197.478506) (xy 218.559266 -197.530801) (xy 218.567022 -197.584749) (xy 218.567508 -197.612)
			(xy 218.567025 -197.640919) (xy 218.558293 -197.698093) (xy 218.541031 -197.753294) (xy 218.515633 -197.805256)
			(xy 218.482681 -197.852789) (xy 218.442932 -197.894803) (xy 218.420442 -197.91299) (xy 218.41164 -197.920601)
			(xy 218.401456 -197.941499) (xy 218.400884 -197.953122) (xy 218.400884 -198.032878) (xy 218.401456 -198.044506)
			(xy 218.411622 -198.065415) (xy 218.420442 -198.07301) (xy 218.442939 -198.091185) (xy 218.482671 -198.133209)
			(xy 218.515608 -198.180748) (xy 218.540993 -198.232712) (xy 218.558247 -198.287912) (xy 218.566974 -198.345083)
			(xy 218.567508 -198.374) (xy 218.567022 -198.401251) (xy 218.559266 -198.455199) (xy 218.543911 -198.507494)
			(xy 218.521269 -198.557071) (xy 218.491803 -198.602921) (xy 218.456112 -198.644112) (xy 218.414921 -198.679803)
			(xy 218.369071 -198.709269) (xy 218.319494 -198.731911) (xy 218.267199 -198.747266) (xy 218.213251 -198.755022)
			(xy 218.158749 -198.755022) (xy 218.104801 -198.747266) (xy 218.052506 -198.731911) (xy 218.002929 -198.709269)
			(xy 217.957079 -198.679803) (xy 217.915888 -198.644112) (xy 217.880197 -198.602921) (xy 217.850731 -198.557071)
			(xy 217.828089 -198.507494) (xy 217.812734 -198.455199) (xy 217.804978 -198.401251) (xy 217.804492 -198.374)
			(xy 216.13266 -198.374) (xy 216.145879 -198.417938) (xy 216.153999 -198.473114) (xy 216.154508 -198.501)
			(xy 216.153999 -198.528886) (xy 216.145879 -198.584062) (xy 216.129811 -198.637469) (xy 216.106139 -198.687966)
			(xy 216.075366 -198.734479) (xy 216.038149 -198.776016) (xy 215.995281 -198.811691) (xy 215.947675 -198.840745)
			(xy 215.896346 -198.862557) (xy 215.842389 -198.876663) (xy 215.786952 -198.882763) (xy 215.731218 -198.880726)
			(xy 215.676375 -198.870596) (xy 215.623591 -198.852589) (xy 215.573991 -198.827088) (xy 215.528633 -198.794637)
			(xy 215.488484 -198.755928) (xy 215.454398 -198.711785) (xy 215.427102 -198.66315) (xy 215.407179 -198.611059)
			(xy 215.395053 -198.556622) (xy 215.390982 -198.501) (xy 213.064344 -198.501) (xy 213.064344 -200.631298)
			(xy 216.35161 -200.631298) (xy 216.355681 -200.575676) (xy 216.367807 -200.521239) (xy 216.38773 -200.469148)
			(xy 216.415026 -200.420513) (xy 216.449112 -200.37637) (xy 216.489261 -200.337661) (xy 216.534619 -200.30521)
			(xy 216.584219 -200.279709) (xy 216.637003 -200.261702) (xy 216.691846 -200.251572) (xy 216.74758 -200.249535)
			(xy 216.803017 -200.255635) (xy 216.856974 -200.269741) (xy 216.908303 -200.291553) (xy 216.955909 -200.320607)
			(xy 216.998777 -200.356282) (xy 217.035994 -200.397819) (xy 217.066767 -200.444332) (xy 217.090439 -200.494829)
			(xy 217.106507 -200.548236) (xy 217.114627 -200.603412) (xy 217.115136 -200.631298) (xy 217.114627 -200.659184)
			(xy 217.106507 -200.71436) (xy 217.090439 -200.767767) (xy 217.066767 -200.818264) (xy 217.035994 -200.864777)
			(xy 216.998777 -200.906314) (xy 216.955909 -200.941989) (xy 216.908303 -200.971043) (xy 216.856974 -200.992855)
			(xy 216.803017 -201.006961) (xy 216.74758 -201.013061) (xy 216.691846 -201.011024) (xy 216.637003 -201.000894)
			(xy 216.584219 -200.982887) (xy 216.534619 -200.957386) (xy 216.489261 -200.924935) (xy 216.449112 -200.886226)
			(xy 216.415026 -200.842083) (xy 216.38773 -200.793448) (xy 216.367807 -200.741357) (xy 216.355681 -200.68692)
			(xy 216.35161 -200.631298) (xy 213.064344 -200.631298) (xy 213.064344 -201.803) (xy 215.390982 -201.803)
			(xy 215.395053 -201.747378) (xy 215.407179 -201.692941) (xy 215.427102 -201.64085) (xy 215.454398 -201.592215)
			(xy 215.488484 -201.548072) (xy 215.528633 -201.509363) (xy 215.573991 -201.476912) (xy 215.623591 -201.451411)
			(xy 215.676375 -201.433404) (xy 215.731218 -201.423274) (xy 215.786952 -201.421237) (xy 215.842389 -201.427337)
			(xy 215.896346 -201.441443) (xy 215.947675 -201.463255) (xy 215.995281 -201.492309) (xy 216.038149 -201.527984)
			(xy 216.075366 -201.569521) (xy 216.106139 -201.616034) (xy 216.129811 -201.666531) (xy 216.145879 -201.719938)
			(xy 216.153999 -201.775114) (xy 216.154508 -201.803) (xy 216.153999 -201.830886) (xy 216.145879 -201.886062)
			(xy 216.129811 -201.939469) (xy 216.106139 -201.989966) (xy 216.075366 -202.036479) (xy 216.038149 -202.078016)
			(xy 215.995281 -202.113691) (xy 215.947675 -202.142745) (xy 215.896346 -202.164557) (xy 215.842389 -202.178663)
			(xy 215.793886 -202.184) (xy 217.803982 -202.184) (xy 217.808053 -202.128378) (xy 217.820179 -202.073941)
			(xy 217.840102 -202.02185) (xy 217.867398 -201.973215) (xy 217.901484 -201.929072) (xy 217.941633 -201.890363)
			(xy 217.986991 -201.857912) (xy 218.036591 -201.832411) (xy 218.089375 -201.814404) (xy 218.144218 -201.804274)
			(xy 218.199952 -201.802237) (xy 218.255389 -201.808337) (xy 218.309346 -201.822443) (xy 218.360675 -201.844255)
			(xy 218.408281 -201.873309) (xy 218.451149 -201.908984) (xy 218.488366 -201.950521) (xy 218.519139 -201.997034)
			(xy 218.542811 -202.047531) (xy 218.558879 -202.100938) (xy 218.566999 -202.156114) (xy 218.567508 -202.184)
			(xy 218.566999 -202.211886) (xy 218.558879 -202.267062) (xy 218.542811 -202.320469) (xy 218.519139 -202.370966)
			(xy 218.488366 -202.417479) (xy 218.451149 -202.459016) (xy 218.408281 -202.494691) (xy 218.360675 -202.523745)
			(xy 218.309346 -202.545557) (xy 218.255389 -202.559663) (xy 218.199952 -202.565763) (xy 218.144218 -202.563726)
			(xy 218.089375 -202.553596) (xy 218.036591 -202.535589) (xy 217.986991 -202.510088) (xy 217.941633 -202.477637)
			(xy 217.901484 -202.438928) (xy 217.867398 -202.394785) (xy 217.840102 -202.34615) (xy 217.820179 -202.294059)
			(xy 217.808053 -202.239622) (xy 217.803982 -202.184) (xy 215.793886 -202.184) (xy 215.786952 -202.184763)
			(xy 215.731218 -202.182726) (xy 215.676375 -202.172596) (xy 215.623591 -202.154589) (xy 215.573991 -202.129088)
			(xy 215.528633 -202.096637) (xy 215.488484 -202.057928) (xy 215.454398 -202.013785) (xy 215.427102 -201.96515)
			(xy 215.407179 -201.913059) (xy 215.395053 -201.858622) (xy 215.390982 -201.803) (xy 213.064344 -201.803)
			(xy 213.064344 -203.073) (xy 215.390982 -203.073) (xy 215.395053 -203.017378) (xy 215.407179 -202.962941)
			(xy 215.427102 -202.91085) (xy 215.454398 -202.862215) (xy 215.488484 -202.818072) (xy 215.528633 -202.779363)
			(xy 215.573991 -202.746912) (xy 215.623591 -202.721411) (xy 215.676375 -202.703404) (xy 215.731218 -202.693274)
			(xy 215.786952 -202.691237) (xy 215.842389 -202.697337) (xy 215.896346 -202.711443) (xy 215.947675 -202.733255)
			(xy 215.995281 -202.762309) (xy 216.038149 -202.797984) (xy 216.075366 -202.839521) (xy 216.106139 -202.886034)
			(xy 216.129811 -202.936531) (xy 216.145879 -202.989938) (xy 216.153999 -203.045114) (xy 216.154508 -203.073)
			(xy 216.153999 -203.100886) (xy 216.145879 -203.156062) (xy 216.13266 -203.2) (xy 217.803982 -203.2)
			(xy 217.808053 -203.144378) (xy 217.820179 -203.089941) (xy 217.840102 -203.03785) (xy 217.867398 -202.989215)
			(xy 217.901484 -202.945072) (xy 217.941633 -202.906363) (xy 217.986991 -202.873912) (xy 218.036591 -202.848411)
			(xy 218.089375 -202.830404) (xy 218.144218 -202.820274) (xy 218.199952 -202.818237) (xy 218.255389 -202.824337)
			(xy 218.309346 -202.838443) (xy 218.360675 -202.860255) (xy 218.408281 -202.889309) (xy 218.451149 -202.924984)
			(xy 218.488366 -202.966521) (xy 218.519139 -203.013034) (xy 218.542811 -203.063531) (xy 218.558879 -203.116938)
			(xy 218.566999 -203.172114) (xy 218.567508 -203.2) (xy 218.566999 -203.227886) (xy 218.558879 -203.283062)
			(xy 218.542811 -203.336469) (xy 218.519139 -203.386966) (xy 218.488366 -203.433479) (xy 218.451149 -203.475016)
			(xy 218.408281 -203.510691) (xy 218.360675 -203.539745) (xy 218.309346 -203.561557) (xy 218.255389 -203.575663)
			(xy 218.199952 -203.581763) (xy 218.144218 -203.579726) (xy 218.089375 -203.569596) (xy 218.036591 -203.551589)
			(xy 217.986991 -203.526088) (xy 217.941633 -203.493637) (xy 217.901484 -203.454928) (xy 217.867398 -203.410785)
			(xy 217.840102 -203.36215) (xy 217.820179 -203.310059) (xy 217.808053 -203.255622) (xy 217.803982 -203.2)
			(xy 216.13266 -203.2) (xy 216.129811 -203.209469) (xy 216.106139 -203.259966) (xy 216.075366 -203.306479)
			(xy 216.038149 -203.348016) (xy 215.995281 -203.383691) (xy 215.947675 -203.412745) (xy 215.896346 -203.434557)
			(xy 215.842389 -203.448663) (xy 215.786952 -203.454763) (xy 215.731218 -203.452726) (xy 215.676375 -203.442596)
			(xy 215.623591 -203.424589) (xy 215.573991 -203.399088) (xy 215.528633 -203.366637) (xy 215.488484 -203.327928)
			(xy 215.454398 -203.283785) (xy 215.427102 -203.23515) (xy 215.407179 -203.183059) (xy 215.395053 -203.128622)
			(xy 215.390982 -203.073) (xy 213.064344 -203.073) (xy 213.064344 -204.09535) (xy 213.065106 -204.103732)
			(xy 213.066625 -204.111334) (xy 213.073619 -204.125161) (xy 213.078822 -204.13091) (xy 214.79383 -205.845918)
			(xy 214.79958 -205.851115) (xy 214.813412 -205.858093) (xy 214.821008 -205.859634) (xy 214.82939 -205.860396)
			(xy 215.316816 -205.860396) (xy 215.32723 -205.860904) (xy 216.21877 -205.860904) (xy 216.229184 -205.860396)
			(xy 217.497914 -205.860396) (xy 217.504494 -205.860184) (xy 217.517224 -205.85684) (xy 217.52306 -205.853792)
			(xy 217.529493 -205.849849) (xy 217.539819 -205.838855) (xy 217.54338 -205.832202) (xy 217.54465 -205.829662)
			(xy 217.546682 -205.82509) (xy 217.54719 -205.823566) (xy 217.556711 -205.79935) (xy 217.581375 -205.753534)
			(xy 217.612026 -205.711487) (xy 217.648099 -205.673987) (xy 217.688925 -205.641727) (xy 217.73375 -205.615305)
			(xy 217.781745 -205.595208) (xy 217.806778 -205.588108) (xy 217.81643 -205.585568) (xy 217.824558 -205.579472)
			(xy 217.848688 -205.561184) (xy 217.850974 -205.55712) (xy 217.854022 -205.551786) (xy 217.868681 -205.527029)
			(xy 217.904275 -205.481829) (xy 217.946249 -205.442482) (xy 217.993652 -205.409879) (xy 218.04541 -205.384757)
			(xy 218.100352 -205.367687) (xy 218.157234 -205.359054) (xy 218.186 -205.358492) (xy 218.213251 -205.358978)
			(xy 218.267199 -205.366734) (xy 218.319494 -205.382089) (xy 218.369071 -205.404731) (xy 218.414921 -205.434197)
			(xy 218.456112 -205.469888) (xy 218.491803 -205.511079) (xy 218.521269 -205.556929) (xy 218.543911 -205.606506)
			(xy 218.559266 -205.658801) (xy 218.567022 -205.712749) (xy 218.567508 -205.74) (xy 218.567254 -205.75524)
			(xy 218.566746 -205.765908) (xy 218.570302 -205.775306) (xy 218.572186 -205.780062) (xy 218.577569 -205.788757)
			(xy 218.58097 -205.792578) (xy 218.59494 -205.806802) (xy 218.59494 -205.80731) (xy 218.63304 -205.846426)
			(xy 218.638747 -205.851539) (xy 218.65245 -205.858382) (xy 218.659964 -205.859888) (xy 218.668092 -205.860396)
			(xy 219.365322 -205.860396) (xy 219.375736 -205.860904) (xy 219.411804 -205.860904) (xy 219.421553 -205.860477)
			(xy 219.439638 -205.853196) (xy 219.45367 -205.83966) (xy 219.458032 -205.830932) (xy 219.458286 -205.830424)
			(xy 219.471401 -205.8016) (xy 219.503767 -205.74717) (xy 219.542659 -205.697194) (xy 219.564712 -205.674468)
			(xy 219.727526 -205.511654) (xy 219.750132 -205.488794) (xy 219.756776 -205.481436) (xy 219.764349 -205.463135)
			(xy 219.764864 -205.453234) (xy 219.764864 -204.130656) (xy 219.764431 -204.120617) (xy 219.756712 -204.102081)
			(xy 219.742473 -204.087923) (xy 219.733368 -204.083666) (xy 219.721176 -204.07884) (xy 219.714178 -204.076247)
			(xy 219.69933 -204.074832) (xy 219.691966 -204.076046) (xy 219.6846 -204.07757) (xy 219.6719 -204.084428)
			(xy 219.324936 -204.431392) (xy 219.32141 -204.43512) (xy 219.315772 -204.44369) (xy 219.31376 -204.44841)
			(xy 219.310204 -204.457046) (xy 219.310204 -204.851) (xy 219.309703 -204.882945) (xy 219.301695 -204.946331)
			(xy 219.285806 -205.008214) (xy 219.262287 -205.067618) (xy 219.231507 -205.123605) (xy 219.193954 -205.175294)
			(xy 219.150218 -205.221868) (xy 219.10099 -205.262593) (xy 219.047045 -205.296827) (xy 218.989236 -205.32403)
			(xy 218.928473 -205.343773) (xy 218.865714 -205.355745) (xy 218.80195 -205.359757) (xy 218.738186 -205.355745)
			(xy 218.675427 -205.343773) (xy 218.614664 -205.32403) (xy 218.556855 -205.296827) (xy 218.50291 -205.262593)
			(xy 218.453682 -205.221868) (xy 218.409946 -205.175294) (xy 218.372393 -205.123605) (xy 218.341613 -205.067618)
			(xy 218.318094 -205.008214) (xy 218.302205 -204.946331) (xy 218.294197 -204.882945) (xy 218.293696 -204.851)
			(xy 218.293696 -204.235304) (xy 218.294239 -204.202026) (xy 218.302924 -204.136039) (xy 218.320145 -204.071749)
			(xy 218.345608 -204.010256) (xy 218.378878 -203.952612) (xy 218.419385 -203.899802) (xy 218.44254 -203.875894)
			(xy 218.46667 -203.85151) (xy 218.78163 -203.53655) (xy 218.786824 -203.530798) (xy 218.793794 -203.516965)
			(xy 218.795346 -203.509372) (xy 218.796108 -203.50099) (xy 218.796108 -202.08113) (xy 218.796641 -202.047841)
			(xy 218.805357 -201.981836) (xy 218.822617 -201.917535) (xy 218.848127 -201.856037) (xy 218.881448 -201.798398)
			(xy 218.922011 -201.745603) (xy 218.945206 -201.72172) (xy 221.760034 -198.906892) (xy 221.765241 -198.901147)
			(xy 221.772236 -198.887317) (xy 221.77375 -198.879714) (xy 221.774512 -198.871332) (xy 221.774512 -198.241158)
			(xy 221.775049 -198.207871) (xy 221.783774 -198.141871) (xy 221.801042 -198.077575) (xy 221.826557 -198.016084)
			(xy 221.859884 -197.958452) (xy 221.90045 -197.905664) (xy 221.92361 -197.881748) (xy 225.008186 -194.797172)
			(xy 225.008694 -194.796664) (xy 225.013893 -194.790915) (xy 225.020872 -194.777083) (xy 225.02241 -194.769486)
			(xy 225.023172 -194.761104) (xy 225.023172 -189.552072) (xy 225.023247 -189.539287) (xy 225.02452 -189.513748)
			(xy 225.025712 -189.501018) (xy 225.025712 -189.498986) (xy 225.029776 -189.45987) (xy 225.030284 -189.454028)
			(xy 225.030039 -189.443602) (xy 225.022244 -189.424282) (xy 225.007429 -189.409634) (xy 224.988021 -189.40206)
			(xy 224.9672 -189.402799) (xy 224.948379 -189.411732) (xy 224.94113 -189.41923) (xy 224.922924 -189.439379)
			(xy 224.881793 -189.474833) (xy 224.836051 -189.5041) (xy 224.786623 -189.526586) (xy 224.734506 -189.54184)
			(xy 224.680753 -189.549551) (xy 224.653602 -189.55004) (xy 224.624353 -189.549482) (xy 224.566541 -189.54056)
			(xy 224.510765 -189.522925) (xy 224.458332 -189.496988) (xy 224.410468 -189.463358) (xy 224.368294 -189.422821)
			(xy 224.332796 -189.376326) (xy 224.318322 -189.350904) (xy 224.310901 -189.338288) (xy 224.290198 -189.317614)
			(xy 224.264491 -189.303645) (xy 224.235881 -189.297524) (xy 224.206708 -189.29975) (xy 224.179358 -189.310143)
			(xy 224.167446 -189.318646) (xy 224.147405 -189.333423) (xy 224.104221 -189.358213) (xy 224.058182 -189.37718)
			(xy 224.010067 -189.390002) (xy 223.960695 -189.396461) (xy 223.935798 -189.396878) (xy 223.908333 -189.396401)
			(xy 223.853971 -189.38853) (xy 223.801297 -189.372952) (xy 223.751398 -189.349988) (xy 223.705304 -189.320111)
			(xy 223.663967 -189.283938) (xy 223.628239 -189.242216) (xy 223.598857 -189.195805) (xy 223.576428 -189.145664)
			(xy 223.561415 -189.092826) (xy 223.557338 -189.065662) (xy 223.554929 -189.051286) (xy 223.543048 -189.024682)
			(xy 223.524137 -189.002516) (xy 223.499736 -188.986593) (xy 223.471831 -188.978209) (xy 223.442695 -188.978047)
			(xy 223.414699 -188.986119) (xy 223.402144 -188.993526) (xy 223.393254 -188.999622) (xy 223.369732 -189.014638)
			(xy 223.319225 -189.038371) (xy 223.265797 -189.054485) (xy 223.21059 -189.062635) (xy 223.182688 -189.063122)
			(xy 223.18218 -189.063122) (xy 223.154996 -189.06264) (xy 223.101178 -189.054923) (xy 223.048999 -189.039648)
			(xy 222.999516 -189.017124) (xy 222.953729 -188.987807) (xy 222.912565 -188.952289) (xy 222.876857 -188.911291)
			(xy 222.847327 -188.86564) (xy 222.824574 -188.816262) (xy 222.81642 -188.790326) (xy 222.816166 -188.789564)
			(xy 222.815912 -188.788548) (xy 222.81112 -188.774109) (xy 222.794396 -188.748714) (xy 222.770932 -188.729376)
			(xy 222.74281 -188.717811) (xy 222.71253 -188.715048) (xy 222.682779 -188.72133) (xy 222.656202 -188.736101)
			(xy 222.645224 -188.746638) (xy 222.62717 -188.764806) (xy 222.587041 -188.796635) (xy 222.543019 -188.822817)
			(xy 222.495893 -188.842881) (xy 222.446509 -188.856466) (xy 222.395751 -188.86333) (xy 222.370142 -188.863732)
			(xy 222.342885 -188.863272) (xy 222.288927 -188.855519) (xy 222.23662 -188.840166) (xy 222.187032 -188.817524)
			(xy 222.14117 -188.788056) (xy 222.09997 -188.75236) (xy 222.06427 -188.711163) (xy 222.034796 -188.665305)
			(xy 222.012149 -188.615719) (xy 221.99679 -188.563415) (xy 221.989031 -188.509457) (xy 221.989031 -188.454943)
			(xy 221.99679 -188.400985) (xy 222.012149 -188.348681) (xy 222.034796 -188.299095) (xy 222.06427 -188.253237)
			(xy 222.09997 -188.21204) (xy 222.14117 -188.176344) (xy 222.187032 -188.146876) (xy 222.23662 -188.124234)
			(xy 222.288927 -188.108881) (xy 222.342885 -188.101128) (xy 222.370142 -188.100716) (xy 222.397429 -188.101184)
			(xy 222.451446 -188.108963) (xy 222.503804 -188.124355) (xy 222.553436 -188.147049) (xy 222.59933 -188.176579)
			(xy 222.64055 -188.212345) (xy 222.676256 -188.253618) (xy 222.705719 -188.299555) (xy 222.72834 -188.34922)
			(xy 222.73641 -188.37529) (xy 222.741205 -188.389735) (xy 222.757936 -188.415139) (xy 222.781407 -188.434488)
			(xy 222.809537 -188.446064) (xy 222.839828 -188.448841) (xy 222.869593 -188.442572) (xy 222.896191 -188.427813)
			(xy 222.907098 -188.4172) (xy 222.925152 -188.399032) (xy 222.96528 -188.367201) (xy 223.009302 -188.34102)
			(xy 223.056428 -188.320957) (xy 223.105813 -188.307372) (xy 223.15657 -188.300511) (xy 223.18218 -188.300106)
			(xy 223.209433 -188.300568) (xy 223.263386 -188.308323) (xy 223.315685 -188.323677) (xy 223.365267 -188.346319)
			(xy 223.411122 -188.375786) (xy 223.452315 -188.41148) (xy 223.48801 -188.452674) (xy 223.517478 -188.498528)
			(xy 223.540121 -188.548109) (xy 223.555476 -188.600408) (xy 223.563232 -188.654361) (xy 223.563688 -188.681614)
			(xy 223.563612 -188.691986) (xy 223.562468 -188.712699) (xy 223.561402 -188.723016) (xy 223.561148 -188.724794)
			(xy 223.560894 -188.729683) (xy 223.562049 -188.739403) (xy 223.563434 -188.744098) (xy 223.565466 -188.749178)
			(xy 223.569964 -188.758188) (xy 223.5846 -188.771996) (xy 223.603413 -188.779134) (xy 223.623525 -188.778508)
			(xy 223.641859 -188.770214) (xy 223.649032 -188.763148) (xy 223.650048 -188.762132) (xy 223.663769 -188.746968)
			(xy 223.693936 -188.719351) (xy 223.710246 -188.707014) (xy 223.722468 -188.697409) (xy 223.740896 -188.672394)
			(xy 223.750939 -188.642992) (xy 223.751666 -188.611931) (xy 223.743011 -188.582091) (xy 223.734884 -188.568838)
			(xy 223.719801 -188.545271) (xy 223.695962 -188.494652) (xy 223.67978 -188.441091) (xy 223.671604 -188.38574)
			(xy 223.67113 -188.357764) (xy 223.67113 -188.35751) (xy 223.671593 -188.330238) (xy 223.679354 -188.27625)
			(xy 223.694719 -188.223916) (xy 223.717376 -188.174301) (xy 223.746863 -188.128415) (xy 223.78258 -188.087193)
			(xy 223.823801 -188.051474) (xy 223.869685 -188.021985) (xy 223.919299 -187.999325) (xy 223.971632 -187.983958)
			(xy 224.02562 -187.976194) (xy 224.052892 -187.975748) (xy 224.079324 -187.976197) (xy 224.131681 -187.983494)
			(xy 224.182531 -187.997948) (xy 224.230897 -188.019284) (xy 224.275856 -188.047093) (xy 224.296478 -188.063632)
			(xy 224.307056 -188.0719) (xy 224.331445 -188.083102) (xy 224.357907 -188.087579) (xy 224.384624 -188.085022)
			(xy 224.397316 -188.08065) (xy 224.407228 -188.07636) (xy 224.422481 -188.061095) (xy 224.42678 -188.051186)
			(xy 224.437489 -188.024374) (xy 224.465816 -187.974069) (xy 224.501398 -187.928605) (xy 224.543422 -187.88902)
			(xy 224.59093 -187.856216) (xy 224.642837 -187.830943) (xy 224.697959 -187.813778) (xy 224.755037 -187.805112)
			(xy 224.783904 -187.804552) (xy 224.811174 -187.805016) (xy 224.86516 -187.812778) (xy 224.917492 -187.828145)
			(xy 224.967103 -187.850803) (xy 225.012985 -187.880291) (xy 225.054204 -187.916009) (xy 225.08992 -187.957229)
			(xy 225.119405 -188.003113) (xy 225.142061 -188.052725) (xy 225.157425 -188.105057) (xy 225.165186 -188.159044)
			(xy 225.165666 -188.186314) (xy 225.165135 -188.215205) (xy 225.156431 -188.272329) (xy 225.139226 -188.32749)
			(xy 225.127058 -188.3537) (xy 225.123502 -188.363352) (xy 225.116018 -188.390287) (xy 225.094251 -188.441778)
			(xy 225.065208 -188.489543) (xy 225.029507 -188.532561) (xy 224.987914 -188.569913) (xy 224.941318 -188.600798)
			(xy 224.890716 -188.624556) (xy 224.837189 -188.64068) (xy 224.781883 -188.648824) (xy 224.753932 -188.649356)
			(xy 224.7275 -188.648909) (xy 224.67514 -188.641615) (xy 224.624289 -188.627163) (xy 224.57592 -188.60583)
			(xy 224.530959 -188.578023) (xy 224.510346 -188.561472) (xy 224.499356 -188.552894) (xy 224.473911 -188.541523)
			(xy 224.446341 -188.537444) (xy 224.418694 -188.540961) (xy 224.393023 -188.551811) (xy 224.371235 -188.56919)
			(xy 224.362772 -188.580268) (xy 224.344769 -188.604445) (xy 224.302409 -188.647328) (xy 224.278444 -188.665612)
			(xy 224.266213 -188.675217) (xy 224.247767 -188.700236) (xy 224.237705 -188.729646) (xy 224.236961 -188.76072)
			(xy 224.245602 -188.790579) (xy 224.253806 -188.803788) (xy 224.271078 -188.83249) (xy 224.278498 -188.845107)
			(xy 224.299201 -188.865782) (xy 224.324909 -188.879752) (xy 224.35352 -188.885874) (xy 224.382693 -188.883647)
			(xy 224.410043 -188.873253) (xy 224.421954 -188.864748) (xy 224.441995 -188.849971) (xy 224.485179 -188.825181)
			(xy 224.531218 -188.806215) (xy 224.579333 -188.793393) (xy 224.628705 -188.786934) (xy 224.653602 -188.786516)
			(xy 224.68086 -188.787002) (xy 224.734823 -188.794757) (xy 224.787133 -188.810109) (xy 224.836727 -188.832747)
			(xy 224.882597 -188.862209) (xy 224.92381 -188.897896) (xy 224.959527 -188.939083) (xy 224.989022 -188.984932)
			(xy 225.011695 -189.03451) (xy 225.027085 -189.086809) (xy 225.034879 -189.140766) (xy 225.035364 -189.168024)
			(xy 225.035364 -189.168532) (xy 225.034602 -189.189106) (xy 225.034602 -189.193932) (xy 225.034856 -189.199774)
			(xy 225.050858 -189.231016) (xy 225.058095 -189.237262) (xy 225.075851 -189.244301) (xy 225.085402 -189.244732)
			(xy 225.120708 -189.226698) (xy 225.129598 -189.219586) (xy 225.132646 -189.215522) (xy 225.145346 -189.200028)
			(xy 225.146362 -189.198758) (xy 225.147886 -189.19698) (xy 225.148648 -189.195964) (xy 225.149156 -189.195456)
			(xy 225.160435 -189.181252) (xy 225.184715 -189.154302) (xy 225.19767 -189.141608) (xy 225.198686 -189.1411)
			(xy 227.016818 -187.322714) (xy 227.017326 -187.322206) (xy 227.022527 -187.316458) (xy 227.029513 -187.302627)
			(xy 227.031042 -187.295028) (xy 227.031804 -187.286646) (xy 227.031804 -179.4637) (xy 227.032058 -179.449984)
			(xy 227.032058 -179.44338) (xy 227.031296 -179.434236) (xy 227.031296 -179.43322) (xy 227.03028 -179.423822)
			(xy 227.029264 -179.413408) (xy 227.024184 -179.40401) (xy 227.017072 -179.39385) (xy 227.010722 -179.388008)
			(xy 226.992688 -179.374038) (xy 226.99218 -179.37353) (xy 226.98583 -179.368704) (xy 226.982492 -179.366355)
			(xy 226.975215 -179.362658) (xy 226.971352 -179.361338) (xy 226.963986 -179.358798) (xy 226.946968 -179.358798)
			(xy 226.942904 -179.359306) (xy 226.928082 -179.361537) (xy 226.898202 -179.363955) (xy 226.883214 -179.364132)
			(xy 226.88296 -179.364132) (xy 226.855719 -179.36363) (xy 226.801796 -179.355846) (xy 226.749529 -179.34047)
			(xy 226.69998 -179.317816) (xy 226.654158 -179.288343) (xy 226.612995 -179.252652) (xy 226.577327 -179.211468)
			(xy 226.547881 -179.16563) (xy 226.525254 -179.116068) (xy 226.509908 -179.063792) (xy 226.502155 -179.009865)
			(xy 226.501706 -178.982624) (xy 226.502168 -178.95537) (xy 226.509922 -178.901418) (xy 226.525276 -178.849118)
			(xy 226.547917 -178.799535) (xy 226.577385 -178.75368) (xy 226.613079 -178.712486) (xy 226.654272 -178.676791)
			(xy 226.700127 -178.647322) (xy 226.749708 -178.62468) (xy 226.802008 -178.609324) (xy 226.85596 -178.601568)
			(xy 226.883214 -178.601116) (xy 226.897749 -178.601218) (xy 226.926737 -178.603376) (xy 226.941126 -178.605434)
			(xy 226.950778 -178.606958) (xy 226.960176 -178.604672) (xy 226.964696 -178.603516) (xy 226.973255 -178.599806)
			(xy 226.977194 -178.597306) (xy 226.995228 -178.585114) (xy 227.00361 -178.579526) (xy 227.023676 -178.549808)
			(xy 227.025962 -178.541172) (xy 227.02901 -178.53025) (xy 227.030026 -178.526694) (xy 227.032312 -178.510184)
			(xy 227.032058 -178.505358) (xy 227.031804 -178.50104) (xy 227.031804 -177.867564) (xy 227.030026 -177.85461)
			(xy 227.025708 -177.837846) (xy 227.022914 -177.832512) (xy 227.009039 -177.805103) (xy 226.987267 -177.747655)
			(xy 226.972583 -177.688) (xy 226.965199 -177.62701) (xy 226.964748 -177.596292) (xy 226.964748 -177.582576)
			(xy 226.964214 -177.572624) (xy 226.956552 -177.554246) (xy 226.942496 -177.540144) (xy 226.933506 -177.53584)
			(xy 226.92406 -177.532287) (xy 226.903897 -177.532175) (xy 226.885268 -177.539889) (xy 226.87788 -177.546762)
			(xy 225.058478 -179.366164) (xy 225.051633 -179.373562) (xy 225.04391 -179.392161) (xy 225.043492 -179.402232)
			(xy 225.043492 -181.125368) (xy 225.042944 -181.158645) (xy 225.034252 -181.224629) (xy 225.017026 -181.288915)
			(xy 224.99156 -181.350404) (xy 224.95829 -181.408045) (xy 224.917784 -181.460853) (xy 224.894648 -181.484778)
			(xy 224.8535 -181.52618) (xy 224.740724 -181.638956) (xy 224.734628 -181.646576) (xy 224.73065 -181.652937)
			(xy 224.726259 -181.667273) (xy 224.725992 -181.67477) (xy 224.725992 -181.85638) (xy 224.874326 -181.85638)
			(xy 224.878397 -181.800758) (xy 224.890523 -181.746321) (xy 224.910446 -181.69423) (xy 224.937742 -181.645595)
			(xy 224.971828 -181.601452) (xy 225.011977 -181.562743) (xy 225.057335 -181.530292) (xy 225.106935 -181.504791)
			(xy 225.159719 -181.486784) (xy 225.214562 -181.476654) (xy 225.270296 -181.474617) (xy 225.325733 -181.480717)
			(xy 225.37969 -181.494823) (xy 225.431019 -181.516635) (xy 225.478625 -181.545689) (xy 225.521493 -181.581364)
			(xy 225.55871 -181.622901) (xy 225.589483 -181.669414) (xy 225.613155 -181.719911) (xy 225.629223 -181.773318)
			(xy 225.637343 -181.828494) (xy 225.637852 -181.85638) (xy 225.637343 -181.884266) (xy 225.629223 -181.939442)
			(xy 225.613155 -181.992849) (xy 225.589483 -182.043346) (xy 225.55871 -182.089859) (xy 225.521493 -182.131396)
			(xy 225.478625 -182.167071) (xy 225.431019 -182.196125) (xy 225.37969 -182.217937) (xy 225.325733 -182.232043)
			(xy 225.270296 -182.238143) (xy 225.214562 -182.236106) (xy 225.159719 -182.225976) (xy 225.106935 -182.207969)
			(xy 225.057335 -182.182468) (xy 225.011977 -182.150017) (xy 224.971828 -182.111308) (xy 224.937742 -182.067165)
			(xy 224.910446 -182.01853) (xy 224.890523 -181.966439) (xy 224.878397 -181.912002) (xy 224.874326 -181.85638)
			(xy 224.725992 -181.85638) (xy 224.725992 -183.40324) (xy 225.557332 -183.40324) (xy 225.561403 -183.347618)
			(xy 225.573529 -183.293181) (xy 225.593452 -183.24109) (xy 225.620748 -183.192455) (xy 225.654834 -183.148312)
			(xy 225.694983 -183.109603) (xy 225.740341 -183.077152) (xy 225.789941 -183.051651) (xy 225.842725 -183.033644)
			(xy 225.897568 -183.023514) (xy 225.953302 -183.021477) (xy 226.008739 -183.027577) (xy 226.062696 -183.041683)
			(xy 226.114025 -183.063495) (xy 226.161631 -183.092549) (xy 226.204499 -183.128224) (xy 226.241716 -183.169761)
			(xy 226.272489 -183.216274) (xy 226.296161 -183.266771) (xy 226.312229 -183.320178) (xy 226.320349 -183.375354)
			(xy 226.320858 -183.40324) (xy 226.320349 -183.431126) (xy 226.312229 -183.486302) (xy 226.296161 -183.539709)
			(xy 226.272489 -183.590206) (xy 226.241716 -183.636719) (xy 226.204499 -183.678256) (xy 226.161631 -183.713931)
			(xy 226.114025 -183.742985) (xy 226.062696 -183.764797) (xy 226.008739 -183.778903) (xy 225.953302 -183.785003)
			(xy 225.897568 -183.782966) (xy 225.842725 -183.772836) (xy 225.789941 -183.754829) (xy 225.740341 -183.729328)
			(xy 225.694983 -183.696877) (xy 225.654834 -183.658168) (xy 225.620748 -183.614025) (xy 225.593452 -183.56539)
			(xy 225.573529 -183.513299) (xy 225.561403 -183.458862) (xy 225.557332 -183.40324) (xy 224.725992 -183.40324)
			(xy 224.725992 -184.170828) (xy 224.725455 -184.204115) (xy 224.716733 -184.270117) (xy 224.699466 -184.334414)
			(xy 224.673952 -184.395906) (xy 224.640627 -184.45354) (xy 224.600061 -184.506329) (xy 224.576894 -184.530238)
			(xy 223.74352 -185.363612) (xy 224.074226 -185.363612) (xy 224.078297 -185.30799) (xy 224.090423 -185.253553)
			(xy 224.110346 -185.201462) (xy 224.137642 -185.152827) (xy 224.171728 -185.108684) (xy 224.211877 -185.069975)
			(xy 224.257235 -185.037524) (xy 224.306835 -185.012023) (xy 224.359619 -184.994016) (xy 224.414462 -184.983886)
			(xy 224.470196 -184.981849) (xy 224.525633 -184.987949) (xy 224.57959 -185.002055) (xy 224.630919 -185.023867)
			(xy 224.678525 -185.052921) (xy 224.721393 -185.088596) (xy 224.75861 -185.130133) (xy 224.789383 -185.176646)
			(xy 224.813055 -185.227143) (xy 224.829123 -185.28055) (xy 224.837243 -185.335726) (xy 224.837752 -185.363612)
			(xy 224.837243 -185.391498) (xy 224.829123 -185.446674) (xy 224.813055 -185.500081) (xy 224.789383 -185.550578)
			(xy 224.75861 -185.597091) (xy 224.721393 -185.638628) (xy 224.678525 -185.674303) (xy 224.630919 -185.703357)
			(xy 224.57959 -185.725169) (xy 224.525633 -185.739275) (xy 224.470196 -185.745375) (xy 224.414462 -185.743338)
			(xy 224.359619 -185.733208) (xy 224.306835 -185.715201) (xy 224.257235 -185.6897) (xy 224.211877 -185.657249)
			(xy 224.171728 -185.61854) (xy 224.137642 -185.574397) (xy 224.110346 -185.525762) (xy 224.090423 -185.473671)
			(xy 224.078297 -185.419234) (xy 224.074226 -185.363612) (xy 223.74352 -185.363612) (xy 221.169992 -187.93714)
			(xy 221.166472 -187.940871) (xy 221.160846 -187.949447) (xy 221.158816 -187.954158) (xy 221.15526 -187.962794)
			(xy 221.15526 -190.224156) (xy 221.65005 -190.224156) (xy 221.654121 -190.168534) (xy 221.666247 -190.114097)
			(xy 221.68617 -190.062006) (xy 221.713466 -190.013371) (xy 221.747552 -189.969228) (xy 221.787701 -189.930519)
			(xy 221.833059 -189.898068) (xy 221.882659 -189.872567) (xy 221.935443 -189.85456) (xy 221.990286 -189.84443)
			(xy 222.04602 -189.842393) (xy 222.101457 -189.848493) (xy 222.155414 -189.862599) (xy 222.206743 -189.884411)
			(xy 222.254349 -189.913465) (xy 222.297217 -189.94914) (xy 222.334434 -189.990677) (xy 222.365207 -190.03719)
			(xy 222.388879 -190.087687) (xy 222.404947 -190.141094) (xy 222.413067 -190.19627) (xy 222.413576 -190.224156)
			(xy 222.413067 -190.252042) (xy 222.408424 -190.283592) (xy 223.43186 -190.283592) (xy 223.435931 -190.22797)
			(xy 223.448057 -190.173533) (xy 223.46798 -190.121442) (xy 223.495276 -190.072807) (xy 223.529362 -190.028664)
			(xy 223.569511 -189.989955) (xy 223.614869 -189.957504) (xy 223.664469 -189.932003) (xy 223.717253 -189.913996)
			(xy 223.772096 -189.903866) (xy 223.82783 -189.901829) (xy 223.883267 -189.907929) (xy 223.937224 -189.922035)
			(xy 223.988553 -189.943847) (xy 224.036159 -189.972901) (xy 224.079027 -190.008576) (xy 224.116244 -190.050113)
			(xy 224.147017 -190.096626) (xy 224.170689 -190.147123) (xy 224.186757 -190.20053) (xy 224.194877 -190.255706)
			(xy 224.195386 -190.283592) (xy 224.194877 -190.311478) (xy 224.186757 -190.366654) (xy 224.170689 -190.420061)
			(xy 224.147017 -190.470558) (xy 224.116244 -190.517071) (xy 224.079027 -190.558608) (xy 224.036159 -190.594283)
			(xy 223.988553 -190.623337) (xy 223.937224 -190.645149) (xy 223.883267 -190.659255) (xy 223.82783 -190.665355)
			(xy 223.772096 -190.663318) (xy 223.717253 -190.653188) (xy 223.664469 -190.635181) (xy 223.614869 -190.60968)
			(xy 223.569511 -190.577229) (xy 223.529362 -190.53852) (xy 223.495276 -190.494377) (xy 223.46798 -190.445742)
			(xy 223.448057 -190.393651) (xy 223.435931 -190.339214) (xy 223.43186 -190.283592) (xy 222.408424 -190.283592)
			(xy 222.404947 -190.307218) (xy 222.388879 -190.360625) (xy 222.365207 -190.411122) (xy 222.334434 -190.457635)
			(xy 222.297217 -190.499172) (xy 222.254349 -190.534847) (xy 222.206743 -190.563901) (xy 222.155414 -190.585713)
			(xy 222.101457 -190.599819) (xy 222.04602 -190.605919) (xy 221.990286 -190.603882) (xy 221.935443 -190.593752)
			(xy 221.882659 -190.575745) (xy 221.833059 -190.550244) (xy 221.787701 -190.517793) (xy 221.747552 -190.479084)
			(xy 221.713466 -190.434941) (xy 221.68617 -190.386306) (xy 221.666247 -190.334215) (xy 221.654121 -190.279778)
			(xy 221.65005 -190.224156) (xy 221.15526 -190.224156) (xy 221.15526 -191.183768) (xy 221.544894 -191.183768)
			(xy 221.548965 -191.128146) (xy 221.561091 -191.073709) (xy 221.581014 -191.021618) (xy 221.60831 -190.972983)
			(xy 221.642396 -190.92884) (xy 221.682545 -190.890131) (xy 221.727903 -190.85768) (xy 221.777503 -190.832179)
			(xy 221.830287 -190.814172) (xy 221.88513 -190.804042) (xy 221.940864 -190.802005) (xy 221.996301 -190.808105)
			(xy 222.050258 -190.822211) (xy 222.101587 -190.844023) (xy 222.149193 -190.873077) (xy 222.192061 -190.908752)
			(xy 222.229278 -190.950289) (xy 222.260051 -190.996802) (xy 222.283723 -191.047299) (xy 222.299791 -191.100706)
			(xy 222.307911 -191.155882) (xy 222.30842 -191.183768) (xy 222.307911 -191.211654) (xy 222.299791 -191.26683)
			(xy 222.283723 -191.320237) (xy 222.260051 -191.370734) (xy 222.229278 -191.417247) (xy 222.229098 -191.417448)
			(xy 223.106232 -191.417448) (xy 223.110303 -191.361826) (xy 223.122429 -191.307389) (xy 223.142352 -191.255298)
			(xy 223.169648 -191.206663) (xy 223.203734 -191.16252) (xy 223.243883 -191.123811) (xy 223.289241 -191.09136)
			(xy 223.338841 -191.065859) (xy 223.391625 -191.047852) (xy 223.446468 -191.037722) (xy 223.502202 -191.035685)
			(xy 223.557639 -191.041785) (xy 223.611596 -191.055891) (xy 223.662925 -191.077703) (xy 223.710531 -191.106757)
			(xy 223.753399 -191.142432) (xy 223.790616 -191.183969) (xy 223.821389 -191.230482) (xy 223.845061 -191.280979)
			(xy 223.861129 -191.334386) (xy 223.869249 -191.389562) (xy 223.869758 -191.417448) (xy 223.869249 -191.445334)
			(xy 223.861129 -191.50051) (xy 223.845061 -191.553917) (xy 223.821389 -191.604414) (xy 223.790616 -191.650927)
			(xy 223.753399 -191.692464) (xy 223.710531 -191.728139) (xy 223.662925 -191.757193) (xy 223.611596 -191.779005)
			(xy 223.557639 -191.793111) (xy 223.502202 -191.799211) (xy 223.446468 -191.797174) (xy 223.391625 -191.787044)
			(xy 223.338841 -191.769037) (xy 223.289241 -191.743536) (xy 223.243883 -191.711085) (xy 223.203734 -191.672376)
			(xy 223.169648 -191.628233) (xy 223.142352 -191.579598) (xy 223.122429 -191.527507) (xy 223.110303 -191.47307)
			(xy 223.106232 -191.417448) (xy 222.229098 -191.417448) (xy 222.192061 -191.458784) (xy 222.149193 -191.494459)
			(xy 222.101587 -191.523513) (xy 222.050258 -191.545325) (xy 221.996301 -191.559431) (xy 221.940864 -191.565531)
			(xy 221.88513 -191.563494) (xy 221.830287 -191.553364) (xy 221.777503 -191.535357) (xy 221.727903 -191.509856)
			(xy 221.682545 -191.477405) (xy 221.642396 -191.438696) (xy 221.60831 -191.394553) (xy 221.581014 -191.345918)
			(xy 221.561091 -191.293827) (xy 221.548965 -191.23939) (xy 221.544894 -191.183768) (xy 221.15526 -191.183768)
			(xy 221.15526 -191.250316) (xy 221.154724 -191.283603) (xy 221.146002 -191.349605) (xy 221.128736 -191.413902)
			(xy 221.103222 -191.475395) (xy 221.069896 -191.533028) (xy 221.029329 -191.585817) (xy 221.006162 -191.609726)
			(xy 220.31452 -192.301368) (xy 220.310994 -192.305095) (xy 220.305354 -192.313665) (xy 220.303344 -192.318386)
			(xy 220.299788 -192.327022) (xy 220.299788 -192.357502) (xy 220.6023 -192.357502) (xy 220.606371 -192.30188)
			(xy 220.618497 -192.247443) (xy 220.63842 -192.195352) (xy 220.665716 -192.146717) (xy 220.699802 -192.102574)
			(xy 220.739951 -192.063865) (xy 220.785309 -192.031414) (xy 220.834909 -192.005913) (xy 220.887693 -191.987906)
			(xy 220.942536 -191.977776) (xy 220.99827 -191.975739) (xy 221.053707 -191.981839) (xy 221.107664 -191.995945)
			(xy 221.158993 -192.017757) (xy 221.206599 -192.046811) (xy 221.249467 -192.082486) (xy 221.286684 -192.124023)
			(xy 221.317457 -192.170536) (xy 221.341129 -192.221033) (xy 221.357197 -192.27444) (xy 221.365317 -192.329616)
			(xy 221.365826 -192.357502) (xy 221.365317 -192.385388) (xy 221.357197 -192.440564) (xy 221.341129 -192.493971)
			(xy 221.317457 -192.544468) (xy 221.286684 -192.590981) (xy 221.249467 -192.632518) (xy 221.206599 -192.668193)
			(xy 221.158993 -192.697247) (xy 221.107664 -192.719059) (xy 221.053707 -192.733165) (xy 220.99827 -192.739265)
			(xy 220.942536 -192.737228) (xy 220.887693 -192.727098) (xy 220.834909 -192.709091) (xy 220.785309 -192.68359)
			(xy 220.739951 -192.651139) (xy 220.699802 -192.61243) (xy 220.665716 -192.568287) (xy 220.63842 -192.519652)
			(xy 220.618497 -192.467561) (xy 220.606371 -192.413124) (xy 220.6023 -192.357502) (xy 220.299788 -192.357502)
			(xy 220.299788 -193.359786) (xy 220.426532 -193.359786) (xy 220.430603 -193.304164) (xy 220.442729 -193.249727)
			(xy 220.462652 -193.197636) (xy 220.489948 -193.149001) (xy 220.524034 -193.104858) (xy 220.564183 -193.066149)
			(xy 220.609541 -193.033698) (xy 220.659141 -193.008197) (xy 220.711925 -192.99019) (xy 220.766768 -192.98006)
			(xy 220.822502 -192.978023) (xy 220.877939 -192.984123) (xy 220.931896 -192.998229) (xy 220.943523 -193.00317)
			(xy 224.004884 -193.00317) (xy 224.008955 -192.947548) (xy 224.021081 -192.893111) (xy 224.041004 -192.84102)
			(xy 224.0683 -192.792385) (xy 224.102386 -192.748242) (xy 224.142535 -192.709533) (xy 224.187893 -192.677082)
			(xy 224.237493 -192.651581) (xy 224.290277 -192.633574) (xy 224.34512 -192.623444) (xy 224.400854 -192.621407)
			(xy 224.456291 -192.627507) (xy 224.510248 -192.641613) (xy 224.561577 -192.663425) (xy 224.609183 -192.692479)
			(xy 224.652051 -192.728154) (xy 224.689268 -192.769691) (xy 224.720041 -192.816204) (xy 224.743713 -192.866701)
			(xy 224.759781 -192.920108) (xy 224.767901 -192.975284) (xy 224.76841 -193.00317) (xy 224.767901 -193.031056)
			(xy 224.759781 -193.086232) (xy 224.743713 -193.139639) (xy 224.720041 -193.190136) (xy 224.689268 -193.236649)
			(xy 224.652051 -193.278186) (xy 224.609183 -193.313861) (xy 224.561577 -193.342915) (xy 224.510248 -193.364727)
			(xy 224.456291 -193.378833) (xy 224.400854 -193.384933) (xy 224.34512 -193.382896) (xy 224.290277 -193.372766)
			(xy 224.237493 -193.354759) (xy 224.187893 -193.329258) (xy 224.142535 -193.296807) (xy 224.102386 -193.258098)
			(xy 224.0683 -193.213955) (xy 224.041004 -193.16532) (xy 224.021081 -193.113229) (xy 224.008955 -193.058792)
			(xy 224.004884 -193.00317) (xy 220.943523 -193.00317) (xy 220.983225 -193.020041) (xy 221.030831 -193.049095)
			(xy 221.073699 -193.08477) (xy 221.110916 -193.126307) (xy 221.141689 -193.17282) (xy 221.165361 -193.223317)
			(xy 221.181429 -193.276724) (xy 221.189549 -193.3319) (xy 221.190058 -193.359786) (xy 221.189549 -193.387672)
			(xy 221.181429 -193.442848) (xy 221.165361 -193.496255) (xy 221.141689 -193.546752) (xy 221.110916 -193.593265)
			(xy 221.073699 -193.634802) (xy 221.030831 -193.670477) (xy 220.983225 -193.699531) (xy 220.931896 -193.721343)
			(xy 220.877939 -193.735449) (xy 220.822502 -193.741549) (xy 220.766768 -193.739512) (xy 220.711925 -193.729382)
			(xy 220.659141 -193.711375) (xy 220.609541 -193.685874) (xy 220.564183 -193.653423) (xy 220.524034 -193.614714)
			(xy 220.489948 -193.570571) (xy 220.462652 -193.521936) (xy 220.442729 -193.469845) (xy 220.430603 -193.415408)
			(xy 220.426532 -193.359786) (xy 220.299788 -193.359786) (xy 220.299788 -193.63436) (xy 220.30055 -193.642742)
			(xy 220.302055 -193.650352) (xy 220.309025 -193.664202) (xy 220.314266 -193.66992) (xy 220.815154 -194.170808)
			(xy 220.83831 -194.194723) (xy 220.87885 -194.247524) (xy 220.912156 -194.305161) (xy 220.937659 -194.36665)
			(xy 220.954925 -194.430941) (xy 220.963657 -194.496934) (xy 220.964252 -194.530218) (xy 220.964252 -194.595496)
			(xy 223.931986 -194.595496) (xy 223.936057 -194.539874) (xy 223.948183 -194.485437) (xy 223.968106 -194.433346)
			(xy 223.995402 -194.384711) (xy 224.029488 -194.340568) (xy 224.069637 -194.301859) (xy 224.114995 -194.269408)
			(xy 224.164595 -194.243907) (xy 224.217379 -194.2259) (xy 224.272222 -194.21577) (xy 224.327956 -194.213733)
			(xy 224.383393 -194.219833) (xy 224.43735 -194.233939) (xy 224.488679 -194.255751) (xy 224.536285 -194.284805)
			(xy 224.579153 -194.32048) (xy 224.61637 -194.362017) (xy 224.647143 -194.40853) (xy 224.670815 -194.459027)
			(xy 224.686883 -194.512434) (xy 224.695003 -194.56761) (xy 224.695512 -194.595496) (xy 224.695003 -194.623382)
			(xy 224.686883 -194.678558) (xy 224.670815 -194.731965) (xy 224.647143 -194.782462) (xy 224.61637 -194.828975)
			(xy 224.579153 -194.870512) (xy 224.536285 -194.906187) (xy 224.488679 -194.935241) (xy 224.43735 -194.957053)
			(xy 224.383393 -194.971159) (xy 224.327956 -194.977259) (xy 224.272222 -194.975222) (xy 224.217379 -194.965092)
			(xy 224.164595 -194.947085) (xy 224.114995 -194.921584) (xy 224.069637 -194.889133) (xy 224.029488 -194.850424)
			(xy 223.995402 -194.806281) (xy 223.968106 -194.757646) (xy 223.948183 -194.705555) (xy 223.936057 -194.651118)
			(xy 223.931986 -194.595496) (xy 220.964252 -194.595496) (xy 220.964252 -196.35851) (xy 220.963717 -196.391798)
			(xy 220.954997 -196.457802) (xy 220.937734 -196.522101) (xy 220.912224 -196.583597) (xy 220.878903 -196.641235)
			(xy 220.838341 -196.694029) (xy 220.815154 -196.71792) (xy 220.36024 -197.172834) (xy 220.356717 -197.176563)
			(xy 220.351085 -197.185136) (xy 220.349064 -197.189852) (xy 220.345508 -197.198488) (xy 220.345508 -198.12)
			(xy 220.597982 -198.12) (xy 220.602053 -198.064378) (xy 220.614179 -198.009941) (xy 220.634102 -197.95785)
			(xy 220.661398 -197.909215) (xy 220.695484 -197.865072) (xy 220.735633 -197.826363) (xy 220.780991 -197.793912)
			(xy 220.830591 -197.768411) (xy 220.883375 -197.750404) (xy 220.938218 -197.740274) (xy 220.993952 -197.738237)
			(xy 221.049389 -197.744337) (xy 221.103346 -197.758443) (xy 221.154675 -197.780255) (xy 221.202281 -197.809309)
			(xy 221.245149 -197.844984) (xy 221.282366 -197.886521) (xy 221.313139 -197.933034) (xy 221.336811 -197.983531)
			(xy 221.352879 -198.036938) (xy 221.360999 -198.092114) (xy 221.361508 -198.12) (xy 221.360999 -198.147886)
			(xy 221.352879 -198.203062) (xy 221.336811 -198.256469) (xy 221.313139 -198.306966) (xy 221.282366 -198.353479)
			(xy 221.245149 -198.395016) (xy 221.202281 -198.430691) (xy 221.154675 -198.459745) (xy 221.103346 -198.481557)
			(xy 221.049389 -198.495663) (xy 220.993952 -198.501763) (xy 220.938218 -198.499726) (xy 220.883375 -198.489596)
			(xy 220.830591 -198.471589) (xy 220.780991 -198.446088) (xy 220.735633 -198.413637) (xy 220.695484 -198.374928)
			(xy 220.661398 -198.330785) (xy 220.634102 -198.28215) (xy 220.614179 -198.230059) (xy 220.602053 -198.175622)
			(xy 220.597982 -198.12) (xy 220.345508 -198.12) (xy 220.345508 -198.482204) (xy 220.344973 -198.515492)
			(xy 220.336253 -198.581495) (xy 220.31899 -198.645794) (xy 220.293478 -198.707289) (xy 220.260155 -198.764926)
			(xy 220.219592 -198.817718) (xy 220.19641 -198.841614) (xy 219.324936 -199.713088) (xy 219.32141 -199.716816)
			(xy 219.315771 -199.725386) (xy 219.31376 -199.730106) (xy 219.310204 -199.738742) (xy 219.310204 -200.013824)
			(xy 219.310458 -200.279) (xy 219.309994 -200.30972) (xy 219.302591 -200.370713) (xy 219.287891 -200.430369)
			(xy 219.266109 -200.487818) (xy 219.237563 -200.542224) (xy 219.202669 -200.592794) (xy 219.161935 -200.63879)
			(xy 219.115955 -200.679543) (xy 219.065399 -200.714457) (xy 219.011004 -200.743025) (xy 218.953563 -200.76483)
			(xy 218.893913 -200.779554) (xy 218.832924 -200.786982) (xy 218.802204 -200.787508) (xy 218.80195 -200.787508)
			(xy 218.771223 -200.787064) (xy 218.710217 -200.779652) (xy 218.650552 -200.76493) (xy 218.5931 -200.743114)
			(xy 218.538702 -200.714523) (xy 218.488152 -200.679575) (xy 218.464892 -200.659492) (xy 218.444372 -200.640871)
			(xy 218.407081 -200.599882) (xy 218.39047 -200.577704) (xy 218.38676 -200.572739) (xy 218.377389 -200.564632)
			(xy 218.371928 -200.561702) (xy 218.362022 -200.556622) (xy 218.316556 -200.556622) (xy 218.308428 -200.557384)
			(xy 218.267788 -200.564496) (xy 218.26728 -200.564496) (xy 218.24569 -200.56856) (xy 218.23877 -200.570136)
			(xy 218.22613 -200.576577) (xy 218.220798 -200.58126) (xy 218.215718 -200.586086) (xy 218.208352 -200.59777)
			(xy 218.20632 -200.605136) (xy 218.202927 -200.617105) (xy 218.19479 -200.640618) (xy 218.190064 -200.652126)
			(xy 218.18981 -200.652634) (xy 218.189048 -200.654412) (xy 218.189048 -200.654666) (xy 218.185118 -200.665342)
			(xy 218.186025 -200.688042) (xy 218.190826 -200.698354) (xy 218.196668 -200.70953) (xy 218.22156 -200.756774)
			(xy 218.224462 -200.761817) (xy 218.232156 -200.770541) (xy 218.2368 -200.774046) (xy 218.24569 -200.78065)
			(xy 218.25712 -200.782936) (xy 218.283761 -200.788349) (xy 218.33533 -200.805556) (xy 218.384023 -200.829729)
			(xy 218.428906 -200.860402) (xy 218.469117 -200.896987) (xy 218.503883 -200.938781) (xy 218.532535 -200.984981)
			(xy 218.554524 -201.034699) (xy 218.569427 -201.086979) (xy 218.576958 -201.140818) (xy 218.577414 -201.168)
			(xy 218.576915 -201.195959) (xy 218.568958 -201.251307) (xy 218.553204 -201.30496) (xy 218.529975 -201.355824)
			(xy 218.499743 -201.402865) (xy 218.463125 -201.445125) (xy 218.420865 -201.481743) (xy 218.373824 -201.511975)
			(xy 218.32296 -201.535204) (xy 218.269307 -201.550958) (xy 218.213959 -201.558915) (xy 218.158041 -201.558915)
			(xy 218.102693 -201.550958) (xy 218.04904 -201.535204) (xy 217.998176 -201.511975) (xy 217.951135 -201.481743)
			(xy 217.908875 -201.445125) (xy 217.872257 -201.402865) (xy 217.842025 -201.355824) (xy 217.818796 -201.30496)
			(xy 217.803042 -201.251307) (xy 217.795085 -201.195959) (xy 217.794586 -201.168) (xy 217.795099 -201.140365)
			(xy 217.802954 -201.085655) (xy 217.818437 -201.032598) (xy 217.829384 -201.007218) (xy 217.829384 -201.00671)
			(xy 217.829638 -201.00671) (xy 217.831831 -201.001394) (xy 217.834021 -200.990108) (xy 217.833956 -200.984358)
			(xy 217.833448 -200.97242) (xy 217.810588 -200.929494) (xy 217.810588 -200.928986) (xy 217.80373 -200.916032)
			(xy 217.804238 -200.902824) (xy 217.782648 -200.886568) (xy 217.779156 -200.884036) (xy 217.771492 -200.880082)
			(xy 217.767408 -200.878694) (xy 217.762582 -200.877678) (xy 217.754454 -200.8759) (xy 217.7542 -200.8759)
			(xy 217.75039 -200.875138) (xy 217.72291 -200.868064) (xy 217.670261 -200.8469) (xy 217.621324 -200.818177)
			(xy 217.577177 -200.782528) (xy 217.538792 -200.740738) (xy 217.507015 -200.693728) (xy 217.482545 -200.642532)
			(xy 217.465922 -200.588278) (xy 217.457511 -200.532162) (xy 217.45702 -200.50379) (xy 217.457484 -200.476538)
			(xy 217.465242 -200.42259) (xy 217.4806 -200.370295) (xy 217.503243 -200.320718) (xy 217.532712 -200.274868)
			(xy 217.568406 -200.233679) (xy 217.609598 -200.197989) (xy 217.655451 -200.168525) (xy 217.705031 -200.145886)
			(xy 217.757327 -200.130534) (xy 217.811276 -200.122781) (xy 217.838528 -200.122282) (xy 217.867345 -200.122802)
			(xy 217.924327 -200.131454) (xy 217.979361 -200.148571) (xy 218.031197 -200.173765) (xy 218.078657 -200.206464)
			(xy 218.120664 -200.245925) (xy 218.156263 -200.291251) (xy 218.184645 -200.341413) (xy 218.195398 -200.368154)
			(xy 218.197938 -200.374758) (xy 218.206828 -200.386696) (xy 218.212734 -200.394167) (xy 218.228766 -200.40442)
			(xy 218.247437 -200.408096) (xy 218.256866 -200.406762) (xy 218.269566 -200.402698) (xy 218.273235 -200.400893)
			(xy 218.279996 -200.396297) (xy 218.283028 -200.393554) (xy 218.287092 -200.388982) (xy 218.292292 -200.382018)
			(xy 218.298131 -200.36566) (xy 218.298522 -200.356978) (xy 218.298522 -200.350882) (xy 218.29776 -200.34504)
			(xy 218.295794 -200.328602) (xy 218.293757 -200.295555) (xy 218.293696 -200.279) (xy 218.293696 -199.517)
			(xy 218.29424 -199.483722) (xy 218.302925 -199.417735) (xy 218.320146 -199.353445) (xy 218.34561 -199.291953)
			(xy 218.37888 -199.234309) (xy 218.419387 -199.181499) (xy 218.44254 -199.15759) (xy 218.675966 -198.92391)
			(xy 219.314014 -198.285862) (xy 219.320603 -198.278484) (xy 219.328065 -198.260184) (xy 219.328492 -198.250302)
			(xy 219.328492 -196.976746) (xy 219.329024 -196.943457) (xy 219.337738 -196.87745) (xy 219.354996 -196.813147)
			(xy 219.380504 -196.751648) (xy 219.413823 -196.694006) (xy 219.454384 -196.641209) (xy 219.47759 -196.617336)
			(xy 219.932758 -196.162168) (xy 219.93774 -196.156666) (xy 219.944575 -196.143498) (xy 219.94622 -196.13626)
			(xy 219.947236 -196.126608) (xy 219.947236 -194.761866) (xy 219.947141 -194.756988) (xy 219.945355 -194.747398)
			(xy 219.94368 -194.742816) (xy 219.93987 -194.733672) (xy 219.654882 -194.448684) (xy 219.643916 -194.438458)
			(xy 219.617494 -194.424314) (xy 219.588105 -194.418444) (xy 219.558277 -194.421352) (xy 219.530576 -194.432789)
			(xy 219.507384 -194.45177) (xy 219.490696 -194.476664) (xy 219.481949 -194.505328) (xy 219.4814 -194.520312)
			(xy 219.4814 -194.773804) (xy 219.480856 -194.807082) (xy 219.472171 -194.873069) (xy 219.454949 -194.937358)
			(xy 219.429485 -194.99885) (xy 219.396214 -195.056493) (xy 219.355706 -195.109302) (xy 219.332556 -195.133214)
			(xy 219.324936 -195.140834) (xy 219.321413 -195.144563) (xy 219.315781 -195.153137) (xy 219.31376 -195.157852)
			(xy 219.310204 -195.166488) (xy 219.310204 -195.707) (xy 219.309703 -195.738945) (xy 219.301695 -195.802331)
			(xy 219.285806 -195.864214) (xy 219.262287 -195.923618) (xy 219.231507 -195.979605) (xy 219.193954 -196.031294)
			(xy 219.150218 -196.077868) (xy 219.10099 -196.118593) (xy 219.047045 -196.152827) (xy 218.989236 -196.18003)
			(xy 218.928473 -196.199773) (xy 218.865714 -196.211745) (xy 218.80195 -196.215757) (xy 218.738186 -196.211745)
			(xy 218.675427 -196.199773) (xy 218.614664 -196.18003) (xy 218.556855 -196.152827) (xy 218.50291 -196.118593)
			(xy 218.453682 -196.077868) (xy 218.409946 -196.031294) (xy 218.372393 -195.979605) (xy 218.341613 -195.923618)
			(xy 218.318094 -195.864214) (xy 218.302205 -195.802331) (xy 218.294197 -195.738945) (xy 218.293696 -195.707)
			(xy 218.293696 -194.945) (xy 218.29424 -194.911722) (xy 218.302925 -194.845735) (xy 218.320146 -194.781445)
			(xy 218.34561 -194.719953) (xy 218.37888 -194.662309) (xy 218.419387 -194.609499) (xy 218.44254 -194.58559)
			(xy 218.450414 -194.577716) (xy 218.455606 -194.571964) (xy 218.462569 -194.558129) (xy 218.46413 -194.550538)
			(xy 218.464892 -194.542156) (xy 218.464892 -194.505326) (xy 218.464751 -194.499107) (xy 218.461807 -194.487025)
			(xy 218.45905 -194.48145) (xy 218.456256 -194.476116) (xy 218.447874 -194.466972) (xy 218.44254 -194.463416)
			(xy 218.37396 -194.416934) (xy 218.369655 -194.414132) (xy 218.36018 -194.410169) (xy 218.355164 -194.40906)
			(xy 218.35094 -194.408385) (xy 218.342388 -194.408259) (xy 218.338146 -194.408806) (xy 218.326208 -194.410838)
			(xy 218.321382 -194.412616) (xy 218.299694 -194.420508) (xy 218.254891 -194.431589) (xy 218.209077 -194.43717)
			(xy 218.186 -194.437508) (xy 218.158749 -194.437022) (xy 218.104801 -194.429266) (xy 218.052506 -194.413911)
			(xy 218.002929 -194.391269) (xy 217.957079 -194.361803) (xy 217.915888 -194.326112) (xy 217.880197 -194.284921)
			(xy 217.850731 -194.239071) (xy 217.828089 -194.189494) (xy 217.812734 -194.137199) (xy 217.804978 -194.083251)
			(xy 217.804978 -194.028749) (xy 217.812734 -193.974801) (xy 217.828089 -193.922506) (xy 217.850731 -193.872929)
			(xy 217.880197 -193.827079) (xy 217.915888 -193.785888) (xy 217.957079 -193.750197) (xy 218.002929 -193.720731)
			(xy 218.052506 -193.698089) (xy 218.104801 -193.682734) (xy 218.158749 -193.674978) (xy 218.186 -193.674492)
			(xy 218.21968 -193.675231) (xy 218.285983 -193.687117) (xy 218.317826 -193.698114) (xy 218.326462 -193.701162)
			(xy 218.349068 -193.701162) (xy 218.354934 -193.700996) (xy 218.366351 -193.698298) (xy 218.371674 -193.695828)
			(xy 218.376246 -193.693542) (xy 218.39174 -193.682874) (xy 218.392502 -193.682366) (xy 218.44254 -193.648584)
			(xy 218.446441 -193.6458) (xy 218.453216 -193.639022) (xy 218.456002 -193.635122) (xy 218.46005 -193.628712)
			(xy 218.464565 -193.614248) (xy 218.464892 -193.606674) (xy 218.464892 -193.489326) (xy 218.464751 -193.483107)
			(xy 218.461807 -193.471025) (xy 218.45905 -193.46545) (xy 218.456256 -193.460116) (xy 218.447874 -193.450972)
			(xy 218.44254 -193.447416) (xy 218.37396 -193.400934) (xy 218.369655 -193.398132) (xy 218.36018 -193.394169)
			(xy 218.355164 -193.39306) (xy 218.35094 -193.392385) (xy 218.342388 -193.392259) (xy 218.338146 -193.392806)
			(xy 218.326208 -193.394838) (xy 218.321382 -193.396616) (xy 218.299694 -193.404508) (xy 218.254891 -193.415589)
			(xy 218.209077 -193.42117) (xy 218.186 -193.421508) (xy 218.158749 -193.421022) (xy 218.104801 -193.413266)
			(xy 218.052506 -193.397911) (xy 218.002929 -193.375269) (xy 217.957079 -193.345803) (xy 217.915888 -193.310112)
			(xy 217.880197 -193.268921) (xy 217.850731 -193.223071) (xy 217.828089 -193.173494) (xy 217.812734 -193.121199)
			(xy 217.804978 -193.067251) (xy 217.804978 -193.012749) (xy 217.812734 -192.958801) (xy 217.828089 -192.906506)
			(xy 217.850731 -192.856929) (xy 217.880197 -192.811079) (xy 217.915888 -192.769888) (xy 217.957079 -192.734197)
			(xy 218.002929 -192.704731) (xy 218.052506 -192.682089) (xy 218.104801 -192.666734) (xy 218.158749 -192.658978)
			(xy 218.186 -192.658492) (xy 218.21968 -192.659231) (xy 218.285983 -192.671117) (xy 218.317826 -192.682114)
			(xy 218.326462 -192.685162) (xy 218.349068 -192.685162) (xy 218.354934 -192.684996) (xy 218.366351 -192.682298)
			(xy 218.371674 -192.679828) (xy 218.376246 -192.677542) (xy 218.39174 -192.666874) (xy 218.392502 -192.666366)
			(xy 218.44254 -192.632584) (xy 218.446441 -192.6298) (xy 218.453216 -192.623022) (xy 218.456002 -192.619122)
			(xy 218.46005 -192.612712) (xy 218.464565 -192.598248) (xy 218.464892 -192.590674) (xy 218.464892 -192.473326)
			(xy 218.464751 -192.467107) (xy 218.461807 -192.455025) (xy 218.45905 -192.44945) (xy 218.456256 -192.444116)
			(xy 218.447874 -192.434972) (xy 218.44254 -192.431416) (xy 218.37396 -192.384934) (xy 218.369655 -192.382132)
			(xy 218.36018 -192.378169) (xy 218.355164 -192.37706) (xy 218.35094 -192.376385) (xy 218.342388 -192.376259)
			(xy 218.338146 -192.376806) (xy 218.326208 -192.378838) (xy 218.321382 -192.380616) (xy 218.299694 -192.388508)
			(xy 218.254891 -192.399589) (xy 218.209077 -192.40517) (xy 218.186 -192.405508) (xy 218.158749 -192.405022)
			(xy 218.104801 -192.397266) (xy 218.052506 -192.381911) (xy 218.002929 -192.359269) (xy 217.957079 -192.329803)
			(xy 217.915888 -192.294112) (xy 217.880197 -192.252921) (xy 217.850731 -192.207071) (xy 217.828089 -192.157494)
			(xy 217.812734 -192.105199) (xy 217.804978 -192.051251) (xy 217.804978 -191.996749) (xy 217.812734 -191.942801)
			(xy 217.828089 -191.890506) (xy 217.850731 -191.840929) (xy 217.880197 -191.795079) (xy 217.915888 -191.753888)
			(xy 217.957079 -191.718197) (xy 218.002929 -191.688731) (xy 218.052506 -191.666089) (xy 218.104801 -191.650734)
			(xy 218.158749 -191.642978) (xy 218.186 -191.642492) (xy 218.186254 -191.642492) (xy 218.21106 -191.642909)
			(xy 218.260251 -191.649367) (xy 218.308194 -191.66213) (xy 218.331288 -191.671194) (xy 218.331542 -191.671194)
			(xy 218.336945 -191.673278) (xy 218.348361 -191.675208) (xy 218.354148 -191.675004) (xy 218.365324 -191.674242)
			(xy 218.377008 -191.667638) (xy 218.383866 -191.663828) (xy 218.445334 -191.62903) (xy 218.450233 -191.626079)
			(xy 218.458689 -191.618383) (xy 218.462098 -191.61379) (xy 218.468702 -191.604138) (xy 218.47048 -191.592454)
			(xy 218.475786 -191.560528) (xy 218.493444 -191.498264) (xy 218.518865 -191.438746) (xy 218.551638 -191.382937)
			(xy 218.591231 -191.331741) (xy 218.613736 -191.308482) (xy 219.412566 -190.509398) (xy 219.419139 -190.502014)
			(xy 219.42657 -190.483715) (xy 219.427044 -190.473838) (xy 219.427044 -187.446412) (xy 219.427577 -187.413123)
			(xy 219.436295 -187.347118) (xy 219.453555 -187.282817) (xy 219.479064 -187.221319) (xy 219.512383 -187.163679)
			(xy 219.552944 -187.110882) (xy 219.576142 -187.087002) (xy 222.874586 -183.788558) (xy 222.879785 -183.782809)
			(xy 222.886763 -183.768977) (xy 222.888302 -183.76138) (xy 222.889064 -183.752998) (xy 222.889064 -181.410864)
			(xy 222.888969 -181.405986) (xy 222.887184 -181.396396) (xy 222.885508 -181.391814) (xy 222.881698 -181.38267)
			(xy 222.627444 -181.128416) (xy 222.604278 -181.104517) (xy 222.563756 -181.051712) (xy 222.530476 -180.994069)
			(xy 222.505008 -180.932573) (xy 222.487787 -180.868279) (xy 222.479108 -180.802286) (xy 222.4786 -180.769006)
			(xy 222.4786 -180.221382) (xy 222.479145 -180.188104) (xy 222.487832 -180.122119) (xy 222.505055 -180.057831)
			(xy 222.530521 -179.99634) (xy 222.563792 -179.938698) (xy 222.604301 -179.88589) (xy 222.627444 -179.861972)
			(xy 222.807784 -179.681378) (xy 223.301306 -179.187856) (xy 223.306503 -179.182106) (xy 223.313478 -179.168273)
			(xy 223.315022 -179.160678) (xy 223.315784 -179.152296) (xy 223.315784 -178.364896) (xy 223.316328 -178.331618)
			(xy 223.325013 -178.265631) (xy 223.342235 -178.201342) (xy 223.367698 -178.139849) (xy 223.400968 -178.082205)
			(xy 223.441475 -178.029395) (xy 223.464628 -178.005486) (xy 224.380298 -177.089816) (xy 224.3861 -177.083501)
			(xy 224.393484 -177.068034) (xy 224.395355 -177.050998) (xy 224.39376 -177.042572) (xy 224.39376 -177.042318)
			(xy 224.389141 -177.021091) (xy 224.384174 -176.977933) (xy 224.383854 -176.956212) (xy 224.384339 -176.928959)
			(xy 224.392094 -176.875008) (xy 224.407448 -176.82271) (xy 224.430087 -176.773129) (xy 224.459553 -176.727274)
			(xy 224.495244 -176.686079) (xy 224.536434 -176.650383) (xy 224.582285 -176.620911) (xy 224.631863 -176.598265)
			(xy 224.684159 -176.582904) (xy 224.738109 -176.575143) (xy 224.765362 -176.574704) (xy 224.787083 -176.575026)
			(xy 224.83024 -176.579995) (xy 224.851468 -176.58461) (xy 224.864422 -176.587658) (xy 224.889568 -176.580292)
			(xy 225.339402 -176.130458) (xy 225.344599 -176.124708) (xy 225.351576 -176.110876) (xy 225.353118 -176.10328)
			(xy 225.35388 -176.094898) (xy 225.35388 -172.883322) (xy 225.353782 -172.878445) (xy 225.351989 -172.868857)
			(xy 225.350324 -172.864272) (xy 225.346514 -172.855128) (xy 224.018602 -171.527216) (xy 224.009406 -171.517966)
			(xy 223.991871 -171.498653) (xy 223.98355 -171.488608) (xy 223.982534 -171.487592) (xy 223.97974 -171.483782)
			(xy 223.97847 -171.482258) (xy 223.960217 -171.460587) (xy 223.92812 -171.413891) (xy 223.901423 -171.363912)
			(xy 223.890586 -171.337732) (xy 223.88703 -171.328588) (xy 223.882712 -171.31792) (xy 223.881188 -171.313856)
			(xy 223.875346 -171.294044) (xy 223.867844 -171.267521) (xy 223.857921 -171.2133) (xy 223.855534 -171.18584)
			(xy 223.855534 -171.185586) (xy 223.85528 -171.181014) (xy 223.855026 -171.18076) (xy 223.853661 -171.166959)
			(xy 223.85226 -171.139257) (xy 223.852232 -171.125388) (xy 223.852232 -170.222418) (xy 223.851978 -169.318432)
			(xy 223.85244 -169.287709) (xy 223.85984 -169.226711) (xy 223.874537 -169.167049) (xy 223.896316 -169.109593)
			(xy 223.92486 -169.055179) (xy 223.959753 -169.004602) (xy 224.000486 -168.958598) (xy 224.046466 -168.917838)
			(xy 224.097022 -168.882915) (xy 224.151419 -168.854339) (xy 224.208862 -168.832526) (xy 224.268516 -168.817794)
			(xy 224.329509 -168.810358) (xy 224.360232 -168.809924) (xy 224.360486 -168.809924) (xy 224.388664 -168.810305)
			(xy 224.444675 -168.816541) (xy 224.472246 -168.82237) (xy 224.503396 -168.829905) (xy 224.563638 -168.851775)
			(xy 224.62065 -168.881051) (xy 224.673524 -168.917268) (xy 224.697798 -168.938194) (xy 224.701354 -168.941496)
			(xy 224.71634 -168.95064) (xy 224.729294 -168.950894) (xy 224.749868 -168.951148) (xy 224.750376 -168.951148)
			(xy 224.759266 -168.951402) (xy 224.76714 -168.951656) (xy 224.774506 -168.949624) (xy 224.777981 -168.948589)
			(xy 224.78461 -168.945655) (xy 224.787714 -168.943782) (xy 224.79254 -168.940734) (xy 224.795588 -168.938194)
			(xy 224.818462 -168.91971) (xy 224.86771 -168.887564) (xy 224.920337 -168.861314) (xy 224.975642 -168.841311)
			(xy 225.032885 -168.827822) (xy 225.091303 -168.821026) (xy 225.120708 -168.820592) (xy 225.121216 -168.820592)
			(xy 225.151946 -168.821057) (xy 225.212959 -168.828467) (xy 225.272633 -168.843177) (xy 225.3301 -168.864973)
			(xy 225.38452 -168.893536) (xy 225.4351 -168.928451) (xy 225.481104 -168.969208) (xy 225.521859 -169.015212)
			(xy 225.556772 -169.065794) (xy 225.585334 -169.120215) (xy 225.607128 -169.177682) (xy 225.621836 -169.237357)
			(xy 225.629244 -169.29837) (xy 225.629724 -169.3291) (xy 225.629724 -170.490388) (xy 225.630486 -170.49877)
			(xy 225.631996 -170.506377) (xy 225.638976 -170.520218) (xy 225.644202 -170.525948) (xy 226.00285 -170.884596)
			(xy 226.013814 -170.894817) (xy 226.040229 -170.908954) (xy 226.069609 -170.91482) (xy 226.099427 -170.911909)
			(xy 226.127118 -170.900471) (xy 226.1503 -170.881492) (xy 226.166978 -170.856604) (xy 226.175717 -170.827947)
			(xy 226.176332 -170.812968) (xy 226.176332 -169.35958) (xy 226.176586 -169.34561) (xy 226.176586 -169.34434)
			(xy 226.17684 -169.343832) (xy 226.17684 -169.338244) (xy 226.177061 -169.307376) (xy 226.184074 -169.246045)
			(xy 226.198463 -169.186014) (xy 226.220017 -169.128168) (xy 226.248418 -169.073358) (xy 226.283248 -169.022392)
			(xy 226.323994 -168.976019) (xy 226.370057 -168.934923) (xy 226.420758 -168.899707) (xy 226.475351 -168.870892)
			(xy 226.533032 -168.848901) (xy 226.592952 -168.834057) (xy 226.654229 -168.82658) (xy 226.685094 -168.82618)
			(xy 226.71581 -168.826625) (xy 226.776795 -168.834029) (xy 226.836442 -168.848731) (xy 226.893883 -168.870516)
			(xy 226.948278 -168.899066) (xy 226.998835 -168.933964) (xy 227.044817 -168.974703) (xy 227.085553 -169.020687)
			(xy 227.120449 -169.071246) (xy 227.148996 -169.125643) (xy 227.170777 -169.183084) (xy 227.185476 -169.242733)
			(xy 227.192877 -169.303718) (xy 227.193348 -169.334434) (xy 227.193348 -171.048172) (xy 227.19411 -171.056554)
			(xy 227.195619 -171.064162) (xy 227.202598 -171.078004) (xy 227.207826 -171.083732) (xy 227.527358 -171.403264)
			(xy 227.625656 -171.501816) (xy 227.849938 -171.725844) (xy 227.857337 -171.732527) (xy 227.875749 -171.740124)
			(xy 227.895667 -171.740121) (xy 227.905056 -171.736766) (xy 227.914191 -171.73256) (xy 227.928432 -171.718383)
			(xy 227.936139 -171.699824) (xy 227.936552 -171.689776) (xy 227.936552 -167.205406) (xy 227.937095 -167.172127)
			(xy 227.945779 -167.106139) (xy 227.962999 -167.041849) (xy 227.98846 -166.980354) (xy 228.021728 -166.922708)
			(xy 228.062233 -166.869895) (xy 228.085396 -166.845996) (xy 228.287326 -166.643812) (xy 228.28758 -166.643558)
			(xy 228.29393 -166.637208) (xy 228.406706 -166.524432) (xy 228.431852 -166.49954) (xy 228.455751 -166.476373)
			(xy 228.508555 -166.435848) (xy 228.566198 -166.402564) (xy 228.627693 -166.377092) (xy 228.691988 -166.359867)
			(xy 228.757981 -166.351185) (xy 228.791262 -166.350696) (xy 228.821979 -166.351139) (xy 228.882966 -166.35854)
			(xy 228.942616 -166.37324) (xy 229.000059 -166.395023) (xy 229.054457 -166.423571) (xy 229.105016 -166.45847)
			(xy 229.151 -166.499208) (xy 229.191738 -166.545193) (xy 229.226635 -166.595754) (xy 229.255182 -166.650152)
			(xy 229.276964 -166.707596) (xy 229.291662 -166.767246) (xy 229.299062 -166.828233) (xy 229.299516 -166.85895)
			(xy 229.299193 -166.885815) (xy 229.293586 -166.939252) (xy 229.282387 -166.991803) (xy 229.27437 -167.017446)
			(xy 229.27056 -167.02913) (xy 229.266496 -167.039544) (xy 229.259246 -167.058146) (xy 229.242206 -167.094255)
			(xy 229.23246 -167.11168) (xy 229.221792 -167.12946) (xy 229.215188 -167.13962) (xy 229.212648 -167.14343)
			(xy 229.191058 -167.172894) (xy 229.183692 -167.182292) (xy 229.182676 -167.183816) (xy 229.179628 -167.187626)
			(xy 229.176915 -167.191026) (xy 229.172571 -167.198559) (xy 229.170992 -167.202612) (xy 229.165404 -167.217852)
			(xy 229.164642 -167.219884) (xy 229.163359 -167.223891) (xy 229.161957 -167.232188) (xy 229.161848 -167.236394)
			(xy 229.161848 -169.345356) (xy 233.320842 -169.345356) (xy 233.324913 -169.289734) (xy 233.337039 -169.235297)
			(xy 233.356962 -169.183206) (xy 233.384258 -169.134571) (xy 233.418344 -169.090428) (xy 233.458493 -169.051719)
			(xy 233.503851 -169.019268) (xy 233.553451 -168.993767) (xy 233.606235 -168.97576) (xy 233.661078 -168.96563)
			(xy 233.716812 -168.963593) (xy 233.772249 -168.969693) (xy 233.826206 -168.983799) (xy 233.877535 -169.005611)
			(xy 233.925141 -169.034665) (xy 233.968009 -169.07034) (xy 234.005226 -169.111877) (xy 234.035999 -169.15839)
			(xy 234.059671 -169.208887) (xy 234.075739 -169.262294) (xy 234.08344 -169.314622) (xy 235.759242 -169.314622)
			(xy 235.763313 -169.259) (xy 235.775439 -169.204563) (xy 235.795362 -169.152472) (xy 235.822658 -169.103837)
			(xy 235.856744 -169.059694) (xy 235.896893 -169.020985) (xy 235.942251 -168.988534) (xy 235.991851 -168.963033)
			(xy 236.044635 -168.945026) (xy 236.099478 -168.934896) (xy 236.155212 -168.932859) (xy 236.210649 -168.938959)
			(xy 236.264606 -168.953065) (xy 236.315935 -168.974877) (xy 236.363541 -169.003931) (xy 236.406409 -169.039606)
			(xy 236.443626 -169.081143) (xy 236.474399 -169.127656) (xy 236.498071 -169.178153) (xy 236.514139 -169.23156)
			(xy 236.522259 -169.286736) (xy 236.522768 -169.314622) (xy 236.522599 -169.323854) (xy 239.935443 -169.323854)
			(xy 239.935443 -169.269346) (xy 239.9432 -169.215392) (xy 239.958558 -169.163091) (xy 239.981202 -169.113509)
			(xy 240.010672 -169.067654) (xy 240.046368 -169.026459) (xy 240.087563 -168.990765) (xy 240.133419 -168.961296)
			(xy 240.183003 -168.938653) (xy 240.235304 -168.923298) (xy 240.289258 -168.915542) (xy 240.316512 -168.91508)
			(xy 240.342671 -168.915512) (xy 240.394497 -168.922662) (xy 240.444861 -168.936827) (xy 240.492817 -168.957741)
			(xy 240.537465 -168.985011) (xy 240.577968 -169.018126) (xy 240.613566 -169.056465) (xy 240.628932 -169.07764)
			(xy 240.636951 -169.08824) (xy 240.657293 -169.105325) (xy 240.681356 -169.116581) (xy 240.707508 -169.121246)
			(xy 240.733978 -169.119003) (xy 240.758972 -169.110005) (xy 240.780798 -169.09486) (xy 240.789714 -169.085006)
			(xy 240.807929 -169.064258) (xy 240.849322 -169.027723) (xy 240.895548 -168.997536) (xy 240.945643 -168.974326)
			(xy 240.998559 -168.958577) (xy 241.053193 -168.95062) (xy 241.080798 -168.950132) (xy 241.108054 -168.950515)
			(xy 241.162011 -168.958272) (xy 241.214314 -168.97363) (xy 241.2639 -168.996275) (xy 241.309758 -169.025746)
			(xy 241.350955 -169.061443) (xy 241.386653 -169.10264) (xy 241.416124 -169.148498) (xy 241.438769 -169.198084)
			(xy 241.454127 -169.250387) (xy 241.461885 -169.304344) (xy 241.461885 -169.334434) (xy 242.067586 -169.334434)
			(xy 242.071657 -169.278812) (xy 242.083783 -169.224375) (xy 242.103706 -169.172284) (xy 242.131002 -169.123649)
			(xy 242.165088 -169.079506) (xy 242.205237 -169.040797) (xy 242.250595 -169.008346) (xy 242.300195 -168.982845)
			(xy 242.352979 -168.964838) (xy 242.407822 -168.954708) (xy 242.463556 -168.952671) (xy 242.518993 -168.958771)
			(xy 242.57295 -168.972877) (xy 242.624279 -168.994689) (xy 242.671885 -169.023743) (xy 242.714753 -169.059418)
			(xy 242.75197 -169.100955) (xy 242.782743 -169.147468) (xy 242.806415 -169.197965) (xy 242.822483 -169.251372)
			(xy 242.830603 -169.306548) (xy 242.831112 -169.334434) (xy 242.830603 -169.36232) (xy 242.822483 -169.417496)
			(xy 242.806415 -169.470903) (xy 242.782743 -169.5214) (xy 242.75197 -169.567913) (xy 242.714753 -169.60945)
			(xy 242.709418 -169.61389) (xy 245.108869 -169.61389) (xy 245.108869 -169.55391) (xy 245.116699 -169.494444)
			(xy 245.132223 -169.436508) (xy 245.155178 -169.381095) (xy 245.185169 -169.329152) (xy 245.221684 -169.281569)
			(xy 245.264097 -169.239158) (xy 245.311684 -169.202648) (xy 245.363629 -169.172661) (xy 245.419045 -169.149711)
			(xy 245.476981 -169.134191) (xy 245.536448 -169.126367) (xy 245.566438 -169.1259) (xy 246.430038 -169.1259)
			(xy 246.460018 -169.126468) (xy 246.519465 -169.134299) (xy 246.577381 -169.149822) (xy 246.632776 -169.172772)
			(xy 246.684702 -169.202755) (xy 246.73227 -169.239259) (xy 246.774667 -169.281659) (xy 246.811166 -169.32923)
			(xy 246.841145 -169.381158) (xy 246.86409 -169.436555) (xy 246.879608 -169.494472) (xy 246.887434 -169.55392)
			(xy 246.887434 -169.61388) (xy 246.879608 -169.673328) (xy 246.86409 -169.731245) (xy 246.841145 -169.786642)
			(xy 246.811166 -169.83857) (xy 246.774667 -169.886141) (xy 246.73227 -169.928541) (xy 246.684702 -169.965045)
			(xy 246.632776 -169.995028) (xy 246.577381 -170.017978) (xy 246.519465 -170.033501) (xy 246.460018 -170.041332)
			(xy 246.430038 -170.041824) (xy 245.566438 -170.041824) (xy 245.536448 -170.041433) (xy 245.476981 -170.033609)
			(xy 245.419045 -170.018089) (xy 245.363629 -169.995139) (xy 245.311684 -169.965152) (xy 245.264097 -169.928642)
			(xy 245.221684 -169.886231) (xy 245.185169 -169.838648) (xy 245.155178 -169.786705) (xy 245.132223 -169.731292)
			(xy 245.116699 -169.673356) (xy 245.108869 -169.61389) (xy 242.709418 -169.61389) (xy 242.671885 -169.645125)
			(xy 242.624279 -169.674179) (xy 242.57295 -169.695991) (xy 242.518993 -169.710097) (xy 242.463556 -169.716197)
			(xy 242.407822 -169.71416) (xy 242.352979 -169.70403) (xy 242.300195 -169.686023) (xy 242.250595 -169.660522)
			(xy 242.205237 -169.628071) (xy 242.165088 -169.589362) (xy 242.131002 -169.545219) (xy 242.103706 -169.496584)
			(xy 242.083783 -169.444493) (xy 242.071657 -169.390056) (xy 242.067586 -169.334434) (xy 241.461885 -169.334434)
			(xy 241.461885 -169.358856) (xy 241.454127 -169.412813) (xy 241.438769 -169.465116) (xy 241.416124 -169.514702)
			(xy 241.386653 -169.56056) (xy 241.350955 -169.601757) (xy 241.309758 -169.637454) (xy 241.2639 -169.666925)
			(xy 241.214314 -169.68957) (xy 241.162011 -169.704928) (xy 241.108054 -169.712685) (xy 241.080798 -169.713148)
			(xy 241.05464 -169.712697) (xy 241.002815 -169.705548) (xy 240.952452 -169.691386) (xy 240.904497 -169.670475)
			(xy 240.859849 -169.643208) (xy 240.819345 -169.610096) (xy 240.783745 -169.571761) (xy 240.768378 -169.550588)
			(xy 240.760347 -169.539997) (xy 240.740009 -169.522907) (xy 240.715949 -169.511647) (xy 240.689798 -169.50698)
			(xy 240.663328 -169.509222) (xy 240.638334 -169.518221) (xy 240.616511 -169.533367) (xy 240.607596 -169.543222)
			(xy 240.589382 -169.563971) (xy 240.547988 -169.600504) (xy 240.501761 -169.630691) (xy 240.451667 -169.653901)
			(xy 240.39875 -169.669649) (xy 240.344117 -169.677607) (xy 240.316512 -169.678096) (xy 240.289258 -169.677658)
			(xy 240.235304 -169.669902) (xy 240.183003 -169.654547) (xy 240.133419 -169.631904) (xy 240.087563 -169.602435)
			(xy 240.046368 -169.566741) (xy 240.010672 -169.525546) (xy 239.981202 -169.479691) (xy 239.958558 -169.430109)
			(xy 239.9432 -169.377808) (xy 239.935443 -169.323854) (xy 236.522599 -169.323854) (xy 236.522259 -169.342508)
			(xy 236.514139 -169.397684) (xy 236.498071 -169.451091) (xy 236.474399 -169.501588) (xy 236.443626 -169.548101)
			(xy 236.406409 -169.589638) (xy 236.363541 -169.625313) (xy 236.315935 -169.654367) (xy 236.264606 -169.676179)
			(xy 236.210649 -169.690285) (xy 236.155212 -169.696385) (xy 236.099478 -169.694348) (xy 236.044635 -169.684218)
			(xy 235.991851 -169.666211) (xy 235.942251 -169.64071) (xy 235.896893 -169.608259) (xy 235.856744 -169.56955)
			(xy 235.822658 -169.525407) (xy 235.795362 -169.476772) (xy 235.775439 -169.424681) (xy 235.763313 -169.370244)
			(xy 235.759242 -169.314622) (xy 234.08344 -169.314622) (xy 234.083859 -169.31747) (xy 234.084368 -169.345356)
			(xy 234.083859 -169.373242) (xy 234.075739 -169.428418) (xy 234.059671 -169.481825) (xy 234.035999 -169.532322)
			(xy 234.005226 -169.578835) (xy 233.968009 -169.620372) (xy 233.925141 -169.656047) (xy 233.877535 -169.685101)
			(xy 233.826206 -169.706913) (xy 233.772249 -169.721019) (xy 233.716812 -169.727119) (xy 233.661078 -169.725082)
			(xy 233.606235 -169.714952) (xy 233.553451 -169.696945) (xy 233.503851 -169.671444) (xy 233.458493 -169.638993)
			(xy 233.418344 -169.600284) (xy 233.384258 -169.556141) (xy 233.356962 -169.507506) (xy 233.337039 -169.455415)
			(xy 233.324913 -169.400978) (xy 233.320842 -169.345356) (xy 229.161848 -169.345356) (xy 229.161848 -172.15993)
			(xy 230.571292 -172.15993) (xy 230.575363 -172.104308) (xy 230.587489 -172.049871) (xy 230.607412 -171.99778)
			(xy 230.634708 -171.949145) (xy 230.668794 -171.905002) (xy 230.708943 -171.866293) (xy 230.754301 -171.833842)
			(xy 230.803901 -171.808341) (xy 230.856685 -171.790334) (xy 230.911528 -171.780204) (xy 230.967262 -171.778167)
			(xy 231.022699 -171.784267) (xy 231.076656 -171.798373) (xy 231.127985 -171.820185) (xy 231.175591 -171.849239)
			(xy 231.218459 -171.884914) (xy 231.255676 -171.926451) (xy 231.286449 -171.972964) (xy 231.310121 -172.023461)
			(xy 231.326189 -172.076868) (xy 231.334309 -172.132044) (xy 231.334818 -172.15993) (xy 231.334309 -172.187816)
			(xy 231.330189 -172.21581) (xy 254.043686 -172.21581) (xy 254.047757 -172.160188) (xy 254.059883 -172.105751)
			(xy 254.079806 -172.05366) (xy 254.107102 -172.005025) (xy 254.141188 -171.960882) (xy 254.181337 -171.922173)
			(xy 254.226695 -171.889722) (xy 254.276295 -171.864221) (xy 254.329079 -171.846214) (xy 254.383922 -171.836084)
			(xy 254.439656 -171.834047) (xy 254.495093 -171.840147) (xy 254.54905 -171.854253) (xy 254.600379 -171.876065)
			(xy 254.647985 -171.905119) (xy 254.690853 -171.940794) (xy 254.72807 -171.982331) (xy 254.758843 -172.028844)
			(xy 254.782515 -172.079341) (xy 254.798583 -172.132748) (xy 254.806703 -172.187924) (xy 254.807212 -172.21581)
			(xy 254.806703 -172.243696) (xy 254.798583 -172.298872) (xy 254.782515 -172.352279) (xy 254.758843 -172.402776)
			(xy 254.72807 -172.449289) (xy 254.690853 -172.490826) (xy 254.647985 -172.526501) (xy 254.600379 -172.555555)
			(xy 254.54905 -172.577367) (xy 254.495093 -172.591473) (xy 254.439656 -172.597573) (xy 254.383922 -172.595536)
			(xy 254.329079 -172.585406) (xy 254.276295 -172.567399) (xy 254.226695 -172.541898) (xy 254.181337 -172.509447)
			(xy 254.141188 -172.470738) (xy 254.107102 -172.426595) (xy 254.079806 -172.37796) (xy 254.059883 -172.325869)
			(xy 254.047757 -172.271432) (xy 254.043686 -172.21581) (xy 231.330189 -172.21581) (xy 231.326189 -172.242992)
			(xy 231.310121 -172.296399) (xy 231.286449 -172.346896) (xy 231.255676 -172.393409) (xy 231.218459 -172.434946)
			(xy 231.175591 -172.470621) (xy 231.127985 -172.499675) (xy 231.076656 -172.521487) (xy 231.022699 -172.535593)
			(xy 230.967262 -172.541693) (xy 230.911528 -172.539656) (xy 230.856685 -172.529526) (xy 230.803901 -172.511519)
			(xy 230.754301 -172.486018) (xy 230.708943 -172.453567) (xy 230.668794 -172.414858) (xy 230.634708 -172.370715)
			(xy 230.607412 -172.32208) (xy 230.587489 -172.269989) (xy 230.575363 -172.215552) (xy 230.571292 -172.15993)
			(xy 229.161848 -172.15993) (xy 229.161848 -172.786294) (xy 235.508798 -172.786294) (xy 235.512869 -172.730672)
			(xy 235.524995 -172.676235) (xy 235.544918 -172.624144) (xy 235.572214 -172.575509) (xy 235.6063 -172.531366)
			(xy 235.646449 -172.492657) (xy 235.691807 -172.460206) (xy 235.741407 -172.434705) (xy 235.794191 -172.416698)
			(xy 235.849034 -172.406568) (xy 235.904768 -172.404531) (xy 235.960205 -172.410631) (xy 236.014162 -172.424737)
			(xy 236.065491 -172.446549) (xy 236.113097 -172.475603) (xy 236.155965 -172.511278) (xy 236.193182 -172.552815)
			(xy 236.223955 -172.599328) (xy 236.247627 -172.649825) (xy 236.263695 -172.703232) (xy 236.271815 -172.758408)
			(xy 236.272324 -172.786294) (xy 236.271815 -172.81418) (xy 236.263695 -172.869356) (xy 236.247627 -172.922763)
			(xy 236.230157 -172.96003) (xy 237.179356 -172.96003) (xy 237.183427 -172.904408) (xy 237.195553 -172.849971)
			(xy 237.215476 -172.79788) (xy 237.242772 -172.749245) (xy 237.276858 -172.705102) (xy 237.317007 -172.666393)
			(xy 237.362365 -172.633942) (xy 237.411965 -172.608441) (xy 237.464749 -172.590434) (xy 237.519592 -172.580304)
			(xy 237.575326 -172.578267) (xy 237.630763 -172.584367) (xy 237.68472 -172.598473) (xy 237.736049 -172.620285)
			(xy 237.783655 -172.649339) (xy 237.826523 -172.685014) (xy 237.86374 -172.726551) (xy 237.894513 -172.773064)
			(xy 237.918185 -172.823561) (xy 237.934253 -172.876968) (xy 237.942373 -172.932144) (xy 237.942882 -172.96003)
			(xy 237.942373 -172.987916) (xy 237.934253 -173.043092) (xy 237.918185 -173.096499) (xy 237.894513 -173.146996)
			(xy 237.86374 -173.193509) (xy 237.826523 -173.235046) (xy 237.783655 -173.270721) (xy 237.736049 -173.299775)
			(xy 237.68472 -173.321587) (xy 237.630763 -173.335693) (xy 237.575326 -173.341793) (xy 237.519592 -173.339756)
			(xy 237.464749 -173.329626) (xy 237.411965 -173.311619) (xy 237.362365 -173.286118) (xy 237.317007 -173.253667)
			(xy 237.276858 -173.214958) (xy 237.242772 -173.170815) (xy 237.215476 -173.12218) (xy 237.195553 -173.070089)
			(xy 237.183427 -173.015652) (xy 237.179356 -172.96003) (xy 236.230157 -172.96003) (xy 236.223955 -172.97326)
			(xy 236.193182 -173.019773) (xy 236.155965 -173.06131) (xy 236.113097 -173.096985) (xy 236.065491 -173.126039)
			(xy 236.014162 -173.147851) (xy 235.960205 -173.161957) (xy 235.904768 -173.168057) (xy 235.849034 -173.16602)
			(xy 235.794191 -173.15589) (xy 235.741407 -173.137883) (xy 235.691807 -173.112382) (xy 235.646449 -173.079931)
			(xy 235.6063 -173.041222) (xy 235.572214 -172.997079) (xy 235.544918 -172.948444) (xy 235.524995 -172.896353)
			(xy 235.512869 -172.841916) (xy 235.508798 -172.786294) (xy 229.161848 -172.786294) (xy 229.161848 -173.67758)
			(xy 231.38333 -173.67758) (xy 231.387401 -173.621958) (xy 231.399527 -173.567521) (xy 231.41945 -173.51543)
			(xy 231.446746 -173.466795) (xy 231.480832 -173.422652) (xy 231.520981 -173.383943) (xy 231.566339 -173.351492)
			(xy 231.615939 -173.325991) (xy 231.668723 -173.307984) (xy 231.723566 -173.297854) (xy 231.7793 -173.295817)
			(xy 231.834737 -173.301917) (xy 231.888694 -173.316023) (xy 231.940023 -173.337835) (xy 231.987629 -173.366889)
			(xy 232.030497 -173.402564) (xy 232.067714 -173.444101) (xy 232.098487 -173.490614) (xy 232.122159 -173.541111)
			(xy 232.138227 -173.594518) (xy 232.146347 -173.649694) (xy 232.146856 -173.67758) (xy 232.146347 -173.705466)
			(xy 232.138227 -173.760642) (xy 232.122159 -173.814049) (xy 232.098487 -173.864546) (xy 232.067714 -173.911059)
			(xy 232.030497 -173.952596) (xy 231.987629 -173.988271) (xy 231.940023 -174.017325) (xy 231.888694 -174.039137)
			(xy 231.834737 -174.053243) (xy 231.7793 -174.059343) (xy 231.723566 -174.057306) (xy 231.668723 -174.047176)
			(xy 231.615939 -174.029169) (xy 231.566339 -174.003668) (xy 231.520981 -173.971217) (xy 231.480832 -173.932508)
			(xy 231.446746 -173.888365) (xy 231.41945 -173.83973) (xy 231.399527 -173.787639) (xy 231.387401 -173.733202)
			(xy 231.38333 -173.67758) (xy 229.161848 -173.67758) (xy 229.161848 -174.660306) (xy 229.162266 -174.669644)
			(xy 229.168954 -174.68708) (xy 229.174799 -174.69358) (xy 231.38333 -174.69358) (xy 231.387401 -174.637958)
			(xy 231.399527 -174.583521) (xy 231.41945 -174.53143) (xy 231.446746 -174.482795) (xy 231.480832 -174.438652)
			(xy 231.520981 -174.399943) (xy 231.566339 -174.367492) (xy 231.615939 -174.341991) (xy 231.668723 -174.323984)
			(xy 231.723566 -174.313854) (xy 231.7793 -174.311817) (xy 231.834737 -174.317917) (xy 231.884276 -174.330868)
			(xy 235.419644 -174.330868) (xy 235.423715 -174.275246) (xy 235.435841 -174.220809) (xy 235.455764 -174.168718)
			(xy 235.48306 -174.120083) (xy 235.517146 -174.07594) (xy 235.557295 -174.037231) (xy 235.602653 -174.00478)
			(xy 235.652253 -173.979279) (xy 235.705037 -173.961272) (xy 235.75988 -173.951142) (xy 235.815614 -173.949105)
			(xy 235.871051 -173.955205) (xy 235.925008 -173.969311) (xy 235.976337 -173.991123) (xy 236.023943 -174.020177)
			(xy 236.066811 -174.055852) (xy 236.104028 -174.097389) (xy 236.134801 -174.143902) (xy 236.158473 -174.194399)
			(xy 236.174541 -174.247806) (xy 236.182661 -174.302982) (xy 236.18317 -174.330868) (xy 236.182661 -174.358754)
			(xy 236.174541 -174.41393) (xy 236.158473 -174.467337) (xy 236.134801 -174.517834) (xy 236.104028 -174.564347)
			(xy 236.066811 -174.605884) (xy 236.023943 -174.641559) (xy 235.976337 -174.670613) (xy 235.925008 -174.692425)
			(xy 235.871051 -174.706531) (xy 235.815614 -174.712631) (xy 235.75988 -174.710594) (xy 235.705037 -174.700464)
			(xy 235.652253 -174.682457) (xy 235.602653 -174.656956) (xy 235.557295 -174.624505) (xy 235.517146 -174.585796)
			(xy 235.48306 -174.541653) (xy 235.455764 -174.493018) (xy 235.435841 -174.440927) (xy 235.423715 -174.38649)
			(xy 235.419644 -174.330868) (xy 231.884276 -174.330868) (xy 231.888694 -174.332023) (xy 231.940023 -174.353835)
			(xy 231.987629 -174.382889) (xy 232.030497 -174.418564) (xy 232.067714 -174.460101) (xy 232.098487 -174.506614)
			(xy 232.122159 -174.557111) (xy 232.138227 -174.610518) (xy 232.146347 -174.665694) (xy 232.146856 -174.69358)
			(xy 232.146347 -174.721466) (xy 232.138227 -174.776642) (xy 232.122159 -174.830049) (xy 232.098487 -174.880546)
			(xy 232.067714 -174.927059) (xy 232.030497 -174.968596) (xy 231.987629 -175.004271) (xy 231.940023 -175.033325)
			(xy 231.888694 -175.055137) (xy 231.834737 -175.069243) (xy 231.7793 -175.075343) (xy 231.723566 -175.073306)
			(xy 231.668723 -175.063176) (xy 231.615939 -175.045169) (xy 231.566339 -175.019668) (xy 231.520981 -174.987217)
			(xy 231.480832 -174.948508) (xy 231.446746 -174.904365) (xy 231.41945 -174.85573) (xy 231.399527 -174.803639)
			(xy 231.387401 -174.749202) (xy 231.38333 -174.69358) (xy 229.174799 -174.69358) (xy 229.181441 -174.700967)
			(xy 229.198072 -174.709462) (xy 229.207314 -174.710852) (xy 229.235115 -174.714235) (xy 229.289375 -174.728103)
			(xy 229.341025 -174.749756) (xy 229.388954 -174.778727) (xy 229.432132 -174.814394) (xy 229.469631 -174.85599)
			(xy 229.500646 -174.902622) (xy 229.52451 -174.953288) (xy 229.540709 -175.006898) (xy 229.548897 -175.062301)
			(xy 229.548897 -175.118305) (xy 229.540708 -175.173707) (xy 229.524508 -175.227317) (xy 229.500643 -175.277983)
			(xy 229.469628 -175.324614) (xy 229.432127 -175.36621) (xy 229.388949 -175.401877) (xy 229.34102 -175.430847)
			(xy 229.28937 -175.452499) (xy 229.23511 -175.466366) (xy 229.207314 -175.469804) (xy 229.187756 -175.471836)
			(xy 229.161848 -175.500792) (xy 229.161848 -175.930306) (xy 229.162266 -175.939644) (xy 229.168954 -175.95708)
			(xy 229.181441 -175.970967) (xy 229.198072 -175.979462) (xy 229.207314 -175.980852) (xy 229.235115 -175.984235)
			(xy 229.289375 -175.998103) (xy 229.341025 -176.019756) (xy 229.388954 -176.048727) (xy 229.432132 -176.084394)
			(xy 229.469631 -176.12599) (xy 229.500646 -176.172622) (xy 229.52451 -176.223288) (xy 229.540709 -176.276898)
			(xy 229.548897 -176.332301) (xy 229.548897 -176.388305) (xy 229.540708 -176.443707) (xy 229.524508 -176.497317)
			(xy 229.500643 -176.547983) (xy 229.469628 -176.594614) (xy 229.432127 -176.63621) (xy 229.388949 -176.671877)
			(xy 229.34102 -176.700847) (xy 229.28937 -176.722499) (xy 229.23511 -176.736366) (xy 229.207314 -176.739804)
			(xy 229.187756 -176.741836) (xy 229.161848 -176.770792) (xy 229.161848 -177.6857) (xy 240.297206 -177.6857)
			(xy 240.301277 -177.630078) (xy 240.313403 -177.575641) (xy 240.333326 -177.52355) (xy 240.360622 -177.474915)
			(xy 240.394708 -177.430772) (xy 240.434857 -177.392063) (xy 240.480215 -177.359612) (xy 240.529815 -177.334111)
			(xy 240.582599 -177.316104) (xy 240.637442 -177.305974) (xy 240.693176 -177.303937) (xy 240.748613 -177.310037)
			(xy 240.80257 -177.324143) (xy 240.853899 -177.345955) (xy 240.901505 -177.375009) (xy 240.944373 -177.410684)
			(xy 240.98159 -177.452221) (xy 241.012363 -177.498734) (xy 241.036035 -177.549231) (xy 241.052103 -177.602638)
			(xy 241.060223 -177.657814) (xy 241.060732 -177.6857) (xy 241.060223 -177.713586) (xy 241.052103 -177.768762)
			(xy 241.036035 -177.822169) (xy 241.012363 -177.872666) (xy 240.98159 -177.919179) (xy 240.944373 -177.960716)
			(xy 240.901505 -177.996391) (xy 240.853899 -178.025445) (xy 240.80257 -178.047257) (xy 240.748613 -178.061363)
			(xy 240.693176 -178.067463) (xy 240.637442 -178.065426) (xy 240.582599 -178.055296) (xy 240.529815 -178.037289)
			(xy 240.480215 -178.011788) (xy 240.434857 -177.979337) (xy 240.394708 -177.940628) (xy 240.360622 -177.896485)
			(xy 240.333326 -177.84785) (xy 240.313403 -177.795759) (xy 240.301277 -177.741322) (xy 240.297206 -177.6857)
			(xy 229.161848 -177.6857) (xy 229.161848 -178.251358) (xy 229.161848 -178.254152) (xy 229.162156 -178.258057)
			(xy 229.16381 -178.265712) (xy 229.16515 -178.269392) (xy 229.166928 -178.27371) (xy 229.169088 -178.27789)
			(xy 229.174719 -178.285427) (xy 229.178104 -178.288696) (xy 229.196646 -178.305206) (xy 229.235762 -178.33975)
			(xy 229.239979 -178.343294) (xy 229.249585 -178.348681) (xy 229.254812 -178.350418) (xy 229.265226 -178.353466)
			(xy 229.276148 -178.351942) (xy 229.287474 -178.350714) (xy 229.310222 -178.349442) (xy 229.321614 -178.349402)
			(xy 229.348864 -178.349889) (xy 229.402809 -178.357647) (xy 229.4551 -178.373003) (xy 229.471274 -178.38039)
			(xy 229.967026 -178.38039) (xy 229.971097 -178.324768) (xy 229.983223 -178.270331) (xy 230.003146 -178.21824)
			(xy 230.030442 -178.169605) (xy 230.064528 -178.125462) (xy 230.104677 -178.086753) (xy 230.150035 -178.054302)
			(xy 230.199635 -178.028801) (xy 230.252419 -178.010794) (xy 230.307262 -178.000664) (xy 230.362996 -177.998627)
			(xy 230.418433 -178.004727) (xy 230.47239 -178.018833) (xy 230.523719 -178.040645) (xy 230.571325 -178.069699)
			(xy 230.614193 -178.105374) (xy 230.65141 -178.146911) (xy 230.682183 -178.193424) (xy 230.705855 -178.243921)
			(xy 230.721923 -178.297328) (xy 230.730043 -178.352504) (xy 230.730552 -178.38039) (xy 230.730043 -178.408276)
			(xy 230.721923 -178.463452) (xy 230.705855 -178.516859) (xy 230.682183 -178.567356) (xy 230.65141 -178.613869)
			(xy 230.614193 -178.655406) (xy 230.571325 -178.691081) (xy 230.523719 -178.720135) (xy 230.47239 -178.741947)
			(xy 230.418433 -178.756053) (xy 230.362996 -178.762153) (xy 230.307262 -178.760116) (xy 230.252419 -178.749986)
			(xy 230.199635 -178.731979) (xy 230.150035 -178.706478) (xy 230.104677 -178.674027) (xy 230.064528 -178.635318)
			(xy 230.030442 -178.591175) (xy 230.003146 -178.54254) (xy 229.983223 -178.490449) (xy 229.971097 -178.436012)
			(xy 229.967026 -178.38039) (xy 229.471274 -178.38039) (xy 229.504674 -178.395644) (xy 229.550522 -178.42511)
			(xy 229.591709 -178.460801) (xy 229.627398 -178.50199) (xy 229.656862 -178.547838) (xy 229.679502 -178.597413)
			(xy 229.694856 -178.649705) (xy 229.702612 -178.70365) (xy 229.702612 -178.75815) (xy 229.694856 -178.812095)
			(xy 229.679502 -178.864387) (xy 229.656862 -178.913962) (xy 229.627398 -178.95981) (xy 229.591709 -179.000999)
			(xy 229.550522 -179.03669) (xy 229.504674 -179.066156) (xy 229.4551 -179.088797) (xy 229.402809 -179.104153)
			(xy 229.348864 -179.111911) (xy 229.321614 -179.112418) (xy 229.310222 -179.11238) (xy 229.287474 -179.111106)
			(xy 229.276148 -179.109878) (xy 229.265226 -179.108354) (xy 229.254812 -179.111402) (xy 229.249576 -179.11312)
			(xy 229.239957 -179.118497) (xy 229.235762 -179.12207) (xy 229.17912 -179.172108) (xy 229.175079 -179.175837)
			(xy 229.16855 -179.184679) (xy 229.166166 -179.189634) (xy 229.161848 -179.199286) (xy 229.161848 -179.554378)
			(xy 242.447824 -179.554378) (xy 242.451895 -179.498756) (xy 242.464021 -179.444319) (xy 242.483944 -179.392228)
			(xy 242.51124 -179.343593) (xy 242.545326 -179.29945) (xy 242.585475 -179.260741) (xy 242.630833 -179.22829)
			(xy 242.680433 -179.202789) (xy 242.733217 -179.184782) (xy 242.78806 -179.174652) (xy 242.843794 -179.172615)
			(xy 242.899231 -179.178715) (xy 242.953188 -179.192821) (xy 243.004517 -179.214633) (xy 243.052123 -179.243687)
			(xy 243.094991 -179.279362) (xy 243.132208 -179.320899) (xy 243.162981 -179.367412) (xy 243.186653 -179.417909)
			(xy 243.202721 -179.471316) (xy 243.210841 -179.526492) (xy 243.21135 -179.554378) (xy 244.924578 -179.554378)
			(xy 244.928649 -179.498756) (xy 244.940775 -179.444319) (xy 244.960698 -179.392228) (xy 244.987994 -179.343593)
			(xy 245.02208 -179.29945) (xy 245.062229 -179.260741) (xy 245.107587 -179.22829) (xy 245.157187 -179.202789)
			(xy 245.209971 -179.184782) (xy 245.264814 -179.174652) (xy 245.320548 -179.172615) (xy 245.375985 -179.178715)
			(xy 245.429942 -179.192821) (xy 245.481271 -179.214633) (xy 245.528877 -179.243687) (xy 245.571745 -179.279362)
			(xy 245.608962 -179.320899) (xy 245.639735 -179.367412) (xy 245.663407 -179.417909) (xy 245.679475 -179.471316)
			(xy 245.687595 -179.526492) (xy 245.688104 -179.554378) (xy 245.687595 -179.582264) (xy 245.679475 -179.63744)
			(xy 245.663407 -179.690847) (xy 245.639735 -179.741344) (xy 245.608962 -179.787857) (xy 245.571745 -179.829394)
			(xy 245.528877 -179.865069) (xy 245.481271 -179.894123) (xy 245.429942 -179.915935) (xy 245.375985 -179.930041)
			(xy 245.320548 -179.936141) (xy 245.264814 -179.934104) (xy 245.209971 -179.923974) (xy 245.157187 -179.905967)
			(xy 245.107587 -179.880466) (xy 245.062229 -179.848015) (xy 245.02208 -179.809306) (xy 244.987994 -179.765163)
			(xy 244.960698 -179.716528) (xy 244.940775 -179.664437) (xy 244.928649 -179.61) (xy 244.924578 -179.554378)
			(xy 243.21135 -179.554378) (xy 243.210841 -179.582264) (xy 243.202721 -179.63744) (xy 243.186653 -179.690847)
			(xy 243.162981 -179.741344) (xy 243.132208 -179.787857) (xy 243.094991 -179.829394) (xy 243.052123 -179.865069)
			(xy 243.004517 -179.894123) (xy 242.953188 -179.915935) (xy 242.899231 -179.930041) (xy 242.843794 -179.936141)
			(xy 242.78806 -179.934104) (xy 242.733217 -179.923974) (xy 242.680433 -179.905967) (xy 242.630833 -179.880466)
			(xy 242.585475 -179.848015) (xy 242.545326 -179.809306) (xy 242.51124 -179.765163) (xy 242.483944 -179.716528)
			(xy 242.464021 -179.664437) (xy 242.451895 -179.61) (xy 242.447824 -179.554378) (xy 229.161848 -179.554378)
			(xy 229.161848 -180.184298) (xy 230.427528 -180.184298) (xy 230.431599 -180.128676) (xy 230.443725 -180.074239)
			(xy 230.463648 -180.022148) (xy 230.490944 -179.973513) (xy 230.52503 -179.92937) (xy 230.565179 -179.890661)
			(xy 230.610537 -179.85821) (xy 230.660137 -179.832709) (xy 230.712921 -179.814702) (xy 230.767764 -179.804572)
			(xy 230.823498 -179.802535) (xy 230.878935 -179.808635) (xy 230.932892 -179.822741) (xy 230.984221 -179.844553)
			(xy 231.031827 -179.873607) (xy 231.074695 -179.909282) (xy 231.111912 -179.950819) (xy 231.142685 -179.997332)
			(xy 231.166357 -180.047829) (xy 231.182425 -180.101236) (xy 231.190545 -180.156412) (xy 231.191054 -180.184298)
			(xy 231.190545 -180.212184) (xy 231.182425 -180.26736) (xy 231.166357 -180.320767) (xy 231.142685 -180.371264)
			(xy 231.111912 -180.417777) (xy 231.074695 -180.459314) (xy 231.031827 -180.494989) (xy 230.984221 -180.524043)
			(xy 230.932892 -180.545855) (xy 230.878935 -180.559961) (xy 230.823498 -180.566061) (xy 230.767764 -180.564024)
			(xy 230.712921 -180.553894) (xy 230.660137 -180.535887) (xy 230.610537 -180.510386) (xy 230.565179 -180.477935)
			(xy 230.52503 -180.439226) (xy 230.490944 -180.395083) (xy 230.463648 -180.346448) (xy 230.443725 -180.294357)
			(xy 230.431599 -180.23992) (xy 230.427528 -180.184298) (xy 229.161848 -180.184298) (xy 229.161848 -181.407816)
			(xy 231.58272 -181.407816) (xy 231.586791 -181.352194) (xy 231.598917 -181.297757) (xy 231.61884 -181.245666)
			(xy 231.646136 -181.197031) (xy 231.680222 -181.152888) (xy 231.720371 -181.114179) (xy 231.765729 -181.081728)
			(xy 231.815329 -181.056227) (xy 231.868113 -181.03822) (xy 231.922956 -181.02809) (xy 231.97869 -181.026053)
			(xy 232.034127 -181.032153) (xy 232.088084 -181.046259) (xy 232.139413 -181.068071) (xy 232.187019 -181.097125)
			(xy 232.229887 -181.1328) (xy 232.267104 -181.174337) (xy 232.297877 -181.22085) (xy 232.321549 -181.271347)
			(xy 232.337617 -181.324754) (xy 232.345737 -181.37993) (xy 232.346246 -181.407816) (xy 232.345737 -181.435702)
			(xy 232.337617 -181.490878) (xy 232.321549 -181.544285) (xy 232.297877 -181.594782) (xy 232.267104 -181.641295)
			(xy 232.229887 -181.682832) (xy 232.199592 -181.708044) (xy 233.567476 -181.708044) (xy 233.571547 -181.652422)
			(xy 233.583673 -181.597985) (xy 233.603596 -181.545894) (xy 233.630892 -181.497259) (xy 233.664978 -181.453116)
			(xy 233.705127 -181.414407) (xy 233.750485 -181.381956) (xy 233.800085 -181.356455) (xy 233.852869 -181.338448)
			(xy 233.907712 -181.328318) (xy 233.963446 -181.326281) (xy 234.018883 -181.332381) (xy 234.07284 -181.346487)
			(xy 234.124169 -181.368299) (xy 234.171775 -181.397353) (xy 234.214643 -181.433028) (xy 234.25186 -181.474565)
			(xy 234.282633 -181.521078) (xy 234.306305 -181.571575) (xy 234.322373 -181.624982) (xy 234.330493 -181.680158)
			(xy 234.331002 -181.708044) (xy 234.330493 -181.73593) (xy 234.322373 -181.791106) (xy 234.306305 -181.844513)
			(xy 234.282633 -181.89501) (xy 234.25186 -181.941523) (xy 234.214643 -181.98306) (xy 234.171775 -182.018735)
			(xy 234.124169 -182.047789) (xy 234.07284 -182.069601) (xy 234.018883 -182.083707) (xy 233.963446 -182.089807)
			(xy 233.907712 -182.08777) (xy 233.852869 -182.07764) (xy 233.800085 -182.059633) (xy 233.750485 -182.034132)
			(xy 233.705127 -182.001681) (xy 233.664978 -181.962972) (xy 233.630892 -181.918829) (xy 233.603596 -181.870194)
			(xy 233.583673 -181.818103) (xy 233.571547 -181.763666) (xy 233.567476 -181.708044) (xy 232.199592 -181.708044)
			(xy 232.187019 -181.718507) (xy 232.139413 -181.747561) (xy 232.088084 -181.769373) (xy 232.034127 -181.783479)
			(xy 231.97869 -181.789579) (xy 231.922956 -181.787542) (xy 231.868113 -181.777412) (xy 231.815329 -181.759405)
			(xy 231.765729 -181.733904) (xy 231.720371 -181.701453) (xy 231.680222 -181.662744) (xy 231.646136 -181.618601)
			(xy 231.61884 -181.569966) (xy 231.598917 -181.517875) (xy 231.586791 -181.463438) (xy 231.58272 -181.407816)
			(xy 229.161848 -181.407816) (xy 229.161848 -182.280814) (xy 250.214382 -182.280814) (xy 250.218453 -182.225192)
			(xy 250.230579 -182.170755) (xy 250.250502 -182.118664) (xy 250.277798 -182.070029) (xy 250.311884 -182.025886)
			(xy 250.352033 -181.987177) (xy 250.397391 -181.954726) (xy 250.446991 -181.929225) (xy 250.499775 -181.911218)
			(xy 250.554618 -181.901088) (xy 250.610352 -181.899051) (xy 250.665789 -181.905151) (xy 250.719746 -181.919257)
			(xy 250.771075 -181.941069) (xy 250.818681 -181.970123) (xy 250.861549 -182.005798) (xy 250.898766 -182.047335)
			(xy 250.929539 -182.093848) (xy 250.953211 -182.144345) (xy 250.969279 -182.197752) (xy 250.977399 -182.252928)
			(xy 250.977908 -182.280814) (xy 250.977399 -182.3087) (xy 250.969279 -182.363876) (xy 250.953211 -182.417283)
			(xy 250.929539 -182.46778) (xy 250.898766 -182.514293) (xy 250.861549 -182.55583) (xy 250.818681 -182.591505)
			(xy 250.771075 -182.620559) (xy 250.719746 -182.642371) (xy 250.665789 -182.656477) (xy 250.610352 -182.662577)
			(xy 250.554618 -182.66054) (xy 250.499775 -182.65041) (xy 250.446991 -182.632403) (xy 250.397391 -182.606902)
			(xy 250.352033 -182.574451) (xy 250.311884 -182.535742) (xy 250.277798 -182.491599) (xy 250.250502 -182.442964)
			(xy 250.230579 -182.390873) (xy 250.218453 -182.336436) (xy 250.214382 -182.280814) (xy 229.161848 -182.280814)
			(xy 229.161848 -182.720234) (xy 236.847378 -182.720234) (xy 236.851449 -182.664612) (xy 236.863575 -182.610175)
			(xy 236.883498 -182.558084) (xy 236.910794 -182.509449) (xy 236.94488 -182.465306) (xy 236.985029 -182.426597)
			(xy 237.030387 -182.394146) (xy 237.079987 -182.368645) (xy 237.132771 -182.350638) (xy 237.187614 -182.340508)
			(xy 237.243348 -182.338471) (xy 237.298785 -182.344571) (xy 237.352742 -182.358677) (xy 237.404071 -182.380489)
			(xy 237.451677 -182.409543) (xy 237.494545 -182.445218) (xy 237.531762 -182.486755) (xy 237.562535 -182.533268)
			(xy 237.586207 -182.583765) (xy 237.602275 -182.637172) (xy 237.610395 -182.692348) (xy 237.610904 -182.720234)
			(xy 237.610395 -182.74812) (xy 237.602275 -182.803296) (xy 237.586207 -182.856703) (xy 237.562535 -182.9072)
			(xy 237.531762 -182.953713) (xy 237.494545 -182.99525) (xy 237.451677 -183.030925) (xy 237.404071 -183.059979)
			(xy 237.352742 -183.081791) (xy 237.298785 -183.095897) (xy 237.243348 -183.101997) (xy 237.187614 -183.09996)
			(xy 237.132771 -183.08983) (xy 237.079987 -183.071823) (xy 237.030387 -183.046322) (xy 236.985029 -183.013871)
			(xy 236.94488 -182.975162) (xy 236.910794 -182.931019) (xy 236.883498 -182.882384) (xy 236.863575 -182.830293)
			(xy 236.851449 -182.775856) (xy 236.847378 -182.720234) (xy 229.161848 -182.720234) (xy 229.161848 -183.306056)
			(xy 230.971235 -183.306056) (xy 230.971235 -183.251544) (xy 230.978994 -183.197586) (xy 230.994353 -183.145282)
			(xy 231.017 -183.095696) (xy 231.046473 -183.049838) (xy 231.082174 -183.008642) (xy 231.123374 -182.972947)
			(xy 231.169235 -182.943478) (xy 231.218823 -182.920837) (xy 231.271129 -182.905484) (xy 231.325088 -182.897732)
			(xy 231.352344 -182.897272) (xy 231.378761 -182.897761) (xy 231.43109 -182.905044) (xy 231.481913 -182.919478)
			(xy 231.530259 -182.940788) (xy 231.575201 -182.968565) (xy 231.61588 -183.002278) (xy 231.63403 -183.021478)
			(xy 231.643343 -183.031183) (xy 231.666024 -183.045634) (xy 231.691691 -183.053665) (xy 231.718563 -183.05472)
			(xy 231.74478 -183.048726) (xy 231.768525 -183.036098) (xy 231.788151 -183.017711) (xy 231.795574 -183.006492)
			(xy 231.810627 -182.983228) (xy 231.846314 -182.940843) (xy 231.887756 -182.904065) (xy 231.934082 -182.873667)
			(xy 231.984316 -182.850289) (xy 232.037404 -182.834421) (xy 232.092228 -182.826398) (xy 232.119932 -182.825898)
			(xy 232.147182 -182.826374) (xy 232.201127 -182.834134) (xy 232.253419 -182.849492) (xy 232.302993 -182.872136)
			(xy 232.34884 -182.901603) (xy 232.390027 -182.937295) (xy 232.425716 -182.978486) (xy 232.45518 -183.024335)
			(xy 232.477819 -183.073911) (xy 232.493172 -183.126204) (xy 232.500928 -183.18015) (xy 232.500928 -183.23465)
			(xy 232.493172 -183.288596) (xy 232.477819 -183.340889) (xy 232.45518 -183.390465) (xy 232.425716 -183.436314)
			(xy 232.390027 -183.477505) (xy 232.34884 -183.513197) (xy 232.302993 -183.542664) (xy 232.253419 -183.565308)
			(xy 232.201127 -183.580666) (xy 232.147182 -183.588426) (xy 232.119932 -183.588914) (xy 232.093514 -183.588446)
			(xy 232.041184 -183.581159) (xy 231.99036 -183.566721) (xy 231.942015 -183.545407) (xy 231.897073 -183.517626)
			(xy 231.856395 -183.483909) (xy 231.838246 -183.464708) (xy 231.828866 -183.455069) (xy 231.806205 -183.440601)
			(xy 231.780552 -183.432554) (xy 231.753688 -183.431486) (xy 231.727477 -183.43747) (xy 231.703738 -183.450092)
			(xy 231.68412 -183.468476) (xy 231.676702 -183.479694) (xy 231.661695 -183.502989) (xy 231.625997 -183.545369)
			(xy 231.584545 -183.582142) (xy 231.538212 -183.612535) (xy 231.487971 -183.635908) (xy 231.434878 -183.651771)
			(xy 231.38005 -183.65979) (xy 231.352344 -183.660288) (xy 231.325088 -183.659868) (xy 231.271129 -183.652116)
			(xy 231.218823 -183.636763) (xy 231.169235 -183.614122) (xy 231.123374 -183.584653) (xy 231.082174 -183.548958)
			(xy 231.046473 -183.507762) (xy 231.017 -183.461904) (xy 230.994353 -183.412318) (xy 230.978994 -183.360014)
			(xy 230.971235 -183.306056) (xy 229.161848 -183.306056) (xy 229.161848 -183.844438) (xy 235.066076 -183.844438)
			(xy 235.070147 -183.788816) (xy 235.082273 -183.734379) (xy 235.102196 -183.682288) (xy 235.129492 -183.633653)
			(xy 235.163578 -183.58951) (xy 235.203727 -183.550801) (xy 235.249085 -183.51835) (xy 235.298685 -183.492849)
			(xy 235.351469 -183.474842) (xy 235.406312 -183.464712) (xy 235.462046 -183.462675) (xy 235.517483 -183.468775)
			(xy 235.57144 -183.482881) (xy 235.622769 -183.504693) (xy 235.670375 -183.533747) (xy 235.713243 -183.569422)
			(xy 235.75046 -183.610959) (xy 235.781233 -183.657472) (xy 235.804905 -183.707969) (xy 235.820973 -183.761376)
			(xy 235.829093 -183.816552) (xy 235.829602 -183.844438) (xy 235.829093 -183.872324) (xy 235.820973 -183.9275)
			(xy 235.804905 -183.980907) (xy 235.781233 -184.031404) (xy 235.75046 -184.077917) (xy 235.713243 -184.119454)
			(xy 235.670375 -184.155129) (xy 235.622769 -184.184183) (xy 235.57144 -184.205995) (xy 235.517483 -184.220101)
			(xy 235.462046 -184.226201) (xy 235.406312 -184.224164) (xy 235.351469 -184.214034) (xy 235.298685 -184.196027)
			(xy 235.249085 -184.170526) (xy 235.203727 -184.138075) (xy 235.163578 -184.099366) (xy 235.129492 -184.055223)
			(xy 235.102196 -184.006588) (xy 235.082273 -183.954497) (xy 235.070147 -183.90006) (xy 235.066076 -183.844438)
			(xy 229.161848 -183.844438) (xy 229.161848 -184.235344) (xy 242.889784 -184.235344) (xy 242.893855 -184.179722)
			(xy 242.905981 -184.125285) (xy 242.925904 -184.073194) (xy 242.9532 -184.024559) (xy 242.987286 -183.980416)
			(xy 243.027435 -183.941707) (xy 243.072793 -183.909256) (xy 243.122393 -183.883755) (xy 243.175177 -183.865748)
			(xy 243.23002 -183.855618) (xy 243.285754 -183.853581) (xy 243.341191 -183.859681) (xy 243.395148 -183.873787)
			(xy 243.446477 -183.895599) (xy 243.494083 -183.924653) (xy 243.536951 -183.960328) (xy 243.574168 -184.001865)
			(xy 243.604941 -184.048378) (xy 243.628613 -184.098875) (xy 243.644681 -184.152282) (xy 243.646476 -184.164478)
			(xy 244.441218 -184.164478) (xy 244.441719 -184.136325) (xy 244.449971 -184.080627) (xy 244.466324 -184.026748)
			(xy 244.490421 -183.975859) (xy 244.521738 -183.929066) (xy 244.559595 -183.887386) (xy 244.603169 -183.851725)
			(xy 244.651512 -183.822859) (xy 244.703575 -183.801414) (xy 244.730778 -183.794146) (xy 244.74381 -183.790438)
			(xy 244.767417 -183.777159) (xy 244.786701 -183.75814) (xy 244.800306 -183.734719) (xy 244.807273 -183.708545)
			(xy 244.807113 -183.681461) (xy 244.799837 -183.655371) (xy 244.793262 -183.643524) (xy 244.780436 -183.621266)
			(xy 244.760219 -183.574041) (xy 244.746523 -183.52453) (xy 244.739596 -183.473629) (xy 244.73916 -183.447944)
			(xy 244.73916 -183.447436) (xy 244.739646 -183.420185) (xy 244.747402 -183.366237) (xy 244.762757 -183.313942)
			(xy 244.785399 -183.264365) (xy 244.814865 -183.218515) (xy 244.850556 -183.177324) (xy 244.891747 -183.141633)
			(xy 244.937597 -183.112167) (xy 244.987174 -183.089525) (xy 245.039469 -183.07417) (xy 245.093417 -183.066414)
			(xy 245.147919 -183.066414) (xy 245.201867 -183.07417) (xy 245.254162 -183.089525) (xy 245.303739 -183.112167)
			(xy 245.349589 -183.141633) (xy 245.39078 -183.177324) (xy 245.426471 -183.218515) (xy 245.455937 -183.264365)
			(xy 245.478579 -183.313942) (xy 245.493934 -183.366237) (xy 245.50169 -183.420185) (xy 245.502176 -183.447436)
			(xy 245.501692 -183.47559) (xy 245.494303 -183.525451) (xy 245.640591 -183.525451) (xy 245.640591 -183.470949)
			(xy 245.648348 -183.417003) (xy 245.663703 -183.36471) (xy 245.686343 -183.315134) (xy 245.715809 -183.269285)
			(xy 245.7515 -183.228096) (xy 245.79269 -183.192406) (xy 245.838539 -183.16294) (xy 245.888115 -183.1403)
			(xy 245.940409 -183.124946) (xy 245.994355 -183.117191) (xy 246.021606 -183.116728) (xy 246.047005 -183.117125)
			(xy 246.097355 -183.123868) (xy 246.146364 -183.137233) (xy 246.193166 -183.156984) (xy 246.236933 -183.182771)
			(xy 246.27689 -183.214139) (xy 246.29491 -183.232044) (xy 246.30126 -183.238648) (xy 246.318024 -183.246522)
			(xy 246.403114 -183.25338) (xy 246.42064 -183.248554) (xy 246.428006 -183.242966) (xy 246.452759 -183.225404)
			(xy 246.506672 -183.197538) (xy 246.564312 -183.178543) (xy 246.62423 -183.168899) (xy 246.654574 -183.16829)
			(xy 246.681863 -183.168741) (xy 246.735885 -183.176517) (xy 246.788246 -183.191913) (xy 246.837879 -183.214616)
			(xy 246.861076 -183.228996) (xy 246.869756 -183.234066) (xy 246.88953 -183.237602) (xy 246.89943 -183.235854)
			(xy 246.979694 -183.218328) (xy 246.996204 -183.206898) (xy 247.001538 -183.198516) (xy 247.01666 -183.175784)
			(xy 247.052362 -183.134479) (xy 247.093585 -183.098683) (xy 247.139489 -183.069126) (xy 247.189135 -183.046412)
			(xy 247.241512 -183.031004) (xy 247.29555 -183.023217) (xy 247.322848 -183.022748) (xy 247.350094 -183.023325)
			(xy 247.40403 -183.031087) (xy 247.456313 -183.046444) (xy 247.505878 -183.069085) (xy 247.551717 -183.098549)
			(xy 247.592897 -183.134237) (xy 247.628579 -183.175421) (xy 247.658038 -183.221264) (xy 247.680673 -183.270832)
			(xy 247.696024 -183.323117) (xy 247.703778 -183.377054) (xy 247.703778 -183.431546) (xy 247.696024 -183.485483)
			(xy 247.680673 -183.537768) (xy 247.658038 -183.587336) (xy 247.628579 -183.633179) (xy 247.592897 -183.674363)
			(xy 247.551717 -183.710051) (xy 247.505878 -183.739515) (xy 247.456313 -183.762156) (xy 247.40403 -183.777513)
			(xy 247.350094 -183.785275) (xy 247.322848 -183.785764) (xy 247.295559 -183.785309) (xy 247.241537 -183.777536)
			(xy 247.189175 -183.762141) (xy 247.139543 -183.739439) (xy 247.116346 -183.725058) (xy 247.107661 -183.719997)
			(xy 247.087891 -183.716457) (xy 247.077992 -183.7182) (xy 246.997728 -183.735726) (xy 246.981218 -183.747156)
			(xy 246.975884 -183.755538) (xy 246.960732 -183.778249) (xy 246.925037 -183.819557) (xy 246.88382 -183.855356)
			(xy 246.837921 -183.884916) (xy 246.788279 -183.907633) (xy 246.735906 -183.923045) (xy 246.681871 -183.930835)
			(xy 246.654574 -183.931306) (xy 246.629175 -183.930911) (xy 246.578825 -183.924167) (xy 246.529817 -183.910801)
			(xy 246.483015 -183.891049) (xy 246.439248 -183.865262) (xy 246.399291 -183.833894) (xy 246.38127 -183.81599)
			(xy 246.37492 -183.809386) (xy 246.358156 -183.801512) (xy 246.273066 -183.794654) (xy 246.25554 -183.79948)
			(xy 246.248174 -183.805068) (xy 246.22343 -183.822643) (xy 246.169513 -183.850505) (xy 246.111871 -183.869496)
			(xy 246.051951 -183.879136) (xy 246.021606 -183.879744) (xy 245.994355 -183.879209) (xy 245.940409 -183.871454)
			(xy 245.888115 -183.8561) (xy 245.838539 -183.83346) (xy 245.79269 -183.803994) (xy 245.7515 -183.768304)
			(xy 245.715809 -183.727115) (xy 245.686343 -183.681266) (xy 245.663703 -183.63169) (xy 245.648348 -183.579397)
			(xy 245.640591 -183.525451) (xy 245.494303 -183.525451) (xy 245.493438 -183.531289) (xy 245.477083 -183.585168)
			(xy 245.452984 -183.636058) (xy 245.421664 -183.682851) (xy 245.383805 -183.724531) (xy 245.34023 -183.760191)
			(xy 245.291884 -183.789057) (xy 245.23982 -183.8105) (xy 245.212616 -183.817768) (xy 245.199577 -183.821453)
			(xy 245.175968 -183.834736) (xy 245.156683 -183.85376) (xy 245.143079 -183.877184) (xy 245.136113 -183.903362)
			(xy 245.136275 -183.93045) (xy 245.143554 -183.956542) (xy 245.150132 -183.96839) (xy 245.162963 -183.990645)
			(xy 245.183179 -184.037871) (xy 245.196874 -184.087383) (xy 245.203799 -184.138285) (xy 245.204234 -184.16397)
			(xy 245.204234 -184.164478) (xy 245.203748 -184.191729) (xy 245.195992 -184.245677) (xy 245.180637 -184.297972)
			(xy 245.157995 -184.347549) (xy 245.128529 -184.393399) (xy 245.092838 -184.43459) (xy 245.051647 -184.470281)
			(xy 245.005797 -184.499747) (xy 244.95622 -184.522389) (xy 244.903925 -184.537744) (xy 244.849977 -184.5455)
			(xy 244.795475 -184.5455) (xy 244.741527 -184.537744) (xy 244.689232 -184.522389) (xy 244.639655 -184.499747)
			(xy 244.593805 -184.470281) (xy 244.552614 -184.43459) (xy 244.516923 -184.393399) (xy 244.487457 -184.347549)
			(xy 244.464815 -184.297972) (xy 244.44946 -184.245677) (xy 244.441704 -184.191729) (xy 244.441218 -184.164478)
			(xy 243.646476 -184.164478) (xy 243.652801 -184.207458) (xy 243.65331 -184.235344) (xy 243.652801 -184.26323)
			(xy 243.644681 -184.318406) (xy 243.628613 -184.371813) (xy 243.604941 -184.42231) (xy 243.574168 -184.468823)
			(xy 243.536951 -184.51036) (xy 243.494083 -184.546035) (xy 243.446477 -184.575089) (xy 243.395148 -184.596901)
			(xy 243.341191 -184.611007) (xy 243.285754 -184.617107) (xy 243.23002 -184.61507) (xy 243.175177 -184.60494)
			(xy 243.122393 -184.586933) (xy 243.072793 -184.561432) (xy 243.027435 -184.528981) (xy 242.987286 -184.490272)
			(xy 242.9532 -184.446129) (xy 242.925904 -184.397494) (xy 242.905981 -184.345403) (xy 242.893855 -184.290966)
			(xy 242.889784 -184.235344) (xy 229.161848 -184.235344) (xy 229.161848 -184.7723) (xy 237.368586 -184.7723)
			(xy 237.372657 -184.716678) (xy 237.384783 -184.662241) (xy 237.404706 -184.61015) (xy 237.432002 -184.561515)
			(xy 237.466088 -184.517372) (xy 237.506237 -184.478663) (xy 237.551595 -184.446212) (xy 237.601195 -184.420711)
			(xy 237.653979 -184.402704) (xy 237.708822 -184.392574) (xy 237.764556 -184.390537) (xy 237.819993 -184.396637)
			(xy 237.87395 -184.410743) (xy 237.925279 -184.432555) (xy 237.972885 -184.461609) (xy 238.015753 -184.497284)
			(xy 238.05297 -184.538821) (xy 238.083743 -184.585334) (xy 238.107415 -184.635831) (xy 238.123483 -184.689238)
			(xy 238.131603 -184.744414) (xy 238.132112 -184.7723) (xy 238.131603 -184.800186) (xy 238.123483 -184.855362)
			(xy 238.107415 -184.908769) (xy 238.083743 -184.959266) (xy 238.05297 -185.005779) (xy 238.015753 -185.047316)
			(xy 237.972885 -185.082991) (xy 237.925279 -185.112045) (xy 237.87395 -185.133857) (xy 237.819993 -185.147963)
			(xy 237.764556 -185.154063) (xy 237.708822 -185.152026) (xy 237.653979 -185.141896) (xy 237.601195 -185.123889)
			(xy 237.551595 -185.098388) (xy 237.506237 -185.065937) (xy 237.466088 -185.027228) (xy 237.432002 -184.983085)
			(xy 237.404706 -184.93445) (xy 237.384783 -184.882359) (xy 237.372657 -184.827922) (xy 237.368586 -184.7723)
			(xy 229.161848 -184.7723) (xy 229.161848 -185.448194) (xy 241.210336 -185.448194) (xy 241.214407 -185.392572)
			(xy 241.226533 -185.338135) (xy 241.246456 -185.286044) (xy 241.273752 -185.237409) (xy 241.307838 -185.193266)
			(xy 241.347987 -185.154557) (xy 241.393345 -185.122106) (xy 241.442945 -185.096605) (xy 241.495729 -185.078598)
			(xy 241.550572 -185.068468) (xy 241.606306 -185.066431) (xy 241.661743 -185.072531) (xy 241.7157 -185.086637)
			(xy 241.767029 -185.108449) (xy 241.814635 -185.137503) (xy 241.857503 -185.173178) (xy 241.89472 -185.214715)
			(xy 241.925493 -185.261228) (xy 241.949165 -185.311725) (xy 241.965233 -185.365132) (xy 241.970429 -185.400442)
			(xy 246.211088 -185.400442) (xy 246.215159 -185.34482) (xy 246.227285 -185.290383) (xy 246.247208 -185.238292)
			(xy 246.274504 -185.189657) (xy 246.30859 -185.145514) (xy 246.348739 -185.106805) (xy 246.394097 -185.074354)
			(xy 246.443697 -185.048853) (xy 246.496481 -185.030846) (xy 246.551324 -185.020716) (xy 246.607058 -185.018679)
			(xy 246.662495 -185.024779) (xy 246.716452 -185.038885) (xy 246.767781 -185.060697) (xy 246.815387 -185.089751)
			(xy 246.858255 -185.125426) (xy 246.895472 -185.166963) (xy 246.926245 -185.213476) (xy 246.949917 -185.263973)
			(xy 246.965985 -185.31738) (xy 246.974105 -185.372556) (xy 246.974614 -185.400442) (xy 246.974105 -185.428328)
			(xy 246.965985 -185.483504) (xy 246.949917 -185.536911) (xy 246.926245 -185.587408) (xy 246.908279 -185.614564)
			(xy 248.11939 -185.614564) (xy 248.123461 -185.558942) (xy 248.135587 -185.504505) (xy 248.15551 -185.452414)
			(xy 248.182806 -185.403779) (xy 248.216892 -185.359636) (xy 248.257041 -185.320927) (xy 248.302399 -185.288476)
			(xy 248.351999 -185.262975) (xy 248.404783 -185.244968) (xy 248.459626 -185.234838) (xy 248.51536 -185.232801)
			(xy 248.570797 -185.238901) (xy 248.624754 -185.253007) (xy 248.676083 -185.274819) (xy 248.723689 -185.303873)
			(xy 248.766557 -185.339548) (xy 248.803774 -185.381085) (xy 248.834547 -185.427598) (xy 248.858219 -185.478095)
			(xy 248.874287 -185.531502) (xy 248.882407 -185.586678) (xy 248.882916 -185.614564) (xy 248.882407 -185.64245)
			(xy 248.874287 -185.697626) (xy 248.858219 -185.751033) (xy 248.834547 -185.80153) (xy 248.803774 -185.848043)
			(xy 248.766557 -185.88958) (xy 248.723689 -185.925255) (xy 248.676083 -185.954309) (xy 248.624754 -185.976121)
			(xy 248.570797 -185.990227) (xy 248.51536 -185.996327) (xy 248.459626 -185.99429) (xy 248.404783 -185.98416)
			(xy 248.351999 -185.966153) (xy 248.302399 -185.940652) (xy 248.257041 -185.908201) (xy 248.216892 -185.869492)
			(xy 248.182806 -185.825349) (xy 248.15551 -185.776714) (xy 248.135587 -185.724623) (xy 248.123461 -185.670186)
			(xy 248.11939 -185.614564) (xy 246.908279 -185.614564) (xy 246.895472 -185.633921) (xy 246.858255 -185.675458)
			(xy 246.815387 -185.711133) (xy 246.767781 -185.740187) (xy 246.716452 -185.761999) (xy 246.662495 -185.776105)
			(xy 246.607058 -185.782205) (xy 246.551324 -185.780168) (xy 246.496481 -185.770038) (xy 246.443697 -185.752031)
			(xy 246.394097 -185.72653) (xy 246.348739 -185.694079) (xy 246.30859 -185.65537) (xy 246.274504 -185.611227)
			(xy 246.247208 -185.562592) (xy 246.227285 -185.510501) (xy 246.215159 -185.456064) (xy 246.211088 -185.400442)
			(xy 241.970429 -185.400442) (xy 241.973353 -185.420308) (xy 241.973862 -185.448194) (xy 241.973353 -185.47608)
			(xy 241.965233 -185.531256) (xy 241.949165 -185.584663) (xy 241.925493 -185.63516) (xy 241.89472 -185.681673)
			(xy 241.857503 -185.72321) (xy 241.814635 -185.758885) (xy 241.767029 -185.787939) (xy 241.7157 -185.809751)
			(xy 241.661743 -185.823857) (xy 241.606306 -185.829957) (xy 241.550572 -185.82792) (xy 241.495729 -185.81779)
			(xy 241.442945 -185.799783) (xy 241.393345 -185.774282) (xy 241.347987 -185.741831) (xy 241.307838 -185.703122)
			(xy 241.273752 -185.658979) (xy 241.246456 -185.610344) (xy 241.226533 -185.558253) (xy 241.214407 -185.503816)
			(xy 241.210336 -185.448194) (xy 229.161848 -185.448194) (xy 229.161848 -186.481212) (xy 242.429282 -186.481212)
			(xy 242.433353 -186.42559) (xy 242.445479 -186.371153) (xy 242.465402 -186.319062) (xy 242.492698 -186.270427)
			(xy 242.526784 -186.226284) (xy 242.566933 -186.187575) (xy 242.612291 -186.155124) (xy 242.661891 -186.129623)
			(xy 242.714675 -186.111616) (xy 242.769518 -186.101486) (xy 242.825252 -186.099449) (xy 242.880689 -186.105549)
			(xy 242.934646 -186.119655) (xy 242.985975 -186.141467) (xy 243.033581 -186.170521) (xy 243.076449 -186.206196)
			(xy 243.113666 -186.247733) (xy 243.144439 -186.294246) (xy 243.168111 -186.344743) (xy 243.184179 -186.39815)
			(xy 243.192299 -186.453326) (xy 243.192808 -186.481212) (xy 243.445282 -186.481212) (xy 243.449353 -186.42559)
			(xy 243.461479 -186.371153) (xy 243.481402 -186.319062) (xy 243.508698 -186.270427) (xy 243.542784 -186.226284)
			(xy 243.582933 -186.187575) (xy 243.628291 -186.155124) (xy 243.677891 -186.129623) (xy 243.730675 -186.111616)
			(xy 243.785518 -186.101486) (xy 243.841252 -186.099449) (xy 243.896689 -186.105549) (xy 243.950646 -186.119655)
			(xy 244.001975 -186.141467) (xy 244.049581 -186.170521) (xy 244.092449 -186.206196) (xy 244.129666 -186.247733)
			(xy 244.160439 -186.294246) (xy 244.184111 -186.344743) (xy 244.200179 -186.39815) (xy 244.208299 -186.453326)
			(xy 244.208808 -186.481212) (xy 244.461282 -186.481212) (xy 244.465353 -186.42559) (xy 244.477479 -186.371153)
			(xy 244.497402 -186.319062) (xy 244.524698 -186.270427) (xy 244.558784 -186.226284) (xy 244.598933 -186.187575)
			(xy 244.644291 -186.155124) (xy 244.693891 -186.129623) (xy 244.746675 -186.111616) (xy 244.801518 -186.101486)
			(xy 244.857252 -186.099449) (xy 244.912689 -186.105549) (xy 244.966646 -186.119655) (xy 245.017975 -186.141467)
			(xy 245.065581 -186.170521) (xy 245.108449 -186.206196) (xy 245.145666 -186.247733) (xy 245.176439 -186.294246)
			(xy 245.200111 -186.344743) (xy 245.216179 -186.39815) (xy 245.224299 -186.453326) (xy 245.224808 -186.481212)
			(xy 245.224299 -186.509098) (xy 245.216179 -186.564274) (xy 245.200111 -186.617681) (xy 245.176439 -186.668178)
			(xy 245.145666 -186.714691) (xy 245.108449 -186.756228) (xy 245.065581 -186.791903) (xy 245.017975 -186.820957)
			(xy 244.966646 -186.842769) (xy 244.912689 -186.856875) (xy 244.857252 -186.862975) (xy 244.801518 -186.860938)
			(xy 244.746675 -186.850808) (xy 244.693891 -186.832801) (xy 244.644291 -186.8073) (xy 244.598933 -186.774849)
			(xy 244.558784 -186.73614) (xy 244.524698 -186.691997) (xy 244.497402 -186.643362) (xy 244.477479 -186.591271)
			(xy 244.465353 -186.536834) (xy 244.461282 -186.481212) (xy 244.208808 -186.481212) (xy 244.208299 -186.509098)
			(xy 244.200179 -186.564274) (xy 244.184111 -186.617681) (xy 244.160439 -186.668178) (xy 244.129666 -186.714691)
			(xy 244.092449 -186.756228) (xy 244.049581 -186.791903) (xy 244.001975 -186.820957) (xy 243.950646 -186.842769)
			(xy 243.896689 -186.856875) (xy 243.841252 -186.862975) (xy 243.785518 -186.860938) (xy 243.730675 -186.850808)
			(xy 243.677891 -186.832801) (xy 243.628291 -186.8073) (xy 243.582933 -186.774849) (xy 243.542784 -186.73614)
			(xy 243.508698 -186.691997) (xy 243.481402 -186.643362) (xy 243.461479 -186.591271) (xy 243.449353 -186.536834)
			(xy 243.445282 -186.481212) (xy 243.192808 -186.481212) (xy 243.192299 -186.509098) (xy 243.184179 -186.564274)
			(xy 243.168111 -186.617681) (xy 243.144439 -186.668178) (xy 243.113666 -186.714691) (xy 243.076449 -186.756228)
			(xy 243.033581 -186.791903) (xy 242.985975 -186.820957) (xy 242.934646 -186.842769) (xy 242.880689 -186.856875)
			(xy 242.825252 -186.862975) (xy 242.769518 -186.860938) (xy 242.714675 -186.850808) (xy 242.661891 -186.832801)
			(xy 242.612291 -186.8073) (xy 242.566933 -186.774849) (xy 242.526784 -186.73614) (xy 242.492698 -186.691997)
			(xy 242.465402 -186.643362) (xy 242.445479 -186.591271) (xy 242.433353 -186.536834) (xy 242.429282 -186.481212)
			(xy 229.161848 -186.481212) (xy 229.161848 -187.41136) (xy 229.161316 -187.444649) (xy 229.152602 -187.510656)
			(xy 229.135344 -187.57496) (xy 229.109838 -187.636459) (xy 229.07652 -187.694102) (xy 229.03596 -187.746901)
			(xy 229.01275 -187.77077) (xy 227.764848 -189.018672) (xy 242.843048 -189.018672) (xy 242.847119 -188.96305)
			(xy 242.859245 -188.908613) (xy 242.879168 -188.856522) (xy 242.906464 -188.807887) (xy 242.94055 -188.763744)
			(xy 242.980699 -188.725035) (xy 243.026057 -188.692584) (xy 243.075657 -188.667083) (xy 243.128441 -188.649076)
			(xy 243.183284 -188.638946) (xy 243.239018 -188.636909) (xy 243.294455 -188.643009) (xy 243.348412 -188.657115)
			(xy 243.399741 -188.678927) (xy 243.447347 -188.707981) (xy 243.490215 -188.743656) (xy 243.527432 -188.785193)
			(xy 243.558205 -188.831706) (xy 243.581877 -188.882203) (xy 243.597945 -188.93561) (xy 243.606065 -188.990786)
			(xy 243.606574 -189.018672) (xy 243.606065 -189.046558) (xy 243.597945 -189.101734) (xy 243.581877 -189.155141)
			(xy 243.558205 -189.205638) (xy 243.527432 -189.252151) (xy 243.506542 -189.275466) (xy 249.014486 -189.275466)
			(xy 249.018557 -189.219844) (xy 249.030683 -189.165407) (xy 249.050606 -189.113316) (xy 249.077902 -189.064681)
			(xy 249.111988 -189.020538) (xy 249.152137 -188.981829) (xy 249.197495 -188.949378) (xy 249.247095 -188.923877)
			(xy 249.299879 -188.90587) (xy 249.354722 -188.89574) (xy 249.410456 -188.893703) (xy 249.465893 -188.899803)
			(xy 249.51985 -188.913909) (xy 249.571179 -188.935721) (xy 249.618785 -188.964775) (xy 249.661653 -189.00045)
			(xy 249.69887 -189.041987) (xy 249.729643 -189.0885) (xy 249.753315 -189.138997) (xy 249.769383 -189.192404)
			(xy 249.777503 -189.24758) (xy 249.778012 -189.275466) (xy 249.777503 -189.303352) (xy 249.769383 -189.358528)
			(xy 249.753315 -189.411935) (xy 249.743823 -189.432184) (xy 250.433076 -189.432184) (xy 250.437147 -189.376562)
			(xy 250.449273 -189.322125) (xy 250.469196 -189.270034) (xy 250.496492 -189.221399) (xy 250.530578 -189.177256)
			(xy 250.570727 -189.138547) (xy 250.616085 -189.106096) (xy 250.665685 -189.080595) (xy 250.718469 -189.062588)
			(xy 250.773312 -189.052458) (xy 250.829046 -189.050421) (xy 250.884483 -189.056521) (xy 250.93844 -189.070627)
			(xy 250.989769 -189.092439) (xy 251.037375 -189.121493) (xy 251.080243 -189.157168) (xy 251.11746 -189.198705)
			(xy 251.148233 -189.245218) (xy 251.171905 -189.295715) (xy 251.187973 -189.349122) (xy 251.196093 -189.404298)
			(xy 251.196602 -189.432184) (xy 251.196093 -189.46007) (xy 251.187973 -189.515246) (xy 251.171905 -189.568653)
			(xy 251.148233 -189.61915) (xy 251.11746 -189.665663) (xy 251.080243 -189.7072) (xy 251.037375 -189.742875)
			(xy 250.989769 -189.771929) (xy 250.93844 -189.793741) (xy 250.884483 -189.807847) (xy 250.829046 -189.813947)
			(xy 250.773312 -189.81191) (xy 250.718469 -189.80178) (xy 250.665685 -189.783773) (xy 250.616085 -189.758272)
			(xy 250.570727 -189.725821) (xy 250.530578 -189.687112) (xy 250.496492 -189.642969) (xy 250.469196 -189.594334)
			(xy 250.449273 -189.542243) (xy 250.437147 -189.487806) (xy 250.433076 -189.432184) (xy 249.743823 -189.432184)
			(xy 249.729643 -189.462432) (xy 249.69887 -189.508945) (xy 249.661653 -189.550482) (xy 249.618785 -189.586157)
			(xy 249.571179 -189.615211) (xy 249.51985 -189.637023) (xy 249.465893 -189.651129) (xy 249.410456 -189.657229)
			(xy 249.354722 -189.655192) (xy 249.299879 -189.645062) (xy 249.247095 -189.627055) (xy 249.197495 -189.601554)
			(xy 249.152137 -189.569103) (xy 249.111988 -189.530394) (xy 249.077902 -189.486251) (xy 249.050606 -189.437616)
			(xy 249.030683 -189.385525) (xy 249.018557 -189.331088) (xy 249.014486 -189.275466) (xy 243.506542 -189.275466)
			(xy 243.490215 -189.293688) (xy 243.447347 -189.329363) (xy 243.399741 -189.358417) (xy 243.348412 -189.380229)
			(xy 243.294455 -189.394335) (xy 243.239018 -189.400435) (xy 243.183284 -189.398398) (xy 243.128441 -189.388268)
			(xy 243.075657 -189.370261) (xy 243.026057 -189.34476) (xy 242.980699 -189.312309) (xy 242.94055 -189.2736)
			(xy 242.906464 -189.229457) (xy 242.879168 -189.180822) (xy 242.859245 -189.128731) (xy 242.847119 -189.074294)
			(xy 242.843048 -189.018672) (xy 227.764848 -189.018672) (xy 226.9744 -189.80912) (xy 246.874282 -189.80912)
			(xy 246.878353 -189.753498) (xy 246.890479 -189.699061) (xy 246.910402 -189.64697) (xy 246.937698 -189.598335)
			(xy 246.971784 -189.554192) (xy 247.011933 -189.515483) (xy 247.057291 -189.483032) (xy 247.106891 -189.457531)
			(xy 247.159675 -189.439524) (xy 247.214518 -189.429394) (xy 247.270252 -189.427357) (xy 247.325689 -189.433457)
			(xy 247.379646 -189.447563) (xy 247.430975 -189.469375) (xy 247.478581 -189.498429) (xy 247.521449 -189.534104)
			(xy 247.558666 -189.575641) (xy 247.589439 -189.622154) (xy 247.613111 -189.672651) (xy 247.629179 -189.726058)
			(xy 247.637299 -189.781234) (xy 247.637808 -189.80912) (xy 247.637299 -189.837006) (xy 247.629179 -189.892182)
			(xy 247.613111 -189.945589) (xy 247.589439 -189.996086) (xy 247.558666 -190.042599) (xy 247.521449 -190.084136)
			(xy 247.478581 -190.119811) (xy 247.430975 -190.148865) (xy 247.379646 -190.170677) (xy 247.325689 -190.184783)
			(xy 247.270252 -190.190883) (xy 247.214518 -190.188846) (xy 247.159675 -190.178716) (xy 247.106891 -190.160709)
			(xy 247.057291 -190.135208) (xy 247.011933 -190.102757) (xy 246.971784 -190.064048) (xy 246.937698 -190.019905)
			(xy 246.910402 -189.97127) (xy 246.890479 -189.919179) (xy 246.878353 -189.864742) (xy 246.874282 -189.80912)
			(xy 226.9744 -189.80912) (xy 226.765612 -190.017908) (xy 226.762089 -190.021637) (xy 226.756456 -190.03021)
			(xy 226.754436 -190.034926) (xy 226.75088 -190.043562) (xy 226.75088 -193.80835) (xy 241.89258 -193.80835)
			(xy 241.896651 -193.752728) (xy 241.908777 -193.698291) (xy 241.9287 -193.6462) (xy 241.955996 -193.597565)
			(xy 241.990082 -193.553422) (xy 242.030231 -193.514713) (xy 242.075589 -193.482262) (xy 242.125189 -193.456761)
			(xy 242.177973 -193.438754) (xy 242.232816 -193.428624) (xy 242.28855 -193.426587) (xy 242.343987 -193.432687)
			(xy 242.397944 -193.446793) (xy 242.449273 -193.468605) (xy 242.496879 -193.497659) (xy 242.539747 -193.533334)
			(xy 242.576964 -193.574871) (xy 242.607737 -193.621384) (xy 242.631409 -193.671881) (xy 242.647477 -193.725288)
			(xy 242.655597 -193.780464) (xy 242.656106 -193.80835) (xy 242.655597 -193.836236) (xy 242.647477 -193.891412)
			(xy 242.631409 -193.944819) (xy 242.630847 -193.946018) (xy 244.977664 -193.946018) (xy 244.981735 -193.890396)
			(xy 244.993861 -193.835959) (xy 245.013784 -193.783868) (xy 245.04108 -193.735233) (xy 245.075166 -193.69109)
			(xy 245.115315 -193.652381) (xy 245.160673 -193.61993) (xy 245.210273 -193.594429) (xy 245.263057 -193.576422)
			(xy 245.3179 -193.566292) (xy 245.373634 -193.564255) (xy 245.429071 -193.570355) (xy 245.483028 -193.584461)
			(xy 245.534357 -193.606273) (xy 245.581963 -193.635327) (xy 245.624831 -193.671002) (xy 245.662048 -193.712539)
			(xy 245.692821 -193.759052) (xy 245.716493 -193.809549) (xy 245.732561 -193.862956) (xy 245.740681 -193.918132)
			(xy 245.74119 -193.946018) (xy 245.740681 -193.973904) (xy 245.732561 -194.02908) (xy 245.716493 -194.082487)
			(xy 245.711883 -194.092322) (xy 250.664216 -194.092322) (xy 250.668287 -194.0367) (xy 250.680413 -193.982263)
			(xy 250.700336 -193.930172) (xy 250.727632 -193.881537) (xy 250.761718 -193.837394) (xy 250.801867 -193.798685)
			(xy 250.847225 -193.766234) (xy 250.896825 -193.740733) (xy 250.949609 -193.722726) (xy 251.004452 -193.712596)
			(xy 251.060186 -193.710559) (xy 251.115623 -193.716659) (xy 251.16958 -193.730765) (xy 251.220909 -193.752577)
			(xy 251.268515 -193.781631) (xy 251.311383 -193.817306) (xy 251.3486 -193.858843) (xy 251.379373 -193.905356)
			(xy 251.403045 -193.955853) (xy 251.419113 -194.00926) (xy 251.427233 -194.064436) (xy 251.427742 -194.092322)
			(xy 251.427233 -194.120208) (xy 251.419113 -194.175384) (xy 251.403045 -194.228791) (xy 251.379373 -194.279288)
			(xy 251.3486 -194.325801) (xy 251.311383 -194.367338) (xy 251.268515 -194.403013) (xy 251.220909 -194.432067)
			(xy 251.16958 -194.453879) (xy 251.115623 -194.467985) (xy 251.060186 -194.474085) (xy 251.004452 -194.472048)
			(xy 250.949609 -194.461918) (xy 250.896825 -194.443911) (xy 250.847225 -194.41841) (xy 250.801867 -194.385959)
			(xy 250.761718 -194.34725) (xy 250.727632 -194.303107) (xy 250.700336 -194.254472) (xy 250.680413 -194.202381)
			(xy 250.668287 -194.147944) (xy 250.664216 -194.092322) (xy 245.711883 -194.092322) (xy 245.692821 -194.132984)
			(xy 245.662048 -194.179497) (xy 245.624831 -194.221034) (xy 245.581963 -194.256709) (xy 245.534357 -194.285763)
			(xy 245.483028 -194.307575) (xy 245.429071 -194.321681) (xy 245.373634 -194.327781) (xy 245.3179 -194.325744)
			(xy 245.263057 -194.315614) (xy 245.210273 -194.297607) (xy 245.160673 -194.272106) (xy 245.115315 -194.239655)
			(xy 245.075166 -194.200946) (xy 245.04108 -194.156803) (xy 245.013784 -194.108168) (xy 244.993861 -194.056077)
			(xy 244.981735 -194.00164) (xy 244.977664 -193.946018) (xy 242.630847 -193.946018) (xy 242.607737 -193.995316)
			(xy 242.576964 -194.041829) (xy 242.539747 -194.083366) (xy 242.496879 -194.119041) (xy 242.449273 -194.148095)
			(xy 242.397944 -194.169907) (xy 242.343987 -194.184013) (xy 242.28855 -194.190113) (xy 242.232816 -194.188076)
			(xy 242.177973 -194.177946) (xy 242.125189 -194.159939) (xy 242.075589 -194.134438) (xy 242.030231 -194.101987)
			(xy 241.990082 -194.063278) (xy 241.955996 -194.019135) (xy 241.9287 -193.9705) (xy 241.908777 -193.918409)
			(xy 241.896651 -193.863972) (xy 241.89258 -193.80835) (xy 226.75088 -193.80835) (xy 226.75088 -194.474338)
			(xy 249.499626 -194.474338) (xy 249.503697 -194.418716) (xy 249.515823 -194.364279) (xy 249.535746 -194.312188)
			(xy 249.563042 -194.263553) (xy 249.597128 -194.21941) (xy 249.637277 -194.180701) (xy 249.682635 -194.14825)
			(xy 249.732235 -194.122749) (xy 249.785019 -194.104742) (xy 249.839862 -194.094612) (xy 249.895596 -194.092575)
			(xy 249.951033 -194.098675) (xy 250.00499 -194.112781) (xy 250.056319 -194.134593) (xy 250.103925 -194.163647)
			(xy 250.146793 -194.199322) (xy 250.18401 -194.240859) (xy 250.214783 -194.287372) (xy 250.238455 -194.337869)
			(xy 250.254523 -194.391276) (xy 250.262643 -194.446452) (xy 250.263152 -194.474338) (xy 250.262643 -194.502224)
			(xy 250.254523 -194.5574) (xy 250.238455 -194.610807) (xy 250.214783 -194.661304) (xy 250.18401 -194.707817)
			(xy 250.146793 -194.749354) (xy 250.103925 -194.785029) (xy 250.056319 -194.814083) (xy 250.00499 -194.835895)
			(xy 249.951033 -194.850001) (xy 249.895596 -194.856101) (xy 249.839862 -194.854064) (xy 249.785019 -194.843934)
			(xy 249.732235 -194.825927) (xy 249.682635 -194.800426) (xy 249.637277 -194.767975) (xy 249.597128 -194.729266)
			(xy 249.563042 -194.685123) (xy 249.535746 -194.636488) (xy 249.515823 -194.584397) (xy 249.503697 -194.52996)
			(xy 249.499626 -194.474338) (xy 226.75088 -194.474338) (xy 226.75088 -195.287646) (xy 226.750334 -195.320923)
			(xy 226.741644 -195.386909) (xy 226.72442 -195.451196) (xy 226.698955 -195.512687) (xy 226.665686 -195.57033)
			(xy 226.62518 -195.623139) (xy 226.602036 -195.647056) (xy 226.592893 -195.6562) (xy 242.4463 -195.6562)
			(xy 242.450371 -195.600578) (xy 242.462497 -195.546141) (xy 242.48242 -195.49405) (xy 242.509716 -195.445415)
			(xy 242.543802 -195.401272) (xy 242.583951 -195.362563) (xy 242.629309 -195.330112) (xy 242.678909 -195.304611)
			(xy 242.731693 -195.286604) (xy 242.786536 -195.276474) (xy 242.84227 -195.274437) (xy 242.897707 -195.280537)
			(xy 242.951664 -195.294643) (xy 243.002993 -195.316455) (xy 243.050599 -195.345509) (xy 243.093467 -195.381184)
			(xy 243.130684 -195.422721) (xy 243.161457 -195.469234) (xy 243.185129 -195.519731) (xy 243.201197 -195.573138)
			(xy 243.209317 -195.628314) (xy 243.209826 -195.6562) (xy 243.209317 -195.684086) (xy 243.201197 -195.739262)
			(xy 243.185129 -195.792669) (xy 243.161457 -195.843166) (xy 243.130684 -195.889679) (xy 243.093467 -195.931216)
			(xy 243.050599 -195.966891) (xy 243.002993 -195.995945) (xy 242.951664 -196.017757) (xy 242.897707 -196.031863)
			(xy 242.84227 -196.037963) (xy 242.786536 -196.035926) (xy 242.731693 -196.025796) (xy 242.678909 -196.007789)
			(xy 242.629309 -195.982288) (xy 242.583951 -195.949837) (xy 242.543802 -195.911128) (xy 242.509716 -195.866985)
			(xy 242.48242 -195.81835) (xy 242.462497 -195.766259) (xy 242.450371 -195.711822) (xy 242.4463 -195.6562)
			(xy 226.592893 -195.6562) (xy 225.651964 -196.59727) (xy 250.567442 -196.59727) (xy 250.571513 -196.541648)
			(xy 250.583639 -196.487211) (xy 250.603562 -196.43512) (xy 250.630858 -196.386485) (xy 250.664944 -196.342342)
			(xy 250.705093 -196.303633) (xy 250.750451 -196.271182) (xy 250.800051 -196.245681) (xy 250.852835 -196.227674)
			(xy 250.907678 -196.217544) (xy 250.963412 -196.215507) (xy 251.018849 -196.221607) (xy 251.072806 -196.235713)
			(xy 251.124135 -196.257525) (xy 251.171741 -196.286579) (xy 251.214609 -196.322254) (xy 251.251826 -196.363791)
			(xy 251.282599 -196.410304) (xy 251.306271 -196.460801) (xy 251.322339 -196.514208) (xy 251.330459 -196.569384)
			(xy 251.330968 -196.59727) (xy 251.330459 -196.625156) (xy 251.322339 -196.680332) (xy 251.306271 -196.733739)
			(xy 251.282599 -196.784236) (xy 251.251826 -196.830749) (xy 251.214609 -196.872286) (xy 251.171741 -196.907961)
			(xy 251.124135 -196.937015) (xy 251.072806 -196.958827) (xy 251.018849 -196.972933) (xy 250.963412 -196.979033)
			(xy 250.907678 -196.976996) (xy 250.852835 -196.966866) (xy 250.800051 -196.948859) (xy 250.750451 -196.923358)
			(xy 250.705093 -196.890907) (xy 250.664944 -196.852198) (xy 250.630858 -196.808055) (xy 250.603562 -196.75942)
			(xy 250.583639 -196.707329) (xy 250.571513 -196.652892) (xy 250.567442 -196.59727) (xy 225.651964 -196.59727)
			(xy 225.048296 -197.201028) (xy 245.01424 -197.201028) (xy 245.018311 -197.145406) (xy 245.030437 -197.090969)
			(xy 245.05036 -197.038878) (xy 245.077656 -196.990243) (xy 245.111742 -196.9461) (xy 245.151891 -196.907391)
			(xy 245.197249 -196.87494) (xy 245.246849 -196.849439) (xy 245.299633 -196.831432) (xy 245.354476 -196.821302)
			(xy 245.41021 -196.819265) (xy 245.465647 -196.825365) (xy 245.519604 -196.839471) (xy 245.570933 -196.861283)
			(xy 245.618539 -196.890337) (xy 245.661407 -196.926012) (xy 245.698624 -196.967549) (xy 245.729397 -197.014062)
			(xy 245.753069 -197.064559) (xy 245.769137 -197.117966) (xy 245.777257 -197.173142) (xy 245.777766 -197.201028)
			(xy 245.777257 -197.228914) (xy 245.769137 -197.28409) (xy 245.753069 -197.337497) (xy 245.729397 -197.387994)
			(xy 245.698624 -197.434507) (xy 245.661407 -197.476044) (xy 245.633859 -197.49897) (xy 249.64466 -197.49897)
			(xy 249.648731 -197.443348) (xy 249.660857 -197.388911) (xy 249.68078 -197.33682) (xy 249.708076 -197.288185)
			(xy 249.742162 -197.244042) (xy 249.782311 -197.205333) (xy 249.827669 -197.172882) (xy 249.877269 -197.147381)
			(xy 249.930053 -197.129374) (xy 249.984896 -197.119244) (xy 250.04063 -197.117207) (xy 250.096067 -197.123307)
			(xy 250.150024 -197.137413) (xy 250.201353 -197.159225) (xy 250.248959 -197.188279) (xy 250.291827 -197.223954)
			(xy 250.329044 -197.265491) (xy 250.359817 -197.312004) (xy 250.383489 -197.362501) (xy 250.399557 -197.415908)
			(xy 250.407677 -197.471084) (xy 250.408186 -197.49897) (xy 250.407677 -197.526856) (xy 250.399557 -197.582032)
			(xy 250.383489 -197.635439) (xy 250.359817 -197.685936) (xy 250.329044 -197.732449) (xy 250.293589 -197.77202)
			(xy 251.255528 -197.77202) (xy 251.259599 -197.716398) (xy 251.271725 -197.661961) (xy 251.291648 -197.60987)
			(xy 251.318944 -197.561235) (xy 251.35303 -197.517092) (xy 251.393179 -197.478383) (xy 251.438537 -197.445932)
			(xy 251.488137 -197.420431) (xy 251.540921 -197.402424) (xy 251.595764 -197.392294) (xy 251.651498 -197.390257)
			(xy 251.706935 -197.396357) (xy 251.760892 -197.410463) (xy 251.812221 -197.432275) (xy 251.859827 -197.461329)
			(xy 251.902695 -197.497004) (xy 251.939912 -197.538541) (xy 251.970685 -197.585054) (xy 251.994357 -197.635551)
			(xy 252.010425 -197.688958) (xy 252.018545 -197.744134) (xy 252.019054 -197.77202) (xy 252.018545 -197.799906)
			(xy 252.010425 -197.855082) (xy 251.994357 -197.908489) (xy 251.970685 -197.958986) (xy 251.939912 -198.005499)
			(xy 251.902695 -198.047036) (xy 251.859827 -198.082711) (xy 251.812221 -198.111765) (xy 251.760892 -198.133577)
			(xy 251.706935 -198.147683) (xy 251.651498 -198.153783) (xy 251.595764 -198.151746) (xy 251.540921 -198.141616)
			(xy 251.488137 -198.123609) (xy 251.438537 -198.098108) (xy 251.393179 -198.065657) (xy 251.35303 -198.026948)
			(xy 251.318944 -197.982805) (xy 251.291648 -197.93417) (xy 251.271725 -197.882079) (xy 251.259599 -197.827642)
			(xy 251.255528 -197.77202) (xy 250.293589 -197.77202) (xy 250.291827 -197.773986) (xy 250.248959 -197.809661)
			(xy 250.201353 -197.838715) (xy 250.150024 -197.860527) (xy 250.096067 -197.874633) (xy 250.04063 -197.880733)
			(xy 249.984896 -197.878696) (xy 249.930053 -197.868566) (xy 249.877269 -197.850559) (xy 249.827669 -197.825058)
			(xy 249.782311 -197.792607) (xy 249.742162 -197.753898) (xy 249.708076 -197.709755) (xy 249.68078 -197.66112)
			(xy 249.660857 -197.609029) (xy 249.648731 -197.554592) (xy 249.64466 -197.49897) (xy 245.633859 -197.49897)
			(xy 245.618539 -197.511719) (xy 245.570933 -197.540773) (xy 245.519604 -197.562585) (xy 245.465647 -197.576691)
			(xy 245.41021 -197.582791) (xy 245.354476 -197.580754) (xy 245.299633 -197.570624) (xy 245.246849 -197.552617)
			(xy 245.197249 -197.527116) (xy 245.151891 -197.494665) (xy 245.111742 -197.455956) (xy 245.077656 -197.411813)
			(xy 245.05036 -197.363178) (xy 245.030437 -197.311087) (xy 245.018311 -197.25665) (xy 245.01424 -197.201028)
			(xy 225.048296 -197.201028) (xy 224.903538 -197.345808) (xy 224.895918 -197.353428) (xy 224.892108 -197.362572)
			(xy 224.8904 -197.367145) (xy 224.888615 -197.376741) (xy 224.888552 -197.381622) (xy 224.888552 -198.046594)
			(xy 241.095528 -198.046594) (xy 241.099599 -197.990972) (xy 241.111725 -197.936535) (xy 241.131648 -197.884444)
			(xy 241.158944 -197.835809) (xy 241.19303 -197.791666) (xy 241.233179 -197.752957) (xy 241.278537 -197.720506)
			(xy 241.328137 -197.695005) (xy 241.380921 -197.676998) (xy 241.435764 -197.666868) (xy 241.491498 -197.664831)
			(xy 241.546935 -197.670931) (xy 241.600892 -197.685037) (xy 241.652221 -197.706849) (xy 241.699827 -197.735903)
			(xy 241.742695 -197.771578) (xy 241.779912 -197.813115) (xy 241.810685 -197.859628) (xy 241.834357 -197.910125)
			(xy 241.850425 -197.963532) (xy 241.858545 -198.018708) (xy 241.859054 -198.046594) (xy 241.858545 -198.07448)
			(xy 241.850425 -198.129656) (xy 241.834357 -198.183063) (xy 241.810685 -198.23356) (xy 241.779912 -198.280073)
			(xy 241.742695 -198.32161) (xy 241.740784 -198.3232) (xy 242.822982 -198.3232) (xy 242.827053 -198.267578)
			(xy 242.839179 -198.213141) (xy 242.859102 -198.16105) (xy 242.886398 -198.112415) (xy 242.920484 -198.068272)
			(xy 242.960633 -198.029563) (xy 243.005991 -197.997112) (xy 243.055591 -197.971611) (xy 243.108375 -197.953604)
			(xy 243.163218 -197.943474) (xy 243.218952 -197.941437) (xy 243.274389 -197.947537) (xy 243.328346 -197.961643)
			(xy 243.379675 -197.983455) (xy 243.427281 -198.012509) (xy 243.470149 -198.048184) (xy 243.507366 -198.089721)
			(xy 243.538139 -198.136234) (xy 243.561811 -198.186731) (xy 243.577879 -198.240138) (xy 243.585999 -198.295314)
			(xy 243.586508 -198.3232) (xy 243.585999 -198.351086) (xy 243.577879 -198.406262) (xy 243.561811 -198.459669)
			(xy 243.538139 -198.510166) (xy 243.507366 -198.556679) (xy 243.470149 -198.598216) (xy 243.427281 -198.633891)
			(xy 243.379675 -198.662945) (xy 243.328346 -198.684757) (xy 243.274389 -198.698863) (xy 243.218952 -198.704963)
			(xy 243.163218 -198.702926) (xy 243.108375 -198.692796) (xy 243.055591 -198.674789) (xy 243.005991 -198.649288)
			(xy 242.960633 -198.616837) (xy 242.920484 -198.578128) (xy 242.886398 -198.533985) (xy 242.859102 -198.48535)
			(xy 242.839179 -198.433259) (xy 242.827053 -198.378822) (xy 242.822982 -198.3232) (xy 241.740784 -198.3232)
			(xy 241.699827 -198.357285) (xy 241.652221 -198.386339) (xy 241.600892 -198.408151) (xy 241.546935 -198.422257)
			(xy 241.491498 -198.428357) (xy 241.435764 -198.42632) (xy 241.380921 -198.41619) (xy 241.328137 -198.398183)
			(xy 241.278537 -198.372682) (xy 241.233179 -198.340231) (xy 241.19303 -198.301522) (xy 241.158944 -198.257379)
			(xy 241.131648 -198.208744) (xy 241.111725 -198.156653) (xy 241.099599 -198.102216) (xy 241.095528 -198.046594)
			(xy 224.888552 -198.046594) (xy 224.888552 -199.265794) (xy 226.196142 -199.265794) (xy 226.200213 -199.210172)
			(xy 226.212339 -199.155735) (xy 226.232262 -199.103644) (xy 226.259558 -199.055009) (xy 226.293644 -199.010866)
			(xy 226.333793 -198.972157) (xy 226.379151 -198.939706) (xy 226.428751 -198.914205) (xy 226.481535 -198.896198)
			(xy 226.536378 -198.886068) (xy 226.592112 -198.884031) (xy 226.647549 -198.890131) (xy 226.701506 -198.904237)
			(xy 226.752835 -198.926049) (xy 226.800441 -198.955103) (xy 226.843309 -198.990778) (xy 226.880526 -199.032315)
			(xy 226.911299 -199.078828) (xy 226.934971 -199.129325) (xy 226.951039 -199.182732) (xy 226.959159 -199.237908)
			(xy 226.959668 -199.265794) (xy 226.959159 -199.29368) (xy 226.951039 -199.348856) (xy 226.949283 -199.354694)
			(xy 242.207286 -199.354694) (xy 242.211357 -199.299072) (xy 242.223483 -199.244635) (xy 242.243406 -199.192544)
			(xy 242.270702 -199.143909) (xy 242.304788 -199.099766) (xy 242.344937 -199.061057) (xy 242.390295 -199.028606)
			(xy 242.439895 -199.003105) (xy 242.492679 -198.985098) (xy 242.547522 -198.974968) (xy 242.603256 -198.972931)
			(xy 242.658693 -198.979031) (xy 242.71265 -198.993137) (xy 242.763979 -199.014949) (xy 242.811585 -199.044003)
			(xy 242.854453 -199.079678) (xy 242.89167 -199.121215) (xy 242.922443 -199.167728) (xy 242.946115 -199.218225)
			(xy 242.962183 -199.271632) (xy 242.970303 -199.326808) (xy 242.970812 -199.354694) (xy 242.970303 -199.38258)
			(xy 242.962183 -199.437756) (xy 242.946115 -199.491163) (xy 242.922443 -199.54166) (xy 242.89167 -199.588173)
			(xy 242.854453 -199.62971) (xy 242.811585 -199.665385) (xy 242.763979 -199.694439) (xy 242.71265 -199.716251)
			(xy 242.658693 -199.730357) (xy 242.603256 -199.736457) (xy 242.547522 -199.73442) (xy 242.492679 -199.72429)
			(xy 242.439895 -199.706283) (xy 242.390295 -199.680782) (xy 242.344937 -199.648331) (xy 242.304788 -199.609622)
			(xy 242.270702 -199.565479) (xy 242.243406 -199.516844) (xy 242.223483 -199.464753) (xy 242.211357 -199.410316)
			(xy 242.207286 -199.354694) (xy 226.949283 -199.354694) (xy 226.934971 -199.402263) (xy 226.911299 -199.45276)
			(xy 226.880526 -199.499273) (xy 226.843309 -199.54081) (xy 226.800441 -199.576485) (xy 226.752835 -199.605539)
			(xy 226.701506 -199.627351) (xy 226.647549 -199.641457) (xy 226.592112 -199.647557) (xy 226.536378 -199.64552)
			(xy 226.481535 -199.63539) (xy 226.428751 -199.617383) (xy 226.379151 -199.591882) (xy 226.333793 -199.559431)
			(xy 226.293644 -199.520722) (xy 226.259558 -199.476579) (xy 226.232262 -199.427944) (xy 226.212339 -199.375853)
			(xy 226.200213 -199.321416) (xy 226.196142 -199.265794) (xy 224.888552 -199.265794) (xy 224.888552 -199.686926)
			(xy 224.888007 -199.720204) (xy 224.8858 -199.736964) (xy 240.148362 -199.736964) (xy 240.152433 -199.681342)
			(xy 240.164559 -199.626905) (xy 240.184482 -199.574814) (xy 240.211778 -199.526179) (xy 240.245864 -199.482036)
			(xy 240.286013 -199.443327) (xy 240.331371 -199.410876) (xy 240.380971 -199.385375) (xy 240.433755 -199.367368)
			(xy 240.488598 -199.357238) (xy 240.544332 -199.355201) (xy 240.599769 -199.361301) (xy 240.653726 -199.375407)
			(xy 240.705055 -199.397219) (xy 240.752661 -199.426273) (xy 240.795529 -199.461948) (xy 240.832746 -199.503485)
			(xy 240.863519 -199.549998) (xy 240.887191 -199.600495) (xy 240.903259 -199.653902) (xy 240.911379 -199.709078)
			(xy 240.911888 -199.736964) (xy 240.911379 -199.76485) (xy 240.903259 -199.820026) (xy 240.887191 -199.873433)
			(xy 240.863519 -199.92393) (xy 240.832746 -199.970443) (xy 240.795529 -200.01198) (xy 240.752661 -200.047655)
			(xy 240.705055 -200.076709) (xy 240.653726 -200.098521) (xy 240.599769 -200.112627) (xy 240.544332 -200.118727)
			(xy 240.488598 -200.11669) (xy 240.433755 -200.10656) (xy 240.380971 -200.088553) (xy 240.331371 -200.063052)
			(xy 240.286013 -200.030601) (xy 240.245864 -199.991892) (xy 240.211778 -199.947749) (xy 240.184482 -199.899114)
			(xy 240.164559 -199.847023) (xy 240.152433 -199.792586) (xy 240.148362 -199.736964) (xy 224.8858 -199.736964)
			(xy 224.879319 -199.78619) (xy 224.862096 -199.850478) (xy 224.836633 -199.91197) (xy 224.803363 -199.969613)
			(xy 224.762857 -200.022423) (xy 224.739708 -200.046336) (xy 224.593658 -200.192386) (xy 225.617784 -200.192386)
			(xy 225.621855 -200.136764) (xy 225.633981 -200.082327) (xy 225.653904 -200.030236) (xy 225.6812 -199.981601)
			(xy 225.715286 -199.937458) (xy 225.755435 -199.898749) (xy 225.800793 -199.866298) (xy 225.850393 -199.840797)
			(xy 225.903177 -199.82279) (xy 225.95802 -199.81266) (xy 226.013754 -199.810623) (xy 226.069191 -199.816723)
			(xy 226.123148 -199.830829) (xy 226.174477 -199.852641) (xy 226.222083 -199.881695) (xy 226.264951 -199.91737)
			(xy 226.302168 -199.958907) (xy 226.332941 -200.00542) (xy 226.356613 -200.055917) (xy 226.372681 -200.109324)
			(xy 226.380801 -200.1645) (xy 226.38131 -200.192386) (xy 226.380801 -200.220272) (xy 226.372681 -200.275448)
			(xy 226.356613 -200.328855) (xy 226.332941 -200.379352) (xy 226.302168 -200.425865) (xy 226.264951 -200.467402)
			(xy 226.222083 -200.503077) (xy 226.174477 -200.532131) (xy 226.123148 -200.553943) (xy 226.069191 -200.568049)
			(xy 226.013754 -200.574149) (xy 225.95802 -200.572112) (xy 225.903177 -200.561982) (xy 225.850393 -200.543975)
			(xy 225.800793 -200.518474) (xy 225.755435 -200.486023) (xy 225.715286 -200.447314) (xy 225.6812 -200.403171)
			(xy 225.653904 -200.354536) (xy 225.633981 -200.302445) (xy 225.621855 -200.248008) (xy 225.617784 -200.192386)
			(xy 224.593658 -200.192386) (xy 224.219008 -200.567036) (xy 224.195109 -200.590203) (xy 224.142305 -200.630725)
			(xy 224.084661 -200.664005) (xy 224.023166 -200.689474) (xy 223.958871 -200.706695) (xy 223.892879 -200.715373)
			(xy 223.859598 -200.71588) (xy 222.695516 -200.71588) (xy 222.687871 -200.716137) (xy 222.673266 -200.720662)
			(xy 222.666814 -200.72477) (xy 222.659448 -200.730866) (xy 222.162878 -201.227182) (xy 221.393512 -201.996802)
			(xy 220.871796 -202.518518) (xy 220.868274 -202.522248) (xy 220.862644 -202.530822) (xy 220.86062 -202.535536)
			(xy 220.857378 -202.54341) (xy 222.22409 -202.54341) (xy 222.228161 -202.487788) (xy 222.240287 -202.433351)
			(xy 222.26021 -202.38126) (xy 222.287506 -202.332625) (xy 222.321592 -202.288482) (xy 222.361741 -202.249773)
			(xy 222.407099 -202.217322) (xy 222.456699 -202.191821) (xy 222.509483 -202.173814) (xy 222.564326 -202.163684)
			(xy 222.62006 -202.161647) (xy 222.675497 -202.167747) (xy 222.729454 -202.181853) (xy 222.780783 -202.203665)
			(xy 222.828389 -202.232719) (xy 222.871257 -202.268394) (xy 222.908474 -202.309931) (xy 222.939247 -202.356444)
			(xy 222.962919 -202.406941) (xy 222.978987 -202.460348) (xy 222.987107 -202.515524) (xy 222.987616 -202.54341)
			(xy 222.987107 -202.571296) (xy 222.978987 -202.626472) (xy 222.962919 -202.679879) (xy 222.939247 -202.730376)
			(xy 222.908474 -202.776889) (xy 222.871257 -202.818426) (xy 222.828389 -202.854101) (xy 222.780783 -202.883155)
			(xy 222.729454 -202.904967) (xy 222.675497 -202.919073) (xy 222.62006 -202.925173) (xy 222.564326 -202.923136)
			(xy 222.509483 -202.913006) (xy 222.456699 -202.894999) (xy 222.407099 -202.869498) (xy 222.361741 -202.837047)
			(xy 222.321592 -202.798338) (xy 222.287506 -202.754195) (xy 222.26021 -202.70556) (xy 222.240287 -202.653469)
			(xy 222.228161 -202.599032) (xy 222.22409 -202.54341) (xy 220.857378 -202.54341) (xy 220.857064 -202.544172)
			(xy 220.857064 -202.979782) (xy 220.857571 -202.990204) (xy 220.865834 -203.009343) (xy 220.873066 -203.016866)
			(xy 220.927168 -203.067666) (xy 220.93508 -203.074417) (xy 220.954614 -203.081504) (xy 220.965014 -203.081382)
			(xy 220.98889 -203.08062) (xy 221.016141 -203.081083) (xy 221.070089 -203.088838) (xy 221.122385 -203.104192)
			(xy 221.171962 -203.126832) (xy 221.217813 -203.156298) (xy 221.259004 -203.191989) (xy 221.294696 -203.233179)
			(xy 221.324163 -203.279029) (xy 221.346805 -203.328606) (xy 221.36216 -203.380901) (xy 221.363394 -203.389484)
			(xy 221.848932 -203.389484) (xy 221.853003 -203.333862) (xy 221.865129 -203.279425) (xy 221.885052 -203.227334)
			(xy 221.912348 -203.178699) (xy 221.946434 -203.134556) (xy 221.986583 -203.095847) (xy 222.031941 -203.063396)
			(xy 222.081541 -203.037895) (xy 222.134325 -203.019888) (xy 222.189168 -203.009758) (xy 222.244902 -203.007721)
			(xy 222.300339 -203.013821) (xy 222.354296 -203.027927) (xy 222.405625 -203.049739) (xy 222.453231 -203.078793)
			(xy 222.496099 -203.114468) (xy 222.533316 -203.156005) (xy 222.564089 -203.202518) (xy 222.587761 -203.253015)
			(xy 222.603829 -203.306422) (xy 222.611949 -203.361598) (xy 222.612458 -203.389484) (xy 222.611949 -203.41737)
			(xy 222.603829 -203.472546) (xy 222.587761 -203.525953) (xy 222.564089 -203.57645) (xy 222.533316 -203.622963)
			(xy 222.496099 -203.6645) (xy 222.453231 -203.700175) (xy 222.405625 -203.729229) (xy 222.354296 -203.751041)
			(xy 222.300339 -203.765147) (xy 222.244902 -203.771247) (xy 222.189168 -203.76921) (xy 222.134325 -203.75908)
			(xy 222.081541 -203.741073) (xy 222.031941 -203.715572) (xy 221.986583 -203.683121) (xy 221.946434 -203.644412)
			(xy 221.912348 -203.600269) (xy 221.885052 -203.551634) (xy 221.865129 -203.499543) (xy 221.853003 -203.445106)
			(xy 221.848932 -203.389484) (xy 221.363394 -203.389484) (xy 221.369917 -203.434849) (xy 221.369917 -203.489351)
			(xy 221.36216 -203.543299) (xy 221.346805 -203.595594) (xy 221.324163 -203.645171) (xy 221.294696 -203.691021)
			(xy 221.259004 -203.732211) (xy 221.217813 -203.767902) (xy 221.171962 -203.797368) (xy 221.122385 -203.820008)
			(xy 221.070089 -203.835362) (xy 221.016141 -203.843117) (xy 220.98889 -203.843636) (xy 220.965014 -203.842874)
			(xy 220.954346 -203.842366) (xy 220.935042 -203.849224) (xy 220.873066 -203.90739) (xy 220.865799 -203.91489)
			(xy 220.857529 -203.934042) (xy 220.857064 -203.944474) (xy 220.857064 -205.610206) (xy 220.856599 -205.641065)
			(xy 220.849089 -205.702325) (xy 220.842078 -205.73238) (xy 220.841316 -205.735428) (xy 220.840554 -205.740254)
			(xy 220.839577 -205.75054) (xy 220.844938 -205.770474) (xy 220.850968 -205.778862) (xy 220.899736 -205.841346)
			(xy 220.904308 -205.845918) (xy 220.910057 -205.851117) (xy 220.923888 -205.858101) (xy 220.931486 -205.859634)
			(xy 220.939868 -205.860396) (xy 223.106742 -205.860396) (xy 223.110806 -205.860142) (xy 223.119959 -205.859061)
			(xy 223.136636 -205.85125) (xy 223.143318 -205.844902) (xy 223.148906 -205.83906) (xy 223.192848 -205.752954)
			(xy 223.196001 -205.746235) (xy 223.198724 -205.731653) (xy 223.198182 -205.724252) (xy 223.19742 -205.717394)
			(xy 223.192594 -205.704948) (xy 223.188784 -205.699868) (xy 223.171917 -205.675402) (xy 223.145162 -205.622343)
			(xy 223.126955 -205.565778) (xy 223.117735 -205.507075) (xy 223.117156 -205.477364) (xy 223.117156 -205.47711)
			(xy 223.117664 -205.459076) (xy 223.117664 -205.457044) (xy 223.119726 -205.428138) (xy 223.13149 -205.371395)
			(xy 223.151702 -205.317084) (xy 223.179896 -205.266456) (xy 223.215424 -205.220674) (xy 223.257467 -205.180793)
			(xy 223.305059 -205.14773) (xy 223.357104 -205.122245) (xy 223.412405 -205.104926) (xy 223.469689 -205.09617)
			(xy 223.498664 -205.095602) (xy 223.525918 -205.096063) (xy 223.579873 -205.103816) (xy 223.632174 -205.119169)
			(xy 223.681758 -205.141809) (xy 223.727615 -205.171277) (xy 223.768811 -205.20697) (xy 223.804508 -205.248164)
			(xy 223.833978 -205.294019) (xy 223.856622 -205.343601) (xy 223.871979 -205.395902) (xy 223.879735 -205.449856)
			(xy 223.880172 -205.47711) (xy 223.880172 -205.477364) (xy 223.879577 -205.507116) (xy 223.870301 -205.565893)
			(xy 223.852029 -205.622523) (xy 223.825203 -205.675638) (xy 223.80829 -205.700122) (xy 223.806004 -205.70317)
			(xy 223.801699 -205.711019) (xy 223.798191 -205.728559) (xy 223.799146 -205.73746) (xy 223.799803 -205.741216)
			(xy 223.8021 -205.748486) (xy 223.803718 -205.751938) (xy 223.8121 -205.767686) (xy 223.8121 -205.768194)
			(xy 223.845374 -205.83271) (xy 223.848798 -205.838899) (xy 223.858474 -205.849205) (xy 223.864424 -205.85303)
			(xy 223.870431 -205.85641) (xy 223.883697 -205.86013) (xy 223.890586 -205.860396) (xy 224.122742 -205.860396)
			(xy 224.126806 -205.860142) (xy 224.135959 -205.859061) (xy 224.152636 -205.85125) (xy 224.159318 -205.844902)
			(xy 224.164906 -205.83906) (xy 224.208848 -205.752954) (xy 224.212001 -205.746235) (xy 224.214724 -205.731653)
			(xy 224.214182 -205.724252) (xy 224.21342 -205.717394) (xy 224.208594 -205.704948) (xy 224.204784 -205.699868)
			(xy 224.187917 -205.675402) (xy 224.161162 -205.622343) (xy 224.142955 -205.565778) (xy 224.133735 -205.507075)
			(xy 224.133156 -205.477364) (xy 224.133156 -205.47711) (xy 224.133664 -205.459076) (xy 224.133664 -205.457044)
			(xy 224.135726 -205.428138) (xy 224.14749 -205.371395) (xy 224.167702 -205.317084) (xy 224.195896 -205.266456)
			(xy 224.231424 -205.220674) (xy 224.273467 -205.180793) (xy 224.321059 -205.14773) (xy 224.373104 -205.122245)
			(xy 224.428405 -205.104926) (xy 224.485689 -205.09617) (xy 224.514664 -205.095602) (xy 224.541918 -205.096063)
			(xy 224.595873 -205.103816) (xy 224.648174 -205.119169) (xy 224.697758 -205.141809) (xy 224.743615 -205.171277)
			(xy 224.784811 -205.20697) (xy 224.820508 -205.248164) (xy 224.849978 -205.294019) (xy 224.872622 -205.343601)
			(xy 224.887979 -205.395902) (xy 224.895735 -205.449856) (xy 224.896172 -205.47711) (xy 224.896172 -205.477364)
			(xy 224.895577 -205.507116) (xy 224.886301 -205.565893) (xy 224.868029 -205.622523) (xy 224.841203 -205.675638)
			(xy 224.82429 -205.700122) (xy 224.822004 -205.70317) (xy 224.817699 -205.711019) (xy 224.814191 -205.728559)
			(xy 224.815146 -205.73746) (xy 224.815803 -205.741216) (xy 224.8181 -205.748486) (xy 224.819718 -205.751938)
			(xy 224.8281 -205.767686) (xy 224.8281 -205.768194) (xy 224.861374 -205.83271) (xy 224.864798 -205.838899)
			(xy 224.874474 -205.849205) (xy 224.880424 -205.85303) (xy 224.886431 -205.85641) (xy 224.899697 -205.86013)
			(xy 224.906586 -205.860396) (xy 225.138742 -205.860396) (xy 225.142806 -205.860142) (xy 225.151959 -205.859061)
			(xy 225.168636 -205.85125) (xy 225.175318 -205.844902) (xy 225.180906 -205.83906) (xy 225.224848 -205.752954)
			(xy 225.228001 -205.746235) (xy 225.230724 -205.731653) (xy 225.230182 -205.724252) (xy 225.22942 -205.717394)
			(xy 225.224594 -205.704948) (xy 225.220784 -205.699868) (xy 225.203917 -205.675402) (xy 225.177162 -205.622343)
			(xy 225.158955 -205.565778) (xy 225.149735 -205.507075) (xy 225.149156 -205.477364) (xy 225.149156 -205.47711)
			(xy 225.149664 -205.459076) (xy 225.149664 -205.457044) (xy 225.151726 -205.428138) (xy 225.16349 -205.371395)
			(xy 225.183702 -205.317084) (xy 225.211896 -205.266456) (xy 225.247424 -205.220674) (xy 225.289467 -205.180793)
			(xy 225.337059 -205.14773) (xy 225.389104 -205.122245) (xy 225.444405 -205.104926) (xy 225.501689 -205.09617)
			(xy 225.530664 -205.095602) (xy 225.557918 -205.096063) (xy 225.611873 -205.103816) (xy 225.664174 -205.119169)
			(xy 225.713758 -205.141809) (xy 225.759615 -205.171277) (xy 225.800811 -205.20697) (xy 225.836508 -205.248164)
			(xy 225.865978 -205.294019) (xy 225.888622 -205.343601) (xy 225.903979 -205.395902) (xy 225.911735 -205.449856)
			(xy 225.912172 -205.47711) (xy 225.912172 -205.477364) (xy 225.911577 -205.507116) (xy 225.902301 -205.565893)
			(xy 225.884029 -205.622523) (xy 225.857203 -205.675638) (xy 225.84029 -205.700122) (xy 225.838004 -205.70317)
			(xy 225.833699 -205.711019) (xy 225.830191 -205.728559) (xy 225.831146 -205.73746) (xy 225.831803 -205.741216)
			(xy 225.8341 -205.748486) (xy 225.835718 -205.751938) (xy 225.8441 -205.767686) (xy 225.8441 -205.768194)
			(xy 225.877374 -205.83271) (xy 225.880798 -205.838899) (xy 225.890474 -205.849205) (xy 225.896424 -205.85303)
			(xy 225.902431 -205.85641) (xy 225.915697 -205.86013) (xy 225.922586 -205.860396) (xy 227.170742 -205.860396)
			(xy 227.174806 -205.860142) (xy 227.183959 -205.859061) (xy 227.200636 -205.85125) (xy 227.207318 -205.844902)
			(xy 227.212906 -205.83906) (xy 227.256848 -205.752954) (xy 227.260001 -205.746235) (xy 227.262724 -205.731653)
			(xy 227.262182 -205.724252) (xy 227.26142 -205.717394) (xy 227.256594 -205.704948) (xy 227.252784 -205.699868)
			(xy 227.235917 -205.675402) (xy 227.209162 -205.622343) (xy 227.190955 -205.565778) (xy 227.181735 -205.507075)
			(xy 227.181156 -205.477364) (xy 227.181156 -205.47711) (xy 227.181664 -205.459076) (xy 227.181664 -205.457044)
			(xy 227.183726 -205.428138) (xy 227.19549 -205.371395) (xy 227.215702 -205.317084) (xy 227.243896 -205.266456)
			(xy 227.279424 -205.220674) (xy 227.321467 -205.180793) (xy 227.369059 -205.14773) (xy 227.421104 -205.122245)
			(xy 227.476405 -205.104926) (xy 227.533689 -205.09617) (xy 227.562664 -205.095602) (xy 227.589918 -205.096063)
			(xy 227.643873 -205.103816) (xy 227.696174 -205.119169) (xy 227.745758 -205.141809) (xy 227.791615 -205.171277)
			(xy 227.832811 -205.20697) (xy 227.868508 -205.248164) (xy 227.897978 -205.294019) (xy 227.920622 -205.343601)
			(xy 227.935979 -205.395902) (xy 227.943735 -205.449856) (xy 227.944172 -205.47711) (xy 227.944172 -205.477364)
			(xy 227.943577 -205.507116) (xy 227.934301 -205.565893) (xy 227.916029 -205.622523) (xy 227.889203 -205.675638)
			(xy 227.87229 -205.700122) (xy 227.870004 -205.70317) (xy 227.865699 -205.711019) (xy 227.862191 -205.728559)
			(xy 227.863146 -205.73746) (xy 227.863803 -205.741216) (xy 227.8661 -205.748486) (xy 227.867718 -205.751938)
			(xy 227.8761 -205.767686) (xy 227.8761 -205.768194) (xy 227.909374 -205.83271) (xy 227.912798 -205.838899)
			(xy 227.922474 -205.849205) (xy 227.928424 -205.85303) (xy 227.934431 -205.85641) (xy 227.947697 -205.86013)
			(xy 227.954586 -205.860396) (xy 228.186742 -205.860396) (xy 228.190806 -205.860142) (xy 228.199959 -205.859061)
			(xy 228.216636 -205.85125) (xy 228.223318 -205.844902) (xy 228.228906 -205.83906) (xy 228.272848 -205.752954)
			(xy 228.276001 -205.746235) (xy 228.278724 -205.731653) (xy 228.278182 -205.724252) (xy 228.27742 -205.717394)
			(xy 228.272594 -205.704948) (xy 228.268784 -205.699868) (xy 228.251917 -205.675402) (xy 228.225162 -205.622343)
			(xy 228.206955 -205.565778) (xy 228.197735 -205.507075) (xy 228.197156 -205.477364) (xy 228.197156 -205.47711)
			(xy 228.197664 -205.459076) (xy 228.197664 -205.457044) (xy 228.199726 -205.428138) (xy 228.21149 -205.371395)
			(xy 228.231702 -205.317084) (xy 228.259896 -205.266456) (xy 228.295424 -205.220674) (xy 228.337467 -205.180793)
			(xy 228.385059 -205.14773) (xy 228.437104 -205.122245) (xy 228.492405 -205.104926) (xy 228.549689 -205.09617)
			(xy 228.578664 -205.095602) (xy 228.605918 -205.096063) (xy 228.659873 -205.103816) (xy 228.712174 -205.119169)
			(xy 228.761758 -205.141809) (xy 228.807615 -205.171277) (xy 228.848811 -205.20697) (xy 228.884508 -205.248164)
			(xy 228.913978 -205.294019) (xy 228.936622 -205.343601) (xy 228.951979 -205.395902) (xy 228.959735 -205.449856)
			(xy 228.960172 -205.47711) (xy 228.960172 -205.477364) (xy 228.959577 -205.507116) (xy 228.950301 -205.565893)
			(xy 228.932029 -205.622523) (xy 228.905203 -205.675638) (xy 228.88829 -205.700122) (xy 228.886004 -205.70317)
			(xy 228.881699 -205.711019) (xy 228.878191 -205.728559) (xy 228.879146 -205.73746) (xy 228.879803 -205.741216)
			(xy 228.8821 -205.748486) (xy 228.883718 -205.751938) (xy 228.8921 -205.767686) (xy 228.8921 -205.768194)
			(xy 228.925374 -205.83271) (xy 228.928798 -205.838899) (xy 228.938474 -205.849205) (xy 228.944424 -205.85303)
			(xy 228.950431 -205.85641) (xy 228.963697 -205.86013) (xy 228.970586 -205.860396) (xy 229.184708 -205.860396)
			(xy 229.192736 -205.860152) (xy 229.208015 -205.855226) (xy 229.21468 -205.850744) (xy 229.220522 -205.846426)
			(xy 229.229666 -205.83398) (xy 229.23246 -205.825598) (xy 229.241231 -205.800558) (xy 229.264727 -205.752987)
			(xy 229.294588 -205.709131) (xy 229.330238 -205.669837) (xy 229.37099 -205.635861) (xy 229.416056 -205.607861)
			(xy 229.464568 -205.586377) (xy 229.51559 -205.571822) (xy 229.568136 -205.564479) (xy 229.594664 -205.563978)
			(xy 229.625007 -205.56459) (xy 229.684923 -205.574239) (xy 229.74256 -205.593238) (xy 229.796469 -205.621107)
			(xy 229.821232 -205.638654) (xy 229.827051 -205.642733) (xy 229.840333 -205.647768) (xy 229.847394 -205.64856)
			(xy 229.861364 -205.649576) (xy 229.888542 -205.63586) (xy 229.95763 -205.600808) (xy 229.958138 -205.600554)
			(xy 229.965573 -205.595794) (xy 229.976891 -205.582263) (xy 229.982922 -205.565686) (xy 229.983284 -205.556866)
			(xy 229.983284 -205.341728) (xy 229.982847 -205.331664) (xy 229.975113 -205.31308) (xy 229.968298 -205.30566)
			(xy 229.40264 -204.740002) (xy 229.395238 -204.733165) (xy 229.37664 -204.725452) (xy 229.366572 -204.725016)
			(xy 224.332292 -204.725016) (xy 224.306205 -204.724529) (xy 224.254675 -204.716361) (xy 224.205059 -204.700226)
			(xy 224.158581 -204.676523) (xy 224.116386 -204.645837) (xy 224.097596 -204.627734) (xy 223.295464 -203.825602)
			(xy 223.277431 -203.806832) (xy 223.246849 -203.764716) (xy 223.223221 -203.71834) (xy 223.207128 -203.668842)
			(xy 223.198965 -203.617438) (xy 223.198436 -203.591414) (xy 223.198436 -201.572876) (xy 223.196404 -201.569066)
			(xy 223.181408 -201.540575) (xy 223.160133 -201.479812) (xy 223.149339 -201.416344) (xy 223.148652 -201.384154)
			(xy 223.149138 -201.356903) (xy 223.156894 -201.302955) (xy 223.172249 -201.25066) (xy 223.194891 -201.201083)
			(xy 223.224357 -201.155233) (xy 223.260048 -201.114042) (xy 223.301239 -201.078351) (xy 223.347089 -201.048885)
			(xy 223.396666 -201.026243) (xy 223.448961 -201.010888) (xy 223.502909 -201.003132) (xy 223.557411 -201.003132)
			(xy 223.611359 -201.010888) (xy 223.663654 -201.026243) (xy 223.713231 -201.048885) (xy 223.759081 -201.078351)
			(xy 223.800272 -201.114042) (xy 223.835963 -201.155233) (xy 223.865429 -201.201083) (xy 223.888071 -201.25066)
			(xy 223.903426 -201.302955) (xy 223.911182 -201.356903) (xy 223.911668 -201.384154) (xy 223.911113 -201.414988)
			(xy 223.901269 -201.475865) (xy 223.881767 -201.534368) (xy 223.86798 -201.561954) (xy 223.864932 -201.567542)
			(xy 223.861884 -201.57948) (xy 223.861884 -203.301346) (xy 223.866202 -203.306426) (xy 223.965262 -203.405486)
			(xy 223.972628 -203.411582) (xy 223.985074 -203.417678) (xy 223.98736 -203.41844) (xy 223.994699 -203.420256)
			(xy 224.009807 -203.420003) (xy 224.017078 -203.417932) (xy 224.103184 -203.389738) (xy 224.10985 -203.387287)
			(xy 224.12159 -203.379306) (xy 224.126298 -203.37399) (xy 224.130616 -203.368656) (xy 224.136204 -203.35621)
			(xy 224.137474 -203.349098) (xy 224.137474 -203.348844) (xy 224.14048 -203.330716) (xy 224.149512 -203.295094)
			(xy 224.155508 -203.277724) (xy 224.164751 -203.253427) (xy 224.188878 -203.20738) (xy 224.219023 -203.165028)
			(xy 224.25463 -203.127152) (xy 224.295041 -203.094452) (xy 224.317052 -203.08062) (xy 224.317306 -203.08062)
			(xy 224.31756 -203.080366) (xy 224.32752 -203.073535) (xy 224.340113 -203.052971) (xy 224.34169 -203.040996)
			(xy 224.342706 -202.996038) (xy 224.342706 -202.99553) (xy 224.343976 -202.954636) (xy 224.343976 -202.95235)
			(xy 224.343376 -202.942489) (xy 224.33568 -202.924312) (xy 224.32899 -202.917044) (xy 224.321878 -202.909932)
			(xy 224.318068 -202.907392) (xy 224.296829 -202.892022) (xy 224.258369 -202.856395) (xy 224.225146 -202.81584)
			(xy 224.197785 -202.771119) (xy 224.176803 -202.723075) (xy 224.162593 -202.672611) (xy 224.155423 -202.620677)
			(xy 224.155 -202.594464) (xy 224.155486 -202.567213) (xy 224.163242 -202.513265) (xy 224.178597 -202.46097)
			(xy 224.201239 -202.411393) (xy 224.230705 -202.365543) (xy 224.266396 -202.324352) (xy 224.307587 -202.288661)
			(xy 224.353437 -202.259195) (xy 224.403014 -202.236553) (xy 224.455309 -202.221198) (xy 224.509257 -202.213442)
			(xy 224.563759 -202.213442) (xy 224.617707 -202.221198) (xy 224.670002 -202.236553) (xy 224.719579 -202.259195)
			(xy 224.765429 -202.288661) (xy 224.80662 -202.324352) (xy 224.842311 -202.365543) (xy 224.871777 -202.411393)
			(xy 224.894419 -202.46097) (xy 224.909774 -202.513265) (xy 224.91753 -202.567213) (xy 224.918016 -202.594464)
			(xy 224.917534 -202.622027) (xy 224.909609 -202.67658) (xy 224.89392 -202.729426) (xy 224.870792 -202.779466)
			(xy 224.840706 -202.825658) (xy 224.804289 -202.867042) (xy 224.762297 -202.902757) (xy 224.7392 -202.917806)
			(xy 224.738946 -202.91806) (xy 224.733866 -202.921362) (xy 224.725439 -202.926995) (xy 224.713504 -202.943358)
			(xy 224.710752 -202.953112) (xy 224.709482 -202.963272) (xy 224.708212 -203.005436) (xy 224.708212 -203.005944)
			(xy 224.707196 -203.048362) (xy 224.70872 -203.06157) (xy 224.711006 -203.070968) (xy 224.721166 -203.085954)
			(xy 224.729548 -203.091542) (xy 224.751209 -203.106863) (xy 224.790481 -203.142536) (xy 224.824433 -203.183306)
			(xy 224.852408 -203.228386) (xy 224.873869 -203.276907) (xy 224.8884 -203.327934) (xy 224.895721 -203.380482)
			(xy 224.896172 -203.40701) (xy 225.148646 -203.40701) (xy 225.152717 -203.351388) (xy 225.164843 -203.296951)
			(xy 225.184766 -203.24486) (xy 225.212062 -203.196225) (xy 225.246148 -203.152082) (xy 225.286297 -203.113373)
			(xy 225.331655 -203.080922) (xy 225.381255 -203.055421) (xy 225.434039 -203.037414) (xy 225.488882 -203.027284)
			(xy 225.544616 -203.025247) (xy 225.600053 -203.031347) (xy 225.65401 -203.045453) (xy 225.705339 -203.067265)
			(xy 225.752945 -203.096319) (xy 225.756972 -203.09967) (xy 226.164646 -203.09967) (xy 226.168717 -203.044048)
			(xy 226.180843 -202.989611) (xy 226.200766 -202.93752) (xy 226.228062 -202.888885) (xy 226.262148 -202.844742)
			(xy 226.302297 -202.806033) (xy 226.347655 -202.773582) (xy 226.397255 -202.748081) (xy 226.450039 -202.730074)
			(xy 226.504882 -202.719944) (xy 226.560616 -202.717907) (xy 226.616053 -202.724007) (xy 226.67001 -202.738113)
			(xy 226.721339 -202.759925) (xy 226.768945 -202.788979) (xy 226.811813 -202.824654) (xy 226.84903 -202.866191)
			(xy 226.879803 -202.912704) (xy 226.903475 -202.963201) (xy 226.919543 -203.016608) (xy 226.927663 -203.071784)
			(xy 226.928172 -203.09967) (xy 226.927663 -203.127556) (xy 226.919543 -203.182732) (xy 226.903475 -203.236139)
			(xy 226.879803 -203.286636) (xy 226.84903 -203.333149) (xy 226.818126 -203.36764) (xy 227.158548 -203.36764)
			(xy 227.162619 -203.312018) (xy 227.174745 -203.257581) (xy 227.194668 -203.20549) (xy 227.221964 -203.156855)
			(xy 227.25605 -203.112712) (xy 227.296199 -203.074003) (xy 227.341557 -203.041552) (xy 227.391157 -203.016051)
			(xy 227.443941 -202.998044) (xy 227.498784 -202.987914) (xy 227.554518 -202.985877) (xy 227.609955 -202.991977)
			(xy 227.663912 -203.006083) (xy 227.715241 -203.027895) (xy 227.762847 -203.056949) (xy 227.805715 -203.092624)
			(xy 227.842932 -203.134161) (xy 227.873705 -203.180674) (xy 227.897377 -203.231171) (xy 227.913445 -203.284578)
			(xy 227.921565 -203.339754) (xy 227.922074 -203.36764) (xy 227.921666 -203.389992) (xy 228.888796 -203.389992)
			(xy 228.892867 -203.33437) (xy 228.904993 -203.279933) (xy 228.924916 -203.227842) (xy 228.952212 -203.179207)
			(xy 228.986298 -203.135064) (xy 229.026447 -203.096355) (xy 229.071805 -203.063904) (xy 229.121405 -203.038403)
			(xy 229.174189 -203.020396) (xy 229.229032 -203.010266) (xy 229.284766 -203.008229) (xy 229.340203 -203.014329)
			(xy 229.39416 -203.028435) (xy 229.445489 -203.050247) (xy 229.493095 -203.079301) (xy 229.535963 -203.114976)
			(xy 229.57318 -203.156513) (xy 229.603953 -203.203026) (xy 229.627625 -203.253523) (xy 229.643693 -203.30693)
			(xy 229.651813 -203.362106) (xy 229.652322 -203.389992) (xy 229.651813 -203.417878) (xy 229.643693 -203.473054)
			(xy 229.627625 -203.526461) (xy 229.603953 -203.576958) (xy 229.57318 -203.623471) (xy 229.535963 -203.665008)
			(xy 229.493095 -203.700683) (xy 229.445489 -203.729737) (xy 229.39416 -203.751549) (xy 229.340203 -203.765655)
			(xy 229.284766 -203.771755) (xy 229.229032 -203.769718) (xy 229.174189 -203.759588) (xy 229.121405 -203.741581)
			(xy 229.071805 -203.71608) (xy 229.026447 -203.683629) (xy 228.986298 -203.64492) (xy 228.952212 -203.600777)
			(xy 228.924916 -203.552142) (xy 228.904993 -203.500051) (xy 228.892867 -203.445614) (xy 228.888796 -203.389992)
			(xy 227.921666 -203.389992) (xy 227.921565 -203.395526) (xy 227.913445 -203.450702) (xy 227.897377 -203.504109)
			(xy 227.873705 -203.554606) (xy 227.842932 -203.601119) (xy 227.805715 -203.642656) (xy 227.762847 -203.678331)
			(xy 227.715241 -203.707385) (xy 227.663912 -203.729197) (xy 227.609955 -203.743303) (xy 227.554518 -203.749403)
			(xy 227.498784 -203.747366) (xy 227.443941 -203.737236) (xy 227.391157 -203.719229) (xy 227.341557 -203.693728)
			(xy 227.296199 -203.661277) (xy 227.25605 -203.622568) (xy 227.221964 -203.578425) (xy 227.194668 -203.52979)
			(xy 227.174745 -203.477699) (xy 227.162619 -203.423262) (xy 227.158548 -203.36764) (xy 226.818126 -203.36764)
			(xy 226.811813 -203.374686) (xy 226.768945 -203.410361) (xy 226.721339 -203.439415) (xy 226.67001 -203.461227)
			(xy 226.616053 -203.475333) (xy 226.560616 -203.481433) (xy 226.504882 -203.479396) (xy 226.450039 -203.469266)
			(xy 226.397255 -203.451259) (xy 226.347655 -203.425758) (xy 226.302297 -203.393307) (xy 226.262148 -203.354598)
			(xy 226.228062 -203.310455) (xy 226.200766 -203.26182) (xy 226.180843 -203.209729) (xy 226.168717 -203.155292)
			(xy 226.164646 -203.09967) (xy 225.756972 -203.09967) (xy 225.795813 -203.131994) (xy 225.83303 -203.173531)
			(xy 225.863803 -203.220044) (xy 225.887475 -203.270541) (xy 225.903543 -203.323948) (xy 225.911663 -203.379124)
			(xy 225.912172 -203.40701) (xy 225.911663 -203.434896) (xy 225.903543 -203.490072) (xy 225.887475 -203.543479)
			(xy 225.863803 -203.593976) (xy 225.83303 -203.640489) (xy 225.795813 -203.682026) (xy 225.752945 -203.717701)
			(xy 225.705339 -203.746755) (xy 225.65401 -203.768567) (xy 225.600053 -203.782673) (xy 225.544616 -203.788773)
			(xy 225.488882 -203.786736) (xy 225.434039 -203.776606) (xy 225.381255 -203.758599) (xy 225.331655 -203.733098)
			(xy 225.286297 -203.700647) (xy 225.246148 -203.661938) (xy 225.212062 -203.617795) (xy 225.184766 -203.56916)
			(xy 225.164843 -203.517069) (xy 225.152717 -203.462632) (xy 225.148646 -203.40701) (xy 224.896172 -203.40701)
			(xy 224.896093 -203.419748) (xy 224.894439 -203.445169) (xy 224.89287 -203.45781) (xy 224.891435 -203.467927)
			(xy 224.887622 -203.488003) (xy 224.88525 -203.497942) (xy 224.882331 -203.509561) (xy 224.875212 -203.532437)
			(xy 224.871026 -203.543662) (xy 224.860361 -203.569998) (xy 224.832371 -203.619443) (xy 224.797366 -203.664196)
			(xy 224.756118 -203.703271) (xy 224.709537 -203.735805) (xy 224.658651 -203.76108) (xy 224.604583 -203.778539)
			(xy 224.57664 -203.783692) (xy 224.576132 -203.783692) (xy 224.574862 -203.783946) (xy 224.561908 -203.785216)
			(xy 224.552256 -203.79182) (xy 224.546831 -203.795688) (xy 224.538086 -203.805735) (xy 224.534984 -203.811632)
			(xy 224.532952 -203.815696) (xy 224.532698 -203.816204) (xy 224.503234 -203.906374) (xy 224.501926 -203.911407)
			(xy 224.501163 -203.921776) (xy 224.50171 -203.926948) (xy 224.502962 -203.934601) (xy 224.509435 -203.948684)
			(xy 224.51441 -203.954634) (xy 224.619566 -204.059282) (xy 224.621852 -204.06106) (xy 229.525068 -204.06106)
			(xy 229.551156 -204.061544) (xy 229.60269 -204.069706) (xy 229.65231 -204.085836) (xy 229.698794 -204.109534)
			(xy 229.740996 -204.140216) (xy 229.759764 -204.158342) (xy 230.587296 -204.985874) (xy 230.605328 -205.004645)
			(xy 230.635907 -205.046762) (xy 230.659534 -205.093138) (xy 230.675627 -205.142635) (xy 230.683793 -205.194039)
			(xy 230.684324 -205.220062) (xy 230.684324 -205.652116) (xy 230.70058 -205.675992) (xy 230.719245 -205.64953)
			(xy 230.762724 -205.601543) (xy 230.812436 -205.560049) (xy 230.867422 -205.525848) (xy 230.926619 -205.499601)
			(xy 230.988884 -205.481816) (xy 231.053013 -205.472836) (xy 231.08539 -205.472284) (xy 231.116125 -205.472777)
			(xy 231.177059 -205.480868) (xy 231.236399 -205.496909) (xy 231.29311 -205.520622) (xy 231.346206 -205.551595)
			(xy 231.394763 -205.589287) (xy 231.437936 -205.633043) (xy 231.474973 -205.682102) (xy 231.505229 -205.735609)
			(xy 231.528179 -205.792634) (xy 231.53624 -205.822296) (xy 231.539605 -205.833023) (xy 231.553942 -205.850304)
			(xy 231.574286 -205.859807) (xy 231.585516 -205.860396) (xy 231.604312 -205.860396) (xy 231.6099 -205.86065)
			(xy 231.611678 -205.860904) (xy 231.621584 -205.860904) (xy 231.634143 -205.860266) (xy 231.656286 -205.848417)
			(xy 231.663748 -205.838298) (xy 231.67086 -205.828138) (xy 231.6734 -205.802992) (xy 231.3178 -204.94498)
			(xy 231.315793 -204.940416) (xy 231.310293 -204.932102) (xy 231.306878 -204.92847) (xy 230.000302 -203.621894)
			(xy 229.985199 -203.60627) (xy 229.958764 -203.571781) (xy 229.937053 -203.534139) (xy 229.92842 -203.514198)
			(xy 229.926896 -203.510642) (xy 229.924886 -203.506137) (xy 229.919387 -203.497948) (xy 229.915974 -203.494386)
			(xy 229.88778 -203.466192) (xy 229.865974 -203.443311) (xy 229.830925 -203.390723) (xy 229.818184 -203.361798)
			(xy 229.62489 -202.89647) (xy 229.622885 -202.891904) (xy 229.617391 -202.883585) (xy 229.613968 -202.87996)
			(xy 228.380544 -201.64679) (xy 228.376926 -201.643357) (xy 228.368608 -201.637857) (xy 228.364034 -201.635868)
			(xy 228.326442 -201.62012) (xy 228.313996 -201.62139) (xy 228.279452 -201.622914) (xy 228.279198 -201.622914)
			(xy 228.251946 -201.622428) (xy 228.197998 -201.614671) (xy 228.145703 -201.599316) (xy 228.096125 -201.576674)
			(xy 228.050274 -201.547207) (xy 228.009083 -201.511515) (xy 227.973392 -201.470324) (xy 227.943925 -201.424473)
			(xy 227.921284 -201.374895) (xy 227.905928 -201.3226) (xy 227.898172 -201.268652) (xy 227.898172 -201.214148)
			(xy 227.905928 -201.1602) (xy 227.921284 -201.107905) (xy 227.943925 -201.058327) (xy 227.973392 -201.012476)
			(xy 228.009083 -200.971285) (xy 228.050274 -200.935593) (xy 228.096125 -200.906126) (xy 228.145703 -200.883484)
			(xy 228.197998 -200.868129) (xy 228.251946 -200.860372) (xy 228.279198 -200.859898) (xy 228.307091 -200.860405)
			(xy 228.362285 -200.868519) (xy 228.415711 -200.884575) (xy 228.466234 -200.908232) (xy 228.512778 -200.938985)
			(xy 228.554354 -200.976181) (xy 228.572568 -200.997312) (xy 228.572822 -200.997566) (xy 228.576873 -201.00207)
			(xy 228.586626 -201.009251) (xy 228.592126 -201.01179) (xy 228.688392 -201.051668) (xy 228.705789 -201.059189)
			(xy 228.738892 -201.077648) (xy 228.754432 -201.088498) (xy 228.759258 -201.0918) (xy 228.845364 -201.127614)
			(xy 228.8667 -201.136504) (xy 228.895602 -201.149288) (xy 228.948174 -201.184342) (xy 228.971094 -201.2061)
			(xy 230.03637 -202.271376) (xy 230.05818 -202.294254) (xy 230.093239 -202.346837) (xy 230.105966 -202.37577)
			(xy 230.143304 -202.465432) (xy 230.145312 -202.469995) (xy 230.150814 -202.478307) (xy 230.154226 -202.481942)
			(xy 230.218234 -202.545696) (xy 230.23334 -202.561318) (xy 230.25978 -202.595804) (xy 230.281496 -202.633444)
			(xy 230.290116 -202.653392) (xy 230.501952 -203.16444) (xy 230.503959 -203.169004) (xy 230.509457 -203.177319)
			(xy 230.512874 -203.18095) (xy 231.869742 -204.537818) (xy 231.891551 -204.560696) (xy 231.926607 -204.613282)
			(xy 231.939338 -204.642212) (xy 232.377234 -205.699106) (xy 232.377488 -205.699614) (xy 232.37952 -205.705202)
			(xy 232.380282 -205.706726) (xy 232.384854 -205.717648) (xy 232.388664 -205.728062) (xy 232.394252 -205.746858)
			(xy 232.394252 -205.748382) (xy 232.39603 -205.754732) (xy 232.401618 -205.780894) (xy 232.401618 -205.781402)
			(xy 232.402126 -205.784958) (xy 232.40492 -205.812898) (xy 232.405428 -205.822804) (xy 232.413556 -205.84033)
			(xy 232.420668 -205.847188) (xy 232.427958 -205.853474) (xy 232.445848 -205.860536) (xy 232.455466 -205.860904)
			(xy 232.55605 -205.860904) (xy 232.557828 -205.86065) (xy 232.563416 -205.860396) (xy 232.789476 -205.860396)
			(xy 232.799382 -205.856078) (xy 232.80116 -205.855316) (xy 232.825798 -205.843632) (xy 232.827068 -205.84287)
			(xy 232.833672 -205.83525) (xy 233.19486 -204.01915) (xy 233.195876 -204.009244) (xy 233.195876 -203.270358)
			(xy 233.195785 -203.265339) (xy 233.193865 -203.255487) (xy 233.192066 -203.2508) (xy 232.999788 -202.78725)
			(xy 232.997782 -202.782685) (xy 232.992285 -202.774368) (xy 232.988866 -202.77074) (xy 232.743502 -202.525376)
			(xy 232.72496 -202.517756) (xy 232.716832 -202.517756) (xy 232.709466 -202.518264) (xy 232.699306 -202.520042)
			(xy 232.691178 -202.522328) (xy 232.664 -202.53198) (xy 232.663492 -202.53198) (xy 232.620566 -202.54722)
			(xy 232.613835 -202.549825) (xy 232.602086 -202.558198) (xy 232.597452 -202.56373) (xy 232.593134 -202.569064)
			(xy 232.5878 -202.58278) (xy 232.587292 -202.590146) (xy 232.584178 -202.618194) (xy 232.570742 -202.673002)
			(xy 232.549377 -202.725232) (xy 232.520549 -202.773745) (xy 232.484888 -202.81748) (xy 232.443173 -202.855484)
			(xy 232.396314 -202.886927) (xy 232.345333 -202.911123) (xy 232.291343 -202.927543) (xy 232.235524 -202.93583)
			(xy 232.207308 -202.936348) (xy 232.179541 -202.935848) (xy 232.124595 -202.927796) (xy 232.071397 -202.911862)
			(xy 232.021071 -202.888383) (xy 231.974682 -202.857854) (xy 231.933211 -202.820921) (xy 231.897533 -202.778364)
			(xy 231.868403 -202.731084) (xy 231.846437 -202.68008) (xy 231.838754 -202.653392) (xy 231.83723 -202.648312)
			(xy 231.832487 -202.637586) (xy 231.815286 -202.621682) (xy 231.80421 -202.617832) (xy 231.802432 -202.617324)
			(xy 231.790748 -202.614276) (xy 231.789732 -202.614022) (xy 231.728518 -202.597004) (xy 231.72801 -202.597004)
			(xy 231.718866 -202.594464) (xy 231.712303 -202.592848) (xy 231.698792 -202.59273) (xy 231.692196 -202.59421)
			(xy 231.685886 -202.596041) (xy 231.674433 -202.60247) (xy 231.66959 -202.60691) (xy 231.669336 -202.607164)
			(xy 231.647771 -202.627686) (xy 231.599458 -202.662462) (xy 231.546331 -202.689314) (xy 231.489679 -202.707592)
			(xy 231.430876 -202.716852) (xy 231.401112 -202.7174) (xy 231.388374 -202.717322) (xy 231.362953 -202.71567)
			(xy 231.350312 -202.714098) (xy 231.324533 -202.71018) (xy 231.274282 -202.69626) (xy 231.226392 -202.675636)
			(xy 231.18175 -202.648691) (xy 231.141188 -202.615926) (xy 231.122982 -202.597258) (xy 231.104997 -202.577476)
			(xy 231.074181 -202.533789) (xy 231.049784 -202.486218) (xy 231.032287 -202.4357) (xy 231.026716 -202.409552)
			(xy 231.026716 -202.409298) (xy 231.02518 -202.402613) (xy 231.018989 -202.390376) (xy 231.014524 -202.385168)
			(xy 231.009952 -202.380088) (xy 230.998776 -202.372976) (xy 230.98506 -202.368658) (xy 230.983536 -202.367896)
			(xy 230.908098 -202.343512) (xy 230.901535 -202.3416) (xy 230.887886 -202.34095) (xy 230.881174 -202.342242)
			(xy 230.874776 -202.343938) (xy 230.863071 -202.35011) (xy 230.85806 -202.354434) (xy 230.857806 -202.354688)
			(xy 230.836509 -202.373777) (xy 230.789272 -202.406018) (xy 230.737754 -202.430853) (xy 230.68311 -202.447729)
			(xy 230.626559 -202.456267) (xy 230.597964 -202.456796) (xy 230.570715 -202.456307) (xy 230.516773 -202.448547)
			(xy 230.464485 -202.433189) (xy 230.414913 -202.410547) (xy 230.369069 -202.38108) (xy 230.327884 -202.34539)
			(xy 230.292198 -202.304202) (xy 230.262736 -202.258355) (xy 230.240098 -202.208782) (xy 230.224745 -202.156492)
			(xy 230.21699 -202.102549) (xy 230.21699 -202.048051) (xy 230.224745 -201.994108) (xy 230.240098 -201.941818)
			(xy 230.262736 -201.892245) (xy 230.292198 -201.846398) (xy 230.327884 -201.80521) (xy 230.369069 -201.76952)
			(xy 230.414913 -201.740053) (xy 230.464485 -201.717411) (xy 230.516773 -201.702053) (xy 230.570715 -201.694293)
			(xy 230.597964 -201.69378) (xy 230.626958 -201.694317) (xy 230.684278 -201.703087) (xy 230.739612 -201.72043)
			(xy 230.791683 -201.745948) (xy 230.839294 -201.779051) (xy 230.881346 -201.818977) (xy 230.916872 -201.864808)
			(xy 230.931466 -201.889868) (xy 230.935276 -201.896726) (xy 230.947893 -201.921582) (xy 230.966514 -201.97412)
			(xy 230.97236 -202.001374) (xy 230.97236 -202.001628) (xy 230.973981 -202.008378) (xy 230.98029 -202.020739)
			(xy 230.984806 -202.026012) (xy 230.989418 -202.030823) (xy 231.000611 -202.038045) (xy 231.006904 -202.040236)
			(xy 231.014016 -202.042522) (xy 231.01554 -202.043284) (xy 231.090978 -202.067668) (xy 231.097541 -202.069584)
			(xy 231.111191 -202.07024) (xy 231.117902 -202.068938) (xy 231.124301 -202.067244) (xy 231.136008 -202.061074)
			(xy 231.141016 -202.056746) (xy 231.14127 -202.056492) (xy 231.162567 -202.037402) (xy 231.209804 -202.00516)
			(xy 231.261321 -201.980323) (xy 231.315966 -201.963445) (xy 231.372516 -201.954904) (xy 231.401112 -201.954384)
			(xy 231.429195 -201.954876) (xy 231.484756 -201.963095) (xy 231.538512 -201.97937) (xy 231.589302 -202.003348)
			(xy 231.636028 -202.034512) (xy 231.677683 -202.072188) (xy 231.713365 -202.115563) (xy 231.742304 -202.163699)
			(xy 231.763875 -202.215557) (xy 231.77119 -202.242674) (xy 231.774048 -202.252227) (xy 231.785808 -202.268305)
			(xy 231.79405 -202.273916) (xy 231.809798 -202.283314) (xy 231.82326 -202.282298) (xy 231.828232 -202.281773)
			(xy 231.838208 -202.282413) (xy 231.843072 -202.283568) (xy 231.855772 -202.287124) (xy 231.889808 -202.296522)
			(xy 231.903016 -202.2983) (xy 231.903524 -202.2983) (xy 231.913332 -202.297794) (xy 231.931482 -202.29034)
			(xy 231.93883 -202.283822) (xy 231.939338 -202.283314) (xy 231.940354 -202.282298) (xy 231.940862 -202.28179)
			(xy 231.959988 -202.26374) (xy 232.0023 -202.232507) (xy 232.02519 -202.21956) (xy 232.031286 -202.216258)
			(xy 232.036366 -202.211432) (xy 232.043962 -202.203471) (xy 232.052137 -202.183065) (xy 232.052114 -202.172062)
			(xy 232.049574 -202.121008) (xy 232.047542 -202.080876) (xy 232.046649 -202.071325) (xy 232.038732 -202.053867)
			(xy 232.024979 -202.040514) (xy 232.0163 -202.036426) (xy 229.244144 -200.888092) (xy 228.801168 -200.70445)
			(xy 228.79648 -200.702656) (xy 228.786628 -200.700746) (xy 228.78161 -200.70064) (xy 228.213666 -200.70064)
			(xy 228.209458 -200.700724) (xy 228.20116 -200.702134) (xy 228.197156 -200.703434) (xy 228.186488 -200.707498)
			(xy 228.184456 -200.70826) (xy 228.14534 -200.724516) (xy 227.918772 -200.818242) (xy 227.844604 -200.848976)
			(xy 227.842318 -200.849992) (xy 226.260914 -201.598022) (xy 226.255372 -201.600825) (xy 226.245743 -201.608665)
			(xy 226.241864 -201.613516) (xy 226.223722 -201.636714) (xy 226.181505 -201.677768) (xy 226.133483 -201.711852)
			(xy 226.080795 -201.738155) (xy 226.024693 -201.756053) (xy 225.966508 -201.765123) (xy 225.937064 -201.765662)
			(xy 225.909814 -201.765196) (xy 225.855869 -201.757435) (xy 225.803579 -201.742075) (xy 225.754006 -201.71943)
			(xy 225.708161 -201.68996) (xy 225.666976 -201.654266) (xy 225.631291 -201.613074) (xy 225.601831 -201.567222)
			(xy 225.579196 -201.517645) (xy 225.563848 -201.46535) (xy 225.556098 -201.411404) (xy 225.555556 -201.384154)
			(xy 225.556044 -201.356915) (xy 225.563799 -201.302993) (xy 225.579145 -201.250722) (xy 225.60177 -201.201165)
			(xy 225.631213 -201.15533) (xy 225.666877 -201.114149) (xy 225.708035 -201.07846) (xy 225.753851 -201.048987)
			(xy 225.803393 -201.02633) (xy 225.855654 -201.010951) (xy 225.909572 -201.003162) (xy 225.93681 -201.002646)
			(xy 225.937318 -201.002646) (xy 225.95332 -201.0029) (xy 225.965766 -201.003408) (xy 227.670614 -200.196958)
			(xy 227.6856 -200.190354) (xy 228.027992 -200.048622) (xy 228.048124 -200.040675) (xy 228.089933 -200.029481)
			(xy 228.132843 -200.023829) (xy 228.154484 -200.023476) (xy 228.85146 -200.023476) (xy 228.8731 -200.023841)
			(xy 228.91601 -200.029493) (xy 228.957823 -200.040669) (xy 228.977952 -200.048622) (xy 230.016379 -200.478644)
			(xy 239.057686 -200.478644) (xy 239.061757 -200.423022) (xy 239.073883 -200.368585) (xy 239.093806 -200.316494)
			(xy 239.121102 -200.267859) (xy 239.155188 -200.223716) (xy 239.195337 -200.185007) (xy 239.240695 -200.152556)
			(xy 239.290295 -200.127055) (xy 239.343079 -200.109048) (xy 239.397922 -200.098918) (xy 239.453656 -200.096881)
			(xy 239.509093 -200.102981) (xy 239.56305 -200.117087) (xy 239.614379 -200.138899) (xy 239.661985 -200.167953)
			(xy 239.704853 -200.203628) (xy 239.74207 -200.245165) (xy 239.772843 -200.291678) (xy 239.796515 -200.342175)
			(xy 239.812583 -200.395582) (xy 239.820703 -200.450758) (xy 239.821212 -200.478644) (xy 239.820864 -200.497694)
			(xy 241.038632 -200.497694) (xy 241.042703 -200.442072) (xy 241.054829 -200.387635) (xy 241.074752 -200.335544)
			(xy 241.102048 -200.286909) (xy 241.136134 -200.242766) (xy 241.176283 -200.204057) (xy 241.221641 -200.171606)
			(xy 241.271241 -200.146105) (xy 241.324025 -200.128098) (xy 241.378868 -200.117968) (xy 241.434602 -200.115931)
			(xy 241.490039 -200.122031) (xy 241.543996 -200.136137) (xy 241.595325 -200.157949) (xy 241.642931 -200.187003)
			(xy 241.685799 -200.222678) (xy 241.723016 -200.264215) (xy 241.753789 -200.310728) (xy 241.777461 -200.361225)
			(xy 241.789709 -200.401936) (xy 242.245132 -200.401936) (xy 242.249203 -200.346314) (xy 242.261329 -200.291877)
			(xy 242.281252 -200.239786) (xy 242.308548 -200.191151) (xy 242.342634 -200.147008) (xy 242.382783 -200.108299)
			(xy 242.428141 -200.075848) (xy 242.477741 -200.050347) (xy 242.530525 -200.03234) (xy 242.585368 -200.02221)
			(xy 242.641102 -200.020173) (xy 242.661886 -200.02246) (xy 250.416058 -200.02246) (xy 250.420129 -199.966838)
			(xy 250.432255 -199.912401) (xy 250.452178 -199.86031) (xy 250.479474 -199.811675) (xy 250.51356 -199.767532)
			(xy 250.553709 -199.728823) (xy 250.599067 -199.696372) (xy 250.648667 -199.670871) (xy 250.701451 -199.652864)
			(xy 250.756294 -199.642734) (xy 250.812028 -199.640697) (xy 250.867465 -199.646797) (xy 250.921422 -199.660903)
			(xy 250.972751 -199.682715) (xy 251.020357 -199.711769) (xy 251.063225 -199.747444) (xy 251.100442 -199.788981)
			(xy 251.131215 -199.835494) (xy 251.154887 -199.885991) (xy 251.170955 -199.939398) (xy 251.179075 -199.994574)
			(xy 251.179584 -200.02246) (xy 251.179075 -200.050346) (xy 251.170955 -200.105522) (xy 251.154887 -200.158929)
			(xy 251.131215 -200.209426) (xy 251.100442 -200.255939) (xy 251.063225 -200.297476) (xy 251.020357 -200.333151)
			(xy 250.972751 -200.362205) (xy 250.921422 -200.384017) (xy 250.867465 -200.398123) (xy 250.812028 -200.404223)
			(xy 250.756294 -200.402186) (xy 250.701451 -200.392056) (xy 250.648667 -200.374049) (xy 250.599067 -200.348548)
			(xy 250.553709 -200.316097) (xy 250.51356 -200.277388) (xy 250.479474 -200.233245) (xy 250.452178 -200.18461)
			(xy 250.432255 -200.132519) (xy 250.420129 -200.078082) (xy 250.416058 -200.02246) (xy 242.661886 -200.02246)
			(xy 242.696539 -200.026273) (xy 242.750496 -200.040379) (xy 242.801825 -200.062191) (xy 242.849431 -200.091245)
			(xy 242.892299 -200.12692) (xy 242.929516 -200.168457) (xy 242.960289 -200.21497) (xy 242.983961 -200.265467)
			(xy 243.000029 -200.318874) (xy 243.008149 -200.37405) (xy 243.008658 -200.401936) (xy 243.008149 -200.429822)
			(xy 243.000029 -200.484998) (xy 242.983961 -200.538405) (xy 242.960289 -200.588902) (xy 242.943667 -200.614026)
			(xy 247.569226 -200.614026) (xy 247.573297 -200.558404) (xy 247.585423 -200.503967) (xy 247.605346 -200.451876)
			(xy 247.632642 -200.403241) (xy 247.666728 -200.359098) (xy 247.706877 -200.320389) (xy 247.752235 -200.287938)
			(xy 247.801835 -200.262437) (xy 247.854619 -200.24443) (xy 247.909462 -200.2343) (xy 247.965196 -200.232263)
			(xy 248.020633 -200.238363) (xy 248.07459 -200.252469) (xy 248.125919 -200.274281) (xy 248.173525 -200.303335)
			(xy 248.216393 -200.33901) (xy 248.25361 -200.380547) (xy 248.284383 -200.42706) (xy 248.308055 -200.477557)
			(xy 248.324123 -200.530964) (xy 248.332243 -200.58614) (xy 248.332752 -200.614026) (xy 248.332243 -200.641912)
			(xy 248.324123 -200.697088) (xy 248.308055 -200.750495) (xy 248.284383 -200.800992) (xy 248.25361 -200.847505)
			(xy 248.216393 -200.889042) (xy 248.173525 -200.924717) (xy 248.125919 -200.953771) (xy 248.07459 -200.975583)
			(xy 248.020633 -200.989689) (xy 247.965196 -200.995789) (xy 247.909462 -200.993752) (xy 247.854619 -200.983622)
			(xy 247.801835 -200.965615) (xy 247.752235 -200.940114) (xy 247.706877 -200.907663) (xy 247.666728 -200.868954)
			(xy 247.632642 -200.824811) (xy 247.605346 -200.776176) (xy 247.585423 -200.724085) (xy 247.573297 -200.669648)
			(xy 247.569226 -200.614026) (xy 242.943667 -200.614026) (xy 242.929516 -200.635415) (xy 242.892299 -200.676952)
			(xy 242.849431 -200.712627) (xy 242.801825 -200.741681) (xy 242.750496 -200.763493) (xy 242.696539 -200.777599)
			(xy 242.641102 -200.783699) (xy 242.585368 -200.781662) (xy 242.530525 -200.771532) (xy 242.477741 -200.753525)
			(xy 242.428141 -200.728024) (xy 242.382783 -200.695573) (xy 242.342634 -200.656864) (xy 242.308548 -200.612721)
			(xy 242.281252 -200.564086) (xy 242.261329 -200.511995) (xy 242.249203 -200.457558) (xy 242.245132 -200.401936)
			(xy 241.789709 -200.401936) (xy 241.793529 -200.414632) (xy 241.801649 -200.469808) (xy 241.802158 -200.497694)
			(xy 241.801649 -200.52558) (xy 241.793529 -200.580756) (xy 241.777461 -200.634163) (xy 241.753789 -200.68466)
			(xy 241.723016 -200.731173) (xy 241.685799 -200.77271) (xy 241.642931 -200.808385) (xy 241.595325 -200.837439)
			(xy 241.543996 -200.859251) (xy 241.490039 -200.873357) (xy 241.434602 -200.879457) (xy 241.378868 -200.87742)
			(xy 241.324025 -200.86729) (xy 241.271241 -200.849283) (xy 241.221641 -200.823782) (xy 241.176283 -200.791331)
			(xy 241.136134 -200.752622) (xy 241.102048 -200.708479) (xy 241.074752 -200.659844) (xy 241.054829 -200.607753)
			(xy 241.042703 -200.553316) (xy 241.038632 -200.497694) (xy 239.820864 -200.497694) (xy 239.820703 -200.50653)
			(xy 239.812583 -200.561706) (xy 239.796515 -200.615113) (xy 239.772843 -200.66561) (xy 239.74207 -200.712123)
			(xy 239.704853 -200.75366) (xy 239.661985 -200.789335) (xy 239.614379 -200.818389) (xy 239.56305 -200.840201)
			(xy 239.509093 -200.854307) (xy 239.453656 -200.860407) (xy 239.397922 -200.85837) (xy 239.343079 -200.84824)
			(xy 239.290295 -200.830233) (xy 239.240695 -200.804732) (xy 239.195337 -200.772281) (xy 239.155188 -200.733572)
			(xy 239.121102 -200.689429) (xy 239.093806 -200.640794) (xy 239.073883 -200.588703) (xy 239.061757 -200.534266)
			(xy 239.057686 -200.478644) (xy 230.016379 -200.478644) (xy 232.718864 -201.597768) (xy 232.738815 -201.606383)
			(xy 232.776463 -201.628089) (xy 232.81095 -201.654531) (xy 232.82656 -201.66965) (xy 233.353864 -202.196954)
			(xy 240.818668 -202.196954) (xy 240.822739 -202.141332) (xy 240.834865 -202.086895) (xy 240.854788 -202.034804)
			(xy 240.882084 -201.986169) (xy 240.91617 -201.942026) (xy 240.956319 -201.903317) (xy 241.001677 -201.870866)
			(xy 241.051277 -201.845365) (xy 241.104061 -201.827358) (xy 241.158904 -201.817228) (xy 241.214638 -201.815191)
			(xy 241.270075 -201.821291) (xy 241.324032 -201.835397) (xy 241.375361 -201.857209) (xy 241.422967 -201.886263)
			(xy 241.465835 -201.921938) (xy 241.503052 -201.963475) (xy 241.533825 -202.009988) (xy 241.557497 -202.060485)
			(xy 241.573565 -202.113892) (xy 241.581685 -202.169068) (xy 241.582194 -202.196954) (xy 241.581685 -202.22484)
			(xy 241.573565 -202.280016) (xy 241.557497 -202.333423) (xy 241.533825 -202.38392) (xy 241.503052 -202.430433)
			(xy 241.465835 -202.47197) (xy 241.422967 -202.507645) (xy 241.375361 -202.536699) (xy 241.324032 -202.558511)
			(xy 241.270075 -202.572617) (xy 241.214638 -202.578717) (xy 241.158904 -202.57668) (xy 241.104061 -202.56655)
			(xy 241.051277 -202.548543) (xy 241.001677 -202.523042) (xy 240.956319 -202.490591) (xy 240.91617 -202.451882)
			(xy 240.882084 -202.407739) (xy 240.854788 -202.359104) (xy 240.834865 -202.307013) (xy 240.822739 -202.252576)
			(xy 240.818668 -202.196954) (xy 233.353864 -202.196954) (xy 233.512106 -202.355196) (xy 233.527209 -202.37082)
			(xy 233.553644 -202.405308) (xy 233.575356 -202.44295) (xy 233.583988 -202.462892) (xy 233.834178 -203.067158)
			(xy 233.835702 -203.070968) (xy 233.844338 -203.09205) (xy 233.852466 -203.096368) (xy 233.858054 -203.098654)
			(xy 233.89844 -203.10729) (xy 233.943906 -203.117196) (xy 233.951526 -203.117704) (xy 233.963464 -203.117704)
			(xy 233.981244 -203.110592) (xy 233.98861 -203.10348) (xy 234.008759 -203.08478) (xy 234.053098 -203.052284)
			(xy 234.077002 -203.03871) (xy 234.102954 -203.025117) (xy 234.157796 -203.004515) (xy 234.214975 -202.991762)
			(xy 234.244134 -202.988926) (xy 234.255056 -202.98791) (xy 234.2642 -202.983084) (xy 234.268894 -202.980319)
			(xy 234.277093 -202.973147) (xy 234.280456 -202.96886) (xy 234.284012 -202.964288) (xy 234.285536 -202.961748)
			(xy 234.297982 -202.94092) (xy 234.29976 -202.937872) (xy 234.302311 -202.932501) (xy 234.305139 -202.920954)
			(xy 234.305348 -202.915012) (xy 234.305348 -202.89266) (xy 234.302554 -202.884532) (xy 234.293106 -202.85513)
			(xy 234.28277 -202.794247) (xy 234.28198 -202.763374) (xy 234.28198 -202.758294) (xy 234.282636 -202.731159)
			(xy 234.290681 -202.677482) (xy 234.306252 -202.625487) (xy 234.329034 -202.576223) (xy 234.358569 -202.530685)
			(xy 234.394258 -202.489793) (xy 234.435383 -202.454371) (xy 234.481113 -202.425135) (xy 234.530525 -202.402675)
			(xy 234.582621 -202.387444) (xy 234.63635 -202.37975) (xy 234.663488 -202.379326) (xy 234.690741 -202.379789)
			(xy 234.744691 -202.387544) (xy 234.796988 -202.4029) (xy 234.846568 -202.425542) (xy 234.89242 -202.45501)
			(xy 234.933611 -202.490704) (xy 234.969303 -202.531898) (xy 234.998769 -202.577752) (xy 235.021408 -202.627332)
			(xy 235.03676 -202.679631) (xy 235.044513 -202.733581) (xy 235.044996 -202.760834) (xy 235.04488 -202.767438)
			(xy 236.651036 -202.767438) (xy 236.655107 -202.711816) (xy 236.667233 -202.657379) (xy 236.687156 -202.605288)
			(xy 236.714452 -202.556653) (xy 236.748538 -202.51251) (xy 236.788687 -202.473801) (xy 236.834045 -202.44135)
			(xy 236.883645 -202.415849) (xy 236.936429 -202.397842) (xy 236.991272 -202.387712) (xy 237.047006 -202.385675)
			(xy 237.102443 -202.391775) (xy 237.1564 -202.405881) (xy 237.207729 -202.427693) (xy 237.255335 -202.456747)
			(xy 237.298203 -202.492422) (xy 237.33542 -202.533959) (xy 237.366193 -202.580472) (xy 237.389865 -202.630969)
			(xy 237.405933 -202.684376) (xy 237.414053 -202.739552) (xy 237.414562 -202.767438) (xy 237.414053 -202.795324)
			(xy 237.405933 -202.8505) (xy 237.389865 -202.903907) (xy 237.366193 -202.954404) (xy 237.33542 -203.000917)
			(xy 237.298203 -203.042454) (xy 237.255335 -203.078129) (xy 237.207729 -203.107183) (xy 237.1564 -203.128995)
			(xy 237.102443 -203.143101) (xy 237.047006 -203.149201) (xy 236.991272 -203.147164) (xy 236.936429 -203.137034)
			(xy 236.883645 -203.119027) (xy 236.834045 -203.093526) (xy 236.788687 -203.061075) (xy 236.748538 -203.022366)
			(xy 236.714452 -202.978223) (xy 236.687156 -202.929588) (xy 236.667233 -202.877497) (xy 236.655107 -202.82306)
			(xy 236.651036 -202.767438) (xy 235.04488 -202.767438) (xy 235.044517 -202.788044) (xy 235.036791 -202.841912)
			(xy 235.021487 -202.894134) (xy 234.998915 -202.943652) (xy 234.969534 -202.989458) (xy 234.933941 -203.030623)
			(xy 234.892858 -203.06631) (xy 234.847119 -203.095796) (xy 234.797653 -203.118481) (xy 234.745466 -203.133905)
			(xy 234.718606 -203.138278) (xy 234.716066 -203.138786) (xy 234.708446 -203.140564) (xy 234.699851 -203.14378)
			(xy 234.685534 -203.155239) (xy 234.680506 -203.162916) (xy 234.656884 -203.20254) (xy 234.656122 -203.214986)
			(xy 234.65536 -203.22667) (xy 234.66044 -203.23937) (xy 234.660694 -203.240132) (xy 234.661456 -203.242164)
			(xy 234.661964 -203.24318) (xy 234.672419 -203.268953) (xy 234.687188 -203.322573) (xy 234.694713 -203.377679)
			(xy 234.695238 -203.405486) (xy 234.694807 -203.430886) (xy 235.308646 -203.430886) (xy 235.312717 -203.375264)
			(xy 235.324843 -203.320827) (xy 235.344766 -203.268736) (xy 235.372062 -203.220101) (xy 235.406148 -203.175958)
			(xy 235.446297 -203.137249) (xy 235.491655 -203.104798) (xy 235.541255 -203.079297) (xy 235.594039 -203.06129)
			(xy 235.648882 -203.05116) (xy 235.704616 -203.049123) (xy 235.760053 -203.055223) (xy 235.81401 -203.069329)
			(xy 235.865339 -203.091141) (xy 235.912945 -203.120195) (xy 235.955813 -203.15587) (xy 235.99303 -203.197407)
			(xy 236.023803 -203.24392) (xy 236.047475 -203.294417) (xy 236.063543 -203.347824) (xy 236.071663 -203.403)
			(xy 236.072172 -203.430886) (xy 236.071663 -203.458772) (xy 236.063543 -203.513948) (xy 236.047475 -203.567355)
			(xy 236.023803 -203.617852) (xy 235.99303 -203.664365) (xy 235.955813 -203.705902) (xy 235.912945 -203.741577)
			(xy 235.865339 -203.770631) (xy 235.81401 -203.792443) (xy 235.760053 -203.806549) (xy 235.704616 -203.812649)
			(xy 235.648882 -203.810612) (xy 235.594039 -203.800482) (xy 235.541255 -203.782475) (xy 235.491655 -203.756974)
			(xy 235.446297 -203.724523) (xy 235.406148 -203.685814) (xy 235.372062 -203.641671) (xy 235.344766 -203.593036)
			(xy 235.324843 -203.540945) (xy 235.312717 -203.486508) (xy 235.308646 -203.430886) (xy 234.694807 -203.430886)
			(xy 234.694732 -203.435334) (xy 234.686238 -203.494424) (xy 234.669421 -203.551703) (xy 234.644624 -203.606006)
			(xy 234.612351 -203.656227) (xy 234.573259 -203.701344) (xy 234.528144 -203.740438) (xy 234.477925 -203.772714)
			(xy 234.423624 -203.797514) (xy 234.366345 -203.814333) (xy 234.307256 -203.82283) (xy 234.277408 -203.823316)
			(xy 234.277154 -203.823316) (xy 234.250291 -203.8229) (xy 234.197007 -203.816015) (xy 234.145043 -203.802365)
			(xy 234.095254 -203.782174) (xy 234.048461 -203.755774) (xy 234.02671 -203.740004) (xy 234.024932 -203.738734)
			(xy 234.019852 -203.734924) (xy 234.001564 -203.728828) (xy 233.996635 -203.727302) (xy 233.986398 -203.726027)
			(xy 233.981244 -203.726288) (xy 233.976213 -203.726848) (xy 233.966489 -203.729655) (xy 233.96194 -203.731876)
			(xy 233.9213 -203.752958) (xy 233.913251 -203.757557) (xy 233.900891 -203.771353) (xy 233.894277 -203.788655)
			(xy 233.893868 -203.797916) (xy 233.893868 -203.8223) (xy 233.893707 -203.838088) (xy 233.890655 -203.869515)
			(xy 233.887772 -203.885038) (xy 233.86034 -204.023722) (xy 233.859324 -204.033628) (xy 233.859324 -204.047344)
			(xy 233.859133 -204.063581) (xy 233.855951 -204.095897) (xy 233.852974 -204.11186) (xy 233.51744 -205.799436)
			(xy 233.51744 -205.810104) (xy 233.517818 -205.819214) (xy 233.524199 -205.836279) (xy 233.536153 -205.850029)
			(xy 233.552164 -205.858723) (xy 233.561128 -205.860396) (xy 233.73969 -205.860396) (xy 233.748768 -205.860035)
			(xy 233.765779 -205.853693) (xy 233.779476 -205.841777) (xy 233.78414 -205.83398) (xy 233.785918 -205.83017)
			(xy 233.798173 -205.803944) (xy 233.82942 -205.755216) (xy 233.848148 -205.733142) (xy 233.866521 -205.712945)
			(xy 233.908045 -205.677492) (xy 233.954198 -205.64832) (xy 234.004039 -205.626027) (xy 234.056549 -205.611066)
			(xy 234.110656 -205.603744) (xy 234.165254 -205.604211) (xy 234.219227 -205.612456) (xy 234.271474 -205.628311)
			(xy 234.320927 -205.651453) (xy 234.366576 -205.681409) (xy 234.407487 -205.717566) (xy 234.442827 -205.759186)
			(xy 234.471872 -205.80542) (xy 234.483402 -205.83017) (xy 234.48645 -205.837282) (xy 234.495848 -205.848204)
			(xy 234.501944 -205.852268) (xy 234.508225 -205.85606) (xy 234.522296 -205.86019) (xy 234.52963 -205.860396)
			(xy 237.972346 -205.860396) (xy 237.985046 -205.858872) (xy 237.995675 -205.855501) (xy 238.012809 -205.841273)
			(xy 238.018066 -205.83144) (xy 238.027718 -205.81112) (xy 238.057182 -205.748636) (xy 238.060785 -205.74017)
			(xy 238.062322 -205.721849) (xy 238.057284 -205.704168) (xy 238.052102 -205.696566) (xy 238.05007 -205.69428)
			(xy 238.049308 -205.693518) (xy 238.048546 -205.692502) (xy 238.046768 -205.69047) (xy 238.044736 -205.68793)
			(xy 238.044482 -205.687676) (xy 238.04372 -205.68666) (xy 238.04245 -205.685136) (xy 238.027124 -205.664898)
			(xy 238.001386 -205.62114) (xy 237.981673 -205.574359) (xy 237.968331 -205.525378) (xy 237.961595 -205.475061)
			(xy 237.96117 -205.449678) (xy 237.96117 -205.449424) (xy 237.961631 -205.422169) (xy 237.969385 -205.368215)
			(xy 237.984739 -205.315913) (xy 238.00738 -205.266328) (xy 238.036847 -205.22047) (xy 238.07254 -205.179273)
			(xy 238.113733 -205.143575) (xy 238.159588 -205.114102) (xy 238.209169 -205.091455) (xy 238.26147 -205.076095)
			(xy 238.315423 -205.068334) (xy 238.342678 -205.067916) (xy 238.369713 -205.068385) (xy 238.423242 -205.076014)
			(xy 238.475158 -205.091124) (xy 238.524422 -205.113411) (xy 238.570046 -205.142429) (xy 238.611116 -205.177597)
			(xy 238.646811 -205.21821) (xy 238.676416 -205.263456) (xy 238.699337 -205.312427) (xy 238.715115 -205.364144)
			(xy 238.723435 -205.41757) (xy 238.724186 -205.444598) (xy 238.724186 -205.450186) (xy 238.723424 -205.477364)
			(xy 238.722662 -205.490064) (xy 238.741204 -205.531466) (xy 238.741712 -205.540864) (xy 238.741824 -205.550099)
			(xy 238.736216 -205.56768) (xy 238.73079 -205.575154) (xy 238.644176 -205.683612) (xy 238.641382 -205.686914)
			(xy 238.640874 -205.687422) (xy 238.639096 -205.689454) (xy 238.637064 -205.692248) (xy 238.633508 -205.696312)
			(xy 238.628936 -205.70571) (xy 238.62538 -205.715616) (xy 238.62538 -205.731364) (xy 238.625524 -205.736947)
			(xy 238.627956 -205.747843) (xy 238.630206 -205.752954) (xy 238.657638 -205.81112) (xy 238.66729 -205.83144)
			(xy 238.672577 -205.841248) (xy 238.689699 -205.855471) (xy 238.70031 -205.858872) (xy 238.71301 -205.860396)
			(xy 239.616742 -205.860396) (xy 239.625725 -205.860046) (xy 239.642579 -205.853828) (xy 239.656227 -205.842145)
			(xy 239.660938 -205.834488) (xy 239.664494 -205.828138) (xy 239.703864 -205.751684) (xy 239.705134 -205.747874)
			(xy 239.705642 -205.746096) (xy 239.708942 -205.734324) (xy 239.705354 -205.710179) (xy 239.698784 -205.699868)
			(xy 239.697514 -205.698344) (xy 239.69599 -205.696312) (xy 239.689386 -205.686406) (xy 239.683798 -205.677262)
			(xy 239.670369 -205.654627) (xy 239.649189 -205.606448) (xy 239.634847 -205.55581) (xy 239.627616 -205.503679)
			(xy 239.627156 -205.477364) (xy 239.627156 -205.471776) (xy 239.628002 -205.444775) (xy 239.636369 -205.391406)
			(xy 239.652181 -205.33975) (xy 239.675122 -205.290843) (xy 239.704733 -205.24566) (xy 239.740422 -205.205107)
			(xy 239.781475 -205.169994) (xy 239.827071 -205.141024) (xy 239.876298 -205.118776) (xy 239.928171 -205.103696)
			(xy 239.981653 -205.096084) (xy 240.008664 -205.095602) (xy 240.036097 -205.096082) (xy 240.090398 -205.103947)
			(xy 240.143012 -205.119506) (xy 240.192857 -205.142438) (xy 240.238905 -205.172271) (xy 240.280207 -205.208389)
			(xy 240.315912 -205.250049) (xy 240.345283 -205.296392) (xy 240.367717 -205.346463) (xy 240.375694 -205.372716)
			(xy 240.376456 -205.375002) (xy 240.381211 -205.386831) (xy 240.399866 -205.404161) (xy 240.412016 -205.408022)
			(xy 240.451132 -205.418182) (xy 240.499392 -205.430628) (xy 240.511815 -205.432364) (xy 240.535778 -205.425039)
			(xy 240.545112 -205.416658) (xy 241.112548 -204.849222) (xy 241.12347 -204.84084) (xy 241.129312 -204.837538)
			(xy 242.604036 -203.362814) (xy 242.617498 -203.350114) (xy 242.620038 -203.347828) (xy 242.682268 -203.285598)
			(xy 242.683792 -203.284328) (xy 242.686586 -203.281534) (xy 242.69573 -203.277724) (xy 242.70047 -203.275856)
			(xy 242.71045 -203.273815) (xy 242.715542 -203.27366) (xy 242.81003 -203.27366) (xy 242.819428 -203.273152)
			(xy 242.85829 -203.273152) (xy 242.870482 -203.271628) (xy 242.87917 -203.269101) (xy 242.894137 -203.258957)
			(xy 242.899692 -203.251816) (xy 242.905026 -203.24191) (xy 242.917218 -203.212954) (xy 242.922552 -203.200254)
			(xy 242.9256 -203.190856) (xy 242.92687 -203.184252) (xy 242.927124 -203.183744) (xy 242.927124 -203.182728)
			(xy 242.928092 -203.176142) (xy 242.926925 -203.162887) (xy 242.924838 -203.156566) (xy 242.923568 -203.153518)
			(xy 242.914932 -203.133706) (xy 242.908074 -203.126848) (xy 242.889071 -203.107286) (xy 242.855825 -203.064053)
			(xy 242.828515 -203.016845) (xy 242.807609 -202.966473) (xy 242.793467 -202.9138) (xy 242.78633 -202.859731)
			(xy 242.7859 -202.832462) (xy 242.786384 -202.804054) (xy 242.794121 -202.747767) (xy 242.80945 -202.693057)
			(xy 242.832086 -202.640944) (xy 242.861607 -202.592399) (xy 242.897463 -202.548326) (xy 242.938986 -202.509546)
			(xy 242.985404 -202.476781) (xy 243.03585 -202.450642) (xy 243.089386 -202.431615) (xy 243.145014 -202.420055)
			(xy 243.201698 -202.416178) (xy 243.258382 -202.420055) (xy 243.31401 -202.431615) (xy 243.367546 -202.450642)
			(xy 243.417992 -202.476781) (xy 243.46441 -202.509546) (xy 243.505933 -202.548326) (xy 243.541789 -202.592399)
			(xy 243.57131 -202.640944) (xy 243.593946 -202.693057) (xy 243.609275 -202.747767) (xy 243.617012 -202.804054)
			(xy 243.617496 -202.832462) (xy 243.617066 -202.859202) (xy 243.610179 -202.912237) (xy 243.596552 -202.963952)
			(xy 243.576409 -203.013494) (xy 243.550084 -203.060046) (xy 243.518009 -203.10284) (xy 243.49964 -203.122276)
			(xy 243.499132 -203.122784) (xy 243.49583 -203.12634) (xy 243.484654 -203.142596) (xy 243.482622 -203.147168)
			(xy 243.479574 -203.15301) (xy 243.477303 -203.158056) (xy 243.474739 -203.168818) (xy 243.474494 -203.174346)
			(xy 243.47424 -203.18476) (xy 243.478558 -203.195174) (xy 243.498116 -203.24191) (xy 243.49964 -203.245212)
			(xy 243.504205 -203.253392) (xy 243.518043 -203.265994) (xy 243.535494 -203.272758) (xy 243.544852 -203.273152)
			(xy 245.420388 -203.273152) (xy 245.428786 -203.271629) (xy 245.443962 -203.263838) (xy 245.450106 -203.257912)
			(xy 245.50243 -203.203048) (xy 245.507844 -203.196285) (xy 245.514216 -203.180189) (xy 245.514876 -203.171552)
			(xy 245.514876 -203.165202) (xy 245.514622 -203.163424) (xy 245.514622 -203.15936) (xy 245.514368 -203.157328)
			(xy 245.514368 -203.14666) (xy 245.514368 -203.146152) (xy 245.514926 -203.118936) (xy 245.522811 -203.065076)
			(xy 245.53827 -203.012884) (xy 245.560991 -202.963418) (xy 245.590511 -202.917684) (xy 245.626232 -202.87661)
			(xy 245.667428 -202.84103) (xy 245.713262 -202.811665) (xy 245.762805 -202.789114) (xy 245.81505 -202.773833)
			(xy 245.868937 -202.766132) (xy 245.923371 -202.766168) (xy 245.977247 -202.77394) (xy 246.029472 -202.789291)
			(xy 246.078984 -202.811909) (xy 246.12478 -202.841334) (xy 246.165928 -202.876969) (xy 246.201594 -202.918091)
			(xy 246.231054 -202.963864) (xy 246.253708 -203.01336) (xy 246.269098 -203.065573) (xy 246.276911 -203.119444)
			(xy 246.277384 -203.14666) (xy 246.277384 -203.147422) (xy 246.276876 -203.16571) (xy 246.276876 -203.16952)
			(xy 246.277242 -203.178628) (xy 246.283608 -203.195694) (xy 246.289322 -203.202794) (xy 246.323612 -203.238862)
			(xy 246.341138 -203.257404) (xy 246.342154 -203.25842) (xy 246.349509 -203.265074) (xy 246.367809 -203.272667)
			(xy 246.377714 -203.273152) (xy 247.745758 -203.273152) (xy 247.75795 -203.27366) (xy 248.668794 -203.27366)
			(xy 248.680986 -203.273152) (xy 250.024646 -203.273152) (xy 250.034044 -203.27366) (xy 250.702826 -203.27366)
			(xy 250.71324 -203.273152) (xy 250.838208 -203.273152) (xy 250.839732 -203.27366) (xy 250.88342 -203.27366)
			(xy 250.888516 -203.273775) (xy 250.8985 -203.275827) (xy 250.903232 -203.277724) (xy 250.912376 -203.281534)
			(xy 250.91517 -203.284328) (xy 250.916694 -203.285598) (xy 250.949206 -203.31811) (xy 250.95327 -203.319634)
			(xy 250.996196 -203.364084) (xy 250.996704 -203.364592) (xy 252.531118 -204.899006) (xy 252.543818 -204.912468)
			(xy 252.546104 -204.915008) (xy 252.567948 -204.936852) (xy 252.575568 -204.943202) (xy 252.579378 -204.945488)
			(xy 252.584458 -204.948028) (xy 252.593188 -204.951212) (xy 252.611747 -204.951775) (xy 252.629297 -204.945714)
			(xy 252.643555 -204.933819) (xy 252.648466 -204.92593) (xy 252.651718 -204.919564) (xy 252.654947 -204.905645)
			(xy 252.654816 -204.898498) (xy 252.654054 -204.884528) (xy 252.648212 -204.870558) (xy 252.648212 -204.867764)
			(xy 252.64872 -204.867256) (xy 252.64872 -183.638698) (xy 252.649619 -183.617627) (xy 252.656321 -183.575988)
			(xy 252.668509 -183.535613) (xy 252.676914 -183.51627) (xy 252.689245 -183.490768) (xy 252.721568 -183.444258)
			(xy 252.741176 -183.423814) (xy 254.318262 -181.846982) (xy 254.333456 -181.832238) (xy 254.36711 -181.80655)
			(xy 254.403912 -181.785619) (xy 254.423418 -181.777386) (xy 254.451489 -181.766911) (xy 254.510306 -181.755538)
			(xy 254.540258 -181.75478) (xy 258.104132 -181.75478) (xy 258.125759 -181.755747) (xy 258.168458 -181.762881)
			(xy 258.189222 -181.769004) (xy 258.192524 -181.77002) (xy 258.209796 -181.773068) (xy 258.217416 -181.773068)
			(xy 258.227486 -181.773493) (xy 258.246089 -181.781208) (xy 258.253484 -181.788054) (xy 258.27736 -181.81193)
			(xy 258.281678 -181.81574) (xy 258.283964 -181.817772) (xy 258.285234 -181.818788) (xy 258.285996 -181.819296)
			(xy 258.294122 -181.825511) (xy 258.309629 -181.838856) (xy 258.316984 -181.845966) (xy 259.810758 -183.339994)
			(xy 259.817849 -183.347233) (xy 259.831193 -183.362486) (xy 259.837428 -183.370474) (xy 259.837682 -183.370982)
			(xy 259.838698 -183.372252) (xy 259.845048 -183.379618) (xy 259.869178 -183.403748) (xy 259.876019 -183.411148)
			(xy 259.88374 -183.429746) (xy 259.884164 -183.439816) (xy 259.884164 -183.44769) (xy 259.886958 -183.463946)
			(xy 259.887974 -183.467248) (xy 259.894734 -183.490218) (xy 259.902012 -183.537542) (xy 259.902452 -183.561482)
			(xy 259.902452 -185.8518) (xy 262.050782 -185.8518) (xy 262.054853 -185.796178) (xy 262.066979 -185.741741)
			(xy 262.086902 -185.68965) (xy 262.114198 -185.641015) (xy 262.148284 -185.596872) (xy 262.188433 -185.558163)
			(xy 262.233791 -185.525712) (xy 262.283391 -185.500211) (xy 262.336175 -185.482204) (xy 262.391018 -185.472074)
			(xy 262.446752 -185.470037) (xy 262.502189 -185.476137) (xy 262.556146 -185.490243) (xy 262.607475 -185.512055)
			(xy 262.655081 -185.541109) (xy 262.697949 -185.576784) (xy 262.735166 -185.618321) (xy 262.765939 -185.664834)
			(xy 262.789611 -185.715331) (xy 262.805679 -185.768738) (xy 262.813799 -185.823914) (xy 262.814308 -185.8518)
			(xy 262.813799 -185.879686) (xy 262.805679 -185.934862) (xy 262.789611 -185.988269) (xy 262.765939 -186.038766)
			(xy 262.735166 -186.085279) (xy 262.697949 -186.126816) (xy 262.655081 -186.162491) (xy 262.607475 -186.191545)
			(xy 262.556146 -186.213357) (xy 262.502189 -186.227463) (xy 262.446752 -186.233563) (xy 262.391018 -186.231526)
			(xy 262.336175 -186.221396) (xy 262.283391 -186.203389) (xy 262.233791 -186.177888) (xy 262.188433 -186.145437)
			(xy 262.148284 -186.106728) (xy 262.114198 -186.062585) (xy 262.086902 -186.01395) (xy 262.066979 -185.961859)
			(xy 262.054853 -185.907422) (xy 262.050782 -185.8518) (xy 259.902452 -185.8518) (xy 259.902452 -191.6547)
			(xy 260.878564 -191.6547) (xy 260.882652 -191.56889) (xy 260.894878 -191.483857) (xy 260.915131 -191.400372)
			(xy 260.943228 -191.319189) (xy 260.978915 -191.241045) (xy 261.021869 -191.166647) (xy 261.071699 -191.096669)
			(xy 261.127956 -191.031745) (xy 261.19013 -190.972462) (xy 261.257657 -190.919357) (xy 261.329926 -190.872911)
			(xy 261.406284 -190.833546) (xy 261.486037 -190.801617) (xy 261.568464 -190.777413) (xy 261.652818 -190.761154)
			(xy 261.738336 -190.752987) (xy 261.78129 -190.752476) (xy 261.823257 -190.752953) (xy 261.906829 -190.760748)
			(xy 261.989316 -190.776271) (xy 262.070004 -190.799389) (xy 262.148197 -190.8299) (xy 262.223218 -190.867543)
			(xy 262.294418 -190.91199) (xy 262.361182 -190.962858) (xy 262.422933 -191.019708) (xy 262.479137 -191.082047)
			(xy 262.529308 -191.149336) (xy 262.573012 -191.220995) (xy 262.609872 -191.296403) (xy 262.639569 -191.374909)
			(xy 262.661845 -191.455834) (xy 262.67651 -191.538477) (xy 262.68045 -191.580262) (xy 262.681466 -191.593724)
			(xy 262.696706 -191.616076) (xy 262.799322 -191.66586) (xy 262.826246 -191.664082) (xy 262.837422 -191.656716)
			(xy 262.860872 -191.641879) (xy 262.911162 -191.618424) (xy 262.964321 -191.60251) (xy 263.019227 -191.594473)
			(xy 263.046972 -191.593978) (xy 263.047226 -191.593978) (xy 263.076379 -191.594536) (xy 263.134006 -191.603412)
			(xy 263.189611 -191.620953) (xy 263.2419 -191.64675) (xy 263.289655 -191.680203) (xy 263.331763 -191.720533)
			(xy 263.367245 -191.7668) (xy 263.381744 -191.792098) (xy 263.386824 -191.801496) (xy 263.403842 -191.81445)
			(xy 263.497314 -191.83731) (xy 263.518396 -191.8335) (xy 263.527286 -191.827658) (xy 263.550926 -191.812478)
			(xy 263.601706 -191.788451) (xy 263.655463 -191.772139) (xy 263.711033 -191.763895) (xy 263.739122 -191.763396)
			(xy 263.739376 -191.763396) (xy 263.76663 -191.76385) (xy 263.820584 -191.771604) (xy 263.872886 -191.786958)
			(xy 263.922469 -191.809599) (xy 263.968326 -191.839067) (xy 264.009522 -191.874761) (xy 264.045218 -191.915955)
			(xy 264.074689 -191.96181) (xy 264.097333 -192.011392) (xy 264.112691 -192.063692) (xy 264.120449 -192.117646)
			(xy 264.120449 -192.172154) (xy 264.112691 -192.226108) (xy 264.097333 -192.278408) (xy 264.074689 -192.32799)
			(xy 264.045218 -192.373845) (xy 264.009522 -192.415039) (xy 263.968326 -192.450733) (xy 263.922469 -192.480201)
			(xy 263.872886 -192.502842) (xy 263.820584 -192.518196) (xy 263.76663 -192.52595) (xy 263.739376 -192.526412)
			(xy 263.710223 -192.525857) (xy 263.652596 -192.516982) (xy 263.59699 -192.499441) (xy 263.544701 -192.473643)
			(xy 263.496946 -192.440189) (xy 263.454838 -192.399859) (xy 263.419356 -192.353591) (xy 263.404858 -192.328292)
			(xy 263.399778 -192.318894) (xy 263.38276 -192.30594) (xy 263.289288 -192.28308) (xy 263.268206 -192.28689)
			(xy 263.259316 -192.292732) (xy 263.235675 -192.30791) (xy 263.184895 -192.331938) (xy 263.131138 -192.348251)
			(xy 263.075569 -192.356495) (xy 263.04748 -192.356994) (xy 263.047226 -192.356994) (xy 263.017819 -192.356399)
			(xy 262.959702 -192.34737) (xy 262.903657 -192.329536) (xy 262.85101 -192.30332) (xy 262.803004 -192.269341)
			(xy 262.760777 -192.228403) (xy 262.725325 -192.181474) (xy 262.71093 -192.155826) (xy 262.704834 -192.144142)
			(xy 262.681974 -192.129664) (xy 262.581136 -192.125346) (xy 262.572422 -192.125342) (xy 262.555791 -192.13051)
			(xy 262.541827 -192.140915) (xy 262.536686 -192.147952) (xy 262.536432 -192.147952) (xy 262.536432 -192.14846)
			(xy 262.513764 -192.182237) (xy 262.463287 -192.246035) (xy 262.407273 -192.30503) (xy 262.346176 -192.358743)
			(xy 262.280491 -192.406739) (xy 262.210754 -192.448628) (xy 262.137529 -192.48407) (xy 262.06141 -192.512776)
			(xy 261.983017 -192.534515) (xy 261.902986 -192.549109) (xy 261.821966 -192.556439) (xy 261.78129 -192.556892)
			(xy 261.738336 -192.556413) (xy 261.652818 -192.548246) (xy 261.568464 -192.531987) (xy 261.486037 -192.507783)
			(xy 261.406284 -192.475854) (xy 261.329926 -192.436489) (xy 261.257657 -192.390043) (xy 261.19013 -192.336938)
			(xy 261.127956 -192.277655) (xy 261.071699 -192.212731) (xy 261.021869 -192.142753) (xy 260.978915 -192.068355)
			(xy 260.943228 -191.990211) (xy 260.915131 -191.909028) (xy 260.894878 -191.825543) (xy 260.882652 -191.74051)
			(xy 260.878564 -191.6547) (xy 259.902452 -191.6547) (xy 259.902452 -191.755522) (xy 259.902886 -191.764679)
			(xy 259.909396 -191.781803) (xy 259.921478 -191.795573) (xy 259.929376 -191.800226) (xy 259.959602 -191.816228)
			(xy 259.96011 -191.816228) (xy 259.982716 -191.827912) (xy 259.985256 -191.829182) (xy 259.990204 -191.831292)
			(xy 260.000707 -191.8336) (xy 260.006084 -191.833754) (xy 260.036056 -191.833754) (xy 260.041924 -191.833602)
			(xy 260.053345 -191.830906) (xy 260.058662 -191.82842) (xy 260.06425 -191.825626) (xy 260.06679 -191.824102)
			(xy 260.067298 -191.823848) (xy 260.067552 -191.823594) (xy 260.090344 -191.809907) (xy 260.13891 -191.788284)
			(xy 260.190008 -191.77361) (xy 260.242647 -191.766167) (xy 260.269228 -191.765682) (xy 260.269736 -191.765682)
			(xy 260.296986 -191.76617) (xy 260.350932 -191.773931) (xy 260.403223 -191.78929) (xy 260.452797 -191.811934)
			(xy 260.498644 -191.841402) (xy 260.539831 -191.877094) (xy 260.57552 -191.918284) (xy 260.604984 -191.964134)
			(xy 260.627623 -192.01371) (xy 260.642977 -192.066004) (xy 260.650732 -192.11995) (xy 260.650732 -192.17445)
			(xy 260.642977 -192.228396) (xy 260.627623 -192.28069) (xy 260.604984 -192.330266) (xy 260.57552 -192.376116)
			(xy 260.539831 -192.417306) (xy 260.498644 -192.452998) (xy 260.452797 -192.482466) (xy 260.403223 -192.50511)
			(xy 260.350932 -192.520469) (xy 260.296986 -192.52823) (xy 260.269736 -192.528698) (xy 260.269482 -192.528698)
			(xy 260.240578 -192.528147) (xy 260.183436 -192.519388) (xy 260.128271 -192.502103) (xy 260.076348 -192.476689)
			(xy 260.052312 -192.460626) (xy 260.046472 -192.456825) (xy 260.033336 -192.45219) (xy 260.026404 -192.451482)
			(xy 260.012434 -192.45072) (xy 259.959856 -192.478152) (xy 259.923788 -192.496948) (xy 259.917184 -192.503552)
			(xy 259.913882 -192.507362) (xy 259.908682 -192.514325) (xy 259.902848 -192.530684) (xy 259.902452 -192.539366)
			(xy 259.902452 -195.599304) (xy 259.901985 -195.623291) (xy 259.894675 -195.670704) (xy 259.880253 -195.716459)
			(xy 259.859055 -195.759496) (xy 259.831572 -195.798817) (xy 259.81533 -195.816474) (xy 259.79247 -195.84035)
			(xy 259.774944 -195.858892) (xy 259.768086 -195.866004) (xy 259.764276 -195.870068) (xy 259.757219 -195.877139)
			(xy 259.742347 -195.890482) (xy 259.734558 -195.896738) (xy 259.73024 -195.900548) (xy 259.720588 -195.907914)
			(xy 259.719318 -195.908676) (xy 259.71881 -195.90893) (xy 259.71627 -195.910454) (xy 259.711952 -195.912994)
			(xy 259.71119 -195.913502) (xy 259.70992 -195.914264) (xy 259.709158 -195.914772) (xy 259.700316 -195.920378)
			(xy 259.682012 -195.930543) (xy 259.672582 -195.935092) (xy 259.6261 -195.956936) (xy 259.621523 -195.958981)
			(xy 259.611797 -195.961405) (xy 259.606796 -195.961762) (xy 259.555234 -195.964302) (xy 259.554726 -195.964302)
			(xy 259.539945 -195.965564) (xy 259.511688 -195.974569) (xy 259.486577 -195.990348) (xy 259.466202 -196.011898)
			(xy 259.451857 -196.037854) (xy 259.444449 -196.066571) (xy 259.444449 -196.096228) (xy 259.451856 -196.124945)
			(xy 259.466202 -196.150902) (xy 259.486577 -196.172452) (xy 259.511688 -196.18823) (xy 259.539945 -196.197236)
			(xy 259.554726 -196.19849) (xy 259.555234 -196.19849) (xy 259.606796 -196.20103) (xy 259.611793 -196.201407)
			(xy 259.621513 -196.203839) (xy 259.6261 -196.205856) (xy 259.672582 -196.2277) (xy 259.698926 -196.240762)
			(xy 259.746611 -196.275155) (xy 259.767324 -196.296026) (xy 259.80517 -196.33565) (xy 259.805678 -196.336158)
			(xy 259.819648 -196.351144) (xy 259.835404 -196.368927) (xy 259.861938 -196.408338) (xy 259.87248 -196.42963)
			(xy 259.881919 -196.450626) (xy 259.895247 -196.494686) (xy 259.902017 -196.540218) (xy 259.902452 -196.563234)
			(xy 259.902452 -196.734684) (xy 260.878586 -196.734684) (xy 260.882552 -196.650153) (xy 260.894417 -196.566366)
			(xy 260.914075 -196.484057) (xy 260.941355 -196.403951) (xy 260.976016 -196.326752) (xy 261.017754 -196.253137)
			(xy 261.066201 -196.183754) (xy 261.120933 -196.119213) (xy 261.181469 -196.060081) (xy 261.247275 -196.006877)
			(xy 261.317775 -195.960069) (xy 261.392347 -195.920068) (xy 261.470338 -195.887226) (xy 261.551062 -195.861832)
			(xy 261.633809 -195.844109) (xy 261.717851 -195.834211) (xy 261.802452 -195.832228) (xy 261.886866 -195.838175)
			(xy 261.970353 -195.852) (xy 262.052178 -195.873583) (xy 262.131622 -195.902733) (xy 262.207988 -195.939194)
			(xy 262.280604 -195.982646) (xy 262.348832 -196.032707) (xy 262.412072 -196.088937) (xy 262.469769 -196.150842)
			(xy 262.521416 -196.217878) (xy 262.566558 -196.289455) (xy 262.6048 -196.364945) (xy 262.635804 -196.443684)
			(xy 262.659299 -196.524981) (xy 262.675078 -196.60812) (xy 262.683002 -196.692372) (xy 262.683498 -196.734684)
			(xy 262.683002 -196.776996) (xy 262.675078 -196.861248) (xy 262.659299 -196.944387) (xy 262.635804 -197.025684)
			(xy 262.6048 -197.104423) (xy 262.566558 -197.179913) (xy 262.521416 -197.25149) (xy 262.48828 -197.2945)
			(xy 263.442194 -197.2945) (xy 263.446265 -197.238878) (xy 263.458391 -197.184441) (xy 263.478314 -197.13235)
			(xy 263.50561 -197.083715) (xy 263.539696 -197.039572) (xy 263.579845 -197.000863) (xy 263.625203 -196.968412)
			(xy 263.674803 -196.942911) (xy 263.727587 -196.924904) (xy 263.78243 -196.914774) (xy 263.838164 -196.912737)
			(xy 263.893601 -196.918837) (xy 263.947558 -196.932943) (xy 263.998887 -196.954755) (xy 264.046493 -196.983809)
			(xy 264.089361 -197.019484) (xy 264.126578 -197.061021) (xy 264.157351 -197.107534) (xy 264.181023 -197.158031)
			(xy 264.197091 -197.211438) (xy 264.205211 -197.266614) (xy 264.20572 -197.2945) (xy 264.205211 -197.322386)
			(xy 264.197091 -197.377562) (xy 264.181023 -197.430969) (xy 264.157351 -197.481466) (xy 264.126578 -197.527979)
			(xy 264.089361 -197.569516) (xy 264.046493 -197.605191) (xy 263.998887 -197.634245) (xy 263.947558 -197.656057)
			(xy 263.893601 -197.670163) (xy 263.838164 -197.676263) (xy 263.78243 -197.674226) (xy 263.727587 -197.664096)
			(xy 263.674803 -197.646089) (xy 263.625203 -197.620588) (xy 263.579845 -197.588137) (xy 263.539696 -197.549428)
			(xy 263.50561 -197.505285) (xy 263.478314 -197.45665) (xy 263.458391 -197.404559) (xy 263.446265 -197.350122)
			(xy 263.442194 -197.2945) (xy 262.48828 -197.2945) (xy 262.469769 -197.318526) (xy 262.412072 -197.380431)
			(xy 262.348832 -197.436661) (xy 262.280604 -197.486722) (xy 262.207988 -197.530174) (xy 262.131622 -197.566635)
			(xy 262.052178 -197.595785) (xy 261.970353 -197.617368) (xy 261.886866 -197.631193) (xy 261.802452 -197.63714)
			(xy 261.717851 -197.635157) (xy 261.633809 -197.625259) (xy 261.551062 -197.607536) (xy 261.470338 -197.582142)
			(xy 261.392347 -197.5493) (xy 261.317775 -197.509299) (xy 261.247275 -197.462491) (xy 261.181469 -197.409287)
			(xy 261.120933 -197.350155) (xy 261.066201 -197.285614) (xy 261.017754 -197.216231) (xy 260.976016 -197.142616)
			(xy 260.941355 -197.065417) (xy 260.914075 -196.985311) (xy 260.894417 -196.903002) (xy 260.882552 -196.819215)
			(xy 260.878586 -196.734684) (xy 259.902452 -196.734684) (xy 259.902452 -199.274684) (xy 260.878586 -199.274684)
			(xy 260.882552 -199.190153) (xy 260.894417 -199.106366) (xy 260.914075 -199.024057) (xy 260.941355 -198.943951)
			(xy 260.976016 -198.866752) (xy 261.017754 -198.793137) (xy 261.066201 -198.723754) (xy 261.120933 -198.659213)
			(xy 261.181469 -198.600081) (xy 261.247275 -198.546877) (xy 261.317775 -198.500069) (xy 261.392347 -198.460068)
			(xy 261.470338 -198.427226) (xy 261.551062 -198.401832) (xy 261.633809 -198.384109) (xy 261.717851 -198.374211)
			(xy 261.802452 -198.372228) (xy 261.886866 -198.378175) (xy 261.970353 -198.392) (xy 262.052178 -198.413583)
			(xy 262.131622 -198.442733) (xy 262.207988 -198.479194) (xy 262.280604 -198.522646) (xy 262.348832 -198.572707)
			(xy 262.412072 -198.628937) (xy 262.449313 -198.668894) (xy 264.544046 -198.668894) (xy 264.548117 -198.613272)
			(xy 264.560243 -198.558835) (xy 264.580166 -198.506744) (xy 264.607462 -198.458109) (xy 264.641548 -198.413966)
			(xy 264.681697 -198.375257) (xy 264.727055 -198.342806) (xy 264.776655 -198.317305) (xy 264.829439 -198.299298)
			(xy 264.884282 -198.289168) (xy 264.940016 -198.287131) (xy 264.995453 -198.293231) (xy 265.04941 -198.307337)
			(xy 265.100739 -198.329149) (xy 265.148345 -198.358203) (xy 265.191213 -198.393878) (xy 265.22843 -198.435415)
			(xy 265.259203 -198.481928) (xy 265.282875 -198.532425) (xy 265.298943 -198.585832) (xy 265.307063 -198.641008)
			(xy 265.307572 -198.668894) (xy 265.307063 -198.69678) (xy 265.298943 -198.751956) (xy 265.282875 -198.805363)
			(xy 265.259203 -198.85586) (xy 265.22843 -198.902373) (xy 265.191213 -198.94391) (xy 265.148345 -198.979585)
			(xy 265.100739 -199.008639) (xy 265.04941 -199.030451) (xy 264.995453 -199.044557) (xy 264.940016 -199.050657)
			(xy 264.884282 -199.04862) (xy 264.829439 -199.03849) (xy 264.776655 -199.020483) (xy 264.727055 -198.994982)
			(xy 264.681697 -198.962531) (xy 264.641548 -198.923822) (xy 264.607462 -198.879679) (xy 264.580166 -198.831044)
			(xy 264.560243 -198.778953) (xy 264.548117 -198.724516) (xy 264.544046 -198.668894) (xy 262.449313 -198.668894)
			(xy 262.469769 -198.690842) (xy 262.521416 -198.757878) (xy 262.566558 -198.829455) (xy 262.6048 -198.904945)
			(xy 262.635804 -198.983684) (xy 262.659299 -199.064981) (xy 262.675078 -199.14812) (xy 262.683002 -199.232372)
			(xy 262.683498 -199.274684) (xy 262.683002 -199.316996) (xy 262.675078 -199.401248) (xy 262.659299 -199.484387)
			(xy 262.635804 -199.565684) (xy 262.6048 -199.644423) (xy 262.566558 -199.719913) (xy 262.521416 -199.79149)
			(xy 262.469769 -199.858526) (xy 262.412072 -199.920431) (xy 262.348832 -199.976661) (xy 262.280604 -200.026722)
			(xy 262.207988 -200.070174) (xy 262.131622 -200.106635) (xy 262.052178 -200.135785) (xy 261.970353 -200.157368)
			(xy 261.886866 -200.171193) (xy 261.802452 -200.17714) (xy 261.717851 -200.175157) (xy 261.633809 -200.165259)
			(xy 261.551062 -200.147536) (xy 261.470338 -200.122142) (xy 261.392347 -200.0893) (xy 261.317775 -200.049299)
			(xy 261.247275 -200.002491) (xy 261.181469 -199.949287) (xy 261.120933 -199.890155) (xy 261.066201 -199.825614)
			(xy 261.017754 -199.756231) (xy 260.976016 -199.682616) (xy 260.941355 -199.605417) (xy 260.914075 -199.525311)
			(xy 260.894417 -199.443002) (xy 260.882552 -199.359215) (xy 260.878586 -199.274684) (xy 259.902452 -199.274684)
			(xy 259.902452 -201.814684) (xy 260.878586 -201.814684) (xy 260.882552 -201.730153) (xy 260.894417 -201.646366)
			(xy 260.914075 -201.564057) (xy 260.941355 -201.483951) (xy 260.976016 -201.406752) (xy 261.017754 -201.333137)
			(xy 261.066201 -201.263754) (xy 261.120933 -201.199213) (xy 261.181469 -201.140081) (xy 261.247275 -201.086877)
			(xy 261.317775 -201.040069) (xy 261.392347 -201.000068) (xy 261.470338 -200.967226) (xy 261.551062 -200.941832)
			(xy 261.633809 -200.924109) (xy 261.717851 -200.914211) (xy 261.802452 -200.912228) (xy 261.886866 -200.918175)
			(xy 261.970353 -200.932) (xy 262.052178 -200.953583) (xy 262.131622 -200.982733) (xy 262.207988 -201.019194)
			(xy 262.280604 -201.062646) (xy 262.348832 -201.112707) (xy 262.412072 -201.168937) (xy 262.469769 -201.230842)
			(xy 262.521416 -201.297878) (xy 262.558367 -201.356468) (xy 265.319254 -201.356468) (xy 265.323325 -201.300846)
			(xy 265.335451 -201.246409) (xy 265.355374 -201.194318) (xy 265.38267 -201.145683) (xy 265.416756 -201.10154)
			(xy 265.456905 -201.062831) (xy 265.502263 -201.03038) (xy 265.551863 -201.004879) (xy 265.604647 -200.986872)
			(xy 265.65949 -200.976742) (xy 265.715224 -200.974705) (xy 265.770661 -200.980805) (xy 265.824618 -200.994911)
			(xy 265.875947 -201.016723) (xy 265.923553 -201.045777) (xy 265.966421 -201.081452) (xy 266.003638 -201.122989)
			(xy 266.034411 -201.169502) (xy 266.058083 -201.219999) (xy 266.074151 -201.273406) (xy 266.082271 -201.328582)
			(xy 266.08278 -201.356468) (xy 266.082271 -201.384354) (xy 266.074151 -201.43953) (xy 266.058083 -201.492937)
			(xy 266.034411 -201.543434) (xy 266.003638 -201.589947) (xy 265.966421 -201.631484) (xy 265.923553 -201.667159)
			(xy 265.875947 -201.696213) (xy 265.824618 -201.718025) (xy 265.770661 -201.732131) (xy 265.715224 -201.738231)
			(xy 265.65949 -201.736194) (xy 265.604647 -201.726064) (xy 265.551863 -201.708057) (xy 265.502263 -201.682556)
			(xy 265.456905 -201.650105) (xy 265.416756 -201.611396) (xy 265.38267 -201.567253) (xy 265.355374 -201.518618)
			(xy 265.335451 -201.466527) (xy 265.323325 -201.41209) (xy 265.319254 -201.356468) (xy 262.558367 -201.356468)
			(xy 262.566558 -201.369455) (xy 262.6048 -201.444945) (xy 262.635804 -201.523684) (xy 262.659299 -201.604981)
			(xy 262.675078 -201.68812) (xy 262.683002 -201.772372) (xy 262.683498 -201.814684) (xy 262.683002 -201.856996)
			(xy 262.675078 -201.941248) (xy 262.659299 -202.024387) (xy 262.635804 -202.105684) (xy 262.6048 -202.184423)
			(xy 262.566558 -202.259913) (xy 262.525208 -202.325478) (xy 265.538202 -202.325478) (xy 265.542273 -202.269856)
			(xy 265.554399 -202.215419) (xy 265.574322 -202.163328) (xy 265.601618 -202.114693) (xy 265.635704 -202.07055)
			(xy 265.675853 -202.031841) (xy 265.721211 -201.99939) (xy 265.770811 -201.973889) (xy 265.823595 -201.955882)
			(xy 265.878438 -201.945752) (xy 265.934172 -201.943715) (xy 265.989609 -201.949815) (xy 266.043566 -201.963921)
			(xy 266.094895 -201.985733) (xy 266.142501 -202.014787) (xy 266.185369 -202.050462) (xy 266.222586 -202.091999)
			(xy 266.253359 -202.138512) (xy 266.277031 -202.189009) (xy 266.293099 -202.242416) (xy 266.301219 -202.297592)
			(xy 266.301728 -202.325478) (xy 266.301219 -202.353364) (xy 266.293099 -202.40854) (xy 266.277031 -202.461947)
			(xy 266.253359 -202.512444) (xy 266.222586 -202.558957) (xy 266.185369 -202.600494) (xy 266.142501 -202.636169)
			(xy 266.094895 -202.665223) (xy 266.043566 -202.687035) (xy 265.989609 -202.701141) (xy 265.934172 -202.707241)
			(xy 265.878438 -202.705204) (xy 265.823595 -202.695074) (xy 265.770811 -202.677067) (xy 265.721211 -202.651566)
			(xy 265.675853 -202.619115) (xy 265.635704 -202.580406) (xy 265.601618 -202.536263) (xy 265.574322 -202.487628)
			(xy 265.554399 -202.435537) (xy 265.542273 -202.3811) (xy 265.538202 -202.325478) (xy 262.525208 -202.325478)
			(xy 262.521416 -202.33149) (xy 262.469769 -202.398526) (xy 262.412072 -202.460431) (xy 262.348832 -202.516661)
			(xy 262.280604 -202.566722) (xy 262.207988 -202.610174) (xy 262.131622 -202.646635) (xy 262.052178 -202.675785)
			(xy 261.970353 -202.697368) (xy 261.886866 -202.711193) (xy 261.802452 -202.71714) (xy 261.717851 -202.715157)
			(xy 261.633809 -202.705259) (xy 261.551062 -202.687536) (xy 261.470338 -202.662142) (xy 261.392347 -202.6293)
			(xy 261.317775 -202.589299) (xy 261.247275 -202.542491) (xy 261.181469 -202.489287) (xy 261.120933 -202.430155)
			(xy 261.066201 -202.365614) (xy 261.017754 -202.296231) (xy 260.976016 -202.222616) (xy 260.941355 -202.145417)
			(xy 260.914075 -202.065311) (xy 260.894417 -201.983002) (xy 260.882552 -201.899215) (xy 260.878586 -201.814684)
			(xy 259.902452 -201.814684) (xy 259.902452 -204.354684) (xy 260.878586 -204.354684) (xy 260.882552 -204.270153)
			(xy 260.894417 -204.186366) (xy 260.914075 -204.104057) (xy 260.941355 -204.023951) (xy 260.976016 -203.946752)
			(xy 261.017754 -203.873137) (xy 261.066201 -203.803754) (xy 261.120933 -203.739213) (xy 261.181469 -203.680081)
			(xy 261.247275 -203.626877) (xy 261.317775 -203.580069) (xy 261.392347 -203.540068) (xy 261.470338 -203.507226)
			(xy 261.551062 -203.481832) (xy 261.633809 -203.464109) (xy 261.717851 -203.454211) (xy 261.802452 -203.452228)
			(xy 261.886866 -203.458175) (xy 261.970353 -203.472) (xy 262.052178 -203.493583) (xy 262.131622 -203.522733)
			(xy 262.207988 -203.559194) (xy 262.220234 -203.566522) (xy 264.391138 -203.566522) (xy 264.395209 -203.5109)
			(xy 264.407335 -203.456463) (xy 264.427258 -203.404372) (xy 264.454554 -203.355737) (xy 264.48864 -203.311594)
			(xy 264.528789 -203.272885) (xy 264.574147 -203.240434) (xy 264.623747 -203.214933) (xy 264.676531 -203.196926)
			(xy 264.731374 -203.186796) (xy 264.787108 -203.184759) (xy 264.842545 -203.190859) (xy 264.896502 -203.204965)
			(xy 264.947831 -203.226777) (xy 264.995437 -203.255831) (xy 265.038305 -203.291506) (xy 265.075522 -203.333043)
			(xy 265.106295 -203.379556) (xy 265.129967 -203.430053) (xy 265.146035 -203.48346) (xy 265.154155 -203.538636)
			(xy 265.154664 -203.566522) (xy 265.154155 -203.594408) (xy 265.146035 -203.649584) (xy 265.129967 -203.702991)
			(xy 265.106295 -203.753488) (xy 265.075522 -203.800001) (xy 265.038305 -203.841538) (xy 264.995437 -203.877213)
			(xy 264.947831 -203.906267) (xy 264.896502 -203.928079) (xy 264.842545 -203.942185) (xy 264.787108 -203.948285)
			(xy 264.731374 -203.946248) (xy 264.676531 -203.936118) (xy 264.623747 -203.918111) (xy 264.574147 -203.89261)
			(xy 264.528789 -203.860159) (xy 264.48864 -203.82145) (xy 264.454554 -203.777307) (xy 264.427258 -203.728672)
			(xy 264.407335 -203.676581) (xy 264.395209 -203.622144) (xy 264.391138 -203.566522) (xy 262.220234 -203.566522)
			(xy 262.280604 -203.602646) (xy 262.348832 -203.652707) (xy 262.412072 -203.708937) (xy 262.469769 -203.770842)
			(xy 262.521416 -203.837878) (xy 262.566558 -203.909455) (xy 262.6048 -203.984945) (xy 262.635804 -204.063684)
			(xy 262.659299 -204.144981) (xy 262.675078 -204.22812) (xy 262.683002 -204.312372) (xy 262.683498 -204.354684)
			(xy 262.683002 -204.396996) (xy 262.675078 -204.481248) (xy 262.659299 -204.564387) (xy 262.635804 -204.645684)
			(xy 262.6048 -204.724423) (xy 262.566558 -204.799913) (xy 262.521416 -204.87149) (xy 262.469769 -204.938526)
			(xy 262.412072 -205.000431) (xy 262.348832 -205.056661) (xy 262.280604 -205.106722) (xy 262.207988 -205.150174)
			(xy 262.131622 -205.186635) (xy 262.052178 -205.215785) (xy 261.970353 -205.237368) (xy 261.886866 -205.251193)
			(xy 261.802452 -205.25714) (xy 261.717851 -205.255157) (xy 261.633809 -205.245259) (xy 261.551062 -205.227536)
			(xy 261.470338 -205.202142) (xy 261.392347 -205.1693) (xy 261.317775 -205.129299) (xy 261.247275 -205.082491)
			(xy 261.181469 -205.029287) (xy 261.120933 -204.970155) (xy 261.066201 -204.905614) (xy 261.017754 -204.836231)
			(xy 260.976016 -204.762616) (xy 260.941355 -204.685417) (xy 260.914075 -204.605311) (xy 260.894417 -204.523002)
			(xy 260.882552 -204.439215) (xy 260.878586 -204.354684) (xy 259.902452 -204.354684) (xy 259.902452 -206.894684)
			(xy 260.878586 -206.894684) (xy 260.882552 -206.810153) (xy 260.894417 -206.726366) (xy 260.914075 -206.644057)
			(xy 260.941355 -206.563951) (xy 260.976016 -206.486752) (xy 261.017754 -206.413137) (xy 261.066201 -206.343754)
			(xy 261.120933 -206.279213) (xy 261.181469 -206.220081) (xy 261.247275 -206.166877) (xy 261.317775 -206.120069)
			(xy 261.392347 -206.080068) (xy 261.470338 -206.047226) (xy 261.551062 -206.021832) (xy 261.633809 -206.004109)
			(xy 261.717851 -205.994211) (xy 261.802452 -205.992228) (xy 261.886866 -205.998175) (xy 261.970353 -206.012)
			(xy 262.052178 -206.033583) (xy 262.131622 -206.062733) (xy 262.207988 -206.099194) (xy 262.280604 -206.142646)
			(xy 262.348832 -206.192707) (xy 262.412072 -206.248937) (xy 262.469769 -206.310842) (xy 262.487888 -206.33436)
			(xy 263.587736 -206.33436) (xy 263.591807 -206.278738) (xy 263.603933 -206.224301) (xy 263.623856 -206.17221)
			(xy 263.651152 -206.123575) (xy 263.685238 -206.079432) (xy 263.725387 -206.040723) (xy 263.770745 -206.008272)
			(xy 263.820345 -205.982771) (xy 263.873129 -205.964764) (xy 263.927972 -205.954634) (xy 263.983706 -205.952597)
			(xy 264.039143 -205.958697) (xy 264.0931 -205.972803) (xy 264.144429 -205.994615) (xy 264.192035 -206.023669)
			(xy 264.234903 -206.059344) (xy 264.27212 -206.100881) (xy 264.302893 -206.147394) (xy 264.326565 -206.197891)
			(xy 264.342633 -206.251298) (xy 264.350753 -206.306474) (xy 264.351262 -206.33436) (xy 264.350753 -206.362246)
			(xy 264.342633 -206.417422) (xy 264.326565 -206.470829) (xy 264.302893 -206.521326) (xy 264.27212 -206.567839)
			(xy 264.234903 -206.609376) (xy 264.192035 -206.645051) (xy 264.144429 -206.674105) (xy 264.0931 -206.695917)
			(xy 264.039143 -206.710023) (xy 263.983706 -206.716123) (xy 263.927972 -206.714086) (xy 263.873129 -206.703956)
			(xy 263.820345 -206.685949) (xy 263.770745 -206.660448) (xy 263.725387 -206.627997) (xy 263.685238 -206.589288)
			(xy 263.651152 -206.545145) (xy 263.623856 -206.49651) (xy 263.603933 -206.444419) (xy 263.591807 -206.389982)
			(xy 263.587736 -206.33436) (xy 262.487888 -206.33436) (xy 262.521416 -206.377878) (xy 262.566558 -206.449455)
			(xy 262.6048 -206.524945) (xy 262.635804 -206.603684) (xy 262.659299 -206.684981) (xy 262.675078 -206.76812)
			(xy 262.683002 -206.852372) (xy 262.683498 -206.894684) (xy 262.683002 -206.936996) (xy 262.675078 -207.021248)
			(xy 262.659299 -207.104387) (xy 262.635804 -207.185684) (xy 262.6048 -207.264423) (xy 262.566558 -207.339913)
			(xy 262.521416 -207.41149) (xy 262.469769 -207.478526) (xy 262.412072 -207.540431) (xy 262.348832 -207.596661)
			(xy 262.280604 -207.646722) (xy 262.207988 -207.690174) (xy 262.131622 -207.726635) (xy 262.052178 -207.755785)
			(xy 261.970353 -207.777368) (xy 261.886866 -207.791193) (xy 261.802452 -207.79714) (xy 261.717851 -207.795157)
			(xy 261.633809 -207.785259) (xy 261.551062 -207.767536) (xy 261.470338 -207.742142) (xy 261.392347 -207.7093)
			(xy 261.317775 -207.669299) (xy 261.247275 -207.622491) (xy 261.181469 -207.569287) (xy 261.120933 -207.510155)
			(xy 261.066201 -207.445614) (xy 261.017754 -207.376231) (xy 260.976016 -207.302616) (xy 260.941355 -207.225417)
			(xy 260.914075 -207.145311) (xy 260.894417 -207.063002) (xy 260.882552 -206.979215) (xy 260.878586 -206.894684)
			(xy 259.902452 -206.894684) (xy 259.902452 -207.537558) (xy 259.902056 -207.554407) (xy 259.898113 -207.587881)
			(xy 259.894578 -207.60436) (xy 259.894324 -207.605884) (xy 259.894324 -207.616552) (xy 259.894112 -207.623363)
			(xy 259.890516 -207.636501) (xy 259.887212 -207.64246) (xy 259.880862 -207.653128) (xy 259.876798 -207.661256)
			(xy 259.87629 -207.662526) (xy 259.873242 -207.66913) (xy 259.872988 -207.669638) (xy 259.868416 -207.679798)
			(xy 259.864084 -207.688171) (xy 259.854551 -207.704437) (xy 259.849366 -207.71231) (xy 259.845048 -207.720438)
			(xy 259.841951 -207.72832) (xy 259.840649 -207.745196) (xy 259.842508 -207.753458) (xy 259.844129 -207.758869)
			(xy 259.849389 -207.768862) (xy 259.852922 -207.77327) (xy 259.871304 -207.795898) (xy 259.901704 -207.845641)
			(xy 259.924194 -207.899426) (xy 259.938251 -207.956003) (xy 259.943549 -208.014059) (xy 259.939965 -208.072246)
			(xy 259.927583 -208.129213) (xy 259.906688 -208.183637) (xy 259.877768 -208.234255) (xy 259.860034 -208.257394)
			(xy 259.8547 -208.263744) (xy 259.847842 -208.281778) (xy 259.846129 -208.287453) (xy 259.845107 -208.29926)
			(xy 259.84581 -208.305146) (xy 259.846064 -208.307178) (xy 259.84752 -208.314366) (xy 259.853986 -208.327521)
			(xy 259.858764 -208.333086) (xy 259.870956 -208.346294) (xy 259.877207 -208.35353) (xy 259.884263 -208.371285)
			(xy 259.884672 -208.380838) (xy 259.884672 -208.388966) (xy 259.887212 -208.404714) (xy 259.888228 -208.408016)
			(xy 259.888228 -208.40827) (xy 259.888736 -208.409286) (xy 259.895146 -208.431731) (xy 259.902034 -208.477896)
			(xy 259.902452 -208.501234) (xy 259.902452 -209.480707) (xy 260.727184 -209.480707) (xy 260.727184 -209.388661)
			(xy 260.735206 -209.296964) (xy 260.75119 -209.206316) (xy 260.775013 -209.117406) (xy 260.806495 -209.030911)
			(xy 260.845396 -208.947488) (xy 260.891419 -208.867774) (xy 260.944215 -208.792373) (xy 261.003381 -208.721862)
			(xy 261.068468 -208.656775) (xy 261.138979 -208.597609) (xy 261.21438 -208.544813) (xy 261.294094 -208.49879)
			(xy 261.377517 -208.459889) (xy 261.464012 -208.428407) (xy 261.552922 -208.404584) (xy 261.64357 -208.3886)
			(xy 261.735267 -208.380578) (xy 261.827313 -208.380578) (xy 261.91901 -208.3886) (xy 262.009658 -208.404584)
			(xy 262.098568 -208.428407) (xy 262.185063 -208.459889) (xy 262.268486 -208.49879) (xy 262.3482 -208.544813)
			(xy 262.423601 -208.597609) (xy 262.494112 -208.656775) (xy 262.559199 -208.721862) (xy 262.618365 -208.792373)
			(xy 262.671161 -208.867774) (xy 262.717184 -208.947488) (xy 262.756085 -209.030911) (xy 262.773619 -209.079084)
			(xy 266.711682 -209.079084) (xy 266.715753 -209.023462) (xy 266.727879 -208.969025) (xy 266.747802 -208.916934)
			(xy 266.775098 -208.868299) (xy 266.809184 -208.824156) (xy 266.849333 -208.785447) (xy 266.894691 -208.752996)
			(xy 266.944291 -208.727495) (xy 266.997075 -208.709488) (xy 267.051918 -208.699358) (xy 267.107652 -208.697321)
			(xy 267.163089 -208.703421) (xy 267.217046 -208.717527) (xy 267.268375 -208.739339) (xy 267.315981 -208.768393)
			(xy 267.358849 -208.804068) (xy 267.396066 -208.845605) (xy 267.426839 -208.892118) (xy 267.450511 -208.942615)
			(xy 267.466579 -208.996022) (xy 267.474699 -209.051198) (xy 267.475208 -209.079084) (xy 267.474699 -209.10697)
			(xy 267.466579 -209.162146) (xy 267.450511 -209.215553) (xy 267.426839 -209.26605) (xy 267.396066 -209.312563)
			(xy 267.358849 -209.3541) (xy 267.315981 -209.389775) (xy 267.268375 -209.418829) (xy 267.217046 -209.440641)
			(xy 267.163089 -209.454747) (xy 267.107652 -209.460847) (xy 267.051918 -209.45881) (xy 266.997075 -209.44868)
			(xy 266.944291 -209.430673) (xy 266.894691 -209.405172) (xy 266.849333 -209.372721) (xy 266.809184 -209.334012)
			(xy 266.775098 -209.289869) (xy 266.747802 -209.241234) (xy 266.727879 -209.189143) (xy 266.715753 -209.134706)
			(xy 266.711682 -209.079084) (xy 262.773619 -209.079084) (xy 262.787567 -209.117406) (xy 262.81139 -209.206316)
			(xy 262.827374 -209.296964) (xy 262.835396 -209.388661) (xy 262.835898 -209.434684) (xy 262.835396 -209.480707)
			(xy 262.827374 -209.572404) (xy 262.81139 -209.663052) (xy 262.787567 -209.751962) (xy 262.756085 -209.838457)
			(xy 262.717184 -209.92188) (xy 262.671161 -210.001594) (xy 262.618365 -210.076995) (xy 262.559199 -210.147506)
			(xy 262.494112 -210.212593) (xy 262.423601 -210.271759) (xy 262.3482 -210.324555) (xy 262.268486 -210.370578)
			(xy 262.185063 -210.409479) (xy 262.098568 -210.440961) (xy 262.009658 -210.464784) (xy 261.91901 -210.480768)
			(xy 261.827313 -210.48879) (xy 261.735267 -210.48879) (xy 261.64357 -210.480768) (xy 261.552922 -210.464784)
			(xy 261.464012 -210.440961) (xy 261.377517 -210.409479) (xy 261.294094 -210.370578) (xy 261.21438 -210.324555)
			(xy 261.138979 -210.271759) (xy 261.068468 -210.212593) (xy 261.003381 -210.147506) (xy 260.944215 -210.076995)
			(xy 260.891419 -210.001594) (xy 260.845396 -209.92188) (xy 260.806495 -209.838457) (xy 260.775013 -209.751962)
			(xy 260.75119 -209.663052) (xy 260.735206 -209.572404) (xy 260.727184 -209.480707) (xy 259.902452 -209.480707)
			(xy 259.902452 -211.0232) (xy 264.647932 -211.0232) (xy 264.652003 -210.967578) (xy 264.664129 -210.913141)
			(xy 264.684052 -210.86105) (xy 264.711348 -210.812415) (xy 264.745434 -210.768272) (xy 264.785583 -210.729563)
			(xy 264.830941 -210.697112) (xy 264.880541 -210.671611) (xy 264.933325 -210.653604) (xy 264.988168 -210.643474)
			(xy 265.043902 -210.641437) (xy 265.099339 -210.647537) (xy 265.153296 -210.661643) (xy 265.204625 -210.683455)
			(xy 265.252231 -210.712509) (xy 265.295099 -210.748184) (xy 265.332316 -210.789721) (xy 265.363089 -210.836234)
			(xy 265.386761 -210.886731) (xy 265.402829 -210.940138) (xy 265.410949 -210.995314) (xy 265.411458 -211.0232)
			(xy 265.410949 -211.051086) (xy 265.402829 -211.106262) (xy 265.386761 -211.159669) (xy 265.363089 -211.210166)
			(xy 265.332316 -211.256679) (xy 265.295099 -211.298216) (xy 265.252231 -211.333891) (xy 265.204625 -211.362945)
			(xy 265.153296 -211.384757) (xy 265.099339 -211.398863) (xy 265.043902 -211.404963) (xy 264.988168 -211.402926)
			(xy 264.933325 -211.392796) (xy 264.880541 -211.374789) (xy 264.830941 -211.349288) (xy 264.785583 -211.316837)
			(xy 264.745434 -211.278128) (xy 264.711348 -211.233985) (xy 264.684052 -211.18535) (xy 264.664129 -211.133259)
			(xy 264.652003 -211.078822) (xy 264.647932 -211.0232) (xy 259.902452 -211.0232) (xy 259.902452 -211.35467)
			(xy 259.901956 -211.379199) (xy 259.8943 -211.427656) (xy 259.87923 -211.474343) (xy 259.857109 -211.518131)
			(xy 259.828472 -211.557965) (xy 259.794011 -211.592881) (xy 259.773677 -211.607908) (xy 265.889738 -211.607908)
			(xy 265.893809 -211.552286) (xy 265.905935 -211.497849) (xy 265.925858 -211.445758) (xy 265.953154 -211.397123)
			(xy 265.98724 -211.35298) (xy 266.027389 -211.314271) (xy 266.072747 -211.28182) (xy 266.122347 -211.256319)
			(xy 266.175131 -211.238312) (xy 266.229974 -211.228182) (xy 266.285708 -211.226145) (xy 266.341145 -211.232245)
			(xy 266.395102 -211.246351) (xy 266.446431 -211.268163) (xy 266.494037 -211.297217) (xy 266.536905 -211.332892)
			(xy 266.574122 -211.374429) (xy 266.604895 -211.420942) (xy 266.628567 -211.471439) (xy 266.644635 -211.524846)
			(xy 266.645122 -211.528152) (xy 267.17955 -211.528152) (xy 267.183621 -211.47253) (xy 267.195747 -211.418093)
			(xy 267.21567 -211.366002) (xy 267.242966 -211.317367) (xy 267.277052 -211.273224) (xy 267.317201 -211.234515)
			(xy 267.362559 -211.202064) (xy 267.412159 -211.176563) (xy 267.464943 -211.158556) (xy 267.519786 -211.148426)
			(xy 267.57552 -211.146389) (xy 267.630957 -211.152489) (xy 267.684914 -211.166595) (xy 267.736243 -211.188407)
			(xy 267.783849 -211.217461) (xy 267.826717 -211.253136) (xy 267.863934 -211.294673) (xy 267.894707 -211.341186)
			(xy 267.918379 -211.391683) (xy 267.934447 -211.44509) (xy 267.942567 -211.500266) (xy 267.943076 -211.528152)
			(xy 267.942567 -211.556038) (xy 267.934447 -211.611214) (xy 267.918379 -211.664621) (xy 267.894707 -211.715118)
			(xy 267.863934 -211.761631) (xy 267.826717 -211.803168) (xy 267.783849 -211.838843) (xy 267.736243 -211.867897)
			(xy 267.684914 -211.889709) (xy 267.630957 -211.903815) (xy 267.57552 -211.909915) (xy 267.519786 -211.907878)
			(xy 267.464943 -211.897748) (xy 267.412159 -211.879741) (xy 267.362559 -211.85424) (xy 267.317201 -211.821789)
			(xy 267.277052 -211.78308) (xy 267.242966 -211.738937) (xy 267.21567 -211.690302) (xy 267.195747 -211.638211)
			(xy 267.183621 -211.583774) (xy 267.17955 -211.528152) (xy 266.645122 -211.528152) (xy 266.652755 -211.580022)
			(xy 266.653264 -211.607908) (xy 266.652755 -211.635794) (xy 266.644635 -211.69097) (xy 266.628567 -211.744377)
			(xy 266.604895 -211.794874) (xy 266.574122 -211.841387) (xy 266.536905 -211.882924) (xy 266.494037 -211.918599)
			(xy 266.446431 -211.947653) (xy 266.395102 -211.969465) (xy 266.341145 -211.983571) (xy 266.285708 -211.989671)
			(xy 266.229974 -211.987634) (xy 266.175131 -211.977504) (xy 266.122347 -211.959497) (xy 266.072747 -211.933996)
			(xy 266.027389 -211.901545) (xy 265.98724 -211.862836) (xy 265.953154 -211.818693) (xy 265.925858 -211.770058)
			(xy 265.905935 -211.717967) (xy 265.893809 -211.66353) (xy 265.889738 -211.607908) (xy 259.773677 -211.607908)
			(xy 259.754556 -211.622038) (xy 259.733034 -211.633816) (xy 259.704078 -211.648802) (xy 259.695442 -211.653628)
			(xy 259.694426 -211.654136) (xy 259.681726 -211.66074) (xy 259.681472 -211.66074) (xy 259.666486 -211.66836)
			(xy 259.659867 -211.671964) (xy 259.648903 -211.682296) (xy 259.644896 -211.68868) (xy 259.64134 -211.69503)
			(xy 259.638038 -211.709762) (xy 259.6388 -211.717636) (xy 259.64007 -211.748624) (xy 259.64007 -211.750402)
			(xy 259.6388 -211.781136) (xy 259.638369 -211.791222) (xy 259.644545 -211.810424) (xy 259.657676 -211.825736)
			(xy 259.666486 -211.830666) (xy 259.699506 -211.84743) (xy 259.704078 -211.84997) (xy 259.733034 -211.864956)
			(xy 259.754582 -211.8767) (xy 259.794069 -211.905836) (xy 259.828557 -211.940745) (xy 259.85721 -211.980584)
			(xy 259.879334 -212.024386) (xy 259.894393 -212.07109) (xy 259.902023 -212.119566) (xy 259.902452 -212.144102)
			(xy 259.902452 -212.37067) (xy 259.901956 -212.395199) (xy 259.8943 -212.443656) (xy 259.886622 -212.467444)
			(xy 263.14984 -212.467444) (xy 263.153911 -212.411822) (xy 263.166037 -212.357385) (xy 263.18596 -212.305294)
			(xy 263.213256 -212.256659) (xy 263.247342 -212.212516) (xy 263.287491 -212.173807) (xy 263.332849 -212.141356)
			(xy 263.382449 -212.115855) (xy 263.435233 -212.097848) (xy 263.490076 -212.087718) (xy 263.54581 -212.085681)
			(xy 263.601247 -212.091781) (xy 263.655204 -212.105887) (xy 263.706533 -212.127699) (xy 263.754139 -212.156753)
			(xy 263.797007 -212.192428) (xy 263.834224 -212.233965) (xy 263.864997 -212.280478) (xy 263.888669 -212.330975)
			(xy 263.904737 -212.384382) (xy 263.912857 -212.439558) (xy 263.913366 -212.467444) (xy 263.912857 -212.49533)
			(xy 263.904737 -212.550506) (xy 263.888669 -212.603913) (xy 263.864997 -212.65441) (xy 263.834224 -212.700923)
			(xy 263.797007 -212.74246) (xy 263.754139 -212.778135) (xy 263.706533 -212.807189) (xy 263.655204 -212.829001)
			(xy 263.601247 -212.843107) (xy 263.54581 -212.849207) (xy 263.490076 -212.84717) (xy 263.435233 -212.83704)
			(xy 263.382449 -212.819033) (xy 263.332849 -212.793532) (xy 263.287491 -212.761081) (xy 263.247342 -212.722372)
			(xy 263.213256 -212.678229) (xy 263.18596 -212.629594) (xy 263.166037 -212.577503) (xy 263.153911 -212.523066)
			(xy 263.14984 -212.467444) (xy 259.886622 -212.467444) (xy 259.87923 -212.490343) (xy 259.857109 -212.534131)
			(xy 259.828472 -212.573965) (xy 259.794011 -212.608881) (xy 259.754556 -212.638038) (xy 259.733034 -212.649816)
			(xy 259.704078 -212.664802) (xy 259.695442 -212.669628) (xy 259.694426 -212.670136) (xy 259.665978 -212.684868)
			(xy 259.659554 -212.688533) (xy 259.648976 -212.698859) (xy 259.64515 -212.705188) (xy 259.641594 -212.711538)
			(xy 259.638546 -212.72627) (xy 259.639054 -212.73389) (xy 259.64007 -212.764624) (xy 259.64007 -212.766148)
			(xy 259.6388 -212.796882) (xy 259.638292 -212.803994) (xy 259.641086 -212.818218) (xy 259.644896 -212.825076)
			(xy 259.648481 -212.83122) (xy 259.658402 -212.841404) (xy 259.664454 -212.845142) (xy 259.669788 -212.84819)
			(xy 259.675511 -212.85115) (xy 259.687985 -212.854368) (xy 259.694426 -212.85454) (xy 259.697474 -212.85454)
			(xy 259.707537 -212.854978) (xy 259.726118 -212.862716) (xy 259.733542 -212.869526) (xy 259.758688 -212.894926)
			(xy 259.766054 -212.901022) (xy 259.767832 -212.902292) (xy 259.788225 -212.917123) (xy 259.824451 -212.952193)
			(xy 259.854622 -212.992591) (xy 259.877965 -213.037282) (xy 259.893884 -213.085124) (xy 259.901971 -213.134892)
			(xy 259.902452 -213.160102) (xy 259.902452 -213.700106) (xy 263.98728 -213.700106) (xy 263.98766 -213.674323)
			(xy 263.994606 -213.623227) (xy 264.008372 -213.573533) (xy 264.028706 -213.526145) (xy 264.055239 -213.48193)
			(xy 264.087487 -213.441691) (xy 264.124861 -213.406164) (xy 264.145522 -213.390734) (xy 264.154017 -213.384061)
			(xy 264.164794 -213.365358) (xy 264.16635 -213.354666) (xy 264.174732 -213.267798) (xy 264.167874 -213.247224)
			(xy 264.160254 -213.239096) (xy 264.141101 -213.217806) (xy 264.108777 -213.170536) (xy 264.083876 -213.118966)
			(xy 264.066959 -213.064256) (xy 264.058404 -213.007633) (xy 264.057892 -212.979) (xy 264.058378 -212.951749)
			(xy 264.066134 -212.897801) (xy 264.081489 -212.845506) (xy 264.104131 -212.795929) (xy 264.133597 -212.750079)
			(xy 264.169288 -212.708888) (xy 264.210479 -212.673197) (xy 264.256329 -212.643731) (xy 264.305906 -212.621089)
			(xy 264.358201 -212.605734) (xy 264.412149 -212.597978) (xy 264.4394 -212.597492) (xy 264.471589 -212.5982)
			(xy 264.535047 -212.609045) (xy 264.565638 -212.619082) (xy 264.565892 -212.619082) (xy 264.577978 -212.622519)
			(xy 264.602752 -212.618534) (xy 264.613136 -212.611462) (xy 264.6807 -212.559646) (xy 264.690365 -212.551366)
			(xy 264.700766 -212.528174) (xy 264.700512 -212.51545) (xy 264.699496 -212.487002) (xy 264.699976 -212.459751)
			(xy 264.707732 -212.405803) (xy 264.723087 -212.353508) (xy 264.745728 -212.30393) (xy 264.775194 -212.258079)
			(xy 264.810885 -212.216889) (xy 264.852076 -212.181197) (xy 264.897926 -212.15173) (xy 264.947503 -212.129088)
			(xy 264.999798 -212.113733) (xy 265.053746 -212.105976) (xy 265.108249 -212.105976) (xy 265.162197 -212.113732)
			(xy 265.214492 -212.129087) (xy 265.264069 -212.151727) (xy 265.30992 -212.181193) (xy 265.351111 -212.216885)
			(xy 265.386803 -212.258075) (xy 265.41627 -212.303925) (xy 265.438911 -212.353503) (xy 265.454267 -212.405797)
			(xy 265.462024 -212.459745) (xy 265.462024 -212.514248) (xy 265.454268 -212.568196) (xy 265.438914 -212.620491)
			(xy 265.416273 -212.670069) (xy 265.386807 -212.71592) (xy 265.351116 -212.75711) (xy 265.309926 -212.792803)
			(xy 265.299626 -212.799422) (xy 266.408914 -212.799422) (xy 266.412985 -212.7438) (xy 266.425111 -212.689363)
			(xy 266.445034 -212.637272) (xy 266.47233 -212.588637) (xy 266.506416 -212.544494) (xy 266.546565 -212.505785)
			(xy 266.591923 -212.473334) (xy 266.641523 -212.447833) (xy 266.694307 -212.429826) (xy 266.74915 -212.419696)
			(xy 266.804884 -212.417659) (xy 266.860321 -212.423759) (xy 266.914278 -212.437865) (xy 266.965607 -212.459677)
			(xy 267.013213 -212.488731) (xy 267.056081 -212.524406) (xy 267.093298 -212.565943) (xy 267.124071 -212.612456)
			(xy 267.147743 -212.662953) (xy 267.163811 -212.71636) (xy 267.171931 -212.771536) (xy 267.172092 -212.780372)
			(xy 267.311884 -212.780372) (xy 267.315955 -212.72475) (xy 267.328081 -212.670313) (xy 267.348004 -212.618222)
			(xy 267.3753 -212.569587) (xy 267.409386 -212.525444) (xy 267.449535 -212.486735) (xy 267.494893 -212.454284)
			(xy 267.544493 -212.428783) (xy 267.597277 -212.410776) (xy 267.65212 -212.400646) (xy 267.707854 -212.398609)
			(xy 267.763291 -212.404709) (xy 267.817248 -212.418815) (xy 267.868577 -212.440627) (xy 267.916183 -212.469681)
			(xy 267.959051 -212.505356) (xy 267.996268 -212.546893) (xy 268.027041 -212.593406) (xy 268.050713 -212.643903)
			(xy 268.066781 -212.69731) (xy 268.074901 -212.752486) (xy 268.07541 -212.780372) (xy 268.074901 -212.808258)
			(xy 268.066781 -212.863434) (xy 268.050713 -212.916841) (xy 268.027041 -212.967338) (xy 267.996268 -213.013851)
			(xy 267.959051 -213.055388) (xy 267.916183 -213.091063) (xy 267.868577 -213.120117) (xy 267.817248 -213.141929)
			(xy 267.763291 -213.156035) (xy 267.707854 -213.162135) (xy 267.65212 -213.160098) (xy 267.597277 -213.149968)
			(xy 267.544493 -213.131961) (xy 267.494893 -213.10646) (xy 267.449535 -213.074009) (xy 267.409386 -213.0353)
			(xy 267.3753 -212.991157) (xy 267.348004 -212.942522) (xy 267.328081 -212.890431) (xy 267.315955 -212.835994)
			(xy 267.311884 -212.780372) (xy 267.172092 -212.780372) (xy 267.17244 -212.799422) (xy 267.171931 -212.827308)
			(xy 267.163811 -212.882484) (xy 267.147743 -212.935891) (xy 267.124071 -212.986388) (xy 267.093298 -213.032901)
			(xy 267.056081 -213.074438) (xy 267.013213 -213.110113) (xy 266.965607 -213.139167) (xy 266.914278 -213.160979)
			(xy 266.860321 -213.175085) (xy 266.804884 -213.181185) (xy 266.74915 -213.179148) (xy 266.694307 -213.169018)
			(xy 266.641523 -213.151011) (xy 266.591923 -213.12551) (xy 266.546565 -213.093059) (xy 266.506416 -213.05435)
			(xy 266.47233 -213.010207) (xy 266.445034 -212.961572) (xy 266.425111 -212.909481) (xy 266.412985 -212.855044)
			(xy 266.408914 -212.799422) (xy 265.299626 -212.799422) (xy 265.264075 -212.822269) (xy 265.214498 -212.844911)
			(xy 265.162203 -212.860267) (xy 265.108255 -212.868024) (xy 265.081004 -212.86851) (xy 265.048815 -212.867805)
			(xy 264.985357 -212.856959) (xy 264.954766 -212.84692) (xy 264.954512 -212.84692) (xy 264.942426 -212.843486)
			(xy 264.917652 -212.847468) (xy 264.907268 -212.85454) (xy 264.839704 -212.906356) (xy 264.830038 -212.914636)
			(xy 264.819637 -212.937828) (xy 264.819892 -212.950552) (xy 264.820908 -212.979) (xy 264.820496 -213.004781)
			(xy 264.813551 -213.055875) (xy 264.799788 -213.105567) (xy 264.779458 -213.152953) (xy 264.752931 -213.197168)
			(xy 264.72069 -213.237409) (xy 264.683323 -213.27294) (xy 264.662666 -213.288372) (xy 264.654166 -213.29504)
			(xy 264.643392 -213.313747) (xy 264.641838 -213.32444) (xy 264.633456 -213.411308) (xy 264.640314 -213.431882)
			(xy 264.647934 -213.44001) (xy 264.667088 -213.461299) (xy 264.699413 -213.50857) (xy 264.724313 -213.560139)
			(xy 264.74123 -213.614849) (xy 264.749428 -213.669118) (xy 265.313412 -213.669118) (xy 265.317483 -213.613496)
			(xy 265.329609 -213.559059) (xy 265.349532 -213.506968) (xy 265.376828 -213.458333) (xy 265.410914 -213.41419)
			(xy 265.451063 -213.375481) (xy 265.496421 -213.34303) (xy 265.546021 -213.317529) (xy 265.598805 -213.299522)
			(xy 265.653648 -213.289392) (xy 265.709382 -213.287355) (xy 265.764819 -213.293455) (xy 265.818776 -213.307561)
			(xy 265.870105 -213.329373) (xy 265.917711 -213.358427) (xy 265.960579 -213.394102) (xy 265.997796 -213.435639)
			(xy 266.028569 -213.482152) (xy 266.052241 -213.532649) (xy 266.068309 -213.586056) (xy 266.076429 -213.641232)
			(xy 266.076938 -213.669118) (xy 266.076519 -213.692051) (xy 266.953978 -213.692051) (xy 266.953978 -213.637549)
			(xy 266.961734 -213.583601) (xy 266.977089 -213.531306) (xy 266.999731 -213.481729) (xy 267.029197 -213.435879)
			(xy 267.064888 -213.394688) (xy 267.106079 -213.358997) (xy 267.151929 -213.329531) (xy 267.201506 -213.306889)
			(xy 267.253801 -213.291534) (xy 267.307749 -213.283778) (xy 267.335 -213.283292) (xy 267.364053 -213.283833)
			(xy 267.421489 -213.292632) (xy 267.476926 -213.31004) (xy 267.529081 -213.335657) (xy 267.576747 -213.368888)
			(xy 267.61882 -213.408964) (xy 267.637006 -213.431628) (xy 267.646374 -213.442846) (xy 267.670074 -213.459923)
			(xy 267.697638 -213.46959) (xy 267.726812 -213.471057) (xy 267.755208 -213.464204) (xy 267.7805 -213.44959)
			(xy 267.80062 -213.428413) (xy 267.807694 -213.415626) (xy 267.820022 -213.39245) (xy 267.850021 -213.349374)
			(xy 267.885639 -213.310814) (xy 267.926205 -213.277499) (xy 267.970953 -213.250057) (xy 268.01904 -213.229005)
			(xy 268.069558 -213.214742) (xy 268.121554 -213.207535) (xy 268.1478 -213.207092) (xy 268.175051 -213.207578)
			(xy 268.228999 -213.215334) (xy 268.281294 -213.230689) (xy 268.330871 -213.253331) (xy 268.376721 -213.282797)
			(xy 268.417912 -213.318488) (xy 268.453603 -213.359679) (xy 268.483069 -213.405529) (xy 268.505711 -213.455106)
			(xy 268.521066 -213.507401) (xy 268.528822 -213.561349) (xy 268.528822 -213.615851) (xy 268.521066 -213.669799)
			(xy 268.505711 -213.722094) (xy 268.483069 -213.771671) (xy 268.453603 -213.817521) (xy 268.417912 -213.858712)
			(xy 268.376721 -213.894403) (xy 268.330871 -213.923869) (xy 268.281294 -213.946511) (xy 268.228999 -213.961866)
			(xy 268.175051 -213.969622) (xy 268.1478 -213.970108) (xy 268.118747 -213.969567) (xy 268.061311 -213.960768)
			(xy 268.005874 -213.94336) (xy 267.953719 -213.917743) (xy 267.906053 -213.884512) (xy 267.86398 -213.844436)
			(xy 267.845794 -213.821772) (xy 267.836426 -213.810554) (xy 267.812726 -213.793477) (xy 267.785162 -213.78381)
			(xy 267.755988 -213.782343) (xy 267.727592 -213.789196) (xy 267.7023 -213.80381) (xy 267.68218 -213.824987)
			(xy 267.675106 -213.837774) (xy 267.662778 -213.86095) (xy 267.632779 -213.904026) (xy 267.597161 -213.942586)
			(xy 267.556595 -213.975901) (xy 267.511847 -214.003343) (xy 267.46376 -214.024395) (xy 267.413242 -214.038658)
			(xy 267.361246 -214.045865) (xy 267.335 -214.046308) (xy 267.307749 -214.045822) (xy 267.253801 -214.038066)
			(xy 267.201506 -214.022711) (xy 267.151929 -214.000069) (xy 267.106079 -213.970603) (xy 267.064888 -213.934912)
			(xy 267.029197 -213.893721) (xy 266.999731 -213.847871) (xy 266.977089 -213.798294) (xy 266.961734 -213.745999)
			(xy 266.953978 -213.692051) (xy 266.076519 -213.692051) (xy 266.076429 -213.697004) (xy 266.068309 -213.75218)
			(xy 266.052241 -213.805587) (xy 266.028569 -213.856084) (xy 265.997796 -213.902597) (xy 265.960579 -213.944134)
			(xy 265.917711 -213.979809) (xy 265.870105 -214.008863) (xy 265.818776 -214.030675) (xy 265.764819 -214.044781)
			(xy 265.709382 -214.050881) (xy 265.653648 -214.048844) (xy 265.598805 -214.038714) (xy 265.546021 -214.020707)
			(xy 265.496421 -213.995206) (xy 265.451063 -213.962755) (xy 265.410914 -213.924046) (xy 265.376828 -213.879903)
			(xy 265.349532 -213.831268) (xy 265.329609 -213.779177) (xy 265.317483 -213.72474) (xy 265.313412 -213.669118)
			(xy 264.749428 -213.669118) (xy 264.749784 -213.671473) (xy 264.750296 -213.700106) (xy 264.74981 -213.727357)
			(xy 264.742054 -213.781305) (xy 264.726699 -213.8336) (xy 264.704057 -213.883177) (xy 264.674591 -213.929027)
			(xy 264.6389 -213.970218) (xy 264.597709 -214.005909) (xy 264.551859 -214.035375) (xy 264.502282 -214.058017)
			(xy 264.449987 -214.073372) (xy 264.396039 -214.081128) (xy 264.341537 -214.081128) (xy 264.287589 -214.073372)
			(xy 264.235294 -214.058017) (xy 264.185717 -214.035375) (xy 264.139867 -214.005909) (xy 264.098676 -213.970218)
			(xy 264.062985 -213.929027) (xy 264.033519 -213.883177) (xy 264.010877 -213.8336) (xy 263.995522 -213.781305)
			(xy 263.987766 -213.727357) (xy 263.98728 -213.700106) (xy 259.902452 -213.700106) (xy 259.902452 -215.118442)
			(xy 259.901598 -215.142213) (xy 259.893616 -215.189103) (xy 259.87867 -215.234258) (xy 259.857101 -215.276652)
			(xy 259.829399 -215.315317) (xy 259.796196 -215.349375) (xy 259.777484 -215.36406) (xy 259.655564 -215.452452)
			(xy 259.650684 -215.455808) (xy 259.639779 -215.460421) (xy 259.633974 -215.461596) (xy 259.578856 -215.47074)
			(xy 259.578348 -215.47074) (xy 259.540248 -215.477598) (xy 259.537454 -215.47836) (xy 259.526786 -215.481408)
			(xy 259.51307 -215.48344) (xy 259.508498 -215.48344) (xy 259.498338 -215.485218) (xy 259.437886 -215.465152)
			(xy 259.435854 -215.464644) (xy 259.421884 -215.459818) (xy 259.414518 -215.458294) (xy 259.411724 -215.457786)
			(xy 259.39496 -215.4555) (xy 259.393182 -215.4555) (xy 259.377531 -215.45558) (xy 259.347139 -215.463014)
			(xy 259.319774 -215.478181) (xy 259.297362 -215.500012) (xy 259.281481 -215.52697) (xy 259.273251 -215.557155)
			(xy 259.27325 -215.588442) (xy 259.28148 -215.618628) (xy 259.29736 -215.645586) (xy 259.319772 -215.667418)
			(xy 259.347137 -215.682585) (xy 259.377528 -215.69002) (xy 259.393182 -215.690196) (xy 259.395976 -215.690196)
			(xy 259.411724 -215.68791) (xy 259.41401 -215.687402) (xy 259.415534 -215.687148) (xy 259.421884 -215.685878)
			(xy 259.435854 -215.681052) (xy 259.437886 -215.680544) (xy 259.486146 -215.664542) (xy 259.492198 -215.662733)
			(xy 259.504792 -215.661828) (xy 259.511038 -215.662764) (xy 259.578348 -215.674956) (xy 259.578856 -215.674956)
			(xy 259.633974 -215.6841) (xy 259.639794 -215.685229) (xy 259.650712 -215.68984) (xy 259.655564 -215.693244)
			(xy 259.777484 -215.781636) (xy 259.796187 -215.796329) (xy 259.829372 -215.830398) (xy 259.857063 -215.869066)
			(xy 259.87863 -215.911455) (xy 259.893584 -215.956603) (xy 259.895758 -215.969342) (xy 261.698484 -215.969342)
			(xy 261.702555 -215.91372) (xy 261.714681 -215.859283) (xy 261.734604 -215.807192) (xy 261.7619 -215.758557)
			(xy 261.795986 -215.714414) (xy 261.836135 -215.675705) (xy 261.881493 -215.643254) (xy 261.931093 -215.617753)
			(xy 261.983877 -215.599746) (xy 262.03872 -215.589616) (xy 262.094454 -215.587579) (xy 262.149891 -215.593679)
			(xy 262.203848 -215.607785) (xy 262.255177 -215.629597) (xy 262.302783 -215.658651) (xy 262.345651 -215.694326)
			(xy 262.382868 -215.735863) (xy 262.413641 -215.782376) (xy 262.437313 -215.832873) (xy 262.453381 -215.88628)
			(xy 262.461501 -215.941456) (xy 262.46201 -215.969342) (xy 262.461501 -215.997228) (xy 262.453381 -216.052404)
			(xy 262.437313 -216.105811) (xy 262.413641 -216.156308) (xy 262.382868 -216.202821) (xy 262.345651 -216.244358)
			(xy 262.302783 -216.280033) (xy 262.255177 -216.309087) (xy 262.203848 -216.330899) (xy 262.149891 -216.345005)
			(xy 262.094454 -216.351105) (xy 262.03872 -216.349068) (xy 261.983877 -216.338938) (xy 261.931093 -216.320931)
			(xy 261.881493 -216.29543) (xy 261.836135 -216.262979) (xy 261.795986 -216.22427) (xy 261.7619 -216.180127)
			(xy 261.734604 -216.131492) (xy 261.714681 -216.079401) (xy 261.702555 -216.024964) (xy 261.698484 -215.969342)
			(xy 259.895758 -215.969342) (xy 259.901586 -216.003486) (xy 259.902452 -216.027254) (xy 259.902452 -217.432382)
			(xy 266.08608 -217.432382) (xy 266.090151 -217.37676) (xy 266.102277 -217.322323) (xy 266.1222 -217.270232)
			(xy 266.149496 -217.221597) (xy 266.183582 -217.177454) (xy 266.223731 -217.138745) (xy 266.269089 -217.106294)
			(xy 266.318689 -217.080793) (xy 266.371473 -217.062786) (xy 266.426316 -217.052656) (xy 266.48205 -217.050619)
			(xy 266.537487 -217.056719) (xy 266.591444 -217.070825) (xy 266.642773 -217.092637) (xy 266.690379 -217.121691)
			(xy 266.733247 -217.157366) (xy 266.770464 -217.198903) (xy 266.801237 -217.245416) (xy 266.822085 -217.289888)
			(xy 267.310868 -217.289888) (xy 267.314939 -217.234266) (xy 267.327065 -217.179829) (xy 267.346988 -217.127738)
			(xy 267.374284 -217.079103) (xy 267.40837 -217.03496) (xy 267.448519 -216.996251) (xy 267.493877 -216.9638)
			(xy 267.543477 -216.938299) (xy 267.596261 -216.920292) (xy 267.651104 -216.910162) (xy 267.706838 -216.908125)
			(xy 267.762275 -216.914225) (xy 267.816232 -216.928331) (xy 267.867561 -216.950143) (xy 267.915167 -216.979197)
			(xy 267.958035 -217.014872) (xy 267.995252 -217.056409) (xy 268.026025 -217.102922) (xy 268.049697 -217.153419)
			(xy 268.065765 -217.206826) (xy 268.073885 -217.262002) (xy 268.074394 -217.289888) (xy 268.073885 -217.317774)
			(xy 268.065765 -217.37295) (xy 268.049697 -217.426357) (xy 268.026025 -217.476854) (xy 267.995252 -217.523367)
			(xy 267.958035 -217.564904) (xy 267.915167 -217.600579) (xy 267.867561 -217.629633) (xy 267.816232 -217.651445)
			(xy 267.762275 -217.665551) (xy 267.706838 -217.671651) (xy 267.651104 -217.669614) (xy 267.596261 -217.659484)
			(xy 267.543477 -217.641477) (xy 267.493877 -217.615976) (xy 267.448519 -217.583525) (xy 267.40837 -217.544816)
			(xy 267.374284 -217.500673) (xy 267.346988 -217.452038) (xy 267.327065 -217.399947) (xy 267.314939 -217.34551)
			(xy 267.310868 -217.289888) (xy 266.822085 -217.289888) (xy 266.824909 -217.295913) (xy 266.840977 -217.34932)
			(xy 266.849097 -217.404496) (xy 266.849606 -217.432382) (xy 266.849097 -217.460268) (xy 266.840977 -217.515444)
			(xy 266.824909 -217.568851) (xy 266.801237 -217.619348) (xy 266.770464 -217.665861) (xy 266.733247 -217.707398)
			(xy 266.690379 -217.743073) (xy 266.642773 -217.772127) (xy 266.591444 -217.793939) (xy 266.537487 -217.808045)
			(xy 266.48205 -217.814145) (xy 266.426316 -217.812108) (xy 266.371473 -217.801978) (xy 266.318689 -217.783971)
			(xy 266.269089 -217.75847) (xy 266.223731 -217.726019) (xy 266.183582 -217.68731) (xy 266.149496 -217.643167)
			(xy 266.1222 -217.594532) (xy 266.102277 -217.542441) (xy 266.090151 -217.488004) (xy 266.08608 -217.432382)
			(xy 259.902452 -217.432382) (xy 259.902452 -218.74734) (xy 264.893042 -218.74734) (xy 264.897113 -218.691718)
			(xy 264.909239 -218.637281) (xy 264.929162 -218.58519) (xy 264.956458 -218.536555) (xy 264.990544 -218.492412)
			(xy 265.030693 -218.453703) (xy 265.076051 -218.421252) (xy 265.125651 -218.395751) (xy 265.178435 -218.377744)
			(xy 265.233278 -218.367614) (xy 265.289012 -218.365577) (xy 265.344449 -218.371677) (xy 265.398406 -218.385783)
			(xy 265.449735 -218.407595) (xy 265.497341 -218.436649) (xy 265.540209 -218.472324) (xy 265.577426 -218.513861)
			(xy 265.608199 -218.560374) (xy 265.631871 -218.610871) (xy 265.647939 -218.664278) (xy 265.656059 -218.719454)
			(xy 265.656568 -218.74734) (xy 265.656059 -218.775226) (xy 265.647939 -218.830402) (xy 265.631871 -218.883809)
			(xy 265.608199 -218.934306) (xy 265.577426 -218.980819) (xy 265.540209 -219.022356) (xy 265.497341 -219.058031)
			(xy 265.449735 -219.087085) (xy 265.398406 -219.108897) (xy 265.344449 -219.123003) (xy 265.289012 -219.129103)
			(xy 265.233278 -219.127066) (xy 265.178435 -219.116936) (xy 265.125651 -219.098929) (xy 265.076051 -219.073428)
			(xy 265.030693 -219.040977) (xy 264.990544 -219.002268) (xy 264.956458 -218.958125) (xy 264.929162 -218.90949)
			(xy 264.909239 -218.857399) (xy 264.897113 -218.802962) (xy 264.893042 -218.74734) (xy 259.902452 -218.74734)
			(xy 259.902452 -219.176649) (xy 262.556 -219.176649) (xy 262.556 -219.122151) (xy 262.563756 -219.068207)
			(xy 262.57911 -219.015916) (xy 262.601749 -218.966343) (xy 262.631212 -218.920495) (xy 262.666901 -218.879308)
			(xy 262.708087 -218.843618) (xy 262.753934 -218.814154) (xy 262.803507 -218.791513) (xy 262.855797 -218.776158)
			(xy 262.909741 -218.768401) (xy 262.93699 -218.767914) (xy 262.964289 -218.7684) (xy 263.01833 -218.776171)
			(xy 263.070711 -218.791568) (xy 263.120361 -218.814279) (xy 263.166264 -218.843837) (xy 263.18718 -218.861386)
			(xy 263.194369 -218.867232) (xy 263.211702 -218.873739) (xy 263.220962 -218.874086) (xy 263.296908 -218.873832)
			(xy 263.313926 -218.867482) (xy 263.320784 -218.861386) (xy 263.34175 -218.843678) (xy 263.387781 -218.813799)
			(xy 263.437621 -218.790831) (xy 263.490241 -218.77525) (xy 263.544551 -218.767377) (xy 263.57199 -218.766898)
			(xy 263.599244 -218.767349) (xy 263.653197 -218.775105) (xy 263.705496 -218.79046) (xy 263.755079 -218.813102)
			(xy 263.800934 -218.84257) (xy 263.842128 -218.878265) (xy 263.877824 -218.919458) (xy 263.907293 -218.965313)
			(xy 263.929936 -219.014894) (xy 263.945293 -219.067194) (xy 263.953051 -219.121146) (xy 263.953051 -219.175654)
			(xy 263.945293 -219.229606) (xy 263.929936 -219.281906) (xy 263.907293 -219.331487) (xy 263.877824 -219.377342)
			(xy 263.842128 -219.418535) (xy 263.800934 -219.45423) (xy 263.755079 -219.483698) (xy 263.705496 -219.50634)
			(xy 263.653197 -219.521695) (xy 263.599244 -219.529451) (xy 263.57199 -219.529914) (xy 263.544691 -219.529432)
			(xy 263.49065 -219.52166) (xy 263.438269 -219.506261) (xy 263.38862 -219.48355) (xy 263.342716 -219.453991)
			(xy 263.3218 -219.436442) (xy 263.314593 -219.430622) (xy 263.297273 -219.424102) (xy 263.288018 -219.423742)
			(xy 263.212072 -219.423996) (xy 263.195054 -219.430346) (xy 263.188196 -219.436442) (xy 263.167242 -219.454164)
			(xy 263.121207 -219.48404) (xy 263.071364 -219.507005) (xy 263.018742 -219.522583) (xy 262.96443 -219.530452)
			(xy 262.93699 -219.53093) (xy 262.909741 -219.530399) (xy 262.855797 -219.522642) (xy 262.803507 -219.507287)
			(xy 262.753934 -219.484646) (xy 262.708087 -219.455182) (xy 262.666901 -219.419492) (xy 262.631212 -219.378305)
			(xy 262.601749 -219.332457) (xy 262.57911 -219.282884) (xy 262.563756 -219.230593) (xy 262.556 -219.176649)
			(xy 259.902452 -219.176649) (xy 259.902452 -221.577408) (xy 265.124182 -221.577408) (xy 265.128253 -221.521786)
			(xy 265.140379 -221.467349) (xy 265.160302 -221.415258) (xy 265.187598 -221.366623) (xy 265.221684 -221.32248)
			(xy 265.261833 -221.283771) (xy 265.307191 -221.25132) (xy 265.356791 -221.225819) (xy 265.409575 -221.207812)
			(xy 265.464418 -221.197682) (xy 265.520152 -221.195645) (xy 265.575589 -221.201745) (xy 265.629546 -221.215851)
			(xy 265.680875 -221.237663) (xy 265.728481 -221.266717) (xy 265.771349 -221.302392) (xy 265.808566 -221.343929)
			(xy 265.839339 -221.390442) (xy 265.863011 -221.440939) (xy 265.879079 -221.494346) (xy 265.887199 -221.549522)
			(xy 265.887708 -221.577408) (xy 265.887199 -221.605294) (xy 265.879079 -221.66047) (xy 265.863011 -221.713877)
			(xy 265.839339 -221.764374) (xy 265.808566 -221.810887) (xy 265.771349 -221.852424) (xy 265.728481 -221.888099)
			(xy 265.680875 -221.917153) (xy 265.629546 -221.938965) (xy 265.575589 -221.953071) (xy 265.520152 -221.959171)
			(xy 265.464418 -221.957134) (xy 265.409575 -221.947004) (xy 265.356791 -221.928997) (xy 265.307191 -221.903496)
			(xy 265.261833 -221.871045) (xy 265.221684 -221.832336) (xy 265.187598 -221.788193) (xy 265.160302 -221.739558)
			(xy 265.140379 -221.687467) (xy 265.128253 -221.63303) (xy 265.124182 -221.577408) (xy 259.902452 -221.577408)
			(xy 259.902452 -222.323152) (xy 263.362184 -222.323152) (xy 263.366255 -222.26753) (xy 263.378381 -222.213093)
			(xy 263.398304 -222.161002) (xy 263.4256 -222.112367) (xy 263.459686 -222.068224) (xy 263.499835 -222.029515)
			(xy 263.545193 -221.997064) (xy 263.594793 -221.971563) (xy 263.647577 -221.953556) (xy 263.70242 -221.943426)
			(xy 263.758154 -221.941389) (xy 263.813591 -221.947489) (xy 263.867548 -221.961595) (xy 263.918877 -221.983407)
			(xy 263.966483 -222.012461) (xy 264.009351 -222.048136) (xy 264.046568 -222.089673) (xy 264.077341 -222.136186)
			(xy 264.101013 -222.186683) (xy 264.117081 -222.24009) (xy 264.125201 -222.295266) (xy 264.12571 -222.323152)
			(xy 264.125201 -222.351038) (xy 264.117081 -222.406214) (xy 264.101013 -222.459621) (xy 264.077341 -222.510118)
			(xy 264.046568 -222.556631) (xy 264.009351 -222.598168) (xy 263.966483 -222.633843) (xy 263.918877 -222.662897)
			(xy 263.867548 -222.684709) (xy 263.813591 -222.698815) (xy 263.758154 -222.704915) (xy 263.70242 -222.702878)
			(xy 263.647577 -222.692748) (xy 263.594793 -222.674741) (xy 263.545193 -222.64924) (xy 263.499835 -222.616789)
			(xy 263.459686 -222.57808) (xy 263.4256 -222.533937) (xy 263.398304 -222.485302) (xy 263.378381 -222.433211)
			(xy 263.366255 -222.378774) (xy 263.362184 -222.323152) (xy 259.902452 -222.323152) (xy 259.902452 -223.347534)
			(xy 267.562582 -223.347534) (xy 267.566653 -223.291912) (xy 267.578779 -223.237475) (xy 267.598702 -223.185384)
			(xy 267.625998 -223.136749) (xy 267.660084 -223.092606) (xy 267.700233 -223.053897) (xy 267.745591 -223.021446)
			(xy 267.795191 -222.995945) (xy 267.847975 -222.977938) (xy 267.902818 -222.967808) (xy 267.958552 -222.965771)
			(xy 268.013989 -222.971871) (xy 268.067946 -222.985977) (xy 268.119275 -223.007789) (xy 268.166881 -223.036843)
			(xy 268.209749 -223.072518) (xy 268.246966 -223.114055) (xy 268.277739 -223.160568) (xy 268.301411 -223.211065)
			(xy 268.317479 -223.264472) (xy 268.325599 -223.319648) (xy 268.326108 -223.347534) (xy 268.325599 -223.37542)
			(xy 268.317479 -223.430596) (xy 268.301411 -223.484003) (xy 268.277739 -223.5345) (xy 268.246966 -223.581013)
			(xy 268.209749 -223.62255) (xy 268.166881 -223.658225) (xy 268.119275 -223.687279) (xy 268.067946 -223.709091)
			(xy 268.013989 -223.723197) (xy 267.958552 -223.729297) (xy 267.902818 -223.72726) (xy 267.847975 -223.71713)
			(xy 267.795191 -223.699123) (xy 267.745591 -223.673622) (xy 267.700233 -223.641171) (xy 267.660084 -223.602462)
			(xy 267.625998 -223.558319) (xy 267.598702 -223.509684) (xy 267.578779 -223.457593) (xy 267.566653 -223.403156)
			(xy 267.562582 -223.347534) (xy 259.902452 -223.347534) (xy 259.902452 -224.190814) (xy 259.902699 -224.197995)
			(xy 259.906699 -224.211789) (xy 259.910326 -224.217992) (xy 259.91439 -224.224088) (xy 259.92455 -224.233232)
			(xy 259.931408 -224.236534) (xy 259.932424 -224.237042) (xy 259.950204 -224.244662) (xy 260.004814 -224.26803)
			(xy 260.005576 -224.268284) (xy 260.0071 -224.268792) (xy 260.016014 -224.271792) (xy 260.03481 -224.271674)
			(xy 260.043676 -224.268538) (xy 260.063996 -224.26041) (xy 260.070854 -224.25406) (xy 260.092049 -224.235426)
			(xy 260.138901 -224.203966) (xy 260.189877 -224.179754) (xy 260.243865 -224.163317) (xy 260.299685 -224.155016)
			(xy 260.327902 -224.154492) (xy 260.355153 -224.154978) (xy 260.409101 -224.162735) (xy 260.461395 -224.17809)
			(xy 260.510972 -224.200731) (xy 260.556822 -224.230198) (xy 260.598012 -224.265889) (xy 260.633704 -224.307079)
			(xy 260.66317 -224.35293) (xy 260.685811 -224.402507) (xy 260.701166 -224.454801) (xy 260.708922 -224.508749)
			(xy 260.708922 -224.563251) (xy 260.701166 -224.617199) (xy 260.685811 -224.669493) (xy 260.66317 -224.71907)
			(xy 260.633704 -224.764921) (xy 260.598012 -224.806111) (xy 260.556822 -224.841802) (xy 260.510972 -224.871269)
			(xy 260.461395 -224.89391) (xy 260.409101 -224.909265) (xy 260.355153 -224.917022) (xy 260.327902 -224.917508)
			(xy 260.299684 -224.917) (xy 260.243863 -224.908691) (xy 260.189874 -224.892253) (xy 260.138893 -224.868044)
			(xy 260.092033 -224.836593) (xy 260.070854 -224.81794) (xy 260.063996 -224.81159) (xy 260.044438 -224.803462)
			(xy 260.035548 -224.800922) (xy 260.027797 -224.799552) (xy 260.012144 -224.801102) (xy 260.004814 -224.80397)
			(xy 259.950204 -224.827338) (xy 259.92328 -224.839022) (xy 259.91439 -224.843372) (xy 259.900538 -224.857484)
			(xy 259.896356 -224.866454) (xy 259.893747 -224.873515) (xy 259.892324 -224.888493) (xy 259.893562 -224.895918)
			(xy 259.901436 -224.934018) (xy 259.902452 -224.944178) (xy 259.902452 -225.097086) (xy 263.196068 -225.097086)
			(xy 263.200139 -225.041464) (xy 263.212265 -224.987027) (xy 263.232188 -224.934936) (xy 263.259484 -224.886301)
			(xy 263.29357 -224.842158) (xy 263.333719 -224.803449) (xy 263.379077 -224.770998) (xy 263.428677 -224.745497)
			(xy 263.481461 -224.72749) (xy 263.536304 -224.71736) (xy 263.592038 -224.715323) (xy 263.647475 -224.721423)
			(xy 263.701432 -224.735529) (xy 263.752761 -224.757341) (xy 263.800367 -224.786395) (xy 263.843235 -224.82207)
			(xy 263.880452 -224.863607) (xy 263.911225 -224.91012) (xy 263.934897 -224.960617) (xy 263.950965 -225.014024)
			(xy 263.959085 -225.0692) (xy 263.959594 -225.097086) (xy 263.959085 -225.124972) (xy 263.950965 -225.180148)
			(xy 263.934897 -225.233555) (xy 263.911225 -225.284052) (xy 263.880452 -225.330565) (xy 263.843235 -225.372102)
			(xy 263.800367 -225.407777) (xy 263.752761 -225.436831) (xy 263.701432 -225.458643) (xy 263.698957 -225.45929)
			(xy 268.389352 -225.45929) (xy 268.393423 -225.403668) (xy 268.405549 -225.349231) (xy 268.425472 -225.29714)
			(xy 268.452768 -225.248505) (xy 268.486854 -225.204362) (xy 268.527003 -225.165653) (xy 268.572361 -225.133202)
			(xy 268.621961 -225.107701) (xy 268.674745 -225.089694) (xy 268.729588 -225.079564) (xy 268.785322 -225.077527)
			(xy 268.840759 -225.083627) (xy 268.894716 -225.097733) (xy 268.946045 -225.119545) (xy 268.993651 -225.148599)
			(xy 269.036519 -225.184274) (xy 269.073736 -225.225811) (xy 269.104509 -225.272324) (xy 269.128181 -225.322821)
			(xy 269.144249 -225.376228) (xy 269.152369 -225.431404) (xy 269.152878 -225.45929) (xy 269.152369 -225.487176)
			(xy 269.144249 -225.542352) (xy 269.128181 -225.595759) (xy 269.104509 -225.646256) (xy 269.073736 -225.692769)
			(xy 269.036519 -225.734306) (xy 268.993651 -225.769981) (xy 268.946045 -225.799035) (xy 268.894716 -225.820847)
			(xy 268.840759 -225.834953) (xy 268.785322 -225.841053) (xy 268.729588 -225.839016) (xy 268.674745 -225.828886)
			(xy 268.621961 -225.810879) (xy 268.572361 -225.785378) (xy 268.527003 -225.752927) (xy 268.486854 -225.714218)
			(xy 268.452768 -225.670075) (xy 268.425472 -225.62144) (xy 268.405549 -225.569349) (xy 268.393423 -225.514912)
			(xy 268.389352 -225.45929) (xy 263.698957 -225.45929) (xy 263.647475 -225.472749) (xy 263.592038 -225.478849)
			(xy 263.536304 -225.476812) (xy 263.481461 -225.466682) (xy 263.428677 -225.448675) (xy 263.379077 -225.423174)
			(xy 263.333719 -225.390723) (xy 263.29357 -225.352014) (xy 263.259484 -225.307871) (xy 263.232188 -225.259236)
			(xy 263.212265 -225.207145) (xy 263.200139 -225.152708) (xy 263.196068 -225.097086) (xy 259.902452 -225.097086)
			(xy 259.902452 -226.3394) (xy 266.392912 -226.3394) (xy 266.396983 -226.283778) (xy 266.409109 -226.229341)
			(xy 266.429032 -226.17725) (xy 266.456328 -226.128615) (xy 266.490414 -226.084472) (xy 266.530563 -226.045763)
			(xy 266.575921 -226.013312) (xy 266.625521 -225.987811) (xy 266.678305 -225.969804) (xy 266.733148 -225.959674)
			(xy 266.788882 -225.957637) (xy 266.844319 -225.963737) (xy 266.898276 -225.977843) (xy 266.949605 -225.999655)
			(xy 266.997211 -226.028709) (xy 267.040079 -226.064384) (xy 267.077296 -226.105921) (xy 267.108069 -226.152434)
			(xy 267.131741 -226.202931) (xy 267.147809 -226.256338) (xy 267.155929 -226.311514) (xy 267.156438 -226.3394)
			(xy 267.155929 -226.367286) (xy 267.147809 -226.422462) (xy 267.131741 -226.475869) (xy 267.108069 -226.526366)
			(xy 267.077296 -226.572879) (xy 267.040079 -226.614416) (xy 266.997211 -226.650091) (xy 266.949605 -226.679145)
			(xy 266.898276 -226.700957) (xy 266.844319 -226.715063) (xy 266.788882 -226.721163) (xy 266.733148 -226.719126)
			(xy 266.678305 -226.708996) (xy 266.625521 -226.690989) (xy 266.575921 -226.665488) (xy 266.530563 -226.633037)
			(xy 266.490414 -226.594328) (xy 266.456328 -226.550185) (xy 266.429032 -226.50155) (xy 266.409109 -226.449459)
			(xy 266.396983 -226.395022) (xy 266.392912 -226.3394) (xy 259.902452 -226.3394) (xy 259.902452 -228.865938)
			(xy 259.901942 -228.891141) (xy 259.89388 -228.940897) (xy 259.877983 -228.98873) (xy 259.85466 -229.033415)
			(xy 259.839968 -229.053898) (xy 259.833091 -229.062935) (xy 259.818219 -229.080098) (xy 259.81025 -229.088188)
			(xy 259.646888 -229.25151) (xy 263.272522 -229.25151) (xy 263.276593 -229.195888) (xy 263.288719 -229.141451)
			(xy 263.308642 -229.08936) (xy 263.335938 -229.040725) (xy 263.370024 -228.996582) (xy 263.410173 -228.957873)
			(xy 263.455531 -228.925422) (xy 263.505131 -228.899921) (xy 263.557915 -228.881914) (xy 263.612758 -228.871784)
			(xy 263.668492 -228.869747) (xy 263.723929 -228.875847) (xy 263.777886 -228.889953) (xy 263.829215 -228.911765)
			(xy 263.876821 -228.940819) (xy 263.919689 -228.976494) (xy 263.956906 -229.018031) (xy 263.987679 -229.064544)
			(xy 264.011351 -229.115041) (xy 264.027419 -229.168448) (xy 264.035539 -229.223624) (xy 264.036048 -229.25151)
			(xy 264.035539 -229.279396) (xy 264.027419 -229.334572) (xy 264.011351 -229.387979) (xy 263.987679 -229.438476)
			(xy 263.956906 -229.484989) (xy 263.919689 -229.526526) (xy 263.876821 -229.562201) (xy 263.829215 -229.591255)
			(xy 263.777886 -229.613067) (xy 263.723929 -229.627173) (xy 263.668492 -229.633273) (xy 263.612758 -229.631236)
			(xy 263.557915 -229.621106) (xy 263.505131 -229.603099) (xy 263.455531 -229.577598) (xy 263.410173 -229.545147)
			(xy 263.370024 -229.506438) (xy 263.335938 -229.462295) (xy 263.308642 -229.41366) (xy 263.288719 -229.361569)
			(xy 263.276593 -229.307132) (xy 263.272522 -229.25151) (xy 259.646888 -229.25151) (xy 258.782566 -230.115618)
			(xy 258.767373 -230.130363) (xy 258.73372 -230.156054) (xy 258.696919 -230.176988) (xy 258.67741 -230.185214)
			(xy 258.64934 -230.195691) (xy 258.590523 -230.20707) (xy 258.56057 -230.20782) (xy 255.754378 -230.20782)
			(xy 255.742186 -230.206296) (xy 255.738884 -230.20528) (xy 255.727962 -230.201216) (xy 255.723722 -230.199788)
			(xy 255.714909 -230.198252) (xy 255.710436 -230.198168) (xy 255.68402 -230.198168) (xy 255.68275 -230.198168)
			(xy 255.67692 -230.198469) (xy 255.665626 -230.201412) (xy 255.660398 -230.20401) (xy 255.658366 -230.20528)
			(xy 255.64846 -230.211122) (xy 255.641602 -230.21798) (xy 255.620093 -230.238193) (xy 255.572 -230.27241)
			(xy 255.519212 -230.298812) (xy 255.462987 -230.316769) (xy 255.404667 -230.325853) (xy 255.375156 -230.326438)
			(xy 255.374902 -230.326438) (xy 255.374394 -230.326438) (xy 255.358646 -230.326184) (xy 255.35382 -230.32593)
			(xy 255.353566 -230.32593) (xy 255.325724 -230.323841) (xy 255.271038 -230.312597) (xy 255.218571 -230.293511)
			(xy 255.169442 -230.266989) (xy 255.124698 -230.233598) (xy 255.104646 -230.21417) (xy 255.103122 -230.212646)
			(xy 255.093724 -230.204264) (xy 255.08331 -230.200962) (xy 255.074928 -230.198168) (xy 255.022604 -230.198168)
			(xy 255.017016 -230.199438) (xy 254.999613 -230.203278) (xy 254.964222 -230.207478) (xy 254.946404 -230.20782)
			(xy 249.234198 -230.20782) (xy 249.221527 -230.208563) (xy 249.199263 -230.220684) (xy 249.19178 -230.230934)
			(xy 249.137932 -230.31323) (xy 249.1359 -230.33863) (xy 249.141234 -230.350568) (xy 249.151565 -230.37499)
			(xy 249.166138 -230.425975) (xy 249.17351 -230.478487) (xy 249.174 -230.505) (xy 249.173514 -230.532251)
			(xy 249.165758 -230.586199) (xy 249.150403 -230.638494) (xy 249.127761 -230.688071) (xy 249.098295 -230.733921)
			(xy 249.062604 -230.775112) (xy 249.021413 -230.810803) (xy 248.975563 -230.840269) (xy 248.925986 -230.862911)
			(xy 248.873691 -230.878266) (xy 248.819743 -230.886022) (xy 248.765241 -230.886022) (xy 248.711293 -230.878266)
			(xy 248.658998 -230.862911) (xy 248.609421 -230.840269) (xy 248.563571 -230.810803) (xy 248.52238 -230.775112)
			(xy 248.486689 -230.733921) (xy 248.457223 -230.688071) (xy 248.434581 -230.638494) (xy 248.419226 -230.586199)
			(xy 248.41147 -230.532251) (xy 248.410984 -230.505) (xy 248.411367 -230.480423) (xy 248.417683 -230.431676)
			(xy 248.430211 -230.384146) (xy 248.448743 -230.338619) (xy 248.460514 -230.31704) (xy 248.46534 -230.308658)
			(xy 248.46788 -230.289354) (xy 248.44629 -230.202486) (xy 248.43486 -230.186738) (xy 248.429272 -230.183182)
			(xy 248.426218 -230.181381) (xy 248.420605 -230.177051) (xy 248.418096 -230.174546) (xy 248.417842 -230.174292)
			(xy 248.393966 -230.150416) (xy 248.389648 -230.146606) (xy 248.387362 -230.144574) (xy 248.386092 -230.143558)
			(xy 248.38533 -230.14305) (xy 248.377139 -230.136773) (xy 248.361506 -230.1233) (xy 248.354088 -230.116126)
			(xy 247.579642 -229.341426) (xy 247.57255 -229.334188) (xy 247.559206 -229.318935) (xy 247.552972 -229.310946)
			(xy 247.552718 -229.310438) (xy 247.551702 -229.309168) (xy 247.545352 -229.301802) (xy 247.521222 -229.277672)
			(xy 247.514378 -229.270273) (xy 247.50665 -229.251675) (xy 247.506236 -229.241604) (xy 247.506236 -229.23373)
			(xy 247.503442 -229.217474) (xy 247.502426 -229.214172) (xy 247.495671 -229.191201) (xy 247.488406 -229.143877)
			(xy 247.487948 -229.119938) (xy 247.487948 -223.724978) (xy 247.487372 -223.710006) (xy 247.478602 -223.681371)
			(xy 247.46191 -223.656506) (xy 247.438728 -223.637546) (xy 247.411046 -223.626118) (xy 247.38124 -223.623203)
			(xy 247.351868 -223.629051) (xy 247.325452 -223.64316) (xy 247.314466 -223.65335) (xy 247.189752 -223.778064)
			(xy 247.17756 -223.789494) (xy 247.17502 -223.79178) (xy 247.11279 -223.85401) (xy 247.111266 -223.85528)
			(xy 247.108472 -223.858074) (xy 247.099328 -223.861884) (xy 247.094589 -223.863757) (xy 247.084609 -223.865809)
			(xy 247.079516 -223.865948) (xy 246.985028 -223.865948) (xy 246.97563 -223.866456) (xy 240.728246 -223.866456)
			(xy 240.722588 -223.866642) (xy 240.711565 -223.869214) (xy 240.706402 -223.871536) (xy 240.686844 -223.881696)
			(xy 240.685066 -223.882712) (xy 240.67516 -223.888808) (xy 240.669318 -223.896936) (xy 240.652779 -223.918604)
			(xy 240.614569 -223.957477) (xy 240.57122 -223.990523) (xy 240.523614 -224.017072) (xy 240.472718 -224.036584)
			(xy 240.419565 -224.048663) (xy 240.365235 -224.053063) (xy 240.310831 -224.049696) (xy 240.257458 -224.03863)
			(xy 240.2062 -224.020088) (xy 240.158098 -223.994449) (xy 240.114129 -223.962233) (xy 240.075187 -223.924093)
			(xy 240.058194 -223.902778) (xy 240.055908 -223.89973) (xy 240.0554 -223.899222) (xy 240.05286 -223.89592)
			(xy 240.052098 -223.894904) (xy 240.048418 -223.890483) (xy 240.03944 -223.883297) (xy 240.034318 -223.88068)
			(xy 240.02365 -223.875346) (xy 240.023142 -223.875346) (xy 240.0173 -223.872298) (xy 240.011712 -223.869504)
			(xy 239.999774 -223.866456) (xy 236.298486 -223.866456) (xy 236.289088 -223.865948) (xy 235.500672 -223.865948)
			(xy 235.490258 -223.866456) (xy 235.444538 -223.866456) (xy 235.434124 -223.865948) (xy 234.700572 -223.865948)
			(xy 234.690158 -223.866456) (xy 234.644692 -223.866456) (xy 234.634278 -223.865948) (xy 233.900726 -223.865948)
			(xy 233.890312 -223.866456) (xy 233.844592 -223.866456) (xy 233.834178 -223.865948) (xy 233.100626 -223.865948)
			(xy 233.090212 -223.866456) (xy 233.044746 -223.866456) (xy 233.034332 -223.865948) (xy 232.30078 -223.865948)
			(xy 232.290366 -223.866456) (xy 232.244646 -223.866456) (xy 232.234232 -223.865948) (xy 231.50068 -223.865948)
			(xy 231.490266 -223.866456) (xy 231.444546 -223.866456) (xy 231.434132 -223.865948) (xy 230.70058 -223.865948)
			(xy 230.690166 -223.866456) (xy 230.6447 -223.866456) (xy 230.634286 -223.865948) (xy 229.84587 -223.865948)
			(xy 229.836472 -223.866456) (xy 229.098856 -223.866456) (xy 229.089458 -223.865948) (xy 228.301042 -223.865948)
			(xy 228.290628 -223.866456) (xy 228.245162 -223.866456) (xy 228.234748 -223.865948) (xy 227.501196 -223.865948)
			(xy 227.490782 -223.866456) (xy 227.445062 -223.866456) (xy 227.434648 -223.865948) (xy 226.701096 -223.865948)
			(xy 226.690682 -223.866456) (xy 226.644962 -223.866456) (xy 226.634548 -223.865948) (xy 225.900996 -223.865948)
			(xy 225.890582 -223.866456) (xy 225.845116 -223.866456) (xy 225.834702 -223.865948) (xy 225.10115 -223.865948)
			(xy 225.090736 -223.866456) (xy 225.045016 -223.866456) (xy 225.034602 -223.865948) (xy 224.246186 -223.865948)
			(xy 224.236788 -223.866456) (xy 221.553532 -223.866456) (xy 221.54326 -223.866973) (xy 221.524382 -223.875089)
			(xy 221.516956 -223.882204) (xy 221.494604 -223.905318) (xy 221.465902 -223.935036) (xy 221.461076 -223.941132)
			(xy 221.462346 -223.962214) (xy 221.463108 -223.995234) (xy 221.463108 -224.329831) (xy 223.537782 -224.329831)
			(xy 223.537782 -224.277857) (xy 223.545912 -224.226522) (xy 223.561973 -224.177092) (xy 223.585569 -224.130782)
			(xy 223.616119 -224.088734) (xy 223.65287 -224.051983) (xy 223.694918 -224.021433) (xy 223.741228 -223.997837)
			(xy 223.790658 -223.981776) (xy 223.841993 -223.973646) (xy 223.893967 -223.973646) (xy 223.945302 -223.981776)
			(xy 223.994732 -223.997837) (xy 224.041042 -224.021433) (xy 224.08309 -224.051983) (xy 224.119841 -224.088734)
			(xy 224.150391 -224.130782) (xy 224.173987 -224.177092) (xy 224.190048 -224.226522) (xy 224.198178 -224.277857)
			(xy 224.198688 -224.303844) (xy 224.198178 -224.329831) (xy 233.137204 -224.329831) (xy 233.137204 -224.277857)
			(xy 233.145334 -224.226522) (xy 233.161395 -224.177092) (xy 233.184991 -224.130782) (xy 233.215541 -224.088734)
			(xy 233.252292 -224.051983) (xy 233.29434 -224.021433) (xy 233.34065 -223.997837) (xy 233.39008 -223.981776)
			(xy 233.441415 -223.973646) (xy 233.493389 -223.973646) (xy 233.544724 -223.981776) (xy 233.594154 -223.997837)
			(xy 233.640464 -224.021433) (xy 233.682512 -224.051983) (xy 233.719263 -224.088734) (xy 233.749813 -224.130782)
			(xy 233.773409 -224.177092) (xy 233.78947 -224.226522) (xy 233.7976 -224.277857) (xy 233.79811 -224.303844)
			(xy 233.7976 -224.329831) (xy 233.937304 -224.329831) (xy 233.937304 -224.277857) (xy 233.945434 -224.226522)
			(xy 233.961495 -224.177092) (xy 233.985091 -224.130782) (xy 234.015641 -224.088734) (xy 234.052392 -224.051983)
			(xy 234.09444 -224.021433) (xy 234.14075 -223.997837) (xy 234.19018 -223.981776) (xy 234.241515 -223.973646)
			(xy 234.293489 -223.973646) (xy 234.344824 -223.981776) (xy 234.394254 -223.997837) (xy 234.440564 -224.021433)
			(xy 234.482612 -224.051983) (xy 234.519363 -224.088734) (xy 234.549913 -224.130782) (xy 234.573509 -224.177092)
			(xy 234.58957 -224.226522) (xy 234.5977 -224.277857) (xy 234.59821 -224.303844) (xy 234.5977 -224.329831)
			(xy 234.73715 -224.329831) (xy 234.73715 -224.277857) (xy 234.74528 -224.226522) (xy 234.761341 -224.177092)
			(xy 234.784937 -224.130782) (xy 234.815487 -224.088734) (xy 234.852238 -224.051983) (xy 234.894286 -224.021433)
			(xy 234.940596 -223.997837) (xy 234.990026 -223.981776) (xy 235.041361 -223.973646) (xy 235.093335 -223.973646)
			(xy 235.14467 -223.981776) (xy 235.1941 -223.997837) (xy 235.24041 -224.021433) (xy 235.282458 -224.051983)
			(xy 235.319209 -224.088734) (xy 235.349759 -224.130782) (xy 235.373355 -224.177092) (xy 235.389416 -224.226522)
			(xy 235.397546 -224.277857) (xy 235.398056 -224.303844) (xy 235.397546 -224.329831) (xy 235.53725 -224.329831)
			(xy 235.53725 -224.277857) (xy 235.54538 -224.226522) (xy 235.561441 -224.177092) (xy 235.585037 -224.130782)
			(xy 235.615587 -224.088734) (xy 235.652338 -224.051983) (xy 235.694386 -224.021433) (xy 235.740696 -223.997837)
			(xy 235.790126 -223.981776) (xy 235.841461 -223.973646) (xy 235.893435 -223.973646) (xy 235.94477 -223.981776)
			(xy 235.9942 -223.997837) (xy 236.04051 -224.021433) (xy 236.082558 -224.051983) (xy 236.119309 -224.088734)
			(xy 236.149859 -224.130782) (xy 236.173455 -224.177092) (xy 236.189516 -224.226522) (xy 236.197646 -224.277857)
			(xy 236.198156 -224.303844) (xy 236.197646 -224.329831) (xy 236.189516 -224.381166) (xy 236.173455 -224.430596)
			(xy 236.149859 -224.476906) (xy 236.119309 -224.518954) (xy 236.082558 -224.555705) (xy 236.04051 -224.586255)
			(xy 235.9942 -224.609851) (xy 235.94477 -224.625912) (xy 235.893435 -224.634042) (xy 235.841461 -224.634042)
			(xy 235.790126 -224.625912) (xy 235.740696 -224.609851) (xy 235.694386 -224.586255) (xy 235.652338 -224.555705)
			(xy 235.615587 -224.518954) (xy 235.585037 -224.476906) (xy 235.561441 -224.430596) (xy 235.54538 -224.381166)
			(xy 235.53725 -224.329831) (xy 235.397546 -224.329831) (xy 235.389416 -224.381166) (xy 235.373355 -224.430596)
			(xy 235.349759 -224.476906) (xy 235.319209 -224.518954) (xy 235.282458 -224.555705) (xy 235.24041 -224.586255)
			(xy 235.1941 -224.609851) (xy 235.14467 -224.625912) (xy 235.093335 -224.634042) (xy 235.041361 -224.634042)
			(xy 234.990026 -224.625912) (xy 234.940596 -224.609851) (xy 234.894286 -224.586255) (xy 234.852238 -224.555705)
			(xy 234.815487 -224.518954) (xy 234.784937 -224.476906) (xy 234.761341 -224.430596) (xy 234.74528 -224.381166)
			(xy 234.73715 -224.329831) (xy 234.5977 -224.329831) (xy 234.58957 -224.381166) (xy 234.573509 -224.430596)
			(xy 234.549913 -224.476906) (xy 234.519363 -224.518954) (xy 234.482612 -224.555705) (xy 234.440564 -224.586255)
			(xy 234.394254 -224.609851) (xy 234.344824 -224.625912) (xy 234.293489 -224.634042) (xy 234.241515 -224.634042)
			(xy 234.19018 -224.625912) (xy 234.14075 -224.609851) (xy 234.09444 -224.586255) (xy 234.052392 -224.555705)
			(xy 234.015641 -224.518954) (xy 233.985091 -224.476906) (xy 233.961495 -224.430596) (xy 233.945434 -224.381166)
			(xy 233.937304 -224.329831) (xy 233.7976 -224.329831) (xy 233.78947 -224.381166) (xy 233.773409 -224.430596)
			(xy 233.749813 -224.476906) (xy 233.719263 -224.518954) (xy 233.682512 -224.555705) (xy 233.640464 -224.586255)
			(xy 233.594154 -224.609851) (xy 233.544724 -224.625912) (xy 233.493389 -224.634042) (xy 233.441415 -224.634042)
			(xy 233.39008 -224.625912) (xy 233.34065 -224.609851) (xy 233.29434 -224.586255) (xy 233.252292 -224.555705)
			(xy 233.215541 -224.518954) (xy 233.184991 -224.476906) (xy 233.161395 -224.430596) (xy 233.145334 -224.381166)
			(xy 233.137204 -224.329831) (xy 224.198178 -224.329831) (xy 224.190048 -224.381166) (xy 224.173987 -224.430596)
			(xy 224.150391 -224.476906) (xy 224.119841 -224.518954) (xy 224.08309 -224.555705) (xy 224.041042 -224.586255)
			(xy 223.994732 -224.609851) (xy 223.945302 -224.625912) (xy 223.893967 -224.634042) (xy 223.841993 -224.634042)
			(xy 223.790658 -224.625912) (xy 223.741228 -224.609851) (xy 223.694918 -224.586255) (xy 223.65287 -224.555705)
			(xy 223.616119 -224.518954) (xy 223.585569 -224.476906) (xy 223.561973 -224.430596) (xy 223.545912 -224.381166)
			(xy 223.537782 -224.329831) (xy 221.463108 -224.329831) (xy 221.463108 -225.129931) (xy 223.537782 -225.129931)
			(xy 223.537782 -225.077957) (xy 223.545912 -225.026622) (xy 223.561973 -224.977192) (xy 223.585569 -224.930882)
			(xy 223.616119 -224.888834) (xy 223.65287 -224.852083) (xy 223.694918 -224.821533) (xy 223.741228 -224.797937)
			(xy 223.790658 -224.781876) (xy 223.841993 -224.773746) (xy 223.893967 -224.773746) (xy 223.945302 -224.781876)
			(xy 223.994732 -224.797937) (xy 224.041042 -224.821533) (xy 224.08309 -224.852083) (xy 224.119841 -224.888834)
			(xy 224.150391 -224.930882) (xy 224.173987 -224.977192) (xy 224.190048 -225.026622) (xy 224.198178 -225.077957)
			(xy 224.198688 -225.103944) (xy 224.198178 -225.129931) (xy 224.193431 -225.159903) (xy 224.354392 -225.159903)
			(xy 224.354392 -225.107929) (xy 224.362522 -225.056594) (xy 224.378583 -225.007164) (xy 224.402179 -224.960854)
			(xy 224.432729 -224.918806) (xy 224.46948 -224.882055) (xy 224.511528 -224.851505) (xy 224.557838 -224.827909)
			(xy 224.607268 -224.811848) (xy 224.658603 -224.803718) (xy 224.710577 -224.803718) (xy 224.761912 -224.811848)
			(xy 224.811342 -224.827909) (xy 224.857652 -224.851505) (xy 224.8997 -224.882055) (xy 224.936451 -224.918806)
			(xy 224.967001 -224.960854) (xy 224.990597 -225.007164) (xy 225.006658 -225.056594) (xy 225.014788 -225.107929)
			(xy 225.01522 -225.129931) (xy 233.937304 -225.129931) (xy 233.937304 -225.077957) (xy 233.945434 -225.026622)
			(xy 233.961495 -224.977192) (xy 233.985091 -224.930882) (xy 234.015641 -224.888834) (xy 234.052392 -224.852083)
			(xy 234.09444 -224.821533) (xy 234.14075 -224.797937) (xy 234.19018 -224.781876) (xy 234.241515 -224.773746)
			(xy 234.293489 -224.773746) (xy 234.344824 -224.781876) (xy 234.394254 -224.797937) (xy 234.440564 -224.821533)
			(xy 234.482612 -224.852083) (xy 234.519363 -224.888834) (xy 234.549913 -224.930882) (xy 234.573509 -224.977192)
			(xy 234.58957 -225.026622) (xy 234.5977 -225.077957) (xy 234.59821 -225.103944) (xy 234.5977 -225.129931)
			(xy 234.73715 -225.129931) (xy 234.73715 -225.077957) (xy 234.74528 -225.026622) (xy 234.761341 -224.977192)
			(xy 234.784937 -224.930882) (xy 234.815487 -224.888834) (xy 234.852238 -224.852083) (xy 234.894286 -224.821533)
			(xy 234.940596 -224.797937) (xy 234.990026 -224.781876) (xy 235.041361 -224.773746) (xy 235.093335 -224.773746)
			(xy 235.14467 -224.781876) (xy 235.1941 -224.797937) (xy 235.24041 -224.821533) (xy 235.282458 -224.852083)
			(xy 235.319209 -224.888834) (xy 235.349759 -224.930882) (xy 235.373355 -224.977192) (xy 235.389416 -225.026622)
			(xy 235.397546 -225.077957) (xy 235.398056 -225.103944) (xy 235.397546 -225.129931) (xy 235.53725 -225.129931)
			(xy 235.53725 -225.077957) (xy 235.54538 -225.026622) (xy 235.561441 -224.977192) (xy 235.585037 -224.930882)
			(xy 235.615587 -224.888834) (xy 235.652338 -224.852083) (xy 235.694386 -224.821533) (xy 235.740696 -224.797937)
			(xy 235.790126 -224.781876) (xy 235.841461 -224.773746) (xy 235.893435 -224.773746) (xy 235.94477 -224.781876)
			(xy 235.9942 -224.797937) (xy 236.04051 -224.821533) (xy 236.082558 -224.852083) (xy 236.119309 -224.888834)
			(xy 236.149859 -224.930882) (xy 236.173455 -224.977192) (xy 236.189516 -225.026622) (xy 236.197646 -225.077957)
			(xy 236.198156 -225.103944) (xy 236.197646 -225.129931) (xy 236.189516 -225.181266) (xy 236.173455 -225.230696)
			(xy 236.157773 -225.261473) (xy 239.822113 -225.261473) (xy 239.822113 -225.201527) (xy 239.829938 -225.142093)
			(xy 239.845454 -225.084189) (xy 239.868395 -225.028806) (xy 239.89837 -224.976891) (xy 239.934864 -224.929333)
			(xy 239.977254 -224.886945) (xy 240.024814 -224.850454) (xy 240.076731 -224.820483) (xy 240.132115 -224.797545)
			(xy 240.19002 -224.782032) (xy 240.249455 -224.774211) (xy 240.279428 -224.773744) (xy 241.143028 -224.773744)
			(xy 241.172991 -224.774332) (xy 241.232405 -224.782157) (xy 241.290289 -224.79767) (xy 241.345653 -224.820606)
			(xy 241.39755 -224.850571) (xy 241.445091 -224.887054) (xy 241.487465 -224.92943) (xy 241.523944 -224.976974)
			(xy 241.553907 -225.028872) (xy 241.576839 -225.084238) (xy 241.592348 -225.142123) (xy 241.60017 -225.201537)
			(xy 241.60017 -225.261463) (xy 241.592348 -225.320877) (xy 241.576839 -225.378762) (xy 241.553907 -225.434128)
			(xy 241.523944 -225.486026) (xy 241.487465 -225.53357) (xy 241.445091 -225.575946) (xy 241.39755 -225.612429)
			(xy 241.345653 -225.642394) (xy 241.290289 -225.66533) (xy 241.232405 -225.680843) (xy 241.172991 -225.688668)
			(xy 241.143028 -225.68916) (xy 240.279428 -225.68916) (xy 240.249455 -225.688789) (xy 240.19002 -225.680968)
			(xy 240.132115 -225.665455) (xy 240.076731 -225.642517) (xy 240.024814 -225.612546) (xy 239.977254 -225.576055)
			(xy 239.934864 -225.533667) (xy 239.89837 -225.486109) (xy 239.868395 -225.434194) (xy 239.845454 -225.378811)
			(xy 239.829938 -225.320907) (xy 239.822113 -225.261473) (xy 236.157773 -225.261473) (xy 236.149859 -225.277006)
			(xy 236.119309 -225.319054) (xy 236.082558 -225.355805) (xy 236.04051 -225.386355) (xy 235.9942 -225.409951)
			(xy 235.94477 -225.426012) (xy 235.893435 -225.434142) (xy 235.841461 -225.434142) (xy 235.790126 -225.426012)
			(xy 235.740696 -225.409951) (xy 235.694386 -225.386355) (xy 235.652338 -225.355805) (xy 235.615587 -225.319054)
			(xy 235.585037 -225.277006) (xy 235.561441 -225.230696) (xy 235.54538 -225.181266) (xy 235.53725 -225.129931)
			(xy 235.397546 -225.129931) (xy 235.389416 -225.181266) (xy 235.373355 -225.230696) (xy 235.349759 -225.277006)
			(xy 235.319209 -225.319054) (xy 235.282458 -225.355805) (xy 235.24041 -225.386355) (xy 235.1941 -225.409951)
			(xy 235.14467 -225.426012) (xy 235.093335 -225.434142) (xy 235.041361 -225.434142) (xy 234.990026 -225.426012)
			(xy 234.940596 -225.409951) (xy 234.894286 -225.386355) (xy 234.852238 -225.355805) (xy 234.815487 -225.319054)
			(xy 234.784937 -225.277006) (xy 234.761341 -225.230696) (xy 234.74528 -225.181266) (xy 234.73715 -225.129931)
			(xy 234.5977 -225.129931) (xy 234.58957 -225.181266) (xy 234.573509 -225.230696) (xy 234.549913 -225.277006)
			(xy 234.519363 -225.319054) (xy 234.482612 -225.355805) (xy 234.440564 -225.386355) (xy 234.394254 -225.409951)
			(xy 234.344824 -225.426012) (xy 234.293489 -225.434142) (xy 234.241515 -225.434142) (xy 234.19018 -225.426012)
			(xy 234.14075 -225.409951) (xy 234.09444 -225.386355) (xy 234.052392 -225.355805) (xy 234.015641 -225.319054)
			(xy 233.985091 -225.277006) (xy 233.961495 -225.230696) (xy 233.945434 -225.181266) (xy 233.937304 -225.129931)
			(xy 225.01522 -225.129931) (xy 225.015298 -225.133916) (xy 225.014788 -225.159903) (xy 225.006658 -225.211238)
			(xy 224.990597 -225.260668) (xy 224.967001 -225.306978) (xy 224.936451 -225.349026) (xy 224.8997 -225.385777)
			(xy 224.857652 -225.416327) (xy 224.811342 -225.439923) (xy 224.761912 -225.455984) (xy 224.710577 -225.464114)
			(xy 224.658603 -225.464114) (xy 224.607268 -225.455984) (xy 224.557838 -225.439923) (xy 224.511528 -225.416327)
			(xy 224.46948 -225.385777) (xy 224.432729 -225.349026) (xy 224.402179 -225.306978) (xy 224.378583 -225.260668)
			(xy 224.362522 -225.211238) (xy 224.354392 -225.159903) (xy 224.193431 -225.159903) (xy 224.190048 -225.181266)
			(xy 224.173987 -225.230696) (xy 224.150391 -225.277006) (xy 224.119841 -225.319054) (xy 224.08309 -225.355805)
			(xy 224.041042 -225.386355) (xy 223.994732 -225.409951) (xy 223.945302 -225.426012) (xy 223.893967 -225.434142)
			(xy 223.841993 -225.434142) (xy 223.790658 -225.426012) (xy 223.741228 -225.409951) (xy 223.694918 -225.386355)
			(xy 223.65287 -225.355805) (xy 223.616119 -225.319054) (xy 223.585569 -225.277006) (xy 223.561973 -225.230696)
			(xy 223.545912 -225.181266) (xy 223.537782 -225.129931) (xy 221.463108 -225.129931) (xy 221.463108 -226.021117)
			(xy 224.466394 -226.021117) (xy 224.466394 -225.967819) (xy 224.474337 -225.915115) (xy 224.490047 -225.864185)
			(xy 224.513173 -225.816164) (xy 224.543197 -225.772127) (xy 224.579449 -225.733056) (xy 224.62112 -225.699825)
			(xy 224.667278 -225.673176) (xy 224.716892 -225.653704) (xy 224.768854 -225.641844) (xy 224.822004 -225.637861)
			(xy 224.875154 -225.641844) (xy 224.927116 -225.653704) (xy 224.97673 -225.673176) (xy 225.022888 -225.699825)
			(xy 225.064559 -225.733056) (xy 225.100811 -225.772127) (xy 225.130835 -225.816164) (xy 225.153961 -225.864185)
			(xy 225.169671 -225.915115) (xy 225.177614 -225.967819) (xy 225.178112 -225.994468) (xy 225.177614 -226.021117)
			(xy 225.169671 -226.073821) (xy 225.158264 -226.1108) (xy 236.422182 -226.1108) (xy 236.426253 -226.055178)
			(xy 236.438379 -226.000741) (xy 236.458302 -225.94865) (xy 236.485598 -225.900015) (xy 236.519684 -225.855872)
			(xy 236.559833 -225.817163) (xy 236.605191 -225.784712) (xy 236.654791 -225.759211) (xy 236.707575 -225.741204)
			(xy 236.762418 -225.731074) (xy 236.818152 -225.729037) (xy 236.873589 -225.735137) (xy 236.927546 -225.749243)
			(xy 236.978875 -225.771055) (xy 237.026481 -225.800109) (xy 237.069349 -225.835784) (xy 237.106566 -225.877321)
			(xy 237.137339 -225.923834) (xy 237.161011 -225.974331) (xy 237.177079 -226.027738) (xy 237.185199 -226.082914)
			(xy 237.185708 -226.1108) (xy 237.185199 -226.138686) (xy 237.177079 -226.193862) (xy 237.161011 -226.247269)
			(xy 237.137339 -226.297766) (xy 237.106566 -226.344279) (xy 237.084538 -226.368864) (xy 238.935258 -226.368864)
			(xy 238.939329 -226.313242) (xy 238.951455 -226.258805) (xy 238.971378 -226.206714) (xy 238.998674 -226.158079)
			(xy 239.03276 -226.113936) (xy 239.072909 -226.075227) (xy 239.118267 -226.042776) (xy 239.167867 -226.017275)
			(xy 239.220651 -225.999268) (xy 239.275494 -225.989138) (xy 239.331228 -225.987101) (xy 239.386665 -225.993201)
			(xy 239.440622 -226.007307) (xy 239.491951 -226.029119) (xy 239.539557 -226.058173) (xy 239.582425 -226.093848)
			(xy 239.619642 -226.135385) (xy 239.650415 -226.181898) (xy 239.674087 -226.232395) (xy 239.690155 -226.285802)
			(xy 239.698275 -226.340978) (xy 239.698784 -226.368864) (xy 239.698275 -226.39675) (xy 239.690155 -226.451926)
			(xy 239.674087 -226.505333) (xy 239.650415 -226.55583) (xy 239.619642 -226.602343) (xy 239.582425 -226.64388)
			(xy 239.539557 -226.679555) (xy 239.491951 -226.708609) (xy 239.440622 -226.730421) (xy 239.386665 -226.744527)
			(xy 239.331228 -226.750627) (xy 239.275494 -226.74859) (xy 239.220651 -226.73846) (xy 239.167867 -226.720453)
			(xy 239.118267 -226.694952) (xy 239.072909 -226.662501) (xy 239.03276 -226.623792) (xy 238.998674 -226.579649)
			(xy 238.971378 -226.531014) (xy 238.951455 -226.478923) (xy 238.939329 -226.424486) (xy 238.935258 -226.368864)
			(xy 237.084538 -226.368864) (xy 237.069349 -226.385816) (xy 237.026481 -226.421491) (xy 236.978875 -226.450545)
			(xy 236.927546 -226.472357) (xy 236.873589 -226.486463) (xy 236.818152 -226.492563) (xy 236.762418 -226.490526)
			(xy 236.707575 -226.480396) (xy 236.654791 -226.462389) (xy 236.605191 -226.436888) (xy 236.559833 -226.404437)
			(xy 236.519684 -226.365728) (xy 236.485598 -226.321585) (xy 236.458302 -226.27295) (xy 236.438379 -226.220859)
			(xy 236.426253 -226.166422) (xy 236.422182 -226.1108) (xy 225.158264 -226.1108) (xy 225.153961 -226.124751)
			(xy 225.130835 -226.172772) (xy 225.100811 -226.216809) (xy 225.064559 -226.25588) (xy 225.022888 -226.289111)
			(xy 224.97673 -226.31576) (xy 224.927116 -226.335232) (xy 224.875154 -226.347092) (xy 224.822004 -226.351076)
			(xy 224.768854 -226.347092) (xy 224.716892 -226.335232) (xy 224.667278 -226.31576) (xy 224.62112 -226.289111)
			(xy 224.579449 -226.25588) (xy 224.543197 -226.216809) (xy 224.513173 -226.172772) (xy 224.490047 -226.124751)
			(xy 224.474337 -226.073821) (xy 224.466394 -226.021117) (xy 221.463108 -226.021117) (xy 221.463108 -227.337366)
			(xy 235.629956 -227.337366) (xy 235.634027 -227.281744) (xy 235.646153 -227.227307) (xy 235.666076 -227.175216)
			(xy 235.693372 -227.126581) (xy 235.727458 -227.082438) (xy 235.767607 -227.043729) (xy 235.812965 -227.011278)
			(xy 235.862565 -226.985777) (xy 235.915349 -226.96777) (xy 235.970192 -226.95764) (xy 236.025926 -226.955603)
			(xy 236.081363 -226.961703) (xy 236.13532 -226.975809) (xy 236.186649 -226.997621) (xy 236.234255 -227.026675)
			(xy 236.277123 -227.06235) (xy 236.31434 -227.103887) (xy 236.345113 -227.1504) (xy 236.368785 -227.200897)
			(xy 236.384853 -227.254304) (xy 236.392973 -227.30948) (xy 236.393482 -227.337366) (xy 236.392973 -227.365252)
			(xy 236.384853 -227.420428) (xy 236.368785 -227.473835) (xy 236.345113 -227.524332) (xy 236.31434 -227.570845)
			(xy 236.277123 -227.612382) (xy 236.234255 -227.648057) (xy 236.186649 -227.677111) (xy 236.13532 -227.698923)
			(xy 236.081363 -227.713029) (xy 236.025926 -227.719129) (xy 235.970192 -227.717092) (xy 235.915349 -227.706962)
			(xy 235.862565 -227.688955) (xy 235.812965 -227.663454) (xy 235.767607 -227.631003) (xy 235.727458 -227.592294)
			(xy 235.693372 -227.548151) (xy 235.666076 -227.499516) (xy 235.646153 -227.447425) (xy 235.634027 -227.392988)
			(xy 235.629956 -227.337366) (xy 221.463108 -227.337366) (xy 221.463108 -227.845874) (xy 221.468442 -227.861368)
			(xy 221.473014 -227.867464) (xy 221.498922 -227.875338) (xy 221.524582 -227.883737) (xy 221.573422 -227.906752)
			(xy 221.618534 -227.936416) (xy 221.659018 -227.972138) (xy 221.694068 -228.013205) (xy 221.722985 -228.0588)
			(xy 221.745192 -228.108012) (xy 221.760246 -228.159862) (xy 221.767849 -228.213315) (xy 221.767847 -228.267306)
			(xy 221.760242 -228.320759) (xy 221.745184 -228.372608) (xy 221.722974 -228.421819) (xy 221.694055 -228.467412)
			(xy 221.659003 -228.508477) (xy 221.618517 -228.544197) (xy 221.573403 -228.573858) (xy 221.524562 -228.596871)
			(xy 221.498922 -228.605334) (xy 221.480888 -228.610922) (xy 221.468188 -228.619558) (xy 221.463108 -228.626162)
			(xy 221.463108 -228.830632) (xy 238.78235 -228.830632) (xy 238.786421 -228.77501) (xy 238.798547 -228.720573)
			(xy 238.81847 -228.668482) (xy 238.845766 -228.619847) (xy 238.879852 -228.575704) (xy 238.920001 -228.536995)
			(xy 238.965359 -228.504544) (xy 239.014959 -228.479043) (xy 239.067743 -228.461036) (xy 239.122586 -228.450906)
			(xy 239.17832 -228.448869) (xy 239.233757 -228.454969) (xy 239.287714 -228.469075) (xy 239.339043 -228.490887)
			(xy 239.386649 -228.519941) (xy 239.429517 -228.555616) (xy 239.466734 -228.597153) (xy 239.497507 -228.643666)
			(xy 239.521179 -228.694163) (xy 239.537247 -228.74757) (xy 239.545367 -228.802746) (xy 239.545876 -228.830632)
			(xy 239.545367 -228.858518) (xy 239.537247 -228.913694) (xy 239.521179 -228.967101) (xy 239.497507 -229.017598)
			(xy 239.466734 -229.064111) (xy 239.429517 -229.105648) (xy 239.386649 -229.141323) (xy 239.339043 -229.170377)
			(xy 239.287714 -229.192189) (xy 239.233757 -229.206295) (xy 239.17832 -229.212395) (xy 239.122586 -229.210358)
			(xy 239.067743 -229.200228) (xy 239.014959 -229.182221) (xy 238.965359 -229.15672) (xy 238.920001 -229.124269)
			(xy 238.879852 -229.08556) (xy 238.845766 -229.041417) (xy 238.81847 -228.992782) (xy 238.798547 -228.940691)
			(xy 238.786421 -228.886254) (xy 238.78235 -228.830632) (xy 221.463108 -228.830632) (xy 221.463108 -230.138224)
			(xy 221.463421 -230.146416) (xy 221.46861 -230.161957) (xy 221.473268 -230.168704) (xy 221.482503 -230.180166)
			(xy 221.506153 -230.197666) (xy 221.533809 -230.207706) (xy 221.563178 -230.209453) (xy 221.591829 -230.202762)
			(xy 221.60484 -230.195882) (xy 221.615762 -230.1875) (xy 222.13189 -229.671118) (xy 222.132398 -229.67061)
			(xy 222.167704 -229.634034) (xy 222.171487 -229.630252) (xy 222.180329 -229.624238) (xy 222.18523 -229.622096)
			(xy 222.28175 -229.583234) (xy 222.286316 -229.581474) (xy 222.295909 -229.579546) (xy 222.3008 -229.579424)
			(xy 225.376486 -229.579424) (xy 225.401949 -229.579924) (xy 225.452178 -229.588329) (xy 225.50033 -229.604911)
			(xy 225.545084 -229.629214) (xy 225.585212 -229.660572) (xy 225.6028 -229.678992) (xy 225.607118 -229.681024)
			(xy 225.613468 -229.684326) (xy 225.635566 -229.68839) (xy 225.636328 -229.688644) (xy 225.638868 -229.689152)
			(xy 225.64852 -229.690422) (xy 225.65559 -229.691154) (xy 225.669647 -229.689097) (xy 225.676206 -229.686358)
			(xy 225.679508 -229.68458) (xy 225.688398 -229.680516) (xy 225.713914 -229.669103) (xy 225.767449 -229.653025)
			(xy 225.822755 -229.644922) (xy 225.850704 -229.644448) (xy 225.851466 -229.644448) (xy 225.881207 -229.645038)
			(xy 225.939968 -229.654282) (xy 225.996596 -229.672491) (xy 226.023424 -229.685342) (xy 226.028758 -229.687882)
			(xy 226.040188 -229.690676) (xy 226.052126 -229.690676) (xy 226.082606 -229.685342) (xy 226.087087 -229.684444)
			(xy 226.095644 -229.68124) (xy 226.099624 -229.678992) (xy 226.117203 -229.660563) (xy 226.157342 -229.629219)
			(xy 226.202099 -229.604921) (xy 226.250249 -229.588334) (xy 226.300475 -229.579912) (xy 226.325938 -229.579424)
			(xy 230.391716 -229.579424) (xy 230.425244 -229.581202) (xy 230.430578 -229.581456) (xy 230.46055 -229.581456)
			(xy 230.468424 -229.585266) (xy 230.470964 -229.586282) (xy 230.488744 -229.594664) (xy 230.49357 -229.596696)
			(xy 230.508583 -229.60222) (xy 230.537472 -229.615962) (xy 230.551228 -229.624128) (xy 230.556308 -229.626922)
			(xy 230.573072 -229.634796) (xy 230.575612 -229.636066) (xy 230.583486 -229.639622) (xy 230.603806 -229.664514)
			(xy 230.604314 -229.665022) (xy 230.61676 -229.677468) (xy 230.617014 -229.677722) (xy 230.619046 -229.679246)
			(xy 230.623736 -229.682318) (xy 230.63412 -229.686538) (xy 230.63962 -229.687628) (xy 230.671624 -229.693216)
			(xy 230.680768 -229.691438) (xy 230.686356 -229.690422) (xy 230.697024 -229.687882) (xy 230.702104 -229.685342)
			(xy 230.71328 -229.680008) (xy 230.71455 -229.6795) (xy 230.717344 -229.678484) (xy 230.720138 -229.677214)
			(xy 230.72217 -229.676452) (xy 230.72471 -229.675182) (xy 230.734362 -229.671626) (xy 230.73614 -229.671118)
			(xy 230.751888 -229.665784) (xy 230.752142 -229.665784) (xy 230.756714 -229.66426) (xy 230.756968 -229.66426)
			(xy 230.763572 -229.662482) (xy 230.765096 -229.661974) (xy 230.765858 -229.66172) (xy 230.768652 -229.660958)
			(xy 230.803704 -229.653592) (xy 230.83166 -229.649491) (xy 230.888154 -229.648602) (xy 230.916226 -229.651814)
			(xy 230.922068 -229.652576) (xy 230.950083 -229.657269) (xy 231.004412 -229.673844) (xy 231.030272 -229.685596)
			(xy 231.035606 -229.688136) (xy 231.048306 -229.69093) (xy 231.048814 -229.69093) (xy 231.057704 -229.692962)
			(xy 231.092248 -229.687628) (xy 231.093772 -229.687374) (xy 231.106726 -229.68331) (xy 231.111298 -229.681024)
			(xy 231.139492 -229.646988) (xy 231.143126 -229.642775) (xy 231.151841 -229.635865) (xy 231.156764 -229.633272)
			(xy 231.259888 -229.58425) (xy 231.265063 -229.581994) (xy 231.276087 -229.579567) (xy 231.281732 -229.579424)
			(xy 233.637836 -229.579424) (xy 233.666792 -229.5525) (xy 233.668316 -229.53472) (xy 233.670954 -229.507753)
			(xy 233.682883 -229.454899) (xy 233.702171 -229.404264) (xy 233.728429 -229.356869) (xy 233.761131 -229.313666)
			(xy 233.799616 -229.275525) (xy 233.843112 -229.243214) (xy 233.890742 -229.217383) (xy 233.941547 -229.198551)
			(xy 233.994507 -229.187099) (xy 234.048554 -229.183255) (xy 234.102601 -229.187099) (xy 234.155561 -229.198551)
			(xy 234.206366 -229.217383) (xy 234.253996 -229.243214) (xy 234.297492 -229.275525) (xy 234.335977 -229.313666)
			(xy 234.368679 -229.356869) (xy 234.394937 -229.404264) (xy 234.414225 -229.454899) (xy 234.426154 -229.507753)
			(xy 234.428792 -229.53472) (xy 234.430316 -229.5525) (xy 234.459272 -229.579424) (xy 236.091476 -229.579424)
			(xy 236.100494 -229.57978) (xy 236.117413 -229.586023) (xy 236.124496 -229.591616) (xy 236.12475 -229.59187)
			(xy 236.142935 -229.569812) (xy 236.18479 -229.530874) (xy 236.231988 -229.498621) (xy 236.283474 -229.473776)
			(xy 236.338091 -229.456897) (xy 236.394617 -229.448362) (xy 236.4232 -229.447852) (xy 236.451498 -229.448366)
			(xy 236.507473 -229.456724) (xy 236.5616 -229.473257) (xy 236.612692 -229.497601) (xy 236.659629 -229.529225)
			(xy 236.701381 -229.567432) (xy 236.719618 -229.589076) (xy 236.726982 -229.597272) (xy 236.746726 -229.607003)
			(xy 236.768727 -229.607645) (xy 236.779054 -229.603808) (xy 236.807722 -229.592474) (xy 236.868124 -229.580196)
			(xy 236.898942 -229.579424) (xy 241.948208 -229.579424) (xy 241.981736 -229.581202) (xy 241.98707 -229.581456)
			(xy 241.997738 -229.581456) (xy 242.002629 -229.581591) (xy 242.012223 -229.583505) (xy 242.016788 -229.585266)
			(xy 242.026694 -229.58933) (xy 242.032028 -229.591108) (xy 242.04787 -229.595756) (xy 242.078543 -229.607975)
			(xy 242.093242 -229.615492) (xy 242.097814 -229.617778) (xy 242.112546 -229.623874) (xy 242.114324 -229.624636)
			(xy 242.122452 -229.627938) (xy 242.129056 -229.634796) (xy 242.129818 -229.635558) (xy 242.141502 -229.647496)
			(xy 242.145058 -229.650798) (xy 242.165378 -229.669594) (xy 242.253012 -229.757224) (xy 245.188484 -229.757224)
			(xy 245.192555 -229.701602) (xy 245.204681 -229.647165) (xy 245.224604 -229.595074) (xy 245.2519 -229.546439)
			(xy 245.285986 -229.502296) (xy 245.326135 -229.463587) (xy 245.371493 -229.431136) (xy 245.421093 -229.405635)
			(xy 245.473877 -229.387628) (xy 245.52872 -229.377498) (xy 245.584454 -229.375461) (xy 245.639891 -229.381561)
			(xy 245.693848 -229.395667) (xy 245.745177 -229.417479) (xy 245.792783 -229.446533) (xy 245.835651 -229.482208)
			(xy 245.872868 -229.523745) (xy 245.903641 -229.570258) (xy 245.927313 -229.620755) (xy 245.943381 -229.674162)
			(xy 245.951501 -229.729338) (xy 245.95201 -229.757224) (xy 245.951501 -229.78511) (xy 245.943381 -229.840286)
			(xy 245.927313 -229.893693) (xy 245.903641 -229.94419) (xy 245.872868 -229.990703) (xy 245.835651 -230.03224)
			(xy 245.792783 -230.067915) (xy 245.745177 -230.096969) (xy 245.693848 -230.118781) (xy 245.639891 -230.132887)
			(xy 245.584454 -230.138987) (xy 245.52872 -230.13695) (xy 245.473877 -230.12682) (xy 245.421093 -230.108813)
			(xy 245.371493 -230.083312) (xy 245.326135 -230.050861) (xy 245.285986 -230.012152) (xy 245.2519 -229.968009)
			(xy 245.224604 -229.919374) (xy 245.204681 -229.867283) (xy 245.192555 -229.812846) (xy 245.188484 -229.757224)
			(xy 242.253012 -229.757224) (xy 243.645507 -231.149652) (xy 247.010934 -231.149652) (xy 247.015005 -231.09403)
			(xy 247.027131 -231.039593) (xy 247.047054 -230.987502) (xy 247.07435 -230.938867) (xy 247.108436 -230.894724)
			(xy 247.148585 -230.856015) (xy 247.193943 -230.823564) (xy 247.243543 -230.798063) (xy 247.296327 -230.780056)
			(xy 247.35117 -230.769926) (xy 247.406904 -230.767889) (xy 247.462341 -230.773989) (xy 247.516298 -230.788095)
			(xy 247.567627 -230.809907) (xy 247.615233 -230.838961) (xy 247.658101 -230.874636) (xy 247.695318 -230.916173)
			(xy 247.726091 -230.962686) (xy 247.749763 -231.013183) (xy 247.765831 -231.06659) (xy 247.773951 -231.121766)
			(xy 247.774261 -231.13873) (xy 249.244864 -231.13873) (xy 249.248935 -231.083108) (xy 249.261061 -231.028671)
			(xy 249.280984 -230.97658) (xy 249.30828 -230.927945) (xy 249.342366 -230.883802) (xy 249.382515 -230.845093)
			(xy 249.427873 -230.812642) (xy 249.477473 -230.787141) (xy 249.530257 -230.769134) (xy 249.5851 -230.759004)
			(xy 249.640834 -230.756967) (xy 249.696271 -230.763067) (xy 249.750228 -230.777173) (xy 249.801557 -230.798985)
			(xy 249.849163 -230.828039) (xy 249.892031 -230.863714) (xy 249.929248 -230.905251) (xy 249.960021 -230.951764)
			(xy 249.983693 -231.002261) (xy 249.999761 -231.055668) (xy 250.007881 -231.110844) (xy 250.00839 -231.13873)
			(xy 250.007881 -231.166616) (xy 249.999761 -231.221792) (xy 249.983693 -231.275199) (xy 249.965509 -231.31399)
			(xy 256.87985 -231.31399) (xy 256.883921 -231.258368) (xy 256.896047 -231.203931) (xy 256.91597 -231.15184)
			(xy 256.943266 -231.103205) (xy 256.977352 -231.059062) (xy 257.017501 -231.020353) (xy 257.062859 -230.987902)
			(xy 257.112459 -230.962401) (xy 257.165243 -230.944394) (xy 257.220086 -230.934264) (xy 257.27582 -230.932227)
			(xy 257.331257 -230.938327) (xy 257.385214 -230.952433) (xy 257.436543 -230.974245) (xy 257.484149 -231.003299)
			(xy 257.527017 -231.038974) (xy 257.564234 -231.080511) (xy 257.595007 -231.127024) (xy 257.618679 -231.177521)
			(xy 257.634747 -231.230928) (xy 257.642867 -231.286104) (xy 257.643376 -231.31399) (xy 257.642867 -231.341876)
			(xy 257.634747 -231.397052) (xy 257.618679 -231.450459) (xy 257.595007 -231.500956) (xy 257.564234 -231.547469)
			(xy 257.527017 -231.589006) (xy 257.484149 -231.624681) (xy 257.436543 -231.653735) (xy 257.385214 -231.675547)
			(xy 257.331257 -231.689653) (xy 257.27582 -231.695753) (xy 257.220086 -231.693716) (xy 257.165243 -231.683586)
			(xy 257.112459 -231.665579) (xy 257.062859 -231.640078) (xy 257.017501 -231.607627) (xy 256.977352 -231.568918)
			(xy 256.943266 -231.524775) (xy 256.91597 -231.47614) (xy 256.896047 -231.424049) (xy 256.883921 -231.369612)
			(xy 256.87985 -231.31399) (xy 249.965509 -231.31399) (xy 249.960021 -231.325696) (xy 249.929248 -231.372209)
			(xy 249.892031 -231.413746) (xy 249.849163 -231.449421) (xy 249.801557 -231.478475) (xy 249.750228 -231.500287)
			(xy 249.696271 -231.514393) (xy 249.640834 -231.520493) (xy 249.5851 -231.518456) (xy 249.530257 -231.508326)
			(xy 249.477473 -231.490319) (xy 249.427873 -231.464818) (xy 249.382515 -231.432367) (xy 249.342366 -231.393658)
			(xy 249.30828 -231.349515) (xy 249.280984 -231.30088) (xy 249.261061 -231.248789) (xy 249.248935 -231.194352)
			(xy 249.244864 -231.13873) (xy 247.774261 -231.13873) (xy 247.77446 -231.149652) (xy 247.773951 -231.177538)
			(xy 247.765831 -231.232714) (xy 247.749763 -231.286121) (xy 247.726091 -231.336618) (xy 247.695318 -231.383131)
			(xy 247.658101 -231.424668) (xy 247.615233 -231.460343) (xy 247.567627 -231.489397) (xy 247.516298 -231.511209)
			(xy 247.462341 -231.525315) (xy 247.406904 -231.531415) (xy 247.35117 -231.529378) (xy 247.296327 -231.519248)
			(xy 247.243543 -231.501241) (xy 247.193943 -231.47574) (xy 247.148585 -231.443289) (xy 247.108436 -231.40458)
			(xy 247.07435 -231.360437) (xy 247.047054 -231.311802) (xy 247.027131 -231.259711) (xy 247.015005 -231.205274)
			(xy 247.010934 -231.149652) (xy 243.645507 -231.149652) (xy 245.559997 -233.06405) (xy 258.296408 -233.06405)
			(xy 258.300479 -233.008428) (xy 258.312605 -232.953991) (xy 258.332528 -232.9019) (xy 258.359824 -232.853265)
			(xy 258.39391 -232.809122) (xy 258.434059 -232.770413) (xy 258.479417 -232.737962) (xy 258.529017 -232.712461)
			(xy 258.581801 -232.694454) (xy 258.636644 -232.684324) (xy 258.692378 -232.682287) (xy 258.747815 -232.688387)
			(xy 258.801772 -232.702493) (xy 258.853101 -232.724305) (xy 258.900707 -232.753359) (xy 258.943575 -232.789034)
			(xy 258.980792 -232.830571) (xy 259.011565 -232.877084) (xy 259.035237 -232.927581) (xy 259.051305 -232.980988)
			(xy 259.059425 -233.036164) (xy 259.059934 -233.06405) (xy 259.059498 -233.087926) (xy 259.293866 -233.087926)
			(xy 259.297937 -233.032304) (xy 259.310063 -232.977867) (xy 259.329986 -232.925776) (xy 259.357282 -232.877141)
			(xy 259.391368 -232.832998) (xy 259.431517 -232.794289) (xy 259.476875 -232.761838) (xy 259.526475 -232.736337)
			(xy 259.579259 -232.71833) (xy 259.634102 -232.7082) (xy 259.689836 -232.706163) (xy 259.745273 -232.712263)
			(xy 259.79923 -232.726369) (xy 259.850559 -232.748181) (xy 259.898165 -232.777235) (xy 259.941033 -232.81291)
			(xy 259.97825 -232.854447) (xy 260.009023 -232.90096) (xy 260.032695 -232.951457) (xy 260.048763 -233.004864)
			(xy 260.056883 -233.06004) (xy 260.057392 -233.087926) (xy 260.057165 -233.100372) (xy 261.128762 -233.100372)
			(xy 261.132833 -233.04475) (xy 261.144959 -232.990313) (xy 261.164882 -232.938222) (xy 261.192178 -232.889587)
			(xy 261.226264 -232.845444) (xy 261.266413 -232.806735) (xy 261.311771 -232.774284) (xy 261.361371 -232.748783)
			(xy 261.414155 -232.730776) (xy 261.468998 -232.720646) (xy 261.524732 -232.718609) (xy 261.580169 -232.724709)
			(xy 261.634126 -232.738815) (xy 261.685455 -232.760627) (xy 261.733061 -232.789681) (xy 261.775929 -232.825356)
			(xy 261.813146 -232.866893) (xy 261.843919 -232.913406) (xy 261.867591 -232.963903) (xy 261.883659 -233.01731)
			(xy 261.891779 -233.072486) (xy 261.892288 -233.100372) (xy 261.891779 -233.128258) (xy 261.883659 -233.183434)
			(xy 261.867591 -233.236841) (xy 261.843919 -233.287338) (xy 261.813146 -233.333851) (xy 261.775929 -233.375388)
			(xy 261.733061 -233.411063) (xy 261.685455 -233.440117) (xy 261.634126 -233.461929) (xy 261.580169 -233.476035)
			(xy 261.524732 -233.482135) (xy 261.468998 -233.480098) (xy 261.414155 -233.469968) (xy 261.361371 -233.451961)
			(xy 261.311771 -233.42646) (xy 261.266413 -233.394009) (xy 261.226264 -233.3553) (xy 261.192178 -233.311157)
			(xy 261.164882 -233.262522) (xy 261.144959 -233.210431) (xy 261.132833 -233.155994) (xy 261.128762 -233.100372)
			(xy 260.057165 -233.100372) (xy 260.056883 -233.115812) (xy 260.048763 -233.170988) (xy 260.032695 -233.224395)
			(xy 260.009023 -233.274892) (xy 259.97825 -233.321405) (xy 259.941033 -233.362942) (xy 259.898165 -233.398617)
			(xy 259.850559 -233.427671) (xy 259.79923 -233.449483) (xy 259.745273 -233.463589) (xy 259.689836 -233.469689)
			(xy 259.634102 -233.467652) (xy 259.579259 -233.457522) (xy 259.526475 -233.439515) (xy 259.476875 -233.414014)
			(xy 259.431517 -233.381563) (xy 259.391368 -233.342854) (xy 259.357282 -233.298711) (xy 259.329986 -233.250076)
			(xy 259.310063 -233.197985) (xy 259.297937 -233.143548) (xy 259.293866 -233.087926) (xy 259.059498 -233.087926)
			(xy 259.059425 -233.091936) (xy 259.051305 -233.147112) (xy 259.035237 -233.200519) (xy 259.011565 -233.251016)
			(xy 258.980792 -233.297529) (xy 258.943575 -233.339066) (xy 258.900707 -233.374741) (xy 258.853101 -233.403795)
			(xy 258.801772 -233.425607) (xy 258.747815 -233.439713) (xy 258.692378 -233.445813) (xy 258.636644 -233.443776)
			(xy 258.581801 -233.433646) (xy 258.529017 -233.415639) (xy 258.479417 -233.390138) (xy 258.434059 -233.357687)
			(xy 258.39391 -233.318978) (xy 258.359824 -233.274835) (xy 258.332528 -233.2262) (xy 258.312605 -233.174109)
			(xy 258.300479 -233.119672) (xy 258.296408 -233.06405) (xy 245.559997 -233.06405) (xy 246.268437 -233.772456)
			(xy 250.902976 -233.772456) (xy 250.907047 -233.716834) (xy 250.919173 -233.662397) (xy 250.939096 -233.610306)
			(xy 250.966392 -233.561671) (xy 251.000478 -233.517528) (xy 251.040627 -233.478819) (xy 251.085985 -233.446368)
			(xy 251.135585 -233.420867) (xy 251.188369 -233.40286) (xy 251.243212 -233.39273) (xy 251.298946 -233.390693)
			(xy 251.354383 -233.396793) (xy 251.40834 -233.410899) (xy 251.459669 -233.432711) (xy 251.507275 -233.461765)
			(xy 251.550143 -233.49744) (xy 251.58736 -233.538977) (xy 251.618133 -233.58549) (xy 251.641805 -233.635987)
			(xy 251.657873 -233.689394) (xy 251.665993 -233.74457) (xy 251.666502 -233.772456) (xy 251.665993 -233.800342)
			(xy 251.657873 -233.855518) (xy 251.641805 -233.908925) (xy 251.618133 -233.959422) (xy 251.58736 -234.005935)
			(xy 251.550143 -234.047472) (xy 251.507275 -234.083147) (xy 251.459669 -234.112201) (xy 251.40834 -234.134013)
			(xy 251.354383 -234.148119) (xy 251.298946 -234.154219) (xy 251.243212 -234.152182) (xy 251.188369 -234.142052)
			(xy 251.135585 -234.124045) (xy 251.085985 -234.098544) (xy 251.040627 -234.066093) (xy 251.000478 -234.027384)
			(xy 250.966392 -233.983241) (xy 250.939096 -233.934606) (xy 250.919173 -233.882515) (xy 250.907047 -233.828078)
			(xy 250.902976 -233.772456) (xy 246.268437 -233.772456) (xy 247.190755 -234.69473) (xy 254.876044 -234.69473)
			(xy 254.880115 -234.639108) (xy 254.892241 -234.584671) (xy 254.912164 -234.53258) (xy 254.93946 -234.483945)
			(xy 254.973546 -234.439802) (xy 255.013695 -234.401093) (xy 255.059053 -234.368642) (xy 255.108653 -234.343141)
			(xy 255.161437 -234.325134) (xy 255.21628 -234.315004) (xy 255.272014 -234.312967) (xy 255.327451 -234.319067)
			(xy 255.381408 -234.333173) (xy 255.432737 -234.354985) (xy 255.480343 -234.384039) (xy 255.523211 -234.419714)
			(xy 255.560428 -234.461251) (xy 255.591201 -234.507764) (xy 255.614873 -234.558261) (xy 255.630941 -234.611668)
			(xy 255.639061 -234.666844) (xy 255.63957 -234.69473) (xy 255.639514 -234.697778) (xy 255.887472 -234.697778)
			(xy 255.891543 -234.642156) (xy 255.903669 -234.587719) (xy 255.923592 -234.535628) (xy 255.950888 -234.486993)
			(xy 255.984974 -234.44285) (xy 256.025123 -234.404141) (xy 256.070481 -234.37169) (xy 256.120081 -234.346189)
			(xy 256.172865 -234.328182) (xy 256.227708 -234.318052) (xy 256.283442 -234.316015) (xy 256.338879 -234.322115)
			(xy 256.392836 -234.336221) (xy 256.444165 -234.358033) (xy 256.491771 -234.387087) (xy 256.534639 -234.422762)
			(xy 256.571856 -234.464299) (xy 256.602629 -234.510812) (xy 256.626301 -234.561309) (xy 256.642369 -234.614716)
			(xy 256.650489 -234.669892) (xy 256.650998 -234.697778) (xy 256.650489 -234.725664) (xy 256.642369 -234.78084)
			(xy 256.626301 -234.834247) (xy 256.602629 -234.884744) (xy 256.571856 -234.931257) (xy 256.534639 -234.972794)
			(xy 256.491771 -235.008469) (xy 256.444165 -235.037523) (xy 256.392836 -235.059335) (xy 256.338879 -235.073441)
			(xy 256.283442 -235.079541) (xy 256.227708 -235.077504) (xy 256.172865 -235.067374) (xy 256.120081 -235.049367)
			(xy 256.070481 -235.023866) (xy 256.025123 -234.991415) (xy 255.984974 -234.952706) (xy 255.950888 -234.908563)
			(xy 255.923592 -234.859928) (xy 255.903669 -234.807837) (xy 255.891543 -234.7534) (xy 255.887472 -234.697778)
			(xy 255.639514 -234.697778) (xy 255.639061 -234.722616) (xy 255.630941 -234.777792) (xy 255.614873 -234.831199)
			(xy 255.591201 -234.881696) (xy 255.560428 -234.928209) (xy 255.523211 -234.969746) (xy 255.480343 -235.005421)
			(xy 255.432737 -235.034475) (xy 255.381408 -235.056287) (xy 255.327451 -235.070393) (xy 255.272014 -235.076493)
			(xy 255.21628 -235.074456) (xy 255.161437 -235.064326) (xy 255.108653 -235.046319) (xy 255.059053 -235.020818)
			(xy 255.013695 -234.988367) (xy 254.973546 -234.949658) (xy 254.93946 -234.905515) (xy 254.912164 -234.85688)
			(xy 254.892241 -234.804789) (xy 254.880115 -234.750352) (xy 254.876044 -234.69473) (xy 247.190755 -234.69473)
			(xy 247.450102 -234.954064) (xy 247.45061 -234.954572) (xy 247.487186 -234.989878) (xy 247.490974 -234.993656)
			(xy 247.497002 -235.002493) (xy 247.499124 -235.007404) (xy 247.537986 -235.103924) (xy 247.539738 -235.108491)
			(xy 247.541652 -235.118084) (xy 247.541796 -235.122974) (xy 247.541796 -236.917992) (xy 247.540018 -236.95152)
			(xy 247.539764 -236.956854) (xy 247.539764 -237.698788) (xy 262.005318 -237.698788) (xy 262.005772 -237.672474)
			(xy 262.013009 -237.620344) (xy 262.02733 -237.569701) (xy 262.048465 -237.521502) (xy 262.076014 -237.476659)
			(xy 262.109455 -237.43602) (xy 262.128508 -237.417864) (xy 262.135928 -237.410359) (xy 262.144442 -237.391066)
			(xy 262.145018 -237.380526) (xy 262.145018 -237.30585) (xy 262.14447 -237.295303) (xy 262.135947 -237.276007)
			(xy 262.128508 -237.268512) (xy 262.109467 -237.250342) (xy 262.076008 -237.209716) (xy 262.048447 -237.164878)
			(xy 262.027306 -237.11668) (xy 262.012986 -237.066035) (xy 262.005758 -237.013903) (xy 262.005318 -236.987588)
			(xy 262.005804 -236.960337) (xy 262.01356 -236.906389) (xy 262.028915 -236.854094) (xy 262.051557 -236.804517)
			(xy 262.081023 -236.758667) (xy 262.116714 -236.717476) (xy 262.157905 -236.681785) (xy 262.203755 -236.652319)
			(xy 262.253332 -236.629677) (xy 262.305627 -236.614322) (xy 262.359575 -236.606566) (xy 262.414077 -236.606566)
			(xy 262.468025 -236.614322) (xy 262.52032 -236.629677) (xy 262.523712 -236.631226) (xy 269.035274 -236.631226)
			(xy 269.039345 -236.575604) (xy 269.051471 -236.521167) (xy 269.071394 -236.469076) (xy 269.09869 -236.420441)
			(xy 269.132776 -236.376298) (xy 269.172925 -236.337589) (xy 269.218283 -236.305138) (xy 269.267883 -236.279637)
			(xy 269.320667 -236.26163) (xy 269.37551 -236.2515) (xy 269.431244 -236.249463) (xy 269.486681 -236.255563)
			(xy 269.540638 -236.269669) (xy 269.591967 -236.291481) (xy 269.639573 -236.320535) (xy 269.682441 -236.35621)
			(xy 269.719658 -236.397747) (xy 269.750431 -236.44426) (xy 269.774103 -236.494757) (xy 269.790171 -236.548164)
			(xy 269.798291 -236.60334) (xy 269.7988 -236.631226) (xy 269.798291 -236.659112) (xy 269.790171 -236.714288)
			(xy 269.784796 -236.732154) (xy 270.605941 -236.732154) (xy 270.605941 -236.677646) (xy 270.613698 -236.623692)
			(xy 270.629056 -236.571391) (xy 270.6517 -236.521808) (xy 270.68117 -236.475953) (xy 270.716866 -236.434758)
			(xy 270.758062 -236.399063) (xy 270.803919 -236.369594) (xy 270.853502 -236.346952) (xy 270.905803 -236.331596)
			(xy 270.959758 -236.32384) (xy 270.987012 -236.323378) (xy 271.015125 -236.323829) (xy 271.070744 -236.33207)
			(xy 271.124551 -236.348385) (xy 271.17538 -236.372422) (xy 271.22213 -236.40366) (xy 271.263788 -236.441422)
			(xy 271.299452 -236.48489) (xy 271.328349 -236.533122) (xy 271.349853 -236.585073) (xy 271.363498 -236.639618)
			(xy 271.366742 -236.667548) (xy 271.368574 -236.681793) (xy 271.379204 -236.708463) (xy 271.396837 -236.73112)
			(xy 271.420081 -236.747972) (xy 271.447098 -236.757688) (xy 271.475751 -236.759499) (xy 271.503776 -236.753261)
			(xy 271.516602 -236.746796) (xy 271.544887 -236.732019) (xy 271.605163 -236.711073) (xy 271.668084 -236.700452)
			(xy 271.69999 -236.699806) (xy 271.727244 -236.70024) (xy 271.781198 -236.707996) (xy 271.833499 -236.723352)
			(xy 271.883083 -236.745995) (xy 271.928939 -236.775464) (xy 271.970134 -236.811159) (xy 272.00583 -236.852353)
			(xy 272.0353 -236.898209) (xy 272.057944 -236.947791) (xy 272.073302 -237.000092) (xy 272.081059 -237.054046)
			(xy 272.081059 -237.108554) (xy 272.073302 -237.162508) (xy 272.057944 -237.214809) (xy 272.0353 -237.264391)
			(xy 272.00583 -237.310247) (xy 271.970134 -237.351441) (xy 271.928939 -237.387136) (xy 271.883083 -237.416605)
			(xy 271.833499 -237.439248) (xy 271.781198 -237.454604) (xy 271.727244 -237.46236) (xy 271.69999 -237.462822)
			(xy 271.671877 -237.462369) (xy 271.616258 -237.454129) (xy 271.562451 -237.437813) (xy 271.511622 -237.413777)
			(xy 271.464872 -237.382539) (xy 271.423214 -237.344777) (xy 271.38755 -237.30131) (xy 271.358653 -237.253078)
			(xy 271.337149 -237.201127) (xy 271.323504 -237.146582) (xy 271.32026 -237.118652) (xy 271.318425 -237.104408)
			(xy 271.307796 -237.077738) (xy 271.290162 -237.055081) (xy 271.266919 -237.038229) (xy 271.239903 -237.028513)
			(xy 271.21125 -237.026702) (xy 271.183226 -237.032939) (xy 271.1704 -237.039404) (xy 271.142115 -237.054181)
			(xy 271.081839 -237.075126) (xy 271.018918 -237.085748) (xy 270.987012 -237.086394) (xy 270.959758 -237.08596)
			(xy 270.905803 -237.078204) (xy 270.853502 -237.062848) (xy 270.803919 -237.040206) (xy 270.758062 -237.010737)
			(xy 270.716866 -236.975042) (xy 270.68117 -236.933847) (xy 270.6517 -236.887992) (xy 270.629056 -236.838409)
			(xy 270.613698 -236.786108) (xy 270.605941 -236.732154) (xy 269.784796 -236.732154) (xy 269.774103 -236.767695)
			(xy 269.750431 -236.818192) (xy 269.719658 -236.864705) (xy 269.682441 -236.906242) (xy 269.639573 -236.941917)
			(xy 269.591967 -236.970971) (xy 269.540638 -236.992783) (xy 269.486681 -237.006889) (xy 269.431244 -237.012989)
			(xy 269.37551 -237.010952) (xy 269.320667 -237.000822) (xy 269.267883 -236.982815) (xy 269.218283 -236.957314)
			(xy 269.172925 -236.924863) (xy 269.132776 -236.886154) (xy 269.09869 -236.842011) (xy 269.071394 -236.793376)
			(xy 269.051471 -236.741285) (xy 269.039345 -236.686848) (xy 269.035274 -236.631226) (xy 262.523712 -236.631226)
			(xy 262.569897 -236.652319) (xy 262.615747 -236.681785) (xy 262.656938 -236.717476) (xy 262.692629 -236.758667)
			(xy 262.722095 -236.804517) (xy 262.744737 -236.854094) (xy 262.760092 -236.906389) (xy 262.767848 -236.960337)
			(xy 262.768334 -236.987588) (xy 262.767848 -237.013901) (xy 262.760615 -237.066028) (xy 262.746299 -237.11667)
			(xy 262.72517 -237.164869) (xy 262.697628 -237.209713) (xy 262.664193 -237.250354) (xy 262.645144 -237.268512)
			(xy 262.637742 -237.276033) (xy 262.629216 -237.295313) (xy 262.628634 -237.30585) (xy 262.628634 -237.380526)
			(xy 262.629179 -237.391074) (xy 262.637702 -237.41037) (xy 262.645144 -237.417864) (xy 262.664232 -237.435987)
			(xy 262.697684 -237.476625) (xy 262.725238 -237.521472) (xy 262.746371 -237.569679) (xy 262.760681 -237.620332)
			(xy 262.767899 -237.67247) (xy 262.768334 -237.698788) (xy 262.767848 -237.726039) (xy 262.760092 -237.779987)
			(xy 262.744737 -237.832282) (xy 262.722095 -237.881859) (xy 262.692629 -237.927709) (xy 262.656938 -237.9689)
			(xy 262.630682 -237.99165) (xy 277.181308 -237.99165) (xy 277.185379 -237.936028) (xy 277.197505 -237.881591)
			(xy 277.217428 -237.8295) (xy 277.244724 -237.780865) (xy 277.27881 -237.736722) (xy 277.318959 -237.698013)
			(xy 277.364317 -237.665562) (xy 277.413917 -237.640061) (xy 277.466701 -237.622054) (xy 277.521544 -237.611924)
			(xy 277.577278 -237.609887) (xy 277.632715 -237.615987) (xy 277.686672 -237.630093) (xy 277.738001 -237.651905)
			(xy 277.785607 -237.680959) (xy 277.828475 -237.716634) (xy 277.865692 -237.758171) (xy 277.896465 -237.804684)
			(xy 277.920137 -237.855181) (xy 277.936205 -237.908588) (xy 277.944325 -237.963764) (xy 277.944834 -237.99165)
			(xy 277.944325 -238.019536) (xy 277.936205 -238.074712) (xy 277.920137 -238.128119) (xy 277.896465 -238.178616)
			(xy 277.865692 -238.225129) (xy 277.828475 -238.266666) (xy 277.785607 -238.302341) (xy 277.738001 -238.331395)
			(xy 277.686672 -238.353207) (xy 277.632715 -238.367313) (xy 277.577278 -238.373413) (xy 277.521544 -238.371376)
			(xy 277.466701 -238.361246) (xy 277.413917 -238.343239) (xy 277.364317 -238.317738) (xy 277.318959 -238.285287)
			(xy 277.27881 -238.246578) (xy 277.244724 -238.202435) (xy 277.217428 -238.1538) (xy 277.197505 -238.101709)
			(xy 277.185379 -238.047272) (xy 277.181308 -237.99165) (xy 262.630682 -237.99165) (xy 262.615747 -238.004591)
			(xy 262.569897 -238.034057) (xy 262.52032 -238.056699) (xy 262.468025 -238.072054) (xy 262.414077 -238.07981)
			(xy 262.359575 -238.07981) (xy 262.305627 -238.072054) (xy 262.253332 -238.056699) (xy 262.203755 -238.034057)
			(xy 262.157905 -238.004591) (xy 262.116714 -237.9689) (xy 262.081023 -237.927709) (xy 262.051557 -237.881859)
			(xy 262.028915 -237.832282) (xy 262.01356 -237.779987) (xy 262.005804 -237.726039) (xy 262.005318 -237.698788)
			(xy 247.539764 -237.698788) (xy 247.539764 -238.30915) (xy 247.540018 -238.314484) (xy 247.54105 -238.333788)
			(xy 257.356608 -238.333788) (xy 257.360679 -238.278166) (xy 257.372805 -238.223729) (xy 257.392728 -238.171638)
			(xy 257.420024 -238.123003) (xy 257.45411 -238.07886) (xy 257.494259 -238.040151) (xy 257.539617 -238.0077)
			(xy 257.589217 -237.982199) (xy 257.642001 -237.964192) (xy 257.696844 -237.954062) (xy 257.752578 -237.952025)
			(xy 257.808015 -237.958125) (xy 257.861972 -237.972231) (xy 257.913301 -237.994043) (xy 257.960907 -238.023097)
			(xy 258.003775 -238.058772) (xy 258.040992 -238.100309) (xy 258.071765 -238.146822) (xy 258.095437 -238.197319)
			(xy 258.111505 -238.250726) (xy 258.119625 -238.305902) (xy 258.120134 -238.333788) (xy 260.557008 -238.333788)
			(xy 260.561079 -238.278166) (xy 260.573205 -238.223729) (xy 260.593128 -238.171638) (xy 260.620424 -238.123003)
			(xy 260.65451 -238.07886) (xy 260.694659 -238.040151) (xy 260.740017 -238.0077) (xy 260.789617 -237.982199)
			(xy 260.842401 -237.964192) (xy 260.897244 -237.954062) (xy 260.952978 -237.952025) (xy 261.008415 -237.958125)
			(xy 261.062372 -237.972231) (xy 261.113701 -237.994043) (xy 261.161307 -238.023097) (xy 261.204175 -238.058772)
			(xy 261.241392 -238.100309) (xy 261.272165 -238.146822) (xy 261.295837 -238.197319) (xy 261.311905 -238.250726)
			(xy 261.320025 -238.305902) (xy 261.320534 -238.333788) (xy 261.32007 -238.359188) (xy 261.446008 -238.359188)
			(xy 261.450079 -238.303566) (xy 261.462205 -238.249129) (xy 261.482128 -238.197038) (xy 261.509424 -238.148403)
			(xy 261.54351 -238.10426) (xy 261.583659 -238.065551) (xy 261.629017 -238.0331) (xy 261.678617 -238.007599)
			(xy 261.731401 -237.989592) (xy 261.786244 -237.979462) (xy 261.841978 -237.977425) (xy 261.897415 -237.983525)
			(xy 261.951372 -237.997631) (xy 262.002701 -238.019443) (xy 262.050307 -238.048497) (xy 262.093175 -238.084172)
			(xy 262.130392 -238.125709) (xy 262.161165 -238.172222) (xy 262.184837 -238.222719) (xy 262.200905 -238.276126)
			(xy 262.209025 -238.331302) (xy 262.209534 -238.359188) (xy 262.209025 -238.387074) (xy 262.200905 -238.44225)
			(xy 262.184837 -238.495657) (xy 262.161165 -238.546154) (xy 262.130392 -238.592667) (xy 262.093175 -238.634204)
			(xy 262.050307 -238.669879) (xy 262.002701 -238.698933) (xy 261.951372 -238.720745) (xy 261.897415 -238.734851)
			(xy 261.841978 -238.740951) (xy 261.786244 -238.738914) (xy 261.731401 -238.728784) (xy 261.678617 -238.710777)
			(xy 261.629017 -238.685276) (xy 261.583659 -238.652825) (xy 261.54351 -238.614116) (xy 261.509424 -238.569973)
			(xy 261.482128 -238.521338) (xy 261.462205 -238.469247) (xy 261.450079 -238.41481) (xy 261.446008 -238.359188)
			(xy 261.32007 -238.359188) (xy 261.320025 -238.361674) (xy 261.311905 -238.41685) (xy 261.295837 -238.470257)
			(xy 261.272165 -238.520754) (xy 261.241392 -238.567267) (xy 261.204175 -238.608804) (xy 261.161307 -238.644479)
			(xy 261.113701 -238.673533) (xy 261.062372 -238.695345) (xy 261.008415 -238.709451) (xy 260.952978 -238.715551)
			(xy 260.897244 -238.713514) (xy 260.842401 -238.703384) (xy 260.789617 -238.685377) (xy 260.740017 -238.659876)
			(xy 260.694659 -238.627425) (xy 260.65451 -238.588716) (xy 260.620424 -238.544573) (xy 260.593128 -238.495938)
			(xy 260.573205 -238.443847) (xy 260.561079 -238.38941) (xy 260.557008 -238.333788) (xy 258.120134 -238.333788)
			(xy 258.119625 -238.361674) (xy 258.111505 -238.41685) (xy 258.095437 -238.470257) (xy 258.071765 -238.520754)
			(xy 258.040992 -238.567267) (xy 258.003775 -238.608804) (xy 257.960907 -238.644479) (xy 257.913301 -238.673533)
			(xy 257.861972 -238.695345) (xy 257.808015 -238.709451) (xy 257.752578 -238.715551) (xy 257.696844 -238.713514)
			(xy 257.642001 -238.703384) (xy 257.589217 -238.685377) (xy 257.539617 -238.659876) (xy 257.494259 -238.627425)
			(xy 257.45411 -238.588716) (xy 257.420024 -238.544573) (xy 257.392728 -238.495938) (xy 257.372805 -238.443847)
			(xy 257.360679 -238.38941) (xy 257.356608 -238.333788) (xy 247.54105 -238.333788) (xy 247.541796 -238.347758)
			(xy 247.541796 -241.028055) (xy 254.817543 -241.028055) (xy 254.817543 -240.973545) (xy 254.825301 -240.91959)
			(xy 254.840659 -240.867288) (xy 254.863304 -240.817705) (xy 254.892775 -240.771849) (xy 254.928473 -240.730654)
			(xy 254.96967 -240.69496) (xy 255.015528 -240.665491) (xy 255.065113 -240.64285) (xy 255.117416 -240.627495)
			(xy 255.171371 -240.619741) (xy 255.198626 -240.61928) (xy 255.22587 -240.619763) (xy 255.279802 -240.627523)
			(xy 255.33208 -240.64288) (xy 255.38164 -240.665523) (xy 255.427473 -240.694989) (xy 255.468644 -240.73068)
			(xy 255.504315 -240.771867) (xy 255.519428 -240.79454) (xy 255.524273 -240.801567) (xy 255.537682 -240.812114)
			(xy 255.553822 -240.817637) (xy 255.562354 -240.817908) (xy 255.647698 -240.817908) (xy 255.656222 -240.817637)
			(xy 255.672335 -240.812066) (xy 255.685742 -240.801535) (xy 255.690624 -240.79454) (xy 255.705721 -240.771855)
			(xy 255.741391 -240.730661) (xy 255.782563 -240.694966) (xy 255.828397 -240.665496) (xy 255.877961 -240.642852)
			(xy 255.930244 -240.627497) (xy 255.98418 -240.619742) (xy 256.011426 -240.61928) (xy 256.037403 -240.61969)
			(xy 256.088876 -240.626737) (xy 256.138914 -240.64071) (xy 256.186591 -240.661351) (xy 256.231022 -240.688277)
			(xy 256.271384 -240.720988) (xy 256.306929 -240.758879) (xy 256.322322 -240.779808) (xy 256.329931 -240.789322)
			(xy 256.35156 -240.800457) (xy 256.363724 -240.801144) (xy 256.446528 -240.801144) (xy 256.458689 -240.800444)
			(xy 256.480312 -240.789311) (xy 256.48793 -240.779808) (xy 256.503344 -240.758898) (xy 256.538896 -240.721023)
			(xy 256.57926 -240.688323) (xy 256.623687 -240.661404) (xy 256.671358 -240.640764) (xy 256.721388 -240.626784)
			(xy 256.772853 -240.619724) (xy 256.798826 -240.61928) (xy 256.826075 -240.619792) (xy 256.880018 -240.627551)
			(xy 256.932308 -240.642908) (xy 256.981881 -240.66555) (xy 257.027726 -240.695016) (xy 257.068912 -240.730706)
			(xy 257.1046 -240.771895) (xy 257.134062 -240.817742) (xy 257.156701 -240.867316) (xy 257.172054 -240.919607)
			(xy 257.17981 -240.973551) (xy 257.17981 -241.028049) (xy 257.172054 -241.081993) (xy 257.156701 -241.134284)
			(xy 257.134062 -241.183858) (xy 257.1046 -241.229705) (xy 257.068912 -241.270894) (xy 257.027726 -241.306584)
			(xy 256.981881 -241.33605) (xy 256.932308 -241.358692) (xy 256.880018 -241.374049) (xy 256.826075 -241.381808)
			(xy 256.798826 -241.382296) (xy 256.772852 -241.381815) (xy 256.721383 -241.374777) (xy 256.671348 -241.360813)
			(xy 256.623672 -241.340183) (xy 256.57924 -241.313269) (xy 256.538876 -241.28057) (xy 256.503326 -241.242691)
			(xy 256.48793 -241.221768) (xy 256.480301 -241.212274) (xy 256.458687 -241.20113) (xy 256.446528 -241.200432)
			(xy 256.363724 -241.200432) (xy 256.351561 -241.201112) (xy 256.329939 -241.21226) (xy 256.322322 -241.221768)
			(xy 256.30693 -241.242695) (xy 256.271375 -241.280571) (xy 256.231008 -241.31327) (xy 256.186577 -241.340188)
			(xy 256.138903 -241.360825) (xy 256.088869 -241.3748) (xy 256.037401 -241.381855) (xy 256.011426 -241.382296)
			(xy 255.984181 -241.381861) (xy 255.930246 -241.374094) (xy 255.877966 -241.358729) (xy 255.828405 -241.336079)
			(xy 255.782574 -241.306605) (xy 255.741404 -241.270907) (xy 255.705735 -241.229712) (xy 255.690624 -241.207036)
			(xy 255.685755 -241.200028) (xy 255.672356 -241.18948) (xy 255.656226 -241.183946) (xy 255.647698 -241.183668)
			(xy 255.562354 -241.183668) (xy 255.553834 -241.183986) (xy 255.537724 -241.189537) (xy 255.524314 -241.200049)
			(xy 255.519428 -241.207036) (xy 255.504289 -241.229691) (xy 255.468627 -241.270887) (xy 255.427463 -241.306585)
			(xy 255.381635 -241.336059) (xy 255.332078 -241.358707) (xy 255.279801 -241.374069) (xy 255.22587 -241.381831)
			(xy 255.198626 -241.382296) (xy 255.171371 -241.381859) (xy 255.117416 -241.374105) (xy 255.065113 -241.35875)
			(xy 255.015528 -241.336109) (xy 254.96967 -241.30664) (xy 254.928473 -241.270946) (xy 254.892775 -241.229751)
			(xy 254.863304 -241.183895) (xy 254.840659 -241.134312) (xy 254.825301 -241.08201) (xy 254.817543 -241.028055)
			(xy 247.541796 -241.028055) (xy 247.541796 -242.664488) (xy 254.886458 -242.664488) (xy 254.890529 -242.608866)
			(xy 254.902655 -242.554429) (xy 254.922578 -242.502338) (xy 254.949874 -242.453703) (xy 254.98396 -242.40956)
			(xy 255.024109 -242.370851) (xy 255.069467 -242.3384) (xy 255.119067 -242.312899) (xy 255.171851 -242.294892)
			(xy 255.226694 -242.284762) (xy 255.282428 -242.282725) (xy 255.337865 -242.288825) (xy 255.391822 -242.302931)
			(xy 255.443151 -242.324743) (xy 255.490757 -242.353797) (xy 255.513096 -242.372388) (xy 256.721608 -242.372388)
			(xy 256.725679 -242.316766) (xy 256.737805 -242.262329) (xy 256.757728 -242.210238) (xy 256.785024 -242.161603)
			(xy 256.81911 -242.11746) (xy 256.859259 -242.078751) (xy 256.904617 -242.0463) (xy 256.954217 -242.020799)
			(xy 257.007001 -242.002792) (xy 257.061844 -241.992662) (xy 257.117578 -241.990625) (xy 257.173015 -241.996725)
			(xy 257.226972 -242.010831) (xy 257.278301 -242.032643) (xy 257.325907 -242.061697) (xy 257.368775 -242.097372)
			(xy 257.405992 -242.138909) (xy 257.436765 -242.185422) (xy 257.460437 -242.235919) (xy 257.476505 -242.289326)
			(xy 257.480206 -242.314476) (xy 262.093962 -242.314476) (xy 262.098033 -242.258854) (xy 262.110159 -242.204417)
			(xy 262.130082 -242.152326) (xy 262.157378 -242.103691) (xy 262.191464 -242.059548) (xy 262.231613 -242.020839)
			(xy 262.276971 -241.988388) (xy 262.326571 -241.962887) (xy 262.379355 -241.94488) (xy 262.434198 -241.93475)
			(xy 262.489932 -241.932713) (xy 262.545369 -241.938813) (xy 262.599326 -241.952919) (xy 262.650655 -241.974731)
			(xy 262.698261 -242.003785) (xy 262.741129 -242.03946) (xy 262.778346 -242.080997) (xy 262.809119 -242.12751)
			(xy 262.832791 -242.178007) (xy 262.848859 -242.231414) (xy 262.856979 -242.28659) (xy 262.857488 -242.314476)
			(xy 262.856979 -242.342362) (xy 262.848859 -242.397538) (xy 262.832791 -242.450945) (xy 262.809119 -242.501442)
			(xy 262.778346 -242.547955) (xy 262.741129 -242.589492) (xy 262.698261 -242.625167) (xy 262.650655 -242.654221)
			(xy 262.599326 -242.676033) (xy 262.545369 -242.690139) (xy 262.489932 -242.696239) (xy 262.434198 -242.694202)
			(xy 262.379355 -242.684072) (xy 262.326571 -242.666065) (xy 262.276971 -242.640564) (xy 262.231613 -242.608113)
			(xy 262.191464 -242.569404) (xy 262.157378 -242.525261) (xy 262.130082 -242.476626) (xy 262.110159 -242.424535)
			(xy 262.098033 -242.370098) (xy 262.093962 -242.314476) (xy 257.480206 -242.314476) (xy 257.484625 -242.344502)
			(xy 257.485134 -242.372388) (xy 257.484625 -242.400274) (xy 257.476505 -242.45545) (xy 257.460437 -242.508857)
			(xy 257.436765 -242.559354) (xy 257.405992 -242.605867) (xy 257.368775 -242.647404) (xy 257.325907 -242.683079)
			(xy 257.278301 -242.712133) (xy 257.226972 -242.733945) (xy 257.173015 -242.748051) (xy 257.117578 -242.754151)
			(xy 257.061844 -242.752114) (xy 257.007001 -242.741984) (xy 256.954217 -242.723977) (xy 256.904617 -242.698476)
			(xy 256.859259 -242.666025) (xy 256.81911 -242.627316) (xy 256.785024 -242.583173) (xy 256.757728 -242.534538)
			(xy 256.737805 -242.482447) (xy 256.725679 -242.42801) (xy 256.721608 -242.372388) (xy 255.513096 -242.372388)
			(xy 255.533625 -242.389472) (xy 255.570842 -242.431009) (xy 255.601615 -242.477522) (xy 255.625287 -242.528019)
			(xy 255.641355 -242.581426) (xy 255.649475 -242.636602) (xy 255.649984 -242.664488) (xy 255.649475 -242.692374)
			(xy 255.641355 -242.74755) (xy 255.625287 -242.800957) (xy 255.601615 -242.851454) (xy 255.570842 -242.897967)
			(xy 255.533625 -242.939504) (xy 255.490757 -242.975179) (xy 255.443151 -243.004233) (xy 255.391822 -243.026045)
			(xy 255.337865 -243.040151) (xy 255.282428 -243.046251) (xy 255.226694 -243.044214) (xy 255.171851 -243.034084)
			(xy 255.119067 -243.016077) (xy 255.069467 -242.990576) (xy 255.024109 -242.958125) (xy 254.98396 -242.919416)
			(xy 254.949874 -242.875273) (xy 254.922578 -242.826638) (xy 254.902655 -242.774547) (xy 254.890529 -242.72011)
			(xy 254.886458 -242.664488) (xy 247.541796 -242.664488) (xy 247.541796 -243.540788) (xy 260.658608 -243.540788)
			(xy 260.662679 -243.485166) (xy 260.674805 -243.430729) (xy 260.694728 -243.378638) (xy 260.722024 -243.330003)
			(xy 260.75611 -243.28586) (xy 260.796259 -243.247151) (xy 260.841617 -243.2147) (xy 260.891217 -243.189199)
			(xy 260.944001 -243.171192) (xy 260.998844 -243.161062) (xy 261.054578 -243.159025) (xy 261.110015 -243.165125)
			(xy 261.163972 -243.179231) (xy 261.215301 -243.201043) (xy 261.262907 -243.230097) (xy 261.305775 -243.265772)
			(xy 261.342992 -243.307309) (xy 261.373765 -243.353822) (xy 261.397437 -243.404319) (xy 261.413505 -243.457726)
			(xy 261.421625 -243.512902) (xy 261.422134 -243.540788) (xy 261.421625 -243.568674) (xy 261.413505 -243.62385)
			(xy 261.397437 -243.677257) (xy 261.373765 -243.727754) (xy 261.342992 -243.774267) (xy 261.305775 -243.815804)
			(xy 261.262907 -243.851479) (xy 261.215301 -243.880533) (xy 261.163972 -243.902345) (xy 261.110015 -243.916451)
			(xy 261.054578 -243.922551) (xy 260.998844 -243.920514) (xy 260.944001 -243.910384) (xy 260.891217 -243.892377)
			(xy 260.841617 -243.866876) (xy 260.796259 -243.834425) (xy 260.75611 -243.795716) (xy 260.722024 -243.751573)
			(xy 260.694728 -243.702938) (xy 260.674805 -243.650847) (xy 260.662679 -243.59641) (xy 260.658608 -243.540788)
			(xy 247.541796 -243.540788) (xy 247.541796 -246.01551) (xy 249.35764 -246.01551) (xy 249.361711 -245.959888)
			(xy 249.373837 -245.905451) (xy 249.39376 -245.85336) (xy 249.421056 -245.804725) (xy 249.455142 -245.760582)
			(xy 249.495291 -245.721873) (xy 249.540649 -245.689422) (xy 249.590249 -245.663921) (xy 249.643033 -245.645914)
			(xy 249.697876 -245.635784) (xy 249.75361 -245.633747) (xy 249.809047 -245.639847) (xy 249.863004 -245.653953)
			(xy 249.914333 -245.675765) (xy 249.961939 -245.704819) (xy 250.004807 -245.740494) (xy 250.042024 -245.782031)
			(xy 250.072797 -245.828544) (xy 250.096469 -245.879041) (xy 250.112537 -245.932448) (xy 250.120657 -245.987624)
			(xy 250.121166 -246.01551) (xy 250.120657 -246.043396) (xy 250.112537 -246.098572) (xy 250.096469 -246.151979)
			(xy 250.072797 -246.202476) (xy 250.042024 -246.248989) (xy 250.004807 -246.290526) (xy 249.961939 -246.326201)
			(xy 249.914333 -246.355255) (xy 249.863004 -246.377067) (xy 249.809047 -246.391173) (xy 249.75361 -246.397273)
			(xy 249.697876 -246.395236) (xy 249.643033 -246.385106) (xy 249.590249 -246.367099) (xy 249.540649 -246.341598)
			(xy 249.495291 -246.309147) (xy 249.455142 -246.270438) (xy 249.421056 -246.226295) (xy 249.39376 -246.17766)
			(xy 249.373837 -246.125569) (xy 249.361711 -246.071132) (xy 249.35764 -246.01551) (xy 247.541796 -246.01551)
			(xy 247.541796 -249.005598) (xy 255.19837 -249.005598) (xy 255.202441 -248.949976) (xy 255.214567 -248.895539)
			(xy 255.23449 -248.843448) (xy 255.261786 -248.794813) (xy 255.295872 -248.75067) (xy 255.336021 -248.711961)
			(xy 255.381379 -248.67951) (xy 255.430979 -248.654009) (xy 255.483763 -248.636002) (xy 255.538606 -248.625872)
			(xy 255.59434 -248.623835) (xy 255.649777 -248.629935) (xy 255.703734 -248.644041) (xy 255.755063 -248.665853)
			(xy 255.802669 -248.694907) (xy 255.845537 -248.730582) (xy 255.882754 -248.772119) (xy 255.913527 -248.818632)
			(xy 255.937199 -248.869129) (xy 255.953267 -248.922536) (xy 255.961387 -248.977712) (xy 255.961896 -249.005598)
			(xy 255.961808 -249.010424) (xy 257.176268 -249.010424) (xy 257.180339 -248.954802) (xy 257.192465 -248.900365)
			(xy 257.212388 -248.848274) (xy 257.239684 -248.799639) (xy 257.27377 -248.755496) (xy 257.313919 -248.716787)
			(xy 257.359277 -248.684336) (xy 257.408877 -248.658835) (xy 257.461661 -248.640828) (xy 257.516504 -248.630698)
			(xy 257.572238 -248.628661) (xy 257.627675 -248.634761) (xy 257.681632 -248.648867) (xy 257.732961 -248.670679)
			(xy 257.780567 -248.699733) (xy 257.823435 -248.735408) (xy 257.860652 -248.776945) (xy 257.891425 -248.823458)
			(xy 257.915097 -248.873955) (xy 257.931165 -248.927362) (xy 257.939285 -248.982538) (xy 257.939794 -249.010424)
			(xy 258.192268 -249.010424) (xy 258.196339 -248.954802) (xy 258.208465 -248.900365) (xy 258.228388 -248.848274)
			(xy 258.255684 -248.799639) (xy 258.28977 -248.755496) (xy 258.329919 -248.716787) (xy 258.375277 -248.684336)
			(xy 258.424877 -248.658835) (xy 258.477661 -248.640828) (xy 258.532504 -248.630698) (xy 258.588238 -248.628661)
			(xy 258.643675 -248.634761) (xy 258.697632 -248.648867) (xy 258.748961 -248.670679) (xy 258.796567 -248.699733)
			(xy 258.839435 -248.735408) (xy 258.876652 -248.776945) (xy 258.907425 -248.823458) (xy 258.931097 -248.873955)
			(xy 258.947165 -248.927362) (xy 258.955285 -248.982538) (xy 258.955794 -249.010424) (xy 258.95533 -249.035824)
			(xy 259.186678 -249.035824) (xy 259.190749 -248.980202) (xy 259.202875 -248.925765) (xy 259.222798 -248.873674)
			(xy 259.250094 -248.825039) (xy 259.28418 -248.780896) (xy 259.324329 -248.742187) (xy 259.369687 -248.709736)
			(xy 259.419287 -248.684235) (xy 259.472071 -248.666228) (xy 259.526914 -248.656098) (xy 259.582648 -248.654061)
			(xy 259.638085 -248.660161) (xy 259.692042 -248.674267) (xy 259.743371 -248.696079) (xy 259.790977 -248.725133)
			(xy 259.833845 -248.760808) (xy 259.871062 -248.802345) (xy 259.901835 -248.848858) (xy 259.925507 -248.899355)
			(xy 259.941575 -248.952762) (xy 259.949089 -249.00382) (xy 270.384268 -249.00382) (xy 270.388339 -248.948198)
			(xy 270.400465 -248.893761) (xy 270.420388 -248.84167) (xy 270.447684 -248.793035) (xy 270.48177 -248.748892)
			(xy 270.521919 -248.710183) (xy 270.567277 -248.677732) (xy 270.616877 -248.652231) (xy 270.669661 -248.634224)
			(xy 270.724504 -248.624094) (xy 270.780238 -248.622057) (xy 270.835675 -248.628157) (xy 270.889632 -248.642263)
			(xy 270.940961 -248.664075) (xy 270.988567 -248.693129) (xy 271.031435 -248.728804) (xy 271.068652 -248.770341)
			(xy 271.099425 -248.816854) (xy 271.123097 -248.867351) (xy 271.139165 -248.920758) (xy 271.14395 -248.953274)
			(xy 271.29816 -248.953274) (xy 271.302231 -248.897652) (xy 271.314357 -248.843215) (xy 271.33428 -248.791124)
			(xy 271.361576 -248.742489) (xy 271.395662 -248.698346) (xy 271.435811 -248.659637) (xy 271.481169 -248.627186)
			(xy 271.530769 -248.601685) (xy 271.583553 -248.583678) (xy 271.638396 -248.573548) (xy 271.69413 -248.571511)
			(xy 271.749567 -248.577611) (xy 271.803524 -248.591717) (xy 271.854853 -248.613529) (xy 271.902459 -248.642583)
			(xy 271.945327 -248.678258) (xy 271.982544 -248.719795) (xy 272.013317 -248.766308) (xy 272.036989 -248.816805)
			(xy 272.053057 -248.870212) (xy 272.061177 -248.925388) (xy 272.061686 -248.953274) (xy 272.061177 -248.98116)
			(xy 272.053057 -249.036336) (xy 272.036989 -249.089743) (xy 272.013317 -249.14024) (xy 271.982544 -249.186753)
			(xy 271.945327 -249.22829) (xy 271.902459 -249.263965) (xy 271.854853 -249.293019) (xy 271.803524 -249.314831)
			(xy 271.749567 -249.328937) (xy 271.69413 -249.335037) (xy 271.638396 -249.333) (xy 271.583553 -249.32287)
			(xy 271.530769 -249.304863) (xy 271.481169 -249.279362) (xy 271.435811 -249.246911) (xy 271.395662 -249.208202)
			(xy 271.361576 -249.164059) (xy 271.33428 -249.115424) (xy 271.314357 -249.063333) (xy 271.302231 -249.008896)
			(xy 271.29816 -248.953274) (xy 271.14395 -248.953274) (xy 271.147285 -248.975934) (xy 271.147794 -249.00382)
			(xy 271.147285 -249.031706) (xy 271.139165 -249.086882) (xy 271.123097 -249.140289) (xy 271.099425 -249.190786)
			(xy 271.068652 -249.237299) (xy 271.031435 -249.278836) (xy 270.988567 -249.314511) (xy 270.940961 -249.343565)
			(xy 270.889632 -249.365377) (xy 270.835675 -249.379483) (xy 270.780238 -249.385583) (xy 270.724504 -249.383546)
			(xy 270.669661 -249.373416) (xy 270.616877 -249.355409) (xy 270.567277 -249.329908) (xy 270.521919 -249.297457)
			(xy 270.48177 -249.258748) (xy 270.447684 -249.214605) (xy 270.420388 -249.16597) (xy 270.400465 -249.113879)
			(xy 270.388339 -249.059442) (xy 270.384268 -249.00382) (xy 259.949089 -249.00382) (xy 259.949695 -249.007938)
			(xy 259.950204 -249.035824) (xy 259.949695 -249.06371) (xy 259.941575 -249.118886) (xy 259.925507 -249.172293)
			(xy 259.901835 -249.22279) (xy 259.871062 -249.269303) (xy 259.833845 -249.31084) (xy 259.790977 -249.346515)
			(xy 259.743371 -249.375569) (xy 259.692042 -249.397381) (xy 259.638085 -249.411487) (xy 259.582648 -249.417587)
			(xy 259.526914 -249.41555) (xy 259.472071 -249.40542) (xy 259.419287 -249.387413) (xy 259.369687 -249.361912)
			(xy 259.324329 -249.329461) (xy 259.28418 -249.290752) (xy 259.250094 -249.246609) (xy 259.222798 -249.197974)
			(xy 259.202875 -249.145883) (xy 259.190749 -249.091446) (xy 259.186678 -249.035824) (xy 258.95533 -249.035824)
			(xy 258.955285 -249.03831) (xy 258.947165 -249.093486) (xy 258.931097 -249.146893) (xy 258.907425 -249.19739)
			(xy 258.876652 -249.243903) (xy 258.839435 -249.28544) (xy 258.796567 -249.321115) (xy 258.748961 -249.350169)
			(xy 258.697632 -249.371981) (xy 258.643675 -249.386087) (xy 258.588238 -249.392187) (xy 258.532504 -249.39015)
			(xy 258.477661 -249.38002) (xy 258.424877 -249.362013) (xy 258.375277 -249.336512) (xy 258.329919 -249.304061)
			(xy 258.28977 -249.265352) (xy 258.255684 -249.221209) (xy 258.228388 -249.172574) (xy 258.208465 -249.120483)
			(xy 258.196339 -249.066046) (xy 258.192268 -249.010424) (xy 257.939794 -249.010424) (xy 257.939285 -249.03831)
			(xy 257.931165 -249.093486) (xy 257.915097 -249.146893) (xy 257.891425 -249.19739) (xy 257.860652 -249.243903)
			(xy 257.823435 -249.28544) (xy 257.780567 -249.321115) (xy 257.732961 -249.350169) (xy 257.681632 -249.371981)
			(xy 257.627675 -249.386087) (xy 257.572238 -249.392187) (xy 257.516504 -249.39015) (xy 257.461661 -249.38002)
			(xy 257.408877 -249.362013) (xy 257.359277 -249.336512) (xy 257.313919 -249.304061) (xy 257.27377 -249.265352)
			(xy 257.239684 -249.221209) (xy 257.212388 -249.172574) (xy 257.192465 -249.120483) (xy 257.180339 -249.066046)
			(xy 257.176268 -249.010424) (xy 255.961808 -249.010424) (xy 255.961387 -249.033484) (xy 255.953267 -249.08866)
			(xy 255.937199 -249.142067) (xy 255.913527 -249.192564) (xy 255.882754 -249.239077) (xy 255.845537 -249.280614)
			(xy 255.802669 -249.316289) (xy 255.755063 -249.345343) (xy 255.703734 -249.367155) (xy 255.649777 -249.381261)
			(xy 255.59434 -249.387361) (xy 255.538606 -249.385324) (xy 255.483763 -249.375194) (xy 255.430979 -249.357187)
			(xy 255.381379 -249.331686) (xy 255.336021 -249.299235) (xy 255.295872 -249.260526) (xy 255.261786 -249.216383)
			(xy 255.23449 -249.167748) (xy 255.214567 -249.115657) (xy 255.202441 -249.06122) (xy 255.19837 -249.005598)
			(xy 247.541796 -249.005598) (xy 247.541796 -251.173996) (xy 256.047238 -251.173996) (xy 256.051309 -251.118374)
			(xy 256.063435 -251.063937) (xy 256.083358 -251.011846) (xy 256.110654 -250.963211) (xy 256.14474 -250.919068)
			(xy 256.184889 -250.880359) (xy 256.230247 -250.847908) (xy 256.279847 -250.822407) (xy 256.332631 -250.8044)
			(xy 256.387474 -250.79427) (xy 256.443208 -250.792233) (xy 256.498645 -250.798333) (xy 256.552602 -250.812439)
			(xy 256.603931 -250.834251) (xy 256.651537 -250.863305) (xy 256.694405 -250.89898) (xy 256.731622 -250.940517)
			(xy 256.762395 -250.98703) (xy 256.786067 -251.037527) (xy 256.802135 -251.090934) (xy 256.810255 -251.14611)
			(xy 256.810481 -251.158502) (xy 257.176268 -251.158502) (xy 257.180339 -251.10288) (xy 257.192465 -251.048443)
			(xy 257.212388 -250.996352) (xy 257.239684 -250.947717) (xy 257.27377 -250.903574) (xy 257.313919 -250.864865)
			(xy 257.359277 -250.832414) (xy 257.408877 -250.806913) (xy 257.461661 -250.788906) (xy 257.516504 -250.778776)
			(xy 257.572238 -250.776739) (xy 257.627675 -250.782839) (xy 257.681632 -250.796945) (xy 257.732961 -250.818757)
			(xy 257.780567 -250.847811) (xy 257.823435 -250.883486) (xy 257.860652 -250.925023) (xy 257.891425 -250.971536)
			(xy 257.915097 -251.022033) (xy 257.931165 -251.07544) (xy 257.939285 -251.130616) (xy 257.939794 -251.158502)
			(xy 258.192268 -251.158502) (xy 258.196339 -251.10288) (xy 258.208465 -251.048443) (xy 258.228388 -250.996352)
			(xy 258.255684 -250.947717) (xy 258.28977 -250.903574) (xy 258.329919 -250.864865) (xy 258.375277 -250.832414)
			(xy 258.424877 -250.806913) (xy 258.477661 -250.788906) (xy 258.532504 -250.778776) (xy 258.588238 -250.776739)
			(xy 258.643675 -250.782839) (xy 258.697632 -250.796945) (xy 258.748961 -250.818757) (xy 258.796567 -250.847811)
			(xy 258.839435 -250.883486) (xy 258.876652 -250.925023) (xy 258.907425 -250.971536) (xy 258.931097 -251.022033)
			(xy 258.947165 -251.07544) (xy 258.955285 -251.130616) (xy 258.955794 -251.158502) (xy 259.208268 -251.158502)
			(xy 259.212339 -251.10288) (xy 259.224465 -251.048443) (xy 259.244388 -250.996352) (xy 259.271684 -250.947717)
			(xy 259.30577 -250.903574) (xy 259.345919 -250.864865) (xy 259.391277 -250.832414) (xy 259.440877 -250.806913)
			(xy 259.493661 -250.788906) (xy 259.548504 -250.778776) (xy 259.604238 -250.776739) (xy 259.659675 -250.782839)
			(xy 259.713632 -250.796945) (xy 259.764961 -250.818757) (xy 259.812567 -250.847811) (xy 259.855435 -250.883486)
			(xy 259.892652 -250.925023) (xy 259.923425 -250.971536) (xy 259.947097 -251.022033) (xy 259.963165 -251.07544)
			(xy 259.971285 -251.130616) (xy 259.971794 -251.158502) (xy 260.224268 -251.158502) (xy 260.228339 -251.10288)
			(xy 260.240465 -251.048443) (xy 260.260388 -250.996352) (xy 260.287684 -250.947717) (xy 260.32177 -250.903574)
			(xy 260.361919 -250.864865) (xy 260.407277 -250.832414) (xy 260.456877 -250.806913) (xy 260.509661 -250.788906)
			(xy 260.564504 -250.778776) (xy 260.620238 -250.776739) (xy 260.675675 -250.782839) (xy 260.729632 -250.796945)
			(xy 260.780961 -250.818757) (xy 260.828567 -250.847811) (xy 260.871435 -250.883486) (xy 260.908652 -250.925023)
			(xy 260.939425 -250.971536) (xy 260.963097 -251.022033) (xy 260.979165 -251.07544) (xy 260.987285 -251.130616)
			(xy 260.987794 -251.158502) (xy 261.240268 -251.158502) (xy 261.244339 -251.10288) (xy 261.256465 -251.048443)
			(xy 261.276388 -250.996352) (xy 261.303684 -250.947717) (xy 261.33777 -250.903574) (xy 261.377919 -250.864865)
			(xy 261.423277 -250.832414) (xy 261.472877 -250.806913) (xy 261.525661 -250.788906) (xy 261.580504 -250.778776)
			(xy 261.636238 -250.776739) (xy 261.691675 -250.782839) (xy 261.745632 -250.796945) (xy 261.796961 -250.818757)
			(xy 261.844567 -250.847811) (xy 261.887435 -250.883486) (xy 261.924652 -250.925023) (xy 261.955425 -250.971536)
			(xy 261.979097 -251.022033) (xy 261.995165 -251.07544) (xy 262.003285 -251.130616) (xy 262.003794 -251.158502)
			(xy 262.256268 -251.158502) (xy 262.260339 -251.10288) (xy 262.272465 -251.048443) (xy 262.292388 -250.996352)
			(xy 262.319684 -250.947717) (xy 262.35377 -250.903574) (xy 262.393919 -250.864865) (xy 262.439277 -250.832414)
			(xy 262.488877 -250.806913) (xy 262.541661 -250.788906) (xy 262.596504 -250.778776) (xy 262.652238 -250.776739)
			(xy 262.707675 -250.782839) (xy 262.761632 -250.796945) (xy 262.812961 -250.818757) (xy 262.860567 -250.847811)
			(xy 262.903435 -250.883486) (xy 262.940652 -250.925023) (xy 262.971425 -250.971536) (xy 262.995097 -251.022033)
			(xy 263.011165 -251.07544) (xy 263.019285 -251.130616) (xy 263.019794 -251.158502) (xy 263.272268 -251.158502)
			(xy 263.276339 -251.10288) (xy 263.288465 -251.048443) (xy 263.308388 -250.996352) (xy 263.335684 -250.947717)
			(xy 263.36977 -250.903574) (xy 263.409919 -250.864865) (xy 263.455277 -250.832414) (xy 263.504877 -250.806913)
			(xy 263.557661 -250.788906) (xy 263.612504 -250.778776) (xy 263.668238 -250.776739) (xy 263.723675 -250.782839)
			(xy 263.777632 -250.796945) (xy 263.828961 -250.818757) (xy 263.876567 -250.847811) (xy 263.919435 -250.883486)
			(xy 263.956652 -250.925023) (xy 263.987425 -250.971536) (xy 264.011097 -251.022033) (xy 264.027165 -251.07544)
			(xy 264.035285 -251.130616) (xy 264.035794 -251.158502) (xy 264.288268 -251.158502) (xy 264.292339 -251.10288)
			(xy 264.304465 -251.048443) (xy 264.324388 -250.996352) (xy 264.351684 -250.947717) (xy 264.38577 -250.903574)
			(xy 264.425919 -250.864865) (xy 264.471277 -250.832414) (xy 264.520877 -250.806913) (xy 264.573661 -250.788906)
			(xy 264.628504 -250.778776) (xy 264.684238 -250.776739) (xy 264.739675 -250.782839) (xy 264.793632 -250.796945)
			(xy 264.844961 -250.818757) (xy 264.892567 -250.847811) (xy 264.935435 -250.883486) (xy 264.972652 -250.925023)
			(xy 265.003425 -250.971536) (xy 265.027097 -251.022033) (xy 265.043165 -251.07544) (xy 265.051285 -251.130616)
			(xy 265.051794 -251.158502) (xy 265.304268 -251.158502) (xy 265.308339 -251.10288) (xy 265.320465 -251.048443)
			(xy 265.340388 -250.996352) (xy 265.367684 -250.947717) (xy 265.40177 -250.903574) (xy 265.441919 -250.864865)
			(xy 265.487277 -250.832414) (xy 265.536877 -250.806913) (xy 265.589661 -250.788906) (xy 265.644504 -250.778776)
			(xy 265.700238 -250.776739) (xy 265.755675 -250.782839) (xy 265.809632 -250.796945) (xy 265.860961 -250.818757)
			(xy 265.908567 -250.847811) (xy 265.951435 -250.883486) (xy 265.988652 -250.925023) (xy 266.019425 -250.971536)
			(xy 266.043097 -251.022033) (xy 266.059165 -251.07544) (xy 266.067285 -251.130616) (xy 266.067794 -251.158502)
			(xy 266.320268 -251.158502) (xy 266.324339 -251.10288) (xy 266.336465 -251.048443) (xy 266.356388 -250.996352)
			(xy 266.383684 -250.947717) (xy 266.41777 -250.903574) (xy 266.457919 -250.864865) (xy 266.503277 -250.832414)
			(xy 266.552877 -250.806913) (xy 266.605661 -250.788906) (xy 266.660504 -250.778776) (xy 266.716238 -250.776739)
			(xy 266.771675 -250.782839) (xy 266.825632 -250.796945) (xy 266.876961 -250.818757) (xy 266.924567 -250.847811)
			(xy 266.967435 -250.883486) (xy 267.004652 -250.925023) (xy 267.035425 -250.971536) (xy 267.059097 -251.022033)
			(xy 267.075165 -251.07544) (xy 267.083285 -251.130616) (xy 267.083794 -251.158502) (xy 267.336268 -251.158502)
			(xy 267.340339 -251.10288) (xy 267.352465 -251.048443) (xy 267.372388 -250.996352) (xy 267.399684 -250.947717)
			(xy 267.43377 -250.903574) (xy 267.473919 -250.864865) (xy 267.519277 -250.832414) (xy 267.568877 -250.806913)
			(xy 267.621661 -250.788906) (xy 267.676504 -250.778776) (xy 267.732238 -250.776739) (xy 267.787675 -250.782839)
			(xy 267.841632 -250.796945) (xy 267.892961 -250.818757) (xy 267.940567 -250.847811) (xy 267.983435 -250.883486)
			(xy 268.020652 -250.925023) (xy 268.051425 -250.971536) (xy 268.075097 -251.022033) (xy 268.091165 -251.07544)
			(xy 268.099285 -251.130616) (xy 268.099794 -251.158502) (xy 268.352268 -251.158502) (xy 268.356339 -251.10288)
			(xy 268.368465 -251.048443) (xy 268.388388 -250.996352) (xy 268.415684 -250.947717) (xy 268.44977 -250.903574)
			(xy 268.489919 -250.864865) (xy 268.535277 -250.832414) (xy 268.584877 -250.806913) (xy 268.637661 -250.788906)
			(xy 268.692504 -250.778776) (xy 268.748238 -250.776739) (xy 268.803675 -250.782839) (xy 268.857632 -250.796945)
			(xy 268.908961 -250.818757) (xy 268.956567 -250.847811) (xy 268.999435 -250.883486) (xy 269.036652 -250.925023)
			(xy 269.067425 -250.971536) (xy 269.091097 -251.022033) (xy 269.107165 -251.07544) (xy 269.115285 -251.130616)
			(xy 269.115794 -251.158502) (xy 269.368268 -251.158502) (xy 269.372339 -251.10288) (xy 269.384465 -251.048443)
			(xy 269.404388 -250.996352) (xy 269.431684 -250.947717) (xy 269.46577 -250.903574) (xy 269.505919 -250.864865)
			(xy 269.551277 -250.832414) (xy 269.600877 -250.806913) (xy 269.653661 -250.788906) (xy 269.708504 -250.778776)
			(xy 269.764238 -250.776739) (xy 269.819675 -250.782839) (xy 269.873632 -250.796945) (xy 269.924961 -250.818757)
			(xy 269.972567 -250.847811) (xy 270.015435 -250.883486) (xy 270.052652 -250.925023) (xy 270.083425 -250.971536)
			(xy 270.107097 -251.022033) (xy 270.123165 -251.07544) (xy 270.131285 -251.130616) (xy 270.131609 -251.148342)
			(xy 270.337024 -251.148342) (xy 270.341095 -251.09272) (xy 270.353221 -251.038283) (xy 270.373144 -250.986192)
			(xy 270.40044 -250.937557) (xy 270.434526 -250.893414) (xy 270.474675 -250.854705) (xy 270.520033 -250.822254)
			(xy 270.569633 -250.796753) (xy 270.622417 -250.778746) (xy 270.67726 -250.768616) (xy 270.732994 -250.766579)
			(xy 270.788431 -250.772679) (xy 270.842388 -250.786785) (xy 270.893717 -250.808597) (xy 270.941323 -250.837651)
			(xy 270.984191 -250.873326) (xy 271.021408 -250.914863) (xy 271.052181 -250.961376) (xy 271.075853 -251.011873)
			(xy 271.091921 -251.06528) (xy 271.100041 -251.120456) (xy 271.10055 -251.148342) (xy 271.100365 -251.158502)
			(xy 271.400268 -251.158502) (xy 271.404339 -251.10288) (xy 271.416465 -251.048443) (xy 271.436388 -250.996352)
			(xy 271.463684 -250.947717) (xy 271.49777 -250.903574) (xy 271.537919 -250.864865) (xy 271.583277 -250.832414)
			(xy 271.632877 -250.806913) (xy 271.685661 -250.788906) (xy 271.740504 -250.778776) (xy 271.796238 -250.776739)
			(xy 271.851675 -250.782839) (xy 271.905632 -250.796945) (xy 271.956961 -250.818757) (xy 272.004567 -250.847811)
			(xy 272.047435 -250.883486) (xy 272.084652 -250.925023) (xy 272.115425 -250.971536) (xy 272.139097 -251.022033)
			(xy 272.155165 -251.07544) (xy 272.163285 -251.130616) (xy 272.163794 -251.158502) (xy 272.416268 -251.158502)
			(xy 272.420339 -251.10288) (xy 272.432465 -251.048443) (xy 272.452388 -250.996352) (xy 272.479684 -250.947717)
			(xy 272.51377 -250.903574) (xy 272.553919 -250.864865) (xy 272.599277 -250.832414) (xy 272.648877 -250.806913)
			(xy 272.701661 -250.788906) (xy 272.756504 -250.778776) (xy 272.812238 -250.776739) (xy 272.867675 -250.782839)
			(xy 272.921632 -250.796945) (xy 272.972961 -250.818757) (xy 273.020567 -250.847811) (xy 273.063435 -250.883486)
			(xy 273.100652 -250.925023) (xy 273.131425 -250.971536) (xy 273.155097 -251.022033) (xy 273.171165 -251.07544)
			(xy 273.179285 -251.130616) (xy 273.179794 -251.158502) (xy 273.179285 -251.186388) (xy 273.171165 -251.241564)
			(xy 273.155097 -251.294971) (xy 273.131425 -251.345468) (xy 273.100652 -251.391981) (xy 273.063435 -251.433518)
			(xy 273.020567 -251.469193) (xy 272.972961 -251.498247) (xy 272.921632 -251.520059) (xy 272.867675 -251.534165)
			(xy 272.812238 -251.540265) (xy 272.756504 -251.538228) (xy 272.701661 -251.528098) (xy 272.648877 -251.510091)
			(xy 272.599277 -251.48459) (xy 272.553919 -251.452139) (xy 272.51377 -251.41343) (xy 272.479684 -251.369287)
			(xy 272.452388 -251.320652) (xy 272.432465 -251.268561) (xy 272.420339 -251.214124) (xy 272.416268 -251.158502)
			(xy 272.163794 -251.158502) (xy 272.163285 -251.186388) (xy 272.155165 -251.241564) (xy 272.139097 -251.294971)
			(xy 272.115425 -251.345468) (xy 272.084652 -251.391981) (xy 272.047435 -251.433518) (xy 272.004567 -251.469193)
			(xy 271.956961 -251.498247) (xy 271.905632 -251.520059) (xy 271.851675 -251.534165) (xy 271.796238 -251.540265)
			(xy 271.740504 -251.538228) (xy 271.685661 -251.528098) (xy 271.632877 -251.510091) (xy 271.583277 -251.48459)
			(xy 271.537919 -251.452139) (xy 271.49777 -251.41343) (xy 271.463684 -251.369287) (xy 271.436388 -251.320652)
			(xy 271.416465 -251.268561) (xy 271.404339 -251.214124) (xy 271.400268 -251.158502) (xy 271.100365 -251.158502)
			(xy 271.100041 -251.176228) (xy 271.091921 -251.231404) (xy 271.075853 -251.284811) (xy 271.052181 -251.335308)
			(xy 271.021408 -251.381821) (xy 270.984191 -251.423358) (xy 270.941323 -251.459033) (xy 270.893717 -251.488087)
			(xy 270.842388 -251.509899) (xy 270.788431 -251.524005) (xy 270.732994 -251.530105) (xy 270.67726 -251.528068)
			(xy 270.622417 -251.517938) (xy 270.569633 -251.499931) (xy 270.520033 -251.47443) (xy 270.474675 -251.441979)
			(xy 270.434526 -251.40327) (xy 270.40044 -251.359127) (xy 270.373144 -251.310492) (xy 270.353221 -251.258401)
			(xy 270.341095 -251.203964) (xy 270.337024 -251.148342) (xy 270.131609 -251.148342) (xy 270.131794 -251.158502)
			(xy 270.131285 -251.186388) (xy 270.123165 -251.241564) (xy 270.107097 -251.294971) (xy 270.083425 -251.345468)
			(xy 270.052652 -251.391981) (xy 270.015435 -251.433518) (xy 269.972567 -251.469193) (xy 269.924961 -251.498247)
			(xy 269.873632 -251.520059) (xy 269.819675 -251.534165) (xy 269.764238 -251.540265) (xy 269.708504 -251.538228)
			(xy 269.653661 -251.528098) (xy 269.600877 -251.510091) (xy 269.551277 -251.48459) (xy 269.505919 -251.452139)
			(xy 269.46577 -251.41343) (xy 269.431684 -251.369287) (xy 269.404388 -251.320652) (xy 269.384465 -251.268561)
			(xy 269.372339 -251.214124) (xy 269.368268 -251.158502) (xy 269.115794 -251.158502) (xy 269.115285 -251.186388)
			(xy 269.107165 -251.241564) (xy 269.091097 -251.294971) (xy 269.067425 -251.345468) (xy 269.036652 -251.391981)
			(xy 268.999435 -251.433518) (xy 268.956567 -251.469193) (xy 268.908961 -251.498247) (xy 268.857632 -251.520059)
			(xy 268.803675 -251.534165) (xy 268.748238 -251.540265) (xy 268.692504 -251.538228) (xy 268.637661 -251.528098)
			(xy 268.584877 -251.510091) (xy 268.535277 -251.48459) (xy 268.489919 -251.452139) (xy 268.44977 -251.41343)
			(xy 268.415684 -251.369287) (xy 268.388388 -251.320652) (xy 268.368465 -251.268561) (xy 268.356339 -251.214124)
			(xy 268.352268 -251.158502) (xy 268.099794 -251.158502) (xy 268.099285 -251.186388) (xy 268.091165 -251.241564)
			(xy 268.075097 -251.294971) (xy 268.051425 -251.345468) (xy 268.020652 -251.391981) (xy 267.983435 -251.433518)
			(xy 267.940567 -251.469193) (xy 267.892961 -251.498247) (xy 267.841632 -251.520059) (xy 267.787675 -251.534165)
			(xy 267.732238 -251.540265) (xy 267.676504 -251.538228) (xy 267.621661 -251.528098) (xy 267.568877 -251.510091)
			(xy 267.519277 -251.48459) (xy 267.473919 -251.452139) (xy 267.43377 -251.41343) (xy 267.399684 -251.369287)
			(xy 267.372388 -251.320652) (xy 267.352465 -251.268561) (xy 267.340339 -251.214124) (xy 267.336268 -251.158502)
			(xy 267.083794 -251.158502) (xy 267.083285 -251.186388) (xy 267.075165 -251.241564) (xy 267.059097 -251.294971)
			(xy 267.035425 -251.345468) (xy 267.004652 -251.391981) (xy 266.967435 -251.433518) (xy 266.924567 -251.469193)
			(xy 266.876961 -251.498247) (xy 266.825632 -251.520059) (xy 266.771675 -251.534165) (xy 266.716238 -251.540265)
			(xy 266.660504 -251.538228) (xy 266.605661 -251.528098) (xy 266.552877 -251.510091) (xy 266.503277 -251.48459)
			(xy 266.457919 -251.452139) (xy 266.41777 -251.41343) (xy 266.383684 -251.369287) (xy 266.356388 -251.320652)
			(xy 266.336465 -251.268561) (xy 266.324339 -251.214124) (xy 266.320268 -251.158502) (xy 266.067794 -251.158502)
			(xy 266.067285 -251.186388) (xy 266.059165 -251.241564) (xy 266.043097 -251.294971) (xy 266.019425 -251.345468)
			(xy 265.988652 -251.391981) (xy 265.951435 -251.433518) (xy 265.908567 -251.469193) (xy 265.860961 -251.498247)
			(xy 265.809632 -251.520059) (xy 265.755675 -251.534165) (xy 265.700238 -251.540265) (xy 265.644504 -251.538228)
			(xy 265.589661 -251.528098) (xy 265.536877 -251.510091) (xy 265.487277 -251.48459) (xy 265.441919 -251.452139)
			(xy 265.40177 -251.41343) (xy 265.367684 -251.369287) (xy 265.340388 -251.320652) (xy 265.320465 -251.268561)
			(xy 265.308339 -251.214124) (xy 265.304268 -251.158502) (xy 265.051794 -251.158502) (xy 265.051285 -251.186388)
			(xy 265.043165 -251.241564) (xy 265.027097 -251.294971) (xy 265.003425 -251.345468) (xy 264.972652 -251.391981)
			(xy 264.935435 -251.433518) (xy 264.892567 -251.469193) (xy 264.844961 -251.498247) (xy 264.793632 -251.520059)
			(xy 264.739675 -251.534165) (xy 264.684238 -251.540265) (xy 264.628504 -251.538228) (xy 264.573661 -251.528098)
			(xy 264.520877 -251.510091) (xy 264.471277 -251.48459) (xy 264.425919 -251.452139) (xy 264.38577 -251.41343)
			(xy 264.351684 -251.369287) (xy 264.324388 -251.320652) (xy 264.304465 -251.268561) (xy 264.292339 -251.214124)
			(xy 264.288268 -251.158502) (xy 264.035794 -251.158502) (xy 264.035285 -251.186388) (xy 264.027165 -251.241564)
			(xy 264.011097 -251.294971) (xy 263.987425 -251.345468) (xy 263.956652 -251.391981) (xy 263.919435 -251.433518)
			(xy 263.876567 -251.469193) (xy 263.828961 -251.498247) (xy 263.777632 -251.520059) (xy 263.723675 -251.534165)
			(xy 263.668238 -251.540265) (xy 263.612504 -251.538228) (xy 263.557661 -251.528098) (xy 263.504877 -251.510091)
			(xy 263.455277 -251.48459) (xy 263.409919 -251.452139) (xy 263.36977 -251.41343) (xy 263.335684 -251.369287)
			(xy 263.308388 -251.320652) (xy 263.288465 -251.268561) (xy 263.276339 -251.214124) (xy 263.272268 -251.158502)
			(xy 263.019794 -251.158502) (xy 263.019285 -251.186388) (xy 263.011165 -251.241564) (xy 262.995097 -251.294971)
			(xy 262.971425 -251.345468) (xy 262.940652 -251.391981) (xy 262.903435 -251.433518) (xy 262.860567 -251.469193)
			(xy 262.812961 -251.498247) (xy 262.761632 -251.520059) (xy 262.707675 -251.534165) (xy 262.652238 -251.540265)
			(xy 262.596504 -251.538228) (xy 262.541661 -251.528098) (xy 262.488877 -251.510091) (xy 262.439277 -251.48459)
			(xy 262.393919 -251.452139) (xy 262.35377 -251.41343) (xy 262.319684 -251.369287) (xy 262.292388 -251.320652)
			(xy 262.272465 -251.268561) (xy 262.260339 -251.214124) (xy 262.256268 -251.158502) (xy 262.003794 -251.158502)
			(xy 262.003285 -251.186388) (xy 261.995165 -251.241564) (xy 261.979097 -251.294971) (xy 261.955425 -251.345468)
			(xy 261.924652 -251.391981) (xy 261.887435 -251.433518) (xy 261.844567 -251.469193) (xy 261.796961 -251.498247)
			(xy 261.745632 -251.520059) (xy 261.691675 -251.534165) (xy 261.636238 -251.540265) (xy 261.580504 -251.538228)
			(xy 261.525661 -251.528098) (xy 261.472877 -251.510091) (xy 261.423277 -251.48459) (xy 261.377919 -251.452139)
			(xy 261.33777 -251.41343) (xy 261.303684 -251.369287) (xy 261.276388 -251.320652) (xy 261.256465 -251.268561)
			(xy 261.244339 -251.214124) (xy 261.240268 -251.158502) (xy 260.987794 -251.158502) (xy 260.987285 -251.186388)
			(xy 260.979165 -251.241564) (xy 260.963097 -251.294971) (xy 260.939425 -251.345468) (xy 260.908652 -251.391981)
			(xy 260.871435 -251.433518) (xy 260.828567 -251.469193) (xy 260.780961 -251.498247) (xy 260.729632 -251.520059)
			(xy 260.675675 -251.534165) (xy 260.620238 -251.540265) (xy 260.564504 -251.538228) (xy 260.509661 -251.528098)
			(xy 260.456877 -251.510091) (xy 260.407277 -251.48459) (xy 260.361919 -251.452139) (xy 260.32177 -251.41343)
			(xy 260.287684 -251.369287) (xy 260.260388 -251.320652) (xy 260.240465 -251.268561) (xy 260.228339 -251.214124)
			(xy 260.224268 -251.158502) (xy 259.971794 -251.158502) (xy 259.971285 -251.186388) (xy 259.963165 -251.241564)
			(xy 259.947097 -251.294971) (xy 259.923425 -251.345468) (xy 259.892652 -251.391981) (xy 259.855435 -251.433518)
			(xy 259.812567 -251.469193) (xy 259.764961 -251.498247) (xy 259.713632 -251.520059) (xy 259.659675 -251.534165)
			(xy 259.604238 -251.540265) (xy 259.548504 -251.538228) (xy 259.493661 -251.528098) (xy 259.440877 -251.510091)
			(xy 259.391277 -251.48459) (xy 259.345919 -251.452139) (xy 259.30577 -251.41343) (xy 259.271684 -251.369287)
			(xy 259.244388 -251.320652) (xy 259.224465 -251.268561) (xy 259.212339 -251.214124) (xy 259.208268 -251.158502)
			(xy 258.955794 -251.158502) (xy 258.955285 -251.186388) (xy 258.947165 -251.241564) (xy 258.931097 -251.294971)
			(xy 258.907425 -251.345468) (xy 258.876652 -251.391981) (xy 258.839435 -251.433518) (xy 258.796567 -251.469193)
			(xy 258.748961 -251.498247) (xy 258.697632 -251.520059) (xy 258.643675 -251.534165) (xy 258.588238 -251.540265)
			(xy 258.532504 -251.538228) (xy 258.477661 -251.528098) (xy 258.424877 -251.510091) (xy 258.375277 -251.48459)
			(xy 258.329919 -251.452139) (xy 258.28977 -251.41343) (xy 258.255684 -251.369287) (xy 258.228388 -251.320652)
			(xy 258.208465 -251.268561) (xy 258.196339 -251.214124) (xy 258.192268 -251.158502) (xy 257.939794 -251.158502)
			(xy 257.939285 -251.186388) (xy 257.931165 -251.241564) (xy 257.915097 -251.294971) (xy 257.891425 -251.345468)
			(xy 257.860652 -251.391981) (xy 257.823435 -251.433518) (xy 257.780567 -251.469193) (xy 257.732961 -251.498247)
			(xy 257.681632 -251.520059) (xy 257.627675 -251.534165) (xy 257.572238 -251.540265) (xy 257.516504 -251.538228)
			(xy 257.461661 -251.528098) (xy 257.408877 -251.510091) (xy 257.359277 -251.48459) (xy 257.313919 -251.452139)
			(xy 257.27377 -251.41343) (xy 257.239684 -251.369287) (xy 257.212388 -251.320652) (xy 257.192465 -251.268561)
			(xy 257.180339 -251.214124) (xy 257.176268 -251.158502) (xy 256.810481 -251.158502) (xy 256.810764 -251.173996)
			(xy 256.810255 -251.201882) (xy 256.802135 -251.257058) (xy 256.786067 -251.310465) (xy 256.762395 -251.360962)
			(xy 256.731622 -251.407475) (xy 256.694405 -251.449012) (xy 256.651537 -251.484687) (xy 256.603931 -251.513741)
			(xy 256.552602 -251.535553) (xy 256.498645 -251.549659) (xy 256.443208 -251.555759) (xy 256.387474 -251.553722)
			(xy 256.332631 -251.543592) (xy 256.279847 -251.525585) (xy 256.230247 -251.500084) (xy 256.184889 -251.467633)
			(xy 256.14474 -251.428924) (xy 256.110654 -251.384781) (xy 256.083358 -251.336146) (xy 256.063435 -251.284055)
			(xy 256.051309 -251.229618) (xy 256.047238 -251.173996) (xy 247.541796 -251.173996) (xy 247.541796 -251.88291)
			(xy 247.539764 -251.88799) (xy 247.539764 -253.489206) (xy 247.54078 -253.498858) (xy 247.542407 -253.506103)
			(xy 247.549244 -253.519275) (xy 247.554242 -253.524766) (xy 247.780302 -253.750826) (xy 247.785801 -253.755814)
			(xy 247.798967 -253.762661) (xy 247.80621 -253.764288) (xy 247.815862 -253.765304) (xy 249.83948 -253.765304)
			(xy 249.844435 -253.765421) (xy 249.854158 -253.767336) (xy 249.858784 -253.769114) (xy 249.877834 -253.777242)
			(xy 249.881582 -253.778544) (xy 249.889366 -253.78008) (xy 249.893328 -253.78029) (xy 253.477776 -253.78029)
			(xy 253.487174 -253.779274) (xy 253.49962 -253.776226) (xy 253.505462 -253.774956) (xy 253.52756 -253.76378)
			(xy 253.534418 -253.755906) (xy 253.55296 -253.734824) (xy 253.579122 -253.705106) (xy 253.584331 -253.698145)
			(xy 253.590186 -253.681787) (xy 253.590552 -253.673102) (xy 253.590552 -253.667006) (xy 253.590298 -253.663958)
			(xy 253.589127 -253.653201) (xy 253.587857 -253.631598) (xy 253.587758 -253.620778) (xy 253.587758 -253.620524)
			(xy 253.588263 -253.593285) (xy 253.596051 -253.539365) (xy 253.611429 -253.487102) (xy 253.634086 -253.437557)
			(xy 253.663559 -253.391739) (xy 253.69925 -253.350579) (xy 253.740433 -253.314914) (xy 253.78627 -253.28547)
			(xy 253.835829 -253.262845) (xy 253.888102 -253.247499) (xy 253.942026 -253.239745) (xy 253.969266 -253.23927)
			(xy 253.996521 -253.239731) (xy 254.050477 -253.247483) (xy 254.10278 -253.262836) (xy 254.152366 -253.285477)
			(xy 254.198225 -253.314943) (xy 254.239424 -253.350637) (xy 254.275123 -253.39183) (xy 254.304597 -253.437685)
			(xy 254.327244 -253.487267) (xy 254.342605 -253.539568) (xy 254.350365 -253.593523) (xy 254.350774 -253.620778)
			(xy 254.350686 -253.632237) (xy 254.349291 -253.655114) (xy 254.34798 -253.666498) (xy 254.34671 -253.67742)
			(xy 254.349758 -253.687326) (xy 254.351466 -253.692256) (xy 254.356585 -253.701346) (xy 254.359918 -253.70536)
			(xy 254.385572 -253.73457) (xy 254.385572 -253.735078) (xy 254.410464 -253.763018) (xy 254.417999 -253.770816)
			(xy 254.437733 -253.779757) (xy 254.448564 -253.78029) (xy 271.348962 -253.78029) (xy 271.359122 -253.77902)
			(xy 271.372076 -253.77521) (xy 271.379343 -253.772073) (xy 271.391632 -253.762112) (xy 271.396206 -253.755652)
			(xy 271.435068 -253.692914) (xy 271.438624 -253.687326) (xy 271.441418 -253.678436) (xy 271.442367 -253.674957)
			(xy 271.443388 -253.667818) (xy 271.44345 -253.664212) (xy 271.44345 -253.64059) (xy 271.441164 -253.630176)
			(xy 271.43837 -253.624588) (xy 271.426461 -253.598626) (xy 271.409685 -253.544028) (xy 271.401241 -253.487539)
			(xy 271.400778 -253.45898) (xy 271.400778 -253.447042) (xy 271.401893 -253.420232) (xy 271.410714 -253.367302)
			(xy 271.426867 -253.316132) (xy 271.450032 -253.26773) (xy 271.479751 -253.223053) (xy 271.515439 -253.182981)
			(xy 271.556391 -253.148307) (xy 271.601798 -253.119715) (xy 271.650764 -253.097768) (xy 271.702323 -253.082901)
			(xy 271.755456 -253.075407) (xy 271.782286 -253.074932) (xy 271.809122 -253.075394) (xy 271.862264 -253.082926)
			(xy 271.913826 -253.097828) (xy 271.962792 -253.119807) (xy 272.008196 -253.14843) (xy 272.049142 -253.183132)
			(xy 272.084822 -253.223228) (xy 272.114533 -253.267927) (xy 272.137689 -253.316348) (xy 272.153832 -253.367535)
			(xy 272.162645 -253.42048) (xy 272.163794 -253.447296) (xy 272.163794 -253.456694) (xy 272.163289 -253.484883)
			(xy 272.154999 -253.540649) (xy 272.138598 -253.594589) (xy 272.126964 -253.62027) (xy 272.126456 -253.621286)
			(xy 272.12544 -253.623318) (xy 272.124932 -253.624334) (xy 272.123662 -253.627382) (xy 272.119852 -253.637542)
			(xy 272.118328 -253.643384) (xy 272.115534 -253.653544) (xy 272.116804 -253.66345) (xy 272.117713 -253.668554)
			(xy 272.121296 -253.67828) (xy 272.123916 -253.682754) (xy 272.15211 -253.72949) (xy 272.168112 -253.755906)
			(xy 272.171668 -253.76124) (xy 272.179281 -253.769884) (xy 272.200039 -253.779814) (xy 272.211546 -253.78029)
			(xy 285.050738 -253.78029) (xy 285.058866 -253.779528) (xy 285.059374 -253.779528) (xy 285.06689 -253.777923)
			(xy 285.080573 -253.770941) (xy 285.086298 -253.765812) (xy 285.554166 -253.297944) (xy 285.559365 -253.292195)
			(xy 285.566343 -253.278363) (xy 285.567882 -253.270766) (xy 285.568644 -253.262384) (xy 285.568644 -252.365764)
			(xy 285.568549 -252.361619) (xy 285.567146 -252.353447) (xy 285.56585 -252.349508) (xy 277.485094 -228.474524)
			(xy 277.478401 -228.469709) (xy 277.462849 -228.464266) (xy 277.454614 -228.463856) (xy 277.40356 -228.46284)
			(xy 277.359618 -228.462078) (xy 277.351844 -228.462278) (xy 277.336975 -228.466804) (xy 277.330408 -228.470968)
			(xy 277.324058 -228.475286) (xy 277.31466 -228.48697) (xy 277.311612 -228.49459) (xy 277.300821 -228.521237)
			(xy 277.272395 -228.571206) (xy 277.2368 -228.616349) (xy 277.194838 -228.655645) (xy 277.147459 -228.688206)
			(xy 277.095734 -228.713295) (xy 277.040832 -228.730346) (xy 276.983994 -228.738973) (xy 276.95525 -228.739446)
			(xy 276.927994 -228.738987) (xy 276.874035 -228.731236) (xy 276.821729 -228.715884) (xy 276.77214 -228.693245)
			(xy 276.726278 -228.663779) (xy 276.685076 -228.628086) (xy 276.649374 -228.586892) (xy 276.619897 -228.541037)
			(xy 276.597247 -228.491453) (xy 276.581883 -228.439151) (xy 276.57412 -228.385194) (xy 276.573742 -228.357938)
			(xy 276.57421 -228.330997) (xy 276.581797 -228.277652) (xy 276.596811 -228.225904) (xy 276.618955 -228.176783)
			(xy 276.647787 -228.131264) (xy 276.682734 -228.090253) (xy 276.723103 -228.054564) (xy 276.768089 -228.024909)
			(xy 276.8168 -228.001875) (xy 276.868266 -227.985921) (xy 276.921464 -227.977364) (xy 276.948392 -227.97643)
			(xy 276.955758 -227.97643) (xy 276.981186 -227.976863) (xy 277.031588 -227.98365) (xy 277.080638 -227.997083)
			(xy 277.127466 -228.016922) (xy 277.14956 -228.029516) (xy 277.161752 -228.034596) (xy 277.181564 -228.040184)
			(xy 277.19005 -228.039861) (xy 277.206122 -228.034413) (xy 277.21306 -228.029516) (xy 277.2156 -228.027484)
			(xy 277.28291 -227.97389) (xy 277.287228 -227.97008) (xy 277.291546 -227.965762) (xy 277.296183 -227.96078)
			(xy 277.302871 -227.948934) (xy 277.304754 -227.942394) (xy 273.928586 -217.967814) (xy 273.92122 -217.962988)
			(xy 273.90598 -217.956892) (xy 273.879618 -217.945955) (xy 273.830209 -217.917391) (xy 273.785608 -217.881783)
			(xy 273.746813 -217.839925) (xy 273.71469 -217.792753) (xy 273.689955 -217.74132) (xy 273.673162 -217.686775)
			(xy 273.664686 -217.630336) (xy 273.664172 -217.6018) (xy 273.664606 -217.575898) (xy 273.671617 -217.524572)
			(xy 273.685511 -217.474666) (xy 273.706031 -217.4271) (xy 273.719036 -217.404696) (xy 273.722846 -217.3986)
			(xy 273.72437 -217.395806) (xy 273.724878 -217.394028) (xy 273.726746 -217.386556) (xy 273.726365 -217.371168)
			(xy 273.724116 -217.363802) (xy 262.001 -182.727854) (xy 261.995695 -182.723933) (xy 261.983607 -182.718659)
			(xy 261.977124 -182.71744) (xy 261.891018 -182.707026) (xy 261.890002 -182.707026) (xy 261.883906 -182.706518)
			(xy 261.876915 -182.706034) (xy 261.863123 -182.708479) (xy 261.856728 -182.711344) (xy 261.850378 -182.714392)
			(xy 261.840218 -182.723536) (xy 261.836154 -182.729632) (xy 261.821039 -182.752511) (xy 261.785297 -182.794095)
			(xy 261.743978 -182.830145) (xy 261.697931 -182.859918) (xy 261.648102 -182.882805) (xy 261.595513 -182.898336)
			(xy 261.541245 -182.906191) (xy 261.513828 -182.90667) (xy 261.513574 -182.90667) (xy 261.484438 -182.906127)
			(xy 261.426845 -182.897266) (xy 261.371277 -182.879724) (xy 261.344918 -182.8673) (xy 261.334758 -182.86222)
			(xy 261.31266 -182.861712) (xy 261.230872 -182.897526) (xy 261.220927 -182.902389) (xy 261.206174 -182.91886)
			(xy 261.202424 -182.929276) (xy 261.202424 -182.92953) (xy 261.19424 -182.955477) (xy 261.171543 -183.004923)
			(xy 261.142054 -183.050645) (xy 261.10637 -183.091715) (xy 261.065215 -183.1273) (xy 261.019424 -183.15668)
			(xy 260.969924 -183.179259) (xy 260.917719 -183.194579) (xy 260.863867 -183.202329) (xy 260.836664 -183.202834)
			(xy 260.809414 -183.202346) (xy 260.755469 -183.194585) (xy 260.703177 -183.179227) (xy 260.653602 -183.156584)
			(xy 260.607755 -183.127118) (xy 260.566566 -183.091426) (xy 260.530876 -183.050237) (xy 260.501411 -183.004389)
			(xy 260.478769 -182.954814) (xy 260.463413 -182.902522) (xy 260.455654 -182.848576) (xy 260.455156 -182.821326)
			(xy 260.45571 -182.791776) (xy 260.464826 -182.733383) (xy 260.482844 -182.677096) (xy 260.509331 -182.624265)
			(xy 260.543655 -182.576153) (xy 260.584992 -182.533914) (xy 260.608318 -182.515764) (xy 260.615037 -182.51029)
			(xy 260.624642 -182.495877) (xy 260.627114 -182.48757) (xy 260.634734 -182.458614) (xy 260.636562 -182.450129)
			(xy 260.634995 -182.432857) (xy 260.631686 -182.424832) (xy 260.62092 -182.399945) (xy 260.605744 -182.34789)
			(xy 260.598101 -182.294209) (xy 260.59765 -182.267098) (xy 260.598114 -182.239827) (xy 260.605876 -182.185841)
			(xy 260.621243 -182.13351) (xy 260.6439 -182.083897) (xy 260.673388 -182.038015) (xy 260.709106 -181.996796)
			(xy 260.750326 -181.96108) (xy 260.79621 -181.931594) (xy 260.845823 -181.908938) (xy 260.898155 -181.893573)
			(xy 260.952141 -181.885813) (xy 260.979412 -181.885336) (xy 261.007072 -181.885821) (xy 261.061815 -181.893795)
			(xy 261.114833 -181.909589) (xy 261.165015 -181.932872) (xy 261.21131 -181.963156) (xy 261.252748 -181.999806)
			(xy 261.288461 -182.042054) (xy 261.3177 -182.089016) (xy 261.32917 -182.11419) (xy 261.333139 -182.122179)
			(xy 261.345482 -182.13504) (xy 261.3533 -182.139336) (xy 261.380986 -182.152798) (xy 261.389312 -182.156463)
			(xy 261.4074 -182.158274) (xy 261.416292 -182.156354) (xy 261.440239 -182.150422) (xy 261.489161 -182.144048)
			(xy 261.513828 -182.143654) (xy 261.51459 -182.143654) (xy 261.548067 -182.144396) (xy 261.613984 -182.156146)
			(xy 261.645654 -182.167022) (xy 261.652408 -182.169254) (xy 261.66659 -182.170294) (xy 261.673594 -182.169054)
			(xy 261.680452 -182.167784) (xy 261.692898 -182.16118) (xy 261.731252 -182.12435) (xy 261.73176 -182.123842)
			(xy 261.769352 -182.087012) (xy 261.776464 -182.07482) (xy 261.777734 -182.069232) (xy 261.467092 -181.151276)
			(xy 261.458964 -181.146196) (xy 261.454392 -181.144164) (xy 261.428033 -181.133518) (xy 261.378542 -181.10555)
			(xy 261.33375 -181.070547) (xy 261.294649 -181.029284) (xy 261.262105 -180.982676) (xy 261.236838 -180.931753)
			(xy 261.219407 -180.877645) (xy 261.2102 -180.821549) (xy 261.209282 -180.793136) (xy 261.209282 -180.781198)
			(xy 261.209554 -180.770178) (xy 261.211209 -180.748193) (xy 261.212584 -180.737256) (xy 261.21663 -180.710537)
			(xy 261.231297 -180.658526) (xy 261.241794 -180.633624) (xy 261.2461 -180.624002) (xy 261.25563 -180.605194)
			(xy 261.260844 -180.596032) (xy 261.26186 -180.594508) (xy 261.262114 -180.593746) (xy 261.263384 -180.59146)
			(xy 261.265162 -180.588158) (xy 261.26694 -180.584856) (xy 261.272274 -180.575458) (xy 261.272274 -180.575204)
			(xy 260.32714 -177.783236) (xy 260.324847 -177.777158) (xy 260.317647 -177.766351) (xy 260.312916 -177.7619)
			(xy 260.308598 -177.75809) (xy 260.298438 -177.750724) (xy 260.293104 -177.74793) (xy 260.287008 -177.746406)
			(xy 260.286246 -177.746152) (xy 260.262473 -177.739782) (xy 260.216677 -177.72175) (xy 260.173578 -177.697982)
			(xy 260.133891 -177.668872) (xy 260.115812 -177.652172) (xy 260.092444 -177.627788) (xy 260.08786 -177.622857)
			(xy 260.076659 -177.615396) (xy 260.070346 -177.613056) (xy 260.063996 -177.611024) (xy 260.050788 -177.610262)
			(xy 260.02615 -177.615342) (xy 260.025642 -177.615342) (xy 259.957824 -177.629058) (xy 259.951404 -177.630547)
			(xy 259.939569 -177.636331) (xy 259.934456 -177.640488) (xy 259.929376 -177.644806) (xy 259.92201 -177.655982)
			(xy 259.919978 -177.662332) (xy 259.911065 -177.687132) (xy 259.887374 -177.734207) (xy 259.857429 -177.777571)
			(xy 259.821798 -177.816401) (xy 259.781162 -177.849955) (xy 259.736293 -177.877596) (xy 259.688046 -177.898797)
			(xy 259.63734 -177.913154) (xy 259.58514 -177.920394) (xy 259.55879 -177.920904) (xy 259.53154 -177.920418)
			(xy 259.477593 -177.91266) (xy 259.4253 -177.897304) (xy 259.375725 -177.874663) (xy 259.329876 -177.845196)
			(xy 259.288688 -177.809505) (xy 259.252998 -177.768316) (xy 259.223533 -177.722466) (xy 259.200892 -177.67289)
			(xy 259.185538 -177.620597) (xy 259.177782 -177.566651) (xy 259.177782 -177.512149) (xy 259.185538 -177.458203)
			(xy 259.200892 -177.40591) (xy 259.223533 -177.356334) (xy 259.252998 -177.310484) (xy 259.288688 -177.269295)
			(xy 259.329876 -177.233604) (xy 259.375725 -177.204137) (xy 259.4253 -177.181496) (xy 259.477593 -177.16614)
			(xy 259.53154 -177.158382) (xy 259.55879 -177.157888) (xy 259.58587 -177.15836) (xy 259.639486 -177.166014)
			(xy 259.691482 -177.18117) (xy 259.740814 -177.203524) (xy 259.786491 -177.232625) (xy 259.827595 -177.267892)
			(xy 259.84581 -177.287936) (xy 259.849112 -177.291746) (xy 259.858687 -177.299637) (xy 259.882584 -177.30616)
			(xy 259.894832 -177.304192) (xy 259.900166 -177.302922) (xy 259.982716 -177.286412) (xy 259.994255 -177.282802)
			(xy 260.012422 -177.266897) (xy 260.017514 -177.255932) (xy 260.018022 -177.2539) (xy 260.020816 -177.245772)
			(xy 260.030722 -177.217324) (xy 260.035548 -177.207164) (xy 260.050788 -177.182272) (xy 260.051042 -177.182018)
			(xy 260.054344 -177.176684) (xy 260.060934 -177.166061) (xy 260.075299 -177.145601) (xy 260.083046 -177.13579)
			(xy 260.093714 -177.122582) (xy 260.096254 -177.117248) (xy 260.099048 -177.109628) (xy 259.727954 -176.012348)
			(xy 259.72389 -176.008538) (xy 259.707634 -176.003204) (xy 259.707126 -176.003204) (xy 259.680304 -175.994354)
			(xy 259.629265 -175.970164) (xy 259.582133 -175.939039) (xy 259.539845 -175.901598) (xy 259.50324 -175.858584)
			(xy 259.473046 -175.810851) (xy 259.449861 -175.759348) (xy 259.434148 -175.705096) (xy 259.426217 -175.649175)
			(xy 259.425694 -175.620934) (xy 259.425694 -175.62068) (xy 259.42625 -175.590442) (xy 259.435356 -175.530656)
			(xy 259.453359 -175.472922) (xy 259.479848 -175.418556) (xy 259.49656 -175.39335) (xy 259.4991 -175.38954)
			(xy 259.503164 -175.382174) (xy 259.506212 -175.374808) (xy 259.507736 -175.37049) (xy 259.509006 -175.366172)
			(xy 258.639056 -172.795946) (xy 258.636484 -172.788988) (xy 258.627962 -172.776854) (xy 258.622292 -172.77207)
			(xy 258.614418 -172.765974) (xy 258.60248 -172.759116) (xy 258.595876 -172.756322) (xy 258.588764 -172.75556)
			(xy 258.572407 -172.753488) (xy 258.540103 -172.746876) (xy 258.524248 -172.742352) (xy 258.52374 -172.742098)
			(xy 258.509008 -172.737272) (xy 258.501134 -172.73524) (xy 258.487926 -172.732954) (xy 258.473956 -172.732954)
			(xy 258.466314 -172.733219) (xy 258.451718 -172.737756) (xy 258.445254 -172.741844) (xy 258.435348 -172.76064)
			(xy 258.435348 -173.495716) (xy 258.434858 -173.5257) (xy 258.42703 -173.585156) (xy 258.411509 -173.643081)
			(xy 258.38856 -173.698485) (xy 258.358576 -173.750419) (xy 258.32207 -173.797995) (xy 258.279665 -173.8404)
			(xy 258.232089 -173.876906) (xy 258.180155 -173.90689) (xy 258.124751 -173.929839) (xy 258.066826 -173.94536)
			(xy 258.00737 -173.953188) (xy 257.947402 -173.953188) (xy 257.887946 -173.94536) (xy 257.830021 -173.929839)
			(xy 257.774617 -173.90689) (xy 257.722683 -173.876906) (xy 257.675107 -173.8404) (xy 257.632702 -173.797995)
			(xy 257.596196 -173.750419) (xy 257.566212 -173.698485) (xy 257.543263 -173.643081) (xy 257.527742 -173.585156)
			(xy 257.519914 -173.5257) (xy 257.519424 -173.495716) (xy 257.519424 -172.632116) (xy 257.519893 -172.602136)
			(xy 257.52772 -172.542691) (xy 257.543243 -172.484776) (xy 257.566196 -172.429384) (xy 257.596185 -172.377463)
			(xy 257.632697 -172.329904) (xy 257.675107 -172.287519) (xy 257.722688 -172.251035) (xy 257.774626 -172.221076)
			(xy 257.830032 -172.198156) (xy 257.887956 -172.182668) (xy 257.947406 -172.174875) (xy 257.977386 -172.174408)
			(xy 258.011401 -172.17499) (xy 258.078693 -172.18497) (xy 258.14377 -172.204789) (xy 258.174744 -172.218858)
			(xy 258.183126 -172.222922) (xy 258.201922 -172.224446) (xy 258.295394 -172.196506) (xy 258.299712 -172.189394)
			(xy 258.311643 -172.168939) (xy 258.339795 -172.130859) (xy 258.355846 -172.113448) (xy 258.37134 -172.097954)
			(xy 258.378452 -172.09135) (xy 258.3815 -172.087032) (xy 258.384802 -172.082206) (xy 258.38724 -172.078507)
			(xy 258.390941 -172.07046) (xy 258.392168 -172.066204) (xy 255.335024 -163.034218) (xy 255.324863 -163.003415)
			(xy 255.308088 -162.940754) (xy 255.301496 -162.908996) (xy 255.151636 -162.155886) (xy 255.147064 -162.148266)
			(xy 255.133942 -162.125799) (xy 255.113241 -162.078065) (xy 255.099223 -162.02796) (xy 255.092148 -161.976415)
			(xy 255.091692 -161.9504) (xy 255.091788 -161.935802) (xy 255.093949 -161.906686) (xy 255.09601 -161.892234)
			(xy 255.097534 -161.883598) (xy 254.736854 -160.070292) (xy 254.732401 -160.047205) (xy 254.725411 -160.000704)
			(xy 254.722884 -159.977328) (xy 254.721809 -159.969244) (xy 254.715195 -159.954347) (xy 254.70993 -159.948118)
			(xy 254.687805 -159.923113) (xy 254.651773 -159.866908) (xy 254.638302 -159.836358) (xy 254.638302 -159.83585)
			(xy 254.634342 -159.827472) (xy 254.621586 -159.814049) (xy 254.61341 -159.809688) (xy 254.551942 -159.780478)
			(xy 254.543325 -159.776849) (xy 254.524696 -159.775431) (xy 254.51562 -159.777684) (xy 254.489416 -159.784922)
			(xy 254.435613 -159.792706) (xy 254.408432 -159.793178) (xy 254.40767 -159.793178) (xy 254.380422 -159.79269)
			(xy 254.326482 -159.78493) (xy 254.274195 -159.769574) (xy 254.224626 -159.746933) (xy 254.178783 -159.717468)
			(xy 254.137599 -159.681779) (xy 254.101914 -159.640593) (xy 254.072453 -159.594748) (xy 254.049816 -159.545177)
			(xy 254.034463 -159.492888) (xy 254.026708 -159.438948) (xy 254.026708 -159.384452) (xy 254.034463 -159.330511)
			(xy 254.049816 -159.278223) (xy 254.072453 -159.228652) (xy 254.101914 -159.182807) (xy 254.137599 -159.141621)
			(xy 254.178783 -159.105932) (xy 254.224626 -159.076467) (xy 254.274195 -159.053826) (xy 254.326482 -159.03847)
			(xy 254.380422 -159.03071) (xy 254.40767 -159.030162) (xy 254.440329 -159.030826) (xy 254.504697 -159.04193)
			(xy 254.535686 -159.05226) (xy 254.54737 -159.056578) (xy 254.57277 -159.052768) (xy 254.650494 -158.994856)
			(xy 254.660239 -158.98683) (xy 254.671038 -158.964046) (xy 254.671068 -158.951422) (xy 254.649732 -158.514034)
			(xy 254.630428 -158.488888) (xy 254.615188 -158.484062) (xy 254.589882 -158.47542) (xy 254.541782 -158.452057)
			(xy 254.497407 -158.422219) (xy 254.457622 -158.38649) (xy 254.423203 -158.345566) (xy 254.394821 -158.300246)
			(xy 254.373031 -158.251413) (xy 254.358258 -158.20002) (xy 254.350788 -158.147071) (xy 254.350266 -158.120334)
			(xy 254.350756 -158.092287) (xy 254.358945 -158.036795) (xy 254.375152 -157.983094) (xy 254.39903 -157.932337)
			(xy 254.430066 -157.885612) (xy 254.467594 -157.843922) (xy 254.51081 -157.808161) (xy 254.558786 -157.779096)
			(xy 254.584454 -157.767782) (xy 254.584962 -157.767782) (xy 254.594614 -157.763464) (xy 254.611378 -157.73654)
			(xy 254.55372 -156.558742) (xy 254.552958 -156.552646) (xy 254.519684 -156.362146) (xy 254.295148 -155.07589)
			(xy 254.288986 -155.038458) (xy 254.281736 -154.962935) (xy 254.28067 -154.925014) (xy 254.268478 -154.28976)
			(xy 254.266954 -154.213814) (xy 254.266954 -154.213306) (xy 254.266446 -154.18054) (xy 254.266113 -154.174426)
			(xy 254.262905 -154.162613) (xy 254.260096 -154.157172) (xy 254.257302 -154.152092) (xy 254.248666 -154.142694)
			(xy 254.243078 -154.139138) (xy 254.217838 -154.122366) (xy 254.171978 -154.082751) (xy 254.132236 -154.037001)
			(xy 254.099424 -153.986052) (xy 254.074213 -153.930945) (xy 254.057118 -153.872805) (xy 254.048487 -153.812822)
			(xy 254.048006 -153.782522) (xy 254.048006 -153.782268) (xy 254.04848 -153.753943) (xy 254.056028 -153.697798)
			(xy 254.070985 -153.643158) (xy 254.093085 -153.590996) (xy 254.121934 -153.542242) (xy 254.157019 -153.497764)
			(xy 254.197714 -153.458354) (xy 254.220218 -153.441146) (xy 254.2286 -153.434796) (xy 254.235458 -153.423112)
			(xy 254.239268 -153.416254) (xy 254.251206 -153.392632) (xy 254.250952 -153.380186) (xy 254.250952 -153.379932)
			(xy 254.217424 -151.630126) (xy 254.156464 -148.47189) (xy 254.156464 -148.470366) (xy 254.129794 -147.926552)
			(xy 254.124714 -147.916646) (xy 254.111278 -147.889405) (xy 254.092265 -147.831722) (xy 254.082638 -147.771754)
			(xy 254.082042 -147.741386) (xy 254.08243 -147.717264) (xy 254.088541 -147.669409) (xy 254.100626 -147.622704)
			(xy 254.10922 -147.600162) (xy 254.113284 -147.589748) (xy 254.018288 -145.65249) (xy 254.017969 -145.648118)
			(xy 254.016053 -145.639563) (xy 254.014478 -145.635472) (xy 252.543564 -142.084298) (xy 252.539641 -142.075986)
			(xy 252.527012 -142.062651) (xy 252.510502 -142.054606) (xy 252.5014 -142.05331) (xy 252.398022 -142.043404)
			(xy 252.372368 -142.055596) (xy 252.364748 -142.067534) (xy 252.355569 -142.081169) (xy 252.335219 -142.106984)
			(xy 252.324108 -142.119096) (xy 252.319028 -142.12443) (xy 252.312678 -142.13713) (xy 252.310392 -142.149322)
			(xy 252.310392 -142.222982) (xy 252.310471 -142.227191) (xy 252.311872 -142.235492) (xy 252.313186 -142.239492)
			(xy 252.318012 -142.251176) (xy 252.324362 -142.258034) (xy 252.343598 -142.279366) (xy 252.376095 -142.326728)
			(xy 252.401125 -142.378426) (xy 252.418123 -142.433293) (xy 252.426703 -142.490087) (xy 252.426671 -142.547526)
			(xy 252.41803 -142.604312) (xy 252.400973 -142.65916) (xy 252.375887 -142.710831) (xy 252.343338 -142.758157)
			(xy 252.324108 -142.779496) (xy 252.319028 -142.78483) (xy 252.312678 -142.79753) (xy 252.310392 -142.809722)
			(xy 252.310392 -142.883382) (xy 252.311154 -142.891764) (xy 252.311154 -142.892018) (xy 252.31256 -142.898885)
			(xy 252.318611 -142.911521) (xy 252.323092 -142.91691) (xy 252.342942 -142.938663) (xy 252.376371 -142.987141)
			(xy 252.38964 -143.01343) (xy 252.392942 -143.020542) (xy 252.39853 -143.033496) (xy 252.408086 -143.057762)
			(xy 252.421221 -143.108233) (xy 252.424692 -143.13408) (xy 252.424692 -143.134334) (xy 252.42647 -143.14932)
			(xy 252.427486 -143.179038) (xy 252.426944 -143.208123) (xy 252.418127 -143.26562) (xy 252.400688 -143.321113)
			(xy 252.37503 -143.373318) (xy 252.341749 -143.421025) (xy 252.301613 -143.463129) (xy 252.278896 -143.481298)
			(xy 252.276102 -143.48333) (xy 252.262894 -143.496538) (xy 252.259084 -143.505174) (xy 252.258068 -143.50746)
			(xy 252.25502 -143.51254) (xy 252.254766 -143.512794) (xy 252.25121 -143.517874) (xy 252.24585 -143.526449)
			(xy 252.241771 -143.546239) (xy 252.243336 -143.556228) (xy 252.244606 -143.56334) (xy 252.245368 -143.572484)
			(xy 252.245368 -143.595598) (xy 252.246638 -143.607536) (xy 252.249432 -143.618712) (xy 252.250956 -143.6243)
			(xy 252.259084 -143.641318) (xy 252.26081 -143.644709) (xy 252.265146 -143.650962) (xy 252.26772 -143.653764)
			(xy 252.269244 -143.655288) (xy 252.27661 -143.662654) (xy 252.27915 -143.664432) (xy 252.301778 -143.682642)
			(xy 252.341786 -143.724747) (xy 252.37496 -143.772423) (xy 252.400535 -143.82457) (xy 252.417924 -143.879987)
			(xy 252.426724 -143.937397) (xy 252.427232 -143.966438) (xy 252.426744 -143.993688) (xy 252.418983 -144.047633)
			(xy 252.403625 -144.099925) (xy 252.380982 -144.149499) (xy 252.351515 -144.195346) (xy 252.315824 -144.236534)
			(xy 252.274635 -144.272223) (xy 252.228786 -144.301688) (xy 252.179211 -144.32433) (xy 252.126919 -144.339686)
			(xy 252.072974 -144.347445) (xy 252.045724 -144.347946) (xy 252.017988 -144.347443) (xy 251.963101 -144.339401)
			(xy 251.909957 -144.323498) (xy 251.859676 -144.300068) (xy 251.813316 -144.269606) (xy 251.771854 -144.232753)
			(xy 251.736165 -144.190286) (xy 251.707 -144.143099) (xy 251.684973 -144.092187) (xy 251.670549 -144.038623)
			(xy 251.666756 -144.011142) (xy 251.664978 -143.996156) (xy 251.663962 -143.966438) (xy 251.664506 -143.937355)
			(xy 251.673327 -143.879861) (xy 251.69077 -143.824371) (xy 251.716432 -143.772172) (xy 251.749717 -143.72447)
			(xy 251.789856 -143.682373) (xy 251.812552 -143.664178) (xy 251.815346 -143.662146) (xy 251.828554 -143.648938)
			(xy 251.832364 -143.640302) (xy 251.83338 -143.638016) (xy 251.836428 -143.632936) (xy 251.836682 -143.632682)
			(xy 251.840238 -143.627602) (xy 251.84559 -143.619025) (xy 251.849656 -143.599239) (xy 251.848112 -143.589248)
			(xy 251.846842 -143.582136) (xy 251.84608 -143.572992) (xy 251.84608 -143.55064) (xy 251.845064 -143.540988)
			(xy 251.841254 -143.524478) (xy 251.83973 -143.519906) (xy 251.830078 -143.499332) (xy 251.828808 -143.496792)
			(xy 251.814838 -143.482822) (xy 251.812298 -143.481044) (xy 251.789674 -143.462831) (xy 251.749674 -143.420724)
			(xy 251.716508 -143.373047) (xy 251.690939 -143.320901) (xy 251.673557 -143.265485) (xy 251.664761 -143.208077)
			(xy 251.664216 -143.179038) (xy 251.664734 -143.150298) (xy 251.673352 -143.093468) (xy 251.690399 -143.038573)
			(xy 251.715488 -142.986858) (xy 251.748052 -142.939492) (xy 251.76734 -142.91818) (xy 251.77242 -142.912846)
			(xy 251.77877 -142.900146) (xy 251.781056 -142.887954) (xy 251.781056 -142.814294) (xy 251.780975 -142.810085)
			(xy 251.779568 -142.801786) (xy 251.778262 -142.797784) (xy 251.773436 -142.7861) (xy 251.767086 -142.779242)
			(xy 251.747842 -142.757911) (xy 251.71533 -142.710548) (xy 251.690285 -142.658847) (xy 251.673276 -142.603975)
			(xy 251.664685 -142.547172) (xy 251.664708 -142.489724) (xy 251.673344 -142.432929) (xy 251.690397 -142.378071)
			(xy 251.715482 -142.326389) (xy 251.748033 -142.279052) (xy 251.76734 -142.25778) (xy 251.77242 -142.252446)
			(xy 251.77877 -142.239746) (xy 251.781056 -142.227554) (xy 251.781056 -142.153894) (xy 251.780975 -142.149685)
			(xy 251.779568 -142.141386) (xy 251.778262 -142.137384) (xy 251.773436 -142.1257) (xy 251.767086 -142.118842)
			(xy 251.747842 -142.097511) (xy 251.71533 -142.050148) (xy 251.690285 -141.998447) (xy 251.673276 -141.943575)
			(xy 251.664685 -141.886772) (xy 251.664708 -141.829324) (xy 251.673344 -141.772529) (xy 251.690397 -141.717671)
			(xy 251.715482 -141.665989) (xy 251.748033 -141.618652) (xy 251.76734 -141.59738) (xy 251.77242 -141.592046)
			(xy 251.77877 -141.579346) (xy 251.781056 -141.567154) (xy 251.781056 -141.493494) (xy 251.780975 -141.489285)
			(xy 251.779568 -141.480986) (xy 251.778262 -141.476984) (xy 251.773436 -141.4653) (xy 251.767086 -141.458442)
			(xy 251.747842 -141.437111) (xy 251.71533 -141.389748) (xy 251.690285 -141.338047) (xy 251.673276 -141.283175)
			(xy 251.664685 -141.226372) (xy 251.664708 -141.168924) (xy 251.673344 -141.112129) (xy 251.690397 -141.057271)
			(xy 251.715482 -141.005589) (xy 251.748033 -140.958252) (xy 251.76734 -140.93698) (xy 251.77242 -140.931646)
			(xy 251.77877 -140.918946) (xy 251.781056 -140.906754) (xy 251.781056 -140.833348) (xy 251.780938 -140.828252)
			(xy 251.778881 -140.818271) (xy 251.776992 -140.813536) (xy 251.773436 -140.804646) (xy 251.767086 -140.798042)
			(xy 251.74786 -140.776724) (xy 251.715376 -140.729393) (xy 251.690352 -140.677729) (xy 251.673351 -140.622899)
			(xy 251.664759 -140.566141) (xy 251.664216 -140.537438) (xy 251.664293 -140.5247) (xy 251.665944 -140.499278)
			(xy 251.667518 -140.486638) (xy 251.671921 -140.457946) (xy 251.688267 -140.402249) (xy 251.712845 -140.349663)
			(xy 251.74509 -140.301397) (xy 251.764292 -140.279628) (xy 251.770496 -140.272217) (xy 251.777337 -140.254157)
			(xy 251.777032 -140.234848) (xy 251.77369 -140.22578) (xy 251.552456 -139.691618) (xy 251.547609 -139.681203)
			(xy 251.530535 -139.665867) (xy 251.508488 -139.659493) (xy 251.497084 -139.660884) (xy 251.49683 -139.660884)
			(xy 251.480764 -139.663489) (xy 251.448335 -139.666287) (xy 251.43206 -139.666472) (xy 251.431552 -139.666472)
			(xy 251.404183 -139.665997) (xy 251.350009 -139.658166) (xy 251.29751 -139.642673) (xy 251.247764 -139.619835)
			(xy 251.201794 -139.590122) (xy 251.180854 -139.572492) (xy 251.1806 -139.572492) (xy 251.1806 -139.572238)
			(xy 251.173515 -139.566649) (xy 251.156597 -139.560403) (xy 251.14758 -139.560046) (xy 251.080524 -139.560046)
			(xy 251.071505 -139.5604) (xy 251.05458 -139.566636) (xy 251.047504 -139.572238) (xy 251.04725 -139.572492)
			(xy 251.026317 -139.590133) (xy 250.980349 -139.619857) (xy 250.930603 -139.642703) (xy 250.878101 -139.658199)
			(xy 250.823923 -139.666028) (xy 250.769181 -139.666028) (xy 250.715003 -139.658199) (xy 250.662501 -139.642703)
			(xy 250.612755 -139.619857) (xy 250.566787 -139.590133) (xy 250.545854 -139.572492) (xy 250.5456 -139.572492)
			(xy 250.5456 -139.572238) (xy 250.538515 -139.566649) (xy 250.521597 -139.560403) (xy 250.51258 -139.560046)
			(xy 250.445524 -139.560046) (xy 250.436505 -139.5604) (xy 250.41958 -139.566636) (xy 250.412504 -139.572238)
			(xy 250.41225 -139.572492) (xy 250.391317 -139.590133) (xy 250.345349 -139.619857) (xy 250.295603 -139.642703)
			(xy 250.243101 -139.658199) (xy 250.188923 -139.666028) (xy 250.134181 -139.666028) (xy 250.080003 -139.658199)
			(xy 250.027501 -139.642703) (xy 249.977755 -139.619857) (xy 249.931787 -139.590133) (xy 249.910854 -139.572492)
			(xy 249.9106 -139.572492) (xy 249.9106 -139.572238) (xy 249.903515 -139.566649) (xy 249.886597 -139.560403)
			(xy 249.87758 -139.560046) (xy 249.810524 -139.560046) (xy 249.801505 -139.5604) (xy 249.78458 -139.566636)
			(xy 249.777504 -139.572238) (xy 249.77725 -139.572492) (xy 249.756318 -139.590132) (xy 249.71035 -139.619852)
			(xy 249.660603 -139.642689) (xy 249.6081 -139.658173) (xy 249.553922 -139.665985) (xy 249.526552 -139.666472)
			(xy 249.499304 -139.665982) (xy 249.445363 -139.65822) (xy 249.393077 -139.642861) (xy 249.343508 -139.620216)
			(xy 249.297666 -139.590748) (xy 249.256484 -139.555056) (xy 249.220802 -139.513867) (xy 249.191344 -139.468018)
			(xy 249.16871 -139.418445) (xy 249.153362 -139.366154) (xy 249.145612 -139.312212) (xy 249.145044 -139.284964)
			(xy 249.145558 -139.25635) (xy 249.154112 -139.199766) (xy 249.171023 -139.145094) (xy 249.195911 -139.093562)
			(xy 249.228218 -139.046326) (xy 249.267219 -139.004446) (xy 249.289316 -138.98626) (xy 249.28957 -138.986006)
			(xy 249.298081 -138.978373) (xy 249.307971 -138.957796) (xy 249.30862 -138.946382) (xy 249.308112 -138.866372)
			(xy 249.307498 -138.854814) (xy 249.297318 -138.834053) (xy 249.288554 -138.826494) (xy 249.266115 -138.808301)
			(xy 249.226462 -138.766296) (xy 249.193593 -138.718795) (xy 249.168258 -138.666882) (xy 249.151036 -138.611744)
			(xy 249.142321 -138.55464) (xy 249.141742 -138.525758) (xy 249.142217 -138.498389) (xy 249.150047 -138.444215)
			(xy 249.16554 -138.391715) (xy 249.188378 -138.34197) (xy 249.218092 -138.295999) (xy 249.235722 -138.27506)
			(xy 249.235722 -138.274806) (xy 249.235976 -138.274806) (xy 249.241564 -138.26772) (xy 249.247811 -138.250803)
			(xy 249.248168 -138.241786) (xy 249.248168 -138.17473) (xy 249.247815 -138.165711) (xy 249.241582 -138.148783)
			(xy 249.235976 -138.14171) (xy 249.235722 -138.141456) (xy 249.218085 -138.120523) (xy 249.188366 -138.074556)
			(xy 249.165527 -138.024812) (xy 249.150036 -137.972312) (xy 249.142213 -137.918137) (xy 249.142217 -137.8634)
			(xy 249.15005 -137.809226) (xy 249.165549 -137.756729) (xy 249.188397 -137.706988) (xy 249.218123 -137.661026)
			(xy 249.235722 -137.64006) (xy 249.235722 -137.639806) (xy 249.235976 -137.639806) (xy 249.241564 -137.63272)
			(xy 249.247811 -137.615803) (xy 249.248168 -137.606786) (xy 249.248168 -137.53973) (xy 249.247815 -137.530711)
			(xy 249.241582 -137.513783) (xy 249.235976 -137.50671) (xy 249.235722 -137.506456) (xy 249.218085 -137.485523)
			(xy 249.188366 -137.439556) (xy 249.165527 -137.389812) (xy 249.150036 -137.337312) (xy 249.142213 -137.283137)
			(xy 249.142217 -137.2284) (xy 249.15005 -137.174226) (xy 249.165549 -137.121729) (xy 249.188397 -137.071988)
			(xy 249.218123 -137.026026) (xy 249.235722 -137.00506) (xy 249.235722 -137.004806) (xy 249.235976 -137.004806)
			(xy 249.241564 -136.99772) (xy 249.247811 -136.980803) (xy 249.248168 -136.971786) (xy 249.248168 -136.90473)
			(xy 249.247815 -136.895711) (xy 249.241582 -136.878783) (xy 249.235976 -136.87171) (xy 249.235722 -136.871456)
			(xy 249.218082 -136.850524) (xy 249.188359 -136.804557) (xy 249.16552 -136.75481) (xy 249.150035 -136.702307)
			(xy 249.142222 -136.648128) (xy 249.141742 -136.620758) (xy 249.142228 -136.593507) (xy 249.149984 -136.539559)
			(xy 249.165339 -136.487264) (xy 249.187981 -136.437687) (xy 249.217447 -136.391837) (xy 249.253138 -136.350646)
			(xy 249.294329 -136.314955) (xy 249.340179 -136.285489) (xy 249.389756 -136.262847) (xy 249.442051 -136.247492)
			(xy 249.495999 -136.239736) (xy 249.550501 -136.239736) (xy 249.604449 -136.247492) (xy 249.656744 -136.262847)
			(xy 249.706321 -136.285489) (xy 249.752171 -136.314955) (xy 249.793362 -136.350646) (xy 249.829053 -136.391837)
			(xy 249.858519 -136.437687) (xy 249.881161 -136.487264) (xy 249.896516 -136.539559) (xy 249.904272 -136.593507)
			(xy 249.904758 -136.620758) (xy 249.904282 -136.648126) (xy 249.89645 -136.7023) (xy 249.880955 -136.754798)
			(xy 249.858116 -136.804542) (xy 249.828401 -136.850511) (xy 249.810778 -136.871456) (xy 249.810778 -136.87171)
			(xy 249.810524 -136.87171) (xy 249.804938 -136.878796) (xy 249.798697 -136.895714) (xy 249.798332 -136.90473)
			(xy 249.798332 -136.971786) (xy 249.798688 -136.980804) (xy 249.804925 -136.997728) (xy 249.810524 -137.004806)
			(xy 249.810778 -137.00506) (xy 249.828421 -137.025993) (xy 249.858152 -137.071962) (xy 249.881003 -137.12171)
			(xy 249.896504 -137.174214) (xy 249.904338 -137.228396) (xy 249.904342 -137.283141) (xy 249.896518 -137.337324)
			(xy 249.881025 -137.389831) (xy 249.858182 -137.439583) (xy 249.82846 -137.485556) (xy 249.810778 -137.506456)
			(xy 249.810778 -137.50671) (xy 249.810524 -137.50671) (xy 249.804938 -137.513796) (xy 249.798697 -137.530714)
			(xy 249.798332 -137.53973) (xy 249.798332 -137.606786) (xy 249.798688 -137.615804) (xy 249.804925 -137.632728)
			(xy 249.810524 -137.639806) (xy 249.810778 -137.64006) (xy 249.828421 -137.660993) (xy 249.858152 -137.706962)
			(xy 249.881003 -137.75671) (xy 249.896504 -137.809214) (xy 249.904338 -137.863396) (xy 249.904342 -137.918141)
			(xy 249.896518 -137.972324) (xy 249.881025 -138.024831) (xy 249.858182 -138.074583) (xy 249.82846 -138.120556)
			(xy 249.810778 -138.141456) (xy 249.810778 -138.14171) (xy 249.810524 -138.14171) (xy 249.804938 -138.148796)
			(xy 249.798697 -138.165714) (xy 249.798332 -138.17473) (xy 249.798332 -138.241786) (xy 249.798688 -138.250804)
			(xy 249.804925 -138.267728) (xy 249.810524 -138.274806) (xy 249.810778 -138.27506) (xy 249.828418 -138.295992)
			(xy 249.858138 -138.341959) (xy 249.880975 -138.391707) (xy 249.896458 -138.44421) (xy 249.904268 -138.498389)
			(xy 249.904758 -138.525758) (xy 249.904242 -138.554371) (xy 249.895685 -138.610954) (xy 249.878772 -138.665623)
			(xy 249.853882 -138.717153) (xy 249.821574 -138.764387) (xy 249.782573 -138.806265) (xy 249.760486 -138.824462)
			(xy 249.760232 -138.824716) (xy 249.751724 -138.83235) (xy 249.741843 -138.852927) (xy 249.741182 -138.86434)
			(xy 249.74169 -138.94435) (xy 249.742308 -138.955905) (xy 249.752494 -138.976659) (xy 249.761248 -138.984228)
			(xy 249.77725 -138.997436) (xy 249.777504 -138.997436) (xy 249.777504 -138.99769) (xy 249.784591 -139.003275)
			(xy 249.801508 -139.009517) (xy 249.810524 -139.009882) (xy 249.87758 -139.009882) (xy 249.886597 -139.009526)
			(xy 249.903517 -139.003282) (xy 249.9106 -138.99769) (xy 249.910854 -138.997436) (xy 249.931787 -138.979795)
			(xy 249.977755 -138.950071) (xy 250.027501 -138.927225) (xy 250.080003 -138.911729) (xy 250.134181 -138.9039)
			(xy 250.188923 -138.9039) (xy 250.243101 -138.911729) (xy 250.295603 -138.927225) (xy 250.345349 -138.950071)
			(xy 250.391317 -138.979795) (xy 250.41225 -138.997436) (xy 250.412504 -138.997436) (xy 250.412504 -138.99769)
			(xy 250.419591 -139.003275) (xy 250.436508 -139.009517) (xy 250.445524 -139.009882) (xy 250.51258 -139.009882)
			(xy 250.521597 -139.009526) (xy 250.538517 -139.003282) (xy 250.5456 -138.99769) (xy 250.545854 -138.997436)
			(xy 250.566787 -138.979795) (xy 250.612755 -138.950071) (xy 250.662501 -138.927225) (xy 250.715003 -138.911729)
			(xy 250.769181 -138.9039) (xy 250.823923 -138.9039) (xy 250.878101 -138.911729) (xy 250.930603 -138.927225)
			(xy 250.980349 -138.950071) (xy 251.026317 -138.979795) (xy 251.04725 -138.997436) (xy 251.047504 -138.997436)
			(xy 251.047504 -138.99769) (xy 251.054591 -139.003275) (xy 251.071508 -139.009517) (xy 251.080524 -139.009882)
			(xy 251.14758 -139.009882) (xy 251.156597 -139.009526) (xy 251.173517 -139.003282) (xy 251.1806 -138.99769)
			(xy 251.180854 -138.997436) (xy 251.200684 -138.980696) (xy 251.244039 -138.952175) (xy 251.290863 -138.9298)
			(xy 251.340289 -138.913985) (xy 251.365766 -138.909044) (xy 251.3838 -138.905996) (xy 251.407676 -138.877802)
			(xy 251.407676 -132.384292) (xy 251.407097 -132.372628) (xy 251.396808 -132.351692) (xy 251.378343 -132.337437)
			(xy 251.367036 -132.334508) (xy 251.340212 -132.328514) (xy 251.288514 -132.309851) (xy 251.24003 -132.283961)
			(xy 251.195765 -132.251379) (xy 251.156636 -132.21278) (xy 251.123452 -132.168965) (xy 251.096902 -132.120839)
			(xy 251.077535 -132.069401) (xy 251.065752 -132.015716) (xy 251.061797 -131.960895) (xy 251.065753 -131.906074)
			(xy 251.077538 -131.852389) (xy 251.096906 -131.800951) (xy 251.123458 -131.752827) (xy 251.156643 -131.709012)
			(xy 251.195773 -131.670414) (xy 251.240039 -131.637834) (xy 251.288523 -131.611945) (xy 251.340222 -131.593284)
			(xy 251.367036 -131.58724) (xy 251.378353 -131.584343) (xy 251.396817 -131.570075) (xy 251.407093 -131.549124)
			(xy 251.407676 -131.537456) (xy 251.407676 -130.71475) (xy 251.408314 -130.66577) (xy 251.417988 -130.568288)
			(xy 251.437169 -130.472223) (xy 251.450856 -130.42519) (xy 256.77622 -112.870488) (xy 256.778883 -112.860062)
			(xy 256.776117 -112.838744) (xy 256.770886 -112.82934) (xy 256.770886 -112.829086) (xy 256.757462 -112.806414)
			(xy 256.736288 -112.758167) (xy 256.721943 -112.707468) (xy 256.7147 -112.655279) (xy 256.714244 -112.628934)
			(xy 256.714728 -112.601374) (xy 256.72266 -112.546827) (xy 256.738366 -112.493991) (xy 256.761516 -112.443968)
			(xy 256.791628 -112.3978) (xy 256.828076 -112.356449) (xy 256.870098 -112.320778) (xy 256.916819 -112.29153)
			(xy 256.941828 -112.279938) (xy 256.942844 -112.27943) (xy 256.946908 -112.277398) (xy 256.960878 -112.261396)
			(xy 257.36804 -110.920022) (xy 257.375239 -110.896631) (xy 257.391629 -110.850509) (xy 257.400806 -110.82782)
			(xy 259.39877 -106.004868) (xy 259.399532 -106.001312) (xy 259.410888 -105.957705) (xy 259.440432 -105.872569)
			(xy 259.477539 -105.790447) (xy 259.521907 -105.712009) (xy 259.573174 -105.637896) (xy 259.63092 -105.568713)
			(xy 259.662422 -105.536492) (xy 264.307574 -100.891086) (xy 264.314421 -100.883688) (xy 264.322154 -100.86509)
			(xy 264.32256 -100.855018) (xy 264.32256 -100.854764) (xy 264.322991 -100.844698) (xy 264.330722 -100.826109)
			(xy 264.337546 -100.818696) (xy 265.252454 -99.903788) (xy 265.291662 -99.865754) (xy 265.377078 -99.797652)
			(xy 265.422888 -99.767898) (xy 265.423396 -99.76739) (xy 265.428222 -99.764596) (xy 265.42873 -99.764088)
			(xy 265.430254 -99.763326) (xy 265.46683 -99.741482) (xy 265.467084 -99.741482) (xy 265.47826 -99.735386)
			(xy 265.481308 -99.733862) (xy 265.48207 -99.733608) (xy 265.504126 -99.721882) (xy 265.549232 -99.700408)
			(xy 265.57224 -99.690682) (xy 267.974826 -98.695764) (xy 268.011376 -98.681063) (xy 268.086347 -98.656841)
			(xy 268.163009 -98.638663) (xy 268.240874 -98.626645) (xy 268.280134 -98.623374) (xy 268.285214 -98.622612)
			(xy 268.327487 -98.615732) (xy 268.412822 -98.608352) (xy 268.455648 -98.60788) (xy 269.243302 -98.60788)
			(xy 269.253024 -98.607398) (xy 269.271049 -98.600089) (xy 269.278354 -98.593656) (xy 269.309222 -98.564737)
			(xy 269.375072 -98.511639) (xy 269.445182 -98.464307) (xy 269.519047 -98.42308) (xy 269.596137 -98.388255)
			(xy 269.675898 -98.360081) (xy 269.757759 -98.338762) (xy 269.841131 -98.324449) (xy 269.925415 -98.317246)
			(xy 269.96771 -98.316796) (xy 270.014394 -98.317336) (xy 270.107353 -98.326057) (xy 270.19909 -98.343431)
			(xy 270.2888 -98.369305) (xy 270.375699 -98.403454) (xy 270.459024 -98.445578) (xy 270.538046 -98.495307)
			(xy 270.612072 -98.552207) (xy 270.680454 -98.615778) (xy 270.742594 -98.685464) (xy 270.797945 -98.760655)
			(xy 270.82242 -98.800412) (xy 270.824937 -98.804392) (xy 270.831201 -98.811424) (xy 270.834866 -98.814382)
			(xy 270.857359 -98.832437) (xy 270.897165 -98.874174) (xy 270.930242 -98.921423) (xy 270.955838 -98.973109)
			(xy 270.973369 -99.028056) (xy 270.982439 -99.085015) (xy 270.983202 -99.113848) (xy 270.983202 -99.117404)
			(xy 270.983202 -99.117912) (xy 270.982601 -99.146956) (xy 270.97367 -99.204357) (xy 270.965422 -99.232212)
			(xy 270.964082 -99.23672) (xy 270.962934 -99.246055) (xy 270.963136 -99.250754) (xy 270.96409 -99.266612)
			(xy 270.965107 -99.298368) (xy 270.965168 -99.314254) (xy 270.964735 -99.356622) (xy 270.957552 -99.441052)
			(xy 270.943224 -99.524568) (xy 270.921857 -99.606565) (xy 270.893603 -99.686452) (xy 270.876522 -99.725226)
			(xy 270.872533 -99.735266) (xy 270.872516 -99.756851) (xy 270.876522 -99.766882) (xy 270.893567 -99.805671)
			(xy 270.921806 -99.885559) (xy 270.943172 -99.967553) (xy 270.957513 -100.051063) (xy 270.964723 -100.135488)
			(xy 270.965168 -100.177854) (xy 270.9651 -100.19374) (xy 270.964084 -100.225496) (xy 270.963136 -100.241354)
			(xy 270.962889 -100.246042) (xy 270.963902 -100.255375) (xy 270.965168 -100.259896) (xy 270.965422 -100.26015)
			(xy 270.965422 -100.260658) (xy 270.970362 -100.276669) (xy 270.977742 -100.309355) (xy 270.980154 -100.325936)
			(xy 270.980154 -100.326952) (xy 270.981932 -100.340922) (xy 270.982186 -100.3427) (xy 270.98244 -100.345748)
			(xy 270.983202 -100.365306) (xy 270.983202 -100.377752) (xy 270.982496 -100.406628) (xy 270.973454 -100.463674)
			(xy 270.955931 -100.518711) (xy 270.930327 -100.570484) (xy 270.897225 -100.617815) (xy 270.857377 -100.659627)
			(xy 270.834866 -100.677726) (xy 270.831203 -100.680686) (xy 270.824939 -100.687717) (xy 270.82242 -100.691696)
			(xy 270.797906 -100.731424) (xy 270.742544 -100.806597) (xy 270.680399 -100.876267) (xy 270.612014 -100.939824)
			(xy 270.53799 -100.996712) (xy 270.458973 -101.046434) (xy 270.375655 -101.088553) (xy 270.288766 -101.122702)
			(xy 270.199065 -101.148581) (xy 270.107339 -101.165964) (xy 270.014389 -101.174699) (xy 269.96771 -101.175312)
			(xy 269.925399 -101.174864) (xy 269.841082 -101.167695) (xy 269.757675 -101.153406) (xy 269.67578 -101.132102)
			(xy 269.595984 -101.103935) (xy 269.518861 -101.069107) (xy 269.444967 -101.02787) (xy 269.374834 -100.980519)
			(xy 269.308964 -100.927397) (xy 269.2781 -100.898452) (xy 269.270734 -100.89134) (xy 269.252954 -100.884228)
			(xy 268.981428 -100.884228) (xy 268.974824 -100.89134) (xy 268.972792 -100.89388) (xy 268.965934 -100.902516)
			(xy 268.9606 -100.911152) (xy 268.950948 -100.932996) (xy 268.95044 -100.942394) (xy 268.947392 -100.974652)
			(xy 268.945868 -100.984558) (xy 268.943534 -100.998535) (xy 268.937049 -101.026122) (xy 268.932914 -101.039676)
			(xy 268.931561 -101.044182) (xy 268.930404 -101.053519) (xy 268.930628 -101.058218) (xy 268.93266 -101.120702)
			(xy 268.932225 -101.163069) (xy 268.925038 -101.247499) (xy 268.910707 -101.331013) (xy 268.889335 -101.413008)
			(xy 268.861078 -101.492893) (xy 268.844014 -101.531674) (xy 268.840031 -101.541713) (xy 268.840032 -101.563291)
			(xy 268.844014 -101.57333) (xy 268.861057 -101.612119) (xy 268.889293 -101.692008) (xy 268.910655 -101.774002)
			(xy 268.924992 -101.857512) (xy 268.932198 -101.941936) (xy 268.93266 -101.984302) (xy 268.930628 -102.04704)
			(xy 268.930461 -102.051737) (xy 268.931617 -102.061064) (xy 268.932914 -102.065582) (xy 268.938378 -102.083627)
			(xy 268.946135 -102.120525) (xy 268.948408 -102.139242) (xy 268.94917 -102.146608) (xy 268.94917 -102.146862)
			(xy 268.949932 -102.154482) (xy 268.95806 -102.174802) (xy 268.95949 -102.17814) (xy 268.963186 -102.18439)
			(xy 268.965426 -102.187248) (xy 268.969744 -102.192582) (xy 268.976348 -102.20071) (xy 268.976856 -102.201218)
			(xy 268.981936 -102.207314) (xy 268.982444 -102.207568) (xy 269.243048 -102.207568) (xy 269.252746 -102.207139)
			(xy 269.270764 -102.199956) (xy 269.2781 -102.193598) (xy 269.308957 -102.164696) (xy 269.374785 -102.11163)
			(xy 269.444871 -102.06433) (xy 269.51871 -102.023135) (xy 269.595774 -101.988343) (xy 269.675507 -101.960203)
			(xy 269.757337 -101.938916) (xy 269.840676 -101.924637) (xy 269.924925 -101.917468) (xy 269.967202 -101.916992)
			(xy 269.96771 -101.916992) (xy 270.014402 -101.917536) (xy 270.107378 -101.926264) (xy 270.199131 -101.943643)
			(xy 270.288858 -101.969521) (xy 270.375774 -102.00367) (xy 270.459119 -102.045793) (xy 270.538162 -102.095521)
			(xy 270.612212 -102.152418) (xy 270.680621 -102.215986) (xy 270.742789 -102.285669) (xy 270.798173 -102.360857)
			(xy 270.822674 -102.400608) (xy 270.825189 -102.40459) (xy 270.831449 -102.411627) (xy 270.83512 -102.414578)
			(xy 270.857505 -102.432552) (xy 270.897135 -102.474087) (xy 270.930097 -102.521089) (xy 270.955647 -102.572497)
			(xy 270.973207 -102.627153) (xy 270.982383 -102.683823) (xy 270.983202 -102.71252) (xy 270.983202 -102.721664)
			(xy 270.982388 -102.749939) (xy 270.973463 -102.805796) (xy 270.965422 -102.832916) (xy 270.964082 -102.837425)
			(xy 270.962935 -102.846759) (xy 270.963136 -102.851458) (xy 270.965168 -102.914196) (xy 270.964733 -102.956563)
			(xy 270.957546 -103.040993) (xy 270.943216 -103.124507) (xy 270.921845 -103.206503) (xy 270.893589 -103.286388)
			(xy 270.876522 -103.325168) (xy 270.872543 -103.335208) (xy 270.872541 -103.356785) (xy 270.876522 -103.366824)
			(xy 270.893565 -103.405613) (xy 270.921801 -103.485502) (xy 270.943164 -103.567496) (xy 270.957501 -103.651006)
			(xy 270.964708 -103.73543) (xy 270.965168 -103.777796) (xy 270.965099 -103.793682) (xy 270.964082 -103.825438)
			(xy 270.963136 -103.841296) (xy 270.962892 -103.845984) (xy 270.963914 -103.855314) (xy 270.965168 -103.859838)
			(xy 270.965422 -103.860092) (xy 270.965422 -103.8606) (xy 270.97036 -103.876611) (xy 270.977736 -103.909298)
			(xy 270.980154 -103.925878) (xy 270.980154 -103.926894) (xy 270.981932 -103.940864) (xy 270.982186 -103.942642)
			(xy 270.98244 -103.94569) (xy 270.983202 -103.965248) (xy 270.983202 -103.977694) (xy 270.9825 -104.006571)
			(xy 270.973466 -104.063623) (xy 270.955949 -104.118665) (xy 270.93035 -104.170445) (xy 270.89725 -104.217783)
			(xy 270.857404 -104.259602) (xy 270.834866 -104.277668) (xy 270.831205 -104.280629) (xy 270.824946 -104.287664)
			(xy 270.82242 -104.291638) (xy 270.797896 -104.331352) (xy 270.742515 -104.406495) (xy 270.680357 -104.476136)
			(xy 270.611965 -104.539665) (xy 270.537937 -104.596527) (xy 270.45892 -104.646226) (xy 270.375607 -104.688325)
			(xy 270.288725 -104.722457) (xy 270.199034 -104.748323) (xy 270.10732 -104.765698) (xy 270.014383 -104.774428)
			(xy 269.96771 -104.775) (xy 269.967456 -104.775) (xy 269.923511 -104.774522) (xy 269.835963 -104.766789)
			(xy 269.749435 -104.751378) (xy 269.6646 -104.728409) (xy 269.582117 -104.698059) (xy 269.502626 -104.660566)
			(xy 269.426745 -104.616219) (xy 269.355063 -104.565364) (xy 269.32128 -104.537256) (xy 269.314049 -104.531573)
			(xy 269.29677 -104.525317) (xy 269.278396 -104.525579) (xy 269.269718 -104.52862) (xy 269.225887 -104.545404)
			(xy 269.13576 -104.571622) (xy 269.043568 -104.589256) (xy 268.950127 -104.59815) (xy 268.903196 -104.598724)
			(xy 268.420596 -104.598724) (xy 268.415262 -104.59847) (xy 268.410436 -104.59847) (xy 268.401557 -104.599716)
			(xy 268.385428 -104.607522) (xy 268.37894 -104.61371) (xy 268.35608 -104.637332) (xy 268.32687 -104.667558)
			(xy 268.322044 -104.673654) (xy 268.322552 -104.693466) (xy 268.322552 -104.693974) (xy 268.32306 -104.720644)
			(xy 268.32306 -104.721152) (xy 268.322615 -104.763494) (xy 268.315416 -104.847871) (xy 268.301081 -104.931333)
			(xy 268.279714 -105.013277) (xy 268.25147 -105.093113) (xy 268.234414 -105.13187) (xy 268.23043 -105.141909)
			(xy 268.230429 -105.163487) (xy 268.234414 -105.173526) (xy 268.251458 -105.212315) (xy 268.279693 -105.292204)
			(xy 268.301056 -105.374198) (xy 268.315393 -105.457708) (xy 268.3226 -105.542132) (xy 268.32306 -105.584498)
			(xy 268.321028 -105.646982) (xy 268.320856 -105.65168) (xy 268.322002 -105.66101) (xy 268.323314 -105.665524)
			(xy 268.327332 -105.678709) (xy 268.33369 -105.705532) (xy 268.336014 -105.719118) (xy 268.33957 -105.74655)
			(xy 268.33957 -105.746804) (xy 268.340332 -105.754678) (xy 268.353032 -105.784904) (xy 268.359636 -105.792524)
			(xy 268.369034 -105.803192) (xy 268.373606 -105.807764) (xy 269.243302 -105.807764) (xy 269.253024 -105.807281)
			(xy 269.271047 -105.79997) (xy 269.278354 -105.79354) (xy 269.309221 -105.764619) (xy 269.37507 -105.711517)
			(xy 269.445178 -105.664181) (xy 269.519042 -105.62295) (xy 269.596132 -105.588122) (xy 269.675895 -105.559946)
			(xy 269.757756 -105.538624) (xy 269.841129 -105.52431) (xy 269.925414 -105.517107) (xy 269.96771 -105.51668)
			(xy 270.014394 -105.51722) (xy 270.107353 -105.525941) (xy 270.19909 -105.543315) (xy 270.288801 -105.569189)
			(xy 270.3757 -105.603337) (xy 270.459026 -105.64546) (xy 270.538048 -105.695189) (xy 270.612075 -105.752088)
			(xy 270.680458 -105.815659) (xy 270.742599 -105.885345) (xy 270.797952 -105.960535) (xy 270.82242 -106.000296)
			(xy 270.824936 -106.004277) (xy 270.831199 -106.011311) (xy 270.834866 -106.014266) (xy 270.85736 -106.032321)
			(xy 270.897168 -106.074058) (xy 270.930247 -106.121306) (xy 270.955844 -106.172992) (xy 270.973378 -106.227939)
			(xy 270.98245 -106.284898) (xy 270.983202 -106.313732) (xy 270.983202 -106.317288) (xy 270.983202 -106.317796)
			(xy 270.982602 -106.346841) (xy 270.973674 -106.404242) (xy 270.965422 -106.432096) (xy 270.96408 -106.436604)
			(xy 270.962929 -106.445939) (xy 270.963136 -106.450638) (xy 270.964091 -106.466496) (xy 270.965108 -106.498252)
			(xy 270.965168 -106.514138) (xy 270.964731 -106.556505) (xy 270.957541 -106.640934) (xy 270.943207 -106.724446)
			(xy 270.921834 -106.806441) (xy 270.893574 -106.886323) (xy 270.876522 -106.92511) (xy 270.872551 -106.935149)
			(xy 270.872566 -106.956719) (xy 270.876522 -106.966766) (xy 270.893564 -107.005555) (xy 270.921796 -107.085444)
			(xy 270.943156 -107.167439) (xy 270.957489 -107.250949) (xy 270.964692 -107.335373) (xy 270.965168 -107.377738)
			(xy 270.9651 -107.393624) (xy 270.964085 -107.42538) (xy 270.963136 -107.441238) (xy 270.962896 -107.445925)
			(xy 270.963925 -107.455254) (xy 270.965168 -107.45978) (xy 270.965422 -107.460034) (xy 270.965422 -107.460542)
			(xy 270.970362 -107.476553) (xy 270.977744 -107.509239) (xy 270.980154 -107.52582) (xy 270.980154 -107.526836)
			(xy 270.981932 -107.540806) (xy 270.982186 -107.542584) (xy 270.98244 -107.545632) (xy 270.983202 -107.56519)
			(xy 270.983202 -107.577636) (xy 270.982497 -107.606512) (xy 270.973457 -107.66356) (xy 270.955936 -107.718598)
			(xy 270.930334 -107.770373) (xy 270.897232 -107.817707) (xy 270.857385 -107.85952) (xy 270.834866 -107.87761)
			(xy 270.831202 -107.880569) (xy 270.824937 -107.887599) (xy 270.82242 -107.89158) (xy 270.797907 -107.931309)
			(xy 270.742545 -108.006483) (xy 270.6804 -108.076153) (xy 270.612016 -108.139712) (xy 270.537992 -108.196601)
			(xy 270.458975 -108.246323) (xy 270.375657 -108.288443) (xy 270.288767 -108.322593) (xy 270.199066 -108.348472)
			(xy 270.10734 -108.365856) (xy 270.01439 -108.374591) (xy 269.96771 -108.375196) (xy 269.923926 -108.374718)
			(xy 269.836697 -108.367028) (xy 269.750479 -108.351715) (xy 269.665937 -108.328897) (xy 269.583722 -108.29875)
			(xy 269.504469 -108.261507) (xy 269.428789 -108.217454) (xy 269.357266 -108.166932) (xy 269.323566 -108.138976)
			(xy 269.30985 -108.137452) (xy 269.301722 -108.137452) (xy 269.296896 -108.138976) (xy 269.256286 -108.153232)
			(xy 269.173136 -108.175478) (xy 269.088367 -108.190414) (xy 269.002621 -108.197927) (xy 268.959584 -108.198412)
			(xy 268.516608 -108.198412) (xy 268.51483 -108.198412) (xy 268.398244 -108.198412) (xy 268.393418 -108.199936)
			(xy 268.32179 -108.267246) (xy 268.321536 -108.267754) (xy 268.32306 -108.32084) (xy 268.322623 -108.363207)
			(xy 268.315433 -108.447635) (xy 268.301099 -108.531148) (xy 268.279725 -108.613142) (xy 268.251465 -108.693025)
			(xy 268.234414 -108.731812) (xy 268.230439 -108.74185) (xy 268.230454 -108.763422) (xy 268.234414 -108.773468)
			(xy 268.251456 -108.812257) (xy 268.279688 -108.892146) (xy 268.301048 -108.974141) (xy 268.315381 -109.057651)
			(xy 268.322584 -109.142075) (xy 268.32306 -109.18444) (xy 268.321028 -109.246924) (xy 268.32086 -109.251621)
			(xy 268.322013 -109.260949) (xy 268.323314 -109.265466) (xy 268.328778 -109.283511) (xy 268.336537 -109.320409)
			(xy 268.338808 -109.339126) (xy 268.338808 -109.341158) (xy 268.339316 -109.34446) (xy 268.339824 -109.349286)
			(xy 268.339824 -109.35081) (xy 268.340078 -109.352842) (xy 268.340078 -109.355128) (xy 268.340332 -109.357668)
			(xy 268.340332 -109.358176) (xy 268.341572 -109.365196) (xy 268.347377 -109.378209) (xy 268.351762 -109.38383)
			(xy 268.356842 -109.389672) (xy 268.35735 -109.39018) (xy 268.36878 -109.403134) (xy 268.37005 -109.404404)
			(xy 268.373098 -109.40796) (xy 269.243302 -109.40796) (xy 269.253024 -109.407477) (xy 269.271046 -109.400166)
			(xy 269.278354 -109.393736) (xy 269.309221 -109.364815) (xy 269.37507 -109.311713) (xy 269.445178 -109.264377)
			(xy 269.519043 -109.223147) (xy 269.596133 -109.188319) (xy 269.675895 -109.160143) (xy 269.757756 -109.138821)
			(xy 269.841129 -109.124507) (xy 269.925414 -109.117304) (xy 269.96771 -109.116876) (xy 270.014394 -109.117416)
			(xy 270.107353 -109.126137) (xy 270.19909 -109.143511) (xy 270.288801 -109.169385) (xy 270.3757 -109.203533)
			(xy 270.459026 -109.245656) (xy 270.538049 -109.295385) (xy 270.612076 -109.352284) (xy 270.680459 -109.415855)
			(xy 270.7426 -109.48554) (xy 270.797953 -109.56073) (xy 270.82242 -109.600492) (xy 270.824936 -109.604474)
			(xy 270.831198 -109.611508) (xy 270.834866 -109.614462) (xy 270.85736 -109.632517) (xy 270.897168 -109.674253)
			(xy 270.930248 -109.721502) (xy 270.955846 -109.773187) (xy 270.97338 -109.828135) (xy 270.982453 -109.885094)
			(xy 270.983202 -109.913928) (xy 270.983202 -109.917484) (xy 270.983202 -109.917992) (xy 270.982602 -109.947037)
			(xy 270.973675 -110.004438) (xy 270.965422 -110.032292) (xy 270.96408 -110.0368) (xy 270.962928 -110.046135)
			(xy 270.963136 -110.050834) (xy 270.964091 -110.066692) (xy 270.965108 -110.098448) (xy 270.965168 -110.114334)
			(xy 270.964732 -110.156701) (xy 270.957542 -110.24113) (xy 270.943208 -110.324643) (xy 270.921835 -110.406637)
			(xy 270.893576 -110.48652) (xy 270.876522 -110.525306) (xy 270.87255 -110.535345) (xy 270.872564 -110.556916)
			(xy 270.876522 -110.566962) (xy 270.893564 -110.605751) (xy 270.921797 -110.68564) (xy 270.943156 -110.767635)
			(xy 270.95749 -110.851145) (xy 270.964694 -110.935569) (xy 270.965168 -110.977934) (xy 270.9651 -110.99382)
			(xy 270.964085 -111.025576) (xy 270.963136 -111.041434) (xy 270.962896 -111.046122) (xy 270.963924 -111.05545)
			(xy 270.965168 -111.059976) (xy 270.965422 -111.06023) (xy 270.965422 -111.060738) (xy 270.970358 -111.07675)
			(xy 270.977732 -111.109437) (xy 270.980154 -111.126016) (xy 270.980154 -111.127032) (xy 270.981932 -111.141002)
			(xy 270.982186 -111.14278) (xy 270.98244 -111.145828) (xy 270.983202 -111.165386) (xy 270.983202 -111.177832)
			(xy 270.982497 -111.206708) (xy 270.973458 -111.263756) (xy 270.955938 -111.318795) (xy 270.930335 -111.370571)
			(xy 270.897233 -111.417904) (xy 270.857386 -111.459718) (xy 270.834866 -111.477806) (xy 270.831202 -111.480765)
			(xy 270.824936 -111.487795) (xy 270.82242 -111.491776) (xy 270.797907 -111.531505) (xy 270.742545 -111.606679)
			(xy 270.680401 -111.67635) (xy 270.612017 -111.739908) (xy 270.537992 -111.796798) (xy 270.458975 -111.84652)
			(xy 270.375657 -111.888641) (xy 270.288768 -111.92279) (xy 270.199067 -111.94867) (xy 270.10734 -111.966054)
			(xy 270.01439 -111.974789) (xy 269.96771 -111.975392) (xy 269.925495 -111.97494) (xy 269.841367 -111.967784)
			(xy 269.758146 -111.95354) (xy 269.676428 -111.932309) (xy 269.596798 -111.904244) (xy 269.519826 -111.869546)
			(xy 269.446065 -111.828463) (xy 269.376041 -111.78129) (xy 269.34287 -111.755174) (xy 269.336038 -111.750108)
			(xy 269.320014 -111.744434) (xy 269.303016 -111.744361) (xy 269.294864 -111.746792) (xy 269.2565 -111.75924)
			(xy 269.178205 -111.778637) (xy 269.098599 -111.791653) (xy 269.018203 -111.798201) (xy 268.977872 -111.798608)
			(xy 268.494002 -111.798608) (xy 268.454335 -111.798265) (xy 268.375246 -111.792033) (xy 268.336014 -111.786162)
			(xy 268.332458 -111.804958) (xy 268.332458 -111.805466) (xy 268.323314 -111.839502) (xy 268.321952 -111.844071)
			(xy 268.320801 -111.853535) (xy 268.321028 -111.858298) (xy 268.32306 -111.920782) (xy 268.322626 -111.96315)
			(xy 268.31544 -112.047579) (xy 268.301111 -112.131094) (xy 268.279741 -112.21309) (xy 268.251485 -112.292975)
			(xy 268.234414 -112.331754) (xy 268.230427 -112.341793) (xy 268.23042 -112.363374) (xy 268.234414 -112.37341)
			(xy 268.251458 -112.412199) (xy 268.279695 -112.492087) (xy 268.301059 -112.574082) (xy 268.315397 -112.657592)
			(xy 268.322606 -112.742016) (xy 268.32306 -112.784382) (xy 268.322991 -112.800268) (xy 268.321975 -112.832024)
			(xy 268.321028 -112.847882) (xy 268.320783 -112.85257) (xy 268.321803 -112.861901) (xy 268.32306 -112.866424)
			(xy 268.323314 -112.866678) (xy 268.323314 -112.867186) (xy 268.328253 -112.883197) (xy 268.335631 -112.915884)
			(xy 268.338046 -112.932464) (xy 268.338046 -112.93348) (xy 268.339824 -112.94745) (xy 268.340078 -112.949228)
			(xy 268.340332 -112.952276) (xy 268.341094 -112.971834) (xy 268.341094 -112.98428) (xy 268.340393 -113.013158)
			(xy 268.33136 -113.07021) (xy 268.313845 -113.125254) (xy 268.288247 -113.177035) (xy 268.255147 -113.224374)
			(xy 268.215301 -113.266194) (xy 268.192758 -113.284254) (xy 268.189097 -113.287215) (xy 268.182837 -113.294249)
			(xy 268.180312 -113.298224) (xy 268.155801 -113.337957) (xy 268.100444 -113.41314) (xy 268.038302 -113.482821)
			(xy 267.969921 -113.546389) (xy 267.895898 -113.603288) (xy 267.816881 -113.65302) (xy 267.733563 -113.695151)
			(xy 267.646672 -113.72931) (xy 267.556968 -113.755199) (xy 267.465238 -113.772592) (xy 267.372284 -113.781337)
			(xy 267.325602 -113.78184) (xy 267.287238 -113.781439) (xy 267.210742 -113.775466) (xy 267.134931 -113.763632)
			(xy 267.09751 -113.75517) (xy 267.088679 -113.753444) (xy 267.070827 -113.755596) (xy 267.054811 -113.763772)
			(xy 267.042598 -113.776969) (xy 267.038836 -113.785142) (xy 266.85748 -114.223546) (xy 266.840204 -114.264045)
			(xy 266.799501 -114.342126) (xy 266.752068 -114.416312) (xy 266.698276 -114.486024) (xy 266.668758 -114.518694)
			(xy 266.662952 -114.525571) (xy 266.656172 -114.542229) (xy 266.65555 -114.551206) (xy 266.653261 -114.595014)
			(xy 266.641953 -114.682013) (xy 266.623054 -114.767683) (xy 266.596711 -114.851365) (xy 266.580366 -114.892074)
			(xy 266.390882 -115.350036) (xy 266.373607 -115.390535) (xy 266.332904 -115.468617) (xy 266.285472 -115.542803)
			(xy 266.23168 -115.612516) (xy 266.20216 -115.645184) (xy 266.196353 -115.65206) (xy 266.189569 -115.668718)
			(xy 266.188952 -115.677696) (xy 266.186663 -115.721504) (xy 266.175356 -115.808503) (xy 266.156459 -115.894174)
			(xy 266.130116 -115.977856) (xy 266.113768 -116.018564) (xy 265.924284 -116.476526) (xy 265.907006 -116.517023)
			(xy 265.866297 -116.595101) (xy 265.81886 -116.669283) (xy 265.765064 -116.738991) (xy 265.735562 -116.771674)
			(xy 265.729767 -116.778554) (xy 265.723013 -116.795214) (xy 265.722354 -116.804186) (xy 265.720066 -116.847994)
			(xy 265.708759 -116.934993) (xy 265.689863 -117.020665) (xy 265.663521 -117.104347) (xy 265.64717 -117.145054)
			(xy 265.457686 -117.603016) (xy 265.440408 -117.643513) (xy 265.399701 -117.721591) (xy 265.352264 -117.795774)
			(xy 265.298468 -117.865483) (xy 265.268964 -117.898164) (xy 265.263168 -117.905044) (xy 265.25641 -117.921703)
			(xy 265.255756 -117.930676) (xy 265.253468 -117.974484) (xy 265.242163 -118.061484) (xy 265.223267 -118.147155)
			(xy 265.196926 -118.230838) (xy 265.180572 -118.271544) (xy 264.991088 -118.729506) (xy 264.97381 -118.770003)
			(xy 264.933104 -118.848082) (xy 264.885668 -118.922265) (xy 264.831873 -118.991975) (xy 264.802366 -119.024654)
			(xy 264.796568 -119.031533) (xy 264.789807 -119.048192) (xy 264.789158 -119.057166) (xy 264.78687 -119.100974)
			(xy 264.775566 -119.187974) (xy 264.756671 -119.273646) (xy 264.730331 -119.35733) (xy 264.713974 -119.398034)
			(xy 264.622026 -119.620284) (xy 264.618112 -119.631304) (xy 264.61968 -119.654611) (xy 264.631409 -119.674814)
			(xy 264.640822 -119.681752) (xy 264.656062 -119.692166) (xy 264.691876 -119.68861) (xy 265.560556 -118.81993)
			(xy 265.599319 -118.782184) (xy 265.683709 -118.714466) (xy 265.728958 -118.684802) (xy 265.729974 -118.684294)
			(xy 265.764979 -118.661586) (xy 265.838122 -118.621416) (xy 265.914364 -118.587497) (xy 265.993174 -118.560067)
			(xy 266.074001 -118.539318) (xy 266.156278 -118.525394) (xy 266.239431 -118.518393) (xy 266.281154 -118.517924)
			(xy 266.601194 -118.517924) (xy 266.610916 -118.517442) (xy 266.628937 -118.510129) (xy 266.636246 -118.5037)
			(xy 266.667114 -118.474783) (xy 266.732966 -118.421689) (xy 266.803076 -118.374361) (xy 266.876941 -118.333139)
			(xy 266.954032 -118.29832) (xy 267.033794 -118.270152) (xy 267.115654 -118.248839) (xy 267.199025 -118.234533)
			(xy 267.283308 -118.227337) (xy 267.325602 -118.22684) (xy 267.372286 -118.22738) (xy 267.465244 -118.2361)
			(xy 267.556981 -118.253474) (xy 267.646691 -118.279349) (xy 267.733589 -118.313498) (xy 267.816913 -118.355622)
			(xy 267.895934 -118.405353) (xy 267.969959 -118.462253) (xy 268.03834 -118.525826) (xy 268.100477 -118.595514)
			(xy 268.155826 -118.670706) (xy 268.180312 -118.710456) (xy 268.182832 -118.714434) (xy 268.189098 -118.721462)
			(xy 268.192758 -118.724426) (xy 268.215254 -118.74248) (xy 268.255067 -118.784215) (xy 268.288152 -118.831463)
			(xy 268.313755 -118.883148) (xy 268.331296 -118.938096) (xy 268.340373 -118.995057) (xy 268.341094 -119.023892)
			(xy 268.341094 -119.027448) (xy 268.341094 -119.027956) (xy 268.340497 -119.057001) (xy 268.331574 -119.114404)
			(xy 268.323314 -119.142256) (xy 268.321959 -119.146762) (xy 268.320798 -119.156099) (xy 268.321028 -119.160798)
			(xy 268.321982 -119.176656) (xy 268.322997 -119.208412) (xy 268.32306 -119.224298) (xy 268.322625 -119.266665)
			(xy 268.315438 -119.351095) (xy 268.301107 -119.434609) (xy 268.279736 -119.516605) (xy 268.25148 -119.596489)
			(xy 268.234414 -119.63527) (xy 268.23043 -119.645309) (xy 268.230429 -119.666887) (xy 268.234414 -119.676926)
			(xy 268.251458 -119.715715) (xy 268.279693 -119.795604) (xy 268.301056 -119.877598) (xy 268.315393 -119.961108)
			(xy 268.3226 -120.045532) (xy 268.32306 -120.087898) (xy 268.321028 -120.15089) (xy 268.320857 -120.155588)
			(xy 268.322004 -120.164917) (xy 268.323314 -120.169432) (xy 268.328053 -120.185019) (xy 268.335178 -120.216812)
			(xy 268.337538 -120.232932) (xy 268.34084 -120.27154) (xy 268.341094 -120.28043) (xy 268.344142 -120.288304)
			(xy 268.345807 -120.292297) (xy 268.35027 -120.299707) (xy 268.353032 -120.303036) (xy 268.362684 -120.313958)
			(xy 268.363446 -120.31472) (xy 268.365986 -120.317768) (xy 268.36878 -120.321324) (xy 268.372082 -120.324372)
			(xy 269.243302 -120.324372) (xy 269.253024 -120.32389) (xy 269.271048 -120.31658) (xy 269.278354 -120.310148)
			(xy 269.309221 -120.281227) (xy 269.375069 -120.228124) (xy 269.445178 -120.180788) (xy 269.519042 -120.139557)
			(xy 269.596132 -120.104729) (xy 269.675894 -120.076552) (xy 269.757756 -120.05523) (xy 269.841128 -120.040916)
			(xy 269.925414 -120.033712) (xy 269.96771 -120.033288) (xy 270.014394 -120.033828) (xy 270.107353 -120.042549)
			(xy 270.19909 -120.059923) (xy 270.288801 -120.085797) (xy 270.375699 -120.119946) (xy 270.459025 -120.162069)
			(xy 270.538047 -120.211798) (xy 270.612074 -120.268697) (xy 270.680456 -120.332269) (xy 270.742596 -120.401955)
			(xy 270.797949 -120.477145) (xy 270.82242 -120.516904) (xy 270.824937 -120.520885) (xy 270.8312 -120.527918)
			(xy 270.834866 -120.530874) (xy 270.857359 -120.548929) (xy 270.897166 -120.590666) (xy 270.930244 -120.637915)
			(xy 270.955841 -120.6896) (xy 270.973374 -120.744547) (xy 270.982444 -120.801506) (xy 270.983202 -120.83034)
			(xy 270.983202 -120.833896) (xy 270.983202 -120.834404) (xy 270.982601 -120.863449) (xy 270.973672 -120.920849)
			(xy 270.965422 -120.948704) (xy 270.964081 -120.953212) (xy 270.962931 -120.962547) (xy 270.963136 -120.967246)
			(xy 270.964091 -120.983104) (xy 270.965108 -121.01486) (xy 270.965168 -121.030746) (xy 270.964731 -121.073113)
			(xy 270.95754 -121.157541) (xy 270.943206 -121.241054) (xy 270.921832 -121.323048) (xy 270.893572 -121.40293)
			(xy 270.876522 -121.441718) (xy 270.872553 -121.451757) (xy 270.872571 -121.473326) (xy 270.876522 -121.483374)
			(xy 270.893564 -121.522163) (xy 270.921795 -121.602052) (xy 270.943154 -121.684047) (xy 270.957486 -121.767557)
			(xy 270.964689 -121.851981) (xy 270.965168 -121.894346) (xy 270.9651 -121.910232) (xy 270.964085 -121.941988)
			(xy 270.963136 -121.957846) (xy 270.962897 -121.962533) (xy 270.963927 -121.971861) (xy 270.965168 -121.976388)
			(xy 270.965422 -121.976642) (xy 270.965422 -121.97715) (xy 270.970362 -121.993161) (xy 270.977743 -122.025847)
			(xy 270.980154 -122.042428) (xy 270.980154 -122.043444) (xy 270.981932 -122.057414) (xy 270.982186 -122.059192)
			(xy 270.98244 -122.06224) (xy 270.983202 -122.081798) (xy 270.983202 -122.094244) (xy 270.982496 -122.12312)
			(xy 270.973456 -122.180167) (xy 270.955934 -122.235204) (xy 270.93033 -122.286979) (xy 270.897228 -122.334311)
			(xy 270.857381 -122.376124) (xy 270.834866 -122.394218) (xy 270.831202 -122.397177) (xy 270.824938 -122.404208)
			(xy 270.82242 -122.408188) (xy 270.797907 -122.447917) (xy 270.742544 -122.52309) (xy 270.680399 -122.59276)
			(xy 270.612015 -122.656318) (xy 270.537991 -122.713206) (xy 270.458974 -122.762928) (xy 270.375656 -122.805048)
			(xy 270.288766 -122.839197) (xy 270.199066 -122.865077) (xy 270.107339 -122.88246) (xy 270.01439 -122.891195)
			(xy 269.96771 -122.891804) (xy 269.925399 -122.891356) (xy 269.841082 -122.884187) (xy 269.757676 -122.869898)
			(xy 269.67578 -122.848594) (xy 269.595984 -122.820426) (xy 269.518862 -122.785598) (xy 269.444968 -122.744361)
			(xy 269.374835 -122.69701) (xy 269.308966 -122.643887) (xy 269.2781 -122.614944) (xy 269.270734 -122.607832)
			(xy 269.252954 -122.60072) (xy 269.223236 -122.60072) (xy 269.213584 -122.605038) (xy 269.178475 -122.62015)
			(xy 269.106386 -122.645577) (xy 269.069566 -122.655838) (xy 269.067534 -122.656346) (xy 269.019361 -122.670924)
			(xy 268.920804 -122.691358) (xy 268.82068 -122.701667) (xy 268.770354 -122.70232) (xy 268.415516 -122.70232)
			(xy 268.405275 -122.702795) (xy 268.386422 -122.710803) (xy 268.37894 -122.717814) (xy 268.35608 -122.741436)
			(xy 268.32687 -122.771662) (xy 268.322044 -122.777758) (xy 268.322552 -122.79757) (xy 268.322552 -122.798078)
			(xy 268.32306 -122.823986) (xy 268.32306 -122.824494) (xy 268.322614 -122.866836) (xy 268.31541 -122.951212)
			(xy 268.301072 -123.034672) (xy 268.279703 -123.116615) (xy 268.251456 -123.196449) (xy 268.234414 -123.235212)
			(xy 268.230439 -123.24525) (xy 268.230454 -123.266822) (xy 268.234414 -123.276868) (xy 268.251456 -123.315657)
			(xy 268.279688 -123.395546) (xy 268.301048 -123.477541) (xy 268.315381 -123.561051) (xy 268.322584 -123.645475)
			(xy 268.32306 -123.68784) (xy 268.321028 -123.751086) (xy 268.320266 -123.760484) (xy 268.322298 -123.766834)
			(xy 268.32306 -123.769374) (xy 268.33449 -123.80595) (xy 268.335252 -123.808744) (xy 268.336268 -123.81484)
			(xy 268.33957 -123.8504) (xy 268.341094 -123.878594) (xy 268.341094 -123.88723) (xy 268.340765 -123.908175)
			(xy 268.336054 -123.949799) (xy 268.331696 -123.970288) (xy 268.330172 -123.9774) (xy 268.330934 -123.99137)
			(xy 268.333474 -123.998482) (xy 268.336049 -124.005123) (xy 268.344313 -124.016715) (xy 268.34973 -124.021342)
			(xy 268.371574 -124.038614) (xy 268.372082 -124.038614) (xy 268.376146 -124.041916) (xy 268.38656 -124.047504)
			(xy 268.392402 -124.048774) (xy 268.398185 -124.049964) (xy 268.409987 -124.049964) (xy 268.41577 -124.048774)
			(xy 268.428724 -124.045726) (xy 268.434058 -124.042932) (xy 268.470269 -124.025148) (xy 268.545049 -123.99486)
			(xy 268.62205 -123.97077) (xy 268.700758 -123.953039) (xy 268.780651 -123.941785) (xy 268.8209 -123.939046)
			(xy 268.826488 -123.938284) (xy 268.867648 -123.931822) (xy 268.950688 -123.924953) (xy 268.99235 -123.924568)
			(xy 269.252954 -123.924568) (xy 269.270734 -123.917456) (xy 269.2781 -123.910344) (xy 269.308973 -123.88141)
			(xy 269.374839 -123.828284) (xy 269.444971 -123.780933) (xy 269.518863 -123.739695) (xy 269.595985 -123.704869)
			(xy 269.675781 -123.676704) (xy 269.757677 -123.655404) (xy 269.841083 -123.641121) (xy 269.9254 -123.633958)
			(xy 269.96771 -123.633484) (xy 270.014394 -123.634024) (xy 270.107353 -123.642745) (xy 270.19909 -123.660119)
			(xy 270.288801 -123.685993) (xy 270.3757 -123.720141) (xy 270.459025 -123.762265) (xy 270.538048 -123.811994)
			(xy 270.612074 -123.868893) (xy 270.680457 -123.932464) (xy 270.742597 -124.00215) (xy 270.79795 -124.07734)
			(xy 270.82242 -124.1171) (xy 270.824937 -124.121081) (xy 270.831199 -124.128114) (xy 270.834866 -124.13107)
			(xy 270.857359 -124.149125) (xy 270.897167 -124.190862) (xy 270.930246 -124.23811) (xy 270.955843 -124.289796)
			(xy 270.973376 -124.344743) (xy 270.982447 -124.401702) (xy 270.983202 -124.430536) (xy 270.983202 -124.434092)
			(xy 270.983202 -124.4346) (xy 270.982601 -124.463645) (xy 270.973673 -124.521046) (xy 270.965422 -124.5489)
			(xy 270.96408 -124.553408) (xy 270.96293 -124.562743) (xy 270.963136 -124.567442) (xy 270.964091 -124.5833)
			(xy 270.965108 -124.615056) (xy 270.965168 -124.630942) (xy 270.964731 -124.673309) (xy 270.957541 -124.757737)
			(xy 270.943207 -124.84125) (xy 270.921833 -124.923244) (xy 270.893573 -125.003127) (xy 270.876522 -125.041914)
			(xy 270.872552 -125.051953) (xy 270.872568 -125.073522) (xy 270.876522 -125.08357) (xy 270.893564 -125.122359)
			(xy 270.921796 -125.202248) (xy 270.943155 -125.284243) (xy 270.957488 -125.367753) (xy 270.964691 -125.452177)
			(xy 270.965168 -125.494542) (xy 270.9651 -125.510428) (xy 270.964085 -125.542184) (xy 270.963136 -125.558042)
			(xy 270.962897 -125.562729) (xy 270.963926 -125.572057) (xy 270.965168 -125.576584) (xy 270.965422 -125.576838)
			(xy 270.965422 -125.577346) (xy 270.970362 -125.593357) (xy 270.977743 -125.626043) (xy 270.980154 -125.642624)
			(xy 270.980154 -125.64364) (xy 270.981932 -125.65761) (xy 270.982186 -125.659388) (xy 270.98244 -125.662436)
			(xy 270.983202 -125.681994) (xy 270.983202 -125.69444) (xy 270.982497 -125.723316) (xy 270.973456 -125.780363)
			(xy 270.955935 -125.835401) (xy 270.930332 -125.887176) (xy 270.89723 -125.934509) (xy 270.857383 -125.976322)
			(xy 270.834866 -125.994414) (xy 270.831202 -125.997373) (xy 270.824937 -126.004404) (xy 270.82242 -126.008384)
			(xy 270.797907 -126.048113) (xy 270.742545 -126.123286) (xy 270.6804 -126.192957) (xy 270.612016 -126.256515)
			(xy 270.537991 -126.313404) (xy 270.458974 -126.363126) (xy 270.375656 -126.405246) (xy 270.288767 -126.439395)
			(xy 270.199066 -126.465275) (xy 270.107339 -126.482658) (xy 270.01439 -126.491393) (xy 269.96771 -126.492)
			(xy 269.923479 -126.491526) (xy 269.835365 -126.483695) (xy 269.748292 -126.468086) (xy 269.662944 -126.44482)
			(xy 269.579995 -126.414082) (xy 269.500097 -126.376112) (xy 269.461742 -126.354078) (xy 269.461742 -126.353824)
			(xy 269.453868 -126.349252) (xy 269.44505 -126.344562) (xy 269.425281 -126.341826) (xy 269.415514 -126.343918)
			(xy 269.407386 -126.34595) (xy 269.383256 -126.387098) (xy 269.3797 -126.390654) (xy 269.067026 -126.703328)
			(xy 269.051532 -126.718568) (xy 269.051024 -126.719076) (xy 268.957806 -126.812294) (xy 268.941308 -126.828611)
			(xy 268.907006 -126.859868) (xy 268.889226 -126.874778) (xy 268.883638 -126.87935) (xy 268.488414 -127.470662)
			(xy 268.486636 -127.48133) (xy 268.479052 -127.52201) (xy 268.45801 -127.602049) (xy 268.430411 -127.680069)
			(xy 268.396445 -127.755536) (xy 268.356346 -127.82793) (xy 268.333728 -127.862584) (xy 268.093698 -128.22174)
			(xy 268.071205 -128.254691) (xy 268.021709 -128.317272) (xy 267.967365 -128.375692) (xy 267.90852 -128.429577)
			(xy 267.87729 -128.454404) (xy 267.871051 -128.459607) (xy 267.861999 -128.473086) (xy 267.85951 -128.48082)
			(xy 267.848494 -128.51926) (xy 267.821126 -128.594402) (xy 267.787834 -128.667114) (xy 267.748831 -128.736929)
			(xy 267.726922 -128.77038) (xy 267.486638 -129.12979) (xy 267.460934 -129.167328) (xy 267.403694 -129.23805)
			(xy 267.372338 -129.271014) (xy 267.36596 -129.278065) (xy 267.358523 -129.295547) (xy 267.358008 -129.314539)
			(xy 267.360908 -129.323592) (xy 267.391896 -129.409698) (xy 267.395527 -129.418444) (xy 267.407962 -129.432703)
			(xy 267.424706 -129.441509) (xy 267.43406 -129.442972) (xy 267.47964 -129.448486) (xy 267.56961 -129.466821)
			(xy 267.657513 -129.493348) (xy 267.742605 -129.527843) (xy 267.824166 -129.570015) (xy 267.901505 -129.619506)
			(xy 267.973968 -129.675896) (xy 268.040939 -129.738709) (xy 268.101853 -129.807412) (xy 268.156194 -129.881425)
			(xy 268.180312 -129.920492) (xy 268.182828 -129.924474) (xy 268.189089 -129.931509) (xy 268.192758 -129.934462)
			(xy 268.215252 -129.952516) (xy 268.255062 -129.994253) (xy 268.288142 -130.041501) (xy 268.31374 -130.093187)
			(xy 268.331275 -130.148134) (xy 268.340348 -130.205094) (xy 268.341094 -130.233928) (xy 268.341094 -130.237484)
			(xy 268.341094 -130.237992) (xy 268.340494 -130.267037) (xy 268.331566 -130.324438) (xy 268.323314 -130.352292)
			(xy 268.321963 -130.356799) (xy 268.320809 -130.366135) (xy 268.321028 -130.370834) (xy 268.321983 -130.386692)
			(xy 268.323 -130.418448) (xy 268.32306 -130.434334) (xy 268.322624 -130.476701) (xy 268.315434 -130.56113)
			(xy 268.3011 -130.644643) (xy 268.279726 -130.726637) (xy 268.251467 -130.80652) (xy 268.234414 -130.845306)
			(xy 268.230437 -130.855345) (xy 268.230451 -130.876917) (xy 268.234414 -130.886962) (xy 268.251456 -130.925751)
			(xy 268.279689 -131.00564) (xy 268.301049 -131.087635) (xy 268.315383 -131.171144) (xy 268.322587 -131.255569)
			(xy 268.32306 -131.297934) (xy 268.321028 -131.360672) (xy 268.320855 -131.36537) (xy 268.321999 -131.374701)
			(xy 268.323314 -131.379214) (xy 268.331493 -131.406824) (xy 268.340426 -131.46371) (xy 268.341094 -131.492498)
			(xy 268.341094 -131.493768) (xy 268.341602 -131.50596) (xy 268.370812 -131.534408) (xy 269.243302 -131.534408)
			(xy 269.253023 -131.533924) (xy 269.271041 -131.526607) (xy 269.278354 -131.520184) (xy 269.309222 -131.491265)
			(xy 269.375071 -131.438165) (xy 269.445181 -131.390832) (xy 269.519045 -131.349604) (xy 269.596135 -131.314777)
			(xy 269.675897 -131.286603) (xy 269.757758 -131.265283) (xy 269.84113 -131.250969) (xy 269.925414 -131.243766)
			(xy 269.96771 -131.243324) (xy 270.014394 -131.243864) (xy 270.107352 -131.252585) (xy 270.199088 -131.269959)
			(xy 270.288798 -131.295834) (xy 270.375696 -131.329984) (xy 270.45902 -131.372108) (xy 270.538041 -131.421838)
			(xy 270.612066 -131.478739) (xy 270.680447 -131.542311) (xy 270.742585 -131.611998) (xy 270.797935 -131.68719)
			(xy 270.82242 -131.72694) (xy 270.824939 -131.730919) (xy 270.831205 -131.737948) (xy 270.834866 -131.74091)
			(xy 270.857362 -131.758964) (xy 270.897177 -131.800699) (xy 270.930263 -131.847946) (xy 270.955868 -131.899631)
			(xy 270.97341 -131.954579) (xy 270.98249 -132.01154) (xy 270.983202 -132.040376) (xy 270.983202 -132.043932)
			(xy 270.983202 -132.04444) (xy 270.982598 -132.073484) (xy 270.973664 -132.130883) (xy 270.965422 -132.15874)
			(xy 270.964084 -132.163249) (xy 270.962942 -132.172583) (xy 270.963136 -132.177282) (xy 270.96409 -132.19314)
			(xy 270.965106 -132.224896) (xy 270.965168 -132.240782) (xy 270.964734 -132.28315) (xy 270.957548 -132.367579)
			(xy 270.943219 -132.451094) (xy 270.921849 -132.53309) (xy 270.893594 -132.612976) (xy 270.876522 -132.651754)
			(xy 270.87254 -132.661794) (xy 270.872533 -132.683373) (xy 270.876522 -132.69341) (xy 270.893557 -132.732175)
			(xy 270.92178 -132.812014) (xy 270.94314 -132.893957) (xy 270.957482 -132.977415) (xy 270.964703 -133.061788)
			(xy 270.965168 -133.104128) (xy 270.965168 -133.104636) (xy 270.964406 -133.139688) (xy 270.964294 -133.144535)
			(xy 270.965697 -133.154128) (xy 270.9672 -133.158738) (xy 270.975669 -133.183969) (xy 270.986285 -133.236123)
			(xy 270.989533 -133.289246) (xy 270.985353 -133.342304) (xy 270.973824 -133.394263) (xy 270.964914 -133.419342)
			(xy 270.963898 -133.42239) (xy 270.959834 -133.434836) (xy 270.956786 -133.44144) (xy 270.956532 -133.441948)
			(xy 270.952722 -133.451346) (xy 270.951706 -133.454394) (xy 270.949674 -133.458458) (xy 270.939202 -133.480871)
			(xy 270.913317 -133.523029) (xy 270.882214 -133.561499) (xy 270.864584 -133.578854) (xy 270.83512 -133.604254)
			(xy 270.831375 -133.607184) (xy 270.824981 -133.614218) (xy 270.82242 -133.618224) (xy 270.797908 -133.657955)
			(xy 270.742549 -133.733132) (xy 270.680406 -133.802807) (xy 270.612023 -133.866368) (xy 270.537999 -133.923261)
			(xy 270.458982 -133.972986) (xy 270.375663 -134.015109) (xy 270.288772 -134.04926) (xy 270.19907 -134.075142)
			(xy 270.107342 -134.092526) (xy 270.014391 -134.101262) (xy 269.96771 -134.10184) (xy 269.925399 -134.101392)
			(xy 269.841082 -134.094223) (xy 269.757675 -134.079935) (xy 269.675779 -134.058631) (xy 269.595982 -134.030464)
			(xy 269.518859 -133.995637) (xy 269.444965 -133.954401) (xy 269.37483 -133.907052) (xy 269.308959 -133.85393)
			(xy 269.2781 -133.82498) (xy 269.270734 -133.817868) (xy 269.252954 -133.810756) (xy 269.122398 -133.810756)
			(xy 269.11639 -133.810929) (xy 269.104712 -133.813761) (xy 269.099284 -133.816344) (xy 269.059366 -133.836139)
			(xy 268.976684 -133.869362) (xy 268.891367 -133.895076) (xy 268.804097 -133.913076) (xy 268.715568 -133.923216)
			(xy 268.67104 -133.924802) (xy 268.661896 -133.925056) (xy 268.501622 -133.99135) (xy 268.468828 -134.004621)
			(xy 268.401707 -134.026994) (xy 268.36751 -134.036054) (xy 268.359636 -134.038086) (xy 268.353032 -134.04215)
			(xy 268.349617 -134.044366) (xy 268.343489 -134.049726) (xy 268.34084 -134.052818) (xy 268.333474 -134.061708)
			(xy 268.332966 -134.062216) (xy 268.332458 -134.062724) (xy 268.32772 -134.069058) (xy 268.32203 -134.083806)
			(xy 268.321282 -134.09168) (xy 268.321282 -134.091934) (xy 268.318097 -134.137577) (xy 268.304417 -134.228052)
			(xy 268.282511 -134.316894) (xy 268.252563 -134.403358) (xy 268.23416 -134.445248) (xy 268.230185 -134.45529)
			(xy 268.230176 -134.476867) (xy 268.23416 -134.486904) (xy 268.25126 -134.525676) (xy 268.279575 -134.605553)
			(xy 268.301 -134.687547) (xy 268.315379 -134.771065) (xy 268.322608 -134.855503) (xy 268.32306 -134.897876)
			(xy 268.322991 -134.913762) (xy 268.321975 -134.945518) (xy 268.321028 -134.961376) (xy 268.320856 -134.966074)
			(xy 268.322 -134.975404) (xy 268.323314 -134.979918) (xy 268.33091 -135.005441) (xy 268.339707 -135.057961)
			(xy 268.34084 -135.084566) (xy 268.34084 -135.085582) (xy 268.341094 -135.092694) (xy 268.341094 -135.094472)
			(xy 268.341094 -135.09625) (xy 268.341094 -135.09752) (xy 268.340778 -135.116579) (xy 268.336833 -135.154496)
			(xy 268.33322 -135.173212) (xy 268.332458 -135.176514) (xy 268.332966 -135.184134) (xy 268.334243 -135.19519)
			(xy 268.344916 -135.21469) (xy 268.35354 -135.221726) (xy 268.390878 -135.249158) (xy 268.391386 -135.249158)
			(xy 268.417294 -135.267954) (xy 268.42208 -135.270859) (xy 268.43259 -135.27471) (xy 268.438122 -135.275574)
			(xy 268.460728 -135.262874) (xy 268.498129 -135.242285) (xy 268.575804 -135.206829) (xy 268.656224 -135.178143)
			(xy 268.738802 -135.156436) (xy 268.822934 -135.141866) (xy 268.908002 -135.134542) (xy 268.950694 -135.134096)
			(xy 269.243302 -135.134096) (xy 269.252997 -135.133658) (xy 269.271004 -135.126465) (xy 269.278354 -135.120126)
			(xy 269.309221 -135.091212) (xy 269.375071 -135.038126) (xy 269.445181 -134.990809) (xy 269.519049 -134.949603)
			(xy 269.596142 -134.914803) (xy 269.675906 -134.88666) (xy 269.757768 -134.865377) (xy 269.841138 -134.851105)
			(xy 269.925418 -134.843948) (xy 269.96771 -134.84352) (xy 270.014404 -134.844051) (xy 270.107385 -134.852758)
			(xy 270.199144 -134.870121) (xy 270.288878 -134.895989) (xy 270.375799 -134.930136) (xy 270.459146 -134.972261)
			(xy 270.538188 -135.021996) (xy 270.612233 -135.078905) (xy 270.680632 -135.142489) (xy 270.742784 -135.212191)
			(xy 270.798146 -135.287399) (xy 270.822674 -135.327136) (xy 270.825191 -135.331117) (xy 270.831453 -135.338151)
			(xy 270.83512 -135.341106) (xy 270.857504 -135.359081) (xy 270.897131 -135.400616) (xy 270.930089 -135.447618)
			(xy 270.955635 -135.499027) (xy 270.973192 -135.553683) (xy 270.982363 -135.610352) (xy 270.983202 -135.639048)
			(xy 270.983202 -135.648192) (xy 270.982386 -135.676467) (xy 270.973457 -135.732322) (xy 270.965422 -135.759444)
			(xy 270.964084 -135.763953) (xy 270.962943 -135.773287) (xy 270.963136 -135.777986) (xy 270.965168 -135.840724)
			(xy 270.964732 -135.883091) (xy 270.957543 -135.96752) (xy 270.94321 -136.051033) (xy 270.921838 -136.133028)
			(xy 270.893579 -136.212912) (xy 270.876522 -136.251696) (xy 270.872548 -136.261736) (xy 270.872558 -136.283308)
			(xy 270.876522 -136.293352) (xy 270.893564 -136.332141) (xy 270.921798 -136.41203) (xy 270.943158 -136.494025)
			(xy 270.957493 -136.577534) (xy 270.964698 -136.661959) (xy 270.965168 -136.704324) (xy 270.9651 -136.72021)
			(xy 270.964086 -136.751966) (xy 270.963136 -136.767824) (xy 270.962895 -136.772512) (xy 270.963921 -136.781841)
			(xy 270.965168 -136.786366) (xy 270.969994 -136.802622) (xy 270.969994 -136.80313) (xy 270.97351 -136.816474)
			(xy 270.978849 -136.843552) (xy 270.980662 -136.857232) (xy 270.981932 -136.867646) (xy 270.983456 -136.901428)
			(xy 270.983456 -136.901936) (xy 270.98291 -136.931006) (xy 270.9741 -136.988476) (xy 270.956689 -137.043949)
			(xy 270.931077 -137.096145) (xy 270.897857 -137.14386) (xy 270.857793 -137.185995) (xy 270.83512 -137.204196)
			(xy 270.831377 -137.207127) (xy 270.824988 -137.214165) (xy 270.82242 -137.218166) (xy 270.802205 -137.251053)
			(xy 270.757417 -137.313937) (xy 270.707903 -137.373172) (xy 270.681196 -137.401046) (xy 270.674607 -137.408425)
			(xy 270.667147 -137.426724) (xy 270.666718 -137.436606) (xy 270.667226 -137.508488) (xy 270.667744 -137.518387)
			(xy 270.675324 -137.536683) (xy 270.681958 -137.544048) (xy 270.73987 -137.60196) (xy 270.774075 -137.63697)
			(xy 270.836191 -137.712619) (xy 270.890591 -137.793994) (xy 270.936753 -137.88031) (xy 270.956024 -137.925302)
			(xy 271.411954 -139.02563) (xy 271.430216 -139.071238) (xy 271.458716 -139.165264) (xy 271.46885 -139.213336)
			(xy 271.469612 -139.21613) (xy 271.47012 -139.218162) (xy 271.475343 -139.236922) (xy 271.484491 -139.274779)
			(xy 271.488408 -139.293854) (xy 271.492489 -139.314551) (xy 271.499095 -139.356222) (xy 271.501616 -139.377166)
			(xy 271.502378 -139.38123) (xy 271.50568 -139.397486) (xy 271.509998 -139.407646) (xy 271.513554 -139.412218)
			(xy 271.539631 -139.448073) (xy 271.58604 -139.523623) (xy 271.625567 -139.60299) (xy 271.657901 -139.685549)
			(xy 271.682787 -139.77065) (xy 271.691862 -139.814046) (xy 271.785842 -140.287756) (xy 271.794762 -140.335773)
			(xy 271.804303 -140.432977) (xy 271.804892 -140.481812) (xy 271.804653 -140.517493) (xy 271.799697 -140.588682)
			(xy 271.794986 -140.624052) (xy 271.794109 -140.632622) (xy 271.797472 -140.649506) (xy 271.80159 -140.657072)
			(xy 271.822904 -140.693845) (xy 271.859919 -140.770365) (xy 271.890293 -140.849756) (xy 271.913806 -140.931442)
			(xy 271.922494 -140.973048) (xy 272.01876 -141.45895) (xy 272.027608 -141.50691) (xy 272.037023 -141.603986)
			(xy 272.037556 -141.652752) (xy 272.037316 -141.688433) (xy 272.032357 -141.759622) (xy 272.02765 -141.794992)
			(xy 272.026779 -141.80356) (xy 272.030158 -141.820436) (xy 272.034254 -141.828012) (xy 272.055571 -141.864784)
			(xy 272.092592 -141.941303) (xy 272.122971 -142.020692) (xy 272.14649 -142.102377) (xy 272.155158 -142.143988)
			(xy 272.198592 -142.36446) (xy 272.216372 -142.38478) (xy 272.224754 -142.387828) (xy 272.251821 -142.397695)
			(xy 272.302857 -142.42442) (xy 272.349286 -142.458526) (xy 272.370042 -142.478506) (xy 272.371058 -142.479522)
			(xy 272.375376 -142.48384) (xy 272.396007 -142.506062) (xy 272.430678 -142.555806) (xy 272.457042 -142.610408)
			(xy 272.474435 -142.668494) (xy 272.479008 -142.69847) (xy 272.482056 -142.733522) (xy 272.482056 -142.734284)
			(xy 272.48231 -142.738094) (xy 272.48231 -142.746222) (xy 272.48231 -142.748762) (xy 272.481799 -142.777426)
			(xy 272.473239 -142.834112) (xy 272.456303 -142.888882) (xy 272.431374 -142.940507) (xy 272.39901 -142.987827)
			(xy 272.359938 -143.029779) (xy 272.337784 -143.047974) (xy 272.329367 -143.055352) (xy 272.319375 -143.075349)
			(xy 272.318849 -143.097697) (xy 272.322798 -143.108172) (xy 272.343963 -143.15819) (xy 272.376552 -143.261799)
			(xy 272.387822 -143.314928) (xy 272.484088 -143.80083) (xy 272.492937 -143.84879) (xy 272.502353 -143.945866)
			(xy 272.502884 -143.994632) (xy 272.502644 -144.030313) (xy 272.497687 -144.101502) (xy 272.492978 -144.136872)
			(xy 272.492104 -144.145441) (xy 272.495473 -144.162322) (xy 272.499582 -144.169892) (xy 272.520895 -144.206666)
			(xy 272.557909 -144.283186) (xy 272.588282 -144.362577) (xy 272.611794 -144.444263) (xy 272.620486 -144.485868)
			(xy 272.716752 -144.97177) (xy 272.725599 -145.01973) (xy 272.735012 -145.116806) (xy 272.735548 -145.165572)
			(xy 272.735307 -145.201253) (xy 272.730347 -145.272442) (xy 272.725642 -145.307812) (xy 272.724775 -145.316379)
			(xy 272.728159 -145.333252) (xy 272.732246 -145.340832) (xy 272.753562 -145.377604) (xy 272.790582 -145.454123)
			(xy 272.82096 -145.533513) (xy 272.844478 -145.615198) (xy 272.85315 -145.656808) (xy 272.949416 -146.14271)
			(xy 272.958267 -146.19067) (xy 272.967685 -146.287745) (xy 272.968212 -146.336512) (xy 272.967973 -146.372193)
			(xy 272.963017 -146.443382) (xy 272.958306 -146.478752) (xy 272.957428 -146.487322) (xy 272.960793 -146.504206)
			(xy 272.96491 -146.511772) (xy 272.986225 -146.548545) (xy 273.023243 -146.625064) (xy 273.05362 -146.704454)
			(xy 273.077135 -146.78614) (xy 273.085814 -146.827748) (xy 273.18208 -147.31365) (xy 273.190928 -147.36161)
			(xy 273.200342 -147.458686) (xy 273.200876 -147.507452) (xy 273.200603 -147.540316) (xy 273.196278 -147.6059)
			(xy 273.19224 -147.638516) (xy 273.191468 -147.64733) (xy 273.195234 -147.664606) (xy 273.199606 -147.672298)
			(xy 273.223299 -147.711053) (xy 273.264362 -147.792082) (xy 273.297887 -147.876511) (xy 273.323595 -147.963638)
			(xy 273.332956 -148.008086) (xy 273.429476 -148.494242) (xy 273.43847 -148.542317) (xy 273.448143 -148.639647)
			(xy 273.44878 -148.688552) (xy 273.448269 -148.734358) (xy 273.439819 -148.825578) (xy 273.422987 -148.91563)
			(xy 273.410934 -148.959824) (xy 273.407632 -148.971508) (xy 276.836632 -166.237412) (xy 276.838841 -166.246533)
			(xy 276.848806 -166.262416) (xy 276.863818 -166.273652) (xy 276.881866 -166.278735) (xy 276.891242 -166.278306)
			(xy 276.900601 -166.277032) (xy 276.917471 -166.268564) (xy 276.930141 -166.254571) (xy 276.936896 -166.236945)
			(xy 276.937216 -166.227506) (xy 276.937216 -154.33929) (xy 276.936792 -154.32922) (xy 276.929076 -154.310617)
			(xy 276.92223 -154.303222) (xy 274.182586 -151.563832) (xy 274.164475 -151.545051) (xy 274.133795 -151.502852)
			(xy 274.1101 -151.456371) (xy 274.093974 -151.406753) (xy 274.085816 -151.355222) (xy 274.085304 -151.329136)
			(xy 274.085304 -121.962926) (xy 274.084867 -121.952862) (xy 274.077134 -121.934276) (xy 274.070318 -121.926858)
			(xy 270.123158 -117.979444) (xy 270.115146 -117.972142) (xy 270.09488 -117.964501) (xy 270.084042 -117.964712)
			(xy 269.99692 -117.970046) (xy 269.977616 -117.980206) (xy 269.971012 -117.988842) (xy 269.952823 -118.011327)
			(xy 269.910807 -118.051068) (xy 269.863273 -118.08401) (xy 269.81131 -118.109397) (xy 269.75611 -118.126649)
			(xy 269.698939 -118.135368) (xy 269.670022 -118.135908) (xy 269.642768 -118.135446) (xy 269.588815 -118.127692)
			(xy 269.536514 -118.112338) (xy 269.486931 -118.089696) (xy 269.441076 -118.060229) (xy 269.39988 -118.024535)
			(xy 269.364184 -117.983342) (xy 269.334714 -117.937488) (xy 269.31207 -117.887906) (xy 269.296713 -117.835607)
			(xy 269.288955 -117.781654) (xy 269.288514 -117.7544) (xy 269.289048 -117.725483) (xy 269.297775 -117.668313)
			(xy 269.31503 -117.613113) (xy 269.340416 -117.56115) (xy 269.373354 -117.513613) (xy 269.413088 -117.47159)
			(xy 269.43558 -117.45341) (xy 269.444216 -117.446806) (xy 269.454376 -117.427502) (xy 269.45971 -117.34038)
			(xy 269.459908 -117.329544) (xy 269.452267 -117.309286) (xy 269.444978 -117.301264) (xy 269.032736 -116.889276)
			(xy 269.028382 -116.885109) (xy 269.018105 -116.878821) (xy 269.012416 -116.87683) (xy 269.012162 -116.87683)
			(xy 268.986603 -116.868396) (xy 268.937968 -116.845345) (xy 268.893055 -116.815689) (xy 268.852755 -116.780015)
			(xy 268.817868 -116.739032) (xy 268.789087 -116.693553) (xy 268.766982 -116.644481) (xy 268.751993 -116.592789)
			(xy 268.744416 -116.539504) (xy 268.743938 -116.512594) (xy 268.744402 -116.485343) (xy 268.75216 -116.431395)
			(xy 268.767517 -116.3791) (xy 268.79016 -116.329524) (xy 268.819629 -116.283675) (xy 268.855323 -116.242487)
			(xy 268.896516 -116.206798) (xy 268.94237 -116.177335) (xy 268.991949 -116.154699) (xy 269.044246 -116.139349)
			(xy 269.098195 -116.131598) (xy 269.125446 -116.131086) (xy 269.151763 -116.131523) (xy 269.203898 -116.138745)
			(xy 269.254548 -116.15306) (xy 269.302751 -116.174196) (xy 269.347594 -116.201753) (xy 269.388227 -116.235208)
			(xy 269.40637 -116.254276) (xy 269.413861 -116.261726) (xy 269.433157 -116.27027) (xy 269.443708 -116.270786)
			(xy 269.512542 -116.270786) (xy 269.523206 -116.270337) (xy 269.542689 -116.261668) (xy 269.550134 -116.254022)
			(xy 269.567956 -116.235011) (xy 269.607832 -116.201465) (xy 269.65185 -116.173575) (xy 269.675356 -116.162328)
			(xy 269.685324 -116.157137) (xy 269.699815 -116.139995) (xy 269.703296 -116.129308) (xy 269.722092 -116.059966)
			(xy 269.724432 -116.04927) (xy 269.720893 -116.027682) (xy 269.715234 -116.01831) (xy 269.699648 -115.994473)
			(xy 269.674965 -115.94315) (xy 269.658196 -115.888724) (xy 269.649714 -115.832409) (xy 269.649194 -115.803934)
			(xy 269.649731 -115.775046) (xy 269.658448 -115.717931) (xy 269.675673 -115.662783) (xy 269.701013 -115.61086)
			(xy 269.733888 -115.56335) (xy 269.773549 -115.521336) (xy 269.819088 -115.48578) (xy 269.869465 -115.457493)
			(xy 269.923531 -115.437121) (xy 269.980049 -115.42513) (xy 270.008858 -115.422934) (xy 270.01978 -115.422426)
			(xy 270.039084 -115.412266) (xy 270.09979 -115.335304) (xy 270.105124 -115.314222) (xy 270.103092 -115.303554)
			(xy 270.100262 -115.286806) (xy 270.09721 -115.252974) (xy 270.096996 -115.23599) (xy 270.096996 -115.235228)
			(xy 270.097482 -115.207977) (xy 270.105238 -115.154029) (xy 270.120593 -115.101734) (xy 270.143235 -115.052157)
			(xy 270.172701 -115.006307) (xy 270.208392 -114.965116) (xy 270.249583 -114.929425) (xy 270.295433 -114.899959)
			(xy 270.34501 -114.877317) (xy 270.397305 -114.861962) (xy 270.451253 -114.854206) (xy 270.505755 -114.854206)
			(xy 270.559703 -114.861962) (xy 270.611998 -114.877317) (xy 270.661575 -114.899959) (xy 270.707425 -114.929425)
			(xy 270.748616 -114.965116) (xy 270.784307 -115.006307) (xy 270.813773 -115.052157) (xy 270.836415 -115.101734)
			(xy 270.85177 -115.154029) (xy 270.859526 -115.207977) (xy 270.860012 -115.235228) (xy 270.859471 -115.264113)
			(xy 270.850746 -115.321221) (xy 270.833516 -115.376362) (xy 270.808172 -115.428277) (xy 270.775295 -115.47578)
			(xy 270.735636 -115.517786) (xy 270.690099 -115.553336) (xy 270.639725 -115.581619) (xy 270.585664 -115.601987)
			(xy 270.529151 -115.613976) (xy 270.500348 -115.616228) (xy 270.489426 -115.616736) (xy 270.470122 -115.626896)
			(xy 270.409416 -115.703858) (xy 270.404082 -115.72494) (xy 270.406114 -115.735608) (xy 270.408977 -115.752544)
			(xy 270.412034 -115.786759) (xy 270.41221 -115.803934) (xy 270.41221 -115.807998) (xy 270.412536 -115.818033)
			(xy 270.420052 -115.836633) (xy 270.434132 -115.850925) (xy 270.443198 -115.855242) (xy 270.530066 -115.891818)
			(xy 270.539509 -115.895353) (xy 270.559656 -115.895441) (xy 270.578266 -115.887719) (xy 270.585692 -115.880896)
			(xy 271.136618 -115.32997) (xy 271.143469 -115.322574) (xy 271.151205 -115.303975) (xy 271.151604 -115.293902)
			(xy 271.151604 -97.998788) (xy 271.151179 -97.988719) (xy 271.143462 -97.970117) (xy 271.136618 -97.96272)
			(xy 270.356584 -97.18294) (xy 270.349675 -97.176579) (xy 270.332547 -97.168917) (xy 270.313809 -97.167954)
			(xy 270.304768 -97.170494) (xy 270.2052 -97.203006) (xy 270.186658 -97.22485) (xy 270.184372 -97.239074)
			(xy 270.179751 -97.265709) (xy 270.163981 -97.317414) (xy 270.14107 -97.366376) (xy 270.111477 -97.411614)
			(xy 270.075795 -97.452221) (xy 270.034739 -97.487385) (xy 269.989129 -97.516402) (xy 269.939881 -97.53869)
			(xy 269.88798 -97.553803) (xy 269.834464 -97.561438) (xy 269.807436 -97.561908) (xy 269.780181 -97.561447)
			(xy 269.726227 -97.553694) (xy 269.673924 -97.538341) (xy 269.62434 -97.515701) (xy 269.578482 -97.486234)
			(xy 269.537285 -97.45054) (xy 269.501588 -97.409347) (xy 269.472116 -97.363492) (xy 269.449471 -97.313909)
			(xy 269.434113 -97.261609) (xy 269.426355 -97.207654) (xy 269.425928 -97.1804) (xy 269.426399 -97.153371)
			(xy 269.43403 -97.099854) (xy 269.44914 -97.047951) (xy 269.471427 -96.998701) (xy 269.500443 -96.95309)
			(xy 269.535607 -96.912032) (xy 269.576216 -96.87635) (xy 269.621455 -96.846758) (xy 269.670419 -96.823849)
			(xy 269.722126 -96.808082) (xy 269.748762 -96.803464) (xy 269.762986 -96.801178) (xy 269.78483 -96.782636)
			(xy 269.817342 -96.683068) (xy 269.819843 -96.674023) (xy 269.818864 -96.6553) (xy 269.811232 -96.638174)
			(xy 269.804896 -96.631252) (xy 269.714726 -96.541082) (xy 269.710372 -96.536915) (xy 269.700094 -96.530628)
			(xy 269.694406 -96.528636) (xy 269.694152 -96.528636) (xy 269.668594 -96.520201) (xy 269.619959 -96.49715)
			(xy 269.575047 -96.467493) (xy 269.534747 -96.431819) (xy 269.499861 -96.390836) (xy 269.471079 -96.345358)
			(xy 269.448975 -96.296286) (xy 269.433985 -96.244595) (xy 269.426408 -96.19131) (xy 269.425928 -96.1644)
			(xy 269.426391 -96.137148) (xy 269.434149 -96.083199) (xy 269.449505 -96.030903) (xy 269.472148 -95.981325)
			(xy 269.501616 -95.935475) (xy 269.537311 -95.894285) (xy 269.578504 -95.858595) (xy 269.624357 -95.829131)
			(xy 269.673937 -95.806492) (xy 269.726234 -95.791141) (xy 269.780184 -95.783389) (xy 269.807436 -95.782892)
			(xy 269.834335 -95.783355) (xy 269.887599 -95.790918) (xy 269.939272 -95.805889) (xy 269.98833 -95.82797)
			(xy 270.033799 -95.856725) (xy 270.074777 -95.891581) (xy 270.110452 -95.931849) (xy 270.140117 -95.97673)
			(xy 270.163182 -96.025333) (xy 270.171672 -96.050862) (xy 270.171672 -96.05137) (xy 270.17372 -96.057031)
			(xy 270.18001 -96.06729) (xy 270.184118 -96.07169) (xy 270.487394 -96.374966) (xy 326.62698 -96.374966)
			(xy 326.631051 -96.319344) (xy 326.643177 -96.264907) (xy 326.6631 -96.212816) (xy 326.690396 -96.164181)
			(xy 326.724482 -96.120038) (xy 326.764631 -96.081329) (xy 326.809989 -96.048878) (xy 326.859589 -96.023377)
			(xy 326.912373 -96.00537) (xy 326.967216 -95.99524) (xy 327.02295 -95.993203) (xy 327.078387 -95.999303)
			(xy 327.132344 -96.013409) (xy 327.183673 -96.035221) (xy 327.231279 -96.064275) (xy 327.274147 -96.09995)
			(xy 327.311364 -96.141487) (xy 327.342137 -96.188) (xy 327.365809 -96.238497) (xy 327.380808 -96.288352)
			(xy 328.052174 -96.288352) (xy 328.056245 -96.23273) (xy 328.068371 -96.178293) (xy 328.088294 -96.126202)
			(xy 328.11559 -96.077567) (xy 328.149676 -96.033424) (xy 328.189825 -95.994715) (xy 328.235183 -95.962264)
			(xy 328.284783 -95.936763) (xy 328.337567 -95.918756) (xy 328.39241 -95.908626) (xy 328.448144 -95.906589)
			(xy 328.503581 -95.912689) (xy 328.557538 -95.926795) (xy 328.608867 -95.948607) (xy 328.656473 -95.977661)
			(xy 328.699341 -96.013336) (xy 328.736558 -96.054873) (xy 328.767331 -96.101386) (xy 328.791003 -96.151883)
			(xy 328.807071 -96.20529) (xy 328.815191 -96.260466) (xy 328.815422 -96.273112) (xy 329.397866 -96.273112)
			(xy 329.401937 -96.21749) (xy 329.414063 -96.163053) (xy 329.433986 -96.110962) (xy 329.461282 -96.062327)
			(xy 329.495368 -96.018184) (xy 329.535517 -95.979475) (xy 329.580875 -95.947024) (xy 329.630475 -95.921523)
			(xy 329.683259 -95.903516) (xy 329.738102 -95.893386) (xy 329.793836 -95.891349) (xy 329.849273 -95.897449)
			(xy 329.90323 -95.911555) (xy 329.954559 -95.933367) (xy 330.002165 -95.962421) (xy 330.045033 -95.998096)
			(xy 330.08225 -96.039633) (xy 330.113023 -96.086146) (xy 330.136695 -96.136643) (xy 330.152763 -96.19005)
			(xy 330.160883 -96.245226) (xy 330.161392 -96.273112) (xy 330.160883 -96.300998) (xy 330.152763 -96.356174)
			(xy 330.136695 -96.409581) (xy 330.113023 -96.460078) (xy 330.08225 -96.506591) (xy 330.045033 -96.548128)
			(xy 330.002165 -96.583803) (xy 329.954559 -96.612857) (xy 329.90323 -96.634669) (xy 329.849273 -96.648775)
			(xy 329.793836 -96.654875) (xy 329.738102 -96.652838) (xy 329.683259 -96.642708) (xy 329.630475 -96.624701)
			(xy 329.580875 -96.5992) (xy 329.535517 -96.566749) (xy 329.495368 -96.52804) (xy 329.461282 -96.483897)
			(xy 329.433986 -96.435262) (xy 329.414063 -96.383171) (xy 329.401937 -96.328734) (xy 329.397866 -96.273112)
			(xy 328.815422 -96.273112) (xy 328.8157 -96.288352) (xy 328.815191 -96.316238) (xy 328.807071 -96.371414)
			(xy 328.791003 -96.424821) (xy 328.767331 -96.475318) (xy 328.736558 -96.521831) (xy 328.699341 -96.563368)
			(xy 328.656473 -96.599043) (xy 328.608867 -96.628097) (xy 328.557538 -96.649909) (xy 328.503581 -96.664015)
			(xy 328.448144 -96.670115) (xy 328.39241 -96.668078) (xy 328.337567 -96.657948) (xy 328.284783 -96.639941)
			(xy 328.235183 -96.61444) (xy 328.189825 -96.581989) (xy 328.149676 -96.54328) (xy 328.11559 -96.499137)
			(xy 328.088294 -96.450502) (xy 328.068371 -96.398411) (xy 328.056245 -96.343974) (xy 328.052174 -96.288352)
			(xy 327.380808 -96.288352) (xy 327.381877 -96.291904) (xy 327.389997 -96.34708) (xy 327.390506 -96.374966)
			(xy 327.389997 -96.402852) (xy 327.381877 -96.458028) (xy 327.365809 -96.511435) (xy 327.342137 -96.561932)
			(xy 327.311364 -96.608445) (xy 327.274147 -96.649982) (xy 327.231279 -96.685657) (xy 327.183673 -96.714711)
			(xy 327.132344 -96.736523) (xy 327.078387 -96.750629) (xy 327.02295 -96.756729) (xy 326.967216 -96.754692)
			(xy 326.912373 -96.744562) (xy 326.859589 -96.726555) (xy 326.809989 -96.701054) (xy 326.764631 -96.668603)
			(xy 326.724482 -96.629894) (xy 326.690396 -96.585751) (xy 326.6631 -96.537116) (xy 326.643177 -96.485025)
			(xy 326.631051 -96.430588) (xy 326.62698 -96.374966) (xy 270.487394 -96.374966) (xy 271.718024 -97.605596)
			(xy 271.736058 -97.624366) (xy 271.766641 -97.666481) (xy 271.79027 -97.712858) (xy 271.806364 -97.762356)
			(xy 271.814528 -97.81376) (xy 271.815052 -97.839784) (xy 271.815052 -113.503456) (xy 282.903676 -113.503456)
			(xy 282.903676 -98.00717) (xy 282.904212 -97.981147) (xy 282.912377 -97.929744) (xy 282.928469 -97.880247)
			(xy 282.952094 -97.833871) (xy 282.982673 -97.791753) (xy 283.000704 -97.772982) (xy 283.81071 -96.962976)
			(xy 283.814825 -96.958582) (xy 283.821111 -96.948318) (xy 283.823156 -96.942656) (xy 283.823156 -96.942148)
			(xy 283.831613 -96.916607) (xy 283.854682 -96.868003) (xy 283.884351 -96.823122) (xy 283.92003 -96.782854)
			(xy 283.961013 -96.747999) (xy 284.006486 -96.719246) (xy 284.055548 -96.697167) (xy 284.107225 -96.682199)
			(xy 284.160492 -96.674639) (xy 284.187392 -96.674178) (xy 284.214642 -96.674685) (xy 284.268589 -96.68244)
			(xy 284.320882 -96.697794) (xy 284.370458 -96.720433) (xy 284.416308 -96.749897) (xy 284.457498 -96.785586)
			(xy 284.49319 -96.826774) (xy 284.522657 -96.872622) (xy 284.535618 -96.901) (xy 301.521874 -96.901)
			(xy 301.525945 -96.845378) (xy 301.538071 -96.790941) (xy 301.557994 -96.73885) (xy 301.58529 -96.690215)
			(xy 301.619376 -96.646072) (xy 301.659525 -96.607363) (xy 301.704883 -96.574912) (xy 301.754483 -96.549411)
			(xy 301.807267 -96.531404) (xy 301.86211 -96.521274) (xy 301.917844 -96.519237) (xy 301.973281 -96.525337)
			(xy 302.027238 -96.539443) (xy 302.078567 -96.561255) (xy 302.126173 -96.590309) (xy 302.169041 -96.625984)
			(xy 302.206258 -96.667521) (xy 302.237031 -96.714034) (xy 302.260703 -96.764531) (xy 302.276771 -96.817938)
			(xy 302.284891 -96.873114) (xy 302.2854 -96.901) (xy 302.284891 -96.928886) (xy 302.276771 -96.984062)
			(xy 302.260703 -97.037469) (xy 302.259546 -97.039938) (xy 306.92547 -97.039938) (xy 306.929541 -96.984316)
			(xy 306.941667 -96.929879) (xy 306.96159 -96.877788) (xy 306.988886 -96.829153) (xy 307.022972 -96.78501)
			(xy 307.063121 -96.746301) (xy 307.108479 -96.71385) (xy 307.158079 -96.688349) (xy 307.210863 -96.670342)
			(xy 307.265706 -96.660212) (xy 307.32144 -96.658175) (xy 307.376877 -96.664275) (xy 307.430834 -96.678381)
			(xy 307.482163 -96.700193) (xy 307.529769 -96.729247) (xy 307.572637 -96.764922) (xy 307.609854 -96.806459)
			(xy 307.640627 -96.852972) (xy 307.664299 -96.903469) (xy 307.680367 -96.956876) (xy 307.687545 -97.005648)
			(xy 310.369456 -97.005648) (xy 310.373527 -96.950026) (xy 310.385653 -96.895589) (xy 310.405576 -96.843498)
			(xy 310.432872 -96.794863) (xy 310.466958 -96.75072) (xy 310.507107 -96.712011) (xy 310.552465 -96.67956)
			(xy 310.602065 -96.654059) (xy 310.654849 -96.636052) (xy 310.709692 -96.625922) (xy 310.765426 -96.623885)
			(xy 310.820863 -96.629985) (xy 310.87482 -96.644091) (xy 310.926149 -96.665903) (xy 310.973755 -96.694957)
			(xy 311.016623 -96.730632) (xy 311.05384 -96.772169) (xy 311.084613 -96.818682) (xy 311.108285 -96.869179)
			(xy 311.124353 -96.922586) (xy 311.132473 -96.977762) (xy 311.132982 -97.005648) (xy 311.132473 -97.033534)
			(xy 311.124353 -97.08871) (xy 311.108285 -97.142117) (xy 311.084613 -97.192614) (xy 311.05384 -97.239127)
			(xy 311.016623 -97.280664) (xy 310.973755 -97.316339) (xy 310.926149 -97.345393) (xy 310.87482 -97.367205)
			(xy 310.820863 -97.381311) (xy 310.765426 -97.387411) (xy 310.709692 -97.385374) (xy 310.654849 -97.375244)
			(xy 310.602065 -97.357237) (xy 310.552465 -97.331736) (xy 310.507107 -97.299285) (xy 310.466958 -97.260576)
			(xy 310.432872 -97.216433) (xy 310.405576 -97.167798) (xy 310.385653 -97.115707) (xy 310.373527 -97.06127)
			(xy 310.369456 -97.005648) (xy 307.687545 -97.005648) (xy 307.688487 -97.012052) (xy 307.688996 -97.039938)
			(xy 307.688487 -97.067824) (xy 307.680367 -97.123) (xy 307.664299 -97.176407) (xy 307.640627 -97.226904)
			(xy 307.609854 -97.273417) (xy 307.572637 -97.314954) (xy 307.529769 -97.350629) (xy 307.482163 -97.379683)
			(xy 307.430834 -97.401495) (xy 307.376877 -97.415601) (xy 307.32144 -97.421701) (xy 307.265706 -97.419664)
			(xy 307.210863 -97.409534) (xy 307.158079 -97.391527) (xy 307.108479 -97.366026) (xy 307.063121 -97.333575)
			(xy 307.022972 -97.294866) (xy 306.988886 -97.250723) (xy 306.96159 -97.202088) (xy 306.941667 -97.149997)
			(xy 306.929541 -97.09556) (xy 306.92547 -97.039938) (xy 302.259546 -97.039938) (xy 302.237031 -97.087966)
			(xy 302.206258 -97.134479) (xy 302.169041 -97.176016) (xy 302.126173 -97.211691) (xy 302.078567 -97.240745)
			(xy 302.027238 -97.262557) (xy 301.973281 -97.276663) (xy 301.917844 -97.282763) (xy 301.86211 -97.280726)
			(xy 301.807267 -97.270596) (xy 301.754483 -97.252589) (xy 301.704883 -97.227088) (xy 301.659525 -97.194637)
			(xy 301.619376 -97.155928) (xy 301.58529 -97.111785) (xy 301.557994 -97.06315) (xy 301.538071 -97.011059)
			(xy 301.525945 -96.956622) (xy 301.521874 -96.901) (xy 284.535618 -96.901) (xy 284.545299 -96.922197)
			(xy 284.560655 -96.97449) (xy 284.568413 -97.028436) (xy 284.5689 -97.055686) (xy 284.568477 -97.082598)
			(xy 284.560888 -97.135884) (xy 284.545889 -97.187575) (xy 284.523775 -97.236647) (xy 284.494987 -97.282124)
			(xy 284.460094 -97.323106) (xy 284.41979 -97.358779) (xy 284.374874 -97.388435) (xy 284.326236 -97.411487)
			(xy 284.300676 -97.419922) (xy 284.300422 -97.419922) (xy 284.294727 -97.421897) (xy 284.284454 -97.428197)
			(xy 284.280102 -97.432368) (xy 284.072254 -97.64014) (xy 306.118004 -97.64014) (xy 306.122075 -97.584518)
			(xy 306.134201 -97.530081) (xy 306.154124 -97.47799) (xy 306.18142 -97.429355) (xy 306.215506 -97.385212)
			(xy 306.255655 -97.346503) (xy 306.301013 -97.314052) (xy 306.350613 -97.288551) (xy 306.403397 -97.270544)
			(xy 306.45824 -97.260414) (xy 306.513974 -97.258377) (xy 306.569411 -97.264477) (xy 306.623368 -97.278583)
			(xy 306.674697 -97.300395) (xy 306.722303 -97.329449) (xy 306.765171 -97.365124) (xy 306.802388 -97.406661)
			(xy 306.833161 -97.453174) (xy 306.856833 -97.503671) (xy 306.872901 -97.557078) (xy 306.881021 -97.612254)
			(xy 306.88153 -97.64014) (xy 306.881021 -97.668026) (xy 306.872901 -97.723202) (xy 306.856833 -97.776609)
			(xy 306.833161 -97.827106) (xy 306.802388 -97.873619) (xy 306.765171 -97.915156) (xy 306.722303 -97.950831)
			(xy 306.674697 -97.979885) (xy 306.623368 -98.001697) (xy 306.569411 -98.015803) (xy 306.513974 -98.021903)
			(xy 306.45824 -98.019866) (xy 306.403397 -98.009736) (xy 306.350613 -97.991729) (xy 306.301013 -97.966228)
			(xy 306.255655 -97.933777) (xy 306.215506 -97.895068) (xy 306.18142 -97.850925) (xy 306.154124 -97.80229)
			(xy 306.134201 -97.750199) (xy 306.122075 -97.695762) (xy 306.118004 -97.64014) (xy 284.072254 -97.64014)
			(xy 283.58211 -98.130106) (xy 283.575276 -98.137511) (xy 283.567552 -98.156106) (xy 283.567124 -98.166174)
			(xy 283.567124 -98.171) (xy 307.763924 -98.171) (xy 307.767995 -98.115378) (xy 307.780121 -98.060941)
			(xy 307.800044 -98.00885) (xy 307.82734 -97.960215) (xy 307.861426 -97.916072) (xy 307.901575 -97.877363)
			(xy 307.946933 -97.844912) (xy 307.996533 -97.819411) (xy 308.049317 -97.801404) (xy 308.10416 -97.791274)
			(xy 308.159894 -97.789237) (xy 308.215331 -97.795337) (xy 308.269288 -97.809443) (xy 308.320617 -97.831255)
			(xy 308.368223 -97.860309) (xy 308.411091 -97.895984) (xy 308.448308 -97.937521) (xy 308.45893 -97.953576)
			(xy 320.542918 -97.953576) (xy 320.546989 -97.897954) (xy 320.559115 -97.843517) (xy 320.579038 -97.791426)
			(xy 320.606334 -97.742791) (xy 320.64042 -97.698648) (xy 320.680569 -97.659939) (xy 320.725927 -97.627488)
			(xy 320.775527 -97.601987) (xy 320.828311 -97.58398) (xy 320.883154 -97.57385) (xy 320.938888 -97.571813)
			(xy 320.994325 -97.577913) (xy 321.048282 -97.592019) (xy 321.099611 -97.613831) (xy 321.147217 -97.642885)
			(xy 321.190085 -97.67856) (xy 321.227302 -97.720097) (xy 321.258075 -97.76661) (xy 321.281747 -97.817107)
			(xy 321.282991 -97.821242) (xy 321.857368 -97.821242) (xy 321.861439 -97.76562) (xy 321.873565 -97.711183)
			(xy 321.893488 -97.659092) (xy 321.920784 -97.610457) (xy 321.95487 -97.566314) (xy 321.995019 -97.527605)
			(xy 322.040377 -97.495154) (xy 322.089977 -97.469653) (xy 322.142761 -97.451646) (xy 322.197604 -97.441516)
			(xy 322.253338 -97.439479) (xy 322.308775 -97.445579) (xy 322.362732 -97.459685) (xy 322.414061 -97.481497)
			(xy 322.461667 -97.510551) (xy 322.504535 -97.546226) (xy 322.541752 -97.587763) (xy 322.572525 -97.634276)
			(xy 322.596197 -97.684773) (xy 322.612265 -97.73818) (xy 322.620385 -97.793356) (xy 322.620894 -97.821242)
			(xy 322.620397 -97.848448) (xy 323.12842 -97.848448) (xy 323.12842 -97.793952) (xy 323.136175 -97.740012)
			(xy 323.151528 -97.687724) (xy 323.174166 -97.638153) (xy 323.203627 -97.592309) (xy 323.239313 -97.551123)
			(xy 323.280497 -97.515436) (xy 323.326341 -97.485972) (xy 323.375911 -97.463333) (xy 323.428198 -97.447978)
			(xy 323.482138 -97.440221) (xy 323.509386 -97.439734) (xy 323.538303 -97.44025) (xy 323.595475 -97.448977)
			(xy 323.650675 -97.466235) (xy 323.702636 -97.491627) (xy 323.75017 -97.524572) (xy 323.792186 -97.564314)
			(xy 323.810376 -97.5868) (xy 323.818003 -97.595586) (xy 323.838889 -97.605781) (xy 323.850508 -97.606358)
			(xy 323.930264 -97.606358) (xy 323.941901 -97.605856) (xy 323.962811 -97.595642) (xy 323.970396 -97.5868)
			(xy 323.988589 -97.564318) (xy 324.030609 -97.524583) (xy 324.078143 -97.491644) (xy 324.130104 -97.466255)
			(xy 324.185301 -97.448999) (xy 324.24247 -97.440269) (xy 324.271386 -97.439734) (xy 324.298643 -97.440112)
			(xy 324.352601 -97.447868) (xy 324.404906 -97.463225) (xy 324.454494 -97.485869) (xy 324.500354 -97.51534)
			(xy 324.541553 -97.551037) (xy 324.577252 -97.592235) (xy 324.606724 -97.638094) (xy 324.62937 -97.687681)
			(xy 324.644729 -97.739985) (xy 324.652487 -97.793943) (xy 324.652487 -97.821242) (xy 324.905368 -97.821242)
			(xy 324.909439 -97.76562) (xy 324.921565 -97.711183) (xy 324.941488 -97.659092) (xy 324.968784 -97.610457)
			(xy 325.00287 -97.566314) (xy 325.043019 -97.527605) (xy 325.088377 -97.495154) (xy 325.137977 -97.469653)
			(xy 325.190761 -97.451646) (xy 325.245604 -97.441516) (xy 325.301338 -97.439479) (xy 325.356775 -97.445579)
			(xy 325.410732 -97.459685) (xy 325.462061 -97.481497) (xy 325.509667 -97.510551) (xy 325.552535 -97.546226)
			(xy 325.589752 -97.587763) (xy 325.620525 -97.634276) (xy 325.644197 -97.684773) (xy 325.660265 -97.73818)
			(xy 325.668385 -97.793356) (xy 325.668894 -97.821242) (xy 325.668385 -97.849128) (xy 325.660265 -97.904304)
			(xy 325.644197 -97.957711) (xy 325.620525 -98.008208) (xy 325.589752 -98.054721) (xy 325.552535 -98.096258)
			(xy 325.509667 -98.131933) (xy 325.462061 -98.160987) (xy 325.410732 -98.182799) (xy 325.356775 -98.196905)
			(xy 325.301338 -98.203005) (xy 325.245604 -98.200968) (xy 325.190761 -98.190838) (xy 325.137977 -98.172831)
			(xy 325.088377 -98.14733) (xy 325.043019 -98.114879) (xy 325.00287 -98.07617) (xy 324.968784 -98.032027)
			(xy 324.941488 -97.983392) (xy 324.921565 -97.931301) (xy 324.909439 -97.876864) (xy 324.905368 -97.821242)
			(xy 324.652487 -97.821242) (xy 324.652487 -97.848457) (xy 324.644729 -97.902415) (xy 324.62937 -97.954719)
			(xy 324.606724 -98.004306) (xy 324.577252 -98.050165) (xy 324.541553 -98.091363) (xy 324.500354 -98.12706)
			(xy 324.454494 -98.156531) (xy 324.404906 -98.179175) (xy 324.352601 -98.194532) (xy 324.298643 -98.202288)
			(xy 324.271386 -98.20275) (xy 324.24247 -98.202189) (xy 324.1853 -98.193471) (xy 324.130102 -98.176223)
			(xy 324.078139 -98.15084) (xy 324.030605 -98.117902) (xy 323.988587 -98.078167) (xy 323.970396 -98.055684)
			(xy 323.962784 -98.046882) (xy 323.941887 -98.036696) (xy 323.930264 -98.036126) (xy 323.850508 -98.036126)
			(xy 323.838877 -98.036675) (xy 323.817967 -98.046856) (xy 323.810376 -98.055684) (xy 323.792194 -98.078176)
			(xy 323.750173 -98.117911) (xy 323.702637 -98.15085) (xy 323.650673 -98.176237) (xy 323.595474 -98.193491)
			(xy 323.538303 -98.202217) (xy 323.509386 -98.20275) (xy 323.482138 -98.202179) (xy 323.428198 -98.194422)
			(xy 323.375911 -98.179067) (xy 323.326341 -98.156428) (xy 323.280497 -98.126964) (xy 323.239313 -98.091277)
			(xy 323.203627 -98.050091) (xy 323.174166 -98.004247) (xy 323.151528 -97.954676) (xy 323.136175 -97.902388)
			(xy 323.12842 -97.848448) (xy 322.620397 -97.848448) (xy 322.620385 -97.849128) (xy 322.612265 -97.904304)
			(xy 322.596197 -97.957711) (xy 322.572525 -98.008208) (xy 322.541752 -98.054721) (xy 322.504535 -98.096258)
			(xy 322.461667 -98.131933) (xy 322.414061 -98.160987) (xy 322.362732 -98.182799) (xy 322.308775 -98.196905)
			(xy 322.253338 -98.203005) (xy 322.197604 -98.200968) (xy 322.142761 -98.190838) (xy 322.089977 -98.172831)
			(xy 322.040377 -98.14733) (xy 321.995019 -98.114879) (xy 321.95487 -98.07617) (xy 321.920784 -98.032027)
			(xy 321.893488 -97.983392) (xy 321.873565 -97.931301) (xy 321.861439 -97.876864) (xy 321.857368 -97.821242)
			(xy 321.282991 -97.821242) (xy 321.297815 -97.870514) (xy 321.305935 -97.92569) (xy 321.306444 -97.953576)
			(xy 321.305935 -97.981462) (xy 321.297815 -98.036638) (xy 321.281747 -98.090045) (xy 321.258075 -98.140542)
			(xy 321.227302 -98.187055) (xy 321.190085 -98.228592) (xy 321.147217 -98.264267) (xy 321.099611 -98.293321)
			(xy 321.048282 -98.315133) (xy 320.994325 -98.329239) (xy 320.938888 -98.335339) (xy 320.883154 -98.333302)
			(xy 320.828311 -98.323172) (xy 320.775527 -98.305165) (xy 320.725927 -98.279664) (xy 320.680569 -98.247213)
			(xy 320.64042 -98.208504) (xy 320.606334 -98.164361) (xy 320.579038 -98.115726) (xy 320.559115 -98.063635)
			(xy 320.546989 -98.009198) (xy 320.542918 -97.953576) (xy 308.45893 -97.953576) (xy 308.479081 -97.984034)
			(xy 308.502753 -98.034531) (xy 308.518821 -98.087938) (xy 308.526941 -98.143114) (xy 308.52745 -98.171)
			(xy 308.526941 -98.198886) (xy 308.518821 -98.254062) (xy 308.502753 -98.307469) (xy 308.479081 -98.357966)
			(xy 308.448308 -98.404479) (xy 308.411091 -98.446016) (xy 308.368223 -98.481691) (xy 308.320617 -98.510745)
			(xy 308.269288 -98.532557) (xy 308.215331 -98.546663) (xy 308.159894 -98.552763) (xy 308.10416 -98.550726)
			(xy 308.049317 -98.540596) (xy 307.996533 -98.522589) (xy 307.946933 -98.497088) (xy 307.901575 -98.464637)
			(xy 307.861426 -98.425928) (xy 307.82734 -98.381785) (xy 307.800044 -98.33315) (xy 307.780121 -98.281059)
			(xy 307.767995 -98.226622) (xy 307.763924 -98.171) (xy 283.567124 -98.171) (xy 283.567124 -98.759518)
			(xy 331.371194 -98.759518) (xy 331.371672 -98.732148) (xy 331.379487 -98.67797) (xy 331.394974 -98.625467)
			(xy 331.417813 -98.57572) (xy 331.447534 -98.529752) (xy 331.465174 -98.50882) (xy 331.465428 -98.508566)
			(xy 331.470996 -98.501467) (xy 331.477253 -98.48456) (xy 331.47762 -98.475546) (xy 331.47762 -98.40849)
			(xy 331.477263 -98.399473) (xy 331.471015 -98.382557) (xy 331.465428 -98.37547) (xy 331.465174 -98.37547)
			(xy 331.465174 -98.375216) (xy 331.447549 -98.35427) (xy 331.41782 -98.308306) (xy 331.394971 -98.258562)
			(xy 331.379471 -98.206061) (xy 331.37164 -98.151884) (xy 331.371638 -98.097143) (xy 331.379465 -98.042965)
			(xy 331.394961 -97.990464) (xy 331.417807 -97.940718) (xy 331.447533 -97.894752) (xy 331.465174 -97.87382)
			(xy 331.465428 -97.873566) (xy 331.470996 -97.866467) (xy 331.477253 -97.84956) (xy 331.47762 -97.840546)
			(xy 331.47762 -97.77349) (xy 331.477263 -97.764473) (xy 331.471015 -97.747557) (xy 331.465428 -97.74047)
			(xy 331.465174 -97.74047) (xy 331.465174 -97.740216) (xy 331.447525 -97.719292) (xy 331.417815 -97.673317)
			(xy 331.394982 -97.623567) (xy 331.379493 -97.571065) (xy 331.371667 -97.516888) (xy 331.371194 -97.489518)
			(xy 331.37168 -97.462267) (xy 331.379436 -97.408319) (xy 331.394791 -97.356024) (xy 331.417433 -97.306447)
			(xy 331.446899 -97.260597) (xy 331.48259 -97.219406) (xy 331.523781 -97.183715) (xy 331.569631 -97.154249)
			(xy 331.619208 -97.131607) (xy 331.671503 -97.116252) (xy 331.725451 -97.108496) (xy 331.779953 -97.108496)
			(xy 331.833901 -97.116252) (xy 331.886196 -97.131607) (xy 331.935773 -97.154249) (xy 331.981623 -97.183715)
			(xy 332.022814 -97.219406) (xy 332.058505 -97.260597) (xy 332.087971 -97.306447) (xy 332.110613 -97.356024)
			(xy 332.125968 -97.408319) (xy 332.133724 -97.462267) (xy 332.13421 -97.489518) (xy 332.133752 -97.516888)
			(xy 332.125932 -97.571068) (xy 332.110441 -97.623571) (xy 332.087597 -97.673318) (xy 332.057872 -97.719284)
			(xy 332.04023 -97.740216) (xy 332.039976 -97.74047) (xy 332.034393 -97.747559) (xy 332.028145 -97.764474)
			(xy 332.027784 -97.77349) (xy 332.027784 -97.840546) (xy 332.02817 -97.84956) (xy 332.034398 -97.866477)
			(xy 332.039976 -97.873566) (xy 332.04023 -97.873566) (xy 332.04023 -97.87382) (xy 332.05789 -97.894738)
			(xy 332.087617 -97.940707) (xy 332.110464 -97.990455) (xy 332.125961 -98.04296) (xy 332.133789 -98.097142)
			(xy 332.133787 -98.151886) (xy 332.125955 -98.206066) (xy 332.110455 -98.25857) (xy 332.087604 -98.308317)
			(xy 332.057874 -98.354284) (xy 332.04023 -98.375216) (xy 332.039976 -98.37547) (xy 332.034393 -98.382559)
			(xy 332.028145 -98.399474) (xy 332.027784 -98.40849) (xy 332.027784 -98.475546) (xy 332.02817 -98.48456)
			(xy 332.034398 -98.501477) (xy 332.036031 -98.503552) (xy 333.025963 -98.503552) (xy 333.025963 -98.449048)
			(xy 333.03372 -98.395097) (xy 333.049076 -98.3428) (xy 333.071718 -98.293221) (xy 333.101186 -98.247369)
			(xy 333.13688 -98.206177) (xy 333.178072 -98.170484) (xy 333.223924 -98.141017) (xy 333.273504 -98.118375)
			(xy 333.325801 -98.103019) (xy 333.379752 -98.095263) (xy 333.407004 -98.0948) (xy 333.433318 -98.095265)
			(xy 333.485447 -98.1025) (xy 333.536089 -98.11682) (xy 333.584288 -98.137953) (xy 333.629132 -98.165499)
			(xy 333.669771 -98.198938) (xy 333.687928 -98.21799) (xy 333.695439 -98.225404) (xy 333.714727 -98.233922)
			(xy 333.725266 -98.2345) (xy 333.799942 -98.2345) (xy 333.81049 -98.233953) (xy 333.829785 -98.225431)
			(xy 333.83728 -98.21799) (xy 333.85545 -98.198949) (xy 333.896077 -98.165491) (xy 333.940914 -98.13793)
			(xy 333.989112 -98.116789) (xy 334.039757 -98.102469) (xy 334.091889 -98.095241) (xy 334.118204 -98.0948)
			(xy 334.145456 -98.09527) (xy 334.199404 -98.103027) (xy 334.251699 -98.118383) (xy 334.301277 -98.141025)
			(xy 334.347128 -98.170492) (xy 334.388319 -98.206184) (xy 334.424011 -98.247375) (xy 334.453477 -98.293226)
			(xy 334.473172 -98.336354) (xy 335.049368 -98.336354) (xy 335.049849 -98.308984) (xy 335.057661 -98.254805)
			(xy 335.073145 -98.202301) (xy 335.095984 -98.152554) (xy 335.125707 -98.106587) (xy 335.143348 -98.085656)
			(xy 335.143602 -98.085402) (xy 335.149194 -98.078319) (xy 335.155437 -98.0614) (xy 335.155794 -98.052382)
			(xy 335.155794 -97.985326) (xy 335.155426 -97.97631) (xy 335.149186 -97.959393) (xy 335.143602 -97.952306)
			(xy 335.143348 -97.952306) (xy 335.143348 -97.952052) (xy 335.125661 -97.931156) (xy 335.095937 -97.885182)
			(xy 335.073093 -97.83543) (xy 335.057599 -97.782922) (xy 335.049775 -97.728738) (xy 335.049779 -97.673992)
			(xy 335.057614 -97.61981) (xy 335.073117 -97.567305) (xy 335.09597 -97.517557) (xy 335.125703 -97.471588)
			(xy 335.143348 -97.450656) (xy 335.143602 -97.450402) (xy 335.149194 -97.443319) (xy 335.155437 -97.4264)
			(xy 335.155794 -97.417382) (xy 335.155794 -97.350326) (xy 335.155426 -97.34131) (xy 335.149186 -97.324393)
			(xy 335.143602 -97.317306) (xy 335.143348 -97.317306) (xy 335.143348 -97.317052) (xy 335.125727 -97.296105)
			(xy 335.096011 -97.250137) (xy 335.073171 -97.200393) (xy 335.057676 -97.147896) (xy 335.049844 -97.093722)
			(xy 335.049368 -97.066354) (xy 335.049854 -97.039103) (xy 335.05761 -96.985155) (xy 335.072965 -96.93286)
			(xy 335.095607 -96.883283) (xy 335.125073 -96.837433) (xy 335.160764 -96.796242) (xy 335.201955 -96.760551)
			(xy 335.247805 -96.731085) (xy 335.297382 -96.708443) (xy 335.349677 -96.693088) (xy 335.403625 -96.685332)
			(xy 335.458127 -96.685332) (xy 335.512075 -96.693088) (xy 335.56437 -96.708443) (xy 335.613947 -96.731085)
			(xy 335.659797 -96.760551) (xy 335.700988 -96.796242) (xy 335.736679 -96.837433) (xy 335.766145 -96.883283)
			(xy 335.788787 -96.93286) (xy 335.804142 -96.985155) (xy 335.811898 -97.039103) (xy 335.812384 -97.066354)
			(xy 335.811895 -97.093723) (xy 335.804083 -97.147902) (xy 335.7886 -97.200405) (xy 335.765763 -97.250152)
			(xy 335.736043 -97.29612) (xy 335.718404 -97.317052) (xy 335.71815 -97.317306) (xy 335.712549 -97.324382)
			(xy 335.706312 -97.341307) (xy 335.705958 -97.350326) (xy 335.705958 -97.417382) (xy 335.706311 -97.4264)
			(xy 335.71256 -97.443317) (xy 335.71815 -97.450402) (xy 335.718404 -97.450402) (xy 335.718404 -97.450656)
			(xy 335.735998 -97.471626) (xy 335.765723 -97.517588) (xy 335.788569 -97.567328) (xy 335.804067 -97.619824)
			(xy 335.8119 -97.673997) (xy 335.811904 -97.728733) (xy 335.804082 -97.782908) (xy 335.788593 -97.835407)
			(xy 335.765756 -97.885151) (xy 335.73604 -97.931119) (xy 335.718404 -97.952052) (xy 335.71815 -97.952306)
			(xy 335.712549 -97.959382) (xy 335.706312 -97.976307) (xy 335.705958 -97.985326) (xy 335.705958 -98.052382)
			(xy 335.706311 -98.0614) (xy 335.71256 -98.078317) (xy 335.71815 -98.085402) (xy 335.718404 -98.085402)
			(xy 335.718404 -98.085656) (xy 335.736037 -98.106593) (xy 335.765749 -98.152565) (xy 335.788586 -98.202311)
			(xy 335.792404 -98.215249) (xy 337.158596 -98.215249) (xy 337.158596 -98.160751) (xy 337.166352 -98.106807)
			(xy 337.181705 -98.054516) (xy 337.204344 -98.004942) (xy 337.233808 -97.959095) (xy 337.269496 -97.917907)
			(xy 337.310682 -97.882217) (xy 337.356528 -97.852752) (xy 337.406101 -97.830111) (xy 337.458391 -97.814755)
			(xy 337.512335 -97.806997) (xy 337.539584 -97.80651) (xy 337.569852 -97.807077) (xy 337.629627 -97.816648)
			(xy 337.687141 -97.835535) (xy 337.740952 -97.863266) (xy 337.78971 -97.899145) (xy 337.811364 -97.920302)
			(xy 337.818785 -97.927252) (xy 337.837527 -97.935099) (xy 337.847686 -97.935542) (xy 337.919822 -97.935542)
			(xy 337.929984 -97.935129) (xy 337.94872 -97.927256) (xy 337.956144 -97.920302) (xy 337.977796 -97.899144)
			(xy 338.026551 -97.863261) (xy 338.080363 -97.83553) (xy 338.137879 -97.816648) (xy 338.197656 -97.807089)
			(xy 338.227924 -97.80651) (xy 338.25776 -97.807056) (xy 338.316701 -97.816363) (xy 338.373475 -97.83473)
			(xy 338.426699 -97.861709) (xy 338.475075 -97.896644) (xy 338.496656 -97.917254) (xy 338.503768 -97.924366)
			(xy 338.52231 -97.931986) (xy 338.614004 -97.931986) (xy 338.632546 -97.924366) (xy 338.639658 -97.917254)
			(xy 338.661247 -97.896655) (xy 338.709619 -97.861718) (xy 338.762841 -97.834741) (xy 338.819615 -97.816382)
			(xy 338.878556 -97.807088) (xy 338.90839 -97.80651) (xy 338.935645 -97.806936) (xy 338.989599 -97.814692)
			(xy 339.041901 -97.830048) (xy 339.091485 -97.852691) (xy 339.137341 -97.88216) (xy 339.178537 -97.917856)
			(xy 339.214234 -97.959051) (xy 339.243704 -98.004907) (xy 339.266348 -98.05449) (xy 339.281705 -98.106791)
			(xy 339.289463 -98.160745) (xy 339.289463 -98.215255) (xy 339.281705 -98.269209) (xy 339.266348 -98.32151)
			(xy 339.243704 -98.371093) (xy 339.214234 -98.416949) (xy 339.178537 -98.458144) (xy 339.137341 -98.49384)
			(xy 339.091485 -98.523309) (xy 339.041901 -98.545952) (xy 338.989599 -98.561308) (xy 338.935645 -98.569064)
			(xy 338.90839 -98.569526) (xy 338.878555 -98.56896) (xy 338.819615 -98.559657) (xy 338.762842 -98.541294)
			(xy 338.709617 -98.514319) (xy 338.66124 -98.47939) (xy 338.639658 -98.458782) (xy 338.632546 -98.45167)
			(xy 338.614004 -98.44405) (xy 338.52231 -98.44405) (xy 338.503768 -98.45167) (xy 338.496656 -98.458782)
			(xy 338.475094 -98.479412) (xy 338.426716 -98.514346) (xy 338.373487 -98.541319) (xy 338.316707 -98.559671)
			(xy 338.25776 -98.568954) (xy 338.227924 -98.569526) (xy 338.197657 -98.568944) (xy 338.137883 -98.559375)
			(xy 338.080369 -98.540491) (xy 338.026558 -98.512763) (xy 337.977799 -98.476889) (xy 337.956144 -98.455734)
			(xy 337.948716 -98.448792) (xy 337.92998 -98.440939) (xy 337.919822 -98.440494) (xy 337.847686 -98.440494)
			(xy 337.837523 -98.440902) (xy 337.818786 -98.448778) (xy 337.811364 -98.455734) (xy 337.789714 -98.476895)
			(xy 337.740958 -98.512776) (xy 337.687146 -98.540506) (xy 337.629629 -98.559387) (xy 337.569852 -98.568947)
			(xy 337.539584 -98.569526) (xy 337.512335 -98.569003) (xy 337.458391 -98.561245) (xy 337.406101 -98.545889)
			(xy 337.356528 -98.523248) (xy 337.310682 -98.493783) (xy 337.269496 -98.458093) (xy 337.233808 -98.416905)
			(xy 337.204344 -98.371058) (xy 337.181705 -98.321484) (xy 337.166352 -98.269193) (xy 337.158596 -98.215249)
			(xy 335.792404 -98.215249) (xy 335.804079 -98.25481) (xy 335.811909 -98.308985) (xy 335.812384 -98.336354)
			(xy 335.811898 -98.363605) (xy 335.804142 -98.417553) (xy 335.788787 -98.469848) (xy 335.766145 -98.519425)
			(xy 335.736679 -98.565275) (xy 335.700988 -98.606466) (xy 335.659797 -98.642157) (xy 335.613947 -98.671623)
			(xy 335.56437 -98.694265) (xy 335.512075 -98.70962) (xy 335.458127 -98.717376) (xy 335.403625 -98.717376)
			(xy 335.349677 -98.70962) (xy 335.297382 -98.694265) (xy 335.247805 -98.671623) (xy 335.201955 -98.642157)
			(xy 335.160764 -98.606466) (xy 335.125073 -98.565275) (xy 335.095607 -98.519425) (xy 335.072965 -98.469848)
			(xy 335.05761 -98.417553) (xy 335.049854 -98.363605) (xy 335.049368 -98.336354) (xy 334.473172 -98.336354)
			(xy 334.476118 -98.342804) (xy 334.491474 -98.3951) (xy 334.49923 -98.449048) (xy 334.49923 -98.503552)
			(xy 334.491474 -98.5575) (xy 334.476118 -98.609796) (xy 334.453477 -98.659374) (xy 334.424011 -98.705225)
			(xy 334.388319 -98.746416) (xy 334.347128 -98.782108) (xy 334.301277 -98.811575) (xy 334.251699 -98.834217)
			(xy 334.199404 -98.849573) (xy 334.145456 -98.85733) (xy 334.118204 -98.857816) (xy 334.09189 -98.857341)
			(xy 334.039762 -98.850107) (xy 333.98912 -98.835789) (xy 333.940921 -98.814658) (xy 333.896077 -98.787113)
			(xy 333.855437 -98.753677) (xy 333.83728 -98.734626) (xy 333.829764 -98.727217) (xy 333.81048 -98.718696)
			(xy 333.799942 -98.718116) (xy 333.725266 -98.718116) (xy 333.714718 -98.718663) (xy 333.695422 -98.727185)
			(xy 333.687928 -98.734626) (xy 333.669757 -98.753666) (xy 333.62913 -98.787123) (xy 333.584293 -98.814684)
			(xy 333.536095 -98.835825) (xy 333.485451 -98.850146) (xy 333.433319 -98.857375) (xy 333.407004 -98.857816)
			(xy 333.379752 -98.857337) (xy 333.325801 -98.849581) (xy 333.273504 -98.834225) (xy 333.223924 -98.811583)
			(xy 333.178072 -98.782116) (xy 333.13688 -98.746423) (xy 333.101186 -98.705231) (xy 333.071718 -98.659379)
			(xy 333.049076 -98.6098) (xy 333.03372 -98.557503) (xy 333.025963 -98.503552) (xy 332.036031 -98.503552)
			(xy 332.039976 -98.508566) (xy 332.04023 -98.509074) (xy 332.051175 -98.521807) (xy 332.071016 -98.548899)
			(xy 332.079854 -98.563176) (xy 332.085188 -98.572066) (xy 332.102206 -98.584258) (xy 332.195424 -98.604578)
			(xy 332.215998 -98.60026) (xy 332.224634 -98.594418) (xy 332.248689 -98.578403) (xy 332.300623 -98.553064)
			(xy 332.355784 -98.535842) (xy 332.412911 -98.527132) (xy 332.441804 -98.5266) (xy 332.469056 -98.52707)
			(xy 332.523004 -98.534827) (xy 332.575299 -98.550183) (xy 332.624877 -98.572825) (xy 332.670728 -98.602292)
			(xy 332.711919 -98.637984) (xy 332.747611 -98.679175) (xy 332.777077 -98.725026) (xy 332.799718 -98.774604)
			(xy 332.815074 -98.8269) (xy 332.82283 -98.880848) (xy 332.82283 -98.935352) (xy 332.815074 -98.9893)
			(xy 332.799718 -99.041596) (xy 332.777077 -99.091174) (xy 332.747611 -99.137025) (xy 332.711919 -99.178216)
			(xy 332.670728 -99.213908) (xy 332.624877 -99.243375) (xy 332.575299 -99.266017) (xy 332.523004 -99.281373)
			(xy 332.469056 -99.28913) (xy 332.441804 -99.289616) (xy 332.413713 -99.289119) (xy 332.358135 -99.280892)
			(xy 332.304367 -99.264601) (xy 332.253569 -99.240599) (xy 332.206842 -99.209405) (xy 332.165197 -99.171693)
			(xy 332.129535 -99.12828) (xy 332.114652 -99.10445) (xy 332.109318 -99.09556) (xy 332.0923 -99.083368)
			(xy 331.999082 -99.063048) (xy 331.978508 -99.067366) (xy 331.969872 -99.073208) (xy 331.945818 -99.089223)
			(xy 331.893883 -99.114562) (xy 331.838722 -99.131784) (xy 331.781595 -99.140494) (xy 331.752702 -99.141026)
			(xy 331.725452 -99.14052) (xy 331.671506 -99.132765) (xy 331.619212 -99.117411) (xy 331.569636 -99.094771)
			(xy 331.523787 -99.065307) (xy 331.482597 -99.029617) (xy 331.446905 -98.988429) (xy 331.417439 -98.942581)
			(xy 331.394796 -98.893007) (xy 331.37944 -98.840714) (xy 331.371681 -98.786768) (xy 331.371194 -98.759518)
			(xy 283.567124 -98.759518) (xy 283.567124 -100.17633) (xy 285.8389 -100.17633) (xy 285.8389 -99.31273)
			(xy 285.83939 -99.282746) (xy 285.847218 -99.22329) (xy 285.862739 -99.165365) (xy 285.885688 -99.109961)
			(xy 285.915672 -99.058027) (xy 285.952178 -99.010451) (xy 285.994583 -98.968046) (xy 286.042159 -98.93154)
			(xy 286.094093 -98.901556) (xy 286.149497 -98.878607) (xy 286.207422 -98.863086) (xy 286.266878 -98.855258)
			(xy 286.326846 -98.855258) (xy 286.386302 -98.863086) (xy 286.444227 -98.878607) (xy 286.499631 -98.901556)
			(xy 286.551565 -98.93154) (xy 286.599141 -98.968046) (xy 286.641546 -99.010451) (xy 286.678052 -99.058027)
			(xy 286.708036 -99.109961) (xy 286.730985 -99.165365) (xy 286.746506 -99.22329) (xy 286.754334 -99.282746)
			(xy 286.754824 -99.31273) (xy 286.754824 -99.739704) (xy 302.321974 -99.739704) (xy 302.326045 -99.684082)
			(xy 302.338171 -99.629645) (xy 302.358094 -99.577554) (xy 302.38539 -99.528919) (xy 302.419476 -99.484776)
			(xy 302.459625 -99.446067) (xy 302.504983 -99.413616) (xy 302.554583 -99.388115) (xy 302.607367 -99.370108)
			(xy 302.66221 -99.359978) (xy 302.717944 -99.357941) (xy 302.773381 -99.364041) (xy 302.827338 -99.378147)
			(xy 302.878667 -99.399959) (xy 302.926273 -99.429013) (xy 302.939456 -99.439984) (xy 307.509924 -99.439984)
			(xy 307.513995 -99.384362) (xy 307.526121 -99.329925) (xy 307.546044 -99.277834) (xy 307.57334 -99.229199)
			(xy 307.607426 -99.185056) (xy 307.647575 -99.146347) (xy 307.692933 -99.113896) (xy 307.742533 -99.088395)
			(xy 307.795317 -99.070388) (xy 307.85016 -99.060258) (xy 307.905894 -99.058221) (xy 307.961331 -99.064321)
			(xy 308.015288 -99.078427) (xy 308.066617 -99.100239) (xy 308.114223 -99.129293) (xy 308.157091 -99.164968)
			(xy 308.194308 -99.206505) (xy 308.225081 -99.253018) (xy 308.248753 -99.303515) (xy 308.264821 -99.356922)
			(xy 308.272941 -99.412098) (xy 308.27345 -99.439984) (xy 308.273278 -99.449382) (xy 320.106038 -99.449382)
			(xy 320.110109 -99.39376) (xy 320.122235 -99.339323) (xy 320.142158 -99.287232) (xy 320.169454 -99.238597)
			(xy 320.20354 -99.194454) (xy 320.243689 -99.155745) (xy 320.289047 -99.123294) (xy 320.338647 -99.097793)
			(xy 320.391431 -99.079786) (xy 320.446274 -99.069656) (xy 320.502008 -99.067619) (xy 320.557445 -99.073719)
			(xy 320.611402 -99.087825) (xy 320.662731 -99.109637) (xy 320.710337 -99.138691) (xy 320.753205 -99.174366)
			(xy 320.790422 -99.215903) (xy 320.821195 -99.262416) (xy 320.844867 -99.312913) (xy 320.860935 -99.36632)
			(xy 320.869055 -99.421496) (xy 320.869564 -99.449382) (xy 320.869397 -99.458526) (xy 325.838564 -99.458526)
			(xy 325.842635 -99.402904) (xy 325.854761 -99.348467) (xy 325.874684 -99.296376) (xy 325.90198 -99.247741)
			(xy 325.936066 -99.203598) (xy 325.976215 -99.164889) (xy 326.021573 -99.132438) (xy 326.071173 -99.106937)
			(xy 326.123957 -99.08893) (xy 326.1788 -99.0788) (xy 326.234534 -99.076763) (xy 326.289971 -99.082863)
			(xy 326.343928 -99.096969) (xy 326.395257 -99.118781) (xy 326.442863 -99.147835) (xy 326.485731 -99.18351)
			(xy 326.522948 -99.225047) (xy 326.553721 -99.27156) (xy 326.577393 -99.322057) (xy 326.593461 -99.375464)
			(xy 326.601581 -99.43064) (xy 326.60209 -99.458526) (xy 326.601581 -99.486412) (xy 326.593461 -99.541588)
			(xy 326.577393 -99.594995) (xy 326.553721 -99.645492) (xy 326.522948 -99.692005) (xy 326.485731 -99.733542)
			(xy 326.442863 -99.769217) (xy 326.395257 -99.798271) (xy 326.343928 -99.820083) (xy 326.289971 -99.834189)
			(xy 326.234534 -99.840289) (xy 326.1788 -99.838252) (xy 326.123957 -99.828122) (xy 326.071173 -99.810115)
			(xy 326.021573 -99.784614) (xy 325.976215 -99.752163) (xy 325.936066 -99.713454) (xy 325.90198 -99.669311)
			(xy 325.874684 -99.620676) (xy 325.854761 -99.568585) (xy 325.842635 -99.514148) (xy 325.838564 -99.458526)
			(xy 320.869397 -99.458526) (xy 320.869055 -99.477268) (xy 320.860935 -99.532444) (xy 320.844867 -99.585851)
			(xy 320.821195 -99.636348) (xy 320.790422 -99.682861) (xy 320.753205 -99.724398) (xy 320.710337 -99.760073)
			(xy 320.662731 -99.789127) (xy 320.611402 -99.810939) (xy 320.557445 -99.825045) (xy 320.502008 -99.831145)
			(xy 320.446274 -99.829108) (xy 320.391431 -99.818978) (xy 320.338647 -99.800971) (xy 320.289047 -99.77547)
			(xy 320.243689 -99.743019) (xy 320.20354 -99.70431) (xy 320.169454 -99.660167) (xy 320.142158 -99.611532)
			(xy 320.122235 -99.559441) (xy 320.110109 -99.505004) (xy 320.106038 -99.449382) (xy 308.273278 -99.449382)
			(xy 308.272941 -99.46787) (xy 308.264821 -99.523046) (xy 308.248753 -99.576453) (xy 308.225081 -99.62695)
			(xy 308.194308 -99.673463) (xy 308.157091 -99.715) (xy 308.114223 -99.750675) (xy 308.066617 -99.779729)
			(xy 308.015288 -99.801541) (xy 307.961331 -99.815647) (xy 307.905894 -99.821747) (xy 307.85016 -99.81971)
			(xy 307.795317 -99.80958) (xy 307.742533 -99.791573) (xy 307.692933 -99.766072) (xy 307.647575 -99.733621)
			(xy 307.607426 -99.694912) (xy 307.57334 -99.650769) (xy 307.546044 -99.602134) (xy 307.526121 -99.550043)
			(xy 307.513995 -99.495606) (xy 307.509924 -99.439984) (xy 302.939456 -99.439984) (xy 302.969141 -99.464688)
			(xy 303.006358 -99.506225) (xy 303.037131 -99.552738) (xy 303.060803 -99.603235) (xy 303.076871 -99.656642)
			(xy 303.084991 -99.711818) (xy 303.0855 -99.739704) (xy 303.084991 -99.76759) (xy 303.076871 -99.822766)
			(xy 303.060803 -99.876173) (xy 303.037131 -99.92667) (xy 303.006358 -99.973183) (xy 302.969141 -100.01472)
			(xy 302.938846 -100.039932) (xy 306.076856 -100.039932) (xy 306.080927 -99.98431) (xy 306.093053 -99.929873)
			(xy 306.112976 -99.877782) (xy 306.140272 -99.829147) (xy 306.174358 -99.785004) (xy 306.214507 -99.746295)
			(xy 306.259865 -99.713844) (xy 306.309465 -99.688343) (xy 306.362249 -99.670336) (xy 306.417092 -99.660206)
			(xy 306.472826 -99.658169) (xy 306.528263 -99.664269) (xy 306.58222 -99.678375) (xy 306.633549 -99.700187)
			(xy 306.681155 -99.729241) (xy 306.724023 -99.764916) (xy 306.76124 -99.806453) (xy 306.792013 -99.852966)
			(xy 306.815685 -99.903463) (xy 306.831753 -99.95687) (xy 306.839873 -100.012046) (xy 306.840382 -100.039932)
			(xy 306.839873 -100.067818) (xy 306.831753 -100.122994) (xy 306.815685 -100.176401) (xy 306.792013 -100.226898)
			(xy 306.76124 -100.273411) (xy 306.724023 -100.314948) (xy 306.681155 -100.350623) (xy 306.633549 -100.379677)
			(xy 306.58222 -100.401489) (xy 306.528263 -100.415595) (xy 306.472826 -100.421695) (xy 306.417092 -100.419658)
			(xy 306.362249 -100.409528) (xy 306.309465 -100.391521) (xy 306.259865 -100.36602) (xy 306.214507 -100.333569)
			(xy 306.174358 -100.29486) (xy 306.140272 -100.250717) (xy 306.112976 -100.202082) (xy 306.093053 -100.149991)
			(xy 306.080927 -100.095554) (xy 306.076856 -100.039932) (xy 302.938846 -100.039932) (xy 302.926273 -100.050395)
			(xy 302.878667 -100.079449) (xy 302.827338 -100.101261) (xy 302.773381 -100.115367) (xy 302.717944 -100.121467)
			(xy 302.66221 -100.11943) (xy 302.607367 -100.1093) (xy 302.554583 -100.091293) (xy 302.504983 -100.065792)
			(xy 302.459625 -100.033341) (xy 302.419476 -99.994632) (xy 302.38539 -99.950489) (xy 302.358094 -99.901854)
			(xy 302.338171 -99.849763) (xy 302.326045 -99.795326) (xy 302.321974 -99.739704) (xy 286.754824 -99.739704)
			(xy 286.754824 -100.17633) (xy 286.754334 -100.206314) (xy 286.746506 -100.26577) (xy 286.730985 -100.323695)
			(xy 286.708036 -100.379099) (xy 286.678052 -100.431033) (xy 286.641546 -100.478609) (xy 286.599141 -100.521014)
			(xy 286.551565 -100.55752) (xy 286.499631 -100.587504) (xy 286.444227 -100.610453) (xy 286.386302 -100.625974)
			(xy 286.326846 -100.633802) (xy 286.266878 -100.633802) (xy 286.207422 -100.625974) (xy 286.149497 -100.610453)
			(xy 286.094093 -100.587504) (xy 286.042159 -100.55752) (xy 285.994583 -100.521014) (xy 285.952178 -100.478609)
			(xy 285.915672 -100.431033) (xy 285.885688 -100.379099) (xy 285.862739 -100.323695) (xy 285.847218 -100.26577)
			(xy 285.83939 -100.206314) (xy 285.8389 -100.17633) (xy 283.567124 -100.17633) (xy 283.567124 -101.976428)
			(xy 283.9847 -101.976428) (xy 283.9847 -101.112828) (xy 283.98519 -101.082844) (xy 283.993018 -101.023388)
			(xy 284.008539 -100.965463) (xy 284.031488 -100.910059) (xy 284.061472 -100.858125) (xy 284.097978 -100.810549)
			(xy 284.140383 -100.768144) (xy 284.187959 -100.731638) (xy 284.239893 -100.701654) (xy 284.295297 -100.678705)
			(xy 284.353222 -100.663184) (xy 284.412678 -100.655356) (xy 284.472646 -100.655356) (xy 284.532102 -100.663184)
			(xy 284.590027 -100.678705) (xy 284.645431 -100.701654) (xy 284.697365 -100.731638) (xy 284.742632 -100.766372)
			(xy 289.797742 -100.766372) (xy 289.801813 -100.71075) (xy 289.813939 -100.656313) (xy 289.833862 -100.604222)
			(xy 289.861158 -100.555587) (xy 289.895244 -100.511444) (xy 289.935393 -100.472735) (xy 289.980751 -100.440284)
			(xy 290.030351 -100.414783) (xy 290.083135 -100.396776) (xy 290.137978 -100.386646) (xy 290.193712 -100.384609)
			(xy 290.249149 -100.390709) (xy 290.303106 -100.404815) (xy 290.354435 -100.426627) (xy 290.402041 -100.455681)
			(xy 290.444909 -100.491356) (xy 290.482126 -100.532893) (xy 290.512899 -100.579406) (xy 290.536571 -100.629903)
			(xy 290.552639 -100.68331) (xy 290.560759 -100.738486) (xy 290.561268 -100.766372) (xy 290.560759 -100.794258)
			(xy 290.552639 -100.849434) (xy 290.536571 -100.902841) (xy 290.512899 -100.953338) (xy 290.482126 -100.999851)
			(xy 290.444909 -101.041388) (xy 290.402041 -101.077063) (xy 290.354435 -101.106117) (xy 290.303106 -101.127929)
			(xy 290.249149 -101.142035) (xy 290.193712 -101.148135) (xy 290.137978 -101.146098) (xy 290.083135 -101.135968)
			(xy 290.030351 -101.117961) (xy 289.980751 -101.09246) (xy 289.935393 -101.060009) (xy 289.895244 -101.0213)
			(xy 289.861158 -100.977157) (xy 289.833862 -100.928522) (xy 289.813939 -100.876431) (xy 289.801813 -100.821994)
			(xy 289.797742 -100.766372) (xy 284.742632 -100.766372) (xy 284.744941 -100.768144) (xy 284.787346 -100.810549)
			(xy 284.823852 -100.858125) (xy 284.853836 -100.910059) (xy 284.876785 -100.965463) (xy 284.892306 -101.023388)
			(xy 284.900134 -101.082844) (xy 284.900624 -101.112828) (xy 284.900624 -101.240082) (xy 306.493924 -101.240082)
			(xy 306.497995 -101.18446) (xy 306.510121 -101.130023) (xy 306.530044 -101.077932) (xy 306.55734 -101.029297)
			(xy 306.591426 -100.985154) (xy 306.631575 -100.946445) (xy 306.676933 -100.913994) (xy 306.726533 -100.888493)
			(xy 306.779317 -100.870486) (xy 306.83416 -100.860356) (xy 306.889894 -100.858319) (xy 306.945331 -100.864419)
			(xy 306.999288 -100.878525) (xy 307.050617 -100.900337) (xy 307.098223 -100.929391) (xy 307.141091 -100.965066)
			(xy 307.178308 -101.006603) (xy 307.209081 -101.053116) (xy 307.216831 -101.069648) (xy 307.786276 -101.069648)
			(xy 307.790347 -101.014026) (xy 307.802473 -100.959589) (xy 307.822396 -100.907498) (xy 307.849692 -100.858863)
			(xy 307.883778 -100.81472) (xy 307.923927 -100.776011) (xy 307.969285 -100.74356) (xy 308.018885 -100.718059)
			(xy 308.071669 -100.700052) (xy 308.126512 -100.689922) (xy 308.182246 -100.687885) (xy 308.237683 -100.693985)
			(xy 308.29164 -100.708091) (xy 308.342969 -100.729903) (xy 308.390575 -100.758957) (xy 308.433443 -100.794632)
			(xy 308.47066 -100.836169) (xy 308.501433 -100.882682) (xy 308.525105 -100.933179) (xy 308.541173 -100.986586)
			(xy 308.549293 -101.041762) (xy 308.549802 -101.069648) (xy 310.369456 -101.069648) (xy 310.373527 -101.014026)
			(xy 310.385653 -100.959589) (xy 310.405576 -100.907498) (xy 310.432872 -100.858863) (xy 310.466958 -100.81472)
			(xy 310.507107 -100.776011) (xy 310.552465 -100.74356) (xy 310.602065 -100.718059) (xy 310.654849 -100.700052)
			(xy 310.709692 -100.689922) (xy 310.765426 -100.687885) (xy 310.820863 -100.693985) (xy 310.87482 -100.708091)
			(xy 310.926149 -100.729903) (xy 310.973755 -100.758957) (xy 311.016623 -100.794632) (xy 311.05384 -100.836169)
			(xy 311.084613 -100.882682) (xy 311.108285 -100.933179) (xy 311.124353 -100.986586) (xy 311.132473 -101.041762)
			(xy 311.132982 -101.069648) (xy 311.132473 -101.097534) (xy 311.124353 -101.15271) (xy 311.113179 -101.18985)
			(xy 329.19339 -101.18985) (xy 329.19339 -101.13535) (xy 329.201146 -101.081404) (xy 329.216501 -101.029111)
			(xy 329.239141 -100.979536) (xy 329.268606 -100.933687) (xy 329.304297 -100.892498) (xy 329.345485 -100.856808)
			(xy 329.391334 -100.827342) (xy 329.440909 -100.804702) (xy 329.493202 -100.789347) (xy 329.547148 -100.78159)
			(xy 329.574398 -100.781104) (xy 329.601768 -100.78157) (xy 329.655947 -100.789388) (xy 329.708451 -100.804877)
			(xy 329.758197 -100.827719) (xy 329.804164 -100.857443) (xy 329.825096 -100.875084) (xy 329.82535 -100.875338)
			(xy 329.832444 -100.880914) (xy 329.849355 -100.887166) (xy 329.85837 -100.88753) (xy 329.925426 -100.88753)
			(xy 329.934443 -100.887179) (xy 329.95136 -100.880927) (xy 329.958446 -100.875338) (xy 329.958446 -100.875084)
			(xy 329.9587 -100.875084) (xy 329.979619 -100.857429) (xy 330.025596 -100.82772) (xy 330.075347 -100.804887)
			(xy 330.12785 -100.7894) (xy 330.182028 -100.781576) (xy 330.209398 -100.781104) (xy 330.236652 -100.781543)
			(xy 330.290605 -100.7893) (xy 330.342905 -100.804656) (xy 330.392487 -100.827299) (xy 330.438341 -100.856768)
			(xy 330.479536 -100.892463) (xy 330.515231 -100.933657) (xy 330.5447 -100.979512) (xy 330.567343 -101.029094)
			(xy 330.5827 -101.081393) (xy 330.590457 -101.135346) (xy 330.590457 -101.189854) (xy 330.5827 -101.243807)
			(xy 330.567343 -101.296106) (xy 330.5447 -101.345688) (xy 330.515231 -101.391543) (xy 330.479536 -101.432737)
			(xy 330.438341 -101.468432) (xy 330.392487 -101.497901) (xy 330.342905 -101.520544) (xy 330.290605 -101.5359)
			(xy 330.236652 -101.543657) (xy 330.209398 -101.54412) (xy 330.182027 -101.543675) (xy 330.127846 -101.535855)
			(xy 330.075342 -101.520362) (xy 330.025595 -101.497515) (xy 329.97963 -101.467784) (xy 329.9587 -101.45014)
			(xy 329.958446 -101.449886) (xy 329.951352 -101.444311) (xy 329.934441 -101.438058) (xy 329.925426 -101.437694)
			(xy 329.85837 -101.437694) (xy 329.849352 -101.438038) (xy 329.832435 -101.444295) (xy 329.82535 -101.449886)
			(xy 329.82535 -101.45014) (xy 329.825096 -101.45014) (xy 329.804182 -101.467801) (xy 329.758203 -101.497508)
			(xy 329.708451 -101.520339) (xy 329.655947 -101.535826) (xy 329.601768 -101.543649) (xy 329.574398 -101.54412)
			(xy 329.547148 -101.54361) (xy 329.493202 -101.535853) (xy 329.440909 -101.520498) (xy 329.391334 -101.497858)
			(xy 329.345485 -101.468392) (xy 329.304297 -101.432702) (xy 329.268606 -101.391513) (xy 329.239141 -101.345664)
			(xy 329.216501 -101.296089) (xy 329.201146 -101.243796) (xy 329.19339 -101.18985) (xy 311.113179 -101.18985)
			(xy 311.108285 -101.206117) (xy 311.084613 -101.256614) (xy 311.05384 -101.303127) (xy 311.016623 -101.344664)
			(xy 310.973755 -101.380339) (xy 310.926149 -101.409393) (xy 310.87482 -101.431205) (xy 310.820863 -101.445311)
			(xy 310.765426 -101.451411) (xy 310.709692 -101.449374) (xy 310.654849 -101.439244) (xy 310.602065 -101.421237)
			(xy 310.552465 -101.395736) (xy 310.507107 -101.363285) (xy 310.466958 -101.324576) (xy 310.432872 -101.280433)
			(xy 310.405576 -101.231798) (xy 310.385653 -101.179707) (xy 310.373527 -101.12527) (xy 310.369456 -101.069648)
			(xy 308.549802 -101.069648) (xy 308.549293 -101.097534) (xy 308.541173 -101.15271) (xy 308.525105 -101.206117)
			(xy 308.501433 -101.256614) (xy 308.47066 -101.303127) (xy 308.433443 -101.344664) (xy 308.390575 -101.380339)
			(xy 308.342969 -101.409393) (xy 308.29164 -101.431205) (xy 308.237683 -101.445311) (xy 308.182246 -101.451411)
			(xy 308.126512 -101.449374) (xy 308.071669 -101.439244) (xy 308.018885 -101.421237) (xy 307.969285 -101.395736)
			(xy 307.923927 -101.363285) (xy 307.883778 -101.324576) (xy 307.849692 -101.280433) (xy 307.822396 -101.231798)
			(xy 307.802473 -101.179707) (xy 307.790347 -101.12527) (xy 307.786276 -101.069648) (xy 307.216831 -101.069648)
			(xy 307.232753 -101.103613) (xy 307.248821 -101.15702) (xy 307.256941 -101.212196) (xy 307.25745 -101.240082)
			(xy 307.256941 -101.267968) (xy 307.248821 -101.323144) (xy 307.232753 -101.376551) (xy 307.209081 -101.427048)
			(xy 307.178308 -101.473561) (xy 307.141091 -101.515098) (xy 307.098223 -101.550773) (xy 307.05169 -101.579172)
			(xy 319.970656 -101.579172) (xy 319.974727 -101.52355) (xy 319.986853 -101.469113) (xy 320.006776 -101.417022)
			(xy 320.034072 -101.368387) (xy 320.068158 -101.324244) (xy 320.108307 -101.285535) (xy 320.153665 -101.253084)
			(xy 320.203265 -101.227583) (xy 320.256049 -101.209576) (xy 320.310892 -101.199446) (xy 320.366626 -101.197409)
			(xy 320.422063 -101.203509) (xy 320.47602 -101.217615) (xy 320.527349 -101.239427) (xy 320.574955 -101.268481)
			(xy 320.617823 -101.304156) (xy 320.65504 -101.345693) (xy 320.685813 -101.392206) (xy 320.709485 -101.442703)
			(xy 320.725553 -101.49611) (xy 320.733673 -101.551286) (xy 320.734182 -101.579172) (xy 320.733673 -101.607058)
			(xy 320.725553 -101.662234) (xy 320.709485 -101.715641) (xy 320.685813 -101.766138) (xy 320.65504 -101.812651)
			(xy 320.617823 -101.854188) (xy 320.597905 -101.870764) (xy 325.439022 -101.870764) (xy 325.443093 -101.815142)
			(xy 325.455219 -101.760705) (xy 325.475142 -101.708614) (xy 325.502438 -101.659979) (xy 325.536524 -101.615836)
			(xy 325.576673 -101.577127) (xy 325.622031 -101.544676) (xy 325.671631 -101.519175) (xy 325.724415 -101.501168)
			(xy 325.779258 -101.491038) (xy 325.834992 -101.489001) (xy 325.890429 -101.495101) (xy 325.944386 -101.509207)
			(xy 325.995715 -101.531019) (xy 326.043321 -101.560073) (xy 326.086189 -101.595748) (xy 326.123406 -101.637285)
			(xy 326.154179 -101.683798) (xy 326.177851 -101.734295) (xy 326.193919 -101.787702) (xy 326.202039 -101.842878)
			(xy 326.202548 -101.870764) (xy 326.202039 -101.89865) (xy 326.193919 -101.953826) (xy 326.177851 -102.007233)
			(xy 326.154179 -102.05773) (xy 326.123406 -102.104243) (xy 326.099924 -102.130451) (xy 328.743052 -102.130451)
			(xy 328.743052 -102.075949) (xy 328.750808 -102.022001) (xy 328.766162 -101.969707) (xy 328.788801 -101.920129)
			(xy 328.818265 -101.874277) (xy 328.853954 -101.833086) (xy 328.895142 -101.797392) (xy 328.94099 -101.767922)
			(xy 328.990565 -101.745277) (xy 329.042858 -101.729917) (xy 329.096805 -101.722155) (xy 329.124056 -101.721666)
			(xy 329.151426 -101.722142) (xy 329.205605 -101.729955) (xy 329.258109 -101.745441) (xy 329.307856 -101.768281)
			(xy 329.353823 -101.798005) (xy 329.374754 -101.815646) (xy 329.375008 -101.8159) (xy 329.382088 -101.821496)
			(xy 329.39901 -101.827737) (xy 329.408028 -101.828092) (xy 329.475084 -101.828092) (xy 329.4841 -101.827729)
			(xy 329.501017 -101.821486) (xy 329.508104 -101.8159) (xy 329.508104 -101.815646) (xy 329.508358 -101.815646)
			(xy 329.529301 -101.79802) (xy 329.57527 -101.768305) (xy 329.625015 -101.745466) (xy 329.677513 -101.729972)
			(xy 329.731687 -101.722141) (xy 329.759056 -101.721666) (xy 329.786309 -101.722178) (xy 329.840261 -101.72993)
			(xy 329.892561 -101.745281) (xy 329.942143 -101.767919) (xy 329.987998 -101.797384) (xy 330.029194 -101.833075)
			(xy 330.06489 -101.874266) (xy 330.09436 -101.920118) (xy 330.117004 -101.969698) (xy 330.132361 -102.021996)
			(xy 330.140119 -102.075947) (xy 330.140119 -102.130453) (xy 330.132361 -102.184404) (xy 330.117004 -102.236702)
			(xy 330.09436 -102.286282) (xy 330.06489 -102.332134) (xy 330.029194 -102.373325) (xy 329.987998 -102.409016)
			(xy 329.942143 -102.438481) (xy 329.892561 -102.461119) (xy 329.840261 -102.47647) (xy 329.786309 -102.484222)
			(xy 329.759056 -102.484682) (xy 329.731687 -102.484187) (xy 329.677509 -102.476377) (xy 329.625006 -102.460895)
			(xy 329.575258 -102.438059) (xy 329.52929 -102.408341) (xy 329.508358 -102.390702) (xy 329.508104 -102.390448)
			(xy 329.501025 -102.384851) (xy 329.484102 -102.378612) (xy 329.475084 -102.378256) (xy 329.408028 -102.378256)
			(xy 329.399011 -102.378614) (xy 329.382093 -102.38486) (xy 329.375008 -102.390448) (xy 329.375008 -102.390702)
			(xy 329.374754 -102.390702) (xy 329.353813 -102.40833) (xy 329.307842 -102.438043) (xy 329.258097 -102.460881)
			(xy 329.205599 -102.476375) (xy 329.151425 -102.484206) (xy 329.124056 -102.484682) (xy 329.096805 -102.484245)
			(xy 329.042858 -102.476483) (xy 328.990565 -102.461123) (xy 328.94099 -102.438478) (xy 328.895142 -102.409008)
			(xy 328.853954 -102.373314) (xy 328.818265 -102.332123) (xy 328.788801 -102.286271) (xy 328.766162 -102.236693)
			(xy 328.750808 -102.184399) (xy 328.743052 -102.130451) (xy 326.099924 -102.130451) (xy 326.086189 -102.14578)
			(xy 326.043321 -102.181455) (xy 325.995715 -102.210509) (xy 325.944386 -102.232321) (xy 325.890429 -102.246427)
			(xy 325.834992 -102.252527) (xy 325.779258 -102.25049) (xy 325.724415 -102.24036) (xy 325.671631 -102.222353)
			(xy 325.622031 -102.196852) (xy 325.576673 -102.164401) (xy 325.536524 -102.125692) (xy 325.502438 -102.081549)
			(xy 325.475142 -102.032914) (xy 325.455219 -101.980823) (xy 325.443093 -101.926386) (xy 325.439022 -101.870764)
			(xy 320.597905 -101.870764) (xy 320.574955 -101.889863) (xy 320.527349 -101.918917) (xy 320.47602 -101.940729)
			(xy 320.422063 -101.954835) (xy 320.366626 -101.960935) (xy 320.310892 -101.958898) (xy 320.256049 -101.948768)
			(xy 320.203265 -101.930761) (xy 320.153665 -101.90526) (xy 320.108307 -101.872809) (xy 320.068158 -101.8341)
			(xy 320.034072 -101.789957) (xy 320.006776 -101.741322) (xy 319.986853 -101.689231) (xy 319.974727 -101.634794)
			(xy 319.970656 -101.579172) (xy 307.05169 -101.579172) (xy 307.050617 -101.579827) (xy 306.999288 -101.601639)
			(xy 306.945331 -101.615745) (xy 306.889894 -101.621845) (xy 306.83416 -101.619808) (xy 306.779317 -101.609678)
			(xy 306.726533 -101.591671) (xy 306.676933 -101.56617) (xy 306.631575 -101.533719) (xy 306.591426 -101.49501)
			(xy 306.55734 -101.450867) (xy 306.530044 -101.402232) (xy 306.510121 -101.350141) (xy 306.497995 -101.295704)
			(xy 306.493924 -101.240082) (xy 284.900624 -101.240082) (xy 284.900624 -101.976428) (xy 284.900134 -102.006412)
			(xy 284.892306 -102.065868) (xy 284.876785 -102.123793) (xy 284.853836 -102.179197) (xy 284.823852 -102.231131)
			(xy 284.787346 -102.278707) (xy 284.744941 -102.321112) (xy 284.697365 -102.357618) (xy 284.645431 -102.387602)
			(xy 284.590027 -102.410551) (xy 284.532102 -102.426072) (xy 284.472646 -102.4339) (xy 284.412678 -102.4339)
			(xy 284.353222 -102.426072) (xy 284.295297 -102.410551) (xy 284.239893 -102.387602) (xy 284.187959 -102.357618)
			(xy 284.140383 -102.321112) (xy 284.097978 -102.278707) (xy 284.061472 -102.231131) (xy 284.031488 -102.179197)
			(xy 284.008539 -102.123793) (xy 283.993018 -102.065868) (xy 283.98519 -102.006412) (xy 283.9847 -101.976428)
			(xy 283.567124 -101.976428) (xy 283.567124 -103.776272) (xy 285.8389 -103.776272) (xy 285.8389 -102.912672)
			(xy 285.83939 -102.882688) (xy 285.847218 -102.823232) (xy 285.862739 -102.765307) (xy 285.885688 -102.709903)
			(xy 285.915672 -102.657969) (xy 285.952178 -102.610393) (xy 285.994583 -102.567988) (xy 286.042159 -102.531482)
			(xy 286.094093 -102.501498) (xy 286.149497 -102.478549) (xy 286.207422 -102.463028) (xy 286.266878 -102.4552)
			(xy 286.326846 -102.4552) (xy 286.386302 -102.463028) (xy 286.444227 -102.478549) (xy 286.469458 -102.489)
			(xy 307.001924 -102.489) (xy 307.005995 -102.433378) (xy 307.018121 -102.378941) (xy 307.038044 -102.32685)
			(xy 307.06534 -102.278215) (xy 307.099426 -102.234072) (xy 307.139575 -102.195363) (xy 307.184933 -102.162912)
			(xy 307.234533 -102.137411) (xy 307.287317 -102.119404) (xy 307.34216 -102.109274) (xy 307.397894 -102.107237)
			(xy 307.453331 -102.113337) (xy 307.507288 -102.127443) (xy 307.558617 -102.149255) (xy 307.606223 -102.178309)
			(xy 307.649091 -102.213984) (xy 307.686308 -102.255521) (xy 307.717081 -102.302034) (xy 307.740753 -102.352531)
			(xy 307.756821 -102.405938) (xy 307.764941 -102.461114) (xy 307.76545 -102.489) (xy 307.764941 -102.516886)
			(xy 307.756821 -102.572062) (xy 307.740753 -102.625469) (xy 307.717081 -102.675966) (xy 307.686308 -102.722479)
			(xy 307.649091 -102.764016) (xy 307.606223 -102.799691) (xy 307.558617 -102.828745) (xy 307.507288 -102.850557)
			(xy 307.453331 -102.864663) (xy 307.397894 -102.870763) (xy 307.34216 -102.868726) (xy 307.287317 -102.858596)
			(xy 307.234533 -102.840589) (xy 307.184933 -102.815088) (xy 307.139575 -102.782637) (xy 307.099426 -102.743928)
			(xy 307.06534 -102.699785) (xy 307.038044 -102.65115) (xy 307.018121 -102.599059) (xy 307.005995 -102.544622)
			(xy 307.001924 -102.489) (xy 286.469458 -102.489) (xy 286.499631 -102.501498) (xy 286.551565 -102.531482)
			(xy 286.599141 -102.567988) (xy 286.641546 -102.610393) (xy 286.678052 -102.657969) (xy 286.708036 -102.709903)
			(xy 286.730985 -102.765307) (xy 286.746506 -102.823232) (xy 286.754334 -102.882688) (xy 286.754824 -102.912672)
			(xy 286.754824 -103.13924) (xy 321.707 -103.13924) (xy 321.711071 -103.083618) (xy 321.723197 -103.029181)
			(xy 321.74312 -102.97709) (xy 321.770416 -102.928455) (xy 321.804502 -102.884312) (xy 321.844651 -102.845603)
			(xy 321.890009 -102.813152) (xy 321.939609 -102.787651) (xy 321.992393 -102.769644) (xy 322.047236 -102.759514)
			(xy 322.10297 -102.757477) (xy 322.158407 -102.763577) (xy 322.212364 -102.777683) (xy 322.263693 -102.799495)
			(xy 322.311299 -102.828549) (xy 322.354167 -102.864224) (xy 322.391384 -102.905761) (xy 322.422157 -102.952274)
			(xy 322.445829 -103.002771) (xy 322.461897 -103.056178) (xy 322.470017 -103.111354) (xy 322.470526 -103.13924)
			(xy 322.470017 -103.167126) (xy 322.461897 -103.222302) (xy 322.445829 -103.275709) (xy 322.422157 -103.326206)
			(xy 322.391384 -103.372719) (xy 322.354167 -103.414256) (xy 322.311299 -103.449931) (xy 322.263693 -103.478985)
			(xy 322.212364 -103.500797) (xy 322.158407 -103.514903) (xy 322.10297 -103.521003) (xy 322.047236 -103.518966)
			(xy 321.992393 -103.508836) (xy 321.939609 -103.490829) (xy 321.890009 -103.465328) (xy 321.844651 -103.432877)
			(xy 321.804502 -103.394168) (xy 321.770416 -103.350025) (xy 321.74312 -103.30139) (xy 321.723197 -103.249299)
			(xy 321.711071 -103.194862) (xy 321.707 -103.13924) (xy 286.754824 -103.13924) (xy 286.754824 -103.776272)
			(xy 286.754334 -103.806256) (xy 286.746506 -103.865712) (xy 286.74107 -103.886) (xy 307.509924 -103.886)
			(xy 307.513995 -103.830378) (xy 307.526121 -103.775941) (xy 307.546044 -103.72385) (xy 307.57334 -103.675215)
			(xy 307.607426 -103.631072) (xy 307.647575 -103.592363) (xy 307.692933 -103.559912) (xy 307.742533 -103.534411)
			(xy 307.795317 -103.516404) (xy 307.85016 -103.506274) (xy 307.905894 -103.504237) (xy 307.961331 -103.510337)
			(xy 308.015288 -103.524443) (xy 308.066617 -103.546255) (xy 308.114223 -103.575309) (xy 308.157091 -103.610984)
			(xy 308.194308 -103.652521) (xy 308.225081 -103.699034) (xy 308.248753 -103.749531) (xy 308.264821 -103.802938)
			(xy 308.272941 -103.858114) (xy 308.27345 -103.886) (xy 308.272941 -103.913886) (xy 308.264821 -103.969062)
			(xy 308.248753 -104.022469) (xy 308.225081 -104.072966) (xy 308.194308 -104.119479) (xy 308.157091 -104.161016)
			(xy 308.114223 -104.196691) (xy 308.066617 -104.225745) (xy 308.015288 -104.247557) (xy 307.961331 -104.261663)
			(xy 307.905894 -104.267763) (xy 307.85016 -104.265726) (xy 307.795317 -104.255596) (xy 307.742533 -104.237589)
			(xy 307.692933 -104.212088) (xy 307.647575 -104.179637) (xy 307.607426 -104.140928) (xy 307.57334 -104.096785)
			(xy 307.546044 -104.04815) (xy 307.526121 -103.996059) (xy 307.513995 -103.941622) (xy 307.509924 -103.886)
			(xy 286.74107 -103.886) (xy 286.730985 -103.923637) (xy 286.708036 -103.979041) (xy 286.678052 -104.030975)
			(xy 286.641546 -104.078551) (xy 286.599141 -104.120956) (xy 286.551565 -104.157462) (xy 286.499631 -104.187446)
			(xy 286.444227 -104.210395) (xy 286.386302 -104.225916) (xy 286.326846 -104.233744) (xy 286.266878 -104.233744)
			(xy 286.207422 -104.225916) (xy 286.149497 -104.210395) (xy 286.094093 -104.187446) (xy 286.042159 -104.157462)
			(xy 285.994583 -104.120956) (xy 285.952178 -104.078551) (xy 285.915672 -104.030975) (xy 285.885688 -103.979041)
			(xy 285.862739 -103.923637) (xy 285.847218 -103.865712) (xy 285.83939 -103.806256) (xy 285.8389 -103.776272)
			(xy 283.567124 -103.776272) (xy 283.567124 -105.57637) (xy 283.9847 -105.57637) (xy 283.9847 -104.71277)
			(xy 283.98519 -104.682786) (xy 283.993018 -104.62333) (xy 284.008539 -104.565405) (xy 284.031488 -104.510001)
			(xy 284.061472 -104.458067) (xy 284.097978 -104.410491) (xy 284.140383 -104.368086) (xy 284.187959 -104.33158)
			(xy 284.239893 -104.301596) (xy 284.295297 -104.278647) (xy 284.353222 -104.263126) (xy 284.412678 -104.255298)
			(xy 284.472646 -104.255298) (xy 284.532102 -104.263126) (xy 284.590027 -104.278647) (xy 284.645431 -104.301596)
			(xy 284.697365 -104.33158) (xy 284.744941 -104.368086) (xy 284.787346 -104.410491) (xy 284.823852 -104.458067)
			(xy 284.853836 -104.510001) (xy 284.876785 -104.565405) (xy 284.892306 -104.62333) (xy 284.899099 -104.674924)
			(xy 320.759326 -104.674924) (xy 320.763397 -104.619302) (xy 320.775523 -104.564865) (xy 320.795446 -104.512774)
			(xy 320.822742 -104.464139) (xy 320.856828 -104.419996) (xy 320.896977 -104.381287) (xy 320.942335 -104.348836)
			(xy 320.991935 -104.323335) (xy 321.044719 -104.305328) (xy 321.099562 -104.295198) (xy 321.155296 -104.293161)
			(xy 321.210733 -104.299261) (xy 321.26469 -104.313367) (xy 321.316019 -104.335179) (xy 321.363625 -104.364233)
			(xy 321.406493 -104.399908) (xy 321.44371 -104.441445) (xy 321.474483 -104.487958) (xy 321.498155 -104.538455)
			(xy 321.514223 -104.591862) (xy 321.522343 -104.647038) (xy 321.522852 -104.674924) (xy 321.522343 -104.70281)
			(xy 321.514223 -104.757986) (xy 321.498155 -104.811393) (xy 321.474483 -104.86189) (xy 321.44371 -104.908403)
			(xy 321.406493 -104.94994) (xy 321.363625 -104.985615) (xy 321.316019 -105.014669) (xy 321.26469 -105.036481)
			(xy 321.210733 -105.050587) (xy 321.155296 -105.056687) (xy 321.099562 -105.05465) (xy 321.044719 -105.04452)
			(xy 320.991935 -105.026513) (xy 320.942335 -105.001012) (xy 320.896977 -104.968561) (xy 320.856828 -104.929852)
			(xy 320.822742 -104.885709) (xy 320.795446 -104.837074) (xy 320.775523 -104.784983) (xy 320.763397 -104.730546)
			(xy 320.759326 -104.674924) (xy 284.899099 -104.674924) (xy 284.900134 -104.682786) (xy 284.900624 -104.71277)
			(xy 284.900624 -105.57637) (xy 284.900134 -105.606354) (xy 284.892306 -105.66581) (xy 284.876785 -105.723735)
			(xy 284.853836 -105.779139) (xy 284.823852 -105.831073) (xy 284.787346 -105.878649) (xy 284.744941 -105.921054)
			(xy 284.697365 -105.95756) (xy 284.645431 -105.987544) (xy 284.590027 -106.010493) (xy 284.532102 -106.026014)
			(xy 284.472646 -106.033842) (xy 284.412678 -106.033842) (xy 284.353222 -106.026014) (xy 284.295297 -106.010493)
			(xy 284.239893 -105.987544) (xy 284.187959 -105.95756) (xy 284.140383 -105.921054) (xy 284.097978 -105.878649)
			(xy 284.061472 -105.831073) (xy 284.031488 -105.779139) (xy 284.008539 -105.723735) (xy 283.993018 -105.66581)
			(xy 283.98519 -105.606354) (xy 283.9847 -105.57637) (xy 283.567124 -105.57637) (xy 283.567124 -107.376214)
			(xy 285.8389 -107.376214) (xy 285.8389 -106.512614) (xy 285.83939 -106.48263) (xy 285.847218 -106.423174)
			(xy 285.862739 -106.365249) (xy 285.885688 -106.309845) (xy 285.915672 -106.257911) (xy 285.952178 -106.210335)
			(xy 285.994583 -106.16793) (xy 286.042159 -106.131424) (xy 286.094093 -106.10144) (xy 286.149497 -106.078491)
			(xy 286.207422 -106.06297) (xy 286.266878 -106.055142) (xy 286.326846 -106.055142) (xy 286.386302 -106.06297)
			(xy 286.444227 -106.078491) (xy 286.499631 -106.10144) (xy 286.551565 -106.131424) (xy 286.599141 -106.16793)
			(xy 286.641546 -106.210335) (xy 286.678052 -106.257911) (xy 286.708036 -106.309845) (xy 286.730985 -106.365249)
			(xy 286.746506 -106.423174) (xy 286.754334 -106.48263) (xy 286.754824 -106.512614) (xy 286.754824 -107.210352)
			(xy 297.165012 -107.210352) (xy 297.169083 -107.15473) (xy 297.181209 -107.100293) (xy 297.201132 -107.048202)
			(xy 297.228428 -106.999567) (xy 297.262514 -106.955424) (xy 297.302663 -106.916715) (xy 297.348021 -106.884264)
			(xy 297.397621 -106.858763) (xy 297.450405 -106.840756) (xy 297.505248 -106.830626) (xy 297.560982 -106.828589)
			(xy 297.616419 -106.834689) (xy 297.670376 -106.848795) (xy 297.721705 -106.870607) (xy 297.769311 -106.899661)
			(xy 297.812179 -106.935336) (xy 297.849396 -106.976873) (xy 297.880169 -107.023386) (xy 297.903841 -107.073883)
			(xy 297.919909 -107.12729) (xy 297.928029 -107.182466) (xy 297.928538 -107.210352) (xy 317.942722 -107.210352)
			(xy 317.943237 -107.181613) (xy 317.951865 -107.124786) (xy 317.968918 -107.069896) (xy 317.994011 -107.018185)
			(xy 318.026576 -106.970822) (xy 318.045846 -106.949494) (xy 318.05245 -106.942636) (xy 318.059562 -106.924602)
			(xy 318.059562 -106.835702) (xy 318.05245 -106.817668) (xy 318.045846 -106.81081) (xy 318.026527 -106.789525)
			(xy 317.993961 -106.742156) (xy 317.968871 -106.690438) (xy 317.951823 -106.63554) (xy 317.943204 -106.578707)
			(xy 317.94321 -106.521223) (xy 317.951839 -106.464391) (xy 317.968896 -106.409497) (xy 317.993996 -106.357783)
			(xy 318.026571 -106.31042) (xy 318.045846 -106.289094) (xy 318.05245 -106.282236) (xy 318.059562 -106.264202)
			(xy 318.059562 -106.175302) (xy 318.05245 -106.157268) (xy 318.045846 -106.15041) (xy 318.026554 -106.129101)
			(xy 317.99399 -106.081735) (xy 317.968902 -106.030018) (xy 317.951856 -105.975123) (xy 317.943239 -105.918292)
			(xy 317.942722 -105.889552) (xy 317.943208 -105.862301) (xy 317.950964 -105.808353) (xy 317.966319 -105.756058)
			(xy 317.988961 -105.706481) (xy 318.018427 -105.660631) (xy 318.054118 -105.61944) (xy 318.095309 -105.583749)
			(xy 318.141159 -105.554283) (xy 318.190736 -105.531641) (xy 318.243031 -105.516286) (xy 318.296979 -105.50853)
			(xy 318.351481 -105.50853) (xy 318.405429 -105.516286) (xy 318.457724 -105.531641) (xy 318.507301 -105.554283)
			(xy 318.553151 -105.583749) (xy 318.594342 -105.61944) (xy 318.630033 -105.660631) (xy 318.659499 -105.706481)
			(xy 318.682141 -105.756058) (xy 318.697496 -105.808353) (xy 318.705252 -105.862301) (xy 318.705738 -105.889552)
			(xy 318.705236 -105.918292) (xy 318.696606 -105.975119) (xy 318.679551 -106.03001) (xy 318.654455 -106.081721)
			(xy 318.621886 -106.129083) (xy 318.602614 -106.15041) (xy 318.59601 -106.157268) (xy 318.588898 -106.175302)
			(xy 318.588898 -106.264202) (xy 318.59601 -106.282236) (xy 318.602614 -106.289094) (xy 318.621836 -106.310463)
			(xy 318.654399 -106.357819) (xy 318.679491 -106.409524) (xy 318.696543 -106.464408) (xy 318.705169 -106.521229)
			(xy 318.705174 -106.578701) (xy 318.696558 -106.635523) (xy 318.679517 -106.69041) (xy 318.654434 -106.74212)
			(xy 318.62188 -106.789482) (xy 318.602614 -106.81081) (xy 318.59601 -106.817668) (xy 318.588898 -106.835702)
			(xy 318.588898 -106.924602) (xy 318.59601 -106.942636) (xy 318.602614 -106.949494) (xy 318.621901 -106.970807)
			(xy 318.654467 -107.018172) (xy 318.67389 -107.058206) (xy 321.773804 -107.058206) (xy 321.77433 -107.029467)
			(xy 321.782952 -106.97264) (xy 321.800001 -106.917749) (xy 321.825093 -106.866037) (xy 321.857657 -106.818675)
			(xy 321.876928 -106.797348) (xy 321.883532 -106.79049) (xy 321.890644 -106.772456) (xy 321.890644 -106.683556)
			(xy 321.883532 -106.665522) (xy 321.876928 -106.658664) (xy 321.857663 -106.637332) (xy 321.825097 -106.589971)
			(xy 321.800005 -106.53826) (xy 321.782954 -106.48337) (xy 321.774331 -106.426543) (xy 321.77433 -106.369066)
			(xy 321.782952 -106.312239) (xy 321.800002 -106.257348) (xy 321.825093 -106.205637) (xy 321.857657 -106.158275)
			(xy 321.876928 -106.136948) (xy 321.883532 -106.13009) (xy 321.890644 -106.112056) (xy 321.890644 -106.023156)
			(xy 321.883532 -106.005122) (xy 321.876928 -105.998264) (xy 321.857659 -105.976936) (xy 321.825092 -105.929574)
			(xy 321.8 -105.877863) (xy 321.782949 -105.822972) (xy 321.774325 -105.766145) (xy 321.773804 -105.737406)
			(xy 321.77429 -105.710155) (xy 321.782046 -105.656207) (xy 321.797401 -105.603912) (xy 321.820043 -105.554335)
			(xy 321.849509 -105.508485) (xy 321.8852 -105.467294) (xy 321.926391 -105.431603) (xy 321.972241 -105.402137)
			(xy 322.021818 -105.379495) (xy 322.074113 -105.36414) (xy 322.128061 -105.356384) (xy 322.182563 -105.356384)
			(xy 322.236511 -105.36414) (xy 322.288806 -105.379495) (xy 322.338383 -105.402137) (xy 322.384233 -105.431603)
			(xy 322.425424 -105.467294) (xy 322.461115 -105.508485) (xy 322.490581 -105.554335) (xy 322.513223 -105.603912)
			(xy 322.528578 -105.656207) (xy 322.536334 -105.710155) (xy 322.53682 -105.737406) (xy 322.536295 -105.766145)
			(xy 322.527672 -105.822972) (xy 322.510622 -105.877862) (xy 322.485531 -105.929574) (xy 322.452966 -105.976937)
			(xy 322.433696 -105.998264) (xy 322.427092 -106.005122) (xy 322.41998 -106.023156) (xy 322.41998 -106.112056)
			(xy 322.427092 -106.13009) (xy 322.433696 -106.136948) (xy 322.452972 -106.15827) (xy 322.485535 -106.205634)
			(xy 322.510625 -106.257347) (xy 322.527674 -106.312238) (xy 322.536295 -106.369065) (xy 322.536295 -106.426543)
			(xy 322.527672 -106.483371) (xy 322.510622 -106.538262) (xy 322.485531 -106.589974) (xy 322.452966 -106.637337)
			(xy 322.433696 -106.658664) (xy 322.427092 -106.665522) (xy 322.41998 -106.683556) (xy 322.41998 -106.772456)
			(xy 322.427092 -106.79049) (xy 322.433696 -106.797348) (xy 322.452958 -106.818683) (xy 322.485528 -106.866041)
			(xy 322.510623 -106.917751) (xy 322.527676 -106.972641) (xy 322.536299 -107.029467) (xy 322.53682 -107.058206)
			(xy 322.536334 -107.085457) (xy 322.528578 -107.139405) (xy 322.513223 -107.1917) (xy 322.490581 -107.241277)
			(xy 322.461115 -107.287127) (xy 322.425424 -107.328318) (xy 322.384233 -107.364009) (xy 322.338383 -107.393475)
			(xy 322.288806 -107.416117) (xy 322.236511 -107.431472) (xy 322.182563 -107.439228) (xy 322.128061 -107.439228)
			(xy 322.074113 -107.431472) (xy 322.021818 -107.416117) (xy 321.972241 -107.393475) (xy 321.926391 -107.364009)
			(xy 321.8852 -107.328318) (xy 321.849509 -107.287127) (xy 321.820043 -107.241277) (xy 321.797401 -107.1917)
			(xy 321.782046 -107.139405) (xy 321.77429 -107.085457) (xy 321.773804 -107.058206) (xy 318.67389 -107.058206)
			(xy 318.679557 -107.069887) (xy 318.696604 -107.124781) (xy 318.705221 -107.181612) (xy 318.705738 -107.210352)
			(xy 318.705252 -107.237603) (xy 318.697496 -107.291551) (xy 318.682141 -107.343846) (xy 318.659499 -107.393423)
			(xy 318.630033 -107.439273) (xy 318.594342 -107.480464) (xy 318.553151 -107.516155) (xy 318.507301 -107.545621)
			(xy 318.457724 -107.568263) (xy 318.405429 -107.583618) (xy 318.351481 -107.591374) (xy 318.296979 -107.591374)
			(xy 318.243031 -107.583618) (xy 318.190736 -107.568263) (xy 318.141159 -107.545621) (xy 318.095309 -107.516155)
			(xy 318.054118 -107.480464) (xy 318.018427 -107.439273) (xy 317.988961 -107.393423) (xy 317.966319 -107.343846)
			(xy 317.950964 -107.291551) (xy 317.943208 -107.237603) (xy 317.942722 -107.210352) (xy 297.928538 -107.210352)
			(xy 297.928029 -107.238238) (xy 297.919909 -107.293414) (xy 297.903841 -107.346821) (xy 297.880169 -107.397318)
			(xy 297.849396 -107.443831) (xy 297.812179 -107.485368) (xy 297.769311 -107.521043) (xy 297.721705 -107.550097)
			(xy 297.670376 -107.571909) (xy 297.616419 -107.586015) (xy 297.560982 -107.592115) (xy 297.505248 -107.590078)
			(xy 297.450405 -107.579948) (xy 297.397621 -107.561941) (xy 297.348021 -107.53644) (xy 297.302663 -107.503989)
			(xy 297.262514 -107.46528) (xy 297.228428 -107.421137) (xy 297.201132 -107.372502) (xy 297.181209 -107.320411)
			(xy 297.169083 -107.265974) (xy 297.165012 -107.210352) (xy 286.754824 -107.210352) (xy 286.754824 -107.376214)
			(xy 286.754334 -107.406198) (xy 286.746506 -107.465654) (xy 286.730985 -107.523579) (xy 286.708036 -107.578983)
			(xy 286.678052 -107.630917) (xy 286.641546 -107.678493) (xy 286.599141 -107.720898) (xy 286.551565 -107.757404)
			(xy 286.499631 -107.787388) (xy 286.444227 -107.810337) (xy 286.386302 -107.825858) (xy 286.326846 -107.833686)
			(xy 286.266878 -107.833686) (xy 286.207422 -107.825858) (xy 286.149497 -107.810337) (xy 286.094093 -107.787388)
			(xy 286.042159 -107.757404) (xy 285.994583 -107.720898) (xy 285.952178 -107.678493) (xy 285.915672 -107.630917)
			(xy 285.885688 -107.578983) (xy 285.862739 -107.523579) (xy 285.847218 -107.465654) (xy 285.83939 -107.406198)
			(xy 285.8389 -107.376214) (xy 283.567124 -107.376214) (xy 283.567124 -109.176312) (xy 283.9847 -109.176312)
			(xy 283.9847 -108.312712) (xy 283.98519 -108.282728) (xy 283.993018 -108.223272) (xy 284.008539 -108.165347)
			(xy 284.031488 -108.109943) (xy 284.061472 -108.058009) (xy 284.097978 -108.010433) (xy 284.140383 -107.968028)
			(xy 284.187959 -107.931522) (xy 284.239893 -107.901538) (xy 284.295297 -107.878589) (xy 284.353222 -107.863068)
			(xy 284.412678 -107.85524) (xy 284.472646 -107.85524) (xy 284.532102 -107.863068) (xy 284.590027 -107.878589)
			(xy 284.645431 -107.901538) (xy 284.697365 -107.931522) (xy 284.744941 -107.968028) (xy 284.787346 -108.010433)
			(xy 284.823852 -108.058009) (xy 284.853836 -108.109943) (xy 284.876785 -108.165347) (xy 284.892306 -108.223272)
			(xy 284.900134 -108.282728) (xy 284.900624 -108.312712) (xy 284.900624 -108.379006) (xy 322.662804 -108.379006)
			(xy 322.66333 -108.350267) (xy 322.671952 -108.29344) (xy 322.689001 -108.238549) (xy 322.714093 -108.186837)
			(xy 322.746657 -108.139475) (xy 322.765928 -108.118148) (xy 322.772532 -108.11129) (xy 322.779644 -108.093256)
			(xy 322.779644 -108.004356) (xy 322.772532 -107.986322) (xy 322.765928 -107.979464) (xy 322.746663 -107.958132)
			(xy 322.714097 -107.910771) (xy 322.689005 -107.85906) (xy 322.671954 -107.80417) (xy 322.663331 -107.747343)
			(xy 322.66333 -107.689866) (xy 322.671952 -107.633039) (xy 322.689002 -107.578148) (xy 322.714093 -107.526437)
			(xy 322.746657 -107.479075) (xy 322.765928 -107.457748) (xy 322.772532 -107.45089) (xy 322.779644 -107.432856)
			(xy 322.779644 -107.343956) (xy 322.772532 -107.325922) (xy 322.765928 -107.319064) (xy 322.746663 -107.297732)
			(xy 322.714097 -107.250371) (xy 322.689005 -107.19866) (xy 322.671954 -107.14377) (xy 322.663331 -107.086943)
			(xy 322.66333 -107.029466) (xy 322.671952 -106.972639) (xy 322.689002 -106.917748) (xy 322.714093 -106.866037)
			(xy 322.746657 -106.818675) (xy 322.765928 -106.797348) (xy 322.772532 -106.79049) (xy 322.779644 -106.772456)
			(xy 322.779644 -106.683556) (xy 322.772532 -106.665522) (xy 322.765928 -106.658664) (xy 322.746663 -106.637332)
			(xy 322.714097 -106.589971) (xy 322.689005 -106.53826) (xy 322.671954 -106.48337) (xy 322.663331 -106.426543)
			(xy 322.66333 -106.369066) (xy 322.671952 -106.312239) (xy 322.689002 -106.257348) (xy 322.714093 -106.205637)
			(xy 322.746657 -106.158275) (xy 322.765928 -106.136948) (xy 322.772532 -106.13009) (xy 322.779644 -106.112056)
			(xy 322.779644 -106.023156) (xy 322.772532 -106.005122) (xy 322.765928 -105.998264) (xy 322.746663 -105.976932)
			(xy 322.714097 -105.929571) (xy 322.689005 -105.87786) (xy 322.671954 -105.82297) (xy 322.663331 -105.766143)
			(xy 322.66333 -105.708666) (xy 322.671952 -105.651839) (xy 322.689002 -105.596948) (xy 322.714093 -105.545237)
			(xy 322.746657 -105.497875) (xy 322.765928 -105.476548) (xy 322.772532 -105.46969) (xy 322.779644 -105.451656)
			(xy 322.779644 -105.362756) (xy 322.772532 -105.344722) (xy 322.765928 -105.337864) (xy 322.746663 -105.316532)
			(xy 322.714097 -105.269171) (xy 322.689005 -105.21746) (xy 322.671954 -105.16257) (xy 322.663331 -105.105743)
			(xy 322.66333 -105.048266) (xy 322.671952 -104.991439) (xy 322.689002 -104.936548) (xy 322.714093 -104.884837)
			(xy 322.746657 -104.837475) (xy 322.765928 -104.816148) (xy 322.772532 -104.80929) (xy 322.779644 -104.791256)
			(xy 322.779644 -104.702356) (xy 322.772532 -104.684322) (xy 322.765928 -104.677464) (xy 322.746663 -104.656132)
			(xy 322.714097 -104.608771) (xy 322.689005 -104.55706) (xy 322.671954 -104.50217) (xy 322.663331 -104.445343)
			(xy 322.66333 -104.387866) (xy 322.671952 -104.331039) (xy 322.689002 -104.276148) (xy 322.714093 -104.224437)
			(xy 322.746657 -104.177075) (xy 322.765928 -104.155748) (xy 322.772532 -104.14889) (xy 322.779644 -104.130856)
			(xy 322.779644 -104.041956) (xy 322.772532 -104.023922) (xy 322.765928 -104.017064) (xy 322.746663 -103.995732)
			(xy 322.714097 -103.948371) (xy 322.689005 -103.89666) (xy 322.671954 -103.84177) (xy 322.663331 -103.784943)
			(xy 322.66333 -103.727466) (xy 322.671952 -103.670639) (xy 322.689002 -103.615748) (xy 322.714093 -103.564037)
			(xy 322.746657 -103.516675) (xy 322.765928 -103.495348) (xy 322.772532 -103.48849) (xy 322.779644 -103.470456)
			(xy 322.779644 -103.381556) (xy 322.772532 -103.363522) (xy 322.765928 -103.356664) (xy 322.746659 -103.335336)
			(xy 322.714092 -103.287974) (xy 322.689 -103.236263) (xy 322.671949 -103.181372) (xy 322.663325 -103.124545)
			(xy 322.662804 -103.095806) (xy 322.663245 -103.068599) (xy 322.67097 -103.014735) (xy 322.686276 -102.962517)
			(xy 322.708854 -102.913007) (xy 322.738244 -102.867212) (xy 322.773848 -102.826063) (xy 322.814943 -102.790395)
			(xy 322.837556 -102.775258) (xy 322.845938 -102.769924) (xy 322.857114 -102.753668) (xy 322.875402 -102.674674)
			(xy 322.87721 -102.665045) (xy 322.874213 -102.645704) (xy 322.86956 -102.637082) (xy 322.869306 -102.637082)
			(xy 322.869306 -102.636574) (xy 322.856101 -102.614063) (xy 322.835245 -102.566221) (xy 322.821095 -102.515987)
			(xy 322.813911 -102.464294) (xy 322.813426 -102.4382) (xy 322.813912 -102.410949) (xy 322.821668 -102.357001)
			(xy 322.837023 -102.304706) (xy 322.859665 -102.255129) (xy 322.889131 -102.209279) (xy 322.924822 -102.168088)
			(xy 322.966013 -102.132397) (xy 323.011863 -102.102931) (xy 323.06144 -102.080289) (xy 323.113735 -102.064934)
			(xy 323.167683 -102.057178) (xy 323.222185 -102.057178) (xy 323.276133 -102.064934) (xy 323.328428 -102.080289)
			(xy 323.378005 -102.102931) (xy 323.423855 -102.132397) (xy 323.465046 -102.168088) (xy 323.500737 -102.209279)
			(xy 323.530203 -102.255129) (xy 323.552845 -102.304706) (xy 323.5682 -102.357001) (xy 323.575956 -102.410949)
			(xy 323.576442 -102.4382) (xy 323.575984 -102.465407) (xy 323.56826 -102.519269) (xy 323.552955 -102.571485)
			(xy 323.530379 -102.620994) (xy 323.500993 -102.666789) (xy 323.465392 -102.70794) (xy 323.424301 -102.743609)
			(xy 323.40169 -102.758748) (xy 323.393308 -102.764082) (xy 323.382132 -102.780338) (xy 323.363844 -102.859332)
			(xy 323.36204 -102.868962) (xy 323.365036 -102.888302) (xy 323.369686 -102.896924) (xy 323.36994 -102.896924)
			(xy 323.36994 -102.897432) (xy 323.383152 -102.919939) (xy 323.404005 -102.967783) (xy 323.418153 -103.018018)
			(xy 323.425335 -103.069712) (xy 323.42582 -103.095806) (xy 323.425295 -103.124545) (xy 323.416672 -103.181372)
			(xy 323.399622 -103.236262) (xy 323.374531 -103.287974) (xy 323.341966 -103.335337) (xy 323.322696 -103.356664)
			(xy 323.316092 -103.363522) (xy 323.30898 -103.381556) (xy 323.30898 -103.470456) (xy 323.316092 -103.48849)
			(xy 323.322696 -103.495348) (xy 323.341972 -103.51667) (xy 323.374535 -103.564034) (xy 323.399625 -103.615747)
			(xy 323.416674 -103.670638) (xy 323.425295 -103.727465) (xy 323.425295 -103.784943) (xy 323.416672 -103.841771)
			(xy 323.399622 -103.896662) (xy 323.374531 -103.948374) (xy 323.341966 -103.995737) (xy 323.322696 -104.017064)
			(xy 323.31707 -104.022906) (xy 328.065892 -104.022906) (xy 328.066366 -103.996592) (xy 328.0736 -103.944464)
			(xy 328.087918 -103.893822) (xy 328.109049 -103.845623) (xy 328.136594 -103.800779) (xy 328.170031 -103.760139)
			(xy 328.189082 -103.741982) (xy 328.196491 -103.734467) (xy 328.205012 -103.715182) (xy 328.205592 -103.704644)
			(xy 328.205592 -103.629968) (xy 328.205042 -103.619421) (xy 328.196522 -103.600125) (xy 328.189082 -103.59263)
			(xy 328.170045 -103.574456) (xy 328.136586 -103.53383) (xy 328.109025 -103.488994) (xy 328.087884 -103.440796)
			(xy 328.073563 -103.390152) (xy 328.066333 -103.338021) (xy 328.065892 -103.311706) (xy 328.066361 -103.284453)
			(xy 328.074117 -103.230503) (xy 328.089472 -103.178205) (xy 328.112114 -103.128625) (xy 328.141582 -103.082772)
			(xy 328.177275 -103.041579) (xy 328.218467 -103.005885) (xy 328.264319 -102.976417) (xy 328.313899 -102.953774)
			(xy 328.366197 -102.938418) (xy 328.420147 -102.930661) (xy 328.4474 -102.930198) (xy 328.475065 -102.930711)
			(xy 328.529814 -102.938711) (xy 328.582836 -102.954527) (xy 328.633019 -102.97783) (xy 328.679315 -103.008131)
			(xy 328.720753 -103.044796) (xy 328.756466 -103.087057) (xy 328.771504 -103.110284) (xy 328.77813 -103.11997)
			(xy 328.797999 -103.132408) (xy 328.809604 -103.13416) (xy 328.889614 -103.142034) (xy 328.901253 -103.142672)
			(xy 328.923091 -103.134588) (xy 328.931524 -103.12654) (xy 328.931778 -103.126286) (xy 328.949884 -103.107731)
			(xy 328.990211 -103.07515) (xy 329.03458 -103.048334) (xy 329.082173 -103.027777) (xy 329.132113 -103.013858)
			(xy 329.183478 -103.006834) (xy 329.2094 -103.006398) (xy 329.236653 -103.006855) (xy 329.290605 -103.014612)
			(xy 329.342903 -103.029969) (xy 329.392483 -103.052612) (xy 329.438337 -103.08208) (xy 329.47953 -103.117775)
			(xy 329.515223 -103.158968) (xy 329.544691 -103.204822) (xy 329.567333 -103.254403) (xy 329.582689 -103.306701)
			(xy 329.590445 -103.360653) (xy 329.590908 -103.387906) (xy 329.590443 -103.415276) (xy 329.582625 -103.469455)
			(xy 329.567135 -103.521958) (xy 329.544293 -103.571705) (xy 329.514569 -103.617672) (xy 329.496928 -103.638604)
			(xy 329.496674 -103.638858) (xy 329.491096 -103.64595) (xy 329.484845 -103.662863) (xy 329.484482 -103.671878)
			(xy 329.484482 -103.685654) (xy 340.692671 -103.685654) (xy 340.692671 -103.631146) (xy 340.700429 -103.577194)
			(xy 340.715787 -103.524895) (xy 340.738431 -103.475315) (xy 340.767901 -103.429462) (xy 340.803598 -103.38827)
			(xy 340.844794 -103.352577) (xy 340.89065 -103.323112) (xy 340.940233 -103.300473) (xy 340.992533 -103.285121)
			(xy 341.046486 -103.277369) (xy 341.07374 -103.276908) (xy 341.100055 -103.277346) (xy 341.152185 -103.284587)
			(xy 341.202828 -103.298911) (xy 341.251027 -103.320049) (xy 341.29587 -103.347601) (xy 341.336508 -103.381044)
			(xy 341.354664 -103.400098) (xy 341.362197 -103.407485) (xy 341.381469 -103.416018) (xy 341.392002 -103.416608)
			(xy 341.466678 -103.416608) (xy 341.477227 -103.416078) (xy 341.496523 -103.407543) (xy 341.504016 -103.400098)
			(xy 341.523836 -103.37931) (xy 341.568608 -103.343335) (xy 341.618266 -103.314475) (xy 341.671688 -103.293382)
			(xy 341.727667 -103.280533) (xy 341.78494 -103.276218) (xy 341.842213 -103.280533) (xy 341.898192 -103.293382)
			(xy 341.951614 -103.314475) (xy 342.001272 -103.343335) (xy 342.046044 -103.37931) (xy 342.065864 -103.400098)
			(xy 342.073397 -103.407485) (xy 342.092669 -103.416018) (xy 342.103202 -103.416608) (xy 342.177878 -103.416608)
			(xy 342.188427 -103.416078) (xy 342.207723 -103.407543) (xy 342.215216 -103.400098) (xy 342.23337 -103.381041)
			(xy 342.274 -103.347584) (xy 342.318841 -103.320026) (xy 342.367042 -103.298887) (xy 342.41769 -103.28457)
			(xy 342.469824 -103.277346) (xy 342.49614 -103.276908) (xy 342.523391 -103.277365) (xy 342.577336 -103.285126)
			(xy 342.629628 -103.300485) (xy 342.679203 -103.32313) (xy 342.72505 -103.352598) (xy 342.766237 -103.388291)
			(xy 342.801926 -103.429482) (xy 342.83139 -103.475333) (xy 342.854029 -103.524909) (xy 342.869383 -103.577203)
			(xy 342.877138 -103.631149) (xy 342.877138 -103.685651) (xy 342.869383 -103.739597) (xy 342.854029 -103.791891)
			(xy 342.83139 -103.841467) (xy 342.801926 -103.887318) (xy 342.766237 -103.928509) (xy 342.72505 -103.964202)
			(xy 342.679203 -103.99367) (xy 342.629628 -104.016315) (xy 342.577336 -104.031674) (xy 342.523391 -104.039435)
			(xy 342.49614 -104.039924) (xy 342.469825 -104.039489) (xy 342.417695 -104.032246) (xy 342.367052 -104.01792)
			(xy 342.318854 -103.996782) (xy 342.274011 -103.969231) (xy 342.233372 -103.935787) (xy 342.215216 -103.916734)
			(xy 342.207686 -103.909342) (xy 342.188413 -103.900811) (xy 342.177878 -103.900224) (xy 342.103202 -103.900224)
			(xy 342.09265 -103.900734) (xy 342.073354 -103.909282) (xy 342.065864 -103.916734) (xy 342.046044 -103.937522)
			(xy 342.001272 -103.973497) (xy 341.951614 -104.002357) (xy 341.898192 -104.02345) (xy 341.842213 -104.036299)
			(xy 341.78494 -104.040614) (xy 341.727667 -104.036299) (xy 341.671688 -104.02345) (xy 341.618266 -104.002357)
			(xy 341.568608 -103.973497) (xy 341.523836 -103.937522) (xy 341.504016 -103.916734) (xy 341.496486 -103.909342)
			(xy 341.477213 -103.900811) (xy 341.466678 -103.900224) (xy 341.392002 -103.900224) (xy 341.38145 -103.900734)
			(xy 341.362154 -103.909282) (xy 341.354664 -103.916734) (xy 341.336526 -103.935806) (xy 341.295891 -103.969261)
			(xy 341.251047 -103.996817) (xy 341.202843 -104.017952) (xy 341.152193 -104.032266) (xy 341.100057 -104.039487)
			(xy 341.07374 -104.039924) (xy 341.046486 -104.039431) (xy 340.992533 -104.031679) (xy 340.940233 -104.016327)
			(xy 340.89065 -103.993688) (xy 340.844794 -103.964223) (xy 340.803598 -103.92853) (xy 340.767901 -103.887338)
			(xy 340.738431 -103.841485) (xy 340.715787 -103.791905) (xy 340.700429 -103.739606) (xy 340.692671 -103.685654)
			(xy 329.484482 -103.685654) (xy 329.484482 -103.738934) (xy 329.484826 -103.747952) (xy 329.491083 -103.764869)
			(xy 329.496674 -103.771954) (xy 329.496928 -103.771954) (xy 329.496928 -103.772208) (xy 329.514589 -103.793123)
			(xy 329.544296 -103.839101) (xy 329.567128 -103.888853) (xy 329.582614 -103.941357) (xy 329.590437 -103.995536)
			(xy 329.590908 -104.022906) (xy 329.590428 -104.050157) (xy 329.58267 -104.104105) (xy 329.567315 -104.1564)
			(xy 329.544673 -104.205977) (xy 329.515206 -104.251828) (xy 329.479514 -104.293018) (xy 329.438323 -104.328709)
			(xy 329.392472 -104.358176) (xy 329.342895 -104.380817) (xy 329.290599 -104.396172) (xy 329.236651 -104.403928)
			(xy 329.2094 -104.404414) (xy 329.180481 -104.403928) (xy 329.123307 -104.395197) (xy 329.068106 -104.377935)
			(xy 329.016144 -104.352537) (xy 328.968611 -104.319586) (xy 328.926598 -104.279837) (xy 328.90841 -104.257348)
			(xy 328.900798 -104.248546) (xy 328.879901 -104.238362) (xy 328.868278 -104.23779) (xy 328.788522 -104.23779)
			(xy 328.776894 -104.23836) (xy 328.755985 -104.248527) (xy 328.74839 -104.257348) (xy 328.730217 -104.279846)
			(xy 328.688192 -104.319578) (xy 328.640653 -104.352514) (xy 328.588688 -104.3779) (xy 328.533488 -104.395153)
			(xy 328.476317 -104.40388) (xy 328.4474 -104.404414) (xy 328.420149 -104.403922) (xy 328.366202 -104.396166)
			(xy 328.313908 -104.380811) (xy 328.264331 -104.35817) (xy 328.218481 -104.328705) (xy 328.177291 -104.293014)
			(xy 328.141599 -104.251824) (xy 328.112133 -104.205975) (xy 328.089491 -104.156398) (xy 328.074135 -104.104104)
			(xy 328.066378 -104.050157) (xy 328.065892 -104.022906) (xy 323.31707 -104.022906) (xy 323.316092 -104.023922)
			(xy 323.30898 -104.041956) (xy 323.30898 -104.130856) (xy 323.316092 -104.14889) (xy 323.322696 -104.155748)
			(xy 323.341972 -104.17707) (xy 323.374535 -104.224434) (xy 323.399625 -104.276147) (xy 323.416674 -104.331038)
			(xy 323.425295 -104.387865) (xy 323.425295 -104.445343) (xy 323.416672 -104.502171) (xy 323.399622 -104.557062)
			(xy 323.374531 -104.608774) (xy 323.341966 -104.656137) (xy 323.322696 -104.677464) (xy 323.316092 -104.684322)
			(xy 323.30898 -104.702356) (xy 323.30898 -104.791256) (xy 323.316092 -104.80929) (xy 323.322696 -104.816148)
			(xy 323.341972 -104.83747) (xy 323.374535 -104.884834) (xy 323.399625 -104.936547) (xy 323.416674 -104.991438)
			(xy 323.425295 -105.048265) (xy 323.425295 -105.08445) (xy 327.943972 -105.08445) (xy 327.943972 -105.02995)
			(xy 327.951728 -104.976003) (xy 327.967082 -104.92371) (xy 327.989721 -104.874134) (xy 328.019185 -104.828284)
			(xy 328.054874 -104.787094) (xy 328.096062 -104.751402) (xy 328.141909 -104.721934) (xy 328.191484 -104.699291)
			(xy 328.243776 -104.683934) (xy 328.297722 -104.676174) (xy 328.324972 -104.675686) (xy 328.352341 -104.676172)
			(xy 328.40652 -104.683985) (xy 328.459022 -104.69947) (xy 328.50877 -104.722307) (xy 328.554737 -104.752027)
			(xy 328.57567 -104.769666) (xy 328.575924 -104.76992) (xy 328.582998 -104.775525) (xy 328.599924 -104.78176)
			(xy 328.608944 -104.782112) (xy 328.676 -104.782112) (xy 328.685017 -104.781752) (xy 328.701933 -104.775506)
			(xy 328.70902 -104.76992) (xy 328.70902 -104.769666) (xy 328.709274 -104.769666) (xy 328.730207 -104.752025)
			(xy 328.776175 -104.722301) (xy 328.825921 -104.699455) (xy 328.878423 -104.683959) (xy 328.932601 -104.67613)
			(xy 328.987343 -104.67613) (xy 329.041521 -104.683959) (xy 329.094023 -104.699455) (xy 329.143769 -104.722301)
			(xy 329.189737 -104.752025) (xy 329.21067 -104.769666) (xy 329.210924 -104.76992) (xy 329.217998 -104.775525)
			(xy 329.234924 -104.78176) (xy 329.243944 -104.782112) (xy 329.311 -104.782112) (xy 329.320017 -104.781752)
			(xy 329.336933 -104.775506) (xy 329.34402 -104.76992) (xy 329.34402 -104.769666) (xy 329.344274 -104.769666)
			(xy 329.365207 -104.752025) (xy 329.411175 -104.722301) (xy 329.460921 -104.699455) (xy 329.513423 -104.683959)
			(xy 329.567601 -104.67613) (xy 329.622343 -104.67613) (xy 329.676521 -104.683959) (xy 329.729023 -104.699455)
			(xy 329.778769 -104.722301) (xy 329.824737 -104.752025) (xy 329.84567 -104.769666) (xy 329.845924 -104.76992)
			(xy 329.852998 -104.775525) (xy 329.869924 -104.78176) (xy 329.878944 -104.782112) (xy 329.946 -104.782112)
			(xy 329.955017 -104.781752) (xy 329.971933 -104.775506) (xy 329.97902 -104.76992) (xy 329.97902 -104.769666)
			(xy 329.979274 -104.769666) (xy 330.000201 -104.75202) (xy 330.046176 -104.722311) (xy 330.095924 -104.699477)
			(xy 330.148426 -104.683987) (xy 330.202603 -104.67616) (xy 330.229972 -104.675686) (xy 330.257226 -104.676159)
			(xy 330.311179 -104.683913) (xy 330.363479 -104.699266) (xy 330.413062 -104.721907) (xy 330.458918 -104.751374)
			(xy 330.500113 -104.787067) (xy 330.535809 -104.82826) (xy 330.56528 -104.874113) (xy 330.587924 -104.923695)
			(xy 330.603281 -104.975994) (xy 330.611039 -105.029946) (xy 330.611039 -105.084454) (xy 330.603281 -105.138406)
			(xy 330.587924 -105.190705) (xy 330.56528 -105.240287) (xy 330.535809 -105.28614) (xy 330.500113 -105.327333)
			(xy 330.458918 -105.363026) (xy 330.413062 -105.392493) (xy 330.363479 -105.415134) (xy 330.311179 -105.430487)
			(xy 330.257226 -105.438241) (xy 330.229972 -105.438702) (xy 330.202601 -105.438252) (xy 330.148421 -105.43043)
			(xy 330.095918 -105.414937) (xy 330.046172 -105.392092) (xy 330.000205 -105.362365) (xy 329.979274 -105.344722)
			(xy 329.97902 -105.344468) (xy 329.971935 -105.33888) (xy 329.955017 -105.332635) (xy 329.946 -105.332276)
			(xy 329.878944 -105.332276) (xy 329.86993 -105.332659) (xy 329.853013 -105.338889) (xy 329.845924 -105.344468)
			(xy 329.845924 -105.344722) (xy 329.84567 -105.344722) (xy 329.824737 -105.362363) (xy 329.778769 -105.392087)
			(xy 329.729023 -105.414933) (xy 329.676521 -105.430429) (xy 329.622343 -105.438258) (xy 329.567601 -105.438258)
			(xy 329.513423 -105.430429) (xy 329.460921 -105.414933) (xy 329.411175 -105.392087) (xy 329.365207 -105.362363)
			(xy 329.344274 -105.344722) (xy 329.34402 -105.344468) (xy 329.336935 -105.33888) (xy 329.320017 -105.332635)
			(xy 329.311 -105.332276) (xy 329.243944 -105.332276) (xy 329.23493 -105.332659) (xy 329.218013 -105.338889)
			(xy 329.210924 -105.344468) (xy 329.210924 -105.344722) (xy 329.21067 -105.344722) (xy 329.189737 -105.362363)
			(xy 329.143769 -105.392087) (xy 329.094023 -105.414933) (xy 329.041521 -105.430429) (xy 328.987343 -105.438258)
			(xy 328.932601 -105.438258) (xy 328.878423 -105.430429) (xy 328.825921 -105.414933) (xy 328.776175 -105.392087)
			(xy 328.730207 -105.362363) (xy 328.709274 -105.344722) (xy 328.70902 -105.344468) (xy 328.701935 -105.33888)
			(xy 328.685017 -105.332635) (xy 328.676 -105.332276) (xy 328.608944 -105.332276) (xy 328.59993 -105.332659)
			(xy 328.583013 -105.338889) (xy 328.575924 -105.344468) (xy 328.575924 -105.344722) (xy 328.57567 -105.344722)
			(xy 328.554725 -105.362345) (xy 328.508756 -105.392059) (xy 328.459011 -105.414897) (xy 328.406514 -105.430392)
			(xy 328.35234 -105.438225) (xy 328.324972 -105.438702) (xy 328.297722 -105.438226) (xy 328.243776 -105.430466)
			(xy 328.191484 -105.415109) (xy 328.141909 -105.392466) (xy 328.096062 -105.362998) (xy 328.054874 -105.327306)
			(xy 328.019185 -105.286116) (xy 327.989721 -105.240266) (xy 327.967082 -105.19069) (xy 327.951728 -105.138397)
			(xy 327.943972 -105.08445) (xy 323.425295 -105.08445) (xy 323.425295 -105.105743) (xy 323.416672 -105.162571)
			(xy 323.399622 -105.217462) (xy 323.374531 -105.269174) (xy 323.341966 -105.316537) (xy 323.322696 -105.337864)
			(xy 323.316092 -105.344722) (xy 323.30898 -105.362756) (xy 323.30898 -105.451656) (xy 323.316092 -105.46969)
			(xy 323.322696 -105.476548) (xy 323.341972 -105.49787) (xy 323.374535 -105.545234) (xy 323.399625 -105.596947)
			(xy 323.416674 -105.651838) (xy 323.425295 -105.708665) (xy 323.425295 -105.766143) (xy 323.416672 -105.822971)
			(xy 323.399622 -105.877862) (xy 323.374531 -105.929574) (xy 323.341966 -105.976937) (xy 323.322696 -105.998264)
			(xy 323.316092 -106.005122) (xy 323.30898 -106.023156) (xy 323.30898 -106.112056) (xy 323.316092 -106.13009)
			(xy 323.322696 -106.136948) (xy 323.341972 -106.15827) (xy 323.374535 -106.205634) (xy 323.399625 -106.257347)
			(xy 323.416674 -106.312238) (xy 323.425295 -106.369065) (xy 323.425295 -106.426543) (xy 323.416672 -106.483371)
			(xy 323.399622 -106.538262) (xy 323.374531 -106.589974) (xy 323.341966 -106.637337) (xy 323.322696 -106.658664)
			(xy 323.316092 -106.665522) (xy 323.30898 -106.683556) (xy 323.30898 -106.772456) (xy 323.316092 -106.79049)
			(xy 323.322696 -106.797348) (xy 323.327305 -106.802446) (xy 340.620928 -106.802446) (xy 340.620928 -106.747954)
			(xy 340.628682 -106.694017) (xy 340.644033 -106.641733) (xy 340.666668 -106.592165) (xy 340.696127 -106.546323)
			(xy 340.731809 -106.505139) (xy 340.772989 -106.469452) (xy 340.818828 -106.439989) (xy 340.868393 -106.417348)
			(xy 340.920676 -106.401991) (xy 340.974612 -106.394231) (xy 341.001858 -106.393742) (xy 341.028174 -106.394157)
			(xy 341.080305 -106.401401) (xy 341.130949 -106.415729) (xy 341.179149 -106.436871) (xy 341.223991 -106.464427)
			(xy 341.264627 -106.497876) (xy 341.282782 -106.516932) (xy 341.290317 -106.524318) (xy 341.309587 -106.532854)
			(xy 341.32012 -106.533442) (xy 341.394796 -106.533442) (xy 341.405345 -106.532912) (xy 341.42464 -106.524376)
			(xy 341.432134 -106.516932) (xy 341.451954 -106.496144) (xy 341.496726 -106.460169) (xy 341.546384 -106.431309)
			(xy 341.599806 -106.410216) (xy 341.655785 -106.397367) (xy 341.713058 -106.393052) (xy 341.770331 -106.397367)
			(xy 341.82631 -106.410216) (xy 341.879732 -106.431309) (xy 341.92939 -106.460169) (xy 341.974162 -106.496144)
			(xy 341.993982 -106.516932) (xy 342.001517 -106.524318) (xy 342.020787 -106.532854) (xy 342.03132 -106.533442)
			(xy 342.105996 -106.533442) (xy 342.116545 -106.532912) (xy 342.13584 -106.524376) (xy 342.143334 -106.516932)
			(xy 342.161486 -106.497873) (xy 342.202116 -106.464415) (xy 342.246957 -106.436856) (xy 342.295158 -106.415718)
			(xy 342.345807 -106.401402) (xy 342.397942 -106.394179) (xy 342.424258 -106.393742) (xy 342.451516 -106.394102)
			(xy 342.505479 -106.401855) (xy 342.557789 -106.41721) (xy 342.607381 -106.439853) (xy 342.653245 -106.469324)
			(xy 342.694448 -106.505022) (xy 342.730151 -106.546221) (xy 342.759627 -106.592082) (xy 342.782276 -106.641672)
			(xy 342.797636 -106.69398) (xy 342.805395 -106.747942) (xy 342.805395 -106.802458) (xy 342.797636 -106.85642)
			(xy 342.782276 -106.908728) (xy 342.759627 -106.958318) (xy 342.730151 -107.004179) (xy 342.694448 -107.045378)
			(xy 342.653245 -107.081076) (xy 342.607381 -107.110547) (xy 342.557789 -107.13319) (xy 342.505479 -107.148545)
			(xy 342.451516 -107.156298) (xy 342.424258 -107.156758) (xy 342.397942 -107.156332) (xy 342.345812 -107.149091)
			(xy 342.295168 -107.134764) (xy 342.246968 -107.113624) (xy 342.202126 -107.08607) (xy 342.161489 -107.052623)
			(xy 342.143334 -107.033568) (xy 342.135793 -107.026189) (xy 342.116528 -107.017649) (xy 342.105996 -107.017058)
			(xy 342.03132 -107.017058) (xy 342.020772 -107.017597) (xy 342.001477 -107.026127) (xy 341.993982 -107.033568)
			(xy 341.974162 -107.054356) (xy 341.92939 -107.090331) (xy 341.879732 -107.119191) (xy 341.82631 -107.140284)
			(xy 341.770331 -107.153133) (xy 341.713058 -107.157448) (xy 341.655785 -107.153133) (xy 341.599806 -107.140284)
			(xy 341.546384 -107.119191) (xy 341.496726 -107.090331) (xy 341.451954 -107.054356) (xy 341.432134 -107.033568)
			(xy 341.424593 -107.026189) (xy 341.405328 -107.017649) (xy 341.394796 -107.017058) (xy 341.32012 -107.017058)
			(xy 341.309572 -107.017597) (xy 341.290277 -107.026127) (xy 341.282782 -107.033568) (xy 341.264622 -107.052619)
			(xy 341.223994 -107.086078) (xy 341.179155 -107.113638) (xy 341.130955 -107.134778) (xy 341.080308 -107.149095)
			(xy 341.028174 -107.15632) (xy 341.001858 -107.156758) (xy 340.974612 -107.156169) (xy 340.920676 -107.148409)
			(xy 340.868393 -107.133052) (xy 340.818828 -107.110411) (xy 340.772989 -107.080948) (xy 340.731809 -107.045261)
			(xy 340.696127 -107.004077) (xy 340.666668 -106.958235) (xy 340.644033 -106.908667) (xy 340.628682 -106.856383)
			(xy 340.620928 -106.802446) (xy 323.327305 -106.802446) (xy 323.341972 -106.81867) (xy 323.374535 -106.866034)
			(xy 323.399625 -106.917747) (xy 323.416674 -106.972638) (xy 323.425295 -107.029465) (xy 323.425295 -107.086943)
			(xy 323.416672 -107.143771) (xy 323.399622 -107.198662) (xy 323.374531 -107.250374) (xy 323.341966 -107.297737)
			(xy 323.322696 -107.319064) (xy 323.316092 -107.325922) (xy 323.30898 -107.343956) (xy 323.30898 -107.432856)
			(xy 323.316092 -107.45089) (xy 323.322696 -107.457748) (xy 323.341972 -107.47907) (xy 323.374535 -107.526434)
			(xy 323.399625 -107.578147) (xy 323.416674 -107.633038) (xy 323.425295 -107.689865) (xy 323.425295 -107.740249)
			(xy 327.884296 -107.740249) (xy 327.884296 -107.685751) (xy 327.892052 -107.631807) (xy 327.907405 -107.579517)
			(xy 327.930044 -107.529943) (xy 327.959507 -107.484096) (xy 327.995195 -107.442908) (xy 328.036381 -107.407218)
			(xy 328.082227 -107.377753) (xy 328.1318 -107.355112) (xy 328.18409 -107.339756) (xy 328.238033 -107.331997)
			(xy 328.265282 -107.33151) (xy 328.292652 -107.331984) (xy 328.346831 -107.3398) (xy 328.399334 -107.355287)
			(xy 328.449081 -107.378127) (xy 328.495048 -107.40785) (xy 328.51598 -107.42549) (xy 328.516234 -107.425744)
			(xy 328.523331 -107.431314) (xy 328.54024 -107.43757) (xy 328.549254 -107.437936) (xy 328.61631 -107.437936)
			(xy 328.625326 -107.437576) (xy 328.642243 -107.43133) (xy 328.64933 -107.425744) (xy 328.64933 -107.42549)
			(xy 328.649584 -107.42549) (xy 328.670517 -107.407849) (xy 328.716485 -107.378125) (xy 328.766231 -107.355279)
			(xy 328.818733 -107.339783) (xy 328.872911 -107.331954) (xy 328.927653 -107.331954) (xy 328.981831 -107.339783)
			(xy 329.034333 -107.355279) (xy 329.084079 -107.378125) (xy 329.130047 -107.407849) (xy 329.15098 -107.42549)
			(xy 329.151234 -107.425744) (xy 329.158331 -107.431314) (xy 329.17524 -107.43757) (xy 329.184254 -107.437936)
			(xy 329.25131 -107.437936) (xy 329.260326 -107.437576) (xy 329.277243 -107.43133) (xy 329.28433 -107.425744)
			(xy 329.28433 -107.42549) (xy 329.284584 -107.42549) (xy 329.305517 -107.407849) (xy 329.351485 -107.378125)
			(xy 329.401231 -107.355279) (xy 329.453733 -107.339783) (xy 329.507911 -107.331954) (xy 329.562653 -107.331954)
			(xy 329.616831 -107.339783) (xy 329.669333 -107.355279) (xy 329.719079 -107.378125) (xy 329.765047 -107.407849)
			(xy 329.78598 -107.42549) (xy 329.786234 -107.425744) (xy 329.793331 -107.431314) (xy 329.81024 -107.43757)
			(xy 329.819254 -107.437936) (xy 329.88631 -107.437936) (xy 329.895326 -107.437576) (xy 329.912243 -107.43133)
			(xy 329.91933 -107.425744) (xy 329.91933 -107.42549) (xy 329.919584 -107.42549) (xy 329.94051 -107.407843)
			(xy 329.986485 -107.378133) (xy 330.036234 -107.355299) (xy 330.088736 -107.339809) (xy 330.142912 -107.331983)
			(xy 330.170282 -107.33151) (xy 330.197537 -107.331936) (xy 330.251492 -107.339691) (xy 330.303795 -107.355046)
			(xy 330.35338 -107.377689) (xy 330.399237 -107.407158) (xy 330.440434 -107.442853) (xy 330.476132 -107.484048)
			(xy 330.505603 -107.529904) (xy 330.528248 -107.579488) (xy 330.543605 -107.63179) (xy 330.551363 -107.685745)
			(xy 330.551363 -107.740255) (xy 330.543605 -107.79421) (xy 330.528248 -107.846512) (xy 330.505603 -107.896096)
			(xy 330.476132 -107.941952) (xy 330.440434 -107.983147) (xy 330.399237 -108.018842) (xy 330.35338 -108.048311)
			(xy 330.303795 -108.070954) (xy 330.251492 -108.086309) (xy 330.197537 -108.094064) (xy 330.170282 -108.094526)
			(xy 330.142911 -108.094089) (xy 330.088729 -108.086267) (xy 330.036225 -108.070772) (xy 329.986479 -108.047923)
			(xy 329.940514 -108.018191) (xy 329.919584 -108.000546) (xy 329.91933 -108.000292) (xy 329.91224 -107.994711)
			(xy 329.895326 -107.988461) (xy 329.88631 -107.9881) (xy 329.819254 -107.9881) (xy 329.81024 -107.988483)
			(xy 329.793323 -107.994713) (xy 329.786234 -108.000292) (xy 329.786234 -108.000546) (xy 329.78598 -108.000546)
			(xy 329.765047 -108.018187) (xy 329.719079 -108.047911) (xy 329.669333 -108.070757) (xy 329.616831 -108.086253)
			(xy 329.562653 -108.094082) (xy 329.507911 -108.094082) (xy 329.453733 -108.086253) (xy 329.401231 -108.070757)
			(xy 329.351485 -108.047911) (xy 329.305517 -108.018187) (xy 329.284584 -108.000546) (xy 329.28433 -108.000292)
			(xy 329.27724 -107.994711) (xy 329.260326 -107.988461) (xy 329.25131 -107.9881) (xy 329.184254 -107.9881)
			(xy 329.17524 -107.988483) (xy 329.158323 -107.994713) (xy 329.151234 -108.000292) (xy 329.151234 -108.000546)
			(xy 329.15098 -108.000546) (xy 329.130047 -108.018187) (xy 329.084079 -108.047911) (xy 329.034333 -108.070757)
			(xy 328.981831 -108.086253) (xy 328.927653 -108.094082) (xy 328.872911 -108.094082) (xy 328.818733 -108.086253)
			(xy 328.766231 -108.070757) (xy 328.716485 -108.047911) (xy 328.670517 -108.018187) (xy 328.649584 -108.000546)
			(xy 328.64933 -108.000292) (xy 328.64224 -107.994711) (xy 328.625326 -107.988461) (xy 328.61631 -107.9881)
			(xy 328.549254 -107.9881) (xy 328.54024 -107.988483) (xy 328.523323 -107.994713) (xy 328.516234 -108.000292)
			(xy 328.516234 -108.000546) (xy 328.51598 -108.000546) (xy 328.495022 -108.018153) (xy 328.449057 -108.047871)
			(xy 328.399316 -108.070714) (xy 328.346821 -108.086213) (xy 328.29265 -108.094048) (xy 328.265282 -108.094526)
			(xy 328.238033 -108.094003) (xy 328.18409 -108.086244) (xy 328.1318 -108.070888) (xy 328.082227 -108.048247)
			(xy 328.036381 -108.018782) (xy 327.995195 -107.983092) (xy 327.959507 -107.941904) (xy 327.930044 -107.896057)
			(xy 327.907405 -107.846483) (xy 327.892052 -107.794193) (xy 327.884296 -107.740249) (xy 323.425295 -107.740249)
			(xy 323.425295 -107.747343) (xy 323.416672 -107.804171) (xy 323.399622 -107.859062) (xy 323.374531 -107.910774)
			(xy 323.341966 -107.958137) (xy 323.322696 -107.979464) (xy 323.316092 -107.986322) (xy 323.30898 -108.004356)
			(xy 323.30898 -108.093256) (xy 323.316092 -108.11129) (xy 323.322696 -108.118148) (xy 323.341958 -108.139483)
			(xy 323.374528 -108.186841) (xy 323.399623 -108.238551) (xy 323.416676 -108.293441) (xy 323.425299 -108.350267)
			(xy 323.42582 -108.379006) (xy 323.425334 -108.406257) (xy 323.417578 -108.460205) (xy 323.402223 -108.5125)
			(xy 323.379581 -108.562077) (xy 323.374807 -108.569506) (xy 339.061044 -108.569506) (xy 339.061503 -108.542135)
			(xy 339.069321 -108.487956) (xy 339.084811 -108.435452) (xy 339.107655 -108.385705) (xy 339.137381 -108.339739)
			(xy 339.155024 -108.318808) (xy 339.155278 -108.318554) (xy 339.160857 -108.311463) (xy 339.167106 -108.294549)
			(xy 339.16747 -108.285534) (xy 339.16747 -108.218478) (xy 339.16713 -108.209459) (xy 339.160871 -108.192542)
			(xy 339.155278 -108.185458) (xy 339.155024 -108.185458) (xy 339.155024 -108.185204) (xy 339.137377 -108.164278)
			(xy 339.107666 -108.118304) (xy 339.084831 -108.068555) (xy 339.069342 -108.016053) (xy 339.061516 -107.961876)
			(xy 339.061044 -107.934506) (xy 339.06153 -107.907255) (xy 339.069286 -107.853307) (xy 339.084641 -107.801012)
			(xy 339.107283 -107.751435) (xy 339.136749 -107.705585) (xy 339.17244 -107.664394) (xy 339.213631 -107.628703)
			(xy 339.259481 -107.599237) (xy 339.309058 -107.576595) (xy 339.361353 -107.56124) (xy 339.415301 -107.553484)
			(xy 339.469803 -107.553484) (xy 339.523751 -107.56124) (xy 339.576046 -107.576595) (xy 339.625623 -107.599237)
			(xy 339.671473 -107.628703) (xy 339.712664 -107.664394) (xy 339.748355 -107.705585) (xy 339.777821 -107.751435)
			(xy 339.800463 -107.801012) (xy 339.815818 -107.853307) (xy 339.823574 -107.907255) (xy 339.82406 -107.934506)
			(xy 339.823607 -107.961877) (xy 339.815788 -108.016057) (xy 339.800296 -108.068561) (xy 339.777451 -108.118307)
			(xy 339.747723 -108.164273) (xy 339.73008 -108.185204) (xy 339.729826 -108.185458) (xy 339.724242 -108.192546)
			(xy 339.717996 -108.209462) (xy 339.717634 -108.218478) (xy 339.717634 -108.285534) (xy 339.717967 -108.294553)
			(xy 339.724231 -108.311471) (xy 339.729826 -108.318554) (xy 339.73008 -108.318554) (xy 339.73008 -108.318808)
			(xy 339.747733 -108.339729) (xy 339.777444 -108.385704) (xy 339.800277 -108.435455) (xy 339.815765 -108.487958)
			(xy 339.823589 -108.542136) (xy 339.82406 -108.569506) (xy 339.823574 -108.596757) (xy 339.815818 -108.650705)
			(xy 339.800463 -108.703) (xy 339.777821 -108.752577) (xy 339.748355 -108.798427) (xy 339.712664 -108.839618)
			(xy 339.671473 -108.875309) (xy 339.625623 -108.904775) (xy 339.576046 -108.927417) (xy 339.523751 -108.942772)
			(xy 339.469803 -108.950528) (xy 339.415301 -108.950528) (xy 339.361353 -108.942772) (xy 339.309058 -108.927417)
			(xy 339.259481 -108.904775) (xy 339.213631 -108.875309) (xy 339.17244 -108.839618) (xy 339.136749 -108.798427)
			(xy 339.107283 -108.752577) (xy 339.084641 -108.703) (xy 339.069286 -108.650705) (xy 339.06153 -108.596757)
			(xy 339.061044 -108.569506) (xy 323.374807 -108.569506) (xy 323.350115 -108.607927) (xy 323.314424 -108.649118)
			(xy 323.273233 -108.684809) (xy 323.227383 -108.714275) (xy 323.177806 -108.736917) (xy 323.125511 -108.752272)
			(xy 323.071563 -108.760028) (xy 323.017061 -108.760028) (xy 322.963113 -108.752272) (xy 322.910818 -108.736917)
			(xy 322.861241 -108.714275) (xy 322.815391 -108.684809) (xy 322.7742 -108.649118) (xy 322.738509 -108.607927)
			(xy 322.709043 -108.562077) (xy 322.686401 -108.5125) (xy 322.671046 -108.460205) (xy 322.66329 -108.406257)
			(xy 322.662804 -108.379006) (xy 284.900624 -108.379006) (xy 284.900624 -109.176312) (xy 284.900134 -109.206296)
			(xy 284.892306 -109.265752) (xy 284.876785 -109.323677) (xy 284.853836 -109.379081) (xy 284.823852 -109.431015)
			(xy 284.787346 -109.478591) (xy 284.744941 -109.520996) (xy 284.697365 -109.557502) (xy 284.645431 -109.587486)
			(xy 284.590027 -109.610435) (xy 284.532102 -109.625956) (xy 284.472646 -109.633784) (xy 284.412678 -109.633784)
			(xy 284.353222 -109.625956) (xy 284.295297 -109.610435) (xy 284.239893 -109.587486) (xy 284.187959 -109.557502)
			(xy 284.140383 -109.520996) (xy 284.097978 -109.478591) (xy 284.061472 -109.431015) (xy 284.031488 -109.379081)
			(xy 284.008539 -109.323677) (xy 283.993018 -109.265752) (xy 283.98519 -109.206296) (xy 283.9847 -109.176312)
			(xy 283.567124 -109.176312) (xy 283.567124 -110.97641) (xy 285.8389 -110.97641) (xy 285.8389 -110.11281)
			(xy 285.83939 -110.082826) (xy 285.847218 -110.02337) (xy 285.862739 -109.965445) (xy 285.885688 -109.910041)
			(xy 285.915672 -109.858107) (xy 285.952178 -109.810531) (xy 285.994583 -109.768126) (xy 286.042159 -109.73162)
			(xy 286.094093 -109.701636) (xy 286.149497 -109.678687) (xy 286.207422 -109.663166) (xy 286.266878 -109.655338)
			(xy 286.326846 -109.655338) (xy 286.386302 -109.663166) (xy 286.444227 -109.678687) (xy 286.499631 -109.701636)
			(xy 286.551565 -109.73162) (xy 286.599141 -109.768126) (xy 286.641546 -109.810531) (xy 286.678052 -109.858107)
			(xy 286.708036 -109.910041) (xy 286.730985 -109.965445) (xy 286.746506 -110.02337) (xy 286.754334 -110.082826)
			(xy 286.754824 -110.11281) (xy 286.754824 -110.530132) (xy 302.62906 -110.530132) (xy 302.633131 -110.47451)
			(xy 302.645257 -110.420073) (xy 302.66518 -110.367982) (xy 302.692476 -110.319347) (xy 302.726562 -110.275204)
			(xy 302.766711 -110.236495) (xy 302.812069 -110.204044) (xy 302.861669 -110.178543) (xy 302.914453 -110.160536)
			(xy 302.969296 -110.150406) (xy 303.02503 -110.148369) (xy 303.080467 -110.154469) (xy 303.134424 -110.168575)
			(xy 303.185753 -110.190387) (xy 303.233359 -110.219441) (xy 303.276227 -110.255116) (xy 303.313444 -110.296653)
			(xy 303.344217 -110.343166) (xy 303.367889 -110.393663) (xy 303.383957 -110.44707) (xy 303.392077 -110.502246)
			(xy 303.392586 -110.530132) (xy 303.392077 -110.558018) (xy 303.383957 -110.613194) (xy 303.367889 -110.666601)
			(xy 303.344217 -110.717098) (xy 303.313444 -110.763611) (xy 303.276227 -110.805148) (xy 303.233359 -110.840823)
			(xy 303.185753 -110.869877) (xy 303.134424 -110.891689) (xy 303.080467 -110.905795) (xy 303.02503 -110.911895)
			(xy 302.969296 -110.909858) (xy 302.914453 -110.899728) (xy 302.861669 -110.881721) (xy 302.812069 -110.85622)
			(xy 302.766711 -110.823769) (xy 302.726562 -110.78506) (xy 302.692476 -110.740917) (xy 302.66518 -110.692282)
			(xy 302.645257 -110.640191) (xy 302.633131 -110.585754) (xy 302.62906 -110.530132) (xy 286.754824 -110.530132)
			(xy 286.754824 -110.97641) (xy 286.754334 -111.006394) (xy 286.746506 -111.06585) (xy 286.730985 -111.123775)
			(xy 286.708036 -111.179179) (xy 286.678052 -111.231113) (xy 286.641546 -111.278689) (xy 286.599141 -111.321094)
			(xy 286.551565 -111.3576) (xy 286.499631 -111.387584) (xy 286.444227 -111.410533) (xy 286.386302 -111.426054)
			(xy 286.326846 -111.433882) (xy 286.266878 -111.433882) (xy 286.207422 -111.426054) (xy 286.149497 -111.410533)
			(xy 286.094093 -111.387584) (xy 286.042159 -111.3576) (xy 285.994583 -111.321094) (xy 285.952178 -111.278689)
			(xy 285.915672 -111.231113) (xy 285.885688 -111.179179) (xy 285.862739 -111.123775) (xy 285.847218 -111.06585)
			(xy 285.83939 -111.006394) (xy 285.8389 -110.97641) (xy 283.567124 -110.97641) (xy 283.567124 -112.776508)
			(xy 283.9847 -112.776508) (xy 283.9847 -111.912908) (xy 283.98519 -111.882924) (xy 283.993018 -111.823468)
			(xy 284.008539 -111.765543) (xy 284.031488 -111.710139) (xy 284.061472 -111.658205) (xy 284.097978 -111.610629)
			(xy 284.140383 -111.568224) (xy 284.187959 -111.531718) (xy 284.239893 -111.501734) (xy 284.295297 -111.478785)
			(xy 284.353222 -111.463264) (xy 284.412678 -111.455436) (xy 284.472646 -111.455436) (xy 284.532102 -111.463264)
			(xy 284.590027 -111.478785) (xy 284.645431 -111.501734) (xy 284.697365 -111.531718) (xy 284.744941 -111.568224)
			(xy 284.787346 -111.610629) (xy 284.823852 -111.658205) (xy 284.853836 -111.710139) (xy 284.876785 -111.765543)
			(xy 284.892306 -111.823468) (xy 284.900134 -111.882924) (xy 284.900624 -111.912908) (xy 284.900624 -112.776508)
			(xy 284.900134 -112.806492) (xy 284.892306 -112.865948) (xy 284.876785 -112.923873) (xy 284.853836 -112.979277)
			(xy 284.823852 -113.031211) (xy 284.787346 -113.078787) (xy 284.744941 -113.121192) (xy 284.697365 -113.157698)
			(xy 284.645431 -113.187682) (xy 284.590027 -113.210631) (xy 284.532102 -113.226152) (xy 284.472646 -113.23398)
			(xy 284.412678 -113.23398) (xy 284.353222 -113.226152) (xy 284.295297 -113.210631) (xy 284.239893 -113.187682)
			(xy 284.187959 -113.157698) (xy 284.140383 -113.121192) (xy 284.097978 -113.078787) (xy 284.061472 -113.031211)
			(xy 284.031488 -112.979277) (xy 284.008539 -112.923873) (xy 283.993018 -112.865948) (xy 283.98519 -112.806492)
			(xy 283.9847 -112.776508) (xy 283.567124 -112.776508) (xy 283.567124 -113.344452) (xy 283.567568 -113.354519)
			(xy 283.575275 -113.373118) (xy 283.58211 -113.38052) (xy 285.814008 -115.612418) (xy 285.821409 -115.619256)
			(xy 285.840008 -115.626976) (xy 285.850076 -115.627404) (xy 287.13049 -115.627404) (xy 287.156513 -115.627957)
			(xy 287.207915 -115.636116) (xy 287.257412 -115.652204) (xy 287.303789 -115.675826) (xy 287.345907 -115.706402)
			(xy 287.364678 -115.724432) (xy 288.021776 -116.38153) (xy 288.051748 -116.387626) (xy 288.065972 -116.38153)
			(xy 288.07508 -116.377277) (xy 288.089318 -116.363118) (xy 288.097036 -116.34458) (xy 288.097468 -116.33454)
			(xy 288.097468 -115.975384) (xy 288.09728 -115.969234) (xy 288.094323 -115.957293) (xy 288.091626 -115.951762)
			(xy 288.07781 -115.924226) (xy 288.058238 -115.865814) (xy 288.048297 -115.805017) (xy 288.047684 -115.774216)
			(xy 288.04817 -115.746965) (xy 288.055926 -115.693017) (xy 288.071281 -115.640722) (xy 288.093923 -115.591145)
			(xy 288.123389 -115.545295) (xy 288.15908 -115.504104) (xy 288.200271 -115.468413) (xy 288.246121 -115.438947)
			(xy 288.295698 -115.416305) (xy 288.347993 -115.40095) (xy 288.401941 -115.393194) (xy 288.456443 -115.393194)
			(xy 288.510391 -115.40095) (xy 288.562686 -115.416305) (xy 288.612263 -115.438947) (xy 288.658113 -115.468413)
			(xy 288.699304 -115.504104) (xy 288.734995 -115.545295) (xy 288.764461 -115.591145) (xy 288.787103 -115.640722)
			(xy 288.802458 -115.693017) (xy 288.810214 -115.746965) (xy 288.8107 -115.774216) (xy 288.81009 -115.805019)
			(xy 288.800165 -115.86582) (xy 288.780591 -115.924234) (xy 288.766758 -115.951762) (xy 288.764054 -115.957291)
			(xy 288.761091 -115.969232) (xy 288.760916 -115.975384) (xy 288.760916 -116.458492) (xy 288.761341 -116.468561)
			(xy 288.769062 -116.487159) (xy 288.775902 -116.49456) (xy 290.202112 -117.920516) (xy 290.220122 -117.939307)
			(xy 290.250705 -117.981419) (xy 290.274336 -118.02779) (xy 290.290436 -118.077282) (xy 290.298609 -118.128682)
			(xy 290.29914 -118.154704) (xy 290.29914 -132.479288) (xy 290.298601 -132.505311) (xy 290.290441 -132.556715)
			(xy 290.274351 -132.606213) (xy 290.250725 -132.65259) (xy 290.220145 -132.694706) (xy 290.202112 -132.713476)
			(xy 288.553906 -134.361682) (xy 288.547082 -134.369095) (xy 288.539353 -134.387684) (xy 288.53892 -134.39775)
			(xy 288.53892 -134.62) (xy 288.890964 -134.62) (xy 288.891385 -134.587118) (xy 288.898753 -134.521769)
			(xy 288.913397 -134.457657) (xy 288.935131 -134.395588) (xy 288.963683 -134.336346) (xy 288.998693 -134.280676)
			(xy 289.039719 -134.229279) (xy 289.062668 -134.205726) (xy 291.27069 -131.997958) (xy 291.27754 -131.990565)
			(xy 291.285254 -131.971961) (xy 291.285676 -131.96189) (xy 291.285676 -116.308378) (xy 291.286146 -116.275525)
			(xy 291.293511 -116.210233) (xy 291.308134 -116.146174) (xy 291.329833 -116.084154) (xy 291.358333 -116.02495)
			(xy 291.393278 -115.969307) (xy 291.43423 -115.917923) (xy 291.457126 -115.894358) (xy 296.431716 -110.919768)
			(xy 296.455278 -110.896834) (xy 296.506692 -110.85584) (xy 296.562368 -110.820854) (xy 296.621609 -110.792316)
			(xy 296.68367 -110.770584) (xy 296.747773 -110.755931) (xy 296.813112 -110.748541) (xy 296.84599 -110.748064)
			(xy 296.881406 -110.748545) (xy 296.95172 -110.757082) (xy 297.020493 -110.774032) (xy 297.086721 -110.79915)
			(xy 297.149438 -110.832067) (xy 297.20773 -110.872305) (xy 297.260747 -110.919276) (xy 297.307715 -110.972295)
			(xy 297.34795 -111.030589) (xy 297.380864 -111.093308) (xy 297.405977 -111.159538) (xy 297.422924 -111.228311)
			(xy 297.431457 -111.298626) (xy 297.431968 -111.334042) (xy 297.4315 -111.366922) (xy 297.424138 -111.43227)
			(xy 297.409502 -111.496381) (xy 297.387775 -111.558448) (xy 297.359231 -111.617691) (xy 297.324229 -111.673362)
			(xy 297.283209 -111.724761) (xy 297.260264 -111.748316) (xy 297.12431 -111.884206) (xy 302.56429 -111.884206)
			(xy 302.568361 -111.828584) (xy 302.580487 -111.774147) (xy 302.60041 -111.722056) (xy 302.627706 -111.673421)
			(xy 302.661792 -111.629278) (xy 302.701941 -111.590569) (xy 302.747299 -111.558118) (xy 302.796899 -111.532617)
			(xy 302.849683 -111.51461) (xy 302.904526 -111.50448) (xy 302.96026 -111.502443) (xy 303.015697 -111.508543)
			(xy 303.069654 -111.522649) (xy 303.120983 -111.544461) (xy 303.168589 -111.573515) (xy 303.211457 -111.60919)
			(xy 303.248674 -111.650727) (xy 303.279447 -111.69724) (xy 303.303119 -111.747737) (xy 303.319187 -111.801144)
			(xy 303.327307 -111.85632) (xy 303.327816 -111.884206) (xy 303.327307 -111.912092) (xy 303.319187 -111.967268)
			(xy 303.315138 -111.980726) (xy 306.101496 -111.980726) (xy 306.102037 -111.951988) (xy 306.110655 -111.895161)
			(xy 306.127701 -111.840271) (xy 306.152789 -111.788559) (xy 306.185351 -111.741195) (xy 306.20462 -111.719868)
			(xy 306.211224 -111.71301) (xy 306.218336 -111.694976) (xy 306.218336 -111.606076) (xy 306.211224 -111.588042)
			(xy 306.20462 -111.581184) (xy 306.185375 -111.559835) (xy 306.152809 -111.512476) (xy 306.127717 -111.460768)
			(xy 306.110665 -111.405881) (xy 306.10204 -111.349056) (xy 306.102037 -111.291581) (xy 306.110656 -111.234756)
			(xy 306.127703 -111.179867) (xy 306.15279 -111.128157) (xy 306.185351 -111.080795) (xy 306.20462 -111.059468)
			(xy 306.211224 -111.05261) (xy 306.218336 -111.034576) (xy 306.218336 -110.945676) (xy 306.211224 -110.927642)
			(xy 306.20462 -110.920784) (xy 306.185375 -110.899435) (xy 306.152809 -110.852076) (xy 306.127717 -110.800368)
			(xy 306.110665 -110.745481) (xy 306.10204 -110.688656) (xy 306.102037 -110.631181) (xy 306.110656 -110.574356)
			(xy 306.127703 -110.519467) (xy 306.15279 -110.467757) (xy 306.185351 -110.420395) (xy 306.20462 -110.399068)
			(xy 306.211224 -110.39221) (xy 306.218336 -110.374176) (xy 306.218336 -110.285276) (xy 306.211224 -110.267242)
			(xy 306.20462 -110.260384) (xy 306.185375 -110.239035) (xy 306.152809 -110.191676) (xy 306.127717 -110.139968)
			(xy 306.110665 -110.085081) (xy 306.10204 -110.028256) (xy 306.102037 -109.970781) (xy 306.110656 -109.913956)
			(xy 306.127703 -109.859067) (xy 306.15279 -109.807357) (xy 306.185351 -109.759995) (xy 306.20462 -109.738668)
			(xy 306.211224 -109.73181) (xy 306.218336 -109.713776) (xy 306.218336 -109.624876) (xy 306.211224 -109.606842)
			(xy 306.20462 -109.599984) (xy 306.185359 -109.578649) (xy 306.152792 -109.531289) (xy 306.127698 -109.479579)
			(xy 306.110645 -109.42469) (xy 306.102019 -109.367864) (xy 306.101496 -109.339126) (xy 306.10198 -109.311874)
			(xy 306.109733 -109.257923) (xy 306.125086 -109.205625) (xy 306.147726 -109.156045) (xy 306.177191 -109.110192)
			(xy 306.212883 -109.068999) (xy 306.254074 -109.033305) (xy 306.299926 -109.003836) (xy 306.349505 -108.981194)
			(xy 306.401802 -108.965838) (xy 306.455752 -108.958081) (xy 306.483004 -108.957618) (xy 306.509318 -108.958077)
			(xy 306.561447 -108.965313) (xy 306.612091 -108.979633) (xy 306.66029 -109.000767) (xy 306.705133 -109.028315)
			(xy 306.745772 -109.061755) (xy 306.763928 -109.080808) (xy 306.771436 -109.088225) (xy 306.790727 -109.09674)
			(xy 306.801266 -109.097318) (xy 306.875942 -109.097318) (xy 306.886489 -109.096766) (xy 306.905784 -109.088246)
			(xy 306.91328 -109.080808) (xy 306.931454 -109.061771) (xy 306.972079 -109.028312) (xy 307.016916 -109.00075)
			(xy 307.065113 -108.979608) (xy 307.115757 -108.965287) (xy 307.167889 -108.958059) (xy 307.194204 -108.957618)
			(xy 307.221458 -108.958052) (xy 307.275411 -108.96581) (xy 307.327711 -108.981168) (xy 307.377293 -109.003813)
			(xy 307.423148 -109.033283) (xy 307.464341 -109.06898) (xy 307.500035 -109.110176) (xy 307.529502 -109.156033)
			(xy 307.552143 -109.205617) (xy 307.567496 -109.257918) (xy 307.57525 -109.311872) (xy 307.575712 -109.339126)
			(xy 307.575201 -109.367865) (xy 307.566575 -109.424693) (xy 307.549522 -109.479584) (xy 307.538426 -109.502448)
			(xy 341.614504 -109.502448) (xy 341.618575 -109.446826) (xy 341.630701 -109.392389) (xy 341.650624 -109.340298)
			(xy 341.67792 -109.291663) (xy 341.712006 -109.24752) (xy 341.752155 -109.208811) (xy 341.797513 -109.17636)
			(xy 341.847113 -109.150859) (xy 341.899897 -109.132852) (xy 341.95474 -109.122722) (xy 342.010474 -109.120685)
			(xy 342.065911 -109.126785) (xy 342.119868 -109.140891) (xy 342.171197 -109.162703) (xy 342.218803 -109.191757)
			(xy 342.261671 -109.227432) (xy 342.298888 -109.268969) (xy 342.329661 -109.315482) (xy 342.353333 -109.365979)
			(xy 342.369401 -109.419386) (xy 342.377521 -109.474562) (xy 342.37803 -109.502448) (xy 342.377521 -109.530334)
			(xy 342.369401 -109.58551) (xy 342.353333 -109.638917) (xy 342.329661 -109.689414) (xy 342.298888 -109.735927)
			(xy 342.261671 -109.777464) (xy 342.218803 -109.813139) (xy 342.171197 -109.842193) (xy 342.119868 -109.864005)
			(xy 342.065911 -109.878111) (xy 342.010474 -109.884211) (xy 341.95474 -109.882174) (xy 341.899897 -109.872044)
			(xy 341.847113 -109.854037) (xy 341.797513 -109.828536) (xy 341.752155 -109.796085) (xy 341.712006 -109.757376)
			(xy 341.67792 -109.713233) (xy 341.650624 -109.664598) (xy 341.630701 -109.612507) (xy 341.618575 -109.55807)
			(xy 341.614504 -109.502448) (xy 307.538426 -109.502448) (xy 307.524427 -109.531295) (xy 307.49186 -109.578657)
			(xy 307.472588 -109.599984) (xy 307.465984 -109.606842) (xy 307.458872 -109.624876) (xy 307.458872 -109.713776)
			(xy 307.465984 -109.73181) (xy 307.472588 -109.738668) (xy 307.491884 -109.759973) (xy 307.524447 -109.807339)
			(xy 307.549537 -109.859055) (xy 307.566584 -109.913949) (xy 307.575204 -109.970779) (xy 307.575201 -110.028259)
			(xy 307.566576 -110.085088) (xy 307.549523 -110.139981) (xy 307.524428 -110.191694) (xy 307.49186 -110.239057)
			(xy 307.472588 -110.260384) (xy 307.465984 -110.267242) (xy 307.458872 -110.285276) (xy 307.458872 -110.374176)
			(xy 307.465984 -110.39221) (xy 307.472588 -110.399068) (xy 307.491884 -110.420373) (xy 307.524447 -110.467739)
			(xy 307.549537 -110.519455) (xy 307.566584 -110.574349) (xy 307.573747 -110.621572) (xy 322.761102 -110.621572)
			(xy 322.76155 -110.595257) (xy 322.768789 -110.543128) (xy 322.783112 -110.492485) (xy 322.804248 -110.444286)
			(xy 322.831797 -110.399443) (xy 322.865239 -110.358804) (xy 322.884292 -110.340648) (xy 322.891717 -110.333147)
			(xy 322.900228 -110.313851) (xy 322.900802 -110.30331) (xy 322.900802 -110.228634) (xy 322.900267 -110.218085)
			(xy 322.891736 -110.19879) (xy 322.884292 -110.191296) (xy 322.86524 -110.173137) (xy 322.831783 -110.132508)
			(xy 322.804224 -110.087668) (xy 322.783085 -110.039468) (xy 322.768767 -109.988821) (xy 322.761541 -109.936688)
			(xy 322.761102 -109.910372) (xy 322.761588 -109.883121) (xy 322.769344 -109.829173) (xy 322.784699 -109.776878)
			(xy 322.807341 -109.727301) (xy 322.836807 -109.681451) (xy 322.872498 -109.64026) (xy 322.913689 -109.604569)
			(xy 322.959539 -109.575103) (xy 323.009116 -109.552461) (xy 323.061411 -109.537106) (xy 323.115359 -109.52935)
			(xy 323.169861 -109.52935) (xy 323.223809 -109.537106) (xy 323.276104 -109.552461) (xy 323.325681 -109.575103)
			(xy 323.371531 -109.604569) (xy 323.412722 -109.64026) (xy 323.448413 -109.681451) (xy 323.477879 -109.727301)
			(xy 323.500521 -109.776878) (xy 323.515876 -109.829173) (xy 323.523632 -109.883121) (xy 323.524118 -109.910372)
			(xy 323.523693 -109.936687) (xy 323.516449 -109.988817) (xy 323.502121 -110.039461) (xy 323.48098 -110.087659)
			(xy 323.453427 -110.132502) (xy 323.419982 -110.17314) (xy 323.400928 -110.191296) (xy 323.39353 -110.198821)
			(xy 323.385003 -110.218098) (xy 323.384418 -110.228634) (xy 323.384418 -110.30331) (xy 323.384923 -110.313863)
			(xy 323.393475 -110.333158) (xy 323.400928 -110.340648) (xy 323.420005 -110.358782) (xy 323.453459 -110.399417)
			(xy 323.481015 -110.444262) (xy 323.502149 -110.492467) (xy 323.516462 -110.543118) (xy 323.523682 -110.595255)
			(xy 323.524118 -110.621572) (xy 323.523632 -110.648823) (xy 323.515876 -110.702771) (xy 323.500521 -110.755066)
			(xy 323.477879 -110.804643) (xy 323.448413 -110.850493) (xy 323.412722 -110.891684) (xy 323.371531 -110.927375)
			(xy 323.325681 -110.956841) (xy 323.276104 -110.979483) (xy 323.223809 -110.994838) (xy 323.169861 -111.002594)
			(xy 323.115359 -111.002594) (xy 323.061411 -110.994838) (xy 323.009116 -110.979483) (xy 322.959539 -110.956841)
			(xy 322.913689 -110.927375) (xy 322.872498 -110.891684) (xy 322.836807 -110.850493) (xy 322.807341 -110.804643)
			(xy 322.784699 -110.755066) (xy 322.769344 -110.702771) (xy 322.761588 -110.648823) (xy 322.761102 -110.621572)
			(xy 307.573747 -110.621572) (xy 307.575204 -110.631179) (xy 307.575201 -110.688659) (xy 307.566576 -110.745488)
			(xy 307.549523 -110.800381) (xy 307.524428 -110.852094) (xy 307.49186 -110.899457) (xy 307.472588 -110.920784)
			(xy 307.465984 -110.927642) (xy 307.458872 -110.945676) (xy 307.458872 -111.034576) (xy 307.465984 -111.05261)
			(xy 307.472588 -111.059468) (xy 307.491884 -111.080773) (xy 307.524447 -111.128139) (xy 307.549537 -111.179855)
			(xy 307.566584 -111.234749) (xy 307.575204 -111.291579) (xy 307.575201 -111.349059) (xy 307.566576 -111.405888)
			(xy 307.549523 -111.460781) (xy 307.524428 -111.512494) (xy 307.49186 -111.559857) (xy 307.472588 -111.581184)
			(xy 307.465984 -111.588042) (xy 307.458872 -111.606076) (xy 307.458872 -111.694976) (xy 307.465984 -111.71301)
			(xy 307.472588 -111.719868) (xy 307.491875 -111.741181) (xy 307.524438 -111.788547) (xy 307.549527 -111.840262)
			(xy 307.566574 -111.895156) (xy 307.575193 -111.951986) (xy 307.575712 -111.980726) (xy 307.575246 -112.007978)
			(xy 307.567486 -112.061926) (xy 307.552128 -112.114221) (xy 307.529484 -112.163798) (xy 307.500016 -112.209648)
			(xy 307.464322 -112.250838) (xy 307.42313 -112.286529) (xy 307.405324 -112.297972) (xy 325.26986 -112.297972)
			(xy 325.27029 -112.271657) (xy 325.277529 -112.219526) (xy 325.291855 -112.168881) (xy 325.312994 -112.120682)
			(xy 325.340548 -112.07584) (xy 325.373994 -112.035203) (xy 325.39305 -112.017048) (xy 325.400469 -112.009541)
			(xy 325.408985 -111.99025) (xy 325.40956 -111.97971) (xy 325.40956 -111.905034) (xy 325.409038 -111.894483)
			(xy 325.400499 -111.875187) (xy 325.39305 -111.867696) (xy 325.37399 -111.849545) (xy 325.340535 -111.808913)
			(xy 325.312978 -111.764072) (xy 325.291841 -111.71587) (xy 325.277524 -111.665222) (xy 325.270299 -111.613088)
			(xy 325.26986 -111.586772) (xy 325.270346 -111.559521) (xy 325.278102 -111.505573) (xy 325.293457 -111.453278)
			(xy 325.316099 -111.403701) (xy 325.345565 -111.357851) (xy 325.381256 -111.31666) (xy 325.422447 -111.280969)
			(xy 325.468297 -111.251503) (xy 325.517874 -111.228861) (xy 325.570169 -111.213506) (xy 325.624117 -111.20575)
			(xy 325.678619 -111.20575) (xy 325.732567 -111.213506) (xy 325.784862 -111.228861) (xy 325.834439 -111.251503)
			(xy 325.880289 -111.280969) (xy 325.92148 -111.31666) (xy 325.957171 -111.357851) (xy 325.986637 -111.403701)
			(xy 326.009279 -111.453278) (xy 326.024634 -111.505573) (xy 326.03239 -111.559521) (xy 326.032876 -111.586772)
			(xy 326.032464 -111.613088) (xy 326.025219 -111.665219) (xy 326.01089 -111.715863) (xy 325.989747 -111.764062)
			(xy 325.962191 -111.808904) (xy 325.928742 -111.849541) (xy 325.909686 -111.867696) (xy 325.902282 -111.875215)
			(xy 325.893759 -111.894497) (xy 325.893176 -111.905034) (xy 325.893176 -111.97971) (xy 325.893693 -111.990261)
			(xy 325.902238 -112.009556) (xy 325.909686 -112.017048) (xy 325.928755 -112.03519) (xy 325.962212 -112.075822)
			(xy 325.989769 -112.120665) (xy 326.010905 -112.168869) (xy 326.025219 -112.219519) (xy 326.03244 -112.271655)
			(xy 326.032876 -112.297972) (xy 327.30186 -112.297972) (xy 327.30229 -112.271657) (xy 327.309529 -112.219526)
			(xy 327.323855 -112.168881) (xy 327.344994 -112.120682) (xy 327.372548 -112.07584) (xy 327.405994 -112.035203)
			(xy 327.42505 -112.017048) (xy 327.432469 -112.009541) (xy 327.440985 -111.99025) (xy 327.44156 -111.97971)
			(xy 327.44156 -111.905034) (xy 327.441038 -111.894483) (xy 327.432499 -111.875187) (xy 327.42505 -111.867696)
			(xy 327.40599 -111.849545) (xy 327.372535 -111.808913) (xy 327.344978 -111.764072) (xy 327.323841 -111.71587)
			(xy 327.309524 -111.665222) (xy 327.302299 -111.613088) (xy 327.30186 -111.586772) (xy 327.302346 -111.559521)
			(xy 327.310102 -111.505573) (xy 327.325457 -111.453278) (xy 327.348099 -111.403701) (xy 327.377565 -111.357851)
			(xy 327.413256 -111.31666) (xy 327.454447 -111.280969) (xy 327.500297 -111.251503) (xy 327.549874 -111.228861)
			(xy 327.602169 -111.213506) (xy 327.656117 -111.20575) (xy 327.710619 -111.20575) (xy 327.764567 -111.213506)
			(xy 327.816862 -111.228861) (xy 327.866439 -111.251503) (xy 327.912289 -111.280969) (xy 327.95348 -111.31666)
			(xy 327.989171 -111.357851) (xy 328.018637 -111.403701) (xy 328.041279 -111.453278) (xy 328.056634 -111.505573)
			(xy 328.06439 -111.559521) (xy 328.064876 -111.586772) (xy 328.064464 -111.613088) (xy 328.057219 -111.665219)
			(xy 328.04289 -111.715863) (xy 328.021747 -111.764062) (xy 327.994191 -111.808904) (xy 327.960742 -111.849541)
			(xy 327.941686 -111.867696) (xy 327.934282 -111.875215) (xy 327.925759 -111.894497) (xy 327.925176 -111.905034)
			(xy 327.925176 -111.97971) (xy 327.925693 -111.990261) (xy 327.934238 -112.009556) (xy 327.941686 -112.017048)
			(xy 327.960755 -112.03519) (xy 327.962752 -112.037615) (xy 329.756103 -112.037615) (xy 329.760416 -111.980345)
			(xy 329.773262 -111.924368) (xy 329.79435 -111.870948) (xy 329.823205 -111.821291) (xy 329.859175 -111.776519)
			(xy 329.87996 -111.756698) (xy 329.887358 -111.749174) (xy 329.895886 -111.729896) (xy 329.89647 -111.71936)
			(xy 329.89647 -111.644684) (xy 329.895972 -111.63413) (xy 329.887416 -111.614835) (xy 329.87996 -111.607346)
			(xy 329.860878 -111.589218) (xy 329.827424 -111.548581) (xy 329.79987 -111.503735) (xy 329.778736 -111.455529)
			(xy 329.764425 -111.404877) (xy 329.757206 -111.35274) (xy 329.75677 -111.326422) (xy 329.757256 -111.299171)
			(xy 329.765012 -111.245223) (xy 329.780367 -111.192928) (xy 329.803009 -111.143351) (xy 329.832475 -111.097501)
			(xy 329.868166 -111.05631) (xy 329.909357 -111.020619) (xy 329.955207 -110.991153) (xy 330.004784 -110.968511)
			(xy 330.057079 -110.953156) (xy 330.111027 -110.9454) (xy 330.165529 -110.9454) (xy 330.219477 -110.953156)
			(xy 330.271772 -110.968511) (xy 330.321349 -110.991153) (xy 330.367199 -111.020619) (xy 330.40839 -111.05631)
			(xy 330.444081 -111.097501) (xy 330.473547 -111.143351) (xy 330.496189 -111.192928) (xy 330.511544 -111.245223)
			(xy 330.5193 -111.299171) (xy 330.519786 -111.326422) (xy 330.519338 -111.352737) (xy 330.5121 -111.404866)
			(xy 330.497777 -111.455509) (xy 330.476641 -111.503708) (xy 330.449091 -111.548551) (xy 330.415649 -111.58919)
			(xy 330.396596 -111.607346) (xy 330.389172 -111.614848) (xy 330.380661 -111.634143) (xy 330.380086 -111.644684)
			(xy 330.380086 -111.71936) (xy 330.380627 -111.729908) (xy 330.389154 -111.749203) (xy 330.396596 -111.756698)
			(xy 330.417407 -111.776495) (xy 330.453384 -111.82127) (xy 330.482245 -111.870931) (xy 330.503337 -111.924356)
			(xy 330.516186 -111.980339) (xy 330.520499 -112.037615) (xy 332.294318 -112.037615) (xy 332.298631 -111.980344)
			(xy 332.311478 -111.924367) (xy 332.332567 -111.870947) (xy 332.361424 -111.82129) (xy 332.397396 -111.776518)
			(xy 332.418182 -111.756698) (xy 332.425584 -111.749177) (xy 332.434109 -111.729897) (xy 332.434692 -111.71936)
			(xy 332.434692 -111.644684) (xy 332.434188 -111.634131) (xy 332.425635 -111.614836) (xy 332.418182 -111.607346)
			(xy 332.399104 -111.589213) (xy 332.365649 -111.548578) (xy 332.338094 -111.503733) (xy 332.316959 -111.455528)
			(xy 332.302647 -111.404877) (xy 332.295428 -111.352739) (xy 332.294992 -111.326422) (xy 332.295478 -111.299171)
			(xy 332.303234 -111.245223) (xy 332.318589 -111.192928) (xy 332.341231 -111.143351) (xy 332.370697 -111.097501)
			(xy 332.406388 -111.05631) (xy 332.447579 -111.020619) (xy 332.493429 -110.991153) (xy 332.543006 -110.968511)
			(xy 332.595301 -110.953156) (xy 332.649249 -110.9454) (xy 332.703751 -110.9454) (xy 332.757699 -110.953156)
			(xy 332.809994 -110.968511) (xy 332.859571 -110.991153) (xy 332.905421 -111.020619) (xy 332.946612 -111.05631)
			(xy 332.982303 -111.097501) (xy 333.011769 -111.143351) (xy 333.034411 -111.192928) (xy 333.049766 -111.245223)
			(xy 333.057522 -111.299171) (xy 333.058008 -111.326422) (xy 333.057553 -111.352736) (xy 333.050315 -111.404865)
			(xy 333.035993 -111.455508) (xy 333.014859 -111.503707) (xy 332.987311 -111.54855) (xy 332.95387 -111.58919)
			(xy 332.934818 -111.607346) (xy 332.927397 -111.614851) (xy 332.918883 -111.634144) (xy 332.918308 -111.644684)
			(xy 332.918308 -111.71936) (xy 332.918843 -111.729909) (xy 332.927374 -111.749205) (xy 332.934818 -111.756698)
			(xy 332.955628 -111.776496) (xy 332.991603 -111.821272) (xy 333.020462 -111.870933) (xy 333.041553 -111.924357)
			(xy 333.054401 -111.98034) (xy 333.055424 -111.993923) (xy 336.497253 -111.993923) (xy 336.501565 -111.936653)
			(xy 336.514411 -111.880675) (xy 336.535502 -111.827255) (xy 336.564359 -111.777599) (xy 336.600333 -111.732829)
			(xy 336.62112 -111.71301) (xy 336.628522 -111.705489) (xy 336.637046 -111.686208) (xy 336.63763 -111.675672)
			(xy 336.63763 -111.600996) (xy 336.637108 -111.590446) (xy 336.628567 -111.571151) (xy 336.62112 -111.563658)
			(xy 336.600364 -111.543805) (xy 336.564385 -111.499039) (xy 336.535522 -111.449386) (xy 336.514425 -111.395969)
			(xy 336.501572 -111.339993) (xy 336.497253 -111.282723) (xy 336.501565 -111.225453) (xy 336.514411 -111.169475)
			(xy 336.535502 -111.116055) (xy 336.564359 -111.066399) (xy 336.600333 -111.021629) (xy 336.62112 -111.00181)
			(xy 336.628522 -110.994289) (xy 336.637046 -110.975008) (xy 336.63763 -110.964472) (xy 336.63763 -110.889796)
			(xy 336.637108 -110.879246) (xy 336.628567 -110.859951) (xy 336.62112 -110.852458) (xy 336.602055 -110.834312)
			(xy 336.568598 -110.793681) (xy 336.54104 -110.748839) (xy 336.519903 -110.700636) (xy 336.505588 -110.649986)
			(xy 336.498366 -110.597851) (xy 336.49793 -110.571534) (xy 336.498387 -110.54428) (xy 336.50614 -110.490327)
			(xy 336.521494 -110.438027) (xy 336.544135 -110.388444) (xy 336.573603 -110.342589) (xy 336.609298 -110.301395)
			(xy 336.650492 -110.265701) (xy 336.696348 -110.236233) (xy 336.745931 -110.213593) (xy 336.798231 -110.19824)
			(xy 336.852184 -110.190487) (xy 336.879438 -110.190026) (xy 336.905753 -110.19046) (xy 336.957884 -110.1977)
			(xy 337.008527 -110.212025) (xy 337.056726 -110.233164) (xy 337.101569 -110.260717) (xy 337.142207 -110.294161)
			(xy 337.160362 -110.313216) (xy 337.167894 -110.320605) (xy 337.187166 -110.329136) (xy 337.1977 -110.329726)
			(xy 337.272376 -110.329726) (xy 337.282925 -110.32919) (xy 337.30222 -110.320659) (xy 337.309714 -110.313216)
			(xy 337.327873 -110.294164) (xy 337.368502 -110.260706) (xy 337.413341 -110.233146) (xy 337.461541 -110.212007)
			(xy 337.512188 -110.197689) (xy 337.564322 -110.190464) (xy 337.590638 -110.190026) (xy 337.617892 -110.190443)
			(xy 337.671844 -110.198205) (xy 337.724142 -110.213567) (xy 337.773721 -110.236215) (xy 337.813342 -110.261683)
			(xy 339.114448 -110.261683) (xy 339.114448 -110.209717) (xy 339.122577 -110.158392) (xy 339.138635 -110.108969)
			(xy 339.162226 -110.062667) (xy 339.192769 -110.020626) (xy 339.229514 -109.98388) (xy 339.271554 -109.953334)
			(xy 339.317854 -109.929741) (xy 339.367276 -109.913681) (xy 339.418601 -109.905549) (xy 339.444584 -109.905038)
			(xy 339.47123 -109.905495) (xy 339.523833 -109.914032) (xy 339.574384 -109.930903) (xy 339.62157 -109.955671)
			(xy 339.664168 -109.987694) (xy 339.701072 -110.026139) (xy 339.716618 -110.047786) (xy 339.724982 -110.059072)
			(xy 339.746655 -110.076927) (xy 339.772369 -110.08821) (xy 339.800184 -110.092068) (xy 339.827999 -110.08821)
			(xy 339.853713 -110.076927) (xy 339.875386 -110.059072) (xy 339.88375 -110.047786) (xy 339.899313 -110.026158)
			(xy 339.936232 -109.987742) (xy 339.978833 -109.955743) (xy 340.026014 -109.930989) (xy 340.076553 -109.91412)
			(xy 340.129144 -109.905574) (xy 340.155784 -109.905038) (xy 340.181778 -109.905428) (xy 340.233125 -109.913558)
			(xy 340.282569 -109.929622) (xy 340.328891 -109.953222) (xy 340.37095 -109.983778) (xy 340.407712 -110.020538)
			(xy 340.43827 -110.062596) (xy 340.461872 -110.108916) (xy 340.477938 -110.158359) (xy 340.486071 -110.209706)
			(xy 340.486071 -110.261694) (xy 340.477938 -110.313041) (xy 340.461872 -110.362484) (xy 340.43827 -110.408804)
			(xy 340.407712 -110.450862) (xy 340.37095 -110.487622) (xy 340.332365 -110.515654) (xy 343.028014 -110.515654)
			(xy 343.032085 -110.460032) (xy 343.044211 -110.405595) (xy 343.064134 -110.353504) (xy 343.09143 -110.304869)
			(xy 343.125516 -110.260726) (xy 343.165665 -110.222017) (xy 343.211023 -110.189566) (xy 343.260623 -110.164065)
			(xy 343.313407 -110.146058) (xy 343.36825 -110.135928) (xy 343.423984 -110.133891) (xy 343.479421 -110.139991)
			(xy 343.533378 -110.154097) (xy 343.584707 -110.175909) (xy 343.632313 -110.204963) (xy 343.675181 -110.240638)
			(xy 343.712398 -110.282175) (xy 343.743171 -110.328688) (xy 343.766843 -110.379185) (xy 343.782911 -110.432592)
			(xy 343.791031 -110.487768) (xy 343.79154 -110.515654) (xy 343.791031 -110.54354) (xy 343.782911 -110.598716)
			(xy 343.766843 -110.652123) (xy 343.743171 -110.70262) (xy 343.712398 -110.749133) (xy 343.675181 -110.79067)
			(xy 343.632313 -110.826345) (xy 343.584707 -110.855399) (xy 343.533378 -110.877211) (xy 343.479421 -110.891317)
			(xy 343.423984 -110.897417) (xy 343.36825 -110.89538) (xy 343.313407 -110.88525) (xy 343.260623 -110.867243)
			(xy 343.211023 -110.841742) (xy 343.165665 -110.809291) (xy 343.125516 -110.770582) (xy 343.09143 -110.726439)
			(xy 343.064134 -110.677804) (xy 343.044211 -110.625713) (xy 343.032085 -110.571276) (xy 343.028014 -110.515654)
			(xy 340.332365 -110.515654) (xy 340.328891 -110.518178) (xy 340.282569 -110.541778) (xy 340.233125 -110.557842)
			(xy 340.181778 -110.565972) (xy 340.155784 -110.566454) (xy 340.12914 -110.56595) (xy 340.076539 -110.557423)
			(xy 340.025989 -110.540562) (xy 339.978802 -110.515803) (xy 339.936203 -110.483788) (xy 339.899297 -110.44535)
			(xy 339.88375 -110.423706) (xy 339.875386 -110.41242) (xy 339.853713 -110.394565) (xy 339.827999 -110.383282)
			(xy 339.800184 -110.379424) (xy 339.772369 -110.383282) (xy 339.746655 -110.394565) (xy 339.724982 -110.41242)
			(xy 339.716618 -110.423706) (xy 339.701011 -110.4453) (xy 339.664101 -110.483718) (xy 339.621509 -110.515721)
			(xy 339.574337 -110.540481) (xy 339.523805 -110.557357) (xy 339.471222 -110.565912) (xy 339.444584 -110.566454)
			(xy 339.418601 -110.565851) (xy 339.367276 -110.557719) (xy 339.317854 -110.541659) (xy 339.271554 -110.518066)
			(xy 339.229514 -110.48752) (xy 339.192769 -110.450774) (xy 339.162226 -110.408733) (xy 339.138635 -110.362431)
			(xy 339.122577 -110.313008) (xy 339.114448 -110.261683) (xy 337.813342 -110.261683) (xy 337.819573 -110.265688)
			(xy 337.860764 -110.301387) (xy 337.896455 -110.342584) (xy 337.92592 -110.388442) (xy 337.948558 -110.438026)
			(xy 337.96391 -110.490327) (xy 337.971663 -110.54428) (xy 337.972146 -110.571534) (xy 337.971718 -110.59785)
			(xy 337.964478 -110.64998) (xy 337.950152 -110.700625) (xy 337.929012 -110.748824) (xy 337.901458 -110.793666)
			(xy 337.868012 -110.834303) (xy 337.848956 -110.852458) (xy 337.841579 -110.860001) (xy 337.833039 -110.879264)
			(xy 337.832446 -110.889796) (xy 337.832446 -110.964472) (xy 337.832963 -110.975023) (xy 337.841505 -110.994319)
			(xy 337.848956 -111.00181) (xy 337.869776 -111.021597) (xy 337.905747 -111.066376) (xy 337.934603 -111.116039)
			(xy 337.9527 -111.161885) (xy 339.114423 -111.161885) (xy 339.114423 -111.109915) (xy 339.122553 -111.058586)
			(xy 339.138612 -111.00916) (xy 339.162205 -110.962855) (xy 339.192751 -110.92081) (xy 339.229498 -110.884061)
			(xy 339.271541 -110.853513) (xy 339.317845 -110.829918) (xy 339.36727 -110.813857) (xy 339.418599 -110.805725)
			(xy 339.444584 -110.805214) (xy 339.471229 -110.805681) (xy 339.523832 -110.814218) (xy 339.574382 -110.831088)
			(xy 339.621568 -110.855854) (xy 339.664166 -110.887874) (xy 339.701071 -110.926316) (xy 339.716618 -110.947962)
			(xy 339.724982 -110.959248) (xy 339.746655 -110.977103) (xy 339.772369 -110.988386) (xy 339.800184 -110.992244)
			(xy 339.827999 -110.988386) (xy 339.853713 -110.977103) (xy 339.875386 -110.959248) (xy 339.88375 -110.947962)
			(xy 339.899306 -110.926329) (xy 339.936227 -110.887914) (xy 339.97883 -110.855916) (xy 340.026012 -110.831163)
			(xy 340.076552 -110.814296) (xy 340.129144 -110.80575) (xy 340.155784 -110.805214) (xy 340.181776 -110.805652)
			(xy 340.23312 -110.813782) (xy 340.28256 -110.829844) (xy 340.328878 -110.853442) (xy 340.370935 -110.883996)
			(xy 340.407693 -110.920753) (xy 340.438249 -110.962808) (xy 340.46185 -111.009126) (xy 340.477914 -111.058565)
			(xy 340.486047 -111.109908) (xy 340.486047 -111.161892) (xy 340.477914 -111.213235) (xy 340.46185 -111.262674)
			(xy 340.438249 -111.308992) (xy 340.407693 -111.351047) (xy 340.370935 -111.387804) (xy 340.328878 -111.418358)
			(xy 340.28256 -111.441956) (xy 340.23312 -111.458018) (xy 340.181776 -111.466148) (xy 340.155784 -111.46663)
			(xy 340.129139 -111.466136) (xy 340.076537 -111.457609) (xy 340.025987 -111.440746) (xy 339.9788 -111.415985)
			(xy 339.936201 -111.383968) (xy 339.899296 -111.345527) (xy 339.88375 -111.323882) (xy 339.875386 -111.312596)
			(xy 339.853713 -111.294741) (xy 339.827999 -111.283458) (xy 339.800184 -111.2796) (xy 339.772369 -111.283458)
			(xy 339.746655 -111.294741) (xy 339.724982 -111.312596) (xy 339.716618 -111.323882) (xy 339.701033 -111.345493)
			(xy 339.664116 -111.383906) (xy 339.621519 -111.415905) (xy 339.574343 -111.440661) (xy 339.523808 -111.457534)
			(xy 339.471222 -111.466088) (xy 339.444584 -111.46663) (xy 339.418599 -111.466075) (xy 339.36727 -111.457943)
			(xy 339.317845 -111.441882) (xy 339.271541 -111.418287) (xy 339.229498 -111.387739) (xy 339.192751 -111.35099)
			(xy 339.162205 -111.308945) (xy 339.138612 -111.26264) (xy 339.122553 -111.213214) (xy 339.114423 -111.161885)
			(xy 337.9527 -111.161885) (xy 337.955692 -111.169465) (xy 337.968537 -111.225448) (xy 337.972849 -111.282723)
			(xy 337.96853 -111.339998) (xy 337.955678 -111.395979) (xy 337.934583 -111.449403) (xy 337.905721 -111.499063)
			(xy 337.869745 -111.543837) (xy 337.848956 -111.563658) (xy 337.841579 -111.571201) (xy 337.833039 -111.590464)
			(xy 337.832446 -111.600996) (xy 337.832446 -111.675672) (xy 337.832963 -111.686223) (xy 337.841505 -111.705519)
			(xy 337.848956 -111.71301) (xy 337.869776 -111.732797) (xy 337.905747 -111.777576) (xy 337.934603 -111.827239)
			(xy 337.955692 -111.880665) (xy 337.968537 -111.936648) (xy 337.972849 -111.993923) (xy 337.96853 -112.051198)
			(xy 337.9661 -112.061783) (xy 339.114446 -112.061783) (xy 339.114446 -112.009817) (xy 339.122575 -111.958491)
			(xy 339.138633 -111.909069) (xy 339.162224 -111.862766) (xy 339.192768 -111.820725) (xy 339.229512 -111.783978)
			(xy 339.271553 -111.753432) (xy 339.317854 -111.729839) (xy 339.367275 -111.713779) (xy 339.418601 -111.705647)
			(xy 339.444584 -111.705136) (xy 339.47123 -111.705594) (xy 339.523833 -111.714131) (xy 339.574384 -111.731002)
			(xy 339.62157 -111.75577) (xy 339.664168 -111.787792) (xy 339.701072 -111.826237) (xy 339.716618 -111.847884)
			(xy 339.724982 -111.85917) (xy 339.746655 -111.877025) (xy 339.772369 -111.888308) (xy 339.800184 -111.892166)
			(xy 339.827999 -111.888308) (xy 339.853713 -111.877025) (xy 339.875386 -111.85917) (xy 339.88375 -111.847884)
			(xy 339.899312 -111.826256) (xy 339.936231 -111.78784) (xy 339.978832 -111.755841) (xy 340.026013 -111.731087)
			(xy 340.076553 -111.714218) (xy 340.129144 -111.705672) (xy 340.155784 -111.705136) (xy 340.181778 -111.70553)
			(xy 340.233125 -111.71366) (xy 340.282568 -111.729723) (xy 340.32889 -111.753323) (xy 340.370949 -111.783879)
			(xy 340.372724 -111.785654) (xy 341.657684 -111.785654) (xy 341.661755 -111.730032) (xy 341.673881 -111.675595)
			(xy 341.693804 -111.623504) (xy 341.7211 -111.574869) (xy 341.755186 -111.530726) (xy 341.795335 -111.492017)
			(xy 341.840693 -111.459566) (xy 341.890293 -111.434065) (xy 341.943077 -111.416058) (xy 341.99792 -111.405928)
			(xy 342.053654 -111.403891) (xy 342.109091 -111.409991) (xy 342.163048 -111.424097) (xy 342.214377 -111.445909)
			(xy 342.261983 -111.474963) (xy 342.304851 -111.510638) (xy 342.342068 -111.552175) (xy 342.372841 -111.598688)
			(xy 342.396513 -111.649185) (xy 342.412581 -111.702592) (xy 342.420701 -111.757768) (xy 342.42121 -111.785654)
			(xy 342.420701 -111.81354) (xy 342.412581 -111.868716) (xy 342.396513 -111.922123) (xy 342.372841 -111.97262)
			(xy 342.342068 -112.019133) (xy 342.304851 -112.06067) (xy 342.261983 -112.096345) (xy 342.214377 -112.125399)
			(xy 342.163048 -112.147211) (xy 342.109091 -112.161317) (xy 342.053654 -112.167417) (xy 341.99792 -112.16538)
			(xy 341.943077 -112.15525) (xy 341.890293 -112.137243) (xy 341.840693 -112.111742) (xy 341.795335 -112.079291)
			(xy 341.755186 -112.040582) (xy 341.7211 -111.996439) (xy 341.693804 -111.947804) (xy 341.673881 -111.895713)
			(xy 341.661755 -111.841276) (xy 341.657684 -111.785654) (xy 340.372724 -111.785654) (xy 340.40771 -111.820639)
			(xy 340.438268 -111.862697) (xy 340.461871 -111.909017) (xy 340.477936 -111.95846) (xy 340.486069 -112.009806)
			(xy 340.486069 -112.061794) (xy 340.477936 -112.11314) (xy 340.461871 -112.162583) (xy 340.438268 -112.208903)
			(xy 340.40771 -112.250961) (xy 340.370949 -112.287721) (xy 340.358237 -112.296956) (xy 343.094816 -112.296956)
			(xy 343.098887 -112.241334) (xy 343.111013 -112.186897) (xy 343.130936 -112.134806) (xy 343.158232 -112.086171)
			(xy 343.192318 -112.042028) (xy 343.232467 -112.003319) (xy 343.277825 -111.970868) (xy 343.327425 -111.945367)
			(xy 343.380209 -111.92736) (xy 343.435052 -111.91723) (xy 343.490786 -111.915193) (xy 343.546223 -111.921293)
			(xy 343.60018 -111.935399) (xy 343.651509 -111.957211) (xy 343.699115 -111.986265) (xy 343.741983 -112.02194)
			(xy 343.7792 -112.063477) (xy 343.809973 -112.10999) (xy 343.833645 -112.160487) (xy 343.849713 -112.213894)
			(xy 343.857833 -112.26907) (xy 343.858342 -112.296956) (xy 343.857833 -112.324842) (xy 343.849713 -112.380018)
			(xy 343.833645 -112.433425) (xy 343.809973 -112.483922) (xy 343.7792 -112.530435) (xy 343.741983 -112.571972)
			(xy 343.699115 -112.607647) (xy 343.651509 -112.636701) (xy 343.60018 -112.658513) (xy 343.546223 -112.672619)
			(xy 343.490786 -112.678719) (xy 343.435052 -112.676682) (xy 343.380209 -112.666552) (xy 343.327425 -112.648545)
			(xy 343.277825 -112.623044) (xy 343.232467 -112.590593) (xy 343.192318 -112.551884) (xy 343.158232 -112.507741)
			(xy 343.130936 -112.459106) (xy 343.111013 -112.407015) (xy 343.098887 -112.352578) (xy 343.094816 -112.296956)
			(xy 340.358237 -112.296956) (xy 340.32889 -112.318277) (xy 340.282568 -112.341877) (xy 340.233125 -112.35794)
			(xy 340.181778 -112.36607) (xy 340.155784 -112.366552) (xy 340.12914 -112.366049) (xy 340.076538 -112.357522)
			(xy 340.025989 -112.34066) (xy 339.978802 -112.315901) (xy 339.936203 -112.283887) (xy 339.899297 -112.245448)
			(xy 339.88375 -112.223804) (xy 339.875386 -112.212518) (xy 339.853713 -112.194663) (xy 339.827999 -112.18338)
			(xy 339.800184 -112.179522) (xy 339.772369 -112.18338) (xy 339.746655 -112.194663) (xy 339.724982 -112.212518)
			(xy 339.716618 -112.223804) (xy 339.70101 -112.245398) (xy 339.664101 -112.283816) (xy 339.621509 -112.315819)
			(xy 339.574337 -112.340579) (xy 339.523805 -112.357455) (xy 339.471221 -112.36601) (xy 339.444584 -112.366552)
			(xy 339.418601 -112.365953) (xy 339.367275 -112.357821) (xy 339.317854 -112.341761) (xy 339.271553 -112.318168)
			(xy 339.229512 -112.287622) (xy 339.192768 -112.250875) (xy 339.162224 -112.208834) (xy 339.138633 -112.162531)
			(xy 339.122575 -112.113109) (xy 339.114446 -112.061783) (xy 337.9661 -112.061783) (xy 337.955678 -112.107179)
			(xy 337.934583 -112.160603) (xy 337.905721 -112.210263) (xy 337.869745 -112.255037) (xy 337.848956 -112.274858)
			(xy 337.841579 -112.282401) (xy 337.833039 -112.301664) (xy 337.832446 -112.312196) (xy 337.832446 -112.386872)
			(xy 337.832963 -112.397423) (xy 337.841505 -112.416719) (xy 337.848956 -112.42421) (xy 337.86802 -112.442357)
			(xy 337.901474 -112.48299) (xy 337.929031 -112.527832) (xy 337.950167 -112.576034) (xy 337.964483 -112.626683)
			(xy 337.971708 -112.678818) (xy 337.972146 -112.705134) (xy 337.971654 -112.732384) (xy 337.963894 -112.78633)
			(xy 337.948536 -112.838622) (xy 337.925894 -112.888197) (xy 337.896428 -112.934045) (xy 337.872387 -112.961789)
			(xy 339.114368 -112.961789) (xy 339.114368 -112.909811) (xy 339.122498 -112.858473) (xy 339.13856 -112.809038)
			(xy 339.162157 -112.762725) (xy 339.192708 -112.720674) (xy 339.229461 -112.683919) (xy 339.271512 -112.653365)
			(xy 339.317824 -112.629766) (xy 339.367257 -112.613702) (xy 339.418595 -112.605569) (xy 339.444584 -112.605058)
			(xy 339.47123 -112.605507) (xy 339.523835 -112.614044) (xy 339.574386 -112.630917) (xy 339.621572 -112.655686)
			(xy 339.66417 -112.68771) (xy 339.701073 -112.726158) (xy 339.716618 -112.747806) (xy 339.724982 -112.759092)
			(xy 339.746655 -112.776947) (xy 339.772369 -112.78823) (xy 339.800184 -112.792088) (xy 339.827999 -112.78823)
			(xy 339.853713 -112.776947) (xy 339.875386 -112.759092) (xy 339.88375 -112.747806) (xy 339.899289 -112.726161)
			(xy 339.936216 -112.687749) (xy 339.978822 -112.655755) (xy 340.026008 -112.631004) (xy 340.07655 -112.614139)
			(xy 340.129143 -112.605594) (xy 340.155784 -112.605058) (xy 340.181771 -112.605608) (xy 340.233107 -112.613736)
			(xy 340.282538 -112.629795) (xy 340.328849 -112.65339) (xy 340.370898 -112.683939) (xy 340.407651 -112.72069)
			(xy 340.438202 -112.762737) (xy 340.461798 -112.809047) (xy 340.47786 -112.858478) (xy 340.485991 -112.909813)
			(xy 340.485991 -112.961787) (xy 340.47786 -113.013122) (xy 340.461798 -113.062553) (xy 340.438202 -113.108863)
			(xy 340.407651 -113.15091) (xy 340.370898 -113.187661) (xy 340.328849 -113.21821) (xy 340.282538 -113.241805)
			(xy 340.233107 -113.257864) (xy 340.181771 -113.265992) (xy 340.155784 -113.266474) (xy 340.12914 -113.265961)
			(xy 340.07654 -113.257435) (xy 340.025991 -113.240575) (xy 339.978804 -113.215817) (xy 339.936205 -113.183805)
			(xy 339.899297 -113.145369) (xy 339.88375 -113.123726) (xy 339.875386 -113.11244) (xy 339.853713 -113.094585)
			(xy 339.827999 -113.083302) (xy 339.800184 -113.079444) (xy 339.772369 -113.083302) (xy 339.746655 -113.094585)
			(xy 339.724982 -113.11244) (xy 339.716618 -113.123726) (xy 339.701017 -113.145325) (xy 339.664105 -113.183741)
			(xy 339.621512 -113.215743) (xy 339.574339 -113.240502) (xy 339.523806 -113.257377) (xy 339.471222 -113.265932)
			(xy 339.444584 -113.266474) (xy 339.418595 -113.266031) (xy 339.367257 -113.257898) (xy 339.317824 -113.241834)
			(xy 339.271512 -113.218235) (xy 339.229461 -113.187681) (xy 339.192708 -113.150926) (xy 339.162157 -113.108875)
			(xy 339.13856 -113.062562) (xy 339.122498 -113.013127) (xy 339.114368 -112.961789) (xy 337.872387 -112.961789)
			(xy 337.860737 -112.975234) (xy 337.819549 -113.010925) (xy 337.773701 -113.040392) (xy 337.724126 -113.063035)
			(xy 337.671834 -113.078393) (xy 337.617888 -113.086154) (xy 337.590638 -113.086642) (xy 337.564322 -113.086234)
			(xy 337.51219 -113.07899) (xy 337.461545 -113.06466) (xy 337.413346 -113.043517) (xy 337.368504 -113.015959)
			(xy 337.327868 -112.982509) (xy 337.309714 -112.963452) (xy 337.302182 -112.956062) (xy 337.28291 -112.947529)
			(xy 337.272376 -112.946942) (xy 337.1977 -112.946942) (xy 337.187147 -112.947445) (xy 337.167851 -112.955997)
			(xy 337.160362 -112.963452) (xy 337.142228 -112.982529) (xy 337.101593 -113.015982) (xy 337.056747 -113.043537)
			(xy 337.008543 -113.064671) (xy 336.957892 -113.078985) (xy 336.905755 -113.086205) (xy 336.879438 -113.086642)
			(xy 336.852188 -113.086109) (xy 336.798241 -113.078359) (xy 336.745946 -113.063009) (xy 336.696369 -113.040373)
			(xy 336.650517 -113.010913) (xy 336.609325 -112.975226) (xy 336.573631 -112.934041) (xy 336.544161 -112.888195)
			(xy 336.521516 -112.838621) (xy 336.506157 -112.786329) (xy 336.498396 -112.732384) (xy 336.49793 -112.705134)
			(xy 336.498344 -112.678818) (xy 336.505588 -112.626687) (xy 336.519917 -112.576043) (xy 336.54106 -112.527844)
			(xy 336.568616 -112.483002) (xy 336.602064 -112.442365) (xy 336.62112 -112.42421) (xy 336.628522 -112.416689)
			(xy 336.637046 -112.397408) (xy 336.63763 -112.386872) (xy 336.63763 -112.312196) (xy 336.637108 -112.301646)
			(xy 336.628567 -112.282351) (xy 336.62112 -112.274858) (xy 336.600364 -112.255005) (xy 336.564385 -112.210239)
			(xy 336.535522 -112.160586) (xy 336.514425 -112.107169) (xy 336.501572 -112.051193) (xy 336.497253 -111.993923)
			(xy 333.055424 -111.993923) (xy 333.058714 -112.037615) (xy 333.054396 -112.09489) (xy 333.041544 -112.150871)
			(xy 333.020449 -112.204294) (xy 332.991586 -112.253953) (xy 332.955607 -112.298726) (xy 332.934818 -112.318546)
			(xy 332.927397 -112.326051) (xy 332.918883 -112.345344) (xy 332.918308 -112.355884) (xy 332.918308 -112.43056)
			(xy 332.918843 -112.441109) (xy 332.927374 -112.460405) (xy 332.934818 -112.467898) (xy 332.953869 -112.486058)
			(xy 332.987326 -112.526687) (xy 333.014885 -112.571527) (xy 333.036024 -112.619726) (xy 333.050343 -112.670373)
			(xy 333.057569 -112.722506) (xy 333.058008 -112.748822) (xy 333.057522 -112.776073) (xy 333.049766 -112.830021)
			(xy 333.034411 -112.882316) (xy 333.011769 -112.931893) (xy 332.982303 -112.977743) (xy 332.946612 -113.018934)
			(xy 332.905421 -113.054625) (xy 332.859571 -113.084091) (xy 332.809994 -113.106733) (xy 332.757699 -113.122088)
			(xy 332.703751 -113.129844) (xy 332.649249 -113.129844) (xy 332.595301 -113.122088) (xy 332.543006 -113.106733)
			(xy 332.493429 -113.084091) (xy 332.447579 -113.054625) (xy 332.406388 -113.018934) (xy 332.370697 -112.977743)
			(xy 332.341231 -112.931893) (xy 332.318589 -112.882316) (xy 332.303234 -112.830021) (xy 332.295478 -112.776073)
			(xy 332.294992 -112.748822) (xy 332.295477 -112.722509) (xy 332.302708 -112.670381) (xy 332.317024 -112.619739)
			(xy 332.338153 -112.57154) (xy 332.365696 -112.526696) (xy 332.399132 -112.486055) (xy 332.418182 -112.467898)
			(xy 332.425584 -112.460377) (xy 332.434109 -112.441097) (xy 332.434692 -112.43056) (xy 332.434692 -112.355884)
			(xy 332.434188 -112.345331) (xy 332.425635 -112.326036) (xy 332.418182 -112.318546) (xy 332.397416 -112.298704)
			(xy 332.361441 -112.253935) (xy 332.33258 -112.20428) (xy 332.311487 -112.150861) (xy 332.298636 -112.094885)
			(xy 332.294318 -112.037615) (xy 330.520499 -112.037615) (xy 330.516181 -112.094891) (xy 330.503328 -112.150872)
			(xy 330.482232 -112.204296) (xy 330.453367 -112.253954) (xy 330.417387 -112.298727) (xy 330.396596 -112.318546)
			(xy 330.389172 -112.326048) (xy 330.380661 -112.345343) (xy 330.380086 -112.355884) (xy 330.380086 -112.43056)
			(xy 330.380627 -112.441108) (xy 330.389154 -112.460403) (xy 330.396596 -112.467898) (xy 330.415643 -112.486062)
			(xy 330.449101 -112.52669) (xy 330.476661 -112.571528) (xy 330.497801 -112.619728) (xy 330.51212 -112.670374)
			(xy 330.519347 -112.722506) (xy 330.519786 -112.748822) (xy 330.5193 -112.776073) (xy 330.511544 -112.830021)
			(xy 330.496189 -112.882316) (xy 330.473547 -112.931893) (xy 330.444081 -112.977743) (xy 330.40839 -113.018934)
			(xy 330.367199 -113.054625) (xy 330.321349 -113.084091) (xy 330.271772 -113.106733) (xy 330.219477 -113.122088)
			(xy 330.165529 -113.129844) (xy 330.111027 -113.129844) (xy 330.057079 -113.122088) (xy 330.004784 -113.106733)
			(xy 329.955207 -113.084091) (xy 329.909357 -113.054625) (xy 329.868166 -113.018934) (xy 329.832475 -112.977743)
			(xy 329.803009 -112.931893) (xy 329.780367 -112.882316) (xy 329.765012 -112.830021) (xy 329.757256 -112.776073)
			(xy 329.75677 -112.748822) (xy 329.757262 -112.722509) (xy 329.764493 -112.670382) (xy 329.778808 -112.61974)
			(xy 329.799936 -112.571541) (xy 329.827477 -112.526697) (xy 329.860911 -112.486056) (xy 329.87996 -112.467898)
			(xy 329.887358 -112.460374) (xy 329.895886 -112.441096) (xy 329.89647 -112.43056) (xy 329.89647 -112.355884)
			(xy 329.895972 -112.34533) (xy 329.887416 -112.326035) (xy 329.87996 -112.318546) (xy 329.859195 -112.298703)
			(xy 329.823222 -112.253933) (xy 329.794363 -112.204279) (xy 329.773271 -112.15086) (xy 329.760421 -112.094884)
			(xy 329.756103 -112.037615) (xy 327.962752 -112.037615) (xy 327.994212 -112.075822) (xy 328.021769 -112.120665)
			(xy 328.042905 -112.168869) (xy 328.057219 -112.219519) (xy 328.06444 -112.271655) (xy 328.064876 -112.297972)
			(xy 328.06439 -112.325223) (xy 328.056634 -112.379171) (xy 328.041279 -112.431466) (xy 328.018637 -112.481043)
			(xy 327.989171 -112.526893) (xy 327.95348 -112.568084) (xy 327.912289 -112.603775) (xy 327.866439 -112.633241)
			(xy 327.816862 -112.655883) (xy 327.764567 -112.671238) (xy 327.710619 -112.678994) (xy 327.656117 -112.678994)
			(xy 327.602169 -112.671238) (xy 327.549874 -112.655883) (xy 327.500297 -112.633241) (xy 327.454447 -112.603775)
			(xy 327.413256 -112.568084) (xy 327.377565 -112.526893) (xy 327.348099 -112.481043) (xy 327.325457 -112.431466)
			(xy 327.310102 -112.379171) (xy 327.302346 -112.325223) (xy 327.30186 -112.297972) (xy 326.032876 -112.297972)
			(xy 326.03239 -112.325223) (xy 326.024634 -112.379171) (xy 326.009279 -112.431466) (xy 325.986637 -112.481043)
			(xy 325.957171 -112.526893) (xy 325.92148 -112.568084) (xy 325.880289 -112.603775) (xy 325.834439 -112.633241)
			(xy 325.784862 -112.655883) (xy 325.732567 -112.671238) (xy 325.678619 -112.678994) (xy 325.624117 -112.678994)
			(xy 325.570169 -112.671238) (xy 325.517874 -112.655883) (xy 325.468297 -112.633241) (xy 325.422447 -112.603775)
			(xy 325.381256 -112.568084) (xy 325.345565 -112.526893) (xy 325.316099 -112.481043) (xy 325.293457 -112.431466)
			(xy 325.278102 -112.379171) (xy 325.270346 -112.325223) (xy 325.26986 -112.297972) (xy 307.405324 -112.297972)
			(xy 307.377279 -112.315995) (xy 307.3277 -112.338636) (xy 307.275404 -112.353991) (xy 307.221456 -112.361748)
			(xy 307.194204 -112.362234) (xy 307.167891 -112.361753) (xy 307.115763 -112.354519) (xy 307.065121 -112.340202)
			(xy 307.016922 -112.319072) (xy 306.972078 -112.291529) (xy 306.931438 -112.258094) (xy 306.91328 -112.239044)
			(xy 306.905762 -112.231638) (xy 306.886479 -112.223115) (xy 306.875942 -112.222534) (xy 306.801266 -112.222534)
			(xy 306.790717 -112.223075) (xy 306.771421 -112.231601) (xy 306.763928 -112.239044) (xy 306.74576 -112.258087)
			(xy 306.705132 -112.291544) (xy 306.660294 -112.319103) (xy 306.612096 -112.340244) (xy 306.561451 -112.354564)
			(xy 306.509319 -112.361793) (xy 306.483004 -112.362234) (xy 306.455754 -112.361719) (xy 306.401809 -112.353963)
			(xy 306.349516 -112.33861) (xy 306.299941 -112.315971) (xy 306.254091 -112.286508) (xy 306.212902 -112.250819)
			(xy 306.17721 -112.209633) (xy 306.147743 -112.163786) (xy 306.125101 -112.114212) (xy 306.109743 -112.061921)
			(xy 306.101984 -112.007976) (xy 306.101496 -111.980726) (xy 303.315138 -111.980726) (xy 303.303119 -112.020675)
			(xy 303.279447 -112.071172) (xy 303.248674 -112.117685) (xy 303.211457 -112.159222) (xy 303.168589 -112.194897)
			(xy 303.120983 -112.223951) (xy 303.069654 -112.245763) (xy 303.015697 -112.259869) (xy 302.96026 -112.265969)
			(xy 302.904526 -112.263932) (xy 302.849683 -112.253802) (xy 302.796899 -112.235795) (xy 302.747299 -112.210294)
			(xy 302.701941 -112.177843) (xy 302.661792 -112.139134) (xy 302.627706 -112.094991) (xy 302.60041 -112.046356)
			(xy 302.580487 -111.994265) (xy 302.568361 -111.939828) (xy 302.56429 -111.884206) (xy 297.12431 -111.884206)
			(xy 296.720514 -112.287812) (xy 296.715688 -112.320578) (xy 296.723308 -112.33531) (xy 296.73675 -112.362548)
			(xy 296.755769 -112.420231) (xy 296.765395 -112.480201) (xy 296.765496 -112.485424) (xy 298.851064 -112.485424)
			(xy 298.855135 -112.429802) (xy 298.867261 -112.375365) (xy 298.887184 -112.323274) (xy 298.91448 -112.274639)
			(xy 298.948566 -112.230496) (xy 298.988715 -112.191787) (xy 299.034073 -112.159336) (xy 299.083673 -112.133835)
			(xy 299.136457 -112.115828) (xy 299.1913 -112.105698) (xy 299.247034 -112.103661) (xy 299.302471 -112.109761)
			(xy 299.356428 -112.123867) (xy 299.407757 -112.145679) (xy 299.455363 -112.174733) (xy 299.498231 -112.210408)
			(xy 299.535448 -112.251945) (xy 299.566221 -112.298458) (xy 299.589893 -112.348955) (xy 299.605961 -112.402362)
			(xy 299.60884 -112.421924) (xy 301.65497 -112.421924) (xy 301.659041 -112.366302) (xy 301.671167 -112.311865)
			(xy 301.69109 -112.259774) (xy 301.718386 -112.211139) (xy 301.752472 -112.166996) (xy 301.792621 -112.128287)
			(xy 301.837979 -112.095836) (xy 301.887579 -112.070335) (xy 301.940363 -112.052328) (xy 301.995206 -112.042198)
			(xy 302.05094 -112.040161) (xy 302.106377 -112.046261) (xy 302.160334 -112.060367) (xy 302.211663 -112.082179)
			(xy 302.259269 -112.111233) (xy 302.302137 -112.146908) (xy 302.339354 -112.188445) (xy 302.370127 -112.234958)
			(xy 302.393799 -112.285455) (xy 302.409867 -112.338862) (xy 302.417987 -112.394038) (xy 302.418496 -112.421924)
			(xy 302.417987 -112.44981) (xy 302.409867 -112.504986) (xy 302.393799 -112.558393) (xy 302.370127 -112.60889)
			(xy 302.339354 -112.655403) (xy 302.302137 -112.69694) (xy 302.259269 -112.732615) (xy 302.211663 -112.761669)
			(xy 302.160334 -112.783481) (xy 302.106377 -112.797587) (xy 302.05094 -112.803687) (xy 301.995206 -112.80165)
			(xy 301.940363 -112.79152) (xy 301.887579 -112.773513) (xy 301.837979 -112.748012) (xy 301.792621 -112.715561)
			(xy 301.752472 -112.676852) (xy 301.718386 -112.632709) (xy 301.69109 -112.584074) (xy 301.671167 -112.531983)
			(xy 301.659041 -112.477546) (xy 301.65497 -112.421924) (xy 299.60884 -112.421924) (xy 299.614081 -112.457538)
			(xy 299.61459 -112.485424) (xy 299.614081 -112.51331) (xy 299.605961 -112.568486) (xy 299.589893 -112.621893)
			(xy 299.566221 -112.67239) (xy 299.535448 -112.718903) (xy 299.498231 -112.76044) (xy 299.455363 -112.796115)
			(xy 299.407757 -112.825169) (xy 299.356428 -112.846981) (xy 299.302471 -112.861087) (xy 299.247034 -112.867187)
			(xy 299.1913 -112.86515) (xy 299.136457 -112.85502) (xy 299.083673 -112.837013) (xy 299.034073 -112.811512)
			(xy 298.988715 -112.779061) (xy 298.948566 -112.740352) (xy 298.91448 -112.696209) (xy 298.887184 -112.647574)
			(xy 298.867261 -112.595483) (xy 298.855135 -112.541046) (xy 298.851064 -112.485424) (xy 296.765496 -112.485424)
			(xy 296.76598 -112.51057) (xy 296.76598 -112.510824) (xy 296.765567 -112.538079) (xy 296.757806 -112.592033)
			(xy 296.742446 -112.644334) (xy 296.719799 -112.693916) (xy 296.690325 -112.73977) (xy 296.654626 -112.780963)
			(xy 296.613428 -112.816657) (xy 296.56757 -112.846124) (xy 296.517985 -112.868764) (xy 296.465682 -112.884117)
			(xy 296.411727 -112.891871) (xy 296.384472 -112.892332) (xy 296.384218 -112.892332) (xy 296.353851 -112.891728)
			(xy 296.293887 -112.88209) (xy 296.236202 -112.863086) (xy 296.208958 -112.84966) (xy 296.194226 -112.84204)
			(xy 296.16146 -112.846866) (xy 295.756584 -113.251742) (xy 296.506136 -113.251742) (xy 296.510207 -113.19612)
			(xy 296.522333 -113.141683) (xy 296.542256 -113.089592) (xy 296.569552 -113.040957) (xy 296.603638 -112.996814)
			(xy 296.643787 -112.958105) (xy 296.689145 -112.925654) (xy 296.738745 -112.900153) (xy 296.791529 -112.882146)
			(xy 296.846372 -112.872016) (xy 296.902106 -112.869979) (xy 296.957543 -112.876079) (xy 297.0115 -112.890185)
			(xy 297.062829 -112.911997) (xy 297.110435 -112.941051) (xy 297.153303 -112.976726) (xy 297.164851 -112.989614)
			(xy 302.639982 -112.989614) (xy 302.644053 -112.933992) (xy 302.656179 -112.879555) (xy 302.676102 -112.827464)
			(xy 302.703398 -112.778829) (xy 302.737484 -112.734686) (xy 302.777633 -112.695977) (xy 302.822991 -112.663526)
			(xy 302.872591 -112.638025) (xy 302.925375 -112.620018) (xy 302.980218 -112.609888) (xy 303.035952 -112.607851)
			(xy 303.091389 -112.613951) (xy 303.145346 -112.628057) (xy 303.196675 -112.649869) (xy 303.244281 -112.678923)
			(xy 303.287149 -112.714598) (xy 303.324366 -112.756135) (xy 303.355139 -112.802648) (xy 303.378811 -112.853145)
			(xy 303.394879 -112.906552) (xy 303.402999 -112.961728) (xy 303.403508 -112.989614) (xy 303.402999 -113.0175)
			(xy 303.394879 -113.072676) (xy 303.378811 -113.126083) (xy 303.355139 -113.17658) (xy 303.324366 -113.223093)
			(xy 303.287149 -113.26463) (xy 303.244281 -113.300305) (xy 303.196675 -113.329359) (xy 303.145346 -113.351171)
			(xy 303.091389 -113.365277) (xy 303.035952 -113.371377) (xy 302.980218 -113.36934) (xy 302.925375 -113.35921)
			(xy 302.872591 -113.341203) (xy 302.822991 -113.315702) (xy 302.777633 -113.283251) (xy 302.737484 -113.244542)
			(xy 302.703398 -113.200399) (xy 302.676102 -113.151764) (xy 302.656179 -113.099673) (xy 302.644053 -113.045236)
			(xy 302.639982 -112.989614) (xy 297.164851 -112.989614) (xy 297.19052 -113.018263) (xy 297.221293 -113.064776)
			(xy 297.244965 -113.115273) (xy 297.261033 -113.16868) (xy 297.269153 -113.223856) (xy 297.269662 -113.251742)
			(xy 297.269153 -113.279628) (xy 297.261033 -113.334804) (xy 297.244965 -113.388211) (xy 297.22297 -113.43513)
			(xy 299.130718 -113.43513) (xy 299.134789 -113.379508) (xy 299.146915 -113.325071) (xy 299.166838 -113.27298)
			(xy 299.194134 -113.224345) (xy 299.22822 -113.180202) (xy 299.268369 -113.141493) (xy 299.313727 -113.109042)
			(xy 299.363327 -113.083541) (xy 299.416111 -113.065534) (xy 299.470954 -113.055404) (xy 299.526688 -113.053367)
			(xy 299.582125 -113.059467) (xy 299.636082 -113.073573) (xy 299.687411 -113.095385) (xy 299.735017 -113.124439)
			(xy 299.777885 -113.160114) (xy 299.815102 -113.201651) (xy 299.845875 -113.248164) (xy 299.869547 -113.298661)
			(xy 299.885615 -113.352068) (xy 299.893735 -113.407244) (xy 299.894244 -113.43513) (xy 299.894193 -113.437924)
			(xy 301.557688 -113.437924) (xy 301.561759 -113.382302) (xy 301.573885 -113.327865) (xy 301.593808 -113.275774)
			(xy 301.621104 -113.227139) (xy 301.65519 -113.182996) (xy 301.695339 -113.144287) (xy 301.740697 -113.111836)
			(xy 301.790297 -113.086335) (xy 301.843081 -113.068328) (xy 301.897924 -113.058198) (xy 301.953658 -113.056161)
			(xy 302.009095 -113.062261) (xy 302.063052 -113.076367) (xy 302.114381 -113.098179) (xy 302.161987 -113.127233)
			(xy 302.204855 -113.162908) (xy 302.242072 -113.204445) (xy 302.272845 -113.250958) (xy 302.296517 -113.301455)
			(xy 302.312585 -113.354862) (xy 302.320705 -113.410038) (xy 302.321214 -113.437924) (xy 302.320705 -113.46581)
			(xy 302.312585 -113.520986) (xy 302.296517 -113.574393) (xy 302.272845 -113.62489) (xy 302.242072 -113.671403)
			(xy 302.204855 -113.71294) (xy 302.161987 -113.748615) (xy 302.114381 -113.777669) (xy 302.063052 -113.799481)
			(xy 302.009095 -113.813587) (xy 301.953658 -113.819687) (xy 301.897924 -113.81765) (xy 301.843081 -113.80752)
			(xy 301.790297 -113.789513) (xy 301.740697 -113.764012) (xy 301.695339 -113.731561) (xy 301.65519 -113.692852)
			(xy 301.621104 -113.648709) (xy 301.593808 -113.600074) (xy 301.573885 -113.547983) (xy 301.561759 -113.493546)
			(xy 301.557688 -113.437924) (xy 299.894193 -113.437924) (xy 299.893735 -113.463016) (xy 299.885615 -113.518192)
			(xy 299.869547 -113.571599) (xy 299.845875 -113.622096) (xy 299.815102 -113.668609) (xy 299.777885 -113.710146)
			(xy 299.735017 -113.745821) (xy 299.687411 -113.774875) (xy 299.636082 -113.796687) (xy 299.582125 -113.810793)
			(xy 299.526688 -113.816893) (xy 299.470954 -113.814856) (xy 299.416111 -113.804726) (xy 299.363327 -113.786719)
			(xy 299.313727 -113.761218) (xy 299.268369 -113.728767) (xy 299.22822 -113.690058) (xy 299.194134 -113.645915)
			(xy 299.166838 -113.59728) (xy 299.146915 -113.545189) (xy 299.134789 -113.490752) (xy 299.130718 -113.43513)
			(xy 297.22297 -113.43513) (xy 297.221293 -113.438708) (xy 297.19052 -113.485221) (xy 297.153303 -113.526758)
			(xy 297.110435 -113.562433) (xy 297.062829 -113.591487) (xy 297.0115 -113.613299) (xy 296.957543 -113.627405)
			(xy 296.902106 -113.633505) (xy 296.846372 -113.631468) (xy 296.791529 -113.621338) (xy 296.738745 -113.603331)
			(xy 296.689145 -113.57783) (xy 296.643787 -113.545379) (xy 296.603638 -113.50667) (xy 296.569552 -113.462527)
			(xy 296.542256 -113.413892) (xy 296.522333 -113.361801) (xy 296.510207 -113.307364) (xy 296.506136 -113.251742)
			(xy 295.756584 -113.251742) (xy 294.426894 -114.581432) (xy 298.499528 -114.581432) (xy 298.503599 -114.52581)
			(xy 298.515725 -114.471373) (xy 298.535648 -114.419282) (xy 298.562944 -114.370647) (xy 298.59703 -114.326504)
			(xy 298.637179 -114.287795) (xy 298.682537 -114.255344) (xy 298.732137 -114.229843) (xy 298.784921 -114.211836)
			(xy 298.839764 -114.201706) (xy 298.895498 -114.199669) (xy 298.950935 -114.205769) (xy 299.004892 -114.219875)
			(xy 299.056221 -114.241687) (xy 299.103827 -114.270741) (xy 299.127082 -114.290094) (xy 302.560226 -114.290094)
			(xy 302.564297 -114.234472) (xy 302.576423 -114.180035) (xy 302.596346 -114.127944) (xy 302.623642 -114.079309)
			(xy 302.657728 -114.035166) (xy 302.697877 -113.996457) (xy 302.743235 -113.964006) (xy 302.792835 -113.938505)
			(xy 302.845619 -113.920498) (xy 302.900462 -113.910368) (xy 302.956196 -113.908331) (xy 303.011633 -113.914431)
			(xy 303.06559 -113.928537) (xy 303.116919 -113.950349) (xy 303.164525 -113.979403) (xy 303.207393 -114.015078)
			(xy 303.24461 -114.056615) (xy 303.263133 -114.084612) (xy 321.649282 -114.084612) (xy 321.649288 -114.03011)
			(xy 321.65705 -113.976164) (xy 321.672411 -113.923871) (xy 321.695057 -113.874297) (xy 321.724528 -113.82845)
			(xy 321.760223 -113.787264) (xy 321.801417 -113.751578) (xy 321.84727 -113.722117) (xy 321.896849 -113.699481)
			(xy 321.949145 -113.684132) (xy 322.003093 -113.676382) (xy 322.030344 -113.675922) (xy 322.064564 -113.676721)
			(xy 322.131897 -113.688991) (xy 322.164202 -113.700306) (xy 322.172392 -113.702978) (xy 322.189602 -113.703321)
			(xy 322.205949 -113.697929) (xy 322.21297 -113.69294) (xy 322.291964 -113.632488) (xy 322.302378 -113.608358)
			(xy 322.301108 -113.595404) (xy 322.29933 -113.558574) (xy 322.299731 -113.531319) (xy 322.307492 -113.477364)
			(xy 322.322854 -113.425062) (xy 322.345502 -113.375479) (xy 322.374976 -113.329624) (xy 322.410676 -113.288431)
			(xy 322.451876 -113.252738) (xy 322.497736 -113.223271) (xy 322.547322 -113.200631) (xy 322.599626 -113.185279)
			(xy 322.653583 -113.177526) (xy 322.680838 -113.177066) (xy 322.709754 -113.177604) (xy 322.766926 -113.186326)
			(xy 322.822125 -113.203578) (xy 322.874088 -113.228966) (xy 322.921622 -113.261907) (xy 322.963638 -113.301647)
			(xy 322.981828 -113.324132) (xy 322.989427 -113.332947) (xy 323.010334 -113.343125) (xy 323.02196 -113.34369)
			(xy 323.101716 -113.34369) (xy 323.113348 -113.343149) (xy 323.134258 -113.332962) (xy 323.141848 -113.324132)
			(xy 323.160076 -113.30168) (xy 323.202087 -113.261941) (xy 323.249614 -113.228998) (xy 323.301568 -113.203604)
			(xy 323.35676 -113.186341) (xy 323.413924 -113.177605) (xy 323.442838 -113.177066) (xy 323.470089 -113.177542)
			(xy 323.524036 -113.185303) (xy 323.576329 -113.200662) (xy 323.625905 -113.223306) (xy 323.671754 -113.252774)
			(xy 323.712943 -113.288466) (xy 323.748634 -113.329656) (xy 323.7781 -113.375506) (xy 323.800742 -113.425082)
			(xy 323.816099 -113.477376) (xy 323.823858 -113.531323) (xy 323.824346 -113.558574) (xy 323.824161 -113.568734)
			(xy 343.089736 -113.568734) (xy 343.093807 -113.513112) (xy 343.105933 -113.458675) (xy 343.125856 -113.406584)
			(xy 343.153152 -113.357949) (xy 343.187238 -113.313806) (xy 343.227387 -113.275097) (xy 343.272745 -113.242646)
			(xy 343.322345 -113.217145) (xy 343.375129 -113.199138) (xy 343.429972 -113.189008) (xy 343.485706 -113.186971)
			(xy 343.541143 -113.193071) (xy 343.5951 -113.207177) (xy 343.646429 -113.228989) (xy 343.694035 -113.258043)
			(xy 343.736903 -113.293718) (xy 343.77412 -113.335255) (xy 343.804893 -113.381768) (xy 343.828565 -113.432265)
			(xy 343.844633 -113.485672) (xy 343.852753 -113.540848) (xy 343.853262 -113.568734) (xy 343.852753 -113.59662)
			(xy 343.844633 -113.651796) (xy 343.828565 -113.705203) (xy 343.804893 -113.7557) (xy 343.77412 -113.802213)
			(xy 343.736903 -113.84375) (xy 343.694035 -113.879425) (xy 343.646429 -113.908479) (xy 343.5951 -113.930291)
			(xy 343.541143 -113.944397) (xy 343.485706 -113.950497) (xy 343.429972 -113.94846) (xy 343.375129 -113.93833)
			(xy 343.322345 -113.920323) (xy 343.272745 -113.894822) (xy 343.227387 -113.862371) (xy 343.187238 -113.823662)
			(xy 343.153152 -113.779519) (xy 343.125856 -113.730884) (xy 343.105933 -113.678793) (xy 343.093807 -113.624356)
			(xy 343.089736 -113.568734) (xy 323.824161 -113.568734) (xy 323.823808 -113.58812) (xy 323.814708 -113.646506)
			(xy 323.796706 -113.702788) (xy 323.770234 -113.755618) (xy 323.735926 -113.80373) (xy 323.694604 -113.84597)
			(xy 323.647258 -113.881327) (xy 323.6214 -113.895632) (xy 323.611313 -113.901734) (xy 323.597673 -113.920928)
			(xy 323.595238 -113.932462) (xy 323.580506 -114.025172) (xy 323.587872 -114.048032) (xy 323.596254 -114.056414)
			(xy 323.603701 -114.064122) (xy 323.617806 -114.080261) (xy 323.624448 -114.088672) (xy 323.632032 -114.097503)
			(xy 323.652951 -114.107671) (xy 323.66458 -114.10823) (xy 323.744336 -114.10823) (xy 323.755972 -114.107722)
			(xy 323.776883 -114.097513) (xy 323.784468 -114.088672) (xy 323.80267 -114.066198) (xy 323.844688 -114.026463)
			(xy 323.892221 -113.993524) (xy 323.94418 -113.968134) (xy 323.999375 -113.950876) (xy 324.056543 -113.942143)
			(xy 324.085458 -113.941606) (xy 324.112714 -113.942038) (xy 324.166671 -113.94979) (xy 324.218976 -113.965143)
			(xy 324.268564 -113.987784) (xy 324.314424 -114.017252) (xy 324.327376 -114.028474) (xy 337.205064 -114.028474)
			(xy 337.209135 -113.972852) (xy 337.221261 -113.918415) (xy 337.241184 -113.866324) (xy 337.26848 -113.817689)
			(xy 337.302566 -113.773546) (xy 337.342715 -113.734837) (xy 337.388073 -113.702386) (xy 337.437673 -113.676885)
			(xy 337.490457 -113.658878) (xy 337.5453 -113.648748) (xy 337.601034 -113.646711) (xy 337.656471 -113.652811)
			(xy 337.710428 -113.666917) (xy 337.761757 -113.688729) (xy 337.809363 -113.717783) (xy 337.852231 -113.753458)
			(xy 337.889448 -113.794995) (xy 337.920221 -113.841508) (xy 337.943893 -113.892005) (xy 337.959961 -113.945412)
			(xy 337.968081 -114.000588) (xy 337.96859 -114.028474) (xy 337.968081 -114.05636) (xy 337.959961 -114.111536)
			(xy 337.943893 -114.164943) (xy 337.920221 -114.21544) (xy 337.889448 -114.261953) (xy 337.852231 -114.30349)
			(xy 337.809363 -114.339165) (xy 337.761757 -114.368219) (xy 337.710428 -114.390031) (xy 337.656471 -114.404137)
			(xy 337.601034 -114.410237) (xy 337.5453 -114.4082) (xy 337.490457 -114.39807) (xy 337.437673 -114.380063)
			(xy 337.388073 -114.354562) (xy 337.342715 -114.322111) (xy 337.302566 -114.283402) (xy 337.26848 -114.239259)
			(xy 337.241184 -114.190624) (xy 337.221261 -114.138533) (xy 337.209135 -114.084096) (xy 337.205064 -114.028474)
			(xy 324.327376 -114.028474) (xy 324.355623 -114.052947) (xy 324.391322 -114.094143) (xy 324.420795 -114.14)
			(xy 324.443442 -114.189584) (xy 324.458801 -114.241888) (xy 324.466559 -114.295844) (xy 324.466559 -114.350356)
			(xy 324.458801 -114.404312) (xy 324.443442 -114.456616) (xy 324.420795 -114.5062) (xy 324.391322 -114.552057)
			(xy 324.355623 -114.593253) (xy 324.314424 -114.628948) (xy 324.268564 -114.658416) (xy 324.218976 -114.681057)
			(xy 324.166671 -114.69641) (xy 324.112714 -114.704162) (xy 324.085458 -114.704622) (xy 324.056541 -114.704091)
			(xy 323.999369 -114.695369) (xy 323.944169 -114.678115) (xy 323.892207 -114.652726) (xy 323.844673 -114.619783)
			(xy 323.802657 -114.580042) (xy 323.784468 -114.557556) (xy 323.776872 -114.548737) (xy 323.755963 -114.538562)
			(xy 323.744336 -114.537998) (xy 323.66458 -114.537998) (xy 323.652949 -114.538541) (xy 323.632039 -114.548727)
			(xy 323.624448 -114.557556) (xy 323.606219 -114.580007) (xy 323.564208 -114.619747) (xy 323.516682 -114.652691)
			(xy 323.464728 -114.678085) (xy 323.409536 -114.695348) (xy 323.352372 -114.704084) (xy 323.323458 -114.704622)
			(xy 323.296206 -114.704161) (xy 323.242258 -114.696399) (xy 323.189964 -114.68104) (xy 323.140388 -114.658395)
			(xy 323.094538 -114.628925) (xy 323.053349 -114.593231) (xy 323.017658 -114.552039) (xy 322.988192 -114.506188)
			(xy 322.965551 -114.45661) (xy 322.950195 -114.404314) (xy 322.942437 -114.350366) (xy 322.94195 -114.323114)
			(xy 322.942428 -114.293565) (xy 322.951532 -114.235174) (xy 322.969541 -114.178888) (xy 322.996022 -114.126056)
			(xy 323.030341 -114.077944) (xy 323.071675 -114.035707) (xy 323.119032 -114.000356) (xy 323.144896 -113.986056)
			(xy 323.154987 -113.979959) (xy 323.168625 -113.960762) (xy 323.171058 -113.949226) (xy 323.18579 -113.856516)
			(xy 323.178424 -113.833656) (xy 323.170042 -113.825274) (xy 323.162595 -113.817567) (xy 323.14849 -113.801427)
			(xy 323.141848 -113.793016) (xy 323.134225 -113.784226) (xy 323.113336 -113.774036) (xy 323.101716 -113.773458)
			(xy 323.02196 -113.773458) (xy 323.010324 -113.773968) (xy 322.989413 -113.784175) (xy 322.981828 -113.793016)
			(xy 322.963625 -113.815489) (xy 322.921607 -113.855225) (xy 322.874075 -113.888164) (xy 322.822116 -113.913554)
			(xy 322.766921 -113.930813) (xy 322.709753 -113.939545) (xy 322.680838 -113.940082) (xy 322.646618 -113.939287)
			(xy 322.579285 -113.927015) (xy 322.54698 -113.915698) (xy 322.538794 -113.913011) (xy 322.521581 -113.912674)
			(xy 322.505233 -113.918072) (xy 322.498212 -113.923064) (xy 322.419218 -113.983516) (xy 322.408804 -114.007646)
			(xy 322.410074 -114.0206) (xy 322.411852 -114.05743) (xy 322.411313 -114.084681) (xy 322.403552 -114.138627)
			(xy 322.388193 -114.19092) (xy 322.365548 -114.240495) (xy 322.336078 -114.286342) (xy 322.300383 -114.327529)
			(xy 322.259191 -114.363217) (xy 322.213338 -114.392679) (xy 322.16376 -114.415315) (xy 322.111464 -114.430666)
			(xy 322.057516 -114.438417) (xy 322.003014 -114.438412) (xy 321.949068 -114.430651) (xy 321.896775 -114.415291)
			(xy 321.847201 -114.392645) (xy 321.801354 -114.363175) (xy 321.760167 -114.32748) (xy 321.72448 -114.286287)
			(xy 321.695019 -114.240434) (xy 321.672383 -114.190855) (xy 321.657033 -114.13856) (xy 321.649282 -114.084612)
			(xy 303.263133 -114.084612) (xy 303.275383 -114.103128) (xy 303.299055 -114.153625) (xy 303.315123 -114.207032)
			(xy 303.323243 -114.262208) (xy 303.323752 -114.290094) (xy 303.323243 -114.31798) (xy 303.315123 -114.373156)
			(xy 303.299055 -114.426563) (xy 303.275383 -114.47706) (xy 303.24461 -114.523573) (xy 303.207393 -114.56511)
			(xy 303.164525 -114.600785) (xy 303.116919 -114.629839) (xy 303.06559 -114.651651) (xy 303.011633 -114.665757)
			(xy 302.956196 -114.671857) (xy 302.900462 -114.66982) (xy 302.845619 -114.65969) (xy 302.792835 -114.641683)
			(xy 302.743235 -114.616182) (xy 302.697877 -114.583731) (xy 302.657728 -114.545022) (xy 302.623642 -114.500879)
			(xy 302.596346 -114.452244) (xy 302.576423 -114.400153) (xy 302.564297 -114.345716) (xy 302.560226 -114.290094)
			(xy 299.127082 -114.290094) (xy 299.146695 -114.306416) (xy 299.183912 -114.347953) (xy 299.214685 -114.394466)
			(xy 299.238357 -114.444963) (xy 299.254425 -114.49837) (xy 299.262545 -114.553546) (xy 299.263054 -114.581432)
			(xy 299.262545 -114.609318) (xy 299.254425 -114.664494) (xy 299.238357 -114.717901) (xy 299.214685 -114.768398)
			(xy 299.183912 -114.814911) (xy 299.146695 -114.856448) (xy 299.103827 -114.892123) (xy 299.056221 -114.921177)
			(xy 299.004892 -114.942989) (xy 298.950935 -114.957095) (xy 298.895498 -114.963195) (xy 298.839764 -114.961158)
			(xy 298.784921 -114.951028) (xy 298.732137 -114.933021) (xy 298.682537 -114.90752) (xy 298.637179 -114.875069)
			(xy 298.59703 -114.83636) (xy 298.562944 -114.792217) (xy 298.535648 -114.743582) (xy 298.515725 -114.691491)
			(xy 298.503599 -114.637054) (xy 298.499528 -114.581432) (xy 294.426894 -114.581432) (xy 293.722552 -115.285774)
			(xy 299.130718 -115.285774) (xy 299.134789 -115.230152) (xy 299.146915 -115.175715) (xy 299.166838 -115.123624)
			(xy 299.194134 -115.074989) (xy 299.22822 -115.030846) (xy 299.268369 -114.992137) (xy 299.313727 -114.959686)
			(xy 299.363327 -114.934185) (xy 299.416111 -114.916178) (xy 299.470954 -114.906048) (xy 299.526688 -114.904011)
			(xy 299.582125 -114.910111) (xy 299.636082 -114.924217) (xy 299.687411 -114.946029) (xy 299.735017 -114.975083)
			(xy 299.777885 -115.010758) (xy 299.815102 -115.052295) (xy 299.845875 -115.098808) (xy 299.869547 -115.149305)
			(xy 299.885615 -115.202712) (xy 299.893735 -115.257888) (xy 299.894244 -115.285774) (xy 299.893735 -115.31366)
			(xy 299.886774 -115.360958) (xy 306.318412 -115.360958) (xy 306.318909 -115.333589) (xy 306.326719 -115.279411)
			(xy 306.342201 -115.226908) (xy 306.365036 -115.177161) (xy 306.394754 -115.131193) (xy 306.412392 -115.11026)
			(xy 306.412646 -115.110006) (xy 306.418242 -115.102926) (xy 306.424482 -115.086004) (xy 306.424838 -115.076986)
			(xy 306.424838 -115.00993) (xy 306.424458 -115.000916) (xy 306.418226 -114.983999) (xy 306.412646 -114.97691)
			(xy 306.412392 -114.97691) (xy 306.412392 -114.976656) (xy 306.394764 -114.955715) (xy 306.365051 -114.909744)
			(xy 306.342213 -114.859999) (xy 306.326719 -114.807501) (xy 306.318888 -114.753327) (xy 306.318412 -114.725958)
			(xy 306.318839 -114.698705) (xy 306.326602 -114.644754) (xy 306.341963 -114.592457) (xy 306.364611 -114.542878)
			(xy 306.394083 -114.497027) (xy 306.429781 -114.455837) (xy 306.470977 -114.420146) (xy 306.516833 -114.390681)
			(xy 306.566415 -114.368041) (xy 306.618715 -114.352688) (xy 306.672667 -114.344934) (xy 306.69992 -114.34445)
			(xy 306.727291 -114.344892) (xy 306.781472 -114.352714) (xy 306.833976 -114.368208) (xy 306.883722 -114.391055)
			(xy 306.929688 -114.420786) (xy 306.950618 -114.43843) (xy 306.950872 -114.438684) (xy 306.957964 -114.444263)
			(xy 306.974876 -114.450515) (xy 306.983892 -114.450876) (xy 307.050948 -114.450876) (xy 307.059963 -114.450499)
			(xy 307.07688 -114.444266) (xy 307.083968 -114.438684) (xy 307.083968 -114.43843) (xy 307.084222 -114.43843)
			(xy 307.105177 -114.420819) (xy 307.151143 -114.391102) (xy 307.200884 -114.36826) (xy 307.25338 -114.352762)
			(xy 307.307552 -114.344927) (xy 307.33492 -114.34445) (xy 307.36217 -114.344959) (xy 307.416115 -114.352717)
			(xy 307.468406 -114.368073) (xy 307.517981 -114.390713) (xy 307.563829 -114.420178) (xy 307.605018 -114.455866)
			(xy 307.640709 -114.497053) (xy 307.670176 -114.5429) (xy 307.69282 -114.592473) (xy 307.708178 -114.644764)
			(xy 307.715939 -114.698708) (xy 307.716428 -114.725958) (xy 307.715955 -114.753328) (xy 307.708141 -114.807508)
			(xy 307.692655 -114.860011) (xy 307.669814 -114.909758) (xy 307.64009 -114.955725) (xy 307.622448 -114.976656)
			(xy 307.622194 -114.97691) (xy 307.616596 -114.983989) (xy 307.610357 -115.000912) (xy 307.610002 -115.00993)
			(xy 307.610002 -115.076986) (xy 307.610365 -115.086002) (xy 307.616608 -115.102919) (xy 307.622194 -115.110006)
			(xy 307.622448 -115.110006) (xy 307.622448 -115.11026) (xy 307.640074 -115.131203) (xy 307.669789 -115.177172)
			(xy 307.692629 -115.226917) (xy 307.708123 -115.279415) (xy 307.715953 -115.333589) (xy 307.716428 -115.360958)
			(xy 307.715906 -115.388209) (xy 307.714092 -115.400836) (xy 319.460624 -115.400836) (xy 319.464695 -115.345214)
			(xy 319.476821 -115.290777) (xy 319.496744 -115.238686) (xy 319.52404 -115.190051) (xy 319.558126 -115.145908)
			(xy 319.598275 -115.107199) (xy 319.643633 -115.074748) (xy 319.693233 -115.049247) (xy 319.746017 -115.03124)
			(xy 319.80086 -115.02111) (xy 319.856594 -115.019073) (xy 319.912031 -115.025173) (xy 319.965988 -115.039279)
			(xy 320.017317 -115.061091) (xy 320.064923 -115.090145) (xy 320.107791 -115.12582) (xy 320.145008 -115.167357)
			(xy 320.175781 -115.21387) (xy 320.199453 -115.264367) (xy 320.215521 -115.317774) (xy 320.223259 -115.370356)
			(xy 321.561204 -115.370356) (xy 321.565275 -115.314734) (xy 321.577401 -115.260297) (xy 321.597324 -115.208206)
			(xy 321.62462 -115.159571) (xy 321.658706 -115.115428) (xy 321.698855 -115.076719) (xy 321.744213 -115.044268)
			(xy 321.793813 -115.018767) (xy 321.846597 -115.00076) (xy 321.90144 -114.99063) (xy 321.957174 -114.988593)
			(xy 322.012611 -114.994693) (xy 322.066568 -115.008799) (xy 322.07162 -115.010946) (xy 338.819742 -115.010946)
			(xy 338.823813 -114.955324) (xy 338.835939 -114.900887) (xy 338.855862 -114.848796) (xy 338.883158 -114.800161)
			(xy 338.917244 -114.756018) (xy 338.957393 -114.717309) (xy 339.002751 -114.684858) (xy 339.052351 -114.659357)
			(xy 339.105135 -114.64135) (xy 339.159978 -114.63122) (xy 339.215712 -114.629183) (xy 339.271149 -114.635283)
			(xy 339.325106 -114.649389) (xy 339.376435 -114.671201) (xy 339.424041 -114.700255) (xy 339.466909 -114.73593)
			(xy 339.504126 -114.777467) (xy 339.534899 -114.82398) (xy 339.558571 -114.874477) (xy 339.574639 -114.927884)
			(xy 339.582759 -114.98306) (xy 339.583268 -115.010946) (xy 339.582759 -115.038832) (xy 339.579835 -115.058698)
			(xy 340.186262 -115.058698) (xy 340.190333 -115.003076) (xy 340.202459 -114.948639) (xy 340.222382 -114.896548)
			(xy 340.249678 -114.847913) (xy 340.283764 -114.80377) (xy 340.323913 -114.765061) (xy 340.369271 -114.73261)
			(xy 340.418871 -114.707109) (xy 340.471655 -114.689102) (xy 340.526498 -114.678972) (xy 340.582232 -114.676935)
			(xy 340.637669 -114.683035) (xy 340.691626 -114.697141) (xy 340.742955 -114.718953) (xy 340.790561 -114.748007)
			(xy 340.833429 -114.783682) (xy 340.870646 -114.825219) (xy 340.901419 -114.871732) (xy 340.925091 -114.922229)
			(xy 340.941159 -114.975636) (xy 340.943328 -114.990372) (xy 341.564974 -114.990372) (xy 341.569045 -114.93475)
			(xy 341.581171 -114.880313) (xy 341.601094 -114.828222) (xy 341.62839 -114.779587) (xy 341.662476 -114.735444)
			(xy 341.702625 -114.696735) (xy 341.747983 -114.664284) (xy 341.797583 -114.638783) (xy 341.850367 -114.620776)
			(xy 341.90521 -114.610646) (xy 341.960944 -114.608609) (xy 342.016381 -114.614709) (xy 342.070338 -114.628815)
			(xy 342.121667 -114.650627) (xy 342.169273 -114.679681) (xy 342.212141 -114.715356) (xy 342.249358 -114.756893)
			(xy 342.280131 -114.803406) (xy 342.303803 -114.853903) (xy 342.319871 -114.90731) (xy 342.327721 -114.960654)
			(xy 343.091768 -114.960654) (xy 343.095839 -114.905032) (xy 343.107965 -114.850595) (xy 343.127888 -114.798504)
			(xy 343.155184 -114.749869) (xy 343.18927 -114.705726) (xy 343.229419 -114.667017) (xy 343.274777 -114.634566)
			(xy 343.324377 -114.609065) (xy 343.377161 -114.591058) (xy 343.432004 -114.580928) (xy 343.487738 -114.578891)
			(xy 343.543175 -114.584991) (xy 343.597132 -114.599097) (xy 343.648461 -114.620909) (xy 343.696067 -114.649963)
			(xy 343.738935 -114.685638) (xy 343.776152 -114.727175) (xy 343.806925 -114.773688) (xy 343.830597 -114.824185)
			(xy 343.846665 -114.877592) (xy 343.854785 -114.932768) (xy 343.855294 -114.960654) (xy 343.854785 -114.98854)
			(xy 343.846665 -115.043716) (xy 343.830597 -115.097123) (xy 343.806925 -115.14762) (xy 343.776152 -115.194133)
			(xy 343.738935 -115.23567) (xy 343.696067 -115.271345) (xy 343.648461 -115.300399) (xy 343.597132 -115.322211)
			(xy 343.543175 -115.336317) (xy 343.487738 -115.342417) (xy 343.432004 -115.34038) (xy 343.377161 -115.33025)
			(xy 343.324377 -115.312243) (xy 343.274777 -115.286742) (xy 343.229419 -115.254291) (xy 343.18927 -115.215582)
			(xy 343.155184 -115.171439) (xy 343.127888 -115.122804) (xy 343.107965 -115.070713) (xy 343.095839 -115.016276)
			(xy 343.091768 -114.960654) (xy 342.327721 -114.960654) (xy 342.327991 -114.962486) (xy 342.3285 -114.990372)
			(xy 342.327991 -115.018258) (xy 342.319871 -115.073434) (xy 342.303803 -115.126841) (xy 342.280131 -115.177338)
			(xy 342.249358 -115.223851) (xy 342.212141 -115.265388) (xy 342.169273 -115.301063) (xy 342.121667 -115.330117)
			(xy 342.070338 -115.351929) (xy 342.016381 -115.366035) (xy 341.960944 -115.372135) (xy 341.90521 -115.370098)
			(xy 341.850367 -115.359968) (xy 341.797583 -115.341961) (xy 341.747983 -115.31646) (xy 341.702625 -115.284009)
			(xy 341.662476 -115.2453) (xy 341.62839 -115.201157) (xy 341.601094 -115.152522) (xy 341.581171 -115.100431)
			(xy 341.569045 -115.045994) (xy 341.564974 -114.990372) (xy 340.943328 -114.990372) (xy 340.949279 -115.030812)
			(xy 340.949788 -115.058698) (xy 340.949279 -115.086584) (xy 340.941159 -115.14176) (xy 340.925091 -115.195167)
			(xy 340.901419 -115.245664) (xy 340.870646 -115.292177) (xy 340.833429 -115.333714) (xy 340.790561 -115.369389)
			(xy 340.742955 -115.398443) (xy 340.691626 -115.420255) (xy 340.637669 -115.434361) (xy 340.582232 -115.440461)
			(xy 340.526498 -115.438424) (xy 340.471655 -115.428294) (xy 340.418871 -115.410287) (xy 340.369271 -115.384786)
			(xy 340.323913 -115.352335) (xy 340.283764 -115.313626) (xy 340.249678 -115.269483) (xy 340.222382 -115.220848)
			(xy 340.202459 -115.168757) (xy 340.190333 -115.11432) (xy 340.186262 -115.058698) (xy 339.579835 -115.058698)
			(xy 339.574639 -115.094008) (xy 339.558571 -115.147415) (xy 339.534899 -115.197912) (xy 339.504126 -115.244425)
			(xy 339.466909 -115.285962) (xy 339.424041 -115.321637) (xy 339.376435 -115.350691) (xy 339.325106 -115.372503)
			(xy 339.271149 -115.386609) (xy 339.215712 -115.392709) (xy 339.159978 -115.390672) (xy 339.105135 -115.380542)
			(xy 339.052351 -115.362535) (xy 339.002751 -115.337034) (xy 338.957393 -115.304583) (xy 338.917244 -115.265874)
			(xy 338.883158 -115.221731) (xy 338.855862 -115.173096) (xy 338.835939 -115.121005) (xy 338.823813 -115.066568)
			(xy 338.819742 -115.010946) (xy 322.07162 -115.010946) (xy 322.117897 -115.030611) (xy 322.165503 -115.059665)
			(xy 322.208371 -115.09534) (xy 322.245588 -115.136877) (xy 322.276361 -115.18339) (xy 322.300033 -115.233887)
			(xy 322.316101 -115.287294) (xy 322.324221 -115.34247) (xy 322.32473 -115.370356) (xy 322.324221 -115.398242)
			(xy 322.316101 -115.453418) (xy 322.300033 -115.506825) (xy 322.276361 -115.557322) (xy 322.245588 -115.603835)
			(xy 322.208371 -115.645372) (xy 322.165503 -115.681047) (xy 322.117897 -115.710101) (xy 322.066568 -115.731913)
			(xy 322.012611 -115.746019) (xy 321.957174 -115.752119) (xy 321.90144 -115.750082) (xy 321.846597 -115.739952)
			(xy 321.793813 -115.721945) (xy 321.744213 -115.696444) (xy 321.698855 -115.663993) (xy 321.658706 -115.625284)
			(xy 321.62462 -115.581141) (xy 321.597324 -115.532506) (xy 321.577401 -115.480415) (xy 321.565275 -115.425978)
			(xy 321.561204 -115.370356) (xy 320.223259 -115.370356) (xy 320.223641 -115.37295) (xy 320.22415 -115.400836)
			(xy 320.223641 -115.428722) (xy 320.215521 -115.483898) (xy 320.199453 -115.537305) (xy 320.175781 -115.587802)
			(xy 320.145008 -115.634315) (xy 320.107791 -115.675852) (xy 320.064923 -115.711527) (xy 320.017317 -115.740581)
			(xy 319.965988 -115.762393) (xy 319.912031 -115.776499) (xy 319.856594 -115.782599) (xy 319.80086 -115.780562)
			(xy 319.746017 -115.770432) (xy 319.693233 -115.752425) (xy 319.643633 -115.726924) (xy 319.598275 -115.694473)
			(xy 319.558126 -115.655764) (xy 319.52404 -115.611621) (xy 319.496744 -115.562986) (xy 319.476821 -115.510895)
			(xy 319.464695 -115.456458) (xy 319.460624 -115.400836) (xy 307.714092 -115.400836) (xy 307.708155 -115.442157)
			(xy 307.692805 -115.494452) (xy 307.670169 -115.544031) (xy 307.640707 -115.589883) (xy 307.60502 -115.631076)
			(xy 307.563833 -115.66677) (xy 307.517985 -115.696239) (xy 307.46841 -115.718884) (xy 307.416117 -115.734242)
			(xy 307.362171 -115.742001) (xy 307.33492 -115.742466) (xy 307.30755 -115.741996) (xy 307.253371 -115.734181)
			(xy 307.200867 -115.718693) (xy 307.15112 -115.695852) (xy 307.105153 -115.666127) (xy 307.084222 -115.648486)
			(xy 307.083968 -115.648232) (xy 307.076872 -115.64266) (xy 307.059962 -115.636406) (xy 307.050948 -115.63604)
			(xy 306.983892 -115.63604) (xy 306.974874 -115.636384) (xy 306.957956 -115.64264) (xy 306.950872 -115.648232)
			(xy 306.950872 -115.648486) (xy 306.950618 -115.648486) (xy 306.929688 -115.666128) (xy 306.883715 -115.69584)
			(xy 306.833967 -115.718675) (xy 306.781466 -115.734166) (xy 306.727289 -115.741993) (xy 306.69992 -115.742466)
			(xy 306.672666 -115.742026) (xy 306.618712 -115.734271) (xy 306.566411 -115.718915) (xy 306.516828 -115.696272)
			(xy 306.470973 -115.666802) (xy 306.429779 -115.631106) (xy 306.394085 -115.58991) (xy 306.364618 -115.544053)
			(xy 306.341977 -115.494468) (xy 306.326625 -115.442167) (xy 306.318872 -115.388212) (xy 306.318412 -115.360958)
			(xy 299.886774 -115.360958) (xy 299.885615 -115.368836) (xy 299.869547 -115.422243) (xy 299.845875 -115.47274)
			(xy 299.815102 -115.519253) (xy 299.777885 -115.56079) (xy 299.735017 -115.596465) (xy 299.687411 -115.625519)
			(xy 299.636082 -115.647331) (xy 299.582125 -115.661437) (xy 299.526688 -115.667537) (xy 299.470954 -115.6655)
			(xy 299.416111 -115.65537) (xy 299.363327 -115.637363) (xy 299.313727 -115.611862) (xy 299.268369 -115.579411)
			(xy 299.22822 -115.540702) (xy 299.194134 -115.496559) (xy 299.166838 -115.447924) (xy 299.146915 -115.395833)
			(xy 299.134789 -115.341396) (xy 299.130718 -115.285774) (xy 293.722552 -115.285774) (xy 293.10584 -115.902486)
			(xy 296.391074 -115.902486) (xy 296.395145 -115.846864) (xy 296.407271 -115.792427) (xy 296.427194 -115.740336)
			(xy 296.45449 -115.691701) (xy 296.488576 -115.647558) (xy 296.528725 -115.608849) (xy 296.574083 -115.576398)
			(xy 296.623683 -115.550897) (xy 296.676467 -115.53289) (xy 296.73131 -115.52276) (xy 296.787044 -115.520723)
			(xy 296.842481 -115.526823) (xy 296.896438 -115.540929) (xy 296.947767 -115.562741) (xy 296.995373 -115.591795)
			(xy 297.038241 -115.62747) (xy 297.075458 -115.669007) (xy 297.106231 -115.71552) (xy 297.129903 -115.766017)
			(xy 297.145971 -115.819424) (xy 297.147915 -115.832636) (xy 325.17918 -115.832636) (xy 325.183251 -115.777014)
			(xy 325.195377 -115.722577) (xy 325.2153 -115.670486) (xy 325.242596 -115.621851) (xy 325.276682 -115.577708)
			(xy 325.316831 -115.538999) (xy 325.362189 -115.506548) (xy 325.411789 -115.481047) (xy 325.464573 -115.46304)
			(xy 325.519416 -115.45291) (xy 325.57515 -115.450873) (xy 325.630587 -115.456973) (xy 325.684544 -115.471079)
			(xy 325.735873 -115.492891) (xy 325.783479 -115.521945) (xy 325.826347 -115.55762) (xy 325.863564 -115.599157)
			(xy 325.894337 -115.64567) (xy 325.918009 -115.696167) (xy 325.934077 -115.749574) (xy 325.942197 -115.80475)
			(xy 325.942706 -115.832636) (xy 325.942197 -115.860522) (xy 325.934077 -115.915698) (xy 325.918009 -115.969105)
			(xy 325.894337 -116.019602) (xy 325.863564 -116.066115) (xy 325.826347 -116.107652) (xy 325.783479 -116.143327)
			(xy 325.735873 -116.172381) (xy 325.684544 -116.194193) (xy 325.630587 -116.208299) (xy 325.57515 -116.214399)
			(xy 325.519416 -116.212362) (xy 325.464573 -116.202232) (xy 325.411789 -116.184225) (xy 325.362189 -116.158724)
			(xy 325.316831 -116.126273) (xy 325.276682 -116.087564) (xy 325.242596 -116.043421) (xy 325.2153 -115.994786)
			(xy 325.195377 -115.942695) (xy 325.183251 -115.888258) (xy 325.17918 -115.832636) (xy 297.147915 -115.832636)
			(xy 297.154091 -115.8746) (xy 297.1546 -115.902486) (xy 297.154091 -115.930372) (xy 297.145971 -115.985548)
			(xy 297.129903 -116.038955) (xy 297.106231 -116.089452) (xy 297.075458 -116.135965) (xy 297.038241 -116.177502)
			(xy 296.995373 -116.213177) (xy 296.947767 -116.242231) (xy 296.896438 -116.264043) (xy 296.842481 -116.278149)
			(xy 296.787044 -116.284249) (xy 296.73131 -116.282212) (xy 296.676467 -116.272082) (xy 296.623683 -116.254075)
			(xy 296.574083 -116.228574) (xy 296.528725 -116.196123) (xy 296.488576 -116.157414) (xy 296.45449 -116.113271)
			(xy 296.427194 -116.064636) (xy 296.407271 -116.012545) (xy 296.395145 -115.958108) (xy 296.391074 -115.902486)
			(xy 293.10584 -115.902486) (xy 292.560756 -116.44757) (xy 298.357034 -116.44757) (xy 298.361105 -116.391948)
			(xy 298.373231 -116.337511) (xy 298.393154 -116.28542) (xy 298.42045 -116.236785) (xy 298.454536 -116.192642)
			(xy 298.494685 -116.153933) (xy 298.540043 -116.121482) (xy 298.589643 -116.095981) (xy 298.642427 -116.077974)
			(xy 298.69727 -116.067844) (xy 298.753004 -116.065807) (xy 298.808441 -116.071907) (xy 298.862398 -116.086013)
			(xy 298.913727 -116.107825) (xy 298.961333 -116.136879) (xy 299.004201 -116.172554) (xy 299.041418 -116.214091)
			(xy 299.072191 -116.260604) (xy 299.095863 -116.311101) (xy 299.111931 -116.364508) (xy 299.120051 -116.419684)
			(xy 299.12056 -116.44757) (xy 299.120051 -116.475456) (xy 299.119781 -116.477288) (xy 303.504344 -116.477288)
			(xy 303.508415 -116.421666) (xy 303.520541 -116.367229) (xy 303.540464 -116.315138) (xy 303.56776 -116.266503)
			(xy 303.601846 -116.22236) (xy 303.641995 -116.183651) (xy 303.687353 -116.1512) (xy 303.736953 -116.125699)
			(xy 303.789737 -116.107692) (xy 303.84458 -116.097562) (xy 303.900314 -116.095525) (xy 303.955751 -116.101625)
			(xy 304.009708 -116.115731) (xy 304.061037 -116.137543) (xy 304.108643 -116.166597) (xy 304.151511 -116.202272)
			(xy 304.188728 -116.243809) (xy 304.219501 -116.290322) (xy 304.243173 -116.340819) (xy 304.259241 -116.394226)
			(xy 304.267361 -116.449402) (xy 304.26787 -116.477288) (xy 304.267361 -116.505174) (xy 304.259241 -116.56035)
			(xy 304.243173 -116.613757) (xy 304.219501 -116.664254) (xy 304.188728 -116.710767) (xy 304.151511 -116.752304)
			(xy 304.108643 -116.787979) (xy 304.061037 -116.817033) (xy 304.009708 -116.838845) (xy 303.955751 -116.852951)
			(xy 303.900314 -116.859051) (xy 303.84458 -116.857014) (xy 303.789737 -116.846884) (xy 303.736953 -116.828877)
			(xy 303.687353 -116.803376) (xy 303.641995 -116.770925) (xy 303.601846 -116.732216) (xy 303.56776 -116.688073)
			(xy 303.540464 -116.639438) (xy 303.520541 -116.587347) (xy 303.508415 -116.53291) (xy 303.504344 -116.477288)
			(xy 299.119781 -116.477288) (xy 299.111931 -116.530632) (xy 299.095863 -116.584039) (xy 299.072191 -116.634536)
			(xy 299.041418 -116.681049) (xy 299.004201 -116.722586) (xy 298.961333 -116.758261) (xy 298.913727 -116.787315)
			(xy 298.862398 -116.809127) (xy 298.808441 -116.823233) (xy 298.753004 -116.829333) (xy 298.69727 -116.827296)
			(xy 298.642427 -116.817166) (xy 298.589643 -116.799159) (xy 298.540043 -116.773658) (xy 298.494685 -116.741207)
			(xy 298.454536 -116.702498) (xy 298.42045 -116.658355) (xy 298.393154 -116.60972) (xy 298.373231 -116.557629)
			(xy 298.361105 -116.503192) (xy 298.357034 -116.44757) (xy 292.560756 -116.44757) (xy 292.47211 -116.536216)
			(xy 292.465272 -116.543618) (xy 292.457551 -116.562216) (xy 292.457124 -116.572284) (xy 292.457124 -117.723666)
			(xy 301.889666 -117.723666) (xy 301.893737 -117.668044) (xy 301.905863 -117.613607) (xy 301.925786 -117.561516)
			(xy 301.953082 -117.512881) (xy 301.987168 -117.468738) (xy 302.027317 -117.430029) (xy 302.072675 -117.397578)
			(xy 302.122275 -117.372077) (xy 302.175059 -117.35407) (xy 302.229902 -117.34394) (xy 302.285636 -117.341903)
			(xy 302.341073 -117.348003) (xy 302.39503 -117.362109) (xy 302.446359 -117.383921) (xy 302.493965 -117.412975)
			(xy 302.536833 -117.44865) (xy 302.57405 -117.490187) (xy 302.604823 -117.5367) (xy 302.628495 -117.587197)
			(xy 302.644563 -117.640604) (xy 302.652683 -117.69578) (xy 302.653192 -117.723666) (xy 302.652683 -117.751552)
			(xy 302.651628 -117.758718) (xy 306.675028 -117.758718) (xy 306.675028 -116.895118) (xy 306.675518 -116.86515)
			(xy 306.683341 -116.805728) (xy 306.698854 -116.747835) (xy 306.72179 -116.692462) (xy 306.751757 -116.640556)
			(xy 306.788244 -116.593006) (xy 306.830624 -116.550626) (xy 306.878174 -116.514139) (xy 306.93008 -116.484172)
			(xy 306.985453 -116.461236) (xy 307.043346 -116.445723) (xy 307.102768 -116.4379) (xy 307.162704 -116.4379)
			(xy 307.222126 -116.445723) (xy 307.280019 -116.461236) (xy 307.335392 -116.484172) (xy 307.387298 -116.514139)
			(xy 307.434848 -116.550626) (xy 307.477228 -116.593006) (xy 307.513715 -116.640556) (xy 307.53061 -116.66982)
			(xy 321.573142 -116.66982) (xy 321.577213 -116.614198) (xy 321.589339 -116.559761) (xy 321.609262 -116.50767)
			(xy 321.636558 -116.459035) (xy 321.670644 -116.414892) (xy 321.710793 -116.376183) (xy 321.756151 -116.343732)
			(xy 321.805751 -116.318231) (xy 321.858535 -116.300224) (xy 321.913378 -116.290094) (xy 321.969112 -116.288057)
			(xy 322.024549 -116.294157) (xy 322.078506 -116.308263) (xy 322.129835 -116.330075) (xy 322.177441 -116.359129)
			(xy 322.220309 -116.394804) (xy 322.257526 -116.436341) (xy 322.288299 -116.482854) (xy 322.311971 -116.533351)
			(xy 322.328039 -116.586758) (xy 322.334282 -116.62918) (xy 337.337906 -116.62918) (xy 337.341977 -116.573558)
			(xy 337.354103 -116.519121) (xy 337.374026 -116.46703) (xy 337.401322 -116.418395) (xy 337.435408 -116.374252)
			(xy 337.475557 -116.335543) (xy 337.520915 -116.303092) (xy 337.570515 -116.277591) (xy 337.623299 -116.259584)
			(xy 337.678142 -116.249454) (xy 337.733876 -116.247417) (xy 337.789313 -116.253517) (xy 337.84327 -116.267623)
			(xy 337.894599 -116.289435) (xy 337.942205 -116.318489) (xy 337.985073 -116.354164) (xy 338.02229 -116.395701)
			(xy 338.053063 -116.442214) (xy 338.076735 -116.492711) (xy 338.092803 -116.546118) (xy 338.100923 -116.601294)
			(xy 338.101432 -116.62918) (xy 338.100923 -116.657066) (xy 338.092803 -116.712242) (xy 338.076735 -116.765649)
			(xy 338.053063 -116.816146) (xy 338.02229 -116.862659) (xy 337.985073 -116.904196) (xy 337.942205 -116.939871)
			(xy 337.894599 -116.968925) (xy 337.84327 -116.990737) (xy 337.789313 -117.004843) (xy 337.733876 -117.010943)
			(xy 337.678142 -117.008906) (xy 337.623299 -116.998776) (xy 337.570515 -116.980769) (xy 337.520915 -116.955268)
			(xy 337.475557 -116.922817) (xy 337.435408 -116.884108) (xy 337.401322 -116.839965) (xy 337.374026 -116.79133)
			(xy 337.354103 -116.739239) (xy 337.341977 -116.684802) (xy 337.337906 -116.62918) (xy 322.334282 -116.62918)
			(xy 322.336159 -116.641934) (xy 322.336668 -116.66982) (xy 322.336159 -116.697706) (xy 322.328039 -116.752882)
			(xy 322.311971 -116.806289) (xy 322.288299 -116.856786) (xy 322.257526 -116.903299) (xy 322.220309 -116.944836)
			(xy 322.177441 -116.980511) (xy 322.129835 -117.009565) (xy 322.078506 -117.031377) (xy 322.024549 -117.045483)
			(xy 321.969112 -117.051583) (xy 321.913378 -117.049546) (xy 321.858535 -117.039416) (xy 321.805751 -117.021409)
			(xy 321.756151 -116.995908) (xy 321.710793 -116.963457) (xy 321.670644 -116.924748) (xy 321.636558 -116.880605)
			(xy 321.609262 -116.83197) (xy 321.589339 -116.779879) (xy 321.577213 -116.725442) (xy 321.573142 -116.66982)
			(xy 307.53061 -116.66982) (xy 307.543682 -116.692462) (xy 307.566618 -116.747835) (xy 307.582131 -116.805728)
			(xy 307.589954 -116.86515) (xy 307.590444 -116.895118) (xy 307.590444 -117.390446) (xy 322.942518 -117.390446)
			(xy 322.942518 -117.335954) (xy 322.950273 -117.282015) (xy 322.965624 -117.229729) (xy 322.98826 -117.18016)
			(xy 323.017719 -117.134317) (xy 323.053402 -117.093132) (xy 323.094583 -117.057444) (xy 323.140423 -117.02798)
			(xy 323.18999 -117.005339) (xy 323.242274 -116.989982) (xy 323.296212 -116.982221) (xy 323.323458 -116.981732)
			(xy 323.352374 -116.982268) (xy 323.409545 -116.990992) (xy 323.464744 -117.008245) (xy 323.516706 -117.033634)
			(xy 323.564241 -117.066575) (xy 323.606258 -117.106313) (xy 323.624448 -117.128798) (xy 323.632044 -117.137617)
			(xy 323.652953 -117.147794) (xy 323.66458 -117.148356) (xy 323.744336 -117.148356) (xy 323.755971 -117.147839)
			(xy 323.776881 -117.137636) (xy 323.784468 -117.128798) (xy 323.802677 -117.106329) (xy 323.844693 -117.066593)
			(xy 323.892224 -117.033653) (xy 323.944182 -117.008262) (xy 323.999376 -116.991002) (xy 324.056543 -116.982269)
			(xy 324.085458 -116.981732) (xy 324.112716 -116.982112) (xy 324.166677 -116.989865) (xy 324.218985 -117.005219)
			(xy 324.268576 -117.027862) (xy 324.314439 -117.057332) (xy 324.355641 -117.093029) (xy 324.363966 -117.102636)
			(xy 325.17918 -117.102636) (xy 325.183251 -117.047014) (xy 325.195377 -116.992577) (xy 325.2153 -116.940486)
			(xy 325.242596 -116.891851) (xy 325.276682 -116.847708) (xy 325.316831 -116.808999) (xy 325.362189 -116.776548)
			(xy 325.411789 -116.751047) (xy 325.464573 -116.73304) (xy 325.519416 -116.72291) (xy 325.57515 -116.720873)
			(xy 325.630587 -116.726973) (xy 325.684544 -116.741079) (xy 325.735873 -116.762891) (xy 325.783479 -116.791945)
			(xy 325.826347 -116.82762) (xy 325.863564 -116.869157) (xy 325.894337 -116.91567) (xy 325.918009 -116.966167)
			(xy 325.934077 -117.019574) (xy 325.942197 -117.07475) (xy 325.942706 -117.102636) (xy 325.942197 -117.130522)
			(xy 325.934077 -117.185698) (xy 325.918009 -117.239105) (xy 325.913756 -117.248178) (xy 339.938866 -117.248178)
			(xy 339.942937 -117.192556) (xy 339.955063 -117.138119) (xy 339.974986 -117.086028) (xy 340.002282 -117.037393)
			(xy 340.036368 -116.99325) (xy 340.076517 -116.954541) (xy 340.121875 -116.92209) (xy 340.171475 -116.896589)
			(xy 340.224259 -116.878582) (xy 340.279102 -116.868452) (xy 340.334836 -116.866415) (xy 340.390273 -116.872515)
			(xy 340.44423 -116.886621) (xy 340.495559 -116.908433) (xy 340.543165 -116.937487) (xy 340.586033 -116.973162)
			(xy 340.62325 -117.014699) (xy 340.654023 -117.061212) (xy 340.677695 -117.111709) (xy 340.693763 -117.165116)
			(xy 340.701883 -117.220292) (xy 340.702392 -117.248178) (xy 340.701883 -117.276064) (xy 340.693763 -117.33124)
			(xy 340.677695 -117.384647) (xy 340.654023 -117.435144) (xy 340.62325 -117.481657) (xy 340.586033 -117.523194)
			(xy 340.543165 -117.558869) (xy 340.495559 -117.587923) (xy 340.44423 -117.609735) (xy 340.390273 -117.623841)
			(xy 340.334836 -117.629941) (xy 340.279102 -117.627904) (xy 340.224259 -117.617774) (xy 340.171475 -117.599767)
			(xy 340.121875 -117.574266) (xy 340.076517 -117.541815) (xy 340.036368 -117.503106) (xy 340.002282 -117.458963)
			(xy 339.974986 -117.410328) (xy 339.955063 -117.358237) (xy 339.942937 -117.3038) (xy 339.938866 -117.248178)
			(xy 325.913756 -117.248178) (xy 325.894337 -117.289602) (xy 325.863564 -117.336115) (xy 325.826347 -117.377652)
			(xy 325.783479 -117.413327) (xy 325.735873 -117.442381) (xy 325.684544 -117.464193) (xy 325.630587 -117.478299)
			(xy 325.57515 -117.484399) (xy 325.519416 -117.482362) (xy 325.464573 -117.472232) (xy 325.411789 -117.454225)
			(xy 325.362189 -117.428724) (xy 325.316831 -117.396273) (xy 325.276682 -117.357564) (xy 325.242596 -117.313421)
			(xy 325.2153 -117.264786) (xy 325.195377 -117.212695) (xy 325.183251 -117.158258) (xy 325.17918 -117.102636)
			(xy 324.363966 -117.102636) (xy 324.391343 -117.134227) (xy 324.420818 -117.180087) (xy 324.443466 -117.229675)
			(xy 324.458826 -117.281982) (xy 324.466585 -117.335942) (xy 324.466585 -117.390458) (xy 324.458826 -117.444418)
			(xy 324.443466 -117.496725) (xy 324.420818 -117.546313) (xy 324.391343 -117.592173) (xy 324.355641 -117.633371)
			(xy 324.314439 -117.669068) (xy 324.268576 -117.698538) (xy 324.218985 -117.721181) (xy 324.166677 -117.736535)
			(xy 324.112716 -117.744288) (xy 324.085458 -117.744748) (xy 324.056542 -117.744208) (xy 323.999371 -117.735486)
			(xy 323.944171 -117.718234) (xy 323.892209 -117.692847) (xy 323.844675 -117.659906) (xy 323.802658 -117.620167)
			(xy 323.784468 -117.597682) (xy 323.776868 -117.588867) (xy 323.755962 -117.578688) (xy 323.744336 -117.578124)
			(xy 323.66458 -117.578124) (xy 323.652947 -117.578657) (xy 323.632037 -117.588849) (xy 323.624448 -117.597682)
			(xy 323.606225 -117.620139) (xy 323.564213 -117.659876) (xy 323.516685 -117.692819) (xy 323.464729 -117.718212)
			(xy 323.409537 -117.735474) (xy 323.352372 -117.74421) (xy 323.323458 -117.744748) (xy 323.296212 -117.744179)
			(xy 323.242274 -117.736418) (xy 323.18999 -117.721061) (xy 323.140423 -117.69842) (xy 323.094583 -117.668956)
			(xy 323.053402 -117.633268) (xy 323.017719 -117.592083) (xy 322.98826 -117.54624) (xy 322.965624 -117.496671)
			(xy 322.950273 -117.444385) (xy 322.942518 -117.390446) (xy 307.590444 -117.390446) (xy 307.590444 -117.758718)
			(xy 307.589954 -117.788686) (xy 307.582131 -117.848108) (xy 307.566618 -117.906001) (xy 307.543682 -117.961374)
			(xy 307.513715 -118.01328) (xy 307.477228 -118.06083) (xy 307.434848 -118.10321) (xy 307.387298 -118.139697)
			(xy 307.335392 -118.169664) (xy 307.280019 -118.1926) (xy 307.222126 -118.208113) (xy 307.162704 -118.215936)
			(xy 307.102768 -118.215936) (xy 307.043346 -118.208113) (xy 306.985453 -118.1926) (xy 306.93008 -118.169664)
			(xy 306.878174 -118.139697) (xy 306.830624 -118.10321) (xy 306.788244 -118.06083) (xy 306.751757 -118.01328)
			(xy 306.72179 -117.961374) (xy 306.698854 -117.906001) (xy 306.683341 -117.848108) (xy 306.675518 -117.788686)
			(xy 306.675028 -117.758718) (xy 302.651628 -117.758718) (xy 302.644563 -117.806728) (xy 302.628495 -117.860135)
			(xy 302.604823 -117.910632) (xy 302.57405 -117.957145) (xy 302.536833 -117.998682) (xy 302.493965 -118.034357)
			(xy 302.446359 -118.063411) (xy 302.39503 -118.085223) (xy 302.341073 -118.099329) (xy 302.285636 -118.105429)
			(xy 302.229902 -118.103392) (xy 302.175059 -118.093262) (xy 302.122275 -118.075255) (xy 302.072675 -118.049754)
			(xy 302.027317 -118.017303) (xy 301.987168 -117.978594) (xy 301.953082 -117.934451) (xy 301.925786 -117.885816)
			(xy 301.905863 -117.833725) (xy 301.893737 -117.779288) (xy 301.889666 -117.723666) (xy 292.457124 -117.723666)
			(xy 292.457124 -132.225796) (xy 292.456637 -132.258649) (xy 292.449275 -132.32394) (xy 292.434654 -132.387999)
			(xy 292.412959 -132.450019) (xy 292.384461 -132.509222) (xy 292.349518 -132.564866) (xy 292.308569 -132.616251)
			(xy 292.285674 -132.639816) (xy 289.891216 -135.034274) (xy 289.867641 -135.057161) (xy 289.816266 -135.098126)
			(xy 289.760628 -135.133082) (xy 289.701426 -135.161589) (xy 289.639405 -135.183288) (xy 289.575344 -135.197908)
			(xy 289.51005 -135.205264) (xy 289.477196 -135.205724) (xy 289.476942 -135.205724) (xy 289.441542 -135.205105)
			(xy 289.371256 -135.196578) (xy 289.30251 -135.179644) (xy 289.236306 -135.154549) (xy 289.173609 -135.121659)
			(xy 289.115331 -135.081454) (xy 289.062323 -135.034519) (xy 289.015357 -134.981538) (xy 288.975118 -134.923284)
			(xy 288.942191 -134.860606) (xy 288.917058 -134.794416) (xy 288.900084 -134.72568) (xy 288.891516 -134.6554)
			(xy 288.890964 -134.62) (xy 288.53892 -134.62) (xy 288.53892 -135.985504) (xy 288.539338 -135.995574)
			(xy 288.547063 -136.014172) (xy 288.553906 -136.021572) (xy 289.442652 -136.910318) (xy 289.44704 -136.91444)
			(xy 289.457308 -136.920721) (xy 289.462972 -136.922764) (xy 289.46348 -136.922764) (xy 289.489029 -136.931197)
			(xy 289.537633 -136.95427) (xy 289.582513 -136.983943) (xy 289.62278 -137.019626) (xy 289.657635 -137.060611)
			(xy 289.686387 -137.106087) (xy 289.708465 -137.155151) (xy 289.723431 -137.20683) (xy 289.730989 -137.260099)
			(xy 289.73145 -137.287) (xy 289.730922 -137.314249) (xy 289.723167 -137.368193) (xy 289.707814 -137.420485)
			(xy 289.685176 -137.470059) (xy 289.655713 -137.515908) (xy 289.620026 -137.557097) (xy 289.578841 -137.592788)
			(xy 289.532996 -137.622256) (xy 289.483424 -137.644899) (xy 289.431134 -137.660258) (xy 289.377191 -137.668019)
			(xy 289.349942 -137.668508) (xy 289.323031 -137.668054) (xy 289.269747 -137.66047) (xy 289.218056 -137.645475)
			(xy 289.168985 -137.623365) (xy 289.123508 -137.59458) (xy 289.082526 -137.559692) (xy 289.046852 -137.519391)
			(xy 289.017195 -137.474477) (xy 288.994142 -137.425843) (xy 288.985706 -137.400284) (xy 288.985706 -137.40003)
			(xy 288.983723 -137.394338) (xy 288.977429 -137.384063) (xy 288.97326 -137.37971) (xy 288.189416 -136.595866)
			(xy 288.159444 -136.58977) (xy 288.14522 -136.595866) (xy 288.136112 -136.600119) (xy 288.121875 -136.614279)
			(xy 288.114157 -136.632816) (xy 288.113724 -136.642856) (xy 288.113724 -138.95705) (xy 288.714434 -138.95705)
			(xy 288.71492 -138.929799) (xy 288.722676 -138.875851) (xy 288.738031 -138.823556) (xy 288.760673 -138.773979)
			(xy 288.790139 -138.728129) (xy 288.82583 -138.686938) (xy 288.867021 -138.651247) (xy 288.912871 -138.621781)
			(xy 288.962448 -138.599139) (xy 289.014743 -138.583784) (xy 289.068691 -138.576028) (xy 289.123193 -138.576028)
			(xy 289.177141 -138.583784) (xy 289.229436 -138.599139) (xy 289.279013 -138.621781) (xy 289.324863 -138.651247)
			(xy 289.366054 -138.686938) (xy 289.401745 -138.728129) (xy 289.431211 -138.773979) (xy 289.453853 -138.823556)
			(xy 289.465977 -138.864848) (xy 294.140382 -138.864848) (xy 294.140848 -138.837938) (xy 294.148431 -138.784654)
			(xy 294.163425 -138.732964) (xy 294.185533 -138.683894) (xy 294.214317 -138.638416) (xy 294.249204 -138.597434)
			(xy 294.289503 -138.56176) (xy 294.334415 -138.532102) (xy 294.383048 -138.509048) (xy 294.408606 -138.500612)
			(xy 294.40886 -138.500612) (xy 294.414558 -138.498645) (xy 294.42483 -138.49234) (xy 294.42918 -138.488166)
			(xy 294.51935 -138.397996) (xy 294.525659 -138.391053) (xy 294.533293 -138.373937) (xy 294.534286 -138.355223)
			(xy 294.531796 -138.34618) (xy 294.499284 -138.246612) (xy 294.47744 -138.22807) (xy 294.463216 -138.225784)
			(xy 294.436578 -138.221175) (xy 294.384867 -138.205412) (xy 294.3359 -138.182505) (xy 294.290657 -138.152914)
			(xy 294.250047 -138.117231) (xy 294.214881 -138.076171) (xy 294.185866 -138.030558) (xy 294.163581 -137.981304)
			(xy 294.148475 -137.929398) (xy 294.140849 -137.875878) (xy 294.140382 -137.848848) (xy 294.1409 -137.821597)
			(xy 294.14865 -137.767648) (xy 294.164 -137.715352) (xy 294.186636 -137.665773) (xy 294.216098 -137.61992)
			(xy 294.251786 -137.578727) (xy 294.292973 -137.543033) (xy 294.338822 -137.513564) (xy 294.388398 -137.49092)
			(xy 294.440692 -137.475562) (xy 294.494639 -137.467804) (xy 294.52189 -137.46734) (xy 294.545572 -137.467699)
			(xy 294.592571 -137.473557) (xy 294.615616 -137.479024) (xy 294.627021 -137.481363) (xy 294.649784 -137.476585)
			(xy 294.659304 -137.46988) (xy 294.72255 -137.420604) (xy 294.731354 -137.412994) (xy 294.741537 -137.392095)
			(xy 294.742108 -137.380472) (xy 294.742108 -118.735602) (xy 294.742579 -118.709514) (xy 294.750748 -118.657981)
			(xy 294.766883 -118.608363) (xy 294.790587 -118.561882) (xy 294.821275 -118.519686) (xy 294.83939 -118.500906)
			(xy 295.10101 -118.239286) (xy 295.105123 -118.23489) (xy 295.11141 -118.224627) (xy 295.113456 -118.218966)
			(xy 295.113456 -118.218458) (xy 295.121919 -118.192919) (xy 295.144987 -118.144315) (xy 295.174654 -118.099434)
			(xy 295.210333 -118.059166) (xy 295.251315 -118.024309) (xy 295.296788 -117.995556) (xy 295.345849 -117.973477)
			(xy 295.397525 -117.958509) (xy 295.450792 -117.950949) (xy 295.477692 -117.950488) (xy 295.504944 -117.950963)
			(xy 295.558895 -117.958719) (xy 295.611192 -117.974073) (xy 295.660772 -117.996715) (xy 295.706625 -118.026181)
			(xy 295.747818 -118.061874) (xy 295.783511 -118.103065) (xy 295.81298 -118.148917) (xy 295.835622 -118.198497)
			(xy 295.850979 -118.250793) (xy 295.858736 -118.304744) (xy 295.8592 -118.331996) (xy 295.858697 -118.358905)
			(xy 295.851121 -118.412188) (xy 295.836133 -118.463878) (xy 295.814031 -118.512948) (xy 295.785252 -118.558426)
			(xy 295.750369 -118.599409) (xy 295.710073 -118.635084) (xy 295.665164 -118.664742) (xy 295.616533 -118.687796)
			(xy 295.590976 -118.696232) (xy 295.590722 -118.696232) (xy 295.585026 -118.698205) (xy 295.574753 -118.704506)
			(xy 295.570402 -118.708678) (xy 295.42105 -118.85803) (xy 295.414211 -118.865431) (xy 295.406489 -118.884029)
			(xy 295.406064 -118.894098) (xy 295.406064 -119.567198) (xy 298.799504 -119.567198) (xy 298.799504 -118.703598)
			(xy 298.799994 -118.67363) (xy 298.807817 -118.614208) (xy 298.82333 -118.556315) (xy 298.846266 -118.500942)
			(xy 298.876233 -118.449036) (xy 298.91272 -118.401486) (xy 298.9551 -118.359106) (xy 299.00265 -118.322619)
			(xy 299.054556 -118.292652) (xy 299.109929 -118.269716) (xy 299.167822 -118.254203) (xy 299.227244 -118.24638)
			(xy 299.28718 -118.24638) (xy 299.346602 -118.254203) (xy 299.404495 -118.269716) (xy 299.459868 -118.292652)
			(xy 299.511774 -118.322619) (xy 299.559324 -118.359106) (xy 299.601704 -118.401486) (xy 299.638191 -118.449036)
			(xy 299.668158 -118.500942) (xy 299.691094 -118.556315) (xy 299.706607 -118.614208) (xy 299.71443 -118.67363)
			(xy 299.71492 -118.703598) (xy 299.71492 -119.567198) (xy 299.71443 -119.597166) (xy 299.706607 -119.656588)
			(xy 299.691094 -119.714481) (xy 299.668158 -119.769854) (xy 299.638191 -119.82176) (xy 299.601704 -119.86931)
			(xy 299.559324 -119.91169) (xy 299.511774 -119.948177) (xy 299.459868 -119.978144) (xy 299.404495 -120.00108)
			(xy 299.346602 -120.016593) (xy 299.28718 -120.024416) (xy 299.227244 -120.024416) (xy 299.167822 -120.016593)
			(xy 299.109929 -120.00108) (xy 299.054556 -119.978144) (xy 299.00265 -119.948177) (xy 298.9551 -119.91169)
			(xy 298.91272 -119.86931) (xy 298.876233 -119.82176) (xy 298.846266 -119.769854) (xy 298.82333 -119.714481)
			(xy 298.807817 -119.656588) (xy 298.799994 -119.597166) (xy 298.799504 -119.567198) (xy 295.406064 -119.567198)
			(xy 295.406064 -121.367296) (xy 296.945304 -121.367296) (xy 296.945304 -120.503696) (xy 296.945794 -120.473728)
			(xy 296.953617 -120.414306) (xy 296.96913 -120.356413) (xy 296.992066 -120.30104) (xy 297.022033 -120.249134)
			(xy 297.05852 -120.201584) (xy 297.1009 -120.159204) (xy 297.14845 -120.122717) (xy 297.200356 -120.09275)
			(xy 297.255729 -120.069814) (xy 297.313622 -120.054301) (xy 297.373044 -120.046478) (xy 297.43298 -120.046478)
			(xy 297.492402 -120.054301) (xy 297.550295 -120.069814) (xy 297.605668 -120.09275) (xy 297.657574 -120.122717)
			(xy 297.705124 -120.159204) (xy 297.747504 -120.201584) (xy 297.783991 -120.249134) (xy 297.813958 -120.30104)
			(xy 297.836894 -120.356413) (xy 297.852407 -120.414306) (xy 297.86023 -120.473728) (xy 297.86072 -120.503696)
			(xy 297.86072 -121.367296) (xy 297.86023 -121.397264) (xy 297.852407 -121.456686) (xy 297.836894 -121.514579)
			(xy 297.813958 -121.569952) (xy 297.783991 -121.621858) (xy 297.747504 -121.669408) (xy 297.705124 -121.711788)
			(xy 297.657574 -121.748275) (xy 297.605668 -121.778242) (xy 297.550295 -121.801178) (xy 297.492402 -121.816691)
			(xy 297.43298 -121.824514) (xy 297.373044 -121.824514) (xy 297.313622 -121.816691) (xy 297.255729 -121.801178)
			(xy 297.200356 -121.778242) (xy 297.14845 -121.748275) (xy 297.1009 -121.711788) (xy 297.05852 -121.669408)
			(xy 297.022033 -121.621858) (xy 296.992066 -121.569952) (xy 296.96913 -121.514579) (xy 296.953617 -121.456686)
			(xy 296.945794 -121.397264) (xy 296.945304 -121.367296) (xy 295.406064 -121.367296) (xy 295.406064 -123.16714)
			(xy 298.799504 -123.16714) (xy 298.799504 -122.30354) (xy 298.799994 -122.273572) (xy 298.807817 -122.21415)
			(xy 298.82333 -122.156257) (xy 298.846266 -122.100884) (xy 298.876233 -122.048978) (xy 298.91272 -122.001428)
			(xy 298.9551 -121.959048) (xy 299.00265 -121.922561) (xy 299.054556 -121.892594) (xy 299.109929 -121.869658)
			(xy 299.167822 -121.854145) (xy 299.227244 -121.846322) (xy 299.28718 -121.846322) (xy 299.346602 -121.854145)
			(xy 299.404495 -121.869658) (xy 299.459868 -121.892594) (xy 299.511774 -121.922561) (xy 299.559324 -121.959048)
			(xy 299.601704 -122.001428) (xy 299.638191 -122.048978) (xy 299.668158 -122.100884) (xy 299.691094 -122.156257)
			(xy 299.706607 -122.21415) (xy 299.71443 -122.273572) (xy 299.71492 -122.30354) (xy 299.71492 -123.16714)
			(xy 299.71443 -123.197108) (xy 299.706607 -123.25653) (xy 299.691094 -123.314423) (xy 299.668158 -123.369796)
			(xy 299.638191 -123.421702) (xy 299.601704 -123.469252) (xy 299.559324 -123.511632) (xy 299.511774 -123.548119)
			(xy 299.459868 -123.578086) (xy 299.404495 -123.601022) (xy 299.346602 -123.616535) (xy 299.28718 -123.624358)
			(xy 299.227244 -123.624358) (xy 299.167822 -123.616535) (xy 299.109929 -123.601022) (xy 299.054556 -123.578086)
			(xy 299.00265 -123.548119) (xy 298.9551 -123.511632) (xy 298.91272 -123.469252) (xy 298.876233 -123.421702)
			(xy 298.846266 -123.369796) (xy 298.82333 -123.314423) (xy 298.807817 -123.25653) (xy 298.799994 -123.197108)
			(xy 298.799504 -123.16714) (xy 295.406064 -123.16714) (xy 295.406064 -124.967238) (xy 296.945304 -124.967238)
			(xy 296.945304 -124.103638) (xy 296.945794 -124.07367) (xy 296.953617 -124.014248) (xy 296.96913 -123.956355)
			(xy 296.992066 -123.900982) (xy 297.022033 -123.849076) (xy 297.05852 -123.801526) (xy 297.1009 -123.759146)
			(xy 297.14845 -123.722659) (xy 297.200356 -123.692692) (xy 297.255729 -123.669756) (xy 297.313622 -123.654243)
			(xy 297.373044 -123.64642) (xy 297.43298 -123.64642) (xy 297.492402 -123.654243) (xy 297.550295 -123.669756)
			(xy 297.605668 -123.692692) (xy 297.657574 -123.722659) (xy 297.705124 -123.759146) (xy 297.747504 -123.801526)
			(xy 297.783991 -123.849076) (xy 297.813958 -123.900982) (xy 297.836894 -123.956355) (xy 297.852407 -124.014248)
			(xy 297.86023 -124.07367) (xy 297.86072 -124.103638) (xy 297.86072 -124.967238) (xy 297.86023 -124.997206)
			(xy 297.852407 -125.056628) (xy 297.836894 -125.114521) (xy 297.813958 -125.169894) (xy 297.783991 -125.2218)
			(xy 297.747504 -125.26935) (xy 297.705124 -125.31173) (xy 297.657574 -125.348217) (xy 297.605668 -125.378184)
			(xy 297.550295 -125.40112) (xy 297.492402 -125.416633) (xy 297.43298 -125.424456) (xy 297.373044 -125.424456)
			(xy 297.313622 -125.416633) (xy 297.255729 -125.40112) (xy 297.200356 -125.378184) (xy 297.14845 -125.348217)
			(xy 297.1009 -125.31173) (xy 297.05852 -125.26935) (xy 297.022033 -125.2218) (xy 296.992066 -125.169894)
			(xy 296.96913 -125.114521) (xy 296.953617 -125.056628) (xy 296.945794 -124.997206) (xy 296.945304 -124.967238)
			(xy 295.406064 -124.967238) (xy 295.406064 -130.777234) (xy 298.799504 -130.777234) (xy 298.799504 -129.913634)
			(xy 298.799994 -129.883666) (xy 298.807817 -129.824244) (xy 298.82333 -129.766351) (xy 298.846266 -129.710978)
			(xy 298.876233 -129.659072) (xy 298.91272 -129.611522) (xy 298.9551 -129.569142) (xy 299.00265 -129.532655)
			(xy 299.054556 -129.502688) (xy 299.109929 -129.479752) (xy 299.167822 -129.464239) (xy 299.227244 -129.456416)
			(xy 299.28718 -129.456416) (xy 299.346602 -129.464239) (xy 299.404495 -129.479752) (xy 299.459868 -129.502688)
			(xy 299.511774 -129.532655) (xy 299.559324 -129.569142) (xy 299.601704 -129.611522) (xy 299.638191 -129.659072)
			(xy 299.668158 -129.710978) (xy 299.691094 -129.766351) (xy 299.706607 -129.824244) (xy 299.71443 -129.883666)
			(xy 299.71492 -129.913634) (xy 299.71492 -130.777234) (xy 299.71443 -130.807202) (xy 299.706607 -130.866624)
			(xy 299.691094 -130.924517) (xy 299.668158 -130.97989) (xy 299.638191 -131.031796) (xy 299.601704 -131.079346)
			(xy 299.559324 -131.121726) (xy 299.511774 -131.158213) (xy 299.459868 -131.18818) (xy 299.404495 -131.211116)
			(xy 299.346602 -131.226629) (xy 299.28718 -131.234452) (xy 299.227244 -131.234452) (xy 299.167822 -131.226629)
			(xy 299.109929 -131.211116) (xy 299.054556 -131.18818) (xy 299.00265 -131.158213) (xy 298.9551 -131.121726)
			(xy 298.91272 -131.079346) (xy 298.876233 -131.031796) (xy 298.846266 -130.97989) (xy 298.82333 -130.924517)
			(xy 298.807817 -130.866624) (xy 298.799994 -130.807202) (xy 298.799504 -130.777234) (xy 295.406064 -130.777234)
			(xy 295.406064 -132.577332) (xy 296.945304 -132.577332) (xy 296.945304 -131.713732) (xy 296.945794 -131.683764)
			(xy 296.953617 -131.624342) (xy 296.96913 -131.566449) (xy 296.992066 -131.511076) (xy 297.022033 -131.45917)
			(xy 297.05852 -131.41162) (xy 297.1009 -131.36924) (xy 297.14845 -131.332753) (xy 297.200356 -131.302786)
			(xy 297.255729 -131.27985) (xy 297.313622 -131.264337) (xy 297.373044 -131.256514) (xy 297.43298 -131.256514)
			(xy 297.492402 -131.264337) (xy 297.550295 -131.27985) (xy 297.605668 -131.302786) (xy 297.657574 -131.332753)
			(xy 297.705124 -131.36924) (xy 297.747504 -131.41162) (xy 297.783991 -131.45917) (xy 297.813958 -131.511076)
			(xy 297.836894 -131.566449) (xy 297.852407 -131.624342) (xy 297.86023 -131.683764) (xy 297.86072 -131.713732)
			(xy 297.86072 -132.577332) (xy 297.86023 -132.6073) (xy 297.852407 -132.666722) (xy 297.836894 -132.724615)
			(xy 297.813958 -132.779988) (xy 297.783991 -132.831894) (xy 297.747504 -132.879444) (xy 297.705124 -132.921824)
			(xy 297.657574 -132.958311) (xy 297.605668 -132.988278) (xy 297.550295 -133.011214) (xy 297.492402 -133.026727)
			(xy 297.43298 -133.03455) (xy 297.373044 -133.03455) (xy 297.313622 -133.026727) (xy 297.255729 -133.011214)
			(xy 297.200356 -132.988278) (xy 297.14845 -132.958311) (xy 297.1009 -132.921824) (xy 297.05852 -132.879444)
			(xy 297.022033 -132.831894) (xy 296.992066 -132.779988) (xy 296.96913 -132.724615) (xy 296.953617 -132.666722)
			(xy 296.945794 -132.6073) (xy 296.945304 -132.577332) (xy 295.406064 -132.577332) (xy 295.406064 -134.377176)
			(xy 298.799504 -134.377176) (xy 298.799504 -133.513576) (xy 298.799994 -133.483608) (xy 298.807817 -133.424186)
			(xy 298.82333 -133.366293) (xy 298.846266 -133.31092) (xy 298.876233 -133.259014) (xy 298.91272 -133.211464)
			(xy 298.9551 -133.169084) (xy 299.00265 -133.132597) (xy 299.054556 -133.10263) (xy 299.109929 -133.079694)
			(xy 299.167822 -133.064181) (xy 299.227244 -133.056358) (xy 299.28718 -133.056358) (xy 299.346602 -133.064181)
			(xy 299.404495 -133.079694) (xy 299.459868 -133.10263) (xy 299.511774 -133.132597) (xy 299.559324 -133.169084)
			(xy 299.601704 -133.211464) (xy 299.638191 -133.259014) (xy 299.668158 -133.31092) (xy 299.691094 -133.366293)
			(xy 299.706607 -133.424186) (xy 299.71443 -133.483608) (xy 299.71492 -133.513576) (xy 299.71492 -134.377176)
			(xy 299.71443 -134.407144) (xy 299.706607 -134.466566) (xy 299.691094 -134.524459) (xy 299.668158 -134.579832)
			(xy 299.638191 -134.631738) (xy 299.601704 -134.679288) (xy 299.559324 -134.721668) (xy 299.511774 -134.758155)
			(xy 299.459868 -134.788122) (xy 299.404495 -134.811058) (xy 299.346602 -134.826571) (xy 299.28718 -134.834394)
			(xy 299.227244 -134.834394) (xy 299.167822 -134.826571) (xy 299.109929 -134.811058) (xy 299.054556 -134.788122)
			(xy 299.00265 -134.758155) (xy 298.9551 -134.721668) (xy 298.91272 -134.679288) (xy 298.876233 -134.631738)
			(xy 298.846266 -134.579832) (xy 298.82333 -134.524459) (xy 298.807817 -134.466566) (xy 298.799994 -134.407144)
			(xy 298.799504 -134.377176) (xy 295.406064 -134.377176) (xy 295.406064 -136.177274) (xy 296.945304 -136.177274)
			(xy 296.945304 -135.313674) (xy 296.945794 -135.283706) (xy 296.953617 -135.224284) (xy 296.96913 -135.166391)
			(xy 296.992066 -135.111018) (xy 297.022033 -135.059112) (xy 297.05852 -135.011562) (xy 297.1009 -134.969182)
			(xy 297.14845 -134.932695) (xy 297.200356 -134.902728) (xy 297.255729 -134.879792) (xy 297.313622 -134.864279)
			(xy 297.373044 -134.856456) (xy 297.43298 -134.856456) (xy 297.492402 -134.864279) (xy 297.550295 -134.879792)
			(xy 297.605668 -134.902728) (xy 297.657574 -134.932695) (xy 297.705124 -134.969182) (xy 297.747504 -135.011562)
			(xy 297.783991 -135.059112) (xy 297.813958 -135.111018) (xy 297.836894 -135.166391) (xy 297.852407 -135.224284)
			(xy 297.86023 -135.283706) (xy 297.86072 -135.313674) (xy 297.86072 -136.177274) (xy 297.86023 -136.207242)
			(xy 297.852407 -136.266664) (xy 297.836894 -136.324557) (xy 297.813958 -136.37993) (xy 297.783991 -136.431836)
			(xy 297.747504 -136.479386) (xy 297.705124 -136.521766) (xy 297.657574 -136.558253) (xy 297.605668 -136.58822)
			(xy 297.550295 -136.611156) (xy 297.492402 -136.626669) (xy 297.43298 -136.634492) (xy 297.373044 -136.634492)
			(xy 297.313622 -136.626669) (xy 297.255729 -136.611156) (xy 297.200356 -136.58822) (xy 297.14845 -136.558253)
			(xy 297.1009 -136.521766) (xy 297.05852 -136.479386) (xy 297.022033 -136.431836) (xy 296.992066 -136.37993)
			(xy 296.96913 -136.324557) (xy 296.953617 -136.266664) (xy 296.945794 -136.207242) (xy 296.945304 -136.177274)
			(xy 295.406064 -136.177274) (xy 295.406064 -136.98601) (xy 312.757564 -136.98601) (xy 312.761635 -136.930388)
			(xy 312.773761 -136.875951) (xy 312.793684 -136.82386) (xy 312.82098 -136.775225) (xy 312.855066 -136.731082)
			(xy 312.895215 -136.692373) (xy 312.940573 -136.659922) (xy 312.990173 -136.634421) (xy 313.042957 -136.616414)
			(xy 313.0978 -136.606284) (xy 313.153534 -136.604247) (xy 313.208971 -136.610347) (xy 313.262928 -136.624453)
			(xy 313.314257 -136.646265) (xy 313.361863 -136.675319) (xy 313.404731 -136.710994) (xy 313.441948 -136.752531)
			(xy 313.472721 -136.799044) (xy 313.496393 -136.849541) (xy 313.512461 -136.902948) (xy 313.520581 -136.958124)
			(xy 313.52109 -136.98601) (xy 313.520581 -137.013896) (xy 313.512461 -137.069072) (xy 313.496393 -137.122479)
			(xy 313.472721 -137.172976) (xy 313.441948 -137.219489) (xy 313.404731 -137.261026) (xy 313.361863 -137.296701)
			(xy 313.314257 -137.325755) (xy 313.262928 -137.347567) (xy 313.208971 -137.361673) (xy 313.153534 -137.367773)
			(xy 313.0978 -137.365736) (xy 313.042957 -137.355606) (xy 312.990173 -137.337599) (xy 312.940573 -137.312098)
			(xy 312.895215 -137.279647) (xy 312.855066 -137.240938) (xy 312.82098 -137.196795) (xy 312.793684 -137.14816)
			(xy 312.773761 -137.096069) (xy 312.761635 -137.041632) (xy 312.757564 -136.98601) (xy 295.406064 -136.98601)
			(xy 295.406064 -138.312652) (xy 295.405572 -138.338739) (xy 295.39741 -138.390271) (xy 295.38128 -138.43989)
			(xy 295.35758 -138.486371) (xy 295.326895 -138.528568) (xy 295.308782 -138.547348) (xy 294.898572 -138.957558)
			(xy 294.894447 -138.961944) (xy 294.888168 -138.972213) (xy 294.886126 -138.977878) (xy 294.886126 -138.978386)
			(xy 294.877705 -139.003939) (xy 294.854631 -139.052544) (xy 294.824957 -139.097424) (xy 294.789272 -139.137691)
			(xy 294.748285 -139.172545) (xy 294.702807 -139.201296) (xy 294.653742 -139.223373) (xy 294.602062 -139.238339)
			(xy 294.548792 -139.245896) (xy 294.52189 -139.246356) (xy 294.494641 -139.245832) (xy 294.440697 -139.238075)
			(xy 294.388406 -139.222721) (xy 294.338832 -139.200082) (xy 294.292984 -139.170619) (xy 294.251795 -139.134932)
			(xy 294.216103 -139.093747) (xy 294.186636 -139.047902) (xy 294.163992 -138.99833) (xy 294.148633 -138.94604)
			(xy 294.140871 -138.892097) (xy 294.140382 -138.864848) (xy 289.465977 -138.864848) (xy 289.469208 -138.875851)
			(xy 289.476964 -138.929799) (xy 289.47745 -138.95705) (xy 289.476953 -138.98483) (xy 289.468879 -139.039801)
			(xy 289.45291 -139.093017) (xy 289.429384 -139.143351) (xy 289.398799 -139.189735) (xy 289.380676 -139.210796)
			(xy 289.380422 -139.21105) (xy 289.374119 -139.218931) (xy 289.367701 -139.238047) (xy 289.367976 -139.248134)
			(xy 289.37331 -139.321286) (xy 289.374479 -139.331363) (xy 289.383651 -139.34944) (xy 289.39109 -139.356338)
			(xy 289.391344 -139.356592) (xy 289.412369 -139.3748) (xy 289.449409 -139.416293) (xy 289.480036 -139.46272)
			(xy 289.503604 -139.5131) (xy 289.519614 -139.566366) (xy 289.527726 -139.621391) (xy 289.52825 -139.6492)
			(xy 289.527764 -139.676451) (xy 289.520008 -139.730399) (xy 289.510713 -139.762055) (xy 312.584753 -139.762055)
			(xy 312.584753 -139.707545) (xy 312.592512 -139.65359) (xy 312.60787 -139.601288) (xy 312.630516 -139.551704)
			(xy 312.659989 -139.505849) (xy 312.695687 -139.464655) (xy 312.736886 -139.428961) (xy 312.782745 -139.399494)
			(xy 312.832331 -139.376854) (xy 312.884635 -139.361502) (xy 312.938591 -139.35375) (xy 312.965846 -139.35329)
			(xy 312.992071 -139.353741) (xy 313.044028 -139.360915) (xy 313.094513 -139.375136) (xy 313.142576 -139.396135)
			(xy 313.18731 -139.423518) (xy 313.227874 -139.456768) (xy 313.246008 -139.475718) (xy 313.253547 -139.483065)
			(xy 313.272831 -139.491455) (xy 313.283346 -139.491974) (xy 313.357514 -139.491974) (xy 313.36804 -139.491515)
			(xy 313.387331 -139.483098) (xy 313.394852 -139.475718) (xy 313.412972 -139.456754) (xy 313.453541 -139.423506)
			(xy 313.498278 -139.396125) (xy 313.546343 -139.375125) (xy 313.59683 -139.360902) (xy 313.648788 -139.353724)
			(xy 313.675014 -139.35329) (xy 313.702264 -139.353781) (xy 313.75621 -139.361539) (xy 313.808503 -139.376895)
			(xy 313.858078 -139.399537) (xy 313.903927 -139.429003) (xy 313.945115 -139.464695) (xy 313.980805 -139.505884)
			(xy 314.01027 -139.551734) (xy 314.03291 -139.60131) (xy 314.048264 -139.653603) (xy 314.05602 -139.70755)
			(xy 314.05602 -139.71651) (xy 314.991748 -139.71651) (xy 314.995819 -139.660888) (xy 315.007945 -139.606451)
			(xy 315.027868 -139.55436) (xy 315.055164 -139.505725) (xy 315.08925 -139.461582) (xy 315.129399 -139.422873)
			(xy 315.174757 -139.390422) (xy 315.224357 -139.364921) (xy 315.277141 -139.346914) (xy 315.331984 -139.336784)
			(xy 315.387718 -139.334747) (xy 315.443155 -139.340847) (xy 315.497112 -139.354953) (xy 315.548441 -139.376765)
			(xy 315.596047 -139.405819) (xy 315.638915 -139.441494) (xy 315.676132 -139.483031) (xy 315.706905 -139.529544)
			(xy 315.730577 -139.580041) (xy 315.746645 -139.633448) (xy 315.754765 -139.688624) (xy 315.755274 -139.71651)
			(xy 315.754765 -139.744396) (xy 315.746645 -139.799572) (xy 315.730577 -139.852979) (xy 315.706905 -139.903476)
			(xy 315.676132 -139.949989) (xy 315.638915 -139.991526) (xy 315.596047 -140.027201) (xy 315.548441 -140.056255)
			(xy 315.497112 -140.078067) (xy 315.443155 -140.092173) (xy 315.387718 -140.098273) (xy 315.331984 -140.096236)
			(xy 315.277141 -140.086106) (xy 315.224357 -140.068099) (xy 315.174757 -140.042598) (xy 315.129399 -140.010147)
			(xy 315.08925 -139.971438) (xy 315.055164 -139.927295) (xy 315.027868 -139.87866) (xy 315.007945 -139.826569)
			(xy 314.995819 -139.772132) (xy 314.991748 -139.71651) (xy 314.05602 -139.71651) (xy 314.05602 -139.76205)
			(xy 314.048264 -139.815997) (xy 314.03291 -139.86829) (xy 314.01027 -139.917866) (xy 313.980805 -139.963716)
			(xy 313.945115 -140.004905) (xy 313.903927 -140.040597) (xy 313.858078 -140.070063) (xy 313.808503 -140.092705)
			(xy 313.75621 -140.108061) (xy 313.702264 -140.115819) (xy 313.675014 -140.116306) (xy 313.648788 -140.115883)
			(xy 313.59683 -140.108703) (xy 313.546344 -140.094477) (xy 313.498282 -140.073472) (xy 313.453548 -140.046085)
			(xy 313.412985 -140.01283) (xy 313.394852 -139.993878) (xy 313.387292 -139.986557) (xy 313.368023 -139.978153)
			(xy 313.357514 -139.977622) (xy 313.283346 -139.977622) (xy 313.272824 -139.978114) (xy 313.253532 -139.986508)
			(xy 313.246008 -139.993878) (xy 313.227858 -140.012812) (xy 313.187296 -140.046063) (xy 313.142565 -140.073448)
			(xy 313.094506 -140.094454) (xy 313.044024 -140.108683) (xy 312.99207 -140.115868) (xy 312.965846 -140.116306)
			(xy 312.938591 -140.11585) (xy 312.884635 -140.108098) (xy 312.832331 -140.092746) (xy 312.782745 -140.070106)
			(xy 312.736886 -140.040639) (xy 312.695687 -140.004945) (xy 312.659989 -139.963751) (xy 312.630516 -139.917896)
			(xy 312.60787 -139.868312) (xy 312.592512 -139.81601) (xy 312.584753 -139.762055) (xy 289.510713 -139.762055)
			(xy 289.504653 -139.782694) (xy 289.482011 -139.832271) (xy 289.452545 -139.878121) (xy 289.416854 -139.919312)
			(xy 289.375663 -139.955003) (xy 289.329813 -139.984469) (xy 289.280236 -140.007111) (xy 289.227941 -140.022466)
			(xy 289.173993 -140.030222) (xy 289.119491 -140.030222) (xy 289.065543 -140.022466) (xy 289.013248 -140.007111)
			(xy 288.963671 -139.984469) (xy 288.917821 -139.955003) (xy 288.87663 -139.919312) (xy 288.840939 -139.878121)
			(xy 288.811473 -139.832271) (xy 288.788831 -139.782694) (xy 288.773476 -139.730399) (xy 288.76572 -139.676451)
			(xy 288.765234 -139.6492) (xy 288.765765 -139.621421) (xy 288.773832 -139.566452) (xy 288.789793 -139.513237)
			(xy 288.813312 -139.462903) (xy 288.843889 -139.416516) (xy 288.862008 -139.395454) (xy 288.862262 -139.3952)
			(xy 288.868587 -139.387334) (xy 288.874992 -139.368207) (xy 288.874708 -139.358116) (xy 288.869374 -139.284964)
			(xy 288.868234 -139.274881) (xy 288.859041 -139.256807) (xy 288.851594 -139.249912) (xy 288.85134 -139.249658)
			(xy 288.830335 -139.231427) (xy 288.793295 -139.189938) (xy 288.762666 -139.143516) (xy 288.739094 -139.093141)
			(xy 288.72308 -139.039879) (xy 288.714962 -138.984858) (xy 288.714434 -138.95705) (xy 288.113724 -138.95705)
			(xy 288.113724 -140.565451) (xy 295.630578 -140.565451) (xy 295.630578 -140.510949) (xy 295.638334 -140.457001)
			(xy 295.653689 -140.404706) (xy 295.676331 -140.355129) (xy 295.705797 -140.309279) (xy 295.741488 -140.268088)
			(xy 295.782679 -140.232397) (xy 295.828529 -140.202931) (xy 295.878106 -140.180289) (xy 295.930401 -140.164934)
			(xy 295.984349 -140.157178) (xy 296.0116 -140.156692) (xy 296.03897 -140.15716) (xy 296.093149 -140.164978)
			(xy 296.145652 -140.180466) (xy 296.195399 -140.203308) (xy 296.241366 -140.233031) (xy 296.262298 -140.250672)
			(xy 296.262552 -140.250926) (xy 296.269646 -140.256502) (xy 296.286557 -140.262754) (xy 296.295572 -140.263118)
			(xy 296.362628 -140.263118) (xy 296.371646 -140.262771) (xy 296.388563 -140.256516) (xy 296.395648 -140.250926)
			(xy 296.395648 -140.250672) (xy 296.395902 -140.250672) (xy 296.416819 -140.233014) (xy 296.462796 -140.203306)
			(xy 296.512548 -140.180474) (xy 296.565052 -140.164987) (xy 296.61923 -140.157164) (xy 296.6466 -140.156692)
			(xy 296.673851 -140.157178) (xy 296.727799 -140.164934) (xy 296.780094 -140.180289) (xy 296.829671 -140.202931)
			(xy 296.875521 -140.232397) (xy 296.916712 -140.268088) (xy 296.952403 -140.309279) (xy 296.981869 -140.355129)
			(xy 297.004511 -140.404706) (xy 297.019866 -140.457001) (xy 297.027622 -140.510949) (xy 297.027622 -140.565451)
			(xy 297.019866 -140.619399) (xy 297.004511 -140.671694) (xy 296.981869 -140.721271) (xy 296.952403 -140.767121)
			(xy 296.916712 -140.808312) (xy 296.875521 -140.844003) (xy 296.829671 -140.873469) (xy 296.780094 -140.896111)
			(xy 296.727799 -140.911466) (xy 296.673851 -140.919222) (xy 296.6466 -140.919708) (xy 296.61923 -140.91924)
			(xy 296.565051 -140.911422) (xy 296.512548 -140.895934) (xy 296.462801 -140.873092) (xy 296.416834 -140.843369)
			(xy 296.395902 -140.825728) (xy 296.395648 -140.825474) (xy 296.388554 -140.819898) (xy 296.371643 -140.813646)
			(xy 296.362628 -140.813282) (xy 296.295572 -140.813282) (xy 296.286554 -140.813629) (xy 296.269637 -140.819884)
			(xy 296.262552 -140.825474) (xy 296.262552 -140.825728) (xy 296.262298 -140.825728) (xy 296.241381 -140.843386)
			(xy 296.195404 -140.873094) (xy 296.145652 -140.895926) (xy 296.093148 -140.911413) (xy 296.03897 -140.919236)
			(xy 296.0116 -140.919708) (xy 295.984349 -140.919222) (xy 295.930401 -140.911466) (xy 295.878106 -140.896111)
			(xy 295.828529 -140.873469) (xy 295.782679 -140.844003) (xy 295.741488 -140.808312) (xy 295.705797 -140.767121)
			(xy 295.676331 -140.721271) (xy 295.653689 -140.671694) (xy 295.638334 -140.619399) (xy 295.630578 -140.565451)
			(xy 288.113724 -140.565451) (xy 288.113724 -141.9352) (xy 288.724084 -141.9352) (xy 288.728155 -141.879578)
			(xy 288.740281 -141.825141) (xy 288.760204 -141.77305) (xy 288.7875 -141.724415) (xy 288.821586 -141.680272)
			(xy 288.861735 -141.641563) (xy 288.907093 -141.609112) (xy 288.956693 -141.583611) (xy 289.009477 -141.565604)
			(xy 289.06432 -141.555474) (xy 289.120054 -141.553437) (xy 289.175491 -141.559537) (xy 289.229448 -141.573643)
			(xy 289.280777 -141.595455) (xy 289.328383 -141.624509) (xy 289.371251 -141.660184) (xy 289.408468 -141.701721)
			(xy 289.439241 -141.748234) (xy 289.462913 -141.798731) (xy 289.478981 -141.852138) (xy 289.487101 -141.907314)
			(xy 289.48761 -141.9352) (xy 289.487101 -141.963086) (xy 289.478981 -142.018262) (xy 289.462913 -142.071669)
			(xy 289.439241 -142.122166) (xy 289.408468 -142.168679) (xy 289.371251 -142.210216) (xy 289.328383 -142.245891)
			(xy 289.280777 -142.274945) (xy 289.229448 -142.296757) (xy 289.175491 -142.310863) (xy 289.120054 -142.316963)
			(xy 289.06432 -142.314926) (xy 289.009477 -142.304796) (xy 288.956693 -142.286789) (xy 288.907093 -142.261288)
			(xy 288.861735 -142.228837) (xy 288.821586 -142.190128) (xy 288.7875 -142.145985) (xy 288.760204 -142.09735)
			(xy 288.740281 -142.045259) (xy 288.728155 -141.990822) (xy 288.724084 -141.9352) (xy 288.113724 -141.9352)
			(xy 288.113724 -142.9512) (xy 288.74034 -142.9512) (xy 288.744411 -142.895578) (xy 288.756537 -142.841141)
			(xy 288.77646 -142.78905) (xy 288.803756 -142.740415) (xy 288.837842 -142.696272) (xy 288.877991 -142.657563)
			(xy 288.923349 -142.625112) (xy 288.972949 -142.599611) (xy 289.025733 -142.581604) (xy 289.080576 -142.571474)
			(xy 289.13631 -142.569437) (xy 289.191747 -142.575537) (xy 289.245704 -142.589643) (xy 289.297033 -142.611455)
			(xy 289.344639 -142.640509) (xy 289.387507 -142.676184) (xy 289.424724 -142.717721) (xy 289.455497 -142.764234)
			(xy 289.479169 -142.814731) (xy 289.495237 -142.868138) (xy 289.503357 -142.923314) (xy 289.503866 -142.9512)
			(xy 289.503357 -142.979086) (xy 289.495237 -143.034262) (xy 289.479169 -143.087669) (xy 289.455497 -143.138166)
			(xy 289.424724 -143.184679) (xy 289.387507 -143.226216) (xy 289.344639 -143.261891) (xy 289.297033 -143.290945)
			(xy 289.245704 -143.312757) (xy 289.191747 -143.326863) (xy 289.13631 -143.332963) (xy 289.080576 -143.330926)
			(xy 289.025733 -143.320796) (xy 288.972949 -143.302789) (xy 288.923349 -143.277288) (xy 288.877991 -143.244837)
			(xy 288.837842 -143.206128) (xy 288.803756 -143.161985) (xy 288.77646 -143.11335) (xy 288.756537 -143.061259)
			(xy 288.744411 -143.006822) (xy 288.74034 -142.9512) (xy 288.113724 -142.9512) (xy 288.113724 -143.48714)
			(xy 298.799504 -143.48714) (xy 298.799504 -142.62354) (xy 298.799994 -142.593572) (xy 298.807817 -142.53415)
			(xy 298.82333 -142.476257) (xy 298.846266 -142.420884) (xy 298.876233 -142.368978) (xy 298.91272 -142.321428)
			(xy 298.9551 -142.279048) (xy 299.00265 -142.242561) (xy 299.054556 -142.212594) (xy 299.109929 -142.189658)
			(xy 299.167822 -142.174145) (xy 299.227244 -142.166322) (xy 299.28718 -142.166322) (xy 299.346602 -142.174145)
			(xy 299.404495 -142.189658) (xy 299.459868 -142.212594) (xy 299.511774 -142.242561) (xy 299.559324 -142.279048)
			(xy 299.601704 -142.321428) (xy 299.638191 -142.368978) (xy 299.668158 -142.420884) (xy 299.691094 -142.476257)
			(xy 299.706607 -142.53415) (xy 299.71443 -142.593572) (xy 299.71492 -142.62354) (xy 299.71492 -143.48714)
			(xy 299.71443 -143.517108) (xy 299.706607 -143.57653) (xy 299.691094 -143.634423) (xy 299.668158 -143.689796)
			(xy 299.638191 -143.741702) (xy 299.601704 -143.789252) (xy 299.559324 -143.831632) (xy 299.511774 -143.868119)
			(xy 299.459868 -143.898086) (xy 299.404495 -143.921022) (xy 299.346602 -143.936535) (xy 299.28718 -143.944358)
			(xy 299.227244 -143.944358) (xy 299.167822 -143.936535) (xy 299.109929 -143.921022) (xy 299.054556 -143.898086)
			(xy 299.00265 -143.868119) (xy 298.9551 -143.831632) (xy 298.91272 -143.789252) (xy 298.876233 -143.741702)
			(xy 298.846266 -143.689796) (xy 298.82333 -143.634423) (xy 298.807817 -143.57653) (xy 298.799994 -143.517108)
			(xy 298.799504 -143.48714) (xy 288.113724 -143.48714) (xy 288.113724 -144.272) (xy 288.586924 -144.272)
			(xy 288.590995 -144.216378) (xy 288.603121 -144.161941) (xy 288.623044 -144.10985) (xy 288.65034 -144.061215)
			(xy 288.684426 -144.017072) (xy 288.724575 -143.978363) (xy 288.769933 -143.945912) (xy 288.819533 -143.920411)
			(xy 288.872317 -143.902404) (xy 288.92716 -143.892274) (xy 288.982894 -143.890237) (xy 289.038331 -143.896337)
			(xy 289.092288 -143.910443) (xy 289.143617 -143.932255) (xy 289.191223 -143.961309) (xy 289.234091 -143.996984)
			(xy 289.271308 -144.038521) (xy 289.302081 -144.085034) (xy 289.325753 -144.135531) (xy 289.341821 -144.188938)
			(xy 289.349941 -144.244114) (xy 289.35045 -144.272) (xy 289.349941 -144.299886) (xy 289.341821 -144.355062)
			(xy 289.325753 -144.408469) (xy 289.302081 -144.458966) (xy 289.271308 -144.505479) (xy 289.234091 -144.547016)
			(xy 289.191223 -144.582691) (xy 289.143617 -144.611745) (xy 289.092288 -144.633557) (xy 289.038331 -144.647663)
			(xy 288.982894 -144.653763) (xy 288.92716 -144.651726) (xy 288.872317 -144.641596) (xy 288.819533 -144.623589)
			(xy 288.769933 -144.598088) (xy 288.724575 -144.565637) (xy 288.684426 -144.526928) (xy 288.65034 -144.482785)
			(xy 288.623044 -144.43415) (xy 288.603121 -144.382059) (xy 288.590995 -144.327622) (xy 288.586924 -144.272)
			(xy 288.113724 -144.272) (xy 288.113724 -145.075656) (xy 288.114166 -145.085723) (xy 288.121875 -145.104322)
			(xy 288.12871 -145.111724) (xy 288.304252 -145.287238) (xy 296.945304 -145.287238) (xy 296.945304 -144.423638)
			(xy 296.945794 -144.39367) (xy 296.953617 -144.334248) (xy 296.96913 -144.276355) (xy 296.992066 -144.220982)
			(xy 297.022033 -144.169076) (xy 297.05852 -144.121526) (xy 297.1009 -144.079146) (xy 297.14845 -144.042659)
			(xy 297.200356 -144.012692) (xy 297.255729 -143.989756) (xy 297.313622 -143.974243) (xy 297.373044 -143.96642)
			(xy 297.43298 -143.96642) (xy 297.492402 -143.974243) (xy 297.550295 -143.989756) (xy 297.605668 -144.012692)
			(xy 297.657574 -144.042659) (xy 297.705124 -144.079146) (xy 297.747504 -144.121526) (xy 297.783991 -144.169076)
			(xy 297.813958 -144.220982) (xy 297.836894 -144.276355) (xy 297.852407 -144.334248) (xy 297.86023 -144.39367)
			(xy 297.86072 -144.423638) (xy 297.86072 -145.287238) (xy 297.86023 -145.317206) (xy 297.852407 -145.376628)
			(xy 297.836894 -145.434521) (xy 297.813958 -145.489894) (xy 297.783991 -145.5418) (xy 297.747504 -145.58935)
			(xy 297.705124 -145.63173) (xy 297.657574 -145.668217) (xy 297.605668 -145.698184) (xy 297.550295 -145.72112)
			(xy 297.492402 -145.736633) (xy 297.43298 -145.744456) (xy 297.373044 -145.744456) (xy 297.313622 -145.736633)
			(xy 297.255729 -145.72112) (xy 297.200356 -145.698184) (xy 297.14845 -145.668217) (xy 297.1009 -145.63173)
			(xy 297.05852 -145.58935) (xy 297.022033 -145.5418) (xy 296.992066 -145.489894) (xy 296.96913 -145.434521)
			(xy 296.953617 -145.376628) (xy 296.945794 -145.317206) (xy 296.945304 -145.287238) (xy 288.304252 -145.287238)
			(xy 289.72891 -146.71167) (xy 289.747014 -146.730459) (xy 289.777697 -146.772656) (xy 289.801398 -146.819135)
			(xy 289.817533 -146.86875) (xy 289.825703 -146.920279) (xy 289.826192 -146.946366) (xy 289.826192 -147.087336)
			(xy 298.799504 -147.087336) (xy 298.799504 -146.223736) (xy 298.799994 -146.193768) (xy 298.807817 -146.134346)
			(xy 298.82333 -146.076453) (xy 298.846266 -146.02108) (xy 298.876233 -145.969174) (xy 298.91272 -145.921624)
			(xy 298.9551 -145.879244) (xy 299.00265 -145.842757) (xy 299.054556 -145.81279) (xy 299.109929 -145.789854)
			(xy 299.167822 -145.774341) (xy 299.227244 -145.766518) (xy 299.28718 -145.766518) (xy 299.346602 -145.774341)
			(xy 299.404495 -145.789854) (xy 299.459868 -145.81279) (xy 299.511774 -145.842757) (xy 299.559324 -145.879244)
			(xy 299.601704 -145.921624) (xy 299.638191 -145.969174) (xy 299.668158 -146.02108) (xy 299.691094 -146.076453)
			(xy 299.706607 -146.134346) (xy 299.71443 -146.193768) (xy 299.71492 -146.223736) (xy 299.71492 -147.087336)
			(xy 299.71443 -147.117304) (xy 299.706607 -147.176726) (xy 299.691094 -147.234619) (xy 299.668158 -147.289992)
			(xy 299.638191 -147.341898) (xy 299.601704 -147.389448) (xy 299.559324 -147.431828) (xy 299.511774 -147.468315)
			(xy 299.459868 -147.498282) (xy 299.404495 -147.521218) (xy 299.346602 -147.536731) (xy 299.28718 -147.544554)
			(xy 299.227244 -147.544554) (xy 299.167822 -147.536731) (xy 299.109929 -147.521218) (xy 299.054556 -147.498282)
			(xy 299.00265 -147.468315) (xy 298.9551 -147.431828) (xy 298.91272 -147.389448) (xy 298.876233 -147.341898)
			(xy 298.846266 -147.289992) (xy 298.82333 -147.234619) (xy 298.807817 -147.176726) (xy 298.799994 -147.117304)
			(xy 298.799504 -147.087336) (xy 289.826192 -147.087336) (xy 289.826192 -148.887434) (xy 296.945304 -148.887434)
			(xy 296.945304 -148.023834) (xy 296.945794 -147.993866) (xy 296.953617 -147.934444) (xy 296.96913 -147.876551)
			(xy 296.992066 -147.821178) (xy 297.022033 -147.769272) (xy 297.05852 -147.721722) (xy 297.1009 -147.679342)
			(xy 297.14845 -147.642855) (xy 297.200356 -147.612888) (xy 297.255729 -147.589952) (xy 297.313622 -147.574439)
			(xy 297.373044 -147.566616) (xy 297.43298 -147.566616) (xy 297.492402 -147.574439) (xy 297.550295 -147.589952)
			(xy 297.605668 -147.612888) (xy 297.657574 -147.642855) (xy 297.705124 -147.679342) (xy 297.747504 -147.721722)
			(xy 297.783991 -147.769272) (xy 297.813958 -147.821178) (xy 297.836894 -147.876551) (xy 297.852407 -147.934444)
			(xy 297.86023 -147.993866) (xy 297.86072 -148.023834) (xy 297.86072 -148.887434) (xy 297.86023 -148.917402)
			(xy 297.852407 -148.976824) (xy 297.836894 -149.034717) (xy 297.813958 -149.09009) (xy 297.783991 -149.141996)
			(xy 297.747504 -149.189546) (xy 297.705124 -149.231926) (xy 297.657574 -149.268413) (xy 297.605668 -149.29838)
			(xy 297.550295 -149.321316) (xy 297.492402 -149.336829) (xy 297.43298 -149.344652) (xy 297.373044 -149.344652)
			(xy 297.313622 -149.336829) (xy 297.255729 -149.321316) (xy 297.200356 -149.29838) (xy 297.14845 -149.268413)
			(xy 297.1009 -149.231926) (xy 297.05852 -149.189546) (xy 297.022033 -149.141996) (xy 296.992066 -149.09009)
			(xy 296.96913 -149.034717) (xy 296.953617 -148.976824) (xy 296.945794 -148.917402) (xy 296.945304 -148.887434)
			(xy 289.826192 -148.887434) (xy 289.826192 -150.687278) (xy 298.799504 -150.687278) (xy 298.799504 -149.823678)
			(xy 298.799994 -149.79371) (xy 298.807817 -149.734288) (xy 298.82333 -149.676395) (xy 298.846266 -149.621022)
			(xy 298.876233 -149.569116) (xy 298.91272 -149.521566) (xy 298.9551 -149.479186) (xy 299.00265 -149.442699)
			(xy 299.054556 -149.412732) (xy 299.109929 -149.389796) (xy 299.167822 -149.374283) (xy 299.227244 -149.36646)
			(xy 299.28718 -149.36646) (xy 299.346602 -149.374283) (xy 299.404495 -149.389796) (xy 299.459868 -149.412732)
			(xy 299.511774 -149.442699) (xy 299.559324 -149.479186) (xy 299.601704 -149.521566) (xy 299.638191 -149.569116)
			(xy 299.668158 -149.621022) (xy 299.691094 -149.676395) (xy 299.706607 -149.734288) (xy 299.71443 -149.79371)
			(xy 299.71492 -149.823678) (xy 299.71492 -150.687278) (xy 299.71443 -150.717246) (xy 299.706607 -150.776668)
			(xy 299.691094 -150.834561) (xy 299.668158 -150.889934) (xy 299.638191 -150.94184) (xy 299.601704 -150.98939)
			(xy 299.559324 -151.03177) (xy 299.511774 -151.068257) (xy 299.459868 -151.098224) (xy 299.404495 -151.12116)
			(xy 299.346602 -151.136673) (xy 299.28718 -151.144496) (xy 299.227244 -151.144496) (xy 299.167822 -151.136673)
			(xy 299.109929 -151.12116) (xy 299.054556 -151.098224) (xy 299.00265 -151.068257) (xy 298.9551 -151.03177)
			(xy 298.91272 -150.98939) (xy 298.876233 -150.94184) (xy 298.846266 -150.889934) (xy 298.82333 -150.834561)
			(xy 298.807817 -150.776668) (xy 298.799994 -150.717246) (xy 298.799504 -150.687278) (xy 289.826192 -150.687278)
			(xy 289.826192 -152.487376) (xy 296.945304 -152.487376) (xy 296.945304 -151.623776) (xy 296.945794 -151.593808)
			(xy 296.953617 -151.534386) (xy 296.96913 -151.476493) (xy 296.992066 -151.42112) (xy 297.022033 -151.369214)
			(xy 297.05852 -151.321664) (xy 297.1009 -151.279284) (xy 297.14845 -151.242797) (xy 297.200356 -151.21283)
			(xy 297.255729 -151.189894) (xy 297.313622 -151.174381) (xy 297.373044 -151.166558) (xy 297.43298 -151.166558)
			(xy 297.492402 -151.174381) (xy 297.550295 -151.189894) (xy 297.605668 -151.21283) (xy 297.657574 -151.242797)
			(xy 297.705124 -151.279284) (xy 297.747504 -151.321664) (xy 297.783991 -151.369214) (xy 297.813958 -151.42112)
			(xy 297.836894 -151.476493) (xy 297.852407 -151.534386) (xy 297.86023 -151.593808) (xy 297.86072 -151.623776)
			(xy 297.86072 -152.487376) (xy 297.86023 -152.517344) (xy 297.852407 -152.576766) (xy 297.836894 -152.634659)
			(xy 297.813958 -152.690032) (xy 297.783991 -152.741938) (xy 297.747504 -152.789488) (xy 297.705124 -152.831868)
			(xy 297.657574 -152.868355) (xy 297.605668 -152.898322) (xy 297.550295 -152.921258) (xy 297.492402 -152.936771)
			(xy 297.43298 -152.944594) (xy 297.373044 -152.944594) (xy 297.313622 -152.936771) (xy 297.255729 -152.921258)
			(xy 297.200356 -152.898322) (xy 297.14845 -152.868355) (xy 297.1009 -152.831868) (xy 297.05852 -152.789488)
			(xy 297.022033 -152.741938) (xy 296.992066 -152.690032) (xy 296.96913 -152.634659) (xy 296.953617 -152.576766)
			(xy 296.945794 -152.517344) (xy 296.945304 -152.487376) (xy 289.826192 -152.487376) (xy 289.826192 -154.28722)
			(xy 298.799504 -154.28722) (xy 298.799504 -153.42362) (xy 298.799994 -153.393652) (xy 298.807817 -153.33423)
			(xy 298.82333 -153.276337) (xy 298.846266 -153.220964) (xy 298.876233 -153.169058) (xy 298.91272 -153.121508)
			(xy 298.9551 -153.079128) (xy 299.00265 -153.042641) (xy 299.054556 -153.012674) (xy 299.109929 -152.989738)
			(xy 299.167822 -152.974225) (xy 299.227244 -152.966402) (xy 299.28718 -152.966402) (xy 299.346602 -152.974225)
			(xy 299.404495 -152.989738) (xy 299.459868 -153.012674) (xy 299.511774 -153.042641) (xy 299.559324 -153.079128)
			(xy 299.601704 -153.121508) (xy 299.638191 -153.169058) (xy 299.668158 -153.220964) (xy 299.691094 -153.276337)
			(xy 299.706607 -153.33423) (xy 299.71443 -153.393652) (xy 299.71492 -153.42362) (xy 299.71492 -154.28722)
			(xy 299.71443 -154.317188) (xy 299.706607 -154.37661) (xy 299.691094 -154.434503) (xy 299.668158 -154.489876)
			(xy 299.638191 -154.541782) (xy 299.601704 -154.589332) (xy 299.559324 -154.631712) (xy 299.511774 -154.668199)
			(xy 299.459868 -154.698166) (xy 299.404495 -154.721102) (xy 299.346602 -154.736615) (xy 299.28718 -154.744438)
			(xy 299.227244 -154.744438) (xy 299.167822 -154.736615) (xy 299.109929 -154.721102) (xy 299.054556 -154.698166)
			(xy 299.00265 -154.668199) (xy 298.9551 -154.631712) (xy 298.91272 -154.589332) (xy 298.876233 -154.541782)
			(xy 298.846266 -154.489876) (xy 298.82333 -154.434503) (xy 298.807817 -154.37661) (xy 298.799994 -154.317188)
			(xy 298.799504 -154.28722) (xy 289.826192 -154.28722) (xy 289.826192 -156.087318) (xy 296.945304 -156.087318)
			(xy 296.945304 -155.223718) (xy 296.945794 -155.19375) (xy 296.953617 -155.134328) (xy 296.96913 -155.076435)
			(xy 296.992066 -155.021062) (xy 297.022033 -154.969156) (xy 297.05852 -154.921606) (xy 297.1009 -154.879226)
			(xy 297.14845 -154.842739) (xy 297.200356 -154.812772) (xy 297.255729 -154.789836) (xy 297.313622 -154.774323)
			(xy 297.373044 -154.7665) (xy 297.43298 -154.7665) (xy 297.492402 -154.774323) (xy 297.550295 -154.789836)
			(xy 297.605668 -154.812772) (xy 297.657574 -154.842739) (xy 297.705124 -154.879226) (xy 297.747504 -154.921606)
			(xy 297.783991 -154.969156) (xy 297.813958 -155.021062) (xy 297.836894 -155.076435) (xy 297.852407 -155.134328)
			(xy 297.86023 -155.19375) (xy 297.86072 -155.223718) (xy 297.86072 -156.087318) (xy 297.86023 -156.117286)
			(xy 297.852407 -156.176708) (xy 297.836894 -156.234601) (xy 297.813958 -156.289974) (xy 297.783991 -156.34188)
			(xy 297.747504 -156.38943) (xy 297.705124 -156.43181) (xy 297.657574 -156.468297) (xy 297.605668 -156.498264)
			(xy 297.550295 -156.5212) (xy 297.492402 -156.536713) (xy 297.43298 -156.544536) (xy 297.373044 -156.544536)
			(xy 297.313622 -156.536713) (xy 297.255729 -156.5212) (xy 297.200356 -156.498264) (xy 297.14845 -156.468297)
			(xy 297.1009 -156.43181) (xy 297.05852 -156.38943) (xy 297.022033 -156.34188) (xy 296.992066 -156.289974)
			(xy 296.96913 -156.234601) (xy 296.953617 -156.176708) (xy 296.945794 -156.117286) (xy 296.945304 -156.087318)
			(xy 289.826192 -156.087318) (xy 289.826192 -157.045152) (xy 293.611046 -157.045152) (xy 293.611532 -157.017901)
			(xy 293.619288 -156.963953) (xy 293.634643 -156.911658) (xy 293.657285 -156.862081) (xy 293.686751 -156.816231)
			(xy 293.722442 -156.77504) (xy 293.763633 -156.739349) (xy 293.809483 -156.709883) (xy 293.85906 -156.687241)
			(xy 293.911355 -156.671886) (xy 293.965303 -156.66413) (xy 294.019805 -156.66413) (xy 294.073753 -156.671886)
			(xy 294.126048 -156.687241) (xy 294.175625 -156.709883) (xy 294.221475 -156.739349) (xy 294.262666 -156.77504)
			(xy 294.298357 -156.816231) (xy 294.327823 -156.862081) (xy 294.350465 -156.911658) (xy 294.36582 -156.963953)
			(xy 294.373576 -157.017901) (xy 294.374062 -157.045152) (xy 294.626536 -157.045152) (xy 294.630607 -156.98953)
			(xy 294.642733 -156.935093) (xy 294.662656 -156.883002) (xy 294.689952 -156.834367) (xy 294.724038 -156.790224)
			(xy 294.764187 -156.751515) (xy 294.809545 -156.719064) (xy 294.859145 -156.693563) (xy 294.911929 -156.675556)
			(xy 294.966772 -156.665426) (xy 295.022506 -156.663389) (xy 295.077943 -156.669489) (xy 295.1319 -156.683595)
			(xy 295.183229 -156.705407) (xy 295.230835 -156.734461) (xy 295.273703 -156.770136) (xy 295.31092 -156.811673)
			(xy 295.341693 -156.858186) (xy 295.365365 -156.908683) (xy 295.381433 -156.96209) (xy 295.389553 -157.017266)
			(xy 295.390062 -157.045152) (xy 295.389553 -157.073038) (xy 295.381433 -157.128214) (xy 295.365365 -157.181621)
			(xy 295.341693 -157.232118) (xy 295.31092 -157.278631) (xy 295.273703 -157.320168) (xy 295.230835 -157.355843)
			(xy 295.183229 -157.384897) (xy 295.1319 -157.406709) (xy 295.077943 -157.420815) (xy 295.022506 -157.426915)
			(xy 294.966772 -157.424878) (xy 294.911929 -157.414748) (xy 294.859145 -157.396741) (xy 294.809545 -157.37124)
			(xy 294.764187 -157.338789) (xy 294.724038 -157.30008) (xy 294.689952 -157.255937) (xy 294.662656 -157.207302)
			(xy 294.642733 -157.155211) (xy 294.630607 -157.100774) (xy 294.626536 -157.045152) (xy 294.374062 -157.045152)
			(xy 294.37347 -157.075956) (xy 294.363538 -157.136757) (xy 294.343957 -157.19517) (xy 294.33012 -157.222698)
			(xy 294.329866 -157.223206) (xy 294.327402 -157.228532) (xy 294.324701 -157.239947) (xy 294.324532 -157.245812)
			(xy 294.324532 -160.1851) (xy 302.088563 -160.1851) (xy 302.09252 -160.093219) (xy 302.10436 -160.002019)
			(xy 302.123997 -159.912174) (xy 302.151284 -159.824349) (xy 302.18602 -159.739196) (xy 302.227948 -159.657343)
			(xy 302.276757 -159.579398) (xy 302.332086 -159.505938) (xy 302.393526 -159.437506) (xy 302.46062 -159.374608)
			(xy 302.532873 -159.317712) (xy 302.60975 -159.267237) (xy 302.690681 -159.223557) (xy 302.775067 -159.186997)
			(xy 302.862284 -159.157826) (xy 302.951686 -159.136261) (xy 303.042611 -159.122461) (xy 303.134385 -159.116528)
			(xy 303.22633 -159.118507) (xy 303.317764 -159.128383) (xy 303.408011 -159.146082) (xy 303.496402 -159.171473)
			(xy 303.582283 -159.204369) (xy 303.665019 -159.244526) (xy 303.743996 -159.291647) (xy 303.81863 -159.345383)
			(xy 303.888368 -159.405335) (xy 303.952694 -159.471061) (xy 304.011133 -159.542073) (xy 304.06325 -159.617846)
			(xy 304.10866 -159.697818) (xy 304.147028 -159.781399) (xy 304.178069 -159.867968) (xy 304.201552 -159.956885)
			(xy 304.217306 -160.047492) (xy 304.225211 -160.139117) (xy 304.225706 -160.1851) (xy 304.225211 -160.231083)
			(xy 304.217306 -160.322708) (xy 304.201552 -160.413315) (xy 304.178069 -160.502232) (xy 304.147028 -160.588801)
			(xy 304.10866 -160.672382) (xy 304.06325 -160.752354) (xy 304.011133 -160.828127) (xy 303.952694 -160.899139)
			(xy 303.888368 -160.964865) (xy 303.81863 -161.024817) (xy 303.743996 -161.078553) (xy 303.665019 -161.125674)
			(xy 303.582283 -161.165831) (xy 303.496402 -161.198727) (xy 303.408011 -161.224118) (xy 303.317764 -161.241817)
			(xy 303.22633 -161.251693) (xy 303.134385 -161.253672) (xy 303.042611 -161.247739) (xy 302.951686 -161.233939)
			(xy 302.862284 -161.212374) (xy 302.775067 -161.183203) (xy 302.690681 -161.146643) (xy 302.60975 -161.102963)
			(xy 302.532873 -161.052488) (xy 302.46062 -160.995592) (xy 302.393526 -160.932694) (xy 302.332086 -160.864262)
			(xy 302.276757 -160.790802) (xy 302.227948 -160.712857) (xy 302.18602 -160.631004) (xy 302.151284 -160.545851)
			(xy 302.123997 -160.458026) (xy 302.10436 -160.368181) (xy 302.09252 -160.276981) (xy 302.088563 -160.1851)
			(xy 294.324532 -160.1851) (xy 294.324532 -160.33877) (xy 294.324965 -160.348839) (xy 294.33268 -160.367437)
			(xy 294.339518 -160.374838) (xy 294.700706 -160.736026) (xy 294.718836 -160.754791) (xy 294.749516 -160.796994)
			(xy 294.773212 -160.843479) (xy 294.789341 -160.8931) (xy 294.797504 -160.944634) (xy 294.797988 -160.970722)
			(xy 294.797988 -163.111688) (xy 294.798396 -163.12176) (xy 294.806126 -163.140359) (xy 294.812974 -163.147756)
			(xy 295.960546 -164.295328) (xy 295.978666 -164.314102) (xy 296.00935 -164.356301) (xy 296.033049 -164.402784)
			(xy 296.04918 -164.452403) (xy 296.057344 -164.503936) (xy 296.057828 -164.530024) (xy 296.057828 -166.51097)
			(xy 296.060368 -166.522146) (xy 296.063162 -166.52748) (xy 296.06367 -166.528496) (xy 296.077394 -166.55597)
			(xy 296.096847 -166.614218) (xy 296.106722 -166.674829) (xy 296.107358 -166.705534) (xy 296.106872 -166.732785)
			(xy 296.099116 -166.786733) (xy 296.083761 -166.839028) (xy 296.061119 -166.888605) (xy 296.031653 -166.934455)
			(xy 295.995962 -166.975646) (xy 295.954771 -167.011337) (xy 295.908921 -167.040803) (xy 295.859344 -167.063445)
			(xy 295.807049 -167.0788) (xy 295.753101 -167.086556) (xy 295.698599 -167.086556) (xy 295.644651 -167.0788)
			(xy 295.592356 -167.063445) (xy 295.542779 -167.040803) (xy 295.496929 -167.011337) (xy 295.455738 -166.975646)
			(xy 295.420047 -166.934455) (xy 295.390581 -166.888605) (xy 295.367939 -166.839028) (xy 295.352584 -166.786733)
			(xy 295.344828 -166.732785) (xy 295.344342 -166.705534) (xy 295.344928 -166.67473) (xy 295.354862 -166.613928)
			(xy 295.374446 -166.555515) (xy 295.388284 -166.527988) (xy 295.388538 -166.52748) (xy 295.391007 -166.522156)
			(xy 295.393705 -166.51074) (xy 295.393872 -166.504874) (xy 295.393872 -164.68852) (xy 295.393444 -164.678451)
			(xy 295.385726 -164.659853) (xy 295.378886 -164.652452) (xy 294.231314 -163.50488) (xy 294.213191 -163.486109)
			(xy 294.182509 -163.443908) (xy 294.158811 -163.397425) (xy 294.142681 -163.347805) (xy 294.134517 -163.296272)
			(xy 294.134032 -163.270184) (xy 294.134032 -161.129218) (xy 294.133615 -161.119147) (xy 294.12589 -161.100549)
			(xy 294.119046 -161.09315) (xy 293.757858 -160.731962) (xy 293.739734 -160.713192) (xy 293.70905 -160.670991)
			(xy 293.685352 -160.624508) (xy 293.669222 -160.574888) (xy 293.66106 -160.523354) (xy 293.660576 -160.497266)
			(xy 293.660576 -157.239716) (xy 293.658036 -157.22854) (xy 293.655242 -157.223206) (xy 293.654734 -157.22219)
			(xy 293.641006 -157.194718) (xy 293.621554 -157.136469) (xy 293.61168 -157.075857) (xy 293.611046 -157.045152)
			(xy 289.826192 -157.045152) (xy 289.826192 -161.331402) (xy 289.826592 -161.341475) (xy 289.834328 -161.360074)
			(xy 289.841178 -161.36747) (xy 294.80256 -166.328852) (xy 294.806954 -166.332968) (xy 294.817218 -166.339253)
			(xy 294.82288 -166.341298) (xy 294.823388 -166.341298) (xy 294.848949 -166.349696) (xy 294.897555 -166.372773)
			(xy 294.942436 -166.40245) (xy 294.982703 -166.438137) (xy 295.017557 -166.479128) (xy 295.046307 -166.524608)
			(xy 295.068382 -166.573676) (xy 295.083345 -166.625359) (xy 295.0909 -166.678631) (xy 295.091358 -166.705534)
			(xy 295.090977 -166.73279) (xy 295.083214 -166.786747) (xy 295.067851 -166.839049) (xy 295.045201 -166.888633)
			(xy 295.015724 -166.934488) (xy 294.980022 -166.975682) (xy 294.938821 -167.011375) (xy 294.892959 -167.040841)
			(xy 294.84337 -167.06348) (xy 294.791064 -167.078832) (xy 294.737106 -167.086583) (xy 294.70985 -167.087042)
			(xy 294.682941 -167.086557) (xy 294.629658 -167.078975) (xy 294.57797 -167.063982) (xy 294.528901 -167.041876)
			(xy 294.483424 -167.013095) (xy 294.442441 -166.97821) (xy 294.406767 -166.937914) (xy 294.377107 -166.893005)
			(xy 294.354052 -166.844375) (xy 294.345614 -166.818818) (xy 294.345614 -166.818564) (xy 294.34364 -166.812869)
			(xy 294.33734 -166.802595) (xy 294.333168 -166.798244) (xy 294.242998 -166.708074) (xy 294.236052 -166.701768)
			(xy 294.218938 -166.694131) (xy 294.200225 -166.693137) (xy 294.191182 -166.695628) (xy 294.091614 -166.72814)
			(xy 294.073072 -166.749984) (xy 294.070786 -166.764208) (xy 294.066193 -166.790849) (xy 294.050427 -166.84256)
			(xy 294.027518 -166.891527) (xy 293.997924 -166.936769) (xy 293.962239 -166.977379) (xy 293.921178 -167.012544)
			(xy 293.875563 -167.041559) (xy 293.826309 -167.063843) (xy 293.774401 -167.078949) (xy 293.720881 -167.086575)
			(xy 293.69385 -167.087042) (xy 293.6666 -167.086498) (xy 293.612654 -167.078749) (xy 293.560359 -167.063401)
			(xy 293.510782 -167.040767) (xy 293.46493 -167.011307) (xy 293.423738 -166.975622) (xy 293.388043 -166.934437)
			(xy 293.358573 -166.888592) (xy 293.335928 -166.839019) (xy 293.320569 -166.786729) (xy 293.312808 -166.732784)
			(xy 293.312342 -166.705534) (xy 293.312826 -166.678507) (xy 293.320465 -166.624994) (xy 293.335579 -166.573095)
			(xy 293.357867 -166.523849) (xy 293.386883 -166.478242) (xy 293.422045 -166.437186) (xy 293.462649 -166.401504)
			(xy 293.507883 -166.37191) (xy 293.556841 -166.348996) (xy 293.608543 -166.333222) (xy 293.635176 -166.328598)
			(xy 293.6494 -166.326312) (xy 293.671244 -166.30777) (xy 293.703756 -166.208202) (xy 293.706308 -166.199158)
			(xy 293.705367 -166.180406) (xy 293.697712 -166.163262) (xy 293.69131 -166.156386) (xy 289.259518 -161.724594)
			(xy 289.241402 -161.705816) (xy 289.210719 -161.663617) (xy 289.18702 -161.617135) (xy 289.170888 -161.567517)
			(xy 289.162722 -161.515985) (xy 289.162236 -161.489898) (xy 289.162236 -147.104862) (xy 289.161847 -147.094788)
			(xy 289.154103 -147.07619) (xy 289.14725 -147.068794) (xy 287.547304 -145.468848) (xy 287.529279 -145.45007)
			(xy 287.498698 -145.407955) (xy 287.475069 -145.361581) (xy 287.458973 -145.312085) (xy 287.450804 -145.260683)
			(xy 287.450276 -145.23466) (xy 287.450276 -134.111746) (xy 287.450797 -134.085722) (xy 287.458965 -134.034319)
			(xy 287.475061 -133.984821) (xy 287.49869 -133.938445) (xy 287.529271 -133.896329) (xy 287.547304 -133.877558)
			(xy 289.18789 -132.237226) (xy 289.19471 -132.22981) (xy 289.202442 -132.211223) (xy 289.202876 -132.201158)
			(xy 289.202876 -118.522242) (xy 289.202435 -118.512174) (xy 289.194726 -118.493576) (xy 289.18789 -118.486174)
			(xy 287.007554 -116.305838) (xy 287.000125 -116.299034) (xy 286.981548 -116.291292) (xy 286.971486 -116.290852)
			(xy 285.691072 -116.290852) (xy 285.665048 -116.290335) (xy 285.613643 -116.282169) (xy 285.564145 -116.266074)
			(xy 285.517769 -116.242443) (xy 285.475653 -116.211859) (xy 285.456884 -116.193824) (xy 283.000704 -113.737644)
			(xy 282.982677 -113.718868) (xy 282.952096 -113.676752) (xy 282.928468 -113.630378) (xy 282.912372 -113.580882)
			(xy 282.904204 -113.529479) (xy 282.903676 -113.503456) (xy 271.815052 -113.503456) (xy 271.815052 -115.452906)
			(xy 271.81452 -115.478928) (xy 271.806346 -115.530327) (xy 271.790245 -115.579819) (xy 271.766614 -115.626189)
			(xy 271.736032 -115.668301) (xy 271.718024 -115.687094) (xy 270.657828 -116.74729) (xy 270.639047 -116.765402)
			(xy 270.59685 -116.796084) (xy 270.550368 -116.81978) (xy 270.50075 -116.835906) (xy 270.449219 -116.844065)
			(xy 270.423132 -116.844572) (xy 270.046704 -116.844572) (xy 270.040343 -116.84473) (xy 270.028 -116.847802)
			(xy 270.02232 -116.850668) (xy 270.009874 -116.857272) (xy 270.002254 -116.875814) (xy 269.998919 -116.885203)
			(xy 269.998941 -116.905106) (xy 270.00653 -116.923507) (xy 270.013176 -116.930932) (xy 271.332198 -118.249954)
			(xy 287.813748 -118.249954) (xy 287.817819 -118.194332) (xy 287.829945 -118.139895) (xy 287.849868 -118.087804)
			(xy 287.877164 -118.039169) (xy 287.91125 -117.995026) (xy 287.951399 -117.956317) (xy 287.996757 -117.923866)
			(xy 288.046357 -117.898365) (xy 288.099141 -117.880358) (xy 288.153984 -117.870228) (xy 288.209718 -117.868191)
			(xy 288.265155 -117.874291) (xy 288.319112 -117.888397) (xy 288.370441 -117.910209) (xy 288.418047 -117.939263)
			(xy 288.460915 -117.974938) (xy 288.498132 -118.016475) (xy 288.528905 -118.062988) (xy 288.552577 -118.113485)
			(xy 288.568645 -118.166892) (xy 288.576765 -118.222068) (xy 288.577274 -118.249954) (xy 288.576765 -118.27784)
			(xy 288.568645 -118.333016) (xy 288.552577 -118.386423) (xy 288.528905 -118.43692) (xy 288.498132 -118.483433)
			(xy 288.460915 -118.52497) (xy 288.418047 -118.560645) (xy 288.370441 -118.589699) (xy 288.319112 -118.611511)
			(xy 288.265155 -118.625617) (xy 288.209718 -118.631717) (xy 288.153984 -118.62968) (xy 288.099141 -118.61955)
			(xy 288.046357 -118.601543) (xy 287.996757 -118.576042) (xy 287.951399 -118.543591) (xy 287.91125 -118.504882)
			(xy 287.877164 -118.460739) (xy 287.849868 -118.412104) (xy 287.829945 -118.360013) (xy 287.817819 -118.305576)
			(xy 287.813748 -118.249954) (xy 271.332198 -118.249954) (xy 273.168618 -120.086374) (xy 285.8389 -120.086374)
			(xy 285.8389 -119.222774) (xy 285.83939 -119.19279) (xy 285.847218 -119.133334) (xy 285.862739 -119.075409)
			(xy 285.885688 -119.020005) (xy 285.915672 -118.968071) (xy 285.952178 -118.920495) (xy 285.994583 -118.87809)
			(xy 286.042159 -118.841584) (xy 286.094093 -118.8116) (xy 286.149497 -118.788651) (xy 286.207422 -118.77313)
			(xy 286.266878 -118.765302) (xy 286.326846 -118.765302) (xy 286.386302 -118.77313) (xy 286.444227 -118.788651)
			(xy 286.499631 -118.8116) (xy 286.551565 -118.841584) (xy 286.599141 -118.87809) (xy 286.641546 -118.920495)
			(xy 286.678052 -118.968071) (xy 286.708036 -119.020005) (xy 286.730985 -119.075409) (xy 286.746506 -119.133334)
			(xy 286.754334 -119.19279) (xy 286.754824 -119.222774) (xy 286.754824 -120.086374) (xy 286.754334 -120.116358)
			(xy 286.746506 -120.175814) (xy 286.730985 -120.233739) (xy 286.708036 -120.289143) (xy 286.678052 -120.341077)
			(xy 286.641546 -120.388653) (xy 286.599141 -120.431058) (xy 286.551565 -120.467564) (xy 286.499631 -120.497548)
			(xy 286.444227 -120.520497) (xy 286.386302 -120.536018) (xy 286.326846 -120.543846) (xy 286.266878 -120.543846)
			(xy 286.207422 -120.536018) (xy 286.149497 -120.520497) (xy 286.094093 -120.497548) (xy 286.042159 -120.467564)
			(xy 285.994583 -120.431058) (xy 285.952178 -120.388653) (xy 285.915672 -120.341077) (xy 285.885688 -120.289143)
			(xy 285.862739 -120.233739) (xy 285.847218 -120.175814) (xy 285.83939 -120.116358) (xy 285.8389 -120.086374)
			(xy 273.168618 -120.086374) (xy 274.651978 -121.569734) (xy 274.670092 -121.588514) (xy 274.70078 -121.63071)
			(xy 274.724483 -121.677191) (xy 274.740616 -121.72681) (xy 274.74878 -121.778342) (xy 274.74926 -121.80443)
			(xy 274.74926 -121.886472) (xy 283.9847 -121.886472) (xy 283.9847 -121.022872) (xy 283.98519 -120.992888)
			(xy 283.993018 -120.933432) (xy 284.008539 -120.875507) (xy 284.031488 -120.820103) (xy 284.061472 -120.768169)
			(xy 284.097978 -120.720593) (xy 284.140383 -120.678188) (xy 284.187959 -120.641682) (xy 284.239893 -120.611698)
			(xy 284.295297 -120.588749) (xy 284.353222 -120.573228) (xy 284.412678 -120.5654) (xy 284.472646 -120.5654)
			(xy 284.532102 -120.573228) (xy 284.590027 -120.588749) (xy 284.645431 -120.611698) (xy 284.697365 -120.641682)
			(xy 284.744941 -120.678188) (xy 284.787346 -120.720593) (xy 284.823852 -120.768169) (xy 284.853836 -120.820103)
			(xy 284.876785 -120.875507) (xy 284.892306 -120.933432) (xy 284.900134 -120.992888) (xy 284.900624 -121.022872)
			(xy 284.900624 -121.886472) (xy 284.900134 -121.916456) (xy 284.892306 -121.975912) (xy 284.876785 -122.033837)
			(xy 284.853836 -122.089241) (xy 284.823852 -122.141175) (xy 284.787346 -122.188751) (xy 284.744941 -122.231156)
			(xy 284.697365 -122.267662) (xy 284.645431 -122.297646) (xy 284.590027 -122.320595) (xy 284.532102 -122.336116)
			(xy 284.472646 -122.343944) (xy 284.412678 -122.343944) (xy 284.353222 -122.336116) (xy 284.295297 -122.320595)
			(xy 284.239893 -122.297646) (xy 284.187959 -122.267662) (xy 284.140383 -122.231156) (xy 284.097978 -122.188751)
			(xy 284.061472 -122.141175) (xy 284.031488 -122.089241) (xy 284.008539 -122.033837) (xy 283.993018 -121.975912)
			(xy 283.98519 -121.916456) (xy 283.9847 -121.886472) (xy 274.74926 -121.886472) (xy 274.74926 -123.686316)
			(xy 285.8389 -123.686316) (xy 285.8389 -122.822716) (xy 285.83939 -122.792732) (xy 285.847218 -122.733276)
			(xy 285.862739 -122.675351) (xy 285.885688 -122.619947) (xy 285.915672 -122.568013) (xy 285.952178 -122.520437)
			(xy 285.994583 -122.478032) (xy 286.042159 -122.441526) (xy 286.094093 -122.411542) (xy 286.149497 -122.388593)
			(xy 286.207422 -122.373072) (xy 286.266878 -122.365244) (xy 286.326846 -122.365244) (xy 286.386302 -122.373072)
			(xy 286.444227 -122.388593) (xy 286.499631 -122.411542) (xy 286.551565 -122.441526) (xy 286.599141 -122.478032)
			(xy 286.641546 -122.520437) (xy 286.678052 -122.568013) (xy 286.708036 -122.619947) (xy 286.730985 -122.675351)
			(xy 286.746506 -122.733276) (xy 286.754334 -122.792732) (xy 286.754824 -122.822716) (xy 286.754824 -123.686316)
			(xy 286.754334 -123.7163) (xy 286.746506 -123.775756) (xy 286.730985 -123.833681) (xy 286.708036 -123.889085)
			(xy 286.678052 -123.941019) (xy 286.641546 -123.988595) (xy 286.599141 -124.031) (xy 286.551565 -124.067506)
			(xy 286.499631 -124.09749) (xy 286.444227 -124.120439) (xy 286.386302 -124.13596) (xy 286.326846 -124.143788)
			(xy 286.266878 -124.143788) (xy 286.207422 -124.13596) (xy 286.149497 -124.120439) (xy 286.094093 -124.09749)
			(xy 286.042159 -124.067506) (xy 285.994583 -124.031) (xy 285.952178 -123.988595) (xy 285.915672 -123.941019)
			(xy 285.885688 -123.889085) (xy 285.862739 -123.833681) (xy 285.847218 -123.775756) (xy 285.83939 -123.7163)
			(xy 285.8389 -123.686316) (xy 274.74926 -123.686316) (xy 274.74926 -125.486414) (xy 283.9847 -125.486414)
			(xy 283.9847 -124.622814) (xy 283.98519 -124.59283) (xy 283.993018 -124.533374) (xy 284.008539 -124.475449)
			(xy 284.031488 -124.420045) (xy 284.061472 -124.368111) (xy 284.097978 -124.320535) (xy 284.140383 -124.27813)
			(xy 284.187959 -124.241624) (xy 284.239893 -124.21164) (xy 284.295297 -124.188691) (xy 284.353222 -124.17317)
			(xy 284.412678 -124.165342) (xy 284.472646 -124.165342) (xy 284.532102 -124.17317) (xy 284.590027 -124.188691)
			(xy 284.645431 -124.21164) (xy 284.697365 -124.241624) (xy 284.744941 -124.27813) (xy 284.787346 -124.320535)
			(xy 284.823852 -124.368111) (xy 284.853836 -124.420045) (xy 284.876785 -124.475449) (xy 284.892306 -124.533374)
			(xy 284.900134 -124.59283) (xy 284.900624 -124.622814) (xy 284.900624 -125.486414) (xy 284.900134 -125.516398)
			(xy 284.892306 -125.575854) (xy 284.876785 -125.633779) (xy 284.853836 -125.689183) (xy 284.823852 -125.741117)
			(xy 284.787346 -125.788693) (xy 284.744941 -125.831098) (xy 284.697365 -125.867604) (xy 284.645431 -125.897588)
			(xy 284.590027 -125.920537) (xy 284.532102 -125.936058) (xy 284.472646 -125.943886) (xy 284.412678 -125.943886)
			(xy 284.353222 -125.936058) (xy 284.295297 -125.920537) (xy 284.239893 -125.897588) (xy 284.187959 -125.867604)
			(xy 284.140383 -125.831098) (xy 284.097978 -125.788693) (xy 284.061472 -125.741117) (xy 284.031488 -125.689183)
			(xy 284.008539 -125.633779) (xy 283.993018 -125.575854) (xy 283.98519 -125.516398) (xy 283.9847 -125.486414)
			(xy 274.74926 -125.486414) (xy 274.74926 -128.589024) (xy 285.77997 -128.589024) (xy 285.784041 -128.533402)
			(xy 285.796167 -128.478965) (xy 285.81609 -128.426874) (xy 285.843386 -128.378239) (xy 285.877472 -128.334096)
			(xy 285.917621 -128.295387) (xy 285.962979 -128.262936) (xy 286.012579 -128.237435) (xy 286.065363 -128.219428)
			(xy 286.120206 -128.209298) (xy 286.17594 -128.207261) (xy 286.231377 -128.213361) (xy 286.285334 -128.227467)
			(xy 286.336663 -128.249279) (xy 286.384269 -128.278333) (xy 286.427137 -128.314008) (xy 286.464354 -128.355545)
			(xy 286.495127 -128.402058) (xy 286.518799 -128.452555) (xy 286.534867 -128.505962) (xy 286.542987 -128.561138)
			(xy 286.543496 -128.589024) (xy 286.542987 -128.61691) (xy 286.534867 -128.672086) (xy 286.518799 -128.725493)
			(xy 286.495127 -128.77599) (xy 286.464354 -128.822503) (xy 286.427137 -128.86404) (xy 286.384269 -128.899715)
			(xy 286.336663 -128.928769) (xy 286.285334 -128.950581) (xy 286.231377 -128.964687) (xy 286.17594 -128.970787)
			(xy 286.120206 -128.96875) (xy 286.065363 -128.95862) (xy 286.012579 -128.940613) (xy 285.962979 -128.915112)
			(xy 285.917621 -128.882661) (xy 285.877472 -128.843952) (xy 285.843386 -128.799809) (xy 285.81609 -128.751174)
			(xy 285.796167 -128.699083) (xy 285.784041 -128.644646) (xy 285.77997 -128.589024) (xy 274.74926 -128.589024)
			(xy 274.74926 -131.29641) (xy 285.8389 -131.29641) (xy 285.8389 -130.43281) (xy 285.83939 -130.402826)
			(xy 285.847218 -130.34337) (xy 285.862739 -130.285445) (xy 285.885688 -130.230041) (xy 285.915672 -130.178107)
			(xy 285.952178 -130.130531) (xy 285.994583 -130.088126) (xy 286.042159 -130.05162) (xy 286.094093 -130.021636)
			(xy 286.149497 -129.998687) (xy 286.207422 -129.983166) (xy 286.266878 -129.975338) (xy 286.326846 -129.975338)
			(xy 286.386302 -129.983166) (xy 286.444227 -129.998687) (xy 286.499631 -130.021636) (xy 286.551565 -130.05162)
			(xy 286.599141 -130.088126) (xy 286.641546 -130.130531) (xy 286.678052 -130.178107) (xy 286.708036 -130.230041)
			(xy 286.730985 -130.285445) (xy 286.746506 -130.34337) (xy 286.754334 -130.402826) (xy 286.754824 -130.43281)
			(xy 286.754824 -131.29641) (xy 286.754334 -131.326394) (xy 286.746506 -131.38585) (xy 286.730985 -131.443775)
			(xy 286.708036 -131.499179) (xy 286.678052 -131.551113) (xy 286.641546 -131.598689) (xy 286.599141 -131.641094)
			(xy 286.551565 -131.6776) (xy 286.499631 -131.707584) (xy 286.444227 -131.730533) (xy 286.386302 -131.746054)
			(xy 286.326846 -131.753882) (xy 286.266878 -131.753882) (xy 286.207422 -131.746054) (xy 286.149497 -131.730533)
			(xy 286.094093 -131.707584) (xy 286.042159 -131.6776) (xy 285.994583 -131.641094) (xy 285.952178 -131.598689)
			(xy 285.915672 -131.551113) (xy 285.885688 -131.499179) (xy 285.862739 -131.443775) (xy 285.847218 -131.38585)
			(xy 285.83939 -131.326394) (xy 285.8389 -131.29641) (xy 274.74926 -131.29641) (xy 274.74926 -133.096508)
			(xy 283.9847 -133.096508) (xy 283.9847 -132.232908) (xy 283.98519 -132.202924) (xy 283.993018 -132.143468)
			(xy 284.008539 -132.085543) (xy 284.031488 -132.030139) (xy 284.061472 -131.978205) (xy 284.097978 -131.930629)
			(xy 284.140383 -131.888224) (xy 284.187959 -131.851718) (xy 284.239893 -131.821734) (xy 284.295297 -131.798785)
			(xy 284.353222 -131.783264) (xy 284.412678 -131.775436) (xy 284.472646 -131.775436) (xy 284.532102 -131.783264)
			(xy 284.590027 -131.798785) (xy 284.645431 -131.821734) (xy 284.697365 -131.851718) (xy 284.744941 -131.888224)
			(xy 284.787346 -131.930629) (xy 284.823852 -131.978205) (xy 284.853836 -132.030139) (xy 284.876785 -132.085543)
			(xy 284.892306 -132.143468) (xy 284.900134 -132.202924) (xy 284.900624 -132.232908) (xy 284.900624 -133.096508)
			(xy 284.900134 -133.126492) (xy 284.892306 -133.185948) (xy 284.876785 -133.243873) (xy 284.853836 -133.299277)
			(xy 284.823852 -133.351211) (xy 284.787346 -133.398787) (xy 284.744941 -133.441192) (xy 284.697365 -133.477698)
			(xy 284.645431 -133.507682) (xy 284.590027 -133.530631) (xy 284.532102 -133.546152) (xy 284.472646 -133.55398)
			(xy 284.412678 -133.55398) (xy 284.353222 -133.546152) (xy 284.295297 -133.530631) (xy 284.239893 -133.507682)
			(xy 284.187959 -133.477698) (xy 284.140383 -133.441192) (xy 284.097978 -133.398787) (xy 284.061472 -133.351211)
			(xy 284.031488 -133.299277) (xy 284.008539 -133.243873) (xy 283.993018 -133.185948) (xy 283.98519 -133.126492)
			(xy 283.9847 -133.096508) (xy 274.74926 -133.096508) (xy 274.74926 -134.896352) (xy 285.8389 -134.896352)
			(xy 285.8389 -134.032752) (xy 285.83939 -134.002768) (xy 285.847218 -133.943312) (xy 285.862739 -133.885387)
			(xy 285.885688 -133.829983) (xy 285.915672 -133.778049) (xy 285.952178 -133.730473) (xy 285.994583 -133.688068)
			(xy 286.042159 -133.651562) (xy 286.094093 -133.621578) (xy 286.149497 -133.598629) (xy 286.207422 -133.583108)
			(xy 286.266878 -133.57528) (xy 286.326846 -133.57528) (xy 286.386302 -133.583108) (xy 286.444227 -133.598629)
			(xy 286.499631 -133.621578) (xy 286.551565 -133.651562) (xy 286.599141 -133.688068) (xy 286.641546 -133.730473)
			(xy 286.678052 -133.778049) (xy 286.708036 -133.829983) (xy 286.730985 -133.885387) (xy 286.746506 -133.943312)
			(xy 286.754334 -134.002768) (xy 286.754824 -134.032752) (xy 286.754824 -134.896352) (xy 286.754334 -134.926336)
			(xy 286.746506 -134.985792) (xy 286.730985 -135.043717) (xy 286.708036 -135.099121) (xy 286.678052 -135.151055)
			(xy 286.641546 -135.198631) (xy 286.599141 -135.241036) (xy 286.551565 -135.277542) (xy 286.499631 -135.307526)
			(xy 286.444227 -135.330475) (xy 286.386302 -135.345996) (xy 286.326846 -135.353824) (xy 286.266878 -135.353824)
			(xy 286.207422 -135.345996) (xy 286.149497 -135.330475) (xy 286.094093 -135.307526) (xy 286.042159 -135.277542)
			(xy 285.994583 -135.241036) (xy 285.952178 -135.198631) (xy 285.915672 -135.151055) (xy 285.885688 -135.099121)
			(xy 285.862739 -135.043717) (xy 285.847218 -134.985792) (xy 285.83939 -134.926336) (xy 285.8389 -134.896352)
			(xy 274.74926 -134.896352) (xy 274.74926 -136.69645) (xy 283.9847 -136.69645) (xy 283.9847 -135.83285)
			(xy 283.98519 -135.802866) (xy 283.993018 -135.74341) (xy 284.008539 -135.685485) (xy 284.031488 -135.630081)
			(xy 284.061472 -135.578147) (xy 284.097978 -135.530571) (xy 284.140383 -135.488166) (xy 284.187959 -135.45166)
			(xy 284.239893 -135.421676) (xy 284.295297 -135.398727) (xy 284.353222 -135.383206) (xy 284.412678 -135.375378)
			(xy 284.472646 -135.375378) (xy 284.532102 -135.383206) (xy 284.590027 -135.398727) (xy 284.645431 -135.421676)
			(xy 284.697365 -135.45166) (xy 284.744941 -135.488166) (xy 284.787346 -135.530571) (xy 284.823852 -135.578147)
			(xy 284.853836 -135.630081) (xy 284.876785 -135.685485) (xy 284.892306 -135.74341) (xy 284.900134 -135.802866)
			(xy 284.900624 -135.83285) (xy 284.900624 -136.69645) (xy 284.900134 -136.726434) (xy 284.892306 -136.78589)
			(xy 284.876785 -136.843815) (xy 284.853836 -136.899219) (xy 284.823852 -136.951153) (xy 284.787346 -136.998729)
			(xy 284.744941 -137.041134) (xy 284.697365 -137.07764) (xy 284.645431 -137.107624) (xy 284.590027 -137.130573)
			(xy 284.532102 -137.146094) (xy 284.472646 -137.153922) (xy 284.412678 -137.153922) (xy 284.353222 -137.146094)
			(xy 284.295297 -137.130573) (xy 284.239893 -137.107624) (xy 284.187959 -137.07764) (xy 284.140383 -137.041134)
			(xy 284.097978 -136.998729) (xy 284.061472 -136.951153) (xy 284.031488 -136.899219) (xy 284.008539 -136.843815)
			(xy 283.993018 -136.78589) (xy 283.98519 -136.726434) (xy 283.9847 -136.69645) (xy 274.74926 -136.69645)
			(xy 274.74926 -138.496548) (xy 276.172676 -138.496548) (xy 276.172676 -137.632948) (xy 276.173166 -137.60298)
			(xy 276.180989 -137.543558) (xy 276.196502 -137.485665) (xy 276.219438 -137.430292) (xy 276.249405 -137.378386)
			(xy 276.285892 -137.330836) (xy 276.328272 -137.288456) (xy 276.375822 -137.251969) (xy 276.427728 -137.222002)
			(xy 276.483101 -137.199066) (xy 276.540994 -137.183553) (xy 276.600416 -137.17573) (xy 276.660352 -137.17573)
			(xy 276.719774 -137.183553) (xy 276.777667 -137.199066) (xy 276.83304 -137.222002) (xy 276.884946 -137.251969)
			(xy 276.932496 -137.288456) (xy 276.974876 -137.330836) (xy 277.011363 -137.378386) (xy 277.04133 -137.430292)
			(xy 277.064266 -137.485665) (xy 277.079779 -137.543558) (xy 277.087602 -137.60298) (xy 277.088092 -137.632948)
			(xy 277.088092 -138.496548) (xy 277.087602 -138.526516) (xy 277.082652 -138.564112) (xy 278.891236 -138.564112)
			(xy 278.895307 -138.50849) (xy 278.907433 -138.454053) (xy 278.927356 -138.401962) (xy 278.954652 -138.353327)
			(xy 278.988738 -138.309184) (xy 279.028887 -138.270475) (xy 279.074245 -138.238024) (xy 279.123845 -138.212523)
			(xy 279.176629 -138.194516) (xy 279.231472 -138.184386) (xy 279.287206 -138.182349) (xy 279.342643 -138.188449)
			(xy 279.3966 -138.202555) (xy 279.447929 -138.224367) (xy 279.495535 -138.253421) (xy 279.538403 -138.289096)
			(xy 279.57562 -138.330633) (xy 279.606393 -138.377146) (xy 279.630065 -138.427643) (xy 279.646133 -138.48105)
			(xy 279.654253 -138.536226) (xy 279.654762 -138.564112) (xy 279.654253 -138.591998) (xy 279.646133 -138.647174)
			(xy 279.630065 -138.700581) (xy 279.606393 -138.751078) (xy 279.57562 -138.797591) (xy 279.538403 -138.839128)
			(xy 279.495535 -138.874803) (xy 279.447929 -138.903857) (xy 279.3966 -138.925669) (xy 279.342643 -138.939775)
			(xy 279.287206 -138.945875) (xy 279.231472 -138.943838) (xy 279.176629 -138.933708) (xy 279.123845 -138.915701)
			(xy 279.074245 -138.8902) (xy 279.028887 -138.857749) (xy 278.988738 -138.81904) (xy 278.954652 -138.774897)
			(xy 278.927356 -138.726262) (xy 278.907433 -138.674171) (xy 278.895307 -138.619734) (xy 278.891236 -138.564112)
			(xy 277.082652 -138.564112) (xy 277.079779 -138.585938) (xy 277.064266 -138.643831) (xy 277.04133 -138.699204)
			(xy 277.011363 -138.75111) (xy 276.974876 -138.79866) (xy 276.932496 -138.84104) (xy 276.884946 -138.877527)
			(xy 276.83304 -138.907494) (xy 276.777667 -138.93043) (xy 276.719774 -138.945943) (xy 276.660352 -138.953766)
			(xy 276.600416 -138.953766) (xy 276.540994 -138.945943) (xy 276.483101 -138.93043) (xy 276.427728 -138.907494)
			(xy 276.375822 -138.877527) (xy 276.328272 -138.84104) (xy 276.285892 -138.79866) (xy 276.249405 -138.75111)
			(xy 276.219438 -138.699204) (xy 276.196502 -138.643831) (xy 276.180989 -138.585938) (xy 276.173166 -138.526516)
			(xy 276.172676 -138.496548) (xy 274.74926 -138.496548) (xy 274.74926 -140.565378) (xy 275.789644 -140.565378)
			(xy 275.790086 -140.538007) (xy 275.797908 -140.483826) (xy 275.813402 -140.431322) (xy 275.83625 -140.381576)
			(xy 275.86598 -140.335611) (xy 275.883624 -140.31468) (xy 275.883878 -140.314426) (xy 275.889469 -140.307343)
			(xy 275.895711 -140.290423) (xy 275.89607 -140.281406) (xy 275.89607 -140.21435) (xy 275.895696 -140.205335)
			(xy 275.889461 -140.188417) (xy 275.883878 -140.18133) (xy 275.883624 -140.18133) (xy 275.883624 -140.181076)
			(xy 275.866011 -140.160123) (xy 275.836294 -140.114156) (xy 275.813453 -140.064414) (xy 275.797956 -140.011918)
			(xy 275.790121 -139.957746) (xy 275.789644 -139.930378) (xy 275.790157 -139.903128) (xy 275.797915 -139.849184)
			(xy 275.813271 -139.796893) (xy 275.835911 -139.747319) (xy 275.865375 -139.701471) (xy 275.901064 -139.660282)
			(xy 275.94225 -139.624591) (xy 275.988096 -139.595124) (xy 276.037668 -139.57248) (xy 276.089959 -139.557121)
			(xy 276.143902 -139.549359) (xy 276.171152 -139.54887) (xy 276.198522 -139.549347) (xy 276.252701 -139.55716)
			(xy 276.305205 -139.572645) (xy 276.354952 -139.595485) (xy 276.400919 -139.625209) (xy 276.42185 -139.64285)
			(xy 276.422104 -139.643104) (xy 276.429185 -139.648699) (xy 276.446106 -139.65494) (xy 276.455124 -139.655296)
			(xy 276.52218 -139.655296) (xy 276.531196 -139.65493) (xy 276.548113 -139.648689) (xy 276.5552 -139.643104)
			(xy 276.5552 -139.64285) (xy 276.555454 -139.64285) (xy 276.576399 -139.625227) (xy 276.622367 -139.595511)
			(xy 276.672112 -139.572671) (xy 276.72461 -139.557176) (xy 276.778784 -139.549345) (xy 276.806152 -139.54887)
			(xy 276.833403 -139.5494) (xy 276.88735 -139.55715) (xy 276.939645 -139.572499) (xy 276.989224 -139.595134)
			(xy 277.035076 -139.624595) (xy 277.076269 -139.660282) (xy 277.111963 -139.701468) (xy 277.141433 -139.747315)
			(xy 277.164077 -139.796889) (xy 277.179435 -139.849181) (xy 277.187195 -139.903127) (xy 277.18766 -139.930378)
			(xy 277.187191 -139.957748) (xy 277.179375 -140.011928) (xy 277.163887 -140.064431) (xy 277.141046 -140.114178)
			(xy 277.132443 -140.127482) (xy 283.80512 -140.127482) (xy 283.809191 -140.07186) (xy 283.821317 -140.017423)
			(xy 283.84124 -139.965332) (xy 283.868536 -139.916697) (xy 283.902622 -139.872554) (xy 283.942771 -139.833845)
			(xy 283.988129 -139.801394) (xy 284.037729 -139.775893) (xy 284.090513 -139.757886) (xy 284.145356 -139.747756)
			(xy 284.20109 -139.745719) (xy 284.256527 -139.751819) (xy 284.310484 -139.765925) (xy 284.361813 -139.787737)
			(xy 284.409419 -139.816791) (xy 284.452287 -139.852466) (xy 284.489504 -139.894003) (xy 284.520277 -139.940516)
			(xy 284.543949 -139.991013) (xy 284.560017 -140.04442) (xy 284.568137 -140.099596) (xy 284.568646 -140.127482)
			(xy 284.568137 -140.155368) (xy 284.560017 -140.210544) (xy 284.543949 -140.263951) (xy 284.520277 -140.314448)
			(xy 284.489504 -140.360961) (xy 284.452287 -140.402498) (xy 284.409419 -140.438173) (xy 284.361813 -140.467227)
			(xy 284.310484 -140.489039) (xy 284.256527 -140.503145) (xy 284.20109 -140.509245) (xy 284.145356 -140.507208)
			(xy 284.090513 -140.497078) (xy 284.037729 -140.479071) (xy 283.988129 -140.45357) (xy 283.942771 -140.421119)
			(xy 283.902622 -140.38241) (xy 283.868536 -140.338267) (xy 283.84124 -140.289632) (xy 283.821317 -140.237541)
			(xy 283.809191 -140.183104) (xy 283.80512 -140.127482) (xy 277.132443 -140.127482) (xy 277.111321 -140.160145)
			(xy 277.09368 -140.181076) (xy 277.093426 -140.18133) (xy 277.087854 -140.188426) (xy 277.0816 -140.205336)
			(xy 277.081234 -140.21435) (xy 277.081234 -140.281406) (xy 277.081581 -140.290424) (xy 277.087834 -140.307341)
			(xy 277.093426 -140.314426) (xy 277.09368 -140.314426) (xy 277.09368 -140.31468) (xy 277.11132 -140.335611)
			(xy 277.141032 -140.381584) (xy 277.163869 -140.431332) (xy 277.179359 -140.483833) (xy 277.187187 -140.538009)
			(xy 277.18766 -140.565378) (xy 277.187224 -140.592632) (xy 277.179469 -140.646587) (xy 277.164113 -140.698888)
			(xy 277.14147 -140.748471) (xy 277.112 -140.794327) (xy 277.076303 -140.835521) (xy 277.035106 -140.871215)
			(xy 276.989249 -140.900682) (xy 276.939664 -140.923322) (xy 276.887361 -140.938674) (xy 276.833407 -140.946426)
			(xy 276.806152 -140.946886) (xy 276.778783 -140.946393) (xy 276.724605 -140.938582) (xy 276.672102 -140.9231)
			(xy 276.622354 -140.900264) (xy 276.576386 -140.870545) (xy 276.555454 -140.852906) (xy 276.5552 -140.852652)
			(xy 276.548122 -140.847054) (xy 276.531198 -140.840815) (xy 276.52218 -140.84046) (xy 276.455124 -140.84046)
			(xy 276.446107 -140.840815) (xy 276.429189 -140.847063) (xy 276.422104 -140.852652) (xy 276.422104 -140.852906)
			(xy 276.42185 -140.852906) (xy 276.400911 -140.870536) (xy 276.35494 -140.900249) (xy 276.305194 -140.923087)
			(xy 276.252695 -140.93858) (xy 276.198521 -140.946411) (xy 276.171152 -140.946886) (xy 276.143899 -140.946467)
			(xy 276.089947 -140.938703) (xy 276.03765 -140.923341) (xy 275.988071 -140.900692) (xy 275.94222 -140.871219)
			(xy 275.90103 -140.835521) (xy 275.865339 -140.794324) (xy 275.835874 -140.748467) (xy 275.813235 -140.698884)
			(xy 275.797882 -140.646584) (xy 275.790128 -140.592632) (xy 275.789644 -140.565378) (xy 274.74926 -140.565378)
			(xy 274.74926 -142.60068) (xy 283.80563 -142.60068) (xy 283.806093 -142.573275) (xy 283.813944 -142.51903)
			(xy 283.829482 -142.466469) (xy 283.852385 -142.416674) (xy 283.882183 -142.370671) (xy 283.899864 -142.349728)
			(xy 283.900118 -142.349474) (xy 283.905682 -142.342372) (xy 283.911942 -142.325467) (xy 283.91231 -142.316454)
			(xy 283.91231 -142.249144) (xy 283.91193 -142.240129) (xy 283.905698 -142.223212) (xy 283.900118 -142.216124)
			(xy 283.89961 -142.215616) (xy 283.881967 -142.194687) (xy 283.852255 -142.148714) (xy 283.82942 -142.098965)
			(xy 283.81393 -142.046464) (xy 283.806103 -141.992287) (xy 283.80563 -141.964918) (xy 283.806116 -141.937667)
			(xy 283.813872 -141.883719) (xy 283.829227 -141.831424) (xy 283.851869 -141.781847) (xy 283.881335 -141.735997)
			(xy 283.917026 -141.694806) (xy 283.958217 -141.659115) (xy 284.004067 -141.629649) (xy 284.053644 -141.607007)
			(xy 284.105939 -141.591652) (xy 284.159887 -141.583896) (xy 284.214389 -141.583896) (xy 284.268337 -141.591652)
			(xy 284.320632 -141.607007) (xy 284.370209 -141.629649) (xy 284.416059 -141.659115) (xy 284.45725 -141.694806)
			(xy 284.492941 -141.735997) (xy 284.522407 -141.781847) (xy 284.545049 -141.831424) (xy 284.560404 -141.883719)
			(xy 284.56816 -141.937667) (xy 284.568646 -141.964918) (xy 284.568187 -141.992323) (xy 284.560336 -142.046568)
			(xy 284.544798 -142.09913) (xy 284.521893 -142.148925) (xy 284.492094 -142.194927) (xy 284.474412 -142.21587)
			(xy 284.474158 -142.216124) (xy 284.46855 -142.223196) (xy 284.462317 -142.240124) (xy 284.461966 -142.249144)
			(xy 284.461966 -142.316454) (xy 284.462352 -142.325468) (xy 284.46858 -142.342385) (xy 284.474158 -142.349474)
			(xy 284.474666 -142.349982) (xy 284.492305 -142.370914) (xy 284.522018 -142.416887) (xy 284.544854 -142.466634)
			(xy 284.560345 -142.519135) (xy 284.568173 -142.573311) (xy 284.568646 -142.60068) (xy 284.56816 -142.627931)
			(xy 284.560404 -142.681879) (xy 284.545049 -142.734174) (xy 284.522407 -142.783751) (xy 284.492941 -142.829601)
			(xy 284.45725 -142.870792) (xy 284.416059 -142.906483) (xy 284.370209 -142.935949) (xy 284.320632 -142.958591)
			(xy 284.268337 -142.973946) (xy 284.214389 -142.981702) (xy 284.159887 -142.981702) (xy 284.105939 -142.973946)
			(xy 284.053644 -142.958591) (xy 284.004067 -142.935949) (xy 283.958217 -142.906483) (xy 283.917026 -142.870792)
			(xy 283.881335 -142.829601) (xy 283.851869 -142.783751) (xy 283.829227 -142.734174) (xy 283.813872 -142.681879)
			(xy 283.806116 -142.627931) (xy 283.80563 -142.60068) (xy 274.74926 -142.60068) (xy 274.74926 -145.30578)
			(xy 275.33854 -145.30578) (xy 275.338981 -145.278444) (xy 275.346762 -145.22433) (xy 275.362191 -145.171881)
			(xy 275.384951 -145.122172) (xy 275.414575 -145.076223) (xy 275.450458 -145.034975) (xy 275.491863 -144.999274)
			(xy 275.537941 -144.969851) (xy 275.587749 -144.947308) (xy 275.613876 -144.939258) (xy 275.622747 -144.936279)
			(xy 275.637723 -144.925083) (xy 275.643086 -144.917414) (xy 275.68398 -144.852136) (xy 275.687536 -144.834356)
			(xy 275.686012 -144.825212) (xy 275.686012 -144.824704) (xy 275.683526 -144.809074) (xy 275.680858 -144.777537)
			(xy 275.680678 -144.761712) (xy 275.681189 -144.734462) (xy 275.688944 -144.680516) (xy 275.704297 -144.628222)
			(xy 275.726935 -144.578646) (xy 275.756399 -144.532796) (xy 275.792088 -144.491606) (xy 275.833276 -144.455915)
			(xy 275.879123 -144.426448) (xy 275.928698 -144.403806) (xy 275.98099 -144.388449) (xy 276.034936 -144.380691)
			(xy 276.062186 -144.380204) (xy 276.074157 -144.380319) (xy 276.09805 -144.381842) (xy 276.109938 -144.383252)
			(xy 276.110192 -144.383252) (xy 276.119366 -144.383961) (xy 276.137209 -144.379527) (xy 276.14499 -144.374616)
			(xy 276.201124 -144.3355) (xy 276.20853 -144.329917) (xy 276.219078 -144.314679) (xy 276.221698 -144.305782)
			(xy 276.221698 -144.305528) (xy 276.228685 -144.277974) (xy 276.249719 -144.225167) (xy 276.278359 -144.176067)
			(xy 276.31397 -144.131763) (xy 276.355762 -144.093234) (xy 276.40281 -144.061336) (xy 276.454072 -144.036774)
			(xy 276.508411 -144.020093) (xy 276.564625 -144.011663) (xy 276.593046 -144.011142) (xy 276.617717 -144.011555)
			(xy 276.666643 -144.017956) (xy 276.714338 -144.030605) (xy 276.737318 -144.03959) (xy 276.748421 -144.043493)
			(xy 276.771863 -144.041773) (xy 276.782276 -144.036288) (xy 276.852126 -143.994632) (xy 276.861901 -143.988159)
			(xy 276.874755 -143.968589) (xy 276.876764 -143.95704) (xy 276.876764 -143.956532) (xy 276.880473 -143.928978)
			(xy 276.894734 -143.875244) (xy 276.916645 -143.824151) (xy 276.945743 -143.77678) (xy 276.981412 -143.734137)
			(xy 277.022894 -143.697125) (xy 277.069311 -143.666528) (xy 277.119679 -143.642996) (xy 277.17293 -143.627027)
			(xy 277.227935 -143.618959) (xy 277.255732 -143.618458) (xy 277.282982 -143.618948) (xy 277.336928 -143.626708)
			(xy 277.389221 -143.642065) (xy 277.438796 -143.664708) (xy 277.484645 -143.694174) (xy 277.525834 -143.729865)
			(xy 277.561525 -143.771054) (xy 277.590991 -143.816902) (xy 277.613634 -143.866477) (xy 277.628992 -143.91877)
			(xy 277.636752 -143.972716) (xy 277.63724 -143.999966) (xy 277.636763 -144.026547) (xy 277.629382 -144.079193)
			(xy 277.614757 -144.130303) (xy 277.593173 -144.178885) (xy 277.565048 -144.223997) (xy 277.530928 -144.264764)
			(xy 277.51151 -144.282922) (xy 277.504912 -144.28939) (xy 277.496452 -144.305801) (xy 277.495 -144.314926)
			(xy 277.487634 -144.381474) (xy 277.486886 -144.39065) (xy 277.491331 -144.408501) (xy 277.49627 -144.416272)
			(xy 277.512386 -144.440397) (xy 277.53792 -144.492491) (xy 277.555277 -144.547849) (xy 277.564056 -144.605196)
			(xy 277.564596 -144.634204) (xy 277.564148 -144.661457) (xy 277.556391 -144.71541) (xy 277.541033 -144.767708)
			(xy 277.51839 -144.817289) (xy 277.48892 -144.863143) (xy 277.453225 -144.904336) (xy 277.41203 -144.94003)
			(xy 277.366175 -144.969497) (xy 277.316593 -144.992139) (xy 277.264294 -145.007494) (xy 277.210342 -145.015249)
			(xy 277.183088 -145.015712) (xy 277.18258 -145.015712) (xy 277.172783 -145.015648) (xy 277.153215 -145.014631)
			(xy 277.143464 -145.01368) (xy 277.14321 -145.01368) (xy 277.13382 -145.013064) (xy 277.115682 -145.018034)
			(xy 277.107904 -145.023332) (xy 277.044912 -145.070068) (xy 277.035006 -145.08607) (xy 277.033228 -145.095722)
			(xy 277.027834 -145.121559) (xy 277.010903 -145.17155) (xy 276.987243 -145.21873) (xy 276.957306 -145.262199)
			(xy 276.921663 -145.301127) (xy 276.880995 -145.334771) (xy 276.836079 -145.362488) (xy 276.78777 -145.38375)
			(xy 276.736992 -145.39815) (xy 276.684714 -145.405415) (xy 276.658324 -145.405856) (xy 276.630773 -145.405409)
			(xy 276.576244 -145.397485) (xy 276.523422 -145.381798) (xy 276.473406 -145.358675) (xy 276.427238 -145.328597)
			(xy 276.385877 -145.29219) (xy 276.350184 -145.25021) (xy 276.320902 -145.203533) (xy 276.309328 -145.178526)
			(xy 276.305518 -145.16989) (xy 276.292056 -145.156428) (xy 276.211792 -145.121122) (xy 276.19325 -145.120106)
			(xy 276.18436 -145.1229) (xy 276.183344 -145.123408) (xy 276.168358 -145.128234) (xy 276.159493 -145.131229)
			(xy 276.144513 -145.142413) (xy 276.139148 -145.150078) (xy 276.098254 -145.215356) (xy 276.094698 -145.233136)
			(xy 276.096222 -145.24228) (xy 276.096222 -145.242788) (xy 276.098706 -145.258418) (xy 276.101375 -145.289955)
			(xy 276.101556 -145.30578) (xy 276.10107 -145.333031) (xy 276.093314 -145.386979) (xy 276.077959 -145.439274)
			(xy 276.055317 -145.488851) (xy 276.025851 -145.534701) (xy 275.99016 -145.575892) (xy 275.948969 -145.611583)
			(xy 275.903119 -145.641049) (xy 275.853542 -145.663691) (xy 275.801247 -145.679046) (xy 275.747299 -145.686802)
			(xy 275.692797 -145.686802) (xy 275.638849 -145.679046) (xy 275.586554 -145.663691) (xy 275.536977 -145.641049)
			(xy 275.491127 -145.611583) (xy 275.449936 -145.575892) (xy 275.414245 -145.534701) (xy 275.384779 -145.488851)
			(xy 275.362137 -145.439274) (xy 275.346782 -145.386979) (xy 275.339026 -145.333031) (xy 275.33854 -145.30578)
			(xy 274.74926 -145.30578) (xy 274.74926 -146.739864) (xy 281.109926 -146.739864) (xy 281.113997 -146.684242)
			(xy 281.126123 -146.629805) (xy 281.146046 -146.577714) (xy 281.173342 -146.529079) (xy 281.207428 -146.484936)
			(xy 281.247577 -146.446227) (xy 281.292935 -146.413776) (xy 281.342535 -146.388275) (xy 281.395319 -146.370268)
			(xy 281.450162 -146.360138) (xy 281.505896 -146.358101) (xy 281.561333 -146.364201) (xy 281.61529 -146.378307)
			(xy 281.666619 -146.400119) (xy 281.714225 -146.429173) (xy 281.757093 -146.464848) (xy 281.79431 -146.506385)
			(xy 281.825083 -146.552898) (xy 281.848755 -146.603395) (xy 281.864823 -146.656802) (xy 281.872943 -146.711978)
			(xy 281.873452 -146.739864) (xy 281.872943 -146.76775) (xy 281.864823 -146.822926) (xy 281.848755 -146.876333)
			(xy 281.825083 -146.92683) (xy 281.79431 -146.973343) (xy 281.757093 -147.01488) (xy 281.714225 -147.050555)
			(xy 281.666619 -147.079609) (xy 281.61529 -147.101421) (xy 281.561333 -147.115527) (xy 281.505896 -147.121627)
			(xy 281.450162 -147.11959) (xy 281.395319 -147.10946) (xy 281.342535 -147.091453) (xy 281.292935 -147.065952)
			(xy 281.247577 -147.033501) (xy 281.207428 -146.994792) (xy 281.173342 -146.950649) (xy 281.146046 -146.902014)
			(xy 281.126123 -146.849923) (xy 281.113997 -146.795486) (xy 281.109926 -146.739864) (xy 274.74926 -146.739864)
			(xy 274.74926 -150.11781) (xy 284.785562 -150.11781) (xy 284.786019 -150.090439) (xy 284.793837 -150.036259)
			(xy 284.809327 -149.983755) (xy 284.832171 -149.934009) (xy 284.861899 -149.888043) (xy 284.879542 -149.867112)
			(xy 284.879796 -149.866858) (xy 284.885364 -149.859759) (xy 284.891622 -149.842852) (xy 284.891988 -149.833838)
			(xy 284.891988 -149.766782) (xy 284.891642 -149.757764) (xy 284.885387 -149.740847) (xy 284.879796 -149.733762)
			(xy 284.879542 -149.733762) (xy 284.879542 -149.733508) (xy 284.8619 -149.712578) (xy 284.832187 -149.666606)
			(xy 284.809351 -149.616858) (xy 284.793861 -149.564356) (xy 284.786035 -149.510179) (xy 284.785562 -149.48281)
			(xy 284.786048 -149.455559) (xy 284.793804 -149.401611) (xy 284.809159 -149.349316) (xy 284.831801 -149.299739)
			(xy 284.861267 -149.253889) (xy 284.896958 -149.212698) (xy 284.938149 -149.177007) (xy 284.983999 -149.147541)
			(xy 285.033576 -149.124899) (xy 285.085871 -149.109544) (xy 285.139819 -149.101788) (xy 285.194321 -149.101788)
			(xy 285.248269 -149.109544) (xy 285.300564 -149.124899) (xy 285.350141 -149.147541) (xy 285.395991 -149.177007)
			(xy 285.437182 -149.212698) (xy 285.472873 -149.253889) (xy 285.502339 -149.299739) (xy 285.524981 -149.349316)
			(xy 285.540336 -149.401611) (xy 285.548092 -149.455559) (xy 285.548578 -149.48281) (xy 285.548123 -149.510181)
			(xy 285.540303 -149.56436) (xy 285.524812 -149.616864) (xy 285.501968 -149.666611) (xy 285.472241 -149.712577)
			(xy 285.454598 -149.733508) (xy 285.454344 -149.733762) (xy 285.448761 -149.74085) (xy 285.442513 -149.757766)
			(xy 285.442152 -149.766782) (xy 285.442152 -149.833838) (xy 285.442479 -149.842858) (xy 285.448746 -149.859775)
			(xy 285.454344 -149.866858) (xy 285.454598 -149.866858) (xy 285.454598 -149.867112) (xy 285.472209 -149.888067)
			(xy 285.501925 -149.934033) (xy 285.524767 -149.983775) (xy 285.540264 -150.036271) (xy 285.5481 -150.090442)
			(xy 285.548578 -150.11781) (xy 285.548092 -150.145061) (xy 285.540336 -150.199009) (xy 285.524981 -150.251304)
			(xy 285.502339 -150.300881) (xy 285.472873 -150.346731) (xy 285.437182 -150.387922) (xy 285.395991 -150.423613)
			(xy 285.350141 -150.453079) (xy 285.300564 -150.475721) (xy 285.248269 -150.491076) (xy 285.194321 -150.498832)
			(xy 285.139819 -150.498832) (xy 285.085871 -150.491076) (xy 285.033576 -150.475721) (xy 284.983999 -150.453079)
			(xy 284.938149 -150.423613) (xy 284.896958 -150.387922) (xy 284.861267 -150.346731) (xy 284.831801 -150.300881)
			(xy 284.809159 -150.251304) (xy 284.793804 -150.199009) (xy 284.786048 -150.145061) (xy 284.785562 -150.11781)
			(xy 274.74926 -150.11781) (xy 274.74926 -151.17064) (xy 274.749692 -151.180706) (xy 274.757423 -151.199294)
			(xy 274.764246 -151.206708) (xy 274.814538 -151.257) (xy 284.776924 -151.257) (xy 284.780995 -151.201378)
			(xy 284.793121 -151.146941) (xy 284.813044 -151.09485) (xy 284.84034 -151.046215) (xy 284.874426 -151.002072)
			(xy 284.914575 -150.963363) (xy 284.959933 -150.930912) (xy 285.009533 -150.905411) (xy 285.062317 -150.887404)
			(xy 285.11716 -150.877274) (xy 285.172894 -150.875237) (xy 285.228331 -150.881337) (xy 285.282288 -150.895443)
			(xy 285.333617 -150.917255) (xy 285.381223 -150.946309) (xy 285.424091 -150.981984) (xy 285.461308 -151.023521)
			(xy 285.492081 -151.070034) (xy 285.515753 -151.120531) (xy 285.531821 -151.173938) (xy 285.539941 -151.229114)
			(xy 285.54045 -151.257) (xy 285.539941 -151.284886) (xy 285.531821 -151.340062) (xy 285.515753 -151.393469)
			(xy 285.492081 -151.443966) (xy 285.461308 -151.490479) (xy 285.424091 -151.532016) (xy 285.381223 -151.567691)
			(xy 285.333617 -151.596745) (xy 285.282288 -151.618557) (xy 285.228331 -151.632663) (xy 285.172894 -151.638763)
			(xy 285.11716 -151.636726) (xy 285.062317 -151.626596) (xy 285.009533 -151.608589) (xy 284.959933 -151.583088)
			(xy 284.914575 -151.550637) (xy 284.874426 -151.511928) (xy 284.84034 -151.467785) (xy 284.813044 -151.41915)
			(xy 284.793121 -151.367059) (xy 284.780995 -151.312622) (xy 284.776924 -151.257) (xy 274.814538 -151.257)
			(xy 277.117556 -153.560018) (xy 284.649924 -153.560018) (xy 284.653995 -153.504396) (xy 284.666121 -153.449959)
			(xy 284.686044 -153.397868) (xy 284.71334 -153.349233) (xy 284.747426 -153.30509) (xy 284.787575 -153.266381)
			(xy 284.832933 -153.23393) (xy 284.882533 -153.208429) (xy 284.935317 -153.190422) (xy 284.99016 -153.180292)
			(xy 285.045894 -153.178255) (xy 285.101331 -153.184355) (xy 285.155288 -153.198461) (xy 285.206617 -153.220273)
			(xy 285.254223 -153.249327) (xy 285.297091 -153.285002) (xy 285.334308 -153.326539) (xy 285.365081 -153.373052)
			(xy 285.388753 -153.423549) (xy 285.404821 -153.476956) (xy 285.412941 -153.532132) (xy 285.41345 -153.560018)
			(xy 285.412941 -153.587904) (xy 285.404821 -153.64308) (xy 285.388753 -153.696487) (xy 285.365081 -153.746984)
			(xy 285.334308 -153.793497) (xy 285.297091 -153.835034) (xy 285.254223 -153.870709) (xy 285.206617 -153.899763)
			(xy 285.155288 -153.921575) (xy 285.101331 -153.935681) (xy 285.045894 -153.941781) (xy 284.99016 -153.939744)
			(xy 284.935317 -153.929614) (xy 284.882533 -153.911607) (xy 284.832933 -153.886106) (xy 284.787575 -153.853655)
			(xy 284.747426 -153.814946) (xy 284.71334 -153.770803) (xy 284.686044 -153.722168) (xy 284.666121 -153.670077)
			(xy 284.653995 -153.61564) (xy 284.649924 -153.560018) (xy 277.117556 -153.560018) (xy 277.503636 -153.946098)
			(xy 277.521669 -153.964868) (xy 277.552251 -154.006984) (xy 277.575879 -154.05336) (xy 277.591972 -154.102858)
			(xy 277.600135 -154.154262) (xy 277.600251 -154.159966) (xy 283.506924 -154.159966) (xy 283.510995 -154.104344)
			(xy 283.523121 -154.049907) (xy 283.543044 -153.997816) (xy 283.57034 -153.949181) (xy 283.604426 -153.905038)
			(xy 283.644575 -153.866329) (xy 283.689933 -153.833878) (xy 283.739533 -153.808377) (xy 283.792317 -153.79037)
			(xy 283.84716 -153.78024) (xy 283.902894 -153.778203) (xy 283.958331 -153.784303) (xy 284.012288 -153.798409)
			(xy 284.063617 -153.820221) (xy 284.111223 -153.849275) (xy 284.154091 -153.88495) (xy 284.191308 -153.926487)
			(xy 284.222081 -153.973) (xy 284.245753 -154.023497) (xy 284.261821 -154.076904) (xy 284.269941 -154.13208)
			(xy 284.27045 -154.159966) (xy 284.269941 -154.187852) (xy 284.261821 -154.243028) (xy 284.245753 -154.296435)
			(xy 284.222081 -154.346932) (xy 284.191308 -154.393445) (xy 284.154091 -154.434982) (xy 284.111223 -154.470657)
			(xy 284.063617 -154.499711) (xy 284.012288 -154.521523) (xy 283.958331 -154.535629) (xy 283.902894 -154.541729)
			(xy 283.84716 -154.539692) (xy 283.792317 -154.529562) (xy 283.739533 -154.511555) (xy 283.689933 -154.486054)
			(xy 283.644575 -154.453603) (xy 283.604426 -154.414894) (xy 283.57034 -154.370751) (xy 283.543044 -154.322116)
			(xy 283.523121 -154.270025) (xy 283.510995 -154.215588) (xy 283.506924 -154.159966) (xy 277.600251 -154.159966)
			(xy 277.600664 -154.180286) (xy 277.600664 -155.0416) (xy 280.363674 -155.0416) (xy 280.367745 -154.985978)
			(xy 280.379871 -154.931541) (xy 280.399794 -154.87945) (xy 280.42709 -154.830815) (xy 280.461176 -154.786672)
			(xy 280.501325 -154.747963) (xy 280.546683 -154.715512) (xy 280.596283 -154.690011) (xy 280.649067 -154.672004)
			(xy 280.70391 -154.661874) (xy 280.759644 -154.659837) (xy 280.815081 -154.665937) (xy 280.869038 -154.680043)
			(xy 280.920367 -154.701855) (xy 280.967973 -154.730909) (xy 281.010841 -154.766584) (xy 281.048058 -154.808121)
			(xy 281.078831 -154.854634) (xy 281.102503 -154.905131) (xy 281.118496 -154.958288) (xy 284.944056 -154.958288)
			(xy 284.948127 -154.902666) (xy 284.960253 -154.848229) (xy 284.980176 -154.796138) (xy 285.007472 -154.747503)
			(xy 285.041558 -154.70336) (xy 285.081707 -154.664651) (xy 285.127065 -154.6322) (xy 285.176665 -154.606699)
			(xy 285.229449 -154.588692) (xy 285.284292 -154.578562) (xy 285.340026 -154.576525) (xy 285.395463 -154.582625)
			(xy 285.44942 -154.596731) (xy 285.500749 -154.618543) (xy 285.548355 -154.647597) (xy 285.591223 -154.683272)
			(xy 285.62844 -154.724809) (xy 285.659213 -154.771322) (xy 285.682885 -154.821819) (xy 285.698953 -154.875226)
			(xy 285.707073 -154.930402) (xy 285.707582 -154.958288) (xy 285.707073 -154.986174) (xy 285.698953 -155.04135)
			(xy 285.682885 -155.094757) (xy 285.659213 -155.145254) (xy 285.62844 -155.191767) (xy 285.591223 -155.233304)
			(xy 285.548355 -155.268979) (xy 285.500749 -155.298033) (xy 285.44942 -155.319845) (xy 285.395463 -155.333951)
			(xy 285.340026 -155.340051) (xy 285.284292 -155.338014) (xy 285.229449 -155.327884) (xy 285.176665 -155.309877)
			(xy 285.127065 -155.284376) (xy 285.081707 -155.251925) (xy 285.041558 -155.213216) (xy 285.007472 -155.169073)
			(xy 284.980176 -155.120438) (xy 284.960253 -155.068347) (xy 284.948127 -155.01391) (xy 284.944056 -154.958288)
			(xy 281.118496 -154.958288) (xy 281.118571 -154.958538) (xy 281.126691 -155.013714) (xy 281.1272 -155.0416)
			(xy 281.126691 -155.069486) (xy 281.118571 -155.124662) (xy 281.102503 -155.178069) (xy 281.078831 -155.228566)
			(xy 281.048058 -155.275079) (xy 281.010841 -155.316616) (xy 280.967973 -155.352291) (xy 280.920367 -155.381345)
			(xy 280.869038 -155.403157) (xy 280.815081 -155.417263) (xy 280.759644 -155.423363) (xy 280.70391 -155.421326)
			(xy 280.649067 -155.411196) (xy 280.596283 -155.393189) (xy 280.546683 -155.367688) (xy 280.501325 -155.335237)
			(xy 280.461176 -155.296528) (xy 280.42709 -155.252385) (xy 280.399794 -155.20375) (xy 280.379871 -155.151659)
			(xy 280.367745 -155.097222) (xy 280.363674 -155.0416) (xy 277.600664 -155.0416) (xy 277.600664 -155.598368)
			(xy 283.568138 -155.598368) (xy 283.572209 -155.542746) (xy 283.584335 -155.488309) (xy 283.604258 -155.436218)
			(xy 283.631554 -155.387583) (xy 283.66564 -155.34344) (xy 283.705789 -155.304731) (xy 283.751147 -155.27228)
			(xy 283.800747 -155.246779) (xy 283.853531 -155.228772) (xy 283.908374 -155.218642) (xy 283.964108 -155.216605)
			(xy 284.019545 -155.222705) (xy 284.073502 -155.236811) (xy 284.124831 -155.258623) (xy 284.172437 -155.287677)
			(xy 284.215305 -155.323352) (xy 284.252522 -155.364889) (xy 284.283295 -155.411402) (xy 284.306967 -155.461899)
			(xy 284.323035 -155.515306) (xy 284.331155 -155.570482) (xy 284.331664 -155.598368) (xy 284.331155 -155.626254)
			(xy 284.323035 -155.68143) (xy 284.306967 -155.734837) (xy 284.283295 -155.785334) (xy 284.252522 -155.831847)
			(xy 284.215305 -155.873384) (xy 284.172437 -155.909059) (xy 284.124831 -155.938113) (xy 284.073502 -155.959925)
			(xy 284.019545 -155.974031) (xy 283.964108 -155.980131) (xy 283.908374 -155.978094) (xy 283.853531 -155.967964)
			(xy 283.800747 -155.949957) (xy 283.751147 -155.924456) (xy 283.705789 -155.892005) (xy 283.66564 -155.853296)
			(xy 283.631554 -155.809153) (xy 283.604258 -155.760518) (xy 283.584335 -155.708427) (xy 283.572209 -155.65399)
			(xy 283.568138 -155.598368) (xy 277.600664 -155.598368) (xy 277.600664 -156.544518) (xy 284.9278 -156.544518)
			(xy 284.931871 -156.488896) (xy 284.943997 -156.434459) (xy 284.96392 -156.382368) (xy 284.991216 -156.333733)
			(xy 285.025302 -156.28959) (xy 285.065451 -156.250881) (xy 285.110809 -156.21843) (xy 285.160409 -156.192929)
			(xy 285.213193 -156.174922) (xy 285.268036 -156.164792) (xy 285.32377 -156.162755) (xy 285.379207 -156.168855)
			(xy 285.433164 -156.182961) (xy 285.484493 -156.204773) (xy 285.532099 -156.233827) (xy 285.574967 -156.269502)
			(xy 285.612184 -156.311039) (xy 285.642957 -156.357552) (xy 285.666629 -156.408049) (xy 285.682697 -156.461456)
			(xy 285.690817 -156.516632) (xy 285.691326 -156.544518) (xy 285.690817 -156.572404) (xy 285.682697 -156.62758)
			(xy 285.666629 -156.680987) (xy 285.642957 -156.731484) (xy 285.612184 -156.777997) (xy 285.574967 -156.819534)
			(xy 285.532099 -156.855209) (xy 285.484493 -156.884263) (xy 285.433164 -156.906075) (xy 285.379207 -156.920181)
			(xy 285.32377 -156.926281) (xy 285.268036 -156.924244) (xy 285.213193 -156.914114) (xy 285.160409 -156.896107)
			(xy 285.110809 -156.870606) (xy 285.065451 -156.838155) (xy 285.025302 -156.799446) (xy 284.991216 -156.755303)
			(xy 284.96392 -156.706668) (xy 284.943997 -156.654577) (xy 284.931871 -156.60014) (xy 284.9278 -156.544518)
			(xy 277.600664 -156.544518) (xy 277.600664 -157.0736) (xy 283.496764 -157.0736) (xy 283.500835 -157.017978)
			(xy 283.512961 -156.963541) (xy 283.532884 -156.91145) (xy 283.56018 -156.862815) (xy 283.594266 -156.818672)
			(xy 283.634415 -156.779963) (xy 283.679773 -156.747512) (xy 283.729373 -156.722011) (xy 283.782157 -156.704004)
			(xy 283.837 -156.693874) (xy 283.892734 -156.691837) (xy 283.948171 -156.697937) (xy 284.002128 -156.712043)
			(xy 284.053457 -156.733855) (xy 284.101063 -156.762909) (xy 284.143931 -156.798584) (xy 284.181148 -156.840121)
			(xy 284.211921 -156.886634) (xy 284.235593 -156.937131) (xy 284.251661 -156.990538) (xy 284.259781 -157.045714)
			(xy 284.26029 -157.0736) (xy 284.259781 -157.101486) (xy 284.251661 -157.156662) (xy 284.235593 -157.210069)
			(xy 284.211921 -157.260566) (xy 284.181148 -157.307079) (xy 284.143931 -157.348616) (xy 284.101063 -157.384291)
			(xy 284.053457 -157.413345) (xy 284.002128 -157.435157) (xy 283.948171 -157.449263) (xy 283.892734 -157.455363)
			(xy 283.837 -157.453326) (xy 283.782157 -157.443196) (xy 283.729373 -157.425189) (xy 283.679773 -157.399688)
			(xy 283.634415 -157.367237) (xy 283.594266 -157.328528) (xy 283.56018 -157.284385) (xy 283.532884 -157.23575)
			(xy 283.512961 -157.183659) (xy 283.500835 -157.129222) (xy 283.496764 -157.0736) (xy 277.600664 -157.0736)
			(xy 277.600664 -160.1851) (xy 277.723867 -160.1851) (xy 277.727823 -160.093241) (xy 277.73966 -160.002062)
			(xy 277.759292 -159.912238) (xy 277.786573 -159.824435) (xy 277.821301 -159.739302) (xy 277.863219 -159.657469)
			(xy 277.912017 -159.579542) (xy 277.967332 -159.506099) (xy 278.028757 -159.437683) (xy 278.095836 -159.374801)
			(xy 278.168071 -159.317918) (xy 278.24493 -159.267455) (xy 278.325842 -159.223786) (xy 278.410208 -159.187234)
			(xy 278.497404 -159.15807) (xy 278.586785 -159.13651) (xy 278.677688 -159.122714) (xy 278.769441 -159.116782)
			(xy 278.861363 -159.118761) (xy 278.952776 -159.128634) (xy 279.043001 -159.146329) (xy 279.131372 -159.171714)
			(xy 279.217232 -159.204602) (xy 279.299948 -159.24475) (xy 279.378906 -159.291859) (xy 279.453523 -159.345582)
			(xy 279.523244 -159.40552) (xy 279.587555 -159.47123) (xy 279.64598 -159.542226) (xy 279.698085 -159.61798)
			(xy 279.743484 -159.697934) (xy 279.781843 -159.781494) (xy 279.812876 -159.868043) (xy 279.836354 -159.956939)
			(xy 279.852104 -160.047524) (xy 279.860008 -160.139128) (xy 279.860502 -160.1851) (xy 279.860008 -160.231072)
			(xy 279.852104 -160.322676) (xy 279.836354 -160.413261) (xy 279.812876 -160.502157) (xy 279.781843 -160.588706)
			(xy 279.743484 -160.672266) (xy 279.698085 -160.75222) (xy 279.64598 -160.827974) (xy 279.587555 -160.89897)
			(xy 279.523244 -160.96468) (xy 279.453523 -161.024618) (xy 279.378906 -161.078341) (xy 279.299948 -161.12545)
			(xy 279.217232 -161.165598) (xy 279.131372 -161.198486) (xy 279.043001 -161.223871) (xy 278.952776 -161.241566)
			(xy 278.861363 -161.251439) (xy 278.769441 -161.253418) (xy 278.677688 -161.247486) (xy 278.586785 -161.23369)
			(xy 278.497404 -161.21213) (xy 278.410208 -161.182966) (xy 278.325842 -161.146414) (xy 278.24493 -161.102745)
			(xy 278.168071 -161.052282) (xy 278.095836 -160.995399) (xy 278.028757 -160.932517) (xy 277.967332 -160.864101)
			(xy 277.912017 -160.790658) (xy 277.863219 -160.712731) (xy 277.821301 -160.630898) (xy 277.786573 -160.545765)
			(xy 277.759292 -160.457962) (xy 277.73966 -160.368138) (xy 277.727823 -160.276959) (xy 277.723867 -160.1851)
			(xy 277.600664 -160.1851) (xy 277.600664 -164.198046) (xy 282.909262 -164.198046) (xy 282.913333 -164.142424)
			(xy 282.925459 -164.087987) (xy 282.945382 -164.035896) (xy 282.972678 -163.987261) (xy 283.006764 -163.943118)
			(xy 283.046913 -163.904409) (xy 283.092271 -163.871958) (xy 283.141871 -163.846457) (xy 283.194655 -163.82845)
			(xy 283.249498 -163.81832) (xy 283.305232 -163.816283) (xy 283.360669 -163.822383) (xy 283.414626 -163.836489)
			(xy 283.465955 -163.858301) (xy 283.513561 -163.887355) (xy 283.556429 -163.92303) (xy 283.593646 -163.964567)
			(xy 283.624419 -164.01108) (xy 283.648091 -164.061577) (xy 283.664159 -164.114984) (xy 283.672279 -164.17016)
			(xy 283.672788 -164.198046) (xy 283.672279 -164.225932) (xy 283.664159 -164.281108) (xy 283.648091 -164.334515)
			(xy 283.624419 -164.385012) (xy 283.593646 -164.431525) (xy 283.556429 -164.473062) (xy 283.513561 -164.508737)
			(xy 283.465955 -164.537791) (xy 283.414626 -164.559603) (xy 283.360669 -164.573709) (xy 283.305232 -164.579809)
			(xy 283.249498 -164.577772) (xy 283.194655 -164.567642) (xy 283.141871 -164.549635) (xy 283.092271 -164.524134)
			(xy 283.046913 -164.491683) (xy 283.006764 -164.452974) (xy 282.972678 -164.408831) (xy 282.945382 -164.360196)
			(xy 282.925459 -164.308105) (xy 282.913333 -164.253668) (xy 282.909262 -164.198046) (xy 277.600664 -164.198046)
			(xy 277.600664 -165.130226) (xy 282.866336 -165.130226) (xy 282.870407 -165.074604) (xy 282.882533 -165.020167)
			(xy 282.902456 -164.968076) (xy 282.929752 -164.919441) (xy 282.963838 -164.875298) (xy 283.003987 -164.836589)
			(xy 283.049345 -164.804138) (xy 283.098945 -164.778637) (xy 283.151729 -164.76063) (xy 283.206572 -164.7505)
			(xy 283.262306 -164.748463) (xy 283.317743 -164.754563) (xy 283.3717 -164.768669) (xy 283.423029 -164.790481)
			(xy 283.470635 -164.819535) (xy 283.513503 -164.85521) (xy 283.55072 -164.896747) (xy 283.581493 -164.94326)
			(xy 283.605165 -164.993757) (xy 283.621233 -165.047164) (xy 283.629353 -165.10234) (xy 283.629862 -165.130226)
			(xy 283.629353 -165.158112) (xy 283.621233 -165.213288) (xy 283.605165 -165.266695) (xy 283.581493 -165.317192)
			(xy 283.55072 -165.363705) (xy 283.513503 -165.405242) (xy 283.470635 -165.440917) (xy 283.423029 -165.469971)
			(xy 283.3717 -165.491783) (xy 283.317743 -165.505889) (xy 283.262306 -165.511989) (xy 283.206572 -165.509952)
			(xy 283.151729 -165.499822) (xy 283.098945 -165.481815) (xy 283.049345 -165.456314) (xy 283.003987 -165.423863)
			(xy 282.963838 -165.385154) (xy 282.929752 -165.341011) (xy 282.902456 -165.292376) (xy 282.882533 -165.240285)
			(xy 282.870407 -165.185848) (xy 282.866336 -165.130226) (xy 277.600664 -165.130226) (xy 277.600664 -167.145716)
			(xy 277.600753 -167.150736) (xy 277.602665 -167.160591) (xy 277.604474 -167.165274) (xy 278.114894 -168.397174)
			(xy 282.841698 -168.397174) (xy 282.845769 -168.341552) (xy 282.857895 -168.287115) (xy 282.877818 -168.235024)
			(xy 282.905114 -168.186389) (xy 282.9392 -168.142246) (xy 282.979349 -168.103537) (xy 283.024707 -168.071086)
			(xy 283.074307 -168.045585) (xy 283.127091 -168.027578) (xy 283.181934 -168.017448) (xy 283.237668 -168.015411)
			(xy 283.293105 -168.021511) (xy 283.347062 -168.035617) (xy 283.398391 -168.057429) (xy 283.445997 -168.086483)
			(xy 283.488865 -168.122158) (xy 283.526082 -168.163695) (xy 283.556855 -168.210208) (xy 283.580527 -168.260705)
			(xy 283.596595 -168.314112) (xy 283.604715 -168.369288) (xy 283.605224 -168.397174) (xy 283.604715 -168.42506)
			(xy 283.596595 -168.480236) (xy 283.580527 -168.533643) (xy 283.556855 -168.58414) (xy 283.526082 -168.630653)
			(xy 283.488865 -168.67219) (xy 283.445997 -168.707865) (xy 283.398391 -168.736919) (xy 283.347062 -168.758731)
			(xy 283.293105 -168.772837) (xy 283.237668 -168.778937) (xy 283.181934 -168.7769) (xy 283.127091 -168.76677)
			(xy 283.074307 -168.748763) (xy 283.024707 -168.723262) (xy 282.979349 -168.690811) (xy 282.9392 -168.652102)
			(xy 282.905114 -168.607959) (xy 282.877818 -168.559324) (xy 282.857895 -168.507233) (xy 282.845769 -168.452796)
			(xy 282.841698 -168.397174) (xy 278.114894 -168.397174) (xy 278.659202 -169.710862) (xy 281.061412 -169.710862)
			(xy 281.065483 -169.65524) (xy 281.077609 -169.600803) (xy 281.097532 -169.548712) (xy 281.124828 -169.500077)
			(xy 281.158914 -169.455934) (xy 281.199063 -169.417225) (xy 281.244421 -169.384774) (xy 281.294021 -169.359273)
			(xy 281.346805 -169.341266) (xy 281.401648 -169.331136) (xy 281.457382 -169.329099) (xy 281.512819 -169.335199)
			(xy 281.566776 -169.349305) (xy 281.618105 -169.371117) (xy 281.665711 -169.400171) (xy 281.708579 -169.435846)
			(xy 281.745796 -169.477383) (xy 281.776569 -169.523896) (xy 281.800241 -169.574393) (xy 281.816309 -169.6278)
			(xy 281.824429 -169.682976) (xy 281.824938 -169.710862) (xy 281.824429 -169.738748) (xy 281.816309 -169.793924)
			(xy 281.800241 -169.847331) (xy 281.776569 -169.897828) (xy 281.745796 -169.944341) (xy 281.708579 -169.985878)
			(xy 281.665711 -170.021553) (xy 281.618105 -170.050607) (xy 281.566776 -170.072419) (xy 281.512819 -170.086525)
			(xy 281.457382 -170.092625) (xy 281.401648 -170.090588) (xy 281.346805 -170.080458) (xy 281.294021 -170.062451)
			(xy 281.244421 -170.03695) (xy 281.199063 -170.004499) (xy 281.158914 -169.96579) (xy 281.124828 -169.921647)
			(xy 281.097532 -169.873012) (xy 281.077609 -169.820921) (xy 281.065483 -169.766484) (xy 281.061412 -169.710862)
			(xy 278.659202 -169.710862) (xy 278.688038 -169.780458) (xy 278.690046 -169.785021) (xy 278.695545 -169.793335)
			(xy 278.69896 -169.796968) (xy 282.47594 -173.574202) (xy 282.483341 -173.581042) (xy 282.501939 -173.588761)
			(xy 282.512008 -173.589188) (xy 283.580078 -173.589188) (xy 283.606101 -173.589717) (xy 283.657504 -173.597887)
			(xy 283.707 -173.613982) (xy 283.753376 -173.637608) (xy 283.795495 -173.668184) (xy 283.814266 -173.686216)
			(xy 289.288474 -179.160424) (xy 289.295877 -179.167092) (xy 289.314285 -179.174664) (xy 289.334189 -179.174649)
			(xy 289.343592 -179.171346) (xy 289.35807 -179.165504) (xy 289.375088 -179.13985) (xy 289.375088 -169.12209)
			(xy 289.374663 -169.112021) (xy 289.366944 -169.09342) (xy 289.360102 -169.086022) (xy 286.420814 -166.146988)
			(xy 286.402699 -166.128209) (xy 286.372009 -166.086013) (xy 286.348304 -166.039532) (xy 286.332168 -165.989913)
			(xy 286.324 -165.93838) (xy 286.323532 -165.912292) (xy 286.323532 -147.735036) (xy 286.323029 -147.724984)
			(xy 286.315313 -147.706419) (xy 286.308546 -147.698968) (xy 285.75254 -147.142962) (xy 285.745141 -147.136118)
			(xy 285.726542 -147.128396) (xy 285.716472 -147.127976) (xy 283.326332 -147.127976) (xy 283.320465 -147.128129)
			(xy 283.309046 -147.13083) (xy 283.303726 -147.13331) (xy 283.303218 -147.133564) (xy 283.275691 -147.147401)
			(xy 283.217277 -147.166984) (xy 283.156476 -147.176918) (xy 283.125672 -147.177506) (xy 283.098422 -147.177018)
			(xy 283.044478 -147.169259) (xy 282.992187 -147.153901) (xy 282.942613 -147.131259) (xy 282.896767 -147.101792)
			(xy 282.85558 -147.0661) (xy 282.819892 -147.024911) (xy 282.790428 -146.979062) (xy 282.767789 -146.929487)
			(xy 282.752435 -146.877195) (xy 282.74468 -146.82325) (xy 282.74468 -146.76875) (xy 282.752435 -146.714805)
			(xy 282.767789 -146.662513) (xy 282.790428 -146.612938) (xy 282.819892 -146.567089) (xy 282.85558 -146.5259)
			(xy 282.896767 -146.490208) (xy 282.942613 -146.460741) (xy 282.992187 -146.438099) (xy 283.044478 -146.422741)
			(xy 283.098422 -146.414982) (xy 283.125672 -146.41449) (xy 283.156376 -146.415127) (xy 283.216987 -146.425004)
			(xy 283.275233 -146.44446) (xy 283.30271 -146.458178) (xy 283.303726 -146.458686) (xy 283.30906 -146.46148)
			(xy 283.320236 -146.46402) (xy 285.874968 -146.46402) (xy 285.901056 -146.464504) (xy 285.952591 -146.472666)
			(xy 286.002213 -146.488793) (xy 286.048698 -146.512489) (xy 286.090902 -146.543169) (xy 286.109664 -146.561302)
			(xy 286.890206 -147.341844) (xy 286.908318 -147.360625) (xy 286.939003 -147.402822) (xy 286.962702 -147.449303)
			(xy 286.978831 -147.498921) (xy 286.986994 -147.550453) (xy 286.987488 -147.57654) (xy 286.987488 -165.753796)
			(xy 286.98791 -165.763867) (xy 286.995622 -165.782474) (xy 287.002474 -165.789864) (xy 289.941508 -168.728898)
			(xy 289.959538 -168.74767) (xy 289.990113 -168.789788) (xy 290.013735 -168.836165) (xy 290.029825 -168.885661)
			(xy 290.037986 -168.937063) (xy 290.038536 -168.963086) (xy 290.038536 -172.329348) (xy 294.047924 -172.329348)
			(xy 294.051995 -172.273726) (xy 294.064121 -172.219289) (xy 294.084044 -172.167198) (xy 294.11134 -172.118563)
			(xy 294.145426 -172.07442) (xy 294.185575 -172.035711) (xy 294.230933 -172.00326) (xy 294.280533 -171.977759)
			(xy 294.333317 -171.959752) (xy 294.38816 -171.949622) (xy 294.443894 -171.947585) (xy 294.499331 -171.953685)
			(xy 294.553288 -171.967791) (xy 294.604617 -171.989603) (xy 294.652223 -172.018657) (xy 294.695091 -172.054332)
			(xy 294.732308 -172.095869) (xy 294.763081 -172.142382) (xy 294.786753 -172.192879) (xy 294.802821 -172.246286)
			(xy 294.810941 -172.301462) (xy 294.81145 -172.329348) (xy 294.811186 -172.343826) (xy 294.985184 -172.343826)
			(xy 294.989255 -172.288204) (xy 295.001381 -172.233767) (xy 295.021304 -172.181676) (xy 295.0486 -172.133041)
			(xy 295.082686 -172.088898) (xy 295.122835 -172.050189) (xy 295.168193 -172.017738) (xy 295.217793 -171.992237)
			(xy 295.270577 -171.97423) (xy 295.32542 -171.9641) (xy 295.381154 -171.962063) (xy 295.436591 -171.968163)
			(xy 295.490548 -171.982269) (xy 295.541877 -172.004081) (xy 295.589483 -172.033135) (xy 295.632351 -172.06881)
			(xy 295.669568 -172.110347) (xy 295.700341 -172.15686) (xy 295.706662 -172.170344) (xy 296.916092 -172.170344)
			(xy 296.920163 -172.114722) (xy 296.932289 -172.060285) (xy 296.952212 -172.008194) (xy 296.979508 -171.959559)
			(xy 297.013594 -171.915416) (xy 297.053743 -171.876707) (xy 297.099101 -171.844256) (xy 297.148701 -171.818755)
			(xy 297.201485 -171.800748) (xy 297.256328 -171.790618) (xy 297.312062 -171.788581) (xy 297.367499 -171.794681)
			(xy 297.421456 -171.808787) (xy 297.472785 -171.830599) (xy 297.520391 -171.859653) (xy 297.563259 -171.895328)
			(xy 297.600476 -171.936865) (xy 297.631249 -171.983378) (xy 297.654921 -172.033875) (xy 297.670989 -172.087282)
			(xy 297.679109 -172.142458) (xy 297.679618 -172.170344) (xy 297.679109 -172.19823) (xy 297.670989 -172.253406)
			(xy 297.654921 -172.306813) (xy 297.631249 -172.35731) (xy 297.600476 -172.403823) (xy 297.563259 -172.44536)
			(xy 297.520391 -172.481035) (xy 297.472785 -172.510089) (xy 297.421456 -172.531901) (xy 297.367499 -172.546007)
			(xy 297.312062 -172.552107) (xy 297.256328 -172.55007) (xy 297.201485 -172.53994) (xy 297.148701 -172.521933)
			(xy 297.099101 -172.496432) (xy 297.053743 -172.463981) (xy 297.013594 -172.425272) (xy 296.979508 -172.381129)
			(xy 296.952212 -172.332494) (xy 296.932289 -172.280403) (xy 296.920163 -172.225966) (xy 296.916092 -172.170344)
			(xy 295.706662 -172.170344) (xy 295.724013 -172.207357) (xy 295.740081 -172.260764) (xy 295.748201 -172.31594)
			(xy 295.74871 -172.343826) (xy 295.748201 -172.371712) (xy 295.740081 -172.426888) (xy 295.724013 -172.480295)
			(xy 295.700341 -172.530792) (xy 295.669568 -172.577305) (xy 295.632351 -172.618842) (xy 295.589483 -172.654517)
			(xy 295.541877 -172.683571) (xy 295.490548 -172.705383) (xy 295.436591 -172.719489) (xy 295.381154 -172.725589)
			(xy 295.32542 -172.723552) (xy 295.270577 -172.713422) (xy 295.217793 -172.695415) (xy 295.168193 -172.669914)
			(xy 295.122835 -172.637463) (xy 295.082686 -172.598754) (xy 295.0486 -172.554611) (xy 295.021304 -172.505976)
			(xy 295.001381 -172.453885) (xy 294.989255 -172.399448) (xy 294.985184 -172.343826) (xy 294.811186 -172.343826)
			(xy 294.810941 -172.357234) (xy 294.802821 -172.41241) (xy 294.786753 -172.465817) (xy 294.763081 -172.516314)
			(xy 294.732308 -172.562827) (xy 294.695091 -172.604364) (xy 294.652223 -172.640039) (xy 294.604617 -172.669093)
			(xy 294.553288 -172.690905) (xy 294.499331 -172.705011) (xy 294.443894 -172.711111) (xy 294.38816 -172.709074)
			(xy 294.333317 -172.698944) (xy 294.280533 -172.680937) (xy 294.230933 -172.655436) (xy 294.185575 -172.622985)
			(xy 294.145426 -172.584276) (xy 294.11134 -172.540133) (xy 294.084044 -172.491498) (xy 294.064121 -172.439407)
			(xy 294.051995 -172.38497) (xy 294.047924 -172.329348) (xy 290.038536 -172.329348) (xy 290.038536 -176.525682)
			(xy 296.609006 -176.525682) (xy 296.613077 -176.47006) (xy 296.625203 -176.415623) (xy 296.645126 -176.363532)
			(xy 296.672422 -176.314897) (xy 296.706508 -176.270754) (xy 296.746657 -176.232045) (xy 296.792015 -176.199594)
			(xy 296.841615 -176.174093) (xy 296.894399 -176.156086) (xy 296.949242 -176.145956) (xy 297.004976 -176.143919)
			(xy 297.060413 -176.150019) (xy 297.11437 -176.164125) (xy 297.165699 -176.185937) (xy 297.213305 -176.214991)
			(xy 297.256173 -176.250666) (xy 297.29339 -176.292203) (xy 297.324163 -176.338716) (xy 297.347835 -176.389213)
			(xy 297.363903 -176.44262) (xy 297.372023 -176.497796) (xy 297.372532 -176.525682) (xy 297.372023 -176.553568)
			(xy 297.363903 -176.608744) (xy 297.347835 -176.662151) (xy 297.324163 -176.712648) (xy 297.29339 -176.759161)
			(xy 297.256173 -176.800698) (xy 297.213305 -176.836373) (xy 297.165699 -176.865427) (xy 297.11437 -176.887239)
			(xy 297.060413 -176.901345) (xy 297.004976 -176.907445) (xy 296.949242 -176.905408) (xy 296.894399 -176.895278)
			(xy 296.841615 -176.877271) (xy 296.792015 -176.85177) (xy 296.746657 -176.819319) (xy 296.706508 -176.78061)
			(xy 296.672422 -176.736467) (xy 296.645126 -176.687832) (xy 296.625203 -176.635741) (xy 296.613077 -176.581304)
			(xy 296.609006 -176.525682) (xy 290.038536 -176.525682) (xy 290.038536 -177.697949) (xy 293.026092 -177.697949)
			(xy 293.026092 -177.643451) (xy 293.033848 -177.589506) (xy 293.049202 -177.537215) (xy 293.071841 -177.48764)
			(xy 293.101305 -177.441793) (xy 293.136993 -177.400604) (xy 293.17818 -177.364914) (xy 293.224026 -177.335449)
			(xy 293.2736 -177.312807) (xy 293.325891 -177.297451) (xy 293.379835 -177.289693) (xy 293.407084 -177.289206)
			(xy 293.434454 -177.28968) (xy 293.488633 -177.297496) (xy 293.541136 -177.312983) (xy 293.590883 -177.335823)
			(xy 293.63685 -177.365546) (xy 293.657782 -177.383186) (xy 293.658036 -177.38344) (xy 293.665133 -177.389011)
			(xy 293.682042 -177.395266) (xy 293.691056 -177.395632) (xy 293.758112 -177.395632) (xy 293.767129 -177.395274)
			(xy 293.784045 -177.389026) (xy 293.791132 -177.38344) (xy 293.791132 -177.383186) (xy 293.791386 -177.383186)
			(xy 293.812319 -177.365545) (xy 293.858287 -177.335821) (xy 293.908033 -177.312975) (xy 293.960535 -177.297479)
			(xy 294.014713 -177.28965) (xy 294.069455 -177.28965) (xy 294.123633 -177.297479) (xy 294.176135 -177.312975)
			(xy 294.225881 -177.335821) (xy 294.271849 -177.365545) (xy 294.292782 -177.383186) (xy 294.293036 -177.38344)
			(xy 294.300133 -177.389011) (xy 294.317042 -177.395266) (xy 294.326056 -177.395632) (xy 294.393112 -177.395632)
			(xy 294.402129 -177.395274) (xy 294.419045 -177.389026) (xy 294.426132 -177.38344) (xy 294.426132 -177.383186)
			(xy 294.426386 -177.383186) (xy 294.447319 -177.365545) (xy 294.493287 -177.335821) (xy 294.543033 -177.312975)
			(xy 294.595535 -177.297479) (xy 294.649713 -177.28965) (xy 294.704455 -177.28965) (xy 294.758633 -177.297479)
			(xy 294.811135 -177.312975) (xy 294.860881 -177.335821) (xy 294.906849 -177.365545) (xy 294.927782 -177.383186)
			(xy 294.928036 -177.38344) (xy 294.935133 -177.389011) (xy 294.952042 -177.395266) (xy 294.961056 -177.395632)
			(xy 295.028112 -177.395632) (xy 295.037129 -177.395274) (xy 295.054045 -177.389026) (xy 295.061132 -177.38344)
			(xy 295.061132 -177.383186) (xy 295.061386 -177.383186) (xy 295.082311 -177.365538) (xy 295.128286 -177.335828)
			(xy 295.178035 -177.312994) (xy 295.230537 -177.297505) (xy 295.284714 -177.289679) (xy 295.312084 -177.289206)
			(xy 295.339339 -177.28964) (xy 295.393293 -177.297395) (xy 295.445595 -177.31275) (xy 295.495179 -177.335393)
			(xy 295.541036 -177.364862) (xy 295.582232 -177.400557) (xy 295.617929 -177.441751) (xy 295.647399 -177.487607)
			(xy 295.670044 -177.53719) (xy 295.685401 -177.589491) (xy 295.693159 -177.643445) (xy 295.693159 -177.697955)
			(xy 295.685401 -177.751909) (xy 295.670044 -177.80421) (xy 295.647399 -177.853793) (xy 295.617929 -177.899649)
			(xy 295.582232 -177.940843) (xy 295.541036 -177.976538) (xy 295.495179 -178.006007) (xy 295.445595 -178.02865)
			(xy 295.393293 -178.044005) (xy 295.339339 -178.05176) (xy 295.312084 -178.052222) (xy 295.284713 -178.051784)
			(xy 295.230531 -178.043963) (xy 295.178027 -178.028468) (xy 295.128281 -178.005619) (xy 295.082316 -177.975887)
			(xy 295.061386 -177.958242) (xy 295.061132 -177.957988) (xy 295.054041 -177.952407) (xy 295.037128 -177.946157)
			(xy 295.028112 -177.945796) (xy 294.961056 -177.945796) (xy 294.952042 -177.946181) (xy 294.935125 -177.952409)
			(xy 294.928036 -177.957988) (xy 294.928036 -177.958242) (xy 294.927782 -177.958242) (xy 294.906849 -177.975883)
			(xy 294.860881 -178.005607) (xy 294.811135 -178.028453) (xy 294.758633 -178.043949) (xy 294.704455 -178.051778)
			(xy 294.649713 -178.051778) (xy 294.595535 -178.043949) (xy 294.543033 -178.028453) (xy 294.493287 -178.005607)
			(xy 294.447319 -177.975883) (xy 294.426386 -177.958242) (xy 294.426132 -177.957988) (xy 294.419041 -177.952407)
			(xy 294.402128 -177.946157) (xy 294.393112 -177.945796) (xy 294.326056 -177.945796) (xy 294.317042 -177.946181)
			(xy 294.300125 -177.952409) (xy 294.293036 -177.957988) (xy 294.293036 -177.958242) (xy 294.292782 -177.958242)
			(xy 294.271849 -177.975883) (xy 294.225881 -178.005607) (xy 294.176135 -178.028453) (xy 294.123633 -178.043949)
			(xy 294.069455 -178.051778) (xy 294.014713 -178.051778) (xy 293.960535 -178.043949) (xy 293.908033 -178.028453)
			(xy 293.858287 -178.005607) (xy 293.812319 -177.975883) (xy 293.791386 -177.958242) (xy 293.791132 -177.957988)
			(xy 293.784041 -177.952407) (xy 293.767128 -177.946157) (xy 293.758112 -177.945796) (xy 293.691056 -177.945796)
			(xy 293.682042 -177.946181) (xy 293.665125 -177.952409) (xy 293.658036 -177.957988) (xy 293.658036 -177.958242)
			(xy 293.657782 -177.958242) (xy 293.636836 -177.975863) (xy 293.590866 -178.005576) (xy 293.541122 -178.028415)
			(xy 293.488625 -178.043911) (xy 293.434452 -178.051745) (xy 293.407084 -178.052222) (xy 293.379835 -178.051707)
			(xy 293.325891 -178.043949) (xy 293.2736 -178.028593) (xy 293.224026 -178.005951) (xy 293.17818 -177.976486)
			(xy 293.136993 -177.940796) (xy 293.101305 -177.899607) (xy 293.071841 -177.85376) (xy 293.049202 -177.804185)
			(xy 293.033848 -177.751894) (xy 293.026092 -177.697949) (xy 290.038536 -177.697949) (xy 290.038536 -179.278534)
			(xy 290.038966 -179.288601) (xy 290.046693 -179.307193) (xy 290.053522 -179.314602) (xy 291.929058 -181.190138)
			(xy 295.216578 -181.190138) (xy 295.220649 -181.134516) (xy 295.232775 -181.080079) (xy 295.252698 -181.027988)
			(xy 295.279994 -180.979353) (xy 295.31408 -180.93521) (xy 295.354229 -180.896501) (xy 295.399587 -180.86405)
			(xy 295.449187 -180.838549) (xy 295.501971 -180.820542) (xy 295.556814 -180.810412) (xy 295.612548 -180.808375)
			(xy 295.667985 -180.814475) (xy 295.721942 -180.828581) (xy 295.773271 -180.850393) (xy 295.820877 -180.879447)
			(xy 295.863745 -180.915122) (xy 295.900962 -180.956659) (xy 295.931735 -181.003172) (xy 295.955407 -181.053669)
			(xy 295.971475 -181.107076) (xy 295.979595 -181.162252) (xy 295.980104 -181.190138) (xy 295.979595 -181.218024)
			(xy 295.971475 -181.2732) (xy 295.955407 -181.326607) (xy 295.931735 -181.377104) (xy 295.900962 -181.423617)
			(xy 295.863745 -181.465154) (xy 295.820877 -181.500829) (xy 295.773271 -181.529883) (xy 295.721942 -181.551695)
			(xy 295.667985 -181.565801) (xy 295.612548 -181.571901) (xy 295.556814 -181.569864) (xy 295.501971 -181.559734)
			(xy 295.449187 -181.541727) (xy 295.399587 -181.516226) (xy 295.354229 -181.483775) (xy 295.31408 -181.445066)
			(xy 295.279994 -181.400923) (xy 295.252698 -181.352288) (xy 295.232775 -181.300197) (xy 295.220649 -181.24576)
			(xy 295.216578 -181.190138) (xy 291.929058 -181.190138) (xy 293.230046 -182.491126) (xy 295.811192 -182.491126)
			(xy 295.815263 -182.435504) (xy 295.827389 -182.381067) (xy 295.847312 -182.328976) (xy 295.874608 -182.280341)
			(xy 295.908694 -182.236198) (xy 295.948843 -182.197489) (xy 295.994201 -182.165038) (xy 296.043801 -182.139537)
			(xy 296.096585 -182.12153) (xy 296.151428 -182.1114) (xy 296.207162 -182.109363) (xy 296.262599 -182.115463)
			(xy 296.316556 -182.129569) (xy 296.367885 -182.151381) (xy 296.415491 -182.180435) (xy 296.458359 -182.21611)
			(xy 296.495576 -182.257647) (xy 296.526349 -182.30416) (xy 296.550021 -182.354657) (xy 296.566089 -182.408064)
			(xy 296.574209 -182.46324) (xy 296.574718 -182.491126) (xy 296.574209 -182.519012) (xy 296.566089 -182.574188)
			(xy 296.550021 -182.627595) (xy 296.526349 -182.678092) (xy 296.495576 -182.724605) (xy 296.458359 -182.766142)
			(xy 296.415491 -182.801817) (xy 296.367885 -182.830871) (xy 296.316556 -182.852683) (xy 296.262599 -182.866789)
			(xy 296.207162 -182.872889) (xy 296.151428 -182.870852) (xy 296.096585 -182.860722) (xy 296.043801 -182.842715)
			(xy 295.994201 -182.817214) (xy 295.948843 -182.784763) (xy 295.908694 -182.746054) (xy 295.874608 -182.701911)
			(xy 295.847312 -182.653276) (xy 295.827389 -182.601185) (xy 295.815263 -182.546748) (xy 295.811192 -182.491126)
			(xy 293.230046 -182.491126) (xy 295.982898 -185.243978) (xy 295.990295 -185.250827) (xy 296.008894 -185.258566)
			(xy 296.018966 -185.258964) (xy 296.862754 -185.258964) (xy 296.888777 -185.259492) (xy 296.94018 -185.267659)
			(xy 296.989677 -185.283754) (xy 297.036052 -185.307382) (xy 297.078169 -185.337962) (xy 297.096942 -185.355992)
			(xy 297.763946 -186.022996) (xy 297.768298 -186.027166) (xy 297.778573 -186.033462) (xy 297.784266 -186.035442)
			(xy 297.78452 -186.035442) (xy 297.810076 -186.04388) (xy 297.858704 -186.066937) (xy 297.90361 -186.096597)
			(xy 297.943904 -186.132272) (xy 297.978785 -186.173255) (xy 298.007563 -186.218732) (xy 298.029666 -186.267801)
			(xy 298.044655 -186.319488) (xy 298.052233 -186.37277) (xy 298.052744 -186.399678) (xy 298.05226 -186.426931)
			(xy 298.044506 -186.480883) (xy 298.029153 -186.533183) (xy 298.006514 -186.582765) (xy 297.977049 -186.628621)
			(xy 297.941358 -186.669817) (xy 297.900167 -186.705514) (xy 297.854316 -186.734986) (xy 297.804737 -186.757633)
			(xy 297.75244 -186.772994) (xy 297.698489 -186.780756) (xy 297.671236 -186.781186) (xy 297.644333 -186.780728)
			(xy 297.591059 -186.773174) (xy 297.539375 -186.758212) (xy 297.490305 -186.736137) (xy 297.444823 -186.707388)
			(xy 297.40383 -186.672535) (xy 297.36814 -186.632269) (xy 297.33846 -186.587389) (xy 297.31538 -186.538784)
			(xy 297.307 -186.513216) (xy 297.307 -186.512708) (xy 297.304949 -186.50705) (xy 297.298653 -186.496796)
			(xy 297.294554 -186.492388) (xy 296.739818 -185.937398) (xy 296.732415 -185.930565) (xy 296.713817 -185.922861)
			(xy 296.70375 -185.922412) (xy 296.173144 -185.922412) (xy 296.163094 -185.922829) (xy 296.144527 -185.930527)
			(xy 296.130337 -185.944762) (xy 296.126154 -185.953908) (xy 296.120058 -185.968132) (xy 296.126154 -185.998104)
			(xy 299.878496 -189.750446) (xy 299.896529 -189.769217) (xy 299.927112 -189.811333) (xy 299.950743 -189.857709)
			(xy 299.96684 -189.907206) (xy 299.97501 -189.95861) (xy 299.975524 -189.984634) (xy 299.975524 -204.644752)
			(xy 299.975153 -204.666391) (xy 299.969489 -204.709297) (xy 299.958304 -204.751105) (xy 299.950378 -204.771244)
			(xy 298.099734 -209.23885) (xy 298.09793 -209.243536) (xy 298.096001 -209.253388) (xy 298.095924 -209.258408)
			(xy 298.095924 -214.438992) (xy 300.739046 -214.438992) (xy 300.743117 -214.38337) (xy 300.755243 -214.328933)
			(xy 300.775166 -214.276842) (xy 300.802462 -214.228207) (xy 300.836548 -214.184064) (xy 300.876697 -214.145355)
			(xy 300.922055 -214.112904) (xy 300.971655 -214.087403) (xy 301.024439 -214.069396) (xy 301.079282 -214.059266)
			(xy 301.135016 -214.057229) (xy 301.190453 -214.063329) (xy 301.24441 -214.077435) (xy 301.295739 -214.099247)
			(xy 301.343345 -214.128301) (xy 301.386213 -214.163976) (xy 301.42343 -214.205513) (xy 301.454203 -214.252026)
			(xy 301.477875 -214.302523) (xy 301.493943 -214.35593) (xy 301.502063 -214.411106) (xy 301.502572 -214.438992)
			(xy 301.502063 -214.466878) (xy 301.493943 -214.522054) (xy 301.477875 -214.575461) (xy 301.454203 -214.625958)
			(xy 301.42343 -214.672471) (xy 301.386213 -214.714008) (xy 301.343345 -214.749683) (xy 301.295739 -214.778737)
			(xy 301.24441 -214.800549) (xy 301.190453 -214.814655) (xy 301.135016 -214.820755) (xy 301.079282 -214.818718)
			(xy 301.024439 -214.808588) (xy 300.971655 -214.790581) (xy 300.922055 -214.76508) (xy 300.876697 -214.732629)
			(xy 300.836548 -214.69392) (xy 300.802462 -214.649777) (xy 300.775166 -214.601142) (xy 300.755243 -214.549051)
			(xy 300.743117 -214.494614) (xy 300.739046 -214.438992) (xy 298.095924 -214.438992) (xy 298.095924 -215.570562)
			(xy 302.123854 -215.570562) (xy 302.127925 -215.51494) (xy 302.140051 -215.460503) (xy 302.159974 -215.408412)
			(xy 302.18727 -215.359777) (xy 302.221356 -215.315634) (xy 302.261505 -215.276925) (xy 302.306863 -215.244474)
			(xy 302.356463 -215.218973) (xy 302.409247 -215.200966) (xy 302.46409 -215.190836) (xy 302.519824 -215.188799)
			(xy 302.575261 -215.194899) (xy 302.629218 -215.209005) (xy 302.680547 -215.230817) (xy 302.728153 -215.259871)
			(xy 302.771021 -215.295546) (xy 302.808238 -215.337083) (xy 302.839011 -215.383596) (xy 302.862683 -215.434093)
			(xy 302.878751 -215.4875) (xy 302.886871 -215.542676) (xy 302.88738 -215.570562) (xy 302.886871 -215.598448)
			(xy 302.878751 -215.653624) (xy 302.862683 -215.707031) (xy 302.839011 -215.757528) (xy 302.808238 -215.804041)
			(xy 302.771021 -215.845578) (xy 302.728153 -215.881253) (xy 302.680547 -215.910307) (xy 302.629218 -215.932119)
			(xy 302.575261 -215.946225) (xy 302.519824 -215.952325) (xy 302.46409 -215.950288) (xy 302.409247 -215.940158)
			(xy 302.356463 -215.922151) (xy 302.306863 -215.89665) (xy 302.261505 -215.864199) (xy 302.221356 -215.82549)
			(xy 302.18727 -215.781347) (xy 302.159974 -215.732712) (xy 302.140051 -215.680621) (xy 302.127925 -215.626184)
			(xy 302.123854 -215.570562) (xy 298.095924 -215.570562) (xy 298.095924 -216.172288) (xy 300.440342 -216.172288)
			(xy 300.444413 -216.116666) (xy 300.456539 -216.062229) (xy 300.476462 -216.010138) (xy 300.503758 -215.961503)
			(xy 300.537844 -215.91736) (xy 300.577993 -215.878651) (xy 300.623351 -215.8462) (xy 300.672951 -215.820699)
			(xy 300.725735 -215.802692) (xy 300.780578 -215.792562) (xy 300.836312 -215.790525) (xy 300.891749 -215.796625)
			(xy 300.945706 -215.810731) (xy 300.997035 -215.832543) (xy 301.044641 -215.861597) (xy 301.087509 -215.897272)
			(xy 301.124726 -215.938809) (xy 301.155499 -215.985322) (xy 301.179171 -216.035819) (xy 301.195239 -216.089226)
			(xy 301.203359 -216.144402) (xy 301.203868 -216.172288) (xy 301.203359 -216.200174) (xy 301.195239 -216.25535)
			(xy 301.179171 -216.308757) (xy 301.155499 -216.359254) (xy 301.124726 -216.405767) (xy 301.087509 -216.447304)
			(xy 301.044641 -216.482979) (xy 300.997035 -216.512033) (xy 300.945706 -216.533845) (xy 300.891749 -216.547951)
			(xy 300.836312 -216.554051) (xy 300.780578 -216.552014) (xy 300.725735 -216.541884) (xy 300.672951 -216.523877)
			(xy 300.623351 -216.498376) (xy 300.577993 -216.465925) (xy 300.537844 -216.427216) (xy 300.503758 -216.383073)
			(xy 300.476462 -216.334438) (xy 300.456539 -216.282347) (xy 300.444413 -216.22791) (xy 300.440342 -216.172288)
			(xy 298.095924 -216.172288) (xy 298.095924 -217.564462) (xy 300.10303 -217.564462) (xy 300.107101 -217.50884)
			(xy 300.119227 -217.454403) (xy 300.13915 -217.402312) (xy 300.166446 -217.353677) (xy 300.200532 -217.309534)
			(xy 300.240681 -217.270825) (xy 300.286039 -217.238374) (xy 300.335639 -217.212873) (xy 300.388423 -217.194866)
			(xy 300.443266 -217.184736) (xy 300.499 -217.182699) (xy 300.554437 -217.188799) (xy 300.608394 -217.202905)
			(xy 300.659723 -217.224717) (xy 300.707329 -217.253771) (xy 300.750197 -217.289446) (xy 300.787414 -217.330983)
			(xy 300.818187 -217.377496) (xy 300.841859 -217.427993) (xy 300.857927 -217.4814) (xy 300.866047 -217.536576)
			(xy 300.866556 -217.564462) (xy 300.866047 -217.592348) (xy 300.86032 -217.631264) (xy 301.932084 -217.631264)
			(xy 301.936155 -217.575642) (xy 301.948281 -217.521205) (xy 301.968204 -217.469114) (xy 301.9955 -217.420479)
			(xy 302.029586 -217.376336) (xy 302.069735 -217.337627) (xy 302.115093 -217.305176) (xy 302.164693 -217.279675)
			(xy 302.217477 -217.261668) (xy 302.27232 -217.251538) (xy 302.328054 -217.249501) (xy 302.383491 -217.255601)
			(xy 302.437448 -217.269707) (xy 302.488777 -217.291519) (xy 302.536383 -217.320573) (xy 302.579251 -217.356248)
			(xy 302.616468 -217.397785) (xy 302.647241 -217.444298) (xy 302.670913 -217.494795) (xy 302.686981 -217.548202)
			(xy 302.695101 -217.603378) (xy 302.69561 -217.631264) (xy 302.695101 -217.65915) (xy 302.686981 -217.714326)
			(xy 302.670913 -217.767733) (xy 302.647241 -217.81823) (xy 302.616468 -217.864743) (xy 302.579251 -217.90628)
			(xy 302.536383 -217.941955) (xy 302.488777 -217.971009) (xy 302.437448 -217.992821) (xy 302.383491 -218.006927)
			(xy 302.328054 -218.013027) (xy 302.27232 -218.01099) (xy 302.217477 -218.00086) (xy 302.164693 -217.982853)
			(xy 302.115093 -217.957352) (xy 302.069735 -217.924901) (xy 302.029586 -217.886192) (xy 301.9955 -217.842049)
			(xy 301.968204 -217.793414) (xy 301.948281 -217.741323) (xy 301.936155 -217.686886) (xy 301.932084 -217.631264)
			(xy 300.86032 -217.631264) (xy 300.857927 -217.647524) (xy 300.841859 -217.700931) (xy 300.818187 -217.751428)
			(xy 300.787414 -217.797941) (xy 300.750197 -217.839478) (xy 300.707329 -217.875153) (xy 300.659723 -217.904207)
			(xy 300.608394 -217.926019) (xy 300.554437 -217.940125) (xy 300.499 -217.946225) (xy 300.443266 -217.944188)
			(xy 300.388423 -217.934058) (xy 300.335639 -217.916051) (xy 300.286039 -217.89055) (xy 300.240681 -217.858099)
			(xy 300.200532 -217.81939) (xy 300.166446 -217.775247) (xy 300.13915 -217.726612) (xy 300.119227 -217.674521)
			(xy 300.107101 -217.620084) (xy 300.10303 -217.564462) (xy 298.095924 -217.564462) (xy 298.095924 -220.58122)
			(xy 299.398688 -220.58122) (xy 299.402759 -220.525598) (xy 299.414885 -220.471161) (xy 299.434808 -220.41907)
			(xy 299.462104 -220.370435) (xy 299.49619 -220.326292) (xy 299.536339 -220.287583) (xy 299.581697 -220.255132)
			(xy 299.631297 -220.229631) (xy 299.684081 -220.211624) (xy 299.738924 -220.201494) (xy 299.794658 -220.199457)
			(xy 299.850095 -220.205557) (xy 299.904052 -220.219663) (xy 299.955381 -220.241475) (xy 300.002987 -220.270529)
			(xy 300.045855 -220.306204) (xy 300.083072 -220.347741) (xy 300.113845 -220.394254) (xy 300.137517 -220.444751)
			(xy 300.153585 -220.498158) (xy 300.161705 -220.553334) (xy 300.161797 -220.55836) (xy 301.225456 -220.55836)
			(xy 301.229527 -220.502738) (xy 301.241653 -220.448301) (xy 301.261576 -220.39621) (xy 301.288872 -220.347575)
			(xy 301.322958 -220.303432) (xy 301.363107 -220.264723) (xy 301.408465 -220.232272) (xy 301.458065 -220.206771)
			(xy 301.510849 -220.188764) (xy 301.565692 -220.178634) (xy 301.621426 -220.176597) (xy 301.676863 -220.182697)
			(xy 301.73082 -220.196803) (xy 301.782149 -220.218615) (xy 301.829755 -220.247669) (xy 301.872623 -220.283344)
			(xy 301.90984 -220.324881) (xy 301.940613 -220.371394) (xy 301.964285 -220.421891) (xy 301.980353 -220.475298)
			(xy 301.988473 -220.530474) (xy 301.988982 -220.55836) (xy 301.988473 -220.586246) (xy 301.980353 -220.641422)
			(xy 301.964285 -220.694829) (xy 301.940613 -220.745326) (xy 301.90984 -220.791839) (xy 301.872623 -220.833376)
			(xy 301.829755 -220.869051) (xy 301.782149 -220.898105) (xy 301.73082 -220.919917) (xy 301.676863 -220.934023)
			(xy 301.621426 -220.940123) (xy 301.565692 -220.938086) (xy 301.510849 -220.927956) (xy 301.458065 -220.909949)
			(xy 301.408465 -220.884448) (xy 301.363107 -220.851997) (xy 301.322958 -220.813288) (xy 301.288872 -220.769145)
			(xy 301.261576 -220.72051) (xy 301.241653 -220.668419) (xy 301.229527 -220.613982) (xy 301.225456 -220.55836)
			(xy 300.161797 -220.55836) (xy 300.162214 -220.58122) (xy 300.161705 -220.609106) (xy 300.153585 -220.664282)
			(xy 300.137517 -220.717689) (xy 300.113845 -220.768186) (xy 300.083072 -220.814699) (xy 300.045855 -220.856236)
			(xy 300.002987 -220.891911) (xy 299.955381 -220.920965) (xy 299.904052 -220.942777) (xy 299.850095 -220.956883)
			(xy 299.794658 -220.962983) (xy 299.738924 -220.960946) (xy 299.684081 -220.950816) (xy 299.631297 -220.932809)
			(xy 299.581697 -220.907308) (xy 299.536339 -220.874857) (xy 299.49619 -220.836148) (xy 299.462104 -220.792005)
			(xy 299.434808 -220.74337) (xy 299.414885 -220.691279) (xy 299.402759 -220.636842) (xy 299.398688 -220.58122)
			(xy 298.095924 -220.58122) (xy 298.095924 -225.094038) (xy 299.26915 -225.094038) (xy 299.269601 -225.066885)
			(xy 299.277321 -225.013131) (xy 299.292582 -224.961014) (xy 299.315076 -224.911586) (xy 299.344348 -224.865845)
			(xy 299.379808 -224.824715) (xy 299.39996 -224.80651) (xy 299.407416 -224.799438) (xy 299.416318 -224.780934)
			(xy 299.417232 -224.770696) (xy 299.421296 -224.686876) (xy 299.414184 -224.667572) (xy 299.407072 -224.659952)
			(xy 299.38752 -224.638591) (xy 299.354484 -224.591033) (xy 299.329019 -224.539025) (xy 299.311712 -224.483765)
			(xy 299.30296 -224.426523) (xy 299.302424 -224.39757) (xy 299.30291 -224.370319) (xy 299.310666 -224.316371)
			(xy 299.326021 -224.264076) (xy 299.348663 -224.214499) (xy 299.378129 -224.168649) (xy 299.41382 -224.127458)
			(xy 299.455011 -224.091767) (xy 299.500861 -224.062301) (xy 299.550438 -224.039659) (xy 299.602733 -224.024304)
			(xy 299.656681 -224.016548) (xy 299.711183 -224.016548) (xy 299.765131 -224.024304) (xy 299.817426 -224.039659)
			(xy 299.867003 -224.062301) (xy 299.912853 -224.091767) (xy 299.954044 -224.127458) (xy 299.989735 -224.168649)
			(xy 300.019201 -224.214499) (xy 300.041843 -224.264076) (xy 300.057198 -224.316371) (xy 300.064954 -224.370319)
			(xy 300.06544 -224.39757) (xy 300.065344 -224.40265) (xy 300.622714 -224.40265) (xy 300.626785 -224.347028)
			(xy 300.638911 -224.292591) (xy 300.658834 -224.2405) (xy 300.68613 -224.191865) (xy 300.720216 -224.147722)
			(xy 300.760365 -224.109013) (xy 300.805723 -224.076562) (xy 300.855323 -224.051061) (xy 300.908107 -224.033054)
			(xy 300.96295 -224.022924) (xy 301.018684 -224.020887) (xy 301.074121 -224.026987) (xy 301.128078 -224.041093)
			(xy 301.179407 -224.062905) (xy 301.227013 -224.091959) (xy 301.269881 -224.127634) (xy 301.307098 -224.169171)
			(xy 301.337871 -224.215684) (xy 301.361543 -224.266181) (xy 301.377611 -224.319588) (xy 301.385731 -224.374764)
			(xy 301.38624 -224.40265) (xy 301.385731 -224.430536) (xy 301.377611 -224.485712) (xy 301.361543 -224.539119)
			(xy 301.337871 -224.589616) (xy 301.307098 -224.636129) (xy 301.269881 -224.677666) (xy 301.227013 -224.713341)
			(xy 301.179407 -224.742395) (xy 301.128078 -224.764207) (xy 301.074121 -224.778313) (xy 301.018684 -224.784413)
			(xy 300.96295 -224.782376) (xy 300.908107 -224.772246) (xy 300.855323 -224.754239) (xy 300.805723 -224.728738)
			(xy 300.760365 -224.696287) (xy 300.720216 -224.657578) (xy 300.68613 -224.613435) (xy 300.658834 -224.5648)
			(xy 300.638911 -224.512709) (xy 300.626785 -224.458272) (xy 300.622714 -224.40265) (xy 300.065344 -224.40265)
			(xy 300.064929 -224.424721) (xy 300.057222 -224.478472) (xy 300.041973 -224.530589) (xy 300.019491 -224.580017)
			(xy 299.990228 -224.625759) (xy 299.954777 -224.666892) (xy 299.93463 -224.685098) (xy 299.927185 -224.692181)
			(xy 299.918273 -224.710676) (xy 299.917358 -224.720912) (xy 299.913294 -224.804732) (xy 299.920406 -224.824036)
			(xy 299.927518 -224.831656) (xy 299.947072 -224.853015) (xy 299.980108 -224.900574) (xy 300.005573 -224.952582)
			(xy 300.022879 -225.007842) (xy 300.031631 -225.065084) (xy 300.032166 -225.094038) (xy 300.03168 -225.121289)
			(xy 300.023924 -225.175237) (xy 300.008569 -225.227532) (xy 299.985927 -225.277109) (xy 299.956461 -225.322959)
			(xy 299.92077 -225.36415) (xy 299.879579 -225.399841) (xy 299.833729 -225.429307) (xy 299.784152 -225.451949)
			(xy 299.731857 -225.467304) (xy 299.677909 -225.47506) (xy 299.623407 -225.47506) (xy 299.569459 -225.467304)
			(xy 299.517164 -225.451949) (xy 299.467587 -225.429307) (xy 299.421737 -225.399841) (xy 299.380546 -225.36415)
			(xy 299.344855 -225.322959) (xy 299.315389 -225.277109) (xy 299.292747 -225.227532) (xy 299.277392 -225.175237)
			(xy 299.269636 -225.121289) (xy 299.26915 -225.094038) (xy 298.095924 -225.094038) (xy 298.095924 -227.246434)
			(xy 299.758098 -227.246434) (xy 299.762169 -227.190812) (xy 299.774295 -227.136375) (xy 299.794218 -227.084284)
			(xy 299.821514 -227.035649) (xy 299.8556 -226.991506) (xy 299.895749 -226.952797) (xy 299.941107 -226.920346)
			(xy 299.990707 -226.894845) (xy 300.043491 -226.876838) (xy 300.098334 -226.866708) (xy 300.154068 -226.864671)
			(xy 300.209505 -226.870771) (xy 300.263462 -226.884877) (xy 300.314791 -226.906689) (xy 300.362397 -226.935743)
			(xy 300.405265 -226.971418) (xy 300.442482 -227.012955) (xy 300.473255 -227.059468) (xy 300.496927 -227.109965)
			(xy 300.512995 -227.163372) (xy 300.521115 -227.218548) (xy 300.521624 -227.246434) (xy 300.521115 -227.27432)
			(xy 300.512995 -227.329496) (xy 300.496927 -227.382903) (xy 300.473255 -227.4334) (xy 300.442482 -227.479913)
			(xy 300.405265 -227.52145) (xy 300.362397 -227.557125) (xy 300.314791 -227.586179) (xy 300.263462 -227.607991)
			(xy 300.209505 -227.622097) (xy 300.154068 -227.628197) (xy 300.098334 -227.62616) (xy 300.043491 -227.61603)
			(xy 299.990707 -227.598023) (xy 299.941107 -227.572522) (xy 299.895749 -227.540071) (xy 299.8556 -227.501362)
			(xy 299.821514 -227.457219) (xy 299.794218 -227.408584) (xy 299.774295 -227.356493) (xy 299.762169 -227.302056)
			(xy 299.758098 -227.246434) (xy 298.095924 -227.246434) (xy 298.095924 -231.817672) (xy 298.096548 -231.829224)
			(xy 298.106744 -231.849965) (xy 298.115482 -231.85755) (xy 298.187872 -231.914446) (xy 298.210732 -231.919272)
			(xy 298.221908 -231.916478) (xy 298.244346 -231.91128) (xy 298.290064 -231.90568) (xy 298.313094 -231.905302)
			(xy 298.340346 -231.905765) (xy 298.394297 -231.913521) (xy 298.446594 -231.928876) (xy 298.496173 -231.951518)
			(xy 298.542026 -231.980985) (xy 298.583218 -232.016677) (xy 298.618912 -232.057869) (xy 298.648379 -232.103721)
			(xy 298.671022 -232.153301) (xy 298.686378 -232.205598) (xy 298.694135 -232.259548) (xy 298.694135 -232.314052)
			(xy 298.686378 -232.368002) (xy 298.671022 -232.420299) (xy 298.648379 -232.469879) (xy 298.618912 -232.515731)
			(xy 298.583218 -232.556923) (xy 298.542026 -232.592615) (xy 298.496173 -232.622082) (xy 298.446594 -232.644724)
			(xy 298.394297 -232.660079) (xy 298.340346 -232.667835) (xy 298.313094 -232.668318) (xy 298.275502 -232.66654)
			(xy 298.261024 -232.665016) (xy 298.234608 -232.678224) (xy 298.179744 -232.769664) (xy 298.175171 -232.778105)
			(xy 298.172048 -232.797032) (xy 298.176073 -232.815788) (xy 298.181014 -232.82402) (xy 298.922784 -233.934)
			(xy 301.154336 -233.934) (xy 301.158407 -233.878378) (xy 301.170533 -233.823941) (xy 301.190456 -233.77185)
			(xy 301.217752 -233.723215) (xy 301.251838 -233.679072) (xy 301.291987 -233.640363) (xy 301.337345 -233.607912)
			(xy 301.386945 -233.582411) (xy 301.439729 -233.564404) (xy 301.494572 -233.554274) (xy 301.550306 -233.552237)
			(xy 301.605743 -233.558337) (xy 301.6597 -233.572443) (xy 301.711029 -233.594255) (xy 301.758635 -233.623309)
			(xy 301.801503 -233.658984) (xy 301.83872 -233.700521) (xy 301.869493 -233.747034) (xy 301.893165 -233.797531)
			(xy 301.909233 -233.850938) (xy 301.917353 -233.906114) (xy 301.917862 -233.934) (xy 301.917353 -233.961886)
			(xy 301.909233 -234.017062) (xy 301.893165 -234.070469) (xy 301.869493 -234.120966) (xy 301.83872 -234.167479)
			(xy 301.801503 -234.209016) (xy 301.758635 -234.244691) (xy 301.711029 -234.273745) (xy 301.6597 -234.295557)
			(xy 301.605743 -234.309663) (xy 301.550306 -234.315763) (xy 301.494572 -234.313726) (xy 301.439729 -234.303596)
			(xy 301.386945 -234.285589) (xy 301.337345 -234.260088) (xy 301.291987 -234.227637) (xy 301.251838 -234.188928)
			(xy 301.217752 -234.144785) (xy 301.190456 -234.09615) (xy 301.170533 -234.044059) (xy 301.158407 -233.989622)
			(xy 301.154336 -233.934) (xy 298.922784 -233.934) (xy 300.610524 -236.459522) (xy 300.619435 -236.473182)
			(xy 300.63483 -236.501937) (xy 300.641258 -236.516926) (xy 301.180707 -237.819184) (xy 302.170336 -237.819184)
			(xy 302.174407 -237.763562) (xy 302.186533 -237.709125) (xy 302.206456 -237.657034) (xy 302.233752 -237.608399)
			(xy 302.267838 -237.564256) (xy 302.307987 -237.525547) (xy 302.353345 -237.493096) (xy 302.402945 -237.467595)
			(xy 302.455729 -237.449588) (xy 302.510572 -237.439458) (xy 302.566306 -237.437421) (xy 302.621743 -237.443521)
			(xy 302.6757 -237.457627) (xy 302.727029 -237.479439) (xy 302.774635 -237.508493) (xy 302.817503 -237.544168)
			(xy 302.85472 -237.585705) (xy 302.885493 -237.632218) (xy 302.909165 -237.682715) (xy 302.925233 -237.736122)
			(xy 302.933353 -237.791298) (xy 302.933862 -237.819184) (xy 302.933353 -237.84707) (xy 302.925233 -237.902246)
			(xy 302.909165 -237.955653) (xy 302.885493 -238.00615) (xy 302.85472 -238.052663) (xy 302.817503 -238.0942)
			(xy 302.774635 -238.129875) (xy 302.727029 -238.158929) (xy 302.6757 -238.180741) (xy 302.621743 -238.194847)
			(xy 302.566306 -238.200947) (xy 302.510572 -238.19891) (xy 302.455729 -238.18878) (xy 302.402945 -238.170773)
			(xy 302.353345 -238.145272) (xy 302.307987 -238.112821) (xy 302.267838 -238.074112) (xy 302.233752 -238.029969)
			(xy 302.206456 -237.981334) (xy 302.186533 -237.929243) (xy 302.174407 -237.874806) (xy 302.170336 -237.819184)
			(xy 301.180707 -237.819184) (xy 301.555912 -238.724948) (xy 301.55985 -238.733426) (xy 301.572693 -238.746986)
			(xy 301.589563 -238.755001) (xy 301.598838 -238.75619) (xy 301.703232 -238.764572) (xy 301.728632 -238.751618)
			(xy 301.736252 -238.739172) (xy 301.751242 -238.71571) (xy 301.786946 -238.67299) (xy 301.828475 -238.635909)
			(xy 301.874949 -238.605251) (xy 301.925382 -238.581667) (xy 301.978705 -238.565658) (xy 302.033789 -238.557562)
			(xy 302.061626 -238.557054) (xy 302.088879 -238.557542) (xy 302.142829 -238.565302) (xy 302.195126 -238.580661)
			(xy 302.244705 -238.603306) (xy 302.290556 -238.632776) (xy 302.331748 -238.668471) (xy 302.36744 -238.709664)
			(xy 302.396907 -238.755518) (xy 302.419548 -238.805099) (xy 302.434904 -238.857396) (xy 302.44266 -238.911347)
			(xy 302.44266 -238.938562) (xy 302.695608 -238.938562) (xy 302.699679 -238.88294) (xy 302.711805 -238.828503)
			(xy 302.731728 -238.776412) (xy 302.759024 -238.727777) (xy 302.79311 -238.683634) (xy 302.833259 -238.644925)
			(xy 302.878617 -238.612474) (xy 302.928217 -238.586973) (xy 302.981001 -238.568966) (xy 303.035844 -238.558836)
			(xy 303.091578 -238.556799) (xy 303.147015 -238.562899) (xy 303.200972 -238.577005) (xy 303.252301 -238.598817)
			(xy 303.299907 -238.627871) (xy 303.342775 -238.663546) (xy 303.379992 -238.705083) (xy 303.410765 -238.751596)
			(xy 303.434437 -238.802093) (xy 303.450505 -238.8555) (xy 303.458625 -238.910676) (xy 303.459134 -238.938562)
			(xy 303.458625 -238.966448) (xy 303.450505 -239.021624) (xy 303.434437 -239.075031) (xy 303.410765 -239.125528)
			(xy 303.379992 -239.172041) (xy 303.342775 -239.213578) (xy 303.299907 -239.249253) (xy 303.252301 -239.278307)
			(xy 303.200972 -239.300119) (xy 303.147015 -239.314225) (xy 303.091578 -239.320325) (xy 303.035844 -239.318288)
			(xy 302.981001 -239.308158) (xy 302.928217 -239.290151) (xy 302.878617 -239.26465) (xy 302.833259 -239.232199)
			(xy 302.79311 -239.19349) (xy 302.759024 -239.149347) (xy 302.731728 -239.100712) (xy 302.711805 -239.048621)
			(xy 302.699679 -238.994184) (xy 302.695608 -238.938562) (xy 302.44266 -238.938562) (xy 302.44266 -238.965853)
			(xy 302.434904 -239.019804) (xy 302.419548 -239.072101) (xy 302.396907 -239.121682) (xy 302.36744 -239.167536)
			(xy 302.331748 -239.208729) (xy 302.290556 -239.244424) (xy 302.244705 -239.273894) (xy 302.195126 -239.296539)
			(xy 302.142829 -239.311898) (xy 302.088879 -239.319658) (xy 302.061626 -239.32007) (xy 302.039184 -239.319697)
			(xy 301.99462 -239.314344) (xy 301.972726 -239.309402) (xy 301.972218 -239.309402) (xy 301.958248 -239.3061)
			(xy 301.931578 -239.314736) (xy 301.863506 -239.394746) (xy 301.857757 -239.402097) (xy 301.851496 -239.419661)
			(xy 301.851933 -239.438302) (xy 301.855124 -239.44707) (xy 304.01641 -244.6655) (xy 304.024358 -244.685631)
			(xy 304.035553 -244.72744) (xy 304.041205 -244.770351) (xy 304.041556 -244.791992) (xy 304.041556 -249.894852)
			(xy 304.041998 -249.904525) (xy 304.049171 -249.922493) (xy 304.062454 -249.936561) (xy 304.07102 -249.94108)
			(xy 304.168302 -249.986038) (xy 304.197512 -249.981974) (xy 304.208942 -249.972322) (xy 304.229707 -249.955326)
			(xy 304.275103 -249.926718) (xy 304.324062 -249.904755) (xy 304.375615 -249.889871) (xy 304.428746 -249.88236)
			(xy 304.455576 -249.881898) (xy 304.48283 -249.88236) (xy 304.536782 -249.890114) (xy 304.589082 -249.905467)
			(xy 304.638664 -249.928108) (xy 304.68452 -249.957575) (xy 304.725715 -249.993268) (xy 304.76141 -250.034461)
			(xy 304.79088 -250.080314) (xy 304.813524 -250.129895) (xy 304.828881 -250.182194) (xy 304.836639 -250.236146)
			(xy 304.836639 -250.290654) (xy 304.828881 -250.344606) (xy 304.813524 -250.396905) (xy 304.79088 -250.446486)
			(xy 304.76141 -250.492339) (xy 304.725715 -250.533532) (xy 304.68452 -250.569225) (xy 304.638664 -250.598692)
			(xy 304.589082 -250.621333) (xy 304.536782 -250.636686) (xy 304.48283 -250.64444) (xy 304.455576 -250.644914)
			(xy 304.428747 -250.644457) (xy 304.375618 -250.636937) (xy 304.324066 -250.622048) (xy 304.275109 -250.600085)
			(xy 304.22971 -250.571481) (xy 304.208942 -250.55449) (xy 304.197512 -250.544838) (xy 304.168302 -250.540774)
			(xy 304.07102 -250.585732) (xy 304.062389 -250.590167) (xy 304.049048 -250.604236) (xy 304.041913 -250.622264)
			(xy 304.041556 -250.63196) (xy 304.041556 -250.76912) (xy 304.045366 -250.782328) (xy 304.048922 -250.78817)
			(xy 304.061932 -250.810571) (xy 304.082447 -250.858139) (xy 304.096339 -250.908046) (xy 304.103351 -250.959372)
			(xy 304.103786 -250.985274) (xy 304.1033 -251.012525) (xy 304.095544 -251.066473) (xy 304.080189 -251.118768)
			(xy 304.057547 -251.168345) (xy 304.028081 -251.214195) (xy 303.99239 -251.255386) (xy 303.951199 -251.291077)
			(xy 303.905349 -251.320543) (xy 303.855772 -251.343185) (xy 303.803477 -251.35854) (xy 303.749529 -251.366296)
			(xy 303.695027 -251.366296) (xy 303.641079 -251.35854) (xy 303.588784 -251.343185) (xy 303.539207 -251.320543)
			(xy 303.493357 -251.291077) (xy 303.452166 -251.255386) (xy 303.416475 -251.214195) (xy 303.387009 -251.168345)
			(xy 303.364367 -251.118768) (xy 303.349012 -251.066473) (xy 303.341256 -251.012525) (xy 303.34077 -250.985274)
			(xy 303.34077 -250.984766) (xy 303.341242 -250.958252) (xy 303.348617 -250.905739) (xy 303.363195 -250.854753)
			(xy 303.373536 -250.830334) (xy 303.378108 -250.820682) (xy 303.378108 -244.8687) (xy 303.378021 -244.86368)
			(xy 303.37611 -244.853824) (xy 303.374298 -244.849142) (xy 300.623732 -238.209074) (xy 300.618622 -238.198389)
			(xy 300.600743 -238.1829) (xy 300.589442 -238.179356) (xy 300.510702 -238.15929) (xy 300.499145 -238.156924)
			(xy 300.476099 -238.161823) (xy 300.466506 -238.168688) (xy 300.446127 -238.18448) (xy 300.401924 -238.211016)
			(xy 300.354548 -238.231352) (xy 300.304864 -238.24512) (xy 300.253778 -238.252067) (xy 300.228 -238.252508)
			(xy 300.200749 -238.252022) (xy 300.146801 -238.244266) (xy 300.094506 -238.228911) (xy 300.044929 -238.206269)
			(xy 299.999079 -238.176803) (xy 299.957888 -238.141112) (xy 299.922197 -238.099921) (xy 299.892731 -238.054071)
			(xy 299.870089 -238.004494) (xy 299.854734 -237.952199) (xy 299.846978 -237.898251) (xy 299.846492 -237.871)
			(xy 299.847 -237.843124) (xy 299.855115 -237.787965) (xy 299.871173 -237.734574) (xy 299.89483 -237.684089)
			(xy 299.925584 -237.637586) (xy 299.962779 -237.596054) (xy 300.005623 -237.560378) (xy 300.053203 -237.531318)
			(xy 300.104507 -237.509493) (xy 300.158441 -237.495368) (xy 300.18609 -237.491778) (xy 300.198028 -237.490508)
			(xy 300.218094 -237.477554) (xy 300.265592 -237.39729) (xy 300.271088 -237.386814) (xy 300.272798 -237.363247)
			(xy 300.268894 -237.352078) (xy 300.04258 -236.805724) (xy 300.037754 -236.797088) (xy 297.488356 -232.981754)
			(xy 297.475162 -232.961204) (xy 297.454294 -232.917053) (xy 297.440112 -232.870323) (xy 297.432921 -232.822021)
			(xy 297.432476 -232.797604) (xy 297.432476 -209.1817) (xy 297.432844 -209.16006) (xy 297.438501 -209.117152)
			(xy 297.449681 -209.075341) (xy 297.457622 -209.055208) (xy 299.308266 -204.587602) (xy 299.310066 -204.582916)
			(xy 299.311985 -204.573063) (xy 299.312076 -204.568044) (xy 299.312076 -199.67194) (xy 299.311552 -199.661441)
			(xy 299.303154 -199.642194) (xy 299.287777 -199.627894) (xy 299.27804 -199.623934) (xy 299.187108 -199.592438)
			(xy 299.177028 -199.589522) (xy 299.156133 -199.591193) (xy 299.137636 -199.601056) (xy 299.13072 -199.608948)
			(xy 299.130466 -199.609202) (xy 299.112285 -199.631441) (xy 299.070373 -199.670719) (xy 299.023043 -199.703266)
			(xy 298.971365 -199.728343) (xy 298.916511 -199.745383) (xy 298.85972 -199.754) (xy 298.831 -199.75449)
			(xy 298.80375 -199.754004) (xy 298.749805 -199.746248) (xy 298.697513 -199.730893) (xy 298.647938 -199.708253)
			(xy 298.60209 -199.678788) (xy 298.560901 -199.643099) (xy 298.525212 -199.60191) (xy 298.495747 -199.556062)
			(xy 298.473107 -199.506487) (xy 298.457752 -199.454195) (xy 298.449996 -199.40025) (xy 298.449996 -199.34575)
			(xy 298.457752 -199.291805) (xy 298.473107 -199.239513) (xy 298.495747 -199.189938) (xy 298.525212 -199.14409)
			(xy 298.560901 -199.102901) (xy 298.60209 -199.067212) (xy 298.647938 -199.037747) (xy 298.697513 -199.015107)
			(xy 298.749805 -198.999752) (xy 298.80375 -198.991996) (xy 298.831 -198.991474) (xy 298.859719 -198.991994)
			(xy 298.916508 -199.000609) (xy 298.971362 -199.017644) (xy 299.023041 -199.042712) (xy 299.070376 -199.075249)
			(xy 299.112295 -199.114516) (xy 299.130466 -199.136762) (xy 299.13072 -199.137016) (xy 299.137624 -199.144922)
			(xy 299.15612 -199.154797) (xy 299.177022 -199.156439) (xy 299.187108 -199.153526) (xy 299.27804 -199.12203)
			(xy 299.287799 -199.118089) (xy 299.303227 -199.103807) (xy 299.31163 -199.084536) (xy 299.312076 -199.074024)
			(xy 299.312076 -190.143638) (xy 299.311641 -190.133573) (xy 299.303908 -190.114987) (xy 299.29709 -190.10757)
			(xy 293.410386 -184.22112) (xy 293.402986 -184.214437) (xy 293.384573 -184.206836) (xy 293.364653 -184.206831)
			(xy 293.355268 -184.210198) (xy 293.34079 -184.21604) (xy 293.323772 -184.241694) (xy 293.323772 -185.049922)
			(xy 293.323277 -185.084008) (xy 293.315362 -185.151718) (xy 293.299641 -185.218052) (xy 293.276325 -185.282112)
			(xy 293.24573 -185.343032) (xy 293.208269 -185.399989) (xy 293.164449 -185.452211) (xy 293.114863 -185.498993)
			(xy 293.060181 -185.539702) (xy 293.001143 -185.573788) (xy 292.938547 -185.600789) (xy 292.87324 -185.620341)
			(xy 292.806104 -185.632179) (xy 292.738048 -185.636143) (xy 292.669992 -185.632179) (xy 292.602856 -185.620341)
			(xy 292.537549 -185.600789) (xy 292.474953 -185.573788) (xy 292.415915 -185.539702) (xy 292.361233 -185.498993)
			(xy 292.311647 -185.452211) (xy 292.267827 -185.399989) (xy 292.230366 -185.343032) (xy 292.199771 -185.282112)
			(xy 292.176455 -185.218052) (xy 292.160734 -185.151718) (xy 292.152819 -185.084008) (xy 292.152324 -185.049922)
			(xy 292.152324 -184.111646) (xy 292.151892 -184.10158) (xy 292.144166 -184.082987) (xy 292.137338 -184.075578)
			(xy 284.00248 -175.940974) (xy 283.99428 -175.933612) (xy 283.973621 -175.925999) (xy 283.962602 -175.926242)
			(xy 283.874464 -175.933354) (xy 283.85516 -175.944276) (xy 283.848556 -175.95342) (xy 283.833125 -175.974078)
			(xy 283.797595 -176.011448) (xy 283.757356 -176.043691) (xy 283.71314 -176.07022) (xy 283.665753 -176.090551)
			(xy 283.61606 -176.104314) (xy 283.564966 -176.111257) (xy 283.539184 -176.111662) (xy 283.511933 -176.111198)
			(xy 283.457986 -176.103438) (xy 283.405693 -176.088081) (xy 283.356118 -176.065437) (xy 283.31027 -176.035967)
			(xy 283.269083 -176.000273) (xy 283.233395 -175.95908) (xy 283.203934 -175.913228) (xy 283.181298 -175.863649)
			(xy 283.165948 -175.811353) (xy 283.158198 -175.757405) (xy 283.157676 -175.730154) (xy 283.158105 -175.704375)
			(xy 283.165054 -175.653287) (xy 283.178821 -175.6036) (xy 283.199154 -175.55622) (xy 283.225682 -175.512009)
			(xy 283.257923 -175.471775) (xy 283.295288 -175.436248) (xy 283.315918 -175.420782) (xy 283.325062 -175.414178)
			(xy 283.335984 -175.394874) (xy 283.343096 -175.306736) (xy 283.343444 -175.295702) (xy 283.335796 -175.275021)
			(xy 283.328364 -175.266858) (xy 283.153104 -175.091598) (xy 283.145706 -175.084751) (xy 283.127108 -175.077015)
			(xy 283.117036 -175.076612) (xy 282.39339 -175.076612) (xy 282.357977 -175.076077) (xy 282.287667 -175.067539)
			(xy 282.218899 -175.050589) (xy 282.152675 -175.025473) (xy 282.089961 -174.992559) (xy 282.031672 -174.952326)
			(xy 281.978657 -174.90536) (xy 281.931689 -174.852347) (xy 281.891453 -174.794059) (xy 281.858537 -174.731347)
			(xy 281.833418 -174.665124) (xy 281.816465 -174.596357) (xy 281.807925 -174.526047) (xy 281.807412 -174.490634)
			(xy 281.807853 -174.458283) (xy 281.815004 -174.393978) (xy 281.829199 -174.330854) (xy 281.850267 -174.269678)
			(xy 281.87795 -174.211198) (xy 281.91191 -174.156126) (xy 281.951735 -174.105133) (xy 281.974036 -174.081694)
			(xy 281.97429 -174.08144) (xy 281.980826 -174.074009) (xy 281.988172 -174.055653) (xy 281.988042 -174.035883)
			(xy 281.980454 -174.017626) (xy 281.973782 -174.01032) (xy 278.17572 -170.212512) (xy 278.160616 -170.196889)
			(xy 278.134178 -170.162402) (xy 278.112464 -170.124761) (xy 278.103838 -170.104816) (xy 277.341584 -168.264332)
			(xy 277.337605 -168.255863) (xy 277.324715 -168.242324) (xy 277.30783 -168.234297) (xy 277.289192 -168.232849)
			(xy 277.280116 -168.235122) (xy 277.27118 -168.238165) (xy 277.256264 -168.249711) (xy 277.246545 -168.265879)
			(xy 277.243346 -168.284469) (xy 277.24481 -168.293796) (xy 279.515378 -179.728368) (xy 283.616652 -179.728368)
			(xy 283.620723 -179.672746) (xy 283.632849 -179.618309) (xy 283.652772 -179.566218) (xy 283.680068 -179.517583)
			(xy 283.714154 -179.47344) (xy 283.754303 -179.434731) (xy 283.799661 -179.40228) (xy 283.849261 -179.376779)
			(xy 283.902045 -179.358772) (xy 283.956888 -179.348642) (xy 284.012622 -179.346605) (xy 284.068059 -179.352705)
			(xy 284.122016 -179.366811) (xy 284.173345 -179.388623) (xy 284.220951 -179.417677) (xy 284.263819 -179.453352)
			(xy 284.301036 -179.494889) (xy 284.331809 -179.541402) (xy 284.355481 -179.591899) (xy 284.371549 -179.645306)
			(xy 284.379669 -179.700482) (xy 284.380178 -179.728368) (xy 284.379669 -179.756254) (xy 284.371549 -179.81143)
			(xy 284.355481 -179.864837) (xy 284.331809 -179.915334) (xy 284.301036 -179.961847) (xy 284.263819 -180.003384)
			(xy 284.220951 -180.039059) (xy 284.173345 -180.068113) (xy 284.122016 -180.089925) (xy 284.068059 -180.104031)
			(xy 284.012622 -180.110131) (xy 283.956888 -180.108094) (xy 283.902045 -180.097964) (xy 283.849261 -180.079957)
			(xy 283.799661 -180.054456) (xy 283.754303 -180.022005) (xy 283.714154 -179.983296) (xy 283.680068 -179.939153)
			(xy 283.652772 -179.890518) (xy 283.632849 -179.838427) (xy 283.620723 -179.78399) (xy 283.616652 -179.728368)
			(xy 279.515378 -179.728368) (xy 280.561288 -184.995566) (xy 280.563066 -185.001916) (xy 280.925655 -186.073034)
			(xy 286.503616 -186.073034) (xy 286.507687 -186.017412) (xy 286.519813 -185.962975) (xy 286.539736 -185.910884)
			(xy 286.567032 -185.862249) (xy 286.601118 -185.818106) (xy 286.641267 -185.779397) (xy 286.686625 -185.746946)
			(xy 286.736225 -185.721445) (xy 286.789009 -185.703438) (xy 286.843852 -185.693308) (xy 286.899586 -185.691271)
			(xy 286.955023 -185.697371) (xy 287.00898 -185.711477) (xy 287.060309 -185.733289) (xy 287.107915 -185.762343)
			(xy 287.150783 -185.798018) (xy 287.188 -185.839555) (xy 287.218773 -185.886068) (xy 287.242445 -185.936565)
			(xy 287.258513 -185.989972) (xy 287.266633 -186.045148) (xy 287.267142 -186.073034) (xy 287.266633 -186.10092)
			(xy 287.258513 -186.156096) (xy 287.242445 -186.209503) (xy 287.218773 -186.26) (xy 287.188 -186.306513)
			(xy 287.150783 -186.34805) (xy 287.107915 -186.383725) (xy 287.060309 -186.412779) (xy 287.00898 -186.434591)
			(xy 286.955023 -186.448697) (xy 286.899586 -186.454797) (xy 286.843852 -186.45276) (xy 286.789009 -186.44263)
			(xy 286.736225 -186.424623) (xy 286.686625 -186.399122) (xy 286.641267 -186.366671) (xy 286.601118 -186.327962)
			(xy 286.567032 -186.283819) (xy 286.539736 -186.235184) (xy 286.519813 -186.183093) (xy 286.507687 -186.128656)
			(xy 286.503616 -186.073034) (xy 280.925655 -186.073034) (xy 282.188054 -189.802262) (xy 291.45433 -189.802262)
			(xy 291.458401 -189.74664) (xy 291.470527 -189.692203) (xy 291.49045 -189.640112) (xy 291.517746 -189.591477)
			(xy 291.551832 -189.547334) (xy 291.591981 -189.508625) (xy 291.637339 -189.476174) (xy 291.686939 -189.450673)
			(xy 291.739723 -189.432666) (xy 291.794566 -189.422536) (xy 291.8503 -189.420499) (xy 291.905737 -189.426599)
			(xy 291.959694 -189.440705) (xy 292.011023 -189.462517) (xy 292.058629 -189.491571) (xy 292.101497 -189.527246)
			(xy 292.138714 -189.568783) (xy 292.169487 -189.615296) (xy 292.193159 -189.665793) (xy 292.209227 -189.7192)
			(xy 292.217347 -189.774376) (xy 292.217856 -189.802262) (xy 292.217347 -189.830148) (xy 292.209227 -189.885324)
			(xy 292.193159 -189.938731) (xy 292.169487 -189.989228) (xy 292.138714 -190.035741) (xy 292.101497 -190.077278)
			(xy 292.058629 -190.112953) (xy 292.011023 -190.142007) (xy 291.959694 -190.163819) (xy 291.905737 -190.177925)
			(xy 291.8503 -190.184025) (xy 291.794566 -190.181988) (xy 291.739723 -190.171858) (xy 291.686939 -190.153851)
			(xy 291.637339 -190.12835) (xy 291.591981 -190.095899) (xy 291.551832 -190.05719) (xy 291.517746 -190.013047)
			(xy 291.49045 -189.964412) (xy 291.470527 -189.912321) (xy 291.458401 -189.857884) (xy 291.45433 -189.802262)
			(xy 282.188054 -189.802262) (xy 283.675471 -194.196208) (xy 292.349172 -194.196208) (xy 292.353243 -194.140586)
			(xy 292.365369 -194.086149) (xy 292.385292 -194.034058) (xy 292.412588 -193.985423) (xy 292.446674 -193.94128)
			(xy 292.486823 -193.902571) (xy 292.532181 -193.87012) (xy 292.581781 -193.844619) (xy 292.634565 -193.826612)
			(xy 292.689408 -193.816482) (xy 292.745142 -193.814445) (xy 292.800579 -193.820545) (xy 292.854536 -193.834651)
			(xy 292.905865 -193.856463) (xy 292.953471 -193.885517) (xy 292.996339 -193.921192) (xy 293.033556 -193.962729)
			(xy 293.064329 -194.009242) (xy 293.088001 -194.059739) (xy 293.104069 -194.113146) (xy 293.112189 -194.168322)
			(xy 293.112698 -194.196208) (xy 293.112189 -194.224094) (xy 293.104069 -194.27927) (xy 293.090238 -194.32524)
			(xy 297.568618 -194.32524) (xy 297.572689 -194.269618) (xy 297.584815 -194.215181) (xy 297.604738 -194.16309)
			(xy 297.632034 -194.114455) (xy 297.66612 -194.070312) (xy 297.706269 -194.031603) (xy 297.751627 -193.999152)
			(xy 297.801227 -193.973651) (xy 297.854011 -193.955644) (xy 297.908854 -193.945514) (xy 297.964588 -193.943477)
			(xy 298.020025 -193.949577) (xy 298.073982 -193.963683) (xy 298.125311 -193.985495) (xy 298.172917 -194.014549)
			(xy 298.215785 -194.050224) (xy 298.253002 -194.091761) (xy 298.283775 -194.138274) (xy 298.307447 -194.188771)
			(xy 298.323515 -194.242178) (xy 298.331635 -194.297354) (xy 298.332144 -194.32524) (xy 298.331635 -194.353126)
			(xy 298.323515 -194.408302) (xy 298.307447 -194.461709) (xy 298.283775 -194.512206) (xy 298.253002 -194.558719)
			(xy 298.215785 -194.600256) (xy 298.172917 -194.635931) (xy 298.125311 -194.664985) (xy 298.073982 -194.686797)
			(xy 298.020025 -194.700903) (xy 297.964588 -194.707003) (xy 297.908854 -194.704966) (xy 297.854011 -194.694836)
			(xy 297.801227 -194.676829) (xy 297.751627 -194.651328) (xy 297.706269 -194.618877) (xy 297.66612 -194.580168)
			(xy 297.632034 -194.536025) (xy 297.604738 -194.48739) (xy 297.584815 -194.435299) (xy 297.572689 -194.380862)
			(xy 297.568618 -194.32524) (xy 293.090238 -194.32524) (xy 293.088001 -194.332677) (xy 293.064329 -194.383174)
			(xy 293.033556 -194.429687) (xy 292.996339 -194.471224) (xy 292.953471 -194.506899) (xy 292.905865 -194.535953)
			(xy 292.854536 -194.557765) (xy 292.800579 -194.571871) (xy 292.745142 -194.577971) (xy 292.689408 -194.575934)
			(xy 292.634565 -194.565804) (xy 292.581781 -194.547797) (xy 292.532181 -194.522296) (xy 292.486823 -194.489845)
			(xy 292.446674 -194.451136) (xy 292.412588 -194.406993) (xy 292.385292 -194.358358) (xy 292.365369 -194.306267)
			(xy 292.353243 -194.25183) (xy 292.349172 -194.196208) (xy 283.675471 -194.196208) (xy 283.80797 -194.587622)
			(xy 291.074854 -194.587622) (xy 291.078925 -194.532) (xy 291.091051 -194.477563) (xy 291.110974 -194.425472)
			(xy 291.13827 -194.376837) (xy 291.172356 -194.332694) (xy 291.212505 -194.293985) (xy 291.257863 -194.261534)
			(xy 291.307463 -194.236033) (xy 291.360247 -194.218026) (xy 291.41509 -194.207896) (xy 291.470824 -194.205859)
			(xy 291.526261 -194.211959) (xy 291.580218 -194.226065) (xy 291.631547 -194.247877) (xy 291.679153 -194.276931)
			(xy 291.722021 -194.312606) (xy 291.759238 -194.354143) (xy 291.790011 -194.400656) (xy 291.813683 -194.451153)
			(xy 291.829751 -194.50456) (xy 291.837871 -194.559736) (xy 291.83838 -194.587622) (xy 291.837871 -194.615508)
			(xy 291.829751 -194.670684) (xy 291.813683 -194.724091) (xy 291.790011 -194.774588) (xy 291.759238 -194.821101)
			(xy 291.722021 -194.862638) (xy 291.679153 -194.898313) (xy 291.631547 -194.927367) (xy 291.580218 -194.949179)
			(xy 291.526261 -194.963285) (xy 291.470824 -194.969385) (xy 291.41509 -194.967348) (xy 291.360247 -194.957218)
			(xy 291.307463 -194.939211) (xy 291.257863 -194.91371) (xy 291.212505 -194.881259) (xy 291.172356 -194.84255)
			(xy 291.13827 -194.798407) (xy 291.110974 -194.749772) (xy 291.091051 -194.697681) (xy 291.078925 -194.643244)
			(xy 291.074854 -194.587622) (xy 283.80797 -194.587622) (xy 284.293859 -196.022976) (xy 297.965112 -196.022976)
			(xy 297.969183 -195.967354) (xy 297.981309 -195.912917) (xy 298.001232 -195.860826) (xy 298.028528 -195.812191)
			(xy 298.062614 -195.768048) (xy 298.102763 -195.729339) (xy 298.148121 -195.696888) (xy 298.197721 -195.671387)
			(xy 298.250505 -195.65338) (xy 298.305348 -195.64325) (xy 298.361082 -195.641213) (xy 298.416519 -195.647313)
			(xy 298.470476 -195.661419) (xy 298.521805 -195.683231) (xy 298.569411 -195.712285) (xy 298.612279 -195.74796)
			(xy 298.649496 -195.789497) (xy 298.680269 -195.83601) (xy 298.703941 -195.886507) (xy 298.720009 -195.939914)
			(xy 298.728129 -195.99509) (xy 298.728638 -196.022976) (xy 298.728129 -196.050862) (xy 298.720009 -196.106038)
			(xy 298.703941 -196.159445) (xy 298.680269 -196.209942) (xy 298.649496 -196.256455) (xy 298.612279 -196.297992)
			(xy 298.569411 -196.333667) (xy 298.521805 -196.362721) (xy 298.470476 -196.384533) (xy 298.416519 -196.398639)
			(xy 298.361082 -196.404739) (xy 298.305348 -196.402702) (xy 298.250505 -196.392572) (xy 298.197721 -196.374565)
			(xy 298.148121 -196.349064) (xy 298.102763 -196.316613) (xy 298.062614 -196.277904) (xy 298.028528 -196.233761)
			(xy 298.001232 -196.185126) (xy 297.981309 -196.133035) (xy 297.969183 -196.078598) (xy 297.965112 -196.022976)
			(xy 284.293859 -196.022976) (xy 285.954359 -200.928224) (xy 292.89959 -200.928224) (xy 292.903661 -200.872602)
			(xy 292.915787 -200.818165) (xy 292.93571 -200.766074) (xy 292.963006 -200.717439) (xy 292.997092 -200.673296)
			(xy 293.037241 -200.634587) (xy 293.082599 -200.602136) (xy 293.132199 -200.576635) (xy 293.184983 -200.558628)
			(xy 293.239826 -200.548498) (xy 293.29556 -200.546461) (xy 293.350997 -200.552561) (xy 293.404954 -200.566667)
			(xy 293.456283 -200.588479) (xy 293.503889 -200.617533) (xy 293.546757 -200.653208) (xy 293.583974 -200.694745)
			(xy 293.614747 -200.741258) (xy 293.638419 -200.791755) (xy 293.654487 -200.845162) (xy 293.662607 -200.900338)
			(xy 293.663116 -200.928224) (xy 293.662607 -200.95611) (xy 293.654487 -201.011286) (xy 293.638419 -201.064693)
			(xy 293.636785 -201.068178) (xy 295.508932 -201.068178) (xy 295.513003 -201.012556) (xy 295.525129 -200.958119)
			(xy 295.545052 -200.906028) (xy 295.572348 -200.857393) (xy 295.606434 -200.81325) (xy 295.646583 -200.774541)
			(xy 295.691941 -200.74209) (xy 295.741541 -200.716589) (xy 295.794325 -200.698582) (xy 295.849168 -200.688452)
			(xy 295.904902 -200.686415) (xy 295.960339 -200.692515) (xy 296.014296 -200.706621) (xy 296.065625 -200.728433)
			(xy 296.113231 -200.757487) (xy 296.156099 -200.793162) (xy 296.193316 -200.834699) (xy 296.224089 -200.881212)
			(xy 296.247761 -200.931709) (xy 296.263829 -200.985116) (xy 296.271949 -201.040292) (xy 296.272458 -201.068178)
			(xy 296.271949 -201.096064) (xy 296.263829 -201.15124) (xy 296.263754 -201.15149) (xy 296.72102 -201.15149)
			(xy 296.725091 -201.095868) (xy 296.737217 -201.041431) (xy 296.75714 -200.98934) (xy 296.784436 -200.940705)
			(xy 296.818522 -200.896562) (xy 296.858671 -200.857853) (xy 296.904029 -200.825402) (xy 296.953629 -200.799901)
			(xy 297.006413 -200.781894) (xy 297.061256 -200.771764) (xy 297.11699 -200.769727) (xy 297.172427 -200.775827)
			(xy 297.226384 -200.789933) (xy 297.277713 -200.811745) (xy 297.325319 -200.840799) (xy 297.368187 -200.876474)
			(xy 297.405404 -200.918011) (xy 297.436177 -200.964524) (xy 297.459849 -201.015021) (xy 297.475917 -201.068428)
			(xy 297.484037 -201.123604) (xy 297.484546 -201.15149) (xy 297.484037 -201.179376) (xy 297.475917 -201.234552)
			(xy 297.459849 -201.287959) (xy 297.436177 -201.338456) (xy 297.405404 -201.384969) (xy 297.368187 -201.426506)
			(xy 297.325319 -201.462181) (xy 297.277713 -201.491235) (xy 297.226384 -201.513047) (xy 297.172427 -201.527153)
			(xy 297.11699 -201.533253) (xy 297.061256 -201.531216) (xy 297.006413 -201.521086) (xy 296.953629 -201.503079)
			(xy 296.904029 -201.477578) (xy 296.858671 -201.445127) (xy 296.818522 -201.406418) (xy 296.784436 -201.362275)
			(xy 296.75714 -201.31364) (xy 296.737217 -201.261549) (xy 296.725091 -201.207112) (xy 296.72102 -201.15149)
			(xy 296.263754 -201.15149) (xy 296.247761 -201.204647) (xy 296.224089 -201.255144) (xy 296.193316 -201.301657)
			(xy 296.156099 -201.343194) (xy 296.113231 -201.378869) (xy 296.065625 -201.407923) (xy 296.014296 -201.429735)
			(xy 295.960339 -201.443841) (xy 295.904902 -201.449941) (xy 295.849168 -201.447904) (xy 295.794325 -201.437774)
			(xy 295.741541 -201.419767) (xy 295.691941 -201.394266) (xy 295.646583 -201.361815) (xy 295.606434 -201.323106)
			(xy 295.572348 -201.278963) (xy 295.545052 -201.230328) (xy 295.525129 -201.178237) (xy 295.513003 -201.1238)
			(xy 295.508932 -201.068178) (xy 293.636785 -201.068178) (xy 293.614747 -201.11519) (xy 293.583974 -201.161703)
			(xy 293.546757 -201.20324) (xy 293.503889 -201.238915) (xy 293.456283 -201.267969) (xy 293.404954 -201.289781)
			(xy 293.350997 -201.303887) (xy 293.29556 -201.309987) (xy 293.239826 -201.30795) (xy 293.184983 -201.29782)
			(xy 293.132199 -201.279813) (xy 293.082599 -201.254312) (xy 293.037241 -201.221861) (xy 292.997092 -201.183152)
			(xy 292.963006 -201.139009) (xy 292.93571 -201.090374) (xy 292.915787 -201.038283) (xy 292.903661 -200.983846)
			(xy 292.89959 -200.928224) (xy 285.954359 -200.928224) (xy 287.036538 -204.125068) (xy 290.679122 -204.125068)
			(xy 290.683193 -204.069446) (xy 290.695319 -204.015009) (xy 290.715242 -203.962918) (xy 290.742538 -203.914283)
			(xy 290.776624 -203.87014) (xy 290.816773 -203.831431) (xy 290.862131 -203.79898) (xy 290.911731 -203.773479)
			(xy 290.964515 -203.755472) (xy 291.019358 -203.745342) (xy 291.075092 -203.743305) (xy 291.130529 -203.749405)
			(xy 291.184486 -203.763511) (xy 291.235815 -203.785323) (xy 291.283421 -203.814377) (xy 291.326289 -203.850052)
			(xy 291.363506 -203.891589) (xy 291.392781 -203.935838) (xy 292.984172 -203.935838) (xy 292.988243 -203.880216)
			(xy 293.000369 -203.825779) (xy 293.020292 -203.773688) (xy 293.047588 -203.725053) (xy 293.081674 -203.68091)
			(xy 293.121823 -203.642201) (xy 293.167181 -203.60975) (xy 293.216781 -203.584249) (xy 293.269565 -203.566242)
			(xy 293.324408 -203.556112) (xy 293.380142 -203.554075) (xy 293.435579 -203.560175) (xy 293.489536 -203.574281)
			(xy 293.540865 -203.596093) (xy 293.588471 -203.625147) (xy 293.631339 -203.660822) (xy 293.668556 -203.702359)
			(xy 293.699329 -203.748872) (xy 293.712199 -203.776326) (xy 295.45991 -203.776326) (xy 295.463981 -203.720704)
			(xy 295.476107 -203.666267) (xy 295.49603 -203.614176) (xy 295.523326 -203.565541) (xy 295.557412 -203.521398)
			(xy 295.597561 -203.482689) (xy 295.642919 -203.450238) (xy 295.692519 -203.424737) (xy 295.745303 -203.40673)
			(xy 295.800146 -203.3966) (xy 295.85588 -203.394563) (xy 295.911317 -203.400663) (xy 295.965274 -203.414769)
			(xy 296.016603 -203.436581) (xy 296.064209 -203.465635) (xy 296.107077 -203.50131) (xy 296.144294 -203.542847)
			(xy 296.175067 -203.58936) (xy 296.198739 -203.639857) (xy 296.214807 -203.693264) (xy 296.222927 -203.74844)
			(xy 296.223436 -203.776326) (xy 296.222927 -203.804212) (xy 296.214807 -203.859388) (xy 296.202352 -203.900786)
			(xy 297.59097 -203.900786) (xy 297.595041 -203.845164) (xy 297.607167 -203.790727) (xy 297.62709 -203.738636)
			(xy 297.654386 -203.690001) (xy 297.688472 -203.645858) (xy 297.728621 -203.607149) (xy 297.773979 -203.574698)
			(xy 297.823579 -203.549197) (xy 297.876363 -203.53119) (xy 297.931206 -203.52106) (xy 297.98694 -203.519023)
			(xy 298.042377 -203.525123) (xy 298.096334 -203.539229) (xy 298.147663 -203.561041) (xy 298.195269 -203.590095)
			(xy 298.238137 -203.62577) (xy 298.275354 -203.667307) (xy 298.306127 -203.71382) (xy 298.329799 -203.764317)
			(xy 298.345867 -203.817724) (xy 298.353987 -203.8729) (xy 298.354496 -203.900786) (xy 298.353987 -203.928672)
			(xy 298.345867 -203.983848) (xy 298.329799 -204.037255) (xy 298.306127 -204.087752) (xy 298.275354 -204.134265)
			(xy 298.238137 -204.175802) (xy 298.195269 -204.211477) (xy 298.147663 -204.240531) (xy 298.096334 -204.262343)
			(xy 298.042377 -204.276449) (xy 297.98694 -204.282549) (xy 297.931206 -204.280512) (xy 297.876363 -204.270382)
			(xy 297.823579 -204.252375) (xy 297.773979 -204.226874) (xy 297.728621 -204.194423) (xy 297.688472 -204.155714)
			(xy 297.654386 -204.111571) (xy 297.62709 -204.062936) (xy 297.607167 -204.010845) (xy 297.595041 -203.956408)
			(xy 297.59097 -203.900786) (xy 296.202352 -203.900786) (xy 296.198739 -203.912795) (xy 296.175067 -203.963292)
			(xy 296.144294 -204.009805) (xy 296.107077 -204.051342) (xy 296.064209 -204.087017) (xy 296.016603 -204.116071)
			(xy 295.965274 -204.137883) (xy 295.911317 -204.151989) (xy 295.85588 -204.158089) (xy 295.800146 -204.156052)
			(xy 295.745303 -204.145922) (xy 295.692519 -204.127915) (xy 295.642919 -204.102414) (xy 295.597561 -204.069963)
			(xy 295.557412 -204.031254) (xy 295.523326 -203.987111) (xy 295.49603 -203.938476) (xy 295.476107 -203.886385)
			(xy 295.463981 -203.831948) (xy 295.45991 -203.776326) (xy 293.712199 -203.776326) (xy 293.723001 -203.799369)
			(xy 293.739069 -203.852776) (xy 293.747189 -203.907952) (xy 293.747698 -203.935838) (xy 293.747189 -203.963724)
			(xy 293.739069 -204.0189) (xy 293.723001 -204.072307) (xy 293.699329 -204.122804) (xy 293.668556 -204.169317)
			(xy 293.631339 -204.210854) (xy 293.588471 -204.246529) (xy 293.540865 -204.275583) (xy 293.489536 -204.297395)
			(xy 293.435579 -204.311501) (xy 293.380142 -204.317601) (xy 293.324408 -204.315564) (xy 293.269565 -204.305434)
			(xy 293.216781 -204.287427) (xy 293.167181 -204.261926) (xy 293.121823 -204.229475) (xy 293.081674 -204.190766)
			(xy 293.047588 -204.146623) (xy 293.020292 -204.097988) (xy 293.000369 -204.045897) (xy 292.988243 -203.99146)
			(xy 292.984172 -203.935838) (xy 291.392781 -203.935838) (xy 291.394279 -203.938102) (xy 291.417951 -203.988599)
			(xy 291.434019 -204.042006) (xy 291.442139 -204.097182) (xy 291.442648 -204.125068) (xy 291.442139 -204.152954)
			(xy 291.434019 -204.20813) (xy 291.417951 -204.261537) (xy 291.394279 -204.312034) (xy 291.363506 -204.358547)
			(xy 291.326289 -204.400084) (xy 291.283421 -204.435759) (xy 291.235815 -204.464813) (xy 291.184486 -204.486625)
			(xy 291.130529 -204.500731) (xy 291.075092 -204.506831) (xy 291.019358 -204.504794) (xy 290.964515 -204.494664)
			(xy 290.911731 -204.476657) (xy 290.862131 -204.451156) (xy 290.816773 -204.418705) (xy 290.776624 -204.379996)
			(xy 290.742538 -204.335853) (xy 290.715242 -204.287218) (xy 290.695319 -204.235127) (xy 290.683193 -204.18069)
			(xy 290.679122 -204.125068) (xy 287.036538 -204.125068) (xy 287.853375 -206.538068) (xy 292.603172 -206.538068)
			(xy 292.607243 -206.482446) (xy 292.619369 -206.428009) (xy 292.639292 -206.375918) (xy 292.666588 -206.327283)
			(xy 292.700674 -206.28314) (xy 292.740823 -206.244431) (xy 292.786181 -206.21198) (xy 292.835781 -206.186479)
			(xy 292.888565 -206.168472) (xy 292.943408 -206.158342) (xy 292.999142 -206.156305) (xy 293.054579 -206.162405)
			(xy 293.108536 -206.176511) (xy 293.159865 -206.198323) (xy 293.207471 -206.227377) (xy 293.250339 -206.263052)
			(xy 293.287556 -206.304589) (xy 293.318329 -206.351102) (xy 293.342001 -206.401599) (xy 293.358069 -206.455006)
			(xy 293.366189 -206.510182) (xy 293.366698 -206.538068) (xy 293.366189 -206.565954) (xy 293.358069 -206.62113)
			(xy 293.342001 -206.674537) (xy 293.318329 -206.725034) (xy 293.287556 -206.771547) (xy 293.250339 -206.813084)
			(xy 293.207471 -206.848759) (xy 293.159865 -206.877813) (xy 293.108536 -206.899625) (xy 293.054579 -206.913731)
			(xy 292.999142 -206.919831) (xy 292.943408 -206.917794) (xy 292.888565 -206.907664) (xy 292.835781 -206.889657)
			(xy 292.786181 -206.864156) (xy 292.740823 -206.831705) (xy 292.700674 -206.792996) (xy 292.666588 -206.748853)
			(xy 292.639292 -206.700218) (xy 292.619369 -206.648127) (xy 292.607243 -206.59369) (xy 292.603172 -206.538068)
			(xy 287.853375 -206.538068) (xy 290.520991 -214.418418) (xy 294.647872 -214.418418) (xy 294.651943 -214.362796)
			(xy 294.664069 -214.308359) (xy 294.683992 -214.256268) (xy 294.711288 -214.207633) (xy 294.745374 -214.16349)
			(xy 294.785523 -214.124781) (xy 294.830881 -214.09233) (xy 294.880481 -214.066829) (xy 294.933265 -214.048822)
			(xy 294.988108 -214.038692) (xy 295.043842 -214.036655) (xy 295.099279 -214.042755) (xy 295.153236 -214.056861)
			(xy 295.204565 -214.078673) (xy 295.252171 -214.107727) (xy 295.295039 -214.143402) (xy 295.332256 -214.184939)
			(xy 295.363029 -214.231452) (xy 295.386701 -214.281949) (xy 295.402769 -214.335356) (xy 295.410889 -214.390532)
			(xy 295.411398 -214.418418) (xy 295.410889 -214.446304) (xy 295.402769 -214.50148) (xy 295.386701 -214.554887)
			(xy 295.363029 -214.605384) (xy 295.332256 -214.651897) (xy 295.295039 -214.693434) (xy 295.252171 -214.729109)
			(xy 295.204565 -214.758163) (xy 295.153236 -214.779975) (xy 295.099279 -214.794081) (xy 295.043842 -214.800181)
			(xy 294.988108 -214.798144) (xy 294.933265 -214.788014) (xy 294.880481 -214.770007) (xy 294.830881 -214.744506)
			(xy 294.785523 -214.712055) (xy 294.745374 -214.673346) (xy 294.711288 -214.629203) (xy 294.683992 -214.580568)
			(xy 294.664069 -214.528477) (xy 294.651943 -214.47404) (xy 294.647872 -214.418418) (xy 290.520991 -214.418418)
			(xy 290.900519 -215.539574) (xy 292.538148 -215.539574) (xy 292.542219 -215.483952) (xy 292.554345 -215.429515)
			(xy 292.574268 -215.377424) (xy 292.601564 -215.328789) (xy 292.63565 -215.284646) (xy 292.675799 -215.245937)
			(xy 292.721157 -215.213486) (xy 292.770757 -215.187985) (xy 292.823541 -215.169978) (xy 292.878384 -215.159848)
			(xy 292.934118 -215.157811) (xy 292.989555 -215.163911) (xy 293.043512 -215.178017) (xy 293.094841 -215.199829)
			(xy 293.142447 -215.228883) (xy 293.185315 -215.264558) (xy 293.222532 -215.306095) (xy 293.253305 -215.352608)
			(xy 293.276977 -215.403105) (xy 293.293045 -215.456512) (xy 293.301165 -215.511688) (xy 293.301674 -215.539574)
			(xy 293.301165 -215.56746) (xy 293.293045 -215.622636) (xy 293.276977 -215.676043) (xy 293.253305 -215.72654)
			(xy 293.222532 -215.773053) (xy 293.185315 -215.81459) (xy 293.142447 -215.850265) (xy 293.094841 -215.879319)
			(xy 293.043512 -215.901131) (xy 292.989555 -215.915237) (xy 292.934118 -215.921337) (xy 292.878384 -215.9193)
			(xy 292.823541 -215.90917) (xy 292.770757 -215.891163) (xy 292.721157 -215.865662) (xy 292.675799 -215.833211)
			(xy 292.63565 -215.794502) (xy 292.601564 -215.750359) (xy 292.574268 -215.701724) (xy 292.554345 -215.649633)
			(xy 292.542219 -215.595196) (xy 292.538148 -215.539574) (xy 290.900519 -215.539574) (xy 291.089079 -216.096596)
			(xy 295.167048 -216.096596) (xy 295.171119 -216.040974) (xy 295.183245 -215.986537) (xy 295.203168 -215.934446)
			(xy 295.230464 -215.885811) (xy 295.26455 -215.841668) (xy 295.304699 -215.802959) (xy 295.350057 -215.770508)
			(xy 295.399657 -215.745007) (xy 295.452441 -215.727) (xy 295.507284 -215.71687) (xy 295.563018 -215.714833)
			(xy 295.618455 -215.720933) (xy 295.672412 -215.735039) (xy 295.723741 -215.756851) (xy 295.771347 -215.785905)
			(xy 295.814215 -215.82158) (xy 295.851432 -215.863117) (xy 295.882205 -215.90963) (xy 295.905877 -215.960127)
			(xy 295.921945 -216.013534) (xy 295.930065 -216.06871) (xy 295.930574 -216.096596) (xy 295.930065 -216.124482)
			(xy 295.921945 -216.179658) (xy 295.905877 -216.233065) (xy 295.882205 -216.283562) (xy 295.851432 -216.330075)
			(xy 295.814215 -216.371612) (xy 295.771347 -216.407287) (xy 295.723741 -216.436341) (xy 295.672412 -216.458153)
			(xy 295.618455 -216.472259) (xy 295.563018 -216.478359) (xy 295.507284 -216.476322) (xy 295.452441 -216.466192)
			(xy 295.399657 -216.448185) (xy 295.350057 -216.422684) (xy 295.304699 -216.390233) (xy 295.26455 -216.351524)
			(xy 295.230464 -216.307381) (xy 295.203168 -216.258746) (xy 295.183245 -216.206655) (xy 295.171119 -216.152218)
			(xy 295.167048 -216.096596) (xy 291.089079 -216.096596) (xy 292.665316 -220.752924) (xy 294.22928 -220.752924)
			(xy 294.233351 -220.697302) (xy 294.245477 -220.642865) (xy 294.2654 -220.590774) (xy 294.292696 -220.542139)
			(xy 294.326782 -220.497996) (xy 294.366931 -220.459287) (xy 294.412289 -220.426836) (xy 294.461889 -220.401335)
			(xy 294.514673 -220.383328) (xy 294.569516 -220.373198) (xy 294.62525 -220.371161) (xy 294.680687 -220.377261)
			(xy 294.734644 -220.391367) (xy 294.785973 -220.413179) (xy 294.833579 -220.442233) (xy 294.876447 -220.477908)
			(xy 294.913664 -220.519445) (xy 294.944437 -220.565958) (xy 294.968109 -220.616455) (xy 294.984177 -220.669862)
			(xy 294.992297 -220.725038) (xy 294.992806 -220.752924) (xy 294.992297 -220.78081) (xy 294.984177 -220.835986)
			(xy 294.968109 -220.889393) (xy 294.944437 -220.93989) (xy 294.913664 -220.986403) (xy 294.876447 -221.02794)
			(xy 294.833579 -221.063615) (xy 294.785973 -221.092669) (xy 294.734644 -221.114481) (xy 294.680687 -221.128587)
			(xy 294.62525 -221.134687) (xy 294.569516 -221.13265) (xy 294.514673 -221.12252) (xy 294.461889 -221.104513)
			(xy 294.412289 -221.079012) (xy 294.366931 -221.046561) (xy 294.326782 -221.007852) (xy 294.292696 -220.963709)
			(xy 294.2654 -220.915074) (xy 294.245477 -220.862983) (xy 294.233351 -220.808546) (xy 294.22928 -220.752924)
			(xy 292.665316 -220.752924) (xy 301.147604 -245.810278) (xy 302.187608 -245.810278) (xy 302.191679 -245.754656)
			(xy 302.203805 -245.700219) (xy 302.223728 -245.648128) (xy 302.251024 -245.599493) (xy 302.28511 -245.55535)
			(xy 302.325259 -245.516641) (xy 302.370617 -245.48419) (xy 302.420217 -245.458689) (xy 302.473001 -245.440682)
			(xy 302.527844 -245.430552) (xy 302.583578 -245.428515) (xy 302.639015 -245.434615) (xy 302.692972 -245.448721)
			(xy 302.744301 -245.470533) (xy 302.791907 -245.499587) (xy 302.834775 -245.535262) (xy 302.871992 -245.576799)
			(xy 302.902765 -245.623312) (xy 302.926437 -245.673809) (xy 302.942505 -245.727216) (xy 302.950625 -245.782392)
			(xy 302.951134 -245.810278) (xy 302.950625 -245.838164) (xy 302.942505 -245.89334) (xy 302.926437 -245.946747)
			(xy 302.902765 -245.997244) (xy 302.871992 -246.043757) (xy 302.834775 -246.085294) (xy 302.791907 -246.120969)
			(xy 302.744301 -246.150023) (xy 302.692972 -246.171835) (xy 302.639015 -246.185941) (xy 302.583578 -246.192041)
			(xy 302.527844 -246.190004) (xy 302.473001 -246.179874) (xy 302.420217 -246.161867) (xy 302.370617 -246.136366)
			(xy 302.325259 -246.103915) (xy 302.28511 -246.065206) (xy 302.251024 -246.021063) (xy 302.223728 -245.972428)
			(xy 302.203805 -245.920337) (xy 302.191679 -245.8659) (xy 302.187608 -245.810278) (xy 301.147604 -245.810278)
			(xy 302.693832 -250.37796) (xy 302.72101 -250.39701) (xy 302.737774 -250.396502) (xy 302.749458 -250.396248)
			(xy 302.749966 -250.396248) (xy 302.777206 -250.396752) (xy 302.831127 -250.404539) (xy 302.883393 -250.419917)
			(xy 302.932939 -250.442572) (xy 302.978759 -250.472045) (xy 303.019921 -250.507736) (xy 303.055588 -250.548919)
			(xy 303.085034 -250.594756) (xy 303.107661 -250.644316) (xy 303.123008 -250.69659) (xy 303.130764 -250.750516)
			(xy 303.13122 -250.777756) (xy 303.13079 -250.80364) (xy 303.12379 -250.854934) (xy 303.109913 -250.904808)
			(xy 303.089415 -250.952346) (xy 303.062672 -250.996672) (xy 303.030176 -251.036971) (xy 302.992526 -251.072503)
			(xy 302.971708 -251.08789) (xy 302.958246 -251.097796) (xy 302.948086 -251.129292) (xy 303.66716 -253.253494)
			(xy 303.670827 -253.262794) (xy 303.683985 -253.277816) (xy 303.701887 -253.286665) (xy 303.721813 -253.287996)
			(xy 303.731422 -253.285244) (xy 303.731676 -253.285244) (xy 303.73193 -253.28499) (xy 303.762858 -253.274676)
			(xy 303.827096 -253.263562) (xy 303.859692 -253.262892) (xy 303.8602 -253.262892) (xy 303.887451 -253.263378)
			(xy 303.941399 -253.271134) (xy 303.993694 -253.286489) (xy 304.043271 -253.309131) (xy 304.089121 -253.338597)
			(xy 304.130312 -253.374288) (xy 304.166003 -253.415479) (xy 304.195469 -253.461329) (xy 304.218111 -253.510906)
			(xy 304.233466 -253.563201) (xy 304.241222 -253.617149) (xy 304.241708 -253.6444) (xy 304.241297 -253.669715)
			(xy 304.234613 -253.719901) (xy 304.221361 -253.768766) (xy 304.201773 -253.815453) (xy 304.176193 -253.859145)
			(xy 304.160936 -253.87935) (xy 304.154078 -253.891034) (xy 304.143885 -253.914102) (xy 304.118299 -253.957563)
			(xy 304.087209 -253.997273) (xy 304.051158 -254.03254) (xy 304.010774 -254.06275) (xy 303.988978 -254.075438)
			(xy 303.97323 -254.084074) (xy 303.960022 -254.118364) (xy 304.744374 -256.435098) (xy 304.771806 -256.454148)
			(xy 304.785522 -256.45364) (xy 304.801524 -256.453386) (xy 304.802032 -256.453386) (xy 304.829282 -256.453874)
			(xy 304.883226 -256.461634) (xy 304.935518 -256.476992) (xy 304.985091 -256.499635) (xy 305.030938 -256.529102)
			(xy 305.072125 -256.564793) (xy 305.107814 -256.605983) (xy 305.137278 -256.651832) (xy 305.159917 -256.701407)
			(xy 305.175271 -256.753699) (xy 305.183028 -256.807644) (xy 305.18354 -256.834894) (xy 305.183001 -256.864233)
			(xy 305.174014 -256.922219) (xy 305.15625 -256.978144) (xy 305.130129 -257.030687) (xy 305.096268 -257.078609)
			(xy 305.055465 -257.120779) (xy 305.03241 -257.138932) (xy 305.03114 -257.139948) (xy 305.024756 -257.14554)
			(xy 305.015788 -257.159939) (xy 305.013614 -257.168142) (xy 305.00574 -257.2004) (xy 305.00574 -257.200654)
			(xy 305.004724 -257.204718) (xy 305.00828 -257.215386) (xy 305.019456 -257.228848) (xy 305.03563 -257.249344)
			(xy 305.062809 -257.293923) (xy 305.083649 -257.341795) (xy 305.097759 -257.392064) (xy 305.104874 -257.443788)
			(xy 305.105308 -257.469894) (xy 305.1048 -257.48996) (xy 305.104292 -257.49885) (xy 305.485038 -258.62407)
			(xy 305.493674 -258.636008) (xy 305.4985 -258.639818) (xy 305.520013 -258.658049) (xy 305.557956 -258.699762)
			(xy 305.589348 -258.746603) (xy 305.613508 -258.797553) (xy 305.629909 -258.851504) (xy 305.638194 -258.90728)
			(xy 305.638708 -258.935474) (xy 305.638354 -258.957718) (xy 305.633139 -259.0019) (xy 305.628294 -259.023612)
			(xy 305.628294 -259.02412) (xy 305.62677 -259.03047) (xy 305.627532 -259.044186) (xy 305.886358 -259.80898)
			(xy 305.890263 -259.818797) (xy 305.904518 -259.834361) (xy 305.923814 -259.842908) (xy 305.934364 -259.843524)
			(xy 306.17287 -259.843524) (xy 306.183406 -259.84294) (xy 306.202687 -259.834416) (xy 306.210208 -259.827014)
			(xy 306.210462 -259.827014) (xy 306.217155 -259.818807) (xy 306.223834 -259.798735) (xy 306.223416 -259.788152)
			(xy 306.00142 -257.24993) (xy 305.999669 -257.23737) (xy 305.985817 -257.216167) (xy 305.975004 -257.209544)
			(xy 305.89982 -257.169412) (xy 305.888325 -257.164045) (xy 305.862991 -257.164168) (xy 305.85156 -257.169666)
			(xy 305.823339 -257.184358) (xy 305.763224 -257.205184) (xy 305.70049 -257.215767) (xy 305.66868 -257.216402)
			(xy 305.668426 -257.216402) (xy 305.641172 -257.21594) (xy 305.587219 -257.208187) (xy 305.534919 -257.192833)
			(xy 305.485337 -257.170192) (xy 305.439481 -257.140726) (xy 305.398286 -257.105032) (xy 305.36259 -257.06384)
			(xy 305.33312 -257.017986) (xy 305.310476 -256.968405) (xy 305.295119 -256.916106) (xy 305.287361 -256.862154)
			(xy 305.287361 -256.807646) (xy 305.295119 -256.753694) (xy 305.310476 -256.701395) (xy 305.33312 -256.651814)
			(xy 305.36259 -256.60596) (xy 305.398286 -256.564768) (xy 305.439481 -256.529074) (xy 305.485337 -256.499608)
			(xy 305.534919 -256.476967) (xy 305.587219 -256.461613) (xy 305.641172 -256.45386) (xy 305.668426 -256.453386)
			(xy 305.66868 -256.453386) (xy 305.699725 -256.454013) (xy 305.760994 -256.464089) (xy 305.7906 -256.473452)
			(xy 305.798688 -256.475919) (xy 305.815588 -256.475906) (xy 305.831546 -256.470341) (xy 305.838352 -256.465324)
			(xy 305.905154 -256.412746) (xy 305.911642 -256.407317) (xy 305.920871 -256.393151) (xy 305.924938 -256.376741)
			(xy 305.924458 -256.368296) (xy 305.712876 -253.95301) (xy 305.71173 -253.943965) (xy 305.703931 -253.9275)
			(xy 305.690859 -253.914809) (xy 305.68265 -253.910846) (xy 305.588162 -253.869698) (xy 305.560476 -253.873254)
			(xy 305.549554 -253.881636) (xy 305.529378 -253.896834) (xy 305.48578 -253.922344) (xy 305.439196 -253.941874)
			(xy 305.390441 -253.955084) (xy 305.340368 -253.961741) (xy 305.315112 -253.962154) (xy 305.287855 -253.961692)
			(xy 305.233896 -253.953935) (xy 305.181591 -253.938578) (xy 305.132003 -253.915934) (xy 305.086143 -253.886463)
			(xy 305.044944 -253.850765) (xy 305.009245 -253.809567) (xy 304.979772 -253.763707) (xy 304.957126 -253.71412)
			(xy 304.941767 -253.661815) (xy 304.934009 -253.607857) (xy 304.934009 -253.553343) (xy 304.941767 -253.499385)
			(xy 304.957126 -253.44708) (xy 304.979772 -253.397493) (xy 305.009245 -253.351633) (xy 305.044944 -253.310435)
			(xy 305.086143 -253.274737) (xy 305.132003 -253.245266) (xy 305.181591 -253.222622) (xy 305.233896 -253.207265)
			(xy 305.287855 -253.199508) (xy 305.315112 -253.199138) (xy 305.346104 -253.199765) (xy 305.407268 -253.209815)
			(xy 305.46601 -253.229603) (xy 305.493674 -253.243588) (xy 305.50612 -253.250192) (xy 305.533806 -253.248668)
			(xy 305.619912 -253.191772) (xy 305.627346 -253.186414) (xy 305.638107 -253.171598) (xy 305.642945 -253.153938)
			(xy 305.642518 -253.144782) (xy 305.061112 -246.50065) (xy 305.060604 -246.497094) (xy 304.324258 -241.874548)
			(xy 304.322064 -241.866288) (xy 304.31302 -241.8518) (xy 304.299691 -241.841121) (xy 304.291746 -241.837972)
			(xy 304.233326 -241.819684) (xy 304.200306 -241.809524) (xy 304.194536 -241.808275) (xy 304.182735 -241.808151)
			(xy 304.176938 -241.80927) (xy 304.173636 -241.810032) (xy 304.167574 -241.812011) (xy 304.156636 -241.81856)
			(xy 304.152046 -241.822986) (xy 304.15103 -241.824002) (xy 304.132934 -241.842566) (xy 304.092596 -241.875128)
			(xy 304.048222 -241.901931) (xy 304.000628 -241.922481) (xy 303.95069 -241.9364) (xy 303.899328 -241.943431)
			(xy 303.873408 -241.94389) (xy 303.846156 -241.943427) (xy 303.792207 -241.935672) (xy 303.73991 -241.920317)
			(xy 303.690332 -241.897676) (xy 303.64448 -241.86821) (xy 303.603288 -241.832518) (xy 303.567595 -241.791327)
			(xy 303.538128 -241.745475) (xy 303.515486 -241.695897) (xy 303.50013 -241.643601) (xy 303.492373 -241.589652)
			(xy 303.492373 -241.535148) (xy 303.50013 -241.481199) (xy 303.515486 -241.428903) (xy 303.538128 -241.379325)
			(xy 303.567595 -241.333473) (xy 303.603288 -241.292282) (xy 303.64448 -241.25659) (xy 303.690332 -241.227124)
			(xy 303.73991 -241.204483) (xy 303.792207 -241.189128) (xy 303.846156 -241.181373) (xy 303.873408 -241.180874)
			(xy 303.873916 -241.180874) (xy 303.904526 -241.1815) (xy 303.964954 -241.191318) (xy 304.023036 -241.210667)
			(xy 304.050446 -241.224308) (xy 304.056288 -241.227356) (xy 304.070258 -241.230658) (xy 304.075707 -241.231851)
			(xy 304.086856 -241.232097) (xy 304.092356 -241.231166) (xy 304.102516 -241.229134) (xy 304.111406 -241.222784)
			(xy 304.111914 -241.222784) (xy 304.183542 -241.172492) (xy 304.189892 -241.167158) (xy 304.190146 -241.166904)
			(xy 304.19826 -241.157862) (xy 304.205798 -241.134802) (xy 304.204624 -241.122708) (xy 304.046636 -240.12906)
			(xy 303.914556 -239.300004) (xy 303.912778 -239.288828) (xy 303.8983 -239.267492) (xy 303.891696 -239.259618)
			(xy 303.880012 -239.248188) (xy 303.875694 -239.245394) (xy 303.852994 -239.23022) (xy 303.811736 -239.194455)
			(xy 303.775988 -239.153182) (xy 303.746477 -239.107243) (xy 303.723804 -239.057571) (xy 303.708431 -239.005178)
			(xy 303.70067 -238.951131) (xy 303.70018 -238.92383) (xy 303.700625 -238.897105) (xy 303.708073 -238.844177)
			(xy 303.722829 -238.792804) (xy 303.744603 -238.74399) (xy 303.772971 -238.698689) (xy 303.789842 -238.677958)
			(xy 303.79543 -238.671354) (xy 303.80813 -238.637572) (xy 303.807622 -238.629952) (xy 303.22012 -234.940094)
			(xy 302.872648 -232.758234) (xy 302.871139 -232.750381) (xy 302.86388 -232.736141) (xy 302.858424 -232.730294)
			(xy 302.851058 -232.722928) (xy 302.840644 -232.715054) (xy 302.836072 -232.712514) (xy 302.810776 -232.697986)
			(xy 302.764516 -232.662452) (xy 302.724193 -232.6203) (xy 302.690746 -232.572509) (xy 302.66495 -232.520191)
			(xy 302.647404 -232.46456) (xy 302.638518 -232.406908) (xy 302.637952 -232.377742) (xy 302.637952 -232.377488)
			(xy 302.638482 -232.34857) (xy 302.647209 -232.291397) (xy 302.664476 -232.2362) (xy 302.689885 -232.184246)
			(xy 302.722855 -232.136728) (xy 302.742346 -232.11536) (xy 302.749458 -232.108248) (xy 302.758348 -232.084372)
			(xy 302.75911 -232.082086) (xy 302.760792 -232.076601) (xy 302.761957 -232.065189) (xy 302.761396 -232.05948)
			(xy 302.544988 -230.700326) (xy 302.539186 -230.661726) (xy 302.532957 -230.58391) (xy 302.532542 -230.544878)
			(xy 302.532542 -230.543354) (xy 302.532713 -230.521479) (xy 302.534744 -230.477775) (xy 302.536606 -230.455978)
			(xy 302.536606 -230.4542) (xy 302.537622 -230.44023) (xy 302.54448 -230.332534) (xy 302.555148 -230.167942)
			(xy 302.556672 -230.145336) (xy 302.575976 -229.844854) (xy 302.576738 -229.834186) (xy 302.565308 -229.802436)
			(xy 302.560228 -229.795832) (xy 302.545027 -229.775657) (xy 302.51951 -229.73206) (xy 302.499972 -229.685476)
			(xy 302.486754 -229.636721) (xy 302.480087 -229.586648) (xy 302.47971 -229.56139) (xy 302.47971 -229.561136)
			(xy 302.480282 -229.530939) (xy 302.489794 -229.471299) (xy 302.508587 -229.413904) (xy 302.53619 -229.360188)
			(xy 302.571914 -229.311493) (xy 302.592994 -229.289864) (xy 302.600106 -229.283006) (xy 302.60925 -229.261924)
			(xy 302.610012 -229.259892) (xy 302.611028 -229.257352) (xy 302.614584 -229.249224) (xy 302.617124 -229.211124)
			(xy 302.61941 -229.209092) (xy 302.618648 -229.183946) (xy 302.618648 -229.18039) (xy 302.61823 -229.170744)
			(xy 302.611107 -229.152816) (xy 302.597871 -229.138781) (xy 302.58039 -229.130622) (xy 302.561132 -229.129489)
			(xy 302.551846 -229.13213) (xy 302.54448 -229.13467) (xy 302.541432 -229.136702) (xy 302.51656 -229.154502)
			(xy 302.462335 -229.182783) (xy 302.404292 -229.202051) (xy 302.343919 -229.211814) (xy 302.31334 -229.212394)
			(xy 302.286086 -229.211933) (xy 302.232131 -229.204181) (xy 302.179829 -229.188828) (xy 302.130245 -229.166188)
			(xy 302.084388 -229.136721) (xy 302.043192 -229.101027) (xy 302.007495 -229.059833) (xy 301.978025 -229.013978)
			(xy 301.955381 -228.964395) (xy 301.940025 -228.912094) (xy 301.932268 -228.85814) (xy 301.931832 -228.830886)
			(xy 301.932297 -228.803945) (xy 301.939879 -228.7506) (xy 301.95489 -228.698851) (xy 301.977032 -228.649729)
			(xy 302.005864 -228.604211) (xy 302.040813 -228.563201) (xy 302.081184 -228.527516) (xy 302.126173 -228.497865)
			(xy 302.174886 -228.474838) (xy 302.226355 -228.458893) (xy 302.279554 -228.450347) (xy 302.306482 -228.449378)
			(xy 302.313848 -228.449378) (xy 302.34009 -228.449831) (xy 302.392075 -228.457055) (xy 302.44258 -228.471334)
			(xy 302.490653 -228.492397) (xy 302.513238 -228.505766) (xy 302.523741 -228.511559) (xy 302.547599 -228.51368)
			(xy 302.558958 -228.50983) (xy 302.561244 -228.508814) (xy 302.615854 -228.48062) (xy 302.616362 -228.48062)
			(xy 302.640746 -228.46792) (xy 302.646518 -228.464706) (xy 302.656299 -228.455833) (xy 302.66005 -228.450394)
			(xy 302.667162 -228.439472) (xy 302.667924 -228.42601) (xy 302.71212 -227.741988) (xy 302.88103 -225.126296)
			(xy 302.881248 -225.122197) (xy 302.880485 -225.114026) (xy 302.879506 -225.11004) (xy 302.879252 -225.109532)
			(xy 302.877576 -225.10374) (xy 302.871923 -225.093094) (xy 302.868076 -225.08845) (xy 302.822864 -225.03765)
			(xy 302.819415 -225.033989) (xy 302.811354 -225.027974) (xy 302.806862 -225.025712) (xy 302.797972 -225.021394)
			(xy 302.787558 -225.020886) (xy 302.761048 -225.01912) (xy 302.708853 -225.009196) (xy 302.658524 -224.992173)
			(xy 302.611022 -224.968375) (xy 302.567254 -224.938256) (xy 302.528055 -224.902392) (xy 302.494174 -224.861467)
			(xy 302.466257 -224.816263) (xy 302.444837 -224.767642) (xy 302.430324 -224.716533) (xy 302.422995 -224.663911)
			(xy 302.42256 -224.637346) (xy 302.423023 -224.60991) (xy 302.430827 -224.555595) (xy 302.446281 -224.502944)
			(xy 302.469072 -224.453028) (xy 302.498735 -224.406865) (xy 302.534666 -224.365393) (xy 302.576134 -224.329458)
			(xy 302.622295 -224.29979) (xy 302.672208 -224.276994) (xy 302.724858 -224.261535) (xy 302.779172 -224.253726)
			(xy 302.806608 -224.253298) (xy 302.837342 -224.254568) (xy 302.847756 -224.25533) (xy 302.856646 -224.252536)
			(xy 302.861575 -224.250826) (xy 302.870662 -224.245704) (xy 302.87468 -224.242376) (xy 302.928782 -224.194878)
			(xy 302.935076 -224.188105) (xy 302.942759 -224.171303) (xy 302.943768 -224.162112) (xy 303.002442 -223.255078)
			(xy 303.012856 -223.095312) (xy 303.012856 -223.087692) (xy 302.83277 -221.030546) (xy 302.810926 -221.0054)
			(xy 302.802544 -221.003622) (xy 302.774096 -220.997367) (xy 302.719386 -220.977387) (xy 302.668349 -220.949322)
			(xy 302.622172 -220.913824) (xy 302.581929 -220.871718) (xy 302.548554 -220.823984) (xy 302.522825 -220.77173)
			(xy 302.505339 -220.716173) (xy 302.496502 -220.658602) (xy 302.495966 -220.62948) (xy 302.496411 -220.602814)
			(xy 302.503839 -220.550003) (xy 302.518547 -220.49874) (xy 302.54025 -220.450024) (xy 302.568523 -220.404804)
			(xy 302.602816 -220.363961) (xy 302.642463 -220.32829) (xy 302.686689 -220.298487) (xy 302.734634 -220.275131)
			(xy 302.759872 -220.266514) (xy 302.760126 -220.266514) (xy 302.769517 -220.263099) (xy 302.784785 -220.25023)
			(xy 302.793946 -220.232488) (xy 302.795178 -220.222572) (xy 304.26279 -203.44384) (xy 304.258472 -203.433934)
			(xy 304.247403 -203.408814) (xy 304.231792 -203.35619) (xy 304.223903 -203.301868) (xy 304.22342 -203.274422)
			(xy 304.22342 -203.273914) (xy 304.223929 -203.245263) (xy 304.232473 -203.188601) (xy 304.249372 -203.133848)
			(xy 304.274247 -203.082227) (xy 304.289968 -203.058268) (xy 304.290222 -203.058014) (xy 304.293731 -203.052552)
			(xy 304.298108 -203.040333) (xy 304.298858 -203.033884) (xy 304.346864 -202.48372) (xy 304.346864 -202.482704)
			(xy 304.350674 -202.425554) (xy 304.362866 -202.2348) (xy 304.367692 -202.159362) (xy 304.372264 -202.089258)
			(xy 304.372264 -202.086718) (xy 304.372518 -202.073002) (xy 304.355246 -202.042014) (xy 304.349912 -202.034648)
			(xy 304.349658 -202.034394) (xy 304.343308 -202.027028) (xy 304.337212 -202.022964) (xy 304.314872 -202.007806)
			(xy 304.274301 -201.972189) (xy 304.23917 -201.931197) (xy 304.210183 -201.885653) (xy 304.187922 -201.836469)
			(xy 304.172834 -201.784634) (xy 304.165221 -201.731187) (xy 304.164746 -201.704194) (xy 304.165218 -201.676775)
			(xy 304.173051 -201.622499) (xy 304.188556 -201.569899) (xy 304.211414 -201.520052) (xy 304.241158 -201.473981)
			(xy 304.277176 -201.432631) (xy 304.318732 -201.396849) (xy 304.364972 -201.367369) (xy 304.38979 -201.355706)
			(xy 304.392584 -201.354436) (xy 304.398172 -201.351134) (xy 304.408234 -201.344194) (xy 304.420977 -201.323376)
			(xy 304.422556 -201.311256) (xy 304.422556 -201.311002) (xy 304.425096 -201.272394) (xy 304.425096 -201.271886)
			(xy 304.427128 -201.242422) (xy 304.427128 -201.241914) (xy 304.427636 -201.232008) (xy 304.427743 -201.227362)
			(xy 304.426469 -201.218159) (xy 304.425096 -201.21372) (xy 304.42154 -201.20229) (xy 304.415444 -201.1934)
			(xy 304.405284 -201.178668) (xy 304.40152 -201.173462) (xy 304.391875 -201.16498) (xy 304.386234 -201.161904)
			(xy 304.38344 -201.160634) (xy 304.382932 -201.16038) (xy 304.358705 -201.148461) (xy 304.313582 -201.118813)
			(xy 304.273086 -201.083103) (xy 304.238027 -201.042042) (xy 304.209102 -200.996452) (xy 304.186891 -200.94724)
			(xy 304.171835 -200.89539) (xy 304.164236 -200.841936) (xy 304.16373 -200.81494) (xy 304.164187 -200.788142)
			(xy 304.171694 -200.735073) (xy 304.186551 -200.683577) (xy 304.208467 -200.634666) (xy 304.23701 -200.589301)
			(xy 304.271619 -200.548376) (xy 304.311613 -200.512696) (xy 304.356205 -200.482961) (xy 304.404519 -200.459758)
			(xy 304.429922 -200.451212) (xy 304.435764 -200.44918) (xy 304.441005 -200.446579) (xy 304.450239 -200.439395)
			(xy 304.454052 -200.434956) (xy 304.47107 -200.414128) (xy 304.473363 -200.411271) (xy 304.47719 -200.405024)
			(xy 304.47869 -200.401682) (xy 304.481992 -200.393554) (xy 304.48377 -200.366122) (xy 304.491136 -200.251314)
			(xy 304.491362 -200.243142) (xy 304.487212 -200.227338) (xy 304.483008 -200.220326) (xy 304.47869 -200.213722)
			(xy 304.465736 -200.203308) (xy 304.458116 -200.200514) (xy 304.431132 -200.189912) (xy 304.38047 -200.161729)
			(xy 304.334654 -200.126205) (xy 304.294741 -200.084158) (xy 304.261649 -200.036557) (xy 304.236141 -199.984496)
			(xy 304.218802 -199.929176) (xy 304.210034 -199.871869) (xy 304.20945 -199.842882) (xy 304.209981 -199.814369)
			(xy 304.218469 -199.757978) (xy 304.235253 -199.703478) (xy 304.25996 -199.652082) (xy 304.292039 -199.604934)
			(xy 304.330776 -199.563084) (xy 304.37531 -199.527464) (xy 304.424647 -199.498867) (xy 304.47769 -199.477929)
			(xy 304.50536 -199.471026) (xy 304.505614 -199.471026) (xy 304.513534 -199.468883) (xy 304.527529 -199.460335)
			(xy 304.533046 -199.454262) (xy 304.538126 -199.44842) (xy 304.544222 -199.43318) (xy 304.550064 -199.34174)
			(xy 304.63998 -197.953884) (xy 304.670714 -197.477634) (xy 304.677318 -197.376288) (xy 304.679604 -197.341236)
			(xy 304.680874 -197.320154) (xy 304.849276 -194.720972) (xy 304.903124 -193.88836) (xy 305.049682 -191.622172)
			(xy 305.887628 -178.67757) (xy 305.89039 -178.639723) (xy 305.901003 -178.564578) (xy 305.917358 -178.49047)
			(xy 305.928014 -178.45405) (xy 307.589174 -172.983652) (xy 307.589682 -172.982128) (xy 308.147974 -170.898058)
			(xy 308.159669 -170.856136) (xy 308.189417 -170.774337) (xy 308.226191 -170.695446) (xy 308.247542 -170.65752)
			(xy 313.608466 -161.371788) (xy 313.608974 -161.346388) (xy 313.603132 -161.334958) (xy 313.590896 -161.309486)
			(xy 313.573221 -161.255814) (xy 313.563638 -161.200125) (xy 313.562492 -161.17189) (xy 313.562492 -161.157158)
			(xy 313.563391 -161.129958) (xy 313.571945 -161.076214) (xy 313.588046 -161.024231) (xy 313.611369 -160.975061)
			(xy 313.641439 -160.929703) (xy 313.677648 -160.889076) (xy 313.698128 -160.871154) (xy 313.705748 -160.864804)
			(xy 313.720734 -160.837372) (xy 313.724036 -160.828228) (xy 313.725052 -160.820862) (xy 313.725306 -160.818068)
			(xy 313.72683 -160.798764) (xy 313.72714 -160.792659) (xy 313.72522 -160.78059) (xy 313.72302 -160.774888)
			(xy 313.71286 -160.750758) (xy 313.70651 -160.7439) (xy 313.706256 -160.743646) (xy 313.685608 -160.720868)
			(xy 313.650708 -160.670256) (xy 313.623815 -160.614972) (xy 313.605542 -160.556273) (xy 313.596304 -160.495493)
			(xy 313.595766 -160.464754) (xy 313.596288 -160.435673) (xy 313.604571 -160.378104) (xy 313.620963 -160.3223)
			(xy 313.64513 -160.269397) (xy 313.676579 -160.220471) (xy 313.714671 -160.176519) (xy 313.75863 -160.138435)
			(xy 313.807562 -160.106994) (xy 313.86047 -160.082837) (xy 313.916277 -160.066456) (xy 313.973847 -160.058183)
			(xy 314.002928 -160.057592) (xy 314.007246 -160.057592) (xy 314.017121 -160.057127) (xy 314.035411 -160.049675)
			(xy 314.042806 -160.043114) (xy 314.064904 -160.021016) (xy 314.071141 -160.014151) (xy 314.078686 -159.997223)
			(xy 314.079636 -159.987996) (xy 314.081631 -159.961302) (xy 314.092158 -159.908819) (xy 314.109919 -159.858322)
			(xy 314.134564 -159.810805) (xy 314.165609 -159.767198) (xy 314.202445 -159.72836) (xy 314.223146 -159.71139)
			(xy 314.227718 -159.707834) (xy 314.23991 -159.698436) (xy 314.246006 -159.694372) (xy 314.247276 -159.69361)
			(xy 314.257944 -159.686752) (xy 314.25896 -159.686244) (xy 314.260992 -159.684974) (xy 314.265079 -159.68237)
			(xy 314.272249 -159.675851) (xy 314.275216 -159.67202) (xy 314.2869 -159.656272) (xy 314.289561 -159.652484)
			(xy 314.293647 -159.64418) (xy 314.295028 -159.639762) (xy 314.295536 -159.63773) (xy 314.303156 -159.60598)
			(xy 314.304426 -159.594296) (xy 314.304426 -159.553148) (xy 314.304275 -159.54728) (xy 314.301578 -159.535859)
			(xy 314.299092 -159.530542) (xy 314.296552 -159.525208) (xy 314.296044 -159.5247) (xy 314.288922 -159.511737)
			(xy 314.276465 -159.484909) (xy 314.271152 -159.471106) (xy 314.266948 -159.459629) (xy 314.259833 -159.436243)
			(xy 314.256928 -159.42437) (xy 314.256674 -159.422846) (xy 314.256166 -159.420814) (xy 314.25515 -159.415988)
			(xy 314.253136 -159.407807) (xy 314.24452 -159.393341) (xy 314.231648 -159.382486) (xy 314.223908 -159.379158)
			(xy 314.194444 -159.367728) (xy 314.182442 -159.363723) (xy 314.15736 -159.366772) (xy 314.146692 -159.37357)
			(xy 314.122381 -159.390106) (xy 314.069745 -159.416302) (xy 314.013716 -159.434119) (xy 313.955617 -159.443136)
			(xy 313.92622 -159.443674) (xy 313.898967 -159.443212) (xy 313.845016 -159.435457) (xy 313.792718 -159.420103)
			(xy 313.743137 -159.397461) (xy 313.697284 -159.367993) (xy 313.656092 -159.332299) (xy 313.620399 -159.291105)
			(xy 313.590933 -159.245251) (xy 313.568293 -159.195669) (xy 313.55294 -159.14337) (xy 313.545187 -159.089419)
			(xy 313.544712 -159.062166) (xy 313.545213 -159.033457) (xy 313.553787 -158.976683) (xy 313.570781 -158.921839)
			(xy 313.595811 -158.870164) (xy 313.628309 -158.822829) (xy 313.667541 -158.780905) (xy 313.689746 -158.7627)
			(xy 313.690254 -158.7627) (xy 313.690254 -158.762446) (xy 313.697202 -158.756371) (xy 313.706559 -158.740481)
			(xy 313.709646 -158.7223) (xy 313.708288 -158.71317) (xy 313.69127 -158.624524) (xy 313.689101 -158.615519)
			(xy 313.679362 -158.599779) (xy 313.664702 -158.588482) (xy 313.655964 -158.585408) (xy 313.630018 -158.577223)
			(xy 313.580573 -158.554526) (xy 313.534854 -158.525036) (xy 313.493786 -158.489352) (xy 313.458203 -158.448197)
			(xy 313.428825 -158.402405) (xy 313.406249 -158.352905) (xy 313.390931 -158.300701) (xy 313.383184 -158.24685)
			(xy 313.38266 -158.219648) (xy 313.383146 -158.192397) (xy 313.390902 -158.138449) (xy 313.406257 -158.086154)
			(xy 313.428899 -158.036577) (xy 313.458365 -157.990727) (xy 313.494056 -157.949536) (xy 313.535247 -157.913845)
			(xy 313.581097 -157.884379) (xy 313.630674 -157.861737) (xy 313.682969 -157.846382) (xy 313.736917 -157.838626)
			(xy 313.791419 -157.838626) (xy 313.845367 -157.846382) (xy 313.897662 -157.861737) (xy 313.947239 -157.884379)
			(xy 313.993089 -157.913845) (xy 314.03428 -157.949536) (xy 314.069971 -157.990727) (xy 314.099437 -158.036577)
			(xy 314.122079 -158.086154) (xy 314.137434 -158.138449) (xy 314.14519 -158.192397) (xy 314.145676 -158.219648)
			(xy 314.145174 -158.248356) (xy 314.136598 -158.305129) (xy 314.119602 -158.359972) (xy 314.094571 -158.411644)
			(xy 314.062071 -158.458977) (xy 314.022838 -158.500898) (xy 314.000642 -158.519114) (xy 314.000134 -158.519114)
			(xy 314.000134 -158.519368) (xy 313.993175 -158.52544) (xy 313.983793 -158.541331) (xy 313.980677 -158.55952)
			(xy 313.9821 -158.568644) (xy 313.999118 -158.65729) (xy 314.001288 -158.666295) (xy 314.011028 -158.682032)
			(xy 314.025688 -158.69333) (xy 314.034424 -158.696406) (xy 314.059953 -158.70443) (xy 314.108643 -158.726635)
			(xy 314.153751 -158.755426) (xy 314.194393 -158.79024) (xy 314.22977 -158.830392) (xy 314.259188 -158.875094)
			(xy 314.28207 -158.923469) (xy 314.290456 -158.948882) (xy 314.290456 -158.949136) (xy 314.29436 -158.959877)
			(xy 314.309963 -158.976547) (xy 314.320428 -158.98114) (xy 314.394342 -159.010096) (xy 314.405172 -159.013614)
			(xy 314.42785 -159.011897) (xy 314.43803 -159.006794) (xy 314.438284 -159.006794) (xy 314.460077 -158.994735)
			(xy 314.506121 -158.975743) (xy 314.554243 -158.962897) (xy 314.603627 -158.956415) (xy 314.62853 -158.955994)
			(xy 314.63742 -158.955994) (xy 314.6671 -158.957254) (xy 314.725554 -158.967828) (xy 314.781664 -158.987332)
			(xy 314.834074 -159.015294) (xy 314.858146 -159.032702) (xy 314.879228 -159.04972) (xy 314.882784 -159.052768)
			(xy 314.887102 -159.055308) (xy 314.895979 -159.059957) (xy 314.91583 -159.062583) (xy 314.935174 -159.057407)
			(xy 314.951062 -159.045219) (xy 314.956444 -159.036766) (xy 315.154056 -158.694374) (xy 315.155326 -158.68396)
			(xy 315.160217 -158.642794) (xy 315.175967 -158.561398) (xy 315.198415 -158.481589) (xy 315.227406 -158.403918)
			(xy 315.262742 -158.328919) (xy 315.283088 -158.2928) (xy 315.530992 -157.86354) (xy 315.551707 -157.828445)
			(xy 315.598061 -157.761408) (xy 315.649734 -157.698381) (xy 315.706382 -157.639785) (xy 315.736732 -157.612588)
			(xy 315.74281 -157.606875) (xy 315.751239 -157.592491) (xy 315.753242 -157.584394) (xy 315.76159 -157.544497)
			(xy 315.783967 -157.466109) (xy 315.812675 -157.389812) (xy 315.847521 -157.316116) (xy 315.867542 -157.28061)
			(xy 315.963046 -157.11551) (xy 315.967786 -157.106355) (xy 315.970281 -157.085909) (xy 315.967872 -157.075886)
			(xy 315.94679 -157.005274) (xy 315.943417 -156.995434) (xy 315.930182 -156.979416) (xy 315.921136 -156.974286)
			(xy 315.880035 -156.952704) (xy 315.801628 -156.902989) (xy 315.728178 -156.846207) (xy 315.660318 -156.78285)
			(xy 315.598635 -156.713464) (xy 315.543662 -156.638649) (xy 315.519308 -156.599128) (xy 315.516789 -156.595149)
			(xy 315.510522 -156.588121) (xy 315.506862 -156.585158) (xy 315.48424 -156.566972) (xy 315.444241 -156.524914)
			(xy 315.411074 -156.477282) (xy 315.385505 -156.425176) (xy 315.368124 -156.369798) (xy 315.359331 -156.312427)
			(xy 315.35878 -156.283406) (xy 315.35878 -156.282898) (xy 315.359295 -156.253596) (xy 315.368225 -156.195678)
			(xy 315.37656 -156.167582) (xy 315.377907 -156.163075) (xy 315.379055 -156.15374) (xy 315.378846 -156.14904)
			(xy 315.37796 -156.133244) (xy 315.37707 -156.101615) (xy 315.377068 -156.085794) (xy 315.377503 -156.043427)
			(xy 315.38469 -155.958997) (xy 315.39902 -155.875483) (xy 315.42039 -155.793487) (xy 315.448646 -155.713602)
			(xy 315.465714 -155.674822) (xy 315.469679 -155.66478) (xy 315.469677 -155.643209) (xy 315.465714 -155.633166)
			(xy 315.44867 -155.594377) (xy 315.420435 -155.514489) (xy 315.399072 -155.432494) (xy 315.384735 -155.348984)
			(xy 315.377529 -155.26456) (xy 315.377068 -155.222194) (xy 315.377322 -155.195016) (xy 315.37783 -155.175712)
			(xy 315.371734 -155.16733) (xy 315.341254 -155.136088) (xy 315.341 -155.135834) (xy 315.320426 -155.115006)
			(xy 315.313314 -155.109164) (xy 315.306815 -155.104978) (xy 315.292082 -155.100319) (xy 315.284358 -155.10002)
			(xy 315.035692 -155.10002) (xy 314.995315 -155.09962) (xy 314.91483 -155.09303) (xy 314.835152 -155.079887)
			(xy 314.756815 -155.060279) (xy 314.718446 -155.047696) (xy 314.71743 -155.047442) (xy 314.713112 -155.046172)
			(xy 314.709048 -155.044902) (xy 314.706 -155.044394) (xy 314.672726 -155.037536) (xy 314.672218 -155.037282)
			(xy 314.66663 -155.036012) (xy 314.65647 -155.033472) (xy 314.652406 -155.032456) (xy 314.632848 -155.027376)
			(xy 314.617354 -155.023058) (xy 314.579508 -155.011374) (xy 314.579254 -155.011374) (xy 314.578238 -155.01112)
			(xy 314.519818 -154.98953) (xy 314.51804 -154.988768) (xy 314.510674 -154.98572) (xy 314.44692 -154.98572)
			(xy 314.42914 -154.992832) (xy 314.421774 -154.999944) (xy 314.390902 -155.028881) (xy 314.325037 -155.082012)
			(xy 314.254907 -155.129369) (xy 314.181015 -155.170613) (xy 314.103894 -155.205445) (xy 314.024098 -155.233616)
			(xy 313.942201 -155.254923) (xy 313.858794 -155.269212) (xy 313.774475 -155.276381) (xy 313.732164 -155.276804)
			(xy 313.685501 -155.27625) (xy 313.592585 -155.267509) (xy 313.500892 -155.250126) (xy 313.411225 -155.224252)
			(xy 313.324366 -155.190114) (xy 313.241077 -155.148011) (xy 313.162086 -155.098311) (xy 313.088083 -155.041448)
			(xy 313.019716 -154.977921) (xy 312.957584 -154.908284) (xy 312.902229 -154.833147) (xy 312.877708 -154.793442)
			(xy 312.875111 -154.789464) (xy 312.868718 -154.782439) (xy 312.865008 -154.779472) (xy 312.842342 -154.761288)
			(xy 312.802261 -154.719217) (xy 312.769027 -154.671552) (xy 312.74341 -154.619396) (xy 312.726002 -154.563958)
			(xy 312.717206 -154.50652) (xy 312.716672 -154.477466) (xy 312.716672 -154.476704) (xy 312.717176 -154.447339)
			(xy 312.726113 -154.389295) (xy 312.734452 -154.361134) (xy 312.735804 -154.356628) (xy 312.736962 -154.347291)
			(xy 312.736738 -154.342592) (xy 312.735853 -154.326796) (xy 312.734964 -154.295167) (xy 312.73496 -154.279346)
			(xy 312.735392 -154.236978) (xy 312.742575 -154.152547) (xy 312.756902 -154.069031) (xy 312.778268 -153.987033)
			(xy 312.80652 -153.907146) (xy 312.823606 -153.868374) (xy 312.827582 -153.858332) (xy 312.8276 -153.836752)
			(xy 312.823606 -153.826718) (xy 312.80656 -153.787929) (xy 312.778321 -153.708041) (xy 312.756954 -153.626047)
			(xy 312.742613 -153.542537) (xy 312.735402 -153.458112) (xy 312.73496 -153.415746) (xy 312.734963 -153.399862)
			(xy 312.735853 -153.368106) (xy 312.736738 -153.352246) (xy 312.736912 -153.347548) (xy 312.735771 -153.338216)
			(xy 312.734452 -153.333704) (xy 312.729164 -153.316337) (xy 312.721529 -153.280843) (xy 312.719212 -153.262838)
			(xy 312.717942 -153.250646) (xy 312.716418 -153.218134) (xy 312.716418 -153.197052) (xy 312.717942 -153.184606)
			(xy 312.720915 -153.156635) (xy 312.734039 -153.10194) (xy 312.755059 -153.049768) (xy 312.78352 -153.001252)
			(xy 312.818801 -152.957445) (xy 312.8391 -152.937972) (xy 312.864754 -152.916128) (xy 312.868356 -152.91316)
			(xy 312.874495 -152.90613) (xy 312.876946 -152.902158) (xy 312.901468 -152.862399) (xy 312.956855 -152.787169)
			(xy 313.019031 -152.717446) (xy 313.087452 -152.65384) (xy 313.161519 -152.596908) (xy 313.240584 -152.547149)
			(xy 313.323954 -152.504998) (xy 313.410899 -152.470826) (xy 313.500658 -152.44493) (xy 313.592444 -152.427538)
			(xy 313.685454 -152.418802) (xy 313.732164 -152.418288) (xy 313.774461 -152.418743) (xy 313.85875 -152.425924)
			(xy 313.942127 -152.44022) (xy 314.023994 -152.46153) (xy 314.10376 -152.489698) (xy 314.180853 -152.524524)
			(xy 314.254719 -152.565756) (xy 314.324825 -152.613099) (xy 314.390668 -152.66621) (xy 314.42152 -152.695148)
			(xy 314.428817 -152.701598) (xy 314.446844 -152.70892) (xy 314.456572 -152.709372) (xy 315.324744 -152.709372)
			(xy 315.327926 -152.707222) (xy 315.333663 -152.702117) (xy 315.336174 -152.699212) (xy 315.340238 -152.694132)
			(xy 315.347096 -152.686512) (xy 315.354462 -152.668478) (xy 315.354462 -152.66797) (xy 315.359542 -152.656032)
			(xy 315.360304 -152.648158) (xy 315.36132 -152.63876) (xy 315.3664 -152.60701) (xy 315.367924 -152.599898)
			(xy 315.368432 -152.597866) (xy 315.368686 -152.596596) (xy 315.369448 -152.593548) (xy 315.369702 -152.592786)
			(xy 315.369702 -152.592278) (xy 315.370464 -152.589484) (xy 315.370718 -152.588214) (xy 315.374782 -152.573482)
			(xy 315.37529 -152.572466) (xy 315.376052 -152.569418) (xy 315.376306 -152.568656) (xy 315.377068 -152.566116)
			(xy 315.377322 -152.565862) (xy 315.379608 -152.557734) (xy 315.378846 -152.548844) (xy 315.377964 -152.533111)
			(xy 315.377077 -152.501609) (xy 315.377068 -152.485852) (xy 315.3775 -152.443484) (xy 315.384683 -152.359053)
			(xy 315.399009 -152.275537) (xy 315.420374 -152.193539) (xy 315.448626 -152.113651) (xy 315.465714 -152.07488)
			(xy 315.46967 -152.064838) (xy 315.469651 -152.043275) (xy 315.465714 -152.033224) (xy 315.448672 -151.994435)
			(xy 315.42044 -151.914546) (xy 315.39908 -151.832551) (xy 315.384747 -151.749041) (xy 315.377544 -151.664617)
			(xy 315.377068 -151.622252) (xy 315.377117 -151.604012) (xy 315.378386 -151.567553) (xy 315.379608 -151.549354)
			(xy 315.376814 -151.541226) (xy 315.376814 -151.540464) (xy 315.374528 -151.533352) (xy 315.368178 -151.508968)
			(xy 315.368178 -151.508714) (xy 315.366639 -151.502732) (xy 315.361126 -151.491683) (xy 315.357256 -151.48687)
			(xy 315.349636 -151.47798) (xy 315.34862 -151.477218) (xy 315.339984 -151.467566) (xy 315.336427 -151.463812)
			(xy 315.328106 -151.457673) (xy 315.323474 -151.455374) (xy 315.322204 -151.454866) (xy 315.32068 -151.454104)
			(xy 315.276992 -151.43861) (xy 315.276738 -151.438356) (xy 315.249283 -151.427945) (xy 315.195526 -151.404309)
			(xy 315.169296 -151.391112) (xy 315.16387 -151.388524) (xy 315.152191 -151.385691) (xy 315.146182 -151.385524)
			(xy 314.456572 -151.385524) (xy 314.446852 -151.386011) (xy 314.428834 -151.393327) (xy 314.42152 -151.399748)
			(xy 314.390653 -151.428668) (xy 314.324804 -151.481769) (xy 314.254696 -151.529104) (xy 314.180831 -151.570333)
			(xy 314.103741 -151.60516) (xy 314.023978 -151.633334) (xy 313.942117 -151.654654) (xy 313.858745 -151.668966)
			(xy 313.77446 -151.676168) (xy 313.732164 -151.676608) (xy 313.685501 -151.676054) (xy 313.592585 -151.667313)
			(xy 313.500892 -151.64993) (xy 313.411224 -151.624056) (xy 313.324366 -151.589918) (xy 313.241077 -151.547815)
			(xy 313.162085 -151.498115) (xy 313.088082 -151.441253) (xy 313.019715 -151.377726) (xy 312.957582 -151.308089)
			(xy 312.902227 -151.232952) (xy 312.877708 -151.193246) (xy 312.875111 -151.189268) (xy 312.868719 -151.182242)
			(xy 312.865008 -151.179276) (xy 312.842342 -151.161092) (xy 312.80226 -151.119021) (xy 312.769026 -151.071356)
			(xy 312.743408 -151.0192) (xy 312.726 -150.963762) (xy 312.717204 -150.906324) (xy 312.716672 -150.87727)
			(xy 312.716672 -150.876508) (xy 312.717176 -150.847143) (xy 312.726112 -150.789098) (xy 312.734452 -150.760938)
			(xy 312.735805 -150.756432) (xy 312.736963 -150.747095) (xy 312.736738 -150.742396) (xy 312.735853 -150.7266)
			(xy 312.734964 -150.694971) (xy 312.73496 -150.67915) (xy 312.735392 -150.636782) (xy 312.742575 -150.552351)
			(xy 312.756901 -150.468835) (xy 312.778267 -150.386837) (xy 312.806518 -150.306949) (xy 312.823606 -150.268178)
			(xy 312.827583 -150.258136) (xy 312.827602 -150.236555) (xy 312.823606 -150.226522) (xy 312.806564 -150.187733)
			(xy 312.778332 -150.107844) (xy 312.756973 -150.025849) (xy 312.74264 -149.942339) (xy 312.735438 -149.857915)
			(xy 312.73496 -149.81555) (xy 312.734963 -149.799666) (xy 312.735852 -149.76791) (xy 312.736738 -149.75205)
			(xy 312.736904 -149.747353) (xy 312.735746 -149.738027) (xy 312.734452 -149.733508) (xy 312.729164 -149.716141)
			(xy 312.721529 -149.680648) (xy 312.719212 -149.662642) (xy 312.717942 -149.65045) (xy 312.716418 -149.617938)
			(xy 312.716418 -149.596856) (xy 312.717942 -149.58441) (xy 312.720914 -149.556439) (xy 312.734038 -149.501744)
			(xy 312.755058 -149.449571) (xy 312.783518 -149.401054) (xy 312.818799 -149.357247) (xy 312.8391 -149.337776)
			(xy 312.864754 -149.315932) (xy 312.868352 -149.31296) (xy 312.874479 -149.305924) (xy 312.876946 -149.301962)
			(xy 312.901468 -149.262203) (xy 312.956854 -149.186973) (xy 313.01903 -149.117249) (xy 313.087451 -149.053643)
			(xy 313.161519 -148.996711) (xy 313.240584 -148.946951) (xy 313.323954 -148.904801) (xy 313.410899 -148.870628)
			(xy 313.500657 -148.844732) (xy 313.592444 -148.82734) (xy 313.685454 -148.818604) (xy 313.732164 -148.818092)
			(xy 313.774461 -148.818547) (xy 313.85875 -148.825728) (xy 313.942127 -148.840024) (xy 314.023993 -148.861334)
			(xy 314.10376 -148.889503) (xy 314.180853 -148.924329) (xy 314.254718 -148.965561) (xy 314.324824 -149.012903)
			(xy 314.390667 -149.066015) (xy 314.42152 -149.094952) (xy 314.428817 -149.101402) (xy 314.446844 -149.108723)
			(xy 314.456572 -149.109176) (xy 315.303916 -149.109176) (xy 315.315026 -149.108618) (xy 315.335187 -149.099273)
			(xy 315.342778 -149.091142) (xy 315.347604 -149.085554) (xy 315.350906 -149.076156) (xy 315.359542 -149.056598)
			(xy 315.360304 -149.048216) (xy 315.361804 -149.03365) (xy 315.366761 -149.004789) (xy 315.37021 -148.990558)
			(xy 315.3791 -148.960586) (xy 315.379354 -148.959316) (xy 315.379608 -148.958808) (xy 315.378389 -148.940608)
			(xy 315.377118 -148.90415) (xy 315.377068 -148.88591) (xy 315.377502 -148.843542) (xy 315.384688 -148.759112)
			(xy 315.399017 -148.675598) (xy 315.420386 -148.593601) (xy 315.44864 -148.513715) (xy 315.465714 -148.474938)
			(xy 315.469682 -148.464896) (xy 315.469686 -148.443322) (xy 315.465714 -148.433282) (xy 315.448679 -148.394517)
			(xy 315.420455 -148.314678) (xy 315.399095 -148.232735) (xy 315.384753 -148.149277) (xy 315.377533 -148.064904)
			(xy 315.377068 -148.022564) (xy 315.377068 -148.022056) (xy 315.377322 -147.992592) (xy 315.377576 -147.982178)
			(xy 315.37021 -147.963128) (xy 315.330332 -147.922488) (xy 315.320934 -147.912836) (xy 315.314076 -147.906994)
			(xy 315.307492 -147.902665) (xy 315.292487 -147.897878) (xy 315.284612 -147.897596) (xy 314.936632 -147.897596)
			(xy 314.8885 -147.896995) (xy 314.792698 -147.887578) (xy 314.74537 -147.8788) (xy 314.732924 -147.87626)
			(xy 314.712223 -147.871762) (xy 314.671188 -147.861217) (xy 314.650882 -147.855178) (xy 314.609373 -147.842186)
			(xy 314.528609 -147.809883) (xy 314.489592 -147.790662) (xy 314.479686 -147.785836) (xy 314.456826 -147.785836)
			(xy 314.44713 -147.78627) (xy 314.429119 -147.79346) (xy 314.421774 -147.799806) (xy 314.390917 -147.828711)
			(xy 314.325091 -147.881781) (xy 314.255006 -147.929086) (xy 314.181167 -147.970286) (xy 314.104104 -148.005084)
			(xy 314.024371 -148.03323) (xy 313.94254 -148.054522) (xy 313.8592 -148.068807) (xy 313.77495 -148.075983)
			(xy 313.732672 -148.076412) (xy 313.732164 -148.076412) (xy 313.685465 -148.075865) (xy 313.592476 -148.06713)
			(xy 313.500711 -148.049738) (xy 313.410974 -148.023843) (xy 313.324052 -147.989672) (xy 313.240705 -147.947523)
			(xy 313.161663 -147.897766) (xy 313.087621 -147.840837) (xy 313.019225 -147.777235) (xy 312.957075 -147.707516)
			(xy 312.901716 -147.632292) (xy 312.8772 -147.592542) (xy 312.874681 -147.588563) (xy 312.868415 -147.581534)
			(xy 312.864754 -147.578572) (xy 312.842131 -147.560386) (xy 312.802132 -147.518328) (xy 312.768964 -147.470696)
			(xy 312.743394 -147.41859) (xy 312.726011 -147.363213) (xy 312.717216 -147.305841) (xy 312.716672 -147.27682)
			(xy 312.716672 -147.276312) (xy 312.716926 -147.262596) (xy 312.716926 -147.260564) (xy 312.717816 -147.244364)
			(xy 312.722011 -147.212188) (xy 312.725308 -147.196302) (xy 312.734706 -147.160996) (xy 312.735975 -147.156475)
			(xy 312.737004 -147.147142) (xy 312.736738 -147.142454) (xy 312.735852 -147.126658) (xy 312.734961 -147.095029)
			(xy 312.73496 -147.079208) (xy 312.735394 -147.03684) (xy 312.74258 -146.95241) (xy 312.756909 -146.868896)
			(xy 312.778278 -146.786899) (xy 312.806533 -146.707014) (xy 312.823606 -146.668236) (xy 312.827574 -146.658194)
			(xy 312.827578 -146.63662) (xy 312.823606 -146.62658) (xy 312.806562 -146.587791) (xy 312.778325 -146.507903)
			(xy 312.756961 -146.425908) (xy 312.742624 -146.342398) (xy 312.735416 -146.257974) (xy 312.73496 -146.215608)
			(xy 312.734964 -146.199724) (xy 312.735854 -146.167968) (xy 312.736738 -146.152108) (xy 312.736909 -146.14741)
			(xy 312.735761 -146.138081) (xy 312.734452 -146.133566) (xy 312.729165 -146.116199) (xy 312.721535 -146.080705)
			(xy 312.719212 -146.0627) (xy 312.717942 -146.050508) (xy 312.716418 -146.017996) (xy 312.716418 -145.996914)
			(xy 312.717942 -145.984468) (xy 312.72091 -145.956495) (xy 312.734027 -145.901795) (xy 312.755041 -145.849617)
			(xy 312.783497 -145.801094) (xy 312.818775 -145.757281) (xy 312.8391 -145.737834) (xy 312.864754 -145.71599)
			(xy 312.868354 -145.71302) (xy 312.874489 -145.705988) (xy 312.876946 -145.70202) (xy 312.901472 -145.662271)
			(xy 312.956864 -145.587061) (xy 313.019045 -145.517359) (xy 313.087471 -145.453777) (xy 313.161542 -145.39687)
			(xy 313.24061 -145.347139) (xy 313.32398 -145.305019) (xy 313.410924 -145.270878) (xy 313.500679 -145.245015)
			(xy 313.592459 -145.227658) (xy 313.68546 -145.218959) (xy 313.732164 -145.218404) (xy 313.774454 -145.218854)
			(xy 313.85873 -145.226022) (xy 313.942096 -145.240301) (xy 314.023953 -145.26159) (xy 314.103713 -145.289733)
			(xy 314.180804 -145.324531) (xy 314.25467 -145.365732) (xy 314.324782 -145.41304) (xy 314.390636 -145.466116)
			(xy 314.42152 -145.49501) (xy 314.428843 -145.501387) (xy 314.446869 -145.508564) (xy 314.456572 -145.50898)
			(xy 315.327284 -145.50898) (xy 315.331602 -145.5039) (xy 315.340746 -145.493486) (xy 315.34735 -145.485866)
			(xy 315.359796 -145.455386) (xy 315.360558 -145.445226) (xy 315.360558 -145.444718) (xy 315.363352 -145.42262)
			(xy 315.363606 -145.422112) (xy 315.367416 -145.401538) (xy 315.368432 -145.397728) (xy 315.368686 -145.396458)
			(xy 315.369448 -145.39341) (xy 315.369702 -145.392648) (xy 315.369702 -145.39214) (xy 315.370464 -145.389346)
			(xy 315.370718 -145.388076) (xy 315.374782 -145.373344) (xy 315.37529 -145.372328) (xy 315.376052 -145.36928)
			(xy 315.376306 -145.368518) (xy 315.377068 -145.365978) (xy 315.377322 -145.365724) (xy 315.379608 -145.357596)
			(xy 315.378846 -145.348706) (xy 315.377963 -145.332973) (xy 315.377074 -145.301471) (xy 315.377068 -145.285714)
			(xy 315.377502 -145.243346) (xy 315.384687 -145.158916) (xy 315.399016 -145.075401) (xy 315.420385 -144.993405)
			(xy 315.448639 -144.913519) (xy 315.465714 -144.874742) (xy 315.469683 -144.8647) (xy 315.469689 -144.843125)
			(xy 315.465714 -144.833086) (xy 315.44867 -144.794297) (xy 315.420432 -144.714409) (xy 315.399068 -144.632415)
			(xy 315.38473 -144.548905) (xy 315.377521 -144.46448) (xy 315.377068 -144.422114) (xy 315.377075 -144.406293)
			(xy 315.377964 -144.374664) (xy 315.378846 -144.358868) (xy 315.379013 -144.354171) (xy 315.377859 -144.344844)
			(xy 315.37656 -144.340326) (xy 315.368289 -144.312346) (xy 315.359357 -144.254689) (xy 315.35878 -144.225518)
			(xy 315.35878 -144.22501) (xy 315.35878 -144.223994) (xy 315.35878 -144.223486) (xy 315.359276 -144.195779)
			(xy 315.367311 -144.140951) (xy 315.374782 -144.114266) (xy 315.375798 -144.110964) (xy 315.378592 -144.0942)
			(xy 315.377068 -144.085564) (xy 315.373004 -144.062196) (xy 315.371738 -144.055844) (xy 315.366465 -144.044018)
			(xy 315.36259 -144.038828) (xy 315.340238 -144.007586) (xy 315.340238 -144.007078) (xy 315.32195 -143.98117)
			(xy 315.31306 -143.973804) (xy 315.218318 -143.973804) (xy 315.2133 -143.973899) (xy 315.20345 -143.975825)
			(xy 315.19876 -143.977614) (xy 314.879736 -144.109948) (xy 314.834368 -144.128058) (xy 314.740871 -144.156375)
			(xy 314.645054 -144.175421) (xy 314.547835 -144.185014) (xy 314.49899 -144.18564) (xy 314.44692 -144.18564)
			(xy 314.42914 -144.192752) (xy 314.421774 -144.199864) (xy 314.390901 -144.228801) (xy 314.325037 -144.28193)
			(xy 314.254906 -144.329287) (xy 314.181014 -144.370529) (xy 314.103893 -144.405361) (xy 314.024097 -144.433532)
			(xy 313.942201 -144.454838) (xy 313.858793 -144.469127) (xy 313.774475 -144.476296) (xy 313.732164 -144.476724)
			(xy 313.685502 -144.47617) (xy 313.592587 -144.467428) (xy 313.500896 -144.450044) (xy 313.41123 -144.424169)
			(xy 313.324373 -144.39003) (xy 313.241087 -144.347925) (xy 313.162098 -144.298222) (xy 313.088099 -144.241357)
			(xy 313.019736 -144.177827) (xy 312.957608 -144.108188) (xy 312.902259 -144.033048) (xy 312.877708 -143.993362)
			(xy 312.875112 -143.989383) (xy 312.868721 -143.982356) (xy 312.865008 -143.979392) (xy 312.842341 -143.961209)
			(xy 312.802258 -143.919138) (xy 312.769022 -143.871473) (xy 312.743402 -143.819317) (xy 312.725991 -143.763879)
			(xy 312.717192 -143.70644) (xy 312.716672 -143.677386) (xy 312.716672 -143.676624) (xy 312.717174 -143.647259)
			(xy 312.726108 -143.589213) (xy 312.734452 -143.561054) (xy 312.735797 -143.556547) (xy 312.736939 -143.547212)
			(xy 312.736738 -143.542512) (xy 312.735853 -143.526716) (xy 312.734963 -143.495087) (xy 312.73496 -143.479266)
			(xy 312.735396 -143.436899) (xy 312.742585 -143.35247) (xy 312.756918 -143.268956) (xy 312.77829 -143.186962)
			(xy 312.806547 -143.107078) (xy 312.823606 -143.068294) (xy 312.827565 -143.058252) (xy 312.827552 -143.036686)
			(xy 312.823606 -143.026638) (xy 312.806564 -142.987849) (xy 312.77833 -142.90796) (xy 312.75697 -142.825966)
			(xy 312.742636 -142.742456) (xy 312.735432 -142.658031) (xy 312.73496 -142.615666) (xy 312.734963 -142.599782)
			(xy 312.735852 -142.568026) (xy 312.736738 -142.552166) (xy 312.736905 -142.547469) (xy 312.73575 -142.538142)
			(xy 312.734452 -142.533624) (xy 312.729163 -142.516257) (xy 312.721527 -142.480764) (xy 312.719212 -142.462758)
			(xy 312.717942 -142.450566) (xy 312.716418 -142.418054) (xy 312.716418 -142.396972) (xy 312.717942 -142.384526)
			(xy 312.720913 -142.356555) (xy 312.734035 -142.301858) (xy 312.755054 -142.249684) (xy 312.783512 -142.201165)
			(xy 312.818793 -142.157357) (xy 312.8391 -142.137892) (xy 312.864754 -142.116048) (xy 312.868352 -142.113077)
			(xy 312.874482 -142.106041) (xy 312.876946 -142.102078) (xy 312.901468 -142.062319) (xy 312.956853 -141.987087)
			(xy 313.019029 -141.917362) (xy 313.087449 -141.853755) (xy 313.161517 -141.796822) (xy 313.240582 -141.747062)
			(xy 313.323952 -141.704911) (xy 313.410897 -141.670737) (xy 313.500656 -141.644841) (xy 313.592443 -141.627449)
			(xy 313.685454 -141.618712) (xy 313.732164 -141.618208) (xy 313.774089 -141.618642) (xy 313.857644 -141.625688)
			(xy 313.940311 -141.639725) (xy 314.021509 -141.660654) (xy 314.100662 -141.688327) (xy 314.177212 -141.722548)
			(xy 314.250618 -141.763076) (xy 314.320362 -141.809624) (xy 314.353448 -141.835378) (xy 314.36437 -141.844268)
			(xy 314.391548 -141.848078) (xy 314.572396 -141.773148) (xy 314.617764 -141.755035) (xy 314.71126 -141.726712)
			(xy 314.807077 -141.707659) (xy 314.904296 -141.69806) (xy 314.953142 -141.697456) (xy 315.844174 -141.697456)
			(xy 315.892989 -141.69807) (xy 315.990147 -141.707659) (xy 316.085901 -141.726708) (xy 316.179332 -141.755034)
			(xy 316.224666 -141.773148) (xy 317.097918 -142.134844) (xy 317.101728 -142.136114) (xy 317.541148 -142.2781)
			(xy 317.581881 -142.291709) (xy 317.661036 -142.325046) (xy 317.736995 -142.365132) (xy 317.809185 -142.411666)
			(xy 317.843408 -142.437612) (xy 317.855092 -142.446502) (xy 317.866776 -142.45336) (xy 318.001142 -142.508986)
			(xy 318.04614 -142.52829) (xy 318.132465 -142.574509) (xy 318.213842 -142.628972) (xy 318.289486 -142.691151)
			(xy 318.324484 -142.725394) (xy 318.730376 -143.131286) (xy 318.735202 -143.135604) (xy 318.78397 -143.173704)
			(xy 319.377314 -143.638016) (xy 319.386518 -143.644444) (xy 319.408384 -143.649407) (xy 319.430292 -143.644627)
			(xy 319.439544 -143.63827) (xy 319.45326 -143.627856) (xy 319.46215 -143.594582) (xy 319.343278 -143.307562)
			(xy 319.337182 -143.298672) (xy 319.332864 -143.294862) (xy 319.3195 -143.282456) (xy 319.293585 -143.256795)
			(xy 319.281048 -143.243554) (xy 319.267078 -143.228314) (xy 319.266062 -143.227298) (xy 319.235038 -143.193816)
			(xy 319.178564 -143.122097) (xy 319.128877 -143.045519) (xy 319.086393 -142.964723) (xy 319.06845 -142.922752)
			(xy 318.893444 -142.500096) (xy 318.878324 -142.462531) (xy 318.853498 -142.385447) (xy 318.835 -142.306604)
			(xy 318.822951 -142.226522) (xy 318.819784 -142.186152) (xy 318.818914 -142.177852) (xy 318.812567 -142.162429)
			(xy 318.807338 -142.155926) (xy 318.780894 -142.125047) (xy 318.732543 -142.059681) (xy 318.689674 -141.990597)
			(xy 318.652569 -141.918252) (xy 318.63665 -141.880844) (xy 318.461644 -141.458188) (xy 318.446499 -141.420565)
			(xy 318.421643 -141.343357) (xy 318.403144 -141.264385) (xy 318.391124 -141.184171) (xy 318.387984 -141.143736)
			(xy 318.387112 -141.135437) (xy 318.380761 -141.120018) (xy 318.375538 -141.11351) (xy 318.345998 -141.078967)
			(xy 318.292641 -141.005379) (xy 318.24621 -140.927237) (xy 318.226186 -140.886434) (xy 318.220852 -140.875258)
			(xy 318.201548 -140.860526) (xy 318.097154 -140.842238) (xy 318.085087 -140.839554) (xy 318.065509 -140.824509)
			(xy 318.059816 -140.813536) (xy 318.059054 -140.811758) (xy 318.057784 -140.808964) (xy 318.05753 -140.808456)
			(xy 318.054482 -140.800836) (xy 318.052417 -140.796258) (xy 318.046789 -140.787943) (xy 318.043306 -140.784326)
			(xy 318.040004 -140.781024) (xy 318.03848 -140.779754) (xy 318.018755 -140.762591) (xy 317.983721 -140.723776)
			(xy 317.95431 -140.680545) (xy 317.931073 -140.633706) (xy 317.914443 -140.584134) (xy 317.909194 -140.55852)
			(xy 317.909194 -140.558266) (xy 317.907162 -140.55852) (xy 317.904114 -140.52169) (xy 317.904114 -140.521182)
			(xy 317.90259 -140.496544) (xy 317.90259 -140.495782) (xy 317.902336 -140.488416) (xy 317.902795 -140.460043)
			(xy 317.911076 -140.403907) (xy 317.927577 -140.349616) (xy 317.951935 -140.298366) (xy 317.96736 -140.274548)
			(xy 317.972677 -140.265887) (xy 317.97662 -140.245969) (xy 317.97498 -140.23594) (xy 317.968344 -140.202654)
			(xy 317.959061 -140.135413) (xy 317.956438 -140.101574) (xy 317.955507 -140.093405) (xy 317.949166 -140.078245)
			(xy 317.943992 -140.071856) (xy 317.916233 -140.039379) (xy 317.865744 -139.97045) (xy 317.843154 -139.934188)
			(xy 317.842646 -139.933172) (xy 317.841884 -139.931902) (xy 317.840868 -139.930378) (xy 317.836804 -139.923774)
			(xy 317.83655 -139.92352) (xy 317.815076 -139.888615) (xy 317.777309 -139.815877) (xy 317.761112 -139.778232)
			(xy 317.706502 -139.647676) (xy 317.590424 -139.370562) (xy 317.59017 -139.370054) (xy 317.586868 -139.362434)
			(xy 317.586868 -139.36218) (xy 317.583058 -139.352782) (xy 317.581026 -139.347702) (xy 317.574676 -139.331192)
			(xy 317.574676 -139.330938) (xy 317.567818 -139.31265) (xy 317.567564 -139.311888) (xy 317.56731 -139.310364)
			(xy 317.55969 -139.287504) (xy 317.546643 -139.244646) (xy 317.527436 -139.157135) (xy 317.521336 -139.112752)
			(xy 317.516764 -139.069826) (xy 317.515494 -139.0523) (xy 317.514986 -139.043918) (xy 317.505588 -139.021566)
			(xy 317.500762 -139.015978) (xy 317.488998 -139.001931) (xy 317.466388 -138.973094) (xy 317.45555 -138.95832)
			(xy 317.454534 -138.956796) (xy 317.432956 -138.928666) (xy 317.393419 -138.869809) (xy 317.37554 -138.839194)
			(xy 317.360682 -138.812694) (xy 317.333864 -138.758173) (xy 317.321946 -138.730228) (xy 317.318644 -138.723624)
			(xy 317.193422 -138.424158) (xy 317.16726 -138.361674) (xy 317.150496 -138.321796) (xy 317.150496 -138.321542)
			(xy 317.146432 -138.31189) (xy 317.1444 -138.307064) (xy 317.1444 -138.30681) (xy 317.140336 -138.297158)
			(xy 317.138812 -138.292586) (xy 317.138304 -138.291316) (xy 317.130176 -138.269218) (xy 317.129668 -138.268456)
			(xy 317.126366 -138.25855) (xy 317.126366 -138.257788) (xy 317.123572 -138.249406) (xy 317.110782 -138.209401)
			(xy 317.091241 -138.12771) (xy 317.078705 -138.044654) (xy 317.075566 -138.002772) (xy 317.075058 -137.993882)
			(xy 317.063628 -137.967466) (xy 317.05804 -137.959846) (xy 317.050674 -137.950448) (xy 317.049404 -137.948924)
			(xy 317.009526 -137.901172) (xy 316.999366 -137.887456) (xy 316.992254 -137.877804) (xy 316.991746 -137.877042)
			(xy 316.989206 -137.873486) (xy 316.960758 -137.831576) (xy 316.938109 -137.795349) (xy 316.898429 -137.719678)
			(xy 316.88151 -137.680446) (xy 316.710568 -137.272776) (xy 316.702847 -137.254175) (xy 316.688747 -137.216443)
			(xy 316.682374 -137.197338) (xy 316.679326 -137.18794) (xy 316.659768 -137.164318) (xy 316.651386 -137.157206)
			(xy 316.643004 -137.15238) (xy 316.636998 -137.148996) (xy 316.623732 -137.145268) (xy 316.616842 -137.145014)
			(xy 316.609222 -137.145014) (xy 316.603634 -137.146284) (xy 316.566008 -137.154824) (xy 316.489778 -137.166775)
			(xy 316.412852 -137.172806) (xy 316.374272 -137.173208) (xy 316.327609 -137.172654) (xy 316.234693 -137.163914)
			(xy 316.142999 -137.146531) (xy 316.053331 -137.120658) (xy 315.966472 -137.086521) (xy 315.883182 -137.044418)
			(xy 315.80419 -136.994719) (xy 315.730186 -136.937856) (xy 315.661819 -136.874329) (xy 315.599685 -136.804692)
			(xy 315.544329 -136.729556) (xy 315.519816 -136.689846) (xy 315.51722 -136.685868) (xy 315.510828 -136.678841)
			(xy 315.507116 -136.675876) (xy 315.484449 -136.657693) (xy 315.444367 -136.615622) (xy 315.411132 -136.567957)
			(xy 315.385514 -136.515801) (xy 315.368105 -136.460362) (xy 315.359308 -136.402924) (xy 315.35878 -136.37387)
			(xy 315.35878 -136.373108) (xy 315.359294 -136.343806) (xy 315.368223 -136.285887) (xy 315.37656 -136.257792)
			(xy 315.377908 -136.253285) (xy 315.379057 -136.24395) (xy 315.378846 -136.23925) (xy 315.377958 -136.22339)
			(xy 315.37707 -136.191634) (xy 315.377068 -136.17575) (xy 315.3775 -136.133382) (xy 315.384683 -136.048951)
			(xy 315.399009 -135.965435) (xy 315.420375 -135.883437) (xy 315.448627 -135.80355) (xy 315.465714 -135.764778)
			(xy 315.469691 -135.754736) (xy 315.46971 -135.733155) (xy 315.465714 -135.723122) (xy 315.448672 -135.684333)
			(xy 315.42044 -135.604444) (xy 315.39908 -135.522449) (xy 315.384748 -135.438939) (xy 315.377545 -135.354515)
			(xy 315.377068 -135.31215) (xy 315.377322 -135.284972) (xy 315.37783 -135.265668) (xy 315.371734 -135.257286)
			(xy 315.341254 -135.226044) (xy 315.341 -135.22579) (xy 315.320426 -135.204962) (xy 315.313314 -135.19912)
			(xy 315.306801 -135.194964) (xy 315.292077 -135.190312) (xy 315.284358 -135.189976) (xy 315.021468 -135.189976)
			(xy 314.990907 -135.189727) (xy 314.929903 -135.185914) (xy 314.899548 -135.182356) (xy 314.89904 -135.182356)
			(xy 314.852477 -135.18182) (xy 314.759757 -135.173144) (xy 314.668249 -135.155862) (xy 314.57875 -135.130127)
			(xy 314.49204 -135.096161) (xy 314.450222 -135.075676) (xy 314.435998 -135.075676) (xy 314.404916 -135.106002)
			(xy 314.338317 -135.161741) (xy 314.267124 -135.211479) (xy 314.191876 -135.254837) (xy 314.113143 -135.291488)
			(xy 314.031521 -135.321154) (xy 313.947628 -135.343611) (xy 313.862101 -135.358688) (xy 313.775587 -135.366271)
			(xy 313.732164 -135.36676) (xy 313.685501 -135.366206) (xy 313.592586 -135.357465) (xy 313.500894 -135.340081)
			(xy 313.411227 -135.314206) (xy 313.32437 -135.280068) (xy 313.241082 -135.237964) (xy 313.162093 -135.188262)
			(xy 313.088092 -135.131398) (xy 313.019727 -135.067869) (xy 312.957597 -134.998231) (xy 312.902245 -134.923093)
			(xy 312.877708 -134.883398) (xy 312.875114 -134.879418) (xy 312.868726 -134.872386) (xy 312.865008 -134.869428)
			(xy 312.842339 -134.851245) (xy 312.802252 -134.809176) (xy 312.769011 -134.761511) (xy 312.743386 -134.709356)
			(xy 312.72597 -134.653917) (xy 312.717166 -134.596477) (xy 312.716672 -134.567422) (xy 312.716672 -134.56666)
			(xy 312.717172 -134.537294) (xy 312.7261 -134.479247) (xy 312.734452 -134.45109) (xy 312.7358 -134.446583)
			(xy 312.736949 -134.437248) (xy 312.736738 -134.432548) (xy 312.735852 -134.416752) (xy 312.734961 -134.385123)
			(xy 312.73496 -134.369302) (xy 312.735394 -134.326934) (xy 312.742581 -134.242505) (xy 312.75691 -134.15899)
			(xy 312.77828 -134.076994) (xy 312.806535 -133.997108) (xy 312.823606 -133.95833) (xy 312.827573 -133.948288)
			(xy 312.827574 -133.926716) (xy 312.823606 -133.916674) (xy 312.806562 -133.877885) (xy 312.778326 -133.797997)
			(xy 312.756963 -133.716002) (xy 312.742626 -133.632492) (xy 312.735418 -133.548068) (xy 312.73496 -133.505702)
			(xy 312.734962 -133.489818) (xy 312.73585 -133.458062) (xy 312.736738 -133.442202) (xy 312.736908 -133.437504)
			(xy 312.735759 -133.428175) (xy 312.734452 -133.42366) (xy 312.729166 -133.406293) (xy 312.721535 -133.370799)
			(xy 312.719212 -133.352794) (xy 312.717942 -133.340602) (xy 312.716418 -133.30809) (xy 312.716418 -133.287008)
			(xy 312.717942 -133.274562) (xy 312.720911 -133.246589) (xy 312.734028 -133.19189) (xy 312.755043 -133.139712)
			(xy 312.783499 -133.09119) (xy 312.818778 -133.047378) (xy 312.8391 -133.027928) (xy 312.864754 -133.006084)
			(xy 312.868354 -133.003114) (xy 312.874488 -132.996081) (xy 312.876946 -132.992114) (xy 312.901469 -132.952357)
			(xy 312.956857 -132.87713) (xy 313.019035 -132.807409) (xy 313.087457 -132.743806) (xy 313.161524 -132.686876)
			(xy 313.240589 -132.63712) (xy 313.323959 -132.594971) (xy 313.410903 -132.5608) (xy 313.500661 -132.534906)
			(xy 313.592446 -132.517515) (xy 313.685455 -132.508779) (xy 313.732164 -132.508244) (xy 313.774461 -132.508699)
			(xy 313.85875 -132.515879) (xy 313.942128 -132.530175) (xy 314.023995 -132.551484) (xy 314.103762 -132.579652)
			(xy 314.180856 -132.614477) (xy 314.254723 -132.655707) (xy 314.324831 -132.703048) (xy 314.390676 -132.756158)
			(xy 314.42152 -132.785104) (xy 314.428819 -132.791549) (xy 314.446846 -132.798862) (xy 314.456572 -132.799328)
			(xy 315.324744 -132.799328) (xy 315.327924 -132.797176) (xy 315.333658 -132.792069) (xy 315.336174 -132.789168)
			(xy 315.340238 -132.784088) (xy 315.347096 -132.776468) (xy 315.354462 -132.758434) (xy 315.354462 -132.757926)
			(xy 315.359542 -132.745988) (xy 315.360304 -132.738114) (xy 315.36132 -132.728716) (xy 315.3664 -132.696966)
			(xy 315.368484 -132.687074) (xy 315.373568 -132.667506) (xy 315.37656 -132.65785) (xy 315.377904 -132.653343)
			(xy 315.379046 -132.644008) (xy 315.378846 -132.639308) (xy 315.377957 -132.623448) (xy 315.377067 -132.591692)
			(xy 315.377068 -132.575808) (xy 315.377502 -132.53344) (xy 315.384688 -132.449011) (xy 315.399017 -132.365496)
			(xy 315.420387 -132.283499) (xy 315.448641 -132.203614) (xy 315.465714 -132.164836) (xy 315.469682 -132.154794)
			(xy 315.469685 -132.133221) (xy 315.465714 -132.12318) (xy 315.44867 -132.084391) (xy 315.420433 -132.004503)
			(xy 315.399069 -131.922509) (xy 315.384731 -131.838999) (xy 315.377523 -131.754574) (xy 315.377068 -131.712208)
			(xy 315.377322 -131.68503) (xy 315.37783 -131.665472) (xy 315.371734 -131.65709) (xy 315.341254 -131.625848)
			(xy 315.341 -131.625594) (xy 315.320426 -131.604766) (xy 315.313314 -131.598924) (xy 315.306801 -131.594768)
			(xy 315.292077 -131.590115) (xy 315.284358 -131.58978) (xy 315.026294 -131.58978) (xy 314.979547 -131.589215)
			(xy 314.886475 -131.580342) (xy 314.794658 -131.562715) (xy 314.704918 -131.53649) (xy 314.618056 -131.501904)
			(xy 314.576206 -131.481068) (xy 314.570778 -131.478492) (xy 314.559098 -131.475681) (xy 314.553092 -131.47548)
			(xy 314.44692 -131.47548) (xy 314.42914 -131.482592) (xy 314.421774 -131.489704) (xy 314.390902 -131.518642)
			(xy 314.325039 -131.571775) (xy 314.254909 -131.619134) (xy 314.181017 -131.660379) (xy 314.103896 -131.695213)
			(xy 314.0241 -131.723385) (xy 313.942203 -131.744693) (xy 313.858795 -131.758983) (xy 313.774476 -131.766152)
			(xy 313.732164 -131.766564) (xy 313.685501 -131.76601) (xy 313.592586 -131.757269) (xy 313.500894 -131.739885)
			(xy 313.411227 -131.71401) (xy 313.32437 -131.679872) (xy 313.241082 -131.637768) (xy 313.162092 -131.588067)
			(xy 313.088091 -131.531203) (xy 313.019726 -131.467674) (xy 312.957596 -131.398036) (xy 312.902244 -131.322898)
			(xy 312.877708 -131.283202) (xy 312.875114 -131.279221) (xy 312.868726 -131.27219) (xy 312.865008 -131.269232)
			(xy 312.842339 -131.251049) (xy 312.802251 -131.20898) (xy 312.76901 -131.161316) (xy 312.743385 -131.10916)
			(xy 312.725968 -131.053721) (xy 312.717163 -130.996281) (xy 312.716672 -130.967226) (xy 312.716672 -130.966464)
			(xy 312.717171 -130.937098) (xy 312.726099 -130.879051) (xy 312.734452 -130.850894) (xy 312.735801 -130.846387)
			(xy 312.73695 -130.837052) (xy 312.736738 -130.832352) (xy 312.735852 -130.816556) (xy 312.734961 -130.784927)
			(xy 312.73496 -130.769106) (xy 312.735394 -130.726738) (xy 312.74258 -130.642309) (xy 312.75691 -130.558794)
			(xy 312.778279 -130.476798) (xy 312.806533 -130.396912) (xy 312.823606 -130.358134) (xy 312.827574 -130.348092)
			(xy 312.827576 -130.326519) (xy 312.823606 -130.316478) (xy 312.806562 -130.277689) (xy 312.778325 -130.197801)
			(xy 312.756962 -130.115806) (xy 312.742624 -130.032296) (xy 312.735417 -129.947872) (xy 312.73496 -129.905506)
			(xy 312.734967 -129.889685) (xy 312.735856 -129.858056) (xy 312.736738 -129.84226) (xy 312.736905 -129.837563)
			(xy 312.735748 -129.828236) (xy 312.734452 -129.823718) (xy 312.726125 -129.79562) (xy 312.717193 -129.737703)
			(xy 312.716672 -129.708402) (xy 312.716672 -129.697226) (xy 312.717968 -129.669097) (xy 312.727806 -129.613653)
			(xy 312.745678 -129.560254) (xy 312.771198 -129.51006) (xy 312.803812 -129.464157) (xy 312.842814 -129.42354)
			(xy 312.864754 -129.405888) (xy 312.868502 -129.402961) (xy 312.874904 -129.395932) (xy 312.877454 -129.391918)
			(xy 312.901954 -129.352172) (xy 312.957295 -129.276963) (xy 313.019425 -129.207258) (xy 313.087799 -129.143667)
			(xy 313.16182 -129.086746) (xy 313.240837 -129.036996) (xy 313.32416 -128.99485) (xy 313.411059 -128.96068)
			(xy 313.500771 -128.934783) (xy 313.592511 -128.917388) (xy 313.685476 -128.908645) (xy 313.732164 -128.908048)
			(xy 313.774461 -128.908503) (xy 313.85875 -128.915683) (xy 313.942128 -128.92998) (xy 314.023995 -128.951288)
			(xy 314.103762 -128.979456) (xy 314.180856 -129.014281) (xy 314.254722 -129.055512) (xy 314.32483 -129.102853)
			(xy 314.390675 -129.155963) (xy 314.42152 -129.184908) (xy 314.428819 -129.191352) (xy 314.446846 -129.198665)
			(xy 314.456572 -129.199132) (xy 316.460124 -129.199132) (xy 316.509104 -129.199715) (xy 316.606592 -129.209321)
			(xy 316.702669 -129.228436) (xy 316.796409 -129.256878) (xy 316.841886 -129.275078) (xy 317.871602 -129.701544)
			(xy 317.880991 -129.704881) (xy 317.900898 -129.704864) (xy 317.919301 -129.697276) (xy 317.92672 -129.690622)
			(xy 317.937642 -129.6797) (xy 317.943738 -129.649474) (xy 317.932308 -129.62255) (xy 317.917214 -129.585643)
			(xy 317.892271 -129.5099) (xy 317.873458 -129.432407) (xy 317.860895 -129.353659) (xy 317.857378 -129.31394)
			(xy 317.856423 -129.305837) (xy 317.850063 -129.290821) (xy 317.844932 -129.284476) (xy 317.8188 -129.254125)
			(xy 317.770939 -129.189898) (xy 317.728394 -129.122033) (xy 317.69144 -129.050968) (xy 317.675514 -129.01422)
			(xy 317.497968 -128.59258) (xy 317.482873 -128.555674) (xy 317.457929 -128.479931) (xy 317.439115 -128.402438)
			(xy 317.42655 -128.323689) (xy 317.423038 -128.28397) (xy 317.422089 -128.275864) (xy 317.415741 -128.260838)
			(xy 317.410592 -128.254506) (xy 317.38446 -128.224155) (xy 317.336599 -128.159928) (xy 317.294054 -128.092063)
			(xy 317.257099 -128.020999) (xy 317.241174 -127.98425) (xy 317.063628 -127.56261) (xy 317.046628 -127.520863)
			(xy 317.019352 -127.434944) (xy 316.999953 -127.34691) (xy 316.993778 -127.30226) (xy 316.991238 -127.292354)
			(xy 316.97861 -127.253968) (xy 316.958926 -127.175588) (xy 316.945707 -127.095862) (xy 316.941962 -127.055626)
			(xy 316.939422 -127.014732) (xy 316.939175 -127.010368) (xy 316.937384 -127.001813) (xy 316.935866 -126.997714)
			(xy 316.918427 -126.95347) (xy 316.891074 -126.862382) (xy 316.881256 -126.81585) (xy 316.713362 -125.971046)
			(xy 316.713108 -125.970792) (xy 316.653164 -125.932946) (xy 316.647068 -125.929136) (xy 316.639956 -125.927104)
			(xy 316.621668 -125.93193) (xy 316.58119 -125.941858) (xy 316.499005 -125.955745) (xy 316.415947 -125.962728)
			(xy 316.374272 -125.963172) (xy 316.327615 -125.962628) (xy 316.23471 -125.953907) (xy 316.143026 -125.936546)
			(xy 316.053365 -125.910694) (xy 315.966512 -125.876579) (xy 315.883225 -125.8345) (xy 315.804234 -125.784823)
			(xy 315.730229 -125.727984) (xy 315.661858 -125.664479) (xy 315.599719 -125.594865) (xy 315.544356 -125.51975)
			(xy 315.519816 -125.480064) (xy 315.517221 -125.476085) (xy 315.51083 -125.469056) (xy 315.507116 -125.466094)
			(xy 315.484432 -125.447897) (xy 315.444324 -125.405791) (xy 315.411073 -125.358084) (xy 315.385451 -125.305882)
			(xy 315.368052 -125.250395) (xy 315.359278 -125.19291) (xy 315.35878 -125.163834) (xy 315.35878 -125.163072)
			(xy 315.359279 -125.133706) (xy 315.368206 -125.075659) (xy 315.37656 -125.047502) (xy 315.377902 -125.042994)
			(xy 315.379053 -125.033659) (xy 315.378846 -125.02896) (xy 315.377961 -125.013164) (xy 315.377074 -124.981535)
			(xy 315.377068 -124.965714) (xy 315.377502 -124.923346) (xy 315.384687 -124.838916) (xy 315.399016 -124.755401)
			(xy 315.420385 -124.673405) (xy 315.448639 -124.593519) (xy 315.465714 -124.554742) (xy 315.469683 -124.5447)
			(xy 315.469689 -124.523125) (xy 315.465714 -124.513086) (xy 315.44867 -124.474297) (xy 315.420432 -124.394409)
			(xy 315.399068 -124.312415) (xy 315.38473 -124.228905) (xy 315.377521 -124.14448) (xy 315.377068 -124.102114)
			(xy 315.377075 -124.086293) (xy 315.377964 -124.054664) (xy 315.378846 -124.038868) (xy 315.379013 -124.034171)
			(xy 315.377859 -124.024844) (xy 315.37656 -124.020326) (xy 315.371711 -124.004433) (xy 315.364463 -123.972001)
			(xy 315.362082 -123.955556) (xy 315.360397 -123.946331) (xy 315.351359 -123.929919) (xy 315.33702 -123.917859)
			(xy 315.3283 -123.914408) (xy 315.300832 -123.904805) (xy 315.24695 -123.882818) (xy 315.220604 -123.870466)
			(xy 315.215429 -123.86821) (xy 315.204405 -123.865784) (xy 315.19876 -123.86564) (xy 314.456572 -123.86564)
			(xy 314.446852 -123.866127) (xy 314.428836 -123.873445) (xy 314.42152 -123.879864) (xy 314.390653 -123.908784)
			(xy 314.324804 -123.961884) (xy 314.254695 -124.009218) (xy 314.18083 -124.050447) (xy 314.10374 -124.085273)
			(xy 314.023978 -124.113447) (xy 313.942117 -124.134766) (xy 313.858744 -124.149078) (xy 313.77446 -124.156279)
			(xy 313.732164 -124.156724) (xy 313.685502 -124.15617) (xy 313.592587 -124.147428) (xy 313.500896 -124.130044)
			(xy 313.41123 -124.104169) (xy 313.324373 -124.07003) (xy 313.241087 -124.027925) (xy 313.162098 -123.978222)
			(xy 313.088099 -123.921357) (xy 313.019736 -123.857827) (xy 312.957608 -123.788188) (xy 312.902259 -123.713048)
			(xy 312.877708 -123.673362) (xy 312.875112 -123.669383) (xy 312.868721 -123.662356) (xy 312.865008 -123.659392)
			(xy 312.842341 -123.641209) (xy 312.802258 -123.599138) (xy 312.769022 -123.551473) (xy 312.743402 -123.499317)
			(xy 312.725991 -123.443879) (xy 312.717192 -123.38644) (xy 312.716672 -123.357386) (xy 312.716672 -123.356624)
			(xy 312.717174 -123.327259) (xy 312.726108 -123.269213) (xy 312.734452 -123.241054) (xy 312.735797 -123.236547)
			(xy 312.736939 -123.227212) (xy 312.736738 -123.222512) (xy 312.735853 -123.206716) (xy 312.734963 -123.175087)
			(xy 312.73496 -123.159266) (xy 312.735396 -123.116899) (xy 312.742585 -123.03247) (xy 312.756918 -122.948956)
			(xy 312.77829 -122.866962) (xy 312.806547 -122.787078) (xy 312.823606 -122.748294) (xy 312.827565 -122.738252)
			(xy 312.827552 -122.716686) (xy 312.823606 -122.706638) (xy 312.806564 -122.667849) (xy 312.77833 -122.58796)
			(xy 312.75697 -122.505966) (xy 312.742636 -122.422456) (xy 312.735432 -122.338031) (xy 312.73496 -122.295666)
			(xy 312.734963 -122.279782) (xy 312.735852 -122.248026) (xy 312.736738 -122.232166) (xy 312.736905 -122.227469)
			(xy 312.73575 -122.218142) (xy 312.734452 -122.213624) (xy 312.729163 -122.196257) (xy 312.721527 -122.160764)
			(xy 312.719212 -122.142758) (xy 312.717942 -122.130566) (xy 312.716418 -122.098054) (xy 312.716418 -122.076972)
			(xy 312.717942 -122.064526) (xy 312.720913 -122.036555) (xy 312.734035 -121.981858) (xy 312.755054 -121.929684)
			(xy 312.783512 -121.881165) (xy 312.818793 -121.837357) (xy 312.8391 -121.817892) (xy 312.864754 -121.796048)
			(xy 312.868352 -121.793077) (xy 312.874482 -121.786041) (xy 312.876946 -121.782078) (xy 312.901468 -121.742319)
			(xy 312.956853 -121.667087) (xy 313.019029 -121.597362) (xy 313.087449 -121.533755) (xy 313.161517 -121.476822)
			(xy 313.240582 -121.427062) (xy 313.323952 -121.384911) (xy 313.410897 -121.350737) (xy 313.500656 -121.324841)
			(xy 313.592443 -121.307449) (xy 313.685454 -121.298712) (xy 313.732164 -121.298208) (xy 313.774461 -121.298663)
			(xy 313.85875 -121.305844) (xy 313.942127 -121.320141) (xy 314.023993 -121.34145) (xy 314.103759 -121.36962)
			(xy 314.180852 -121.404446) (xy 314.254717 -121.445679) (xy 314.324822 -121.493021) (xy 314.390665 -121.546134)
			(xy 314.42152 -121.575068) (xy 314.428817 -121.581516) (xy 314.446845 -121.588835) (xy 314.456572 -121.589292)
			(xy 315.324744 -121.589292) (xy 315.327926 -121.587142) (xy 315.333665 -121.582039) (xy 315.336174 -121.579132)
			(xy 315.340238 -121.574052) (xy 315.347096 -121.566432) (xy 315.354462 -121.548398) (xy 315.354462 -121.54789)
			(xy 315.359542 -121.535952) (xy 315.360304 -121.528078) (xy 315.36132 -121.51868) (xy 315.3664 -121.48693)
			(xy 315.368483 -121.477038) (xy 315.373564 -121.457469) (xy 315.37656 -121.447814) (xy 315.377903 -121.443306)
			(xy 315.379057 -121.433971) (xy 315.378846 -121.429272) (xy 315.377958 -121.413412) (xy 315.377069 -121.381656)
			(xy 315.377068 -121.365772) (xy 315.377504 -121.323405) (xy 315.384693 -121.238976) (xy 315.399025 -121.155462)
			(xy 315.420396 -121.073467) (xy 315.448654 -120.993583) (xy 315.465714 -120.9548) (xy 315.469674 -120.944758)
			(xy 315.469663 -120.923191) (xy 315.465714 -120.913144) (xy 315.448681 -120.874379) (xy 315.42046 -120.794539)
			(xy 315.399103 -120.712596) (xy 315.384764 -120.629138) (xy 315.377547 -120.544766) (xy 315.377068 -120.502426)
			(xy 315.377068 -120.501918) (xy 315.377322 -120.472962) (xy 315.378084 -120.453404) (xy 315.372496 -120.446292)
			(xy 315.332618 -120.403112) (xy 315.329445 -120.399835) (xy 315.322162 -120.394343) (xy 315.31814 -120.39219)
			(xy 315.291978 -120.378982) (xy 315.281818 -120.377966) (xy 315.280294 -120.377712) (xy 315.276992 -120.377458)
			(xy 315.232795 -120.373802) (xy 315.145258 -120.359544) (xy 315.059353 -120.337489) (xy 315.017404 -120.323102)
			(xy 314.998354 -120.316244) (xy 314.997846 -120.315736) (xy 314.99302 -120.313958) (xy 314.992766 -120.313958)
			(xy 314.989972 -120.312688) (xy 314.987686 -120.311926) (xy 314.944506 -120.294146) (xy 314.94349 -120.293638)
			(xy 314.891928 -120.270778) (xy 314.89142 -120.270778) (xy 314.88126 -120.265952) (xy 314.456572 -120.265952)
			(xy 314.446871 -120.266376) (xy 314.428841 -120.273545) (xy 314.42152 -120.279922) (xy 314.390663 -120.308825)
			(xy 314.324835 -120.361891) (xy 314.254749 -120.409191) (xy 314.18091 -120.450386) (xy 314.103846 -120.485179)
			(xy 314.024113 -120.513321) (xy 313.942283 -120.534608) (xy 313.858944 -120.548889) (xy 313.774695 -120.55606)
			(xy 313.732418 -120.556528) (xy 313.732164 -120.556528) (xy 313.685465 -120.555981) (xy 313.592476 -120.547246)
			(xy 313.50071 -120.529854) (xy 313.410973 -120.50396) (xy 313.32405 -120.469788) (xy 313.240703 -120.42764)
			(xy 313.161661 -120.377884) (xy 313.087617 -120.320955) (xy 313.019221 -120.257353) (xy 312.95707 -120.187635)
			(xy 312.90171 -120.112412) (xy 312.8772 -120.072658) (xy 312.874682 -120.068678) (xy 312.868417 -120.061648)
			(xy 312.864754 -120.058688) (xy 312.842131 -120.040502) (xy 312.802129 -119.998445) (xy 312.768959 -119.950813)
			(xy 312.743387 -119.898708) (xy 312.726001 -119.84333) (xy 312.717205 -119.785957) (xy 312.716672 -119.756936)
			(xy 312.716672 -119.756428) (xy 312.716926 -119.742712) (xy 312.716926 -119.74068) (xy 312.717817 -119.72448)
			(xy 312.722012 -119.692304) (xy 312.725308 -119.676418) (xy 312.734706 -119.641112) (xy 312.735977 -119.636591)
			(xy 312.737008 -119.627258) (xy 312.736738 -119.62257) (xy 312.735853 -119.606774) (xy 312.734965 -119.575145)
			(xy 312.73496 -119.559324) (xy 312.735393 -119.516956) (xy 312.742578 -119.432526) (xy 312.756906 -119.349011)
			(xy 312.778274 -119.267014) (xy 312.806527 -119.187127) (xy 312.823606 -119.148352) (xy 312.827578 -119.13831)
			(xy 312.827587 -119.116734) (xy 312.823606 -119.106696) (xy 312.806561 -119.067907) (xy 312.778323 -118.988019)
			(xy 312.756958 -118.906025) (xy 312.742619 -118.822515) (xy 312.73541 -118.73809) (xy 312.73496 -118.695724)
			(xy 312.734963 -118.67984) (xy 312.735854 -118.648084) (xy 312.736738 -118.632224) (xy 312.73691 -118.627526)
			(xy 312.735765 -118.618196) (xy 312.734452 -118.613682) (xy 312.729165 -118.596315) (xy 312.721532 -118.560821)
			(xy 312.719212 -118.542816) (xy 312.717942 -118.530624) (xy 312.716418 -118.498112) (xy 312.716418 -118.47703)
			(xy 312.717942 -118.464584) (xy 312.720909 -118.436611) (xy 312.734024 -118.381909) (xy 312.755037 -118.32973)
			(xy 312.783491 -118.281205) (xy 312.818768 -118.23739) (xy 312.8391 -118.21795) (xy 312.864754 -118.196106)
			(xy 312.868355 -118.193137) (xy 312.874491 -118.186106) (xy 312.876946 -118.182136) (xy 312.901483 -118.142397)
			(xy 312.956892 -118.067208) (xy 313.019086 -117.997526) (xy 313.087518 -117.933959) (xy 313.16159 -117.877065)
			(xy 313.240655 -117.827342) (xy 313.324019 -117.785223) (xy 313.410955 -117.751079) (xy 313.500701 -117.725207)
			(xy 313.592471 -117.707835) (xy 313.685464 -117.699114) (xy 313.732164 -117.69852) (xy 313.732418 -117.69852)
			(xy 313.774694 -117.69898) (xy 313.85894 -117.706165) (xy 313.942275 -117.720456) (xy 314.024101 -117.741752)
			(xy 314.10383 -117.769898) (xy 314.180891 -117.804693) (xy 314.254729 -117.845887) (xy 314.324814 -117.893184)
			(xy 314.390644 -117.946244) (xy 314.42152 -117.975126) (xy 314.42884 -117.981511) (xy 314.446867 -117.988701)
			(xy 314.456572 -117.989096) (xy 316.42177 -117.989096) (xy 316.463732 -117.98954) (xy 316.547358 -117.996614)
			(xy 316.630094 -118.01069) (xy 316.711354 -118.031667) (xy 316.790565 -118.059398) (xy 316.867165 -118.093686)
			(xy 316.940614 -118.13429) (xy 316.975744 -118.157244) (xy 317.440724 -118.467886) (xy 329.682346 -118.467886)
			(xy 329.686417 -118.412264) (xy 329.698543 -118.357827) (xy 329.718466 -118.305736) (xy 329.745762 -118.257101)
			(xy 329.779848 -118.212958) (xy 329.819997 -118.174249) (xy 329.865355 -118.141798) (xy 329.914955 -118.116297)
			(xy 329.967739 -118.09829) (xy 330.022582 -118.08816) (xy 330.078316 -118.086123) (xy 330.133753 -118.092223)
			(xy 330.18771 -118.106329) (xy 330.239039 -118.128141) (xy 330.286645 -118.157195) (xy 330.329513 -118.19287)
			(xy 330.36673 -118.234407) (xy 330.397503 -118.28092) (xy 330.421175 -118.331417) (xy 330.437243 -118.384824)
			(xy 330.445363 -118.44) (xy 330.445872 -118.467886) (xy 330.445363 -118.495772) (xy 330.437243 -118.550948)
			(xy 330.421175 -118.604355) (xy 330.397503 -118.654852) (xy 330.36673 -118.701365) (xy 330.329513 -118.742902)
			(xy 330.308679 -118.76024) (xy 334.764378 -118.76024) (xy 334.768449 -118.704618) (xy 334.780575 -118.650181)
			(xy 334.800498 -118.59809) (xy 334.827794 -118.549455) (xy 334.86188 -118.505312) (xy 334.902029 -118.466603)
			(xy 334.947387 -118.434152) (xy 334.996987 -118.408651) (xy 335.049771 -118.390644) (xy 335.104614 -118.380514)
			(xy 335.160348 -118.378477) (xy 335.215785 -118.384577) (xy 335.269742 -118.398683) (xy 335.321071 -118.420495)
			(xy 335.368677 -118.449549) (xy 335.411545 -118.485224) (xy 335.448762 -118.526761) (xy 335.479535 -118.573274)
			(xy 335.503207 -118.623771) (xy 335.519275 -118.677178) (xy 335.527395 -118.732354) (xy 335.527904 -118.76024)
			(xy 335.527395 -118.788126) (xy 335.519275 -118.843302) (xy 335.503207 -118.896709) (xy 335.479535 -118.947206)
			(xy 335.448762 -118.993719) (xy 335.411545 -119.035256) (xy 335.368677 -119.070931) (xy 335.321071 -119.099985)
			(xy 335.269742 -119.121797) (xy 335.215785 -119.135903) (xy 335.160348 -119.142003) (xy 335.104614 -119.139966)
			(xy 335.049771 -119.129836) (xy 334.996987 -119.111829) (xy 334.947387 -119.086328) (xy 334.902029 -119.053877)
			(xy 334.86188 -119.015168) (xy 334.827794 -118.971025) (xy 334.800498 -118.92239) (xy 334.780575 -118.870299)
			(xy 334.768449 -118.815862) (xy 334.764378 -118.76024) (xy 330.308679 -118.76024) (xy 330.286645 -118.778577)
			(xy 330.239039 -118.807631) (xy 330.18771 -118.829443) (xy 330.133753 -118.843549) (xy 330.078316 -118.849649)
			(xy 330.022582 -118.847612) (xy 329.967739 -118.837482) (xy 329.914955 -118.819475) (xy 329.865355 -118.793974)
			(xy 329.819997 -118.761523) (xy 329.779848 -118.722814) (xy 329.745762 -118.678671) (xy 329.718466 -118.630036)
			(xy 329.698543 -118.577945) (xy 329.686417 -118.523508) (xy 329.682346 -118.467886) (xy 317.440724 -118.467886)
			(xy 318.847257 -119.407557) (xy 326.699509 -119.407557) (xy 326.699509 -119.353043) (xy 326.707268 -119.299083)
			(xy 326.722627 -119.246777) (xy 326.745274 -119.197189) (xy 326.774748 -119.151329) (xy 326.810449 -119.11013)
			(xy 326.85165 -119.074432) (xy 326.897512 -119.044962) (xy 326.947101 -119.022318) (xy 326.999408 -119.006962)
			(xy 327.053369 -118.999207) (xy 327.080626 -118.998746) (xy 327.107997 -118.999186) (xy 327.162178 -119.007008)
			(xy 327.214682 -119.022503) (xy 327.264428 -119.045351) (xy 327.310394 -119.075082) (xy 327.331324 -119.092726)
			(xy 327.331578 -119.09298) (xy 327.33866 -119.098573) (xy 327.355581 -119.104814) (xy 327.364598 -119.105172)
			(xy 327.431654 -119.105172) (xy 327.440669 -119.104799) (xy 327.457587 -119.098563) (xy 327.464674 -119.09298)
			(xy 327.464674 -119.092726) (xy 327.464928 -119.092726) (xy 327.48588 -119.075111) (xy 327.531847 -119.045395)
			(xy 327.581589 -119.022554) (xy 327.634086 -119.007057) (xy 327.688258 -118.999223) (xy 327.715626 -118.998746)
			(xy 327.742873 -118.999326) (xy 327.796811 -119.007085) (xy 327.849096 -119.02244) (xy 327.898664 -119.04508)
			(xy 327.944506 -119.074543) (xy 327.985688 -119.11023) (xy 328.021372 -119.151415) (xy 328.050833 -119.197259)
			(xy 328.073469 -119.246828) (xy 328.088821 -119.299114) (xy 328.096576 -119.353053) (xy 328.096576 -119.407547)
			(xy 328.088821 -119.461486) (xy 328.084258 -119.477028) (xy 331.808072 -119.477028) (xy 331.812143 -119.421406)
			(xy 331.824269 -119.366969) (xy 331.844192 -119.314878) (xy 331.871488 -119.266243) (xy 331.905574 -119.2221)
			(xy 331.945723 -119.183391) (xy 331.991081 -119.15094) (xy 332.040681 -119.125439) (xy 332.093465 -119.107432)
			(xy 332.148308 -119.097302) (xy 332.204042 -119.095265) (xy 332.259479 -119.101365) (xy 332.313436 -119.115471)
			(xy 332.364765 -119.137283) (xy 332.412371 -119.166337) (xy 332.455239 -119.202012) (xy 332.492456 -119.243549)
			(xy 332.523229 -119.290062) (xy 332.546901 -119.340559) (xy 332.562969 -119.393966) (xy 332.571089 -119.449142)
			(xy 332.571598 -119.477028) (xy 332.571089 -119.504914) (xy 332.562969 -119.56009) (xy 332.546901 -119.613497)
			(xy 332.523229 -119.663994) (xy 332.492456 -119.710507) (xy 332.455239 -119.752044) (xy 332.426164 -119.77624)
			(xy 332.735934 -119.77624) (xy 332.740005 -119.720618) (xy 332.752131 -119.666181) (xy 332.772054 -119.61409)
			(xy 332.79935 -119.565455) (xy 332.833436 -119.521312) (xy 332.873585 -119.482603) (xy 332.918943 -119.450152)
			(xy 332.968543 -119.424651) (xy 333.021327 -119.406644) (xy 333.07617 -119.396514) (xy 333.131904 -119.394477)
			(xy 333.187341 -119.400577) (xy 333.241298 -119.414683) (xy 333.292627 -119.436495) (xy 333.340233 -119.465549)
			(xy 333.383101 -119.501224) (xy 333.420318 -119.542761) (xy 333.451091 -119.589274) (xy 333.474763 -119.639771)
			(xy 333.490831 -119.693178) (xy 333.494607 -119.718836) (xy 339.736428 -119.718836) (xy 339.740499 -119.663214)
			(xy 339.752625 -119.608777) (xy 339.772548 -119.556686) (xy 339.799844 -119.508051) (xy 339.83393 -119.463908)
			(xy 339.874079 -119.425199) (xy 339.919437 -119.392748) (xy 339.969037 -119.367247) (xy 340.021821 -119.34924)
			(xy 340.076664 -119.33911) (xy 340.132398 -119.337073) (xy 340.187835 -119.343173) (xy 340.241792 -119.357279)
			(xy 340.293121 -119.379091) (xy 340.340727 -119.408145) (xy 340.383595 -119.44382) (xy 340.420812 -119.485357)
			(xy 340.451585 -119.53187) (xy 340.475257 -119.582367) (xy 340.491325 -119.635774) (xy 340.499445 -119.69095)
			(xy 340.499954 -119.718836) (xy 340.499445 -119.746722) (xy 340.491325 -119.801898) (xy 340.475257 -119.855305)
			(xy 340.451585 -119.905802) (xy 340.420812 -119.952315) (xy 340.383595 -119.993852) (xy 340.340727 -120.029527)
			(xy 340.293121 -120.058581) (xy 340.241792 -120.080393) (xy 340.187835 -120.094499) (xy 340.132398 -120.100599)
			(xy 340.076664 -120.098562) (xy 340.021821 -120.088432) (xy 339.969037 -120.070425) (xy 339.919437 -120.044924)
			(xy 339.874079 -120.012473) (xy 339.83393 -119.973764) (xy 339.799844 -119.929621) (xy 339.772548 -119.880986)
			(xy 339.752625 -119.828895) (xy 339.740499 -119.774458) (xy 339.736428 -119.718836) (xy 333.494607 -119.718836)
			(xy 333.498951 -119.748354) (xy 333.49946 -119.77624) (xy 333.498951 -119.804126) (xy 333.490831 -119.859302)
			(xy 333.474763 -119.912709) (xy 333.451091 -119.963206) (xy 333.420318 -120.009719) (xy 333.383101 -120.051256)
			(xy 333.340233 -120.086931) (xy 333.292627 -120.115985) (xy 333.241298 -120.137797) (xy 333.187341 -120.151903)
			(xy 333.131904 -120.158003) (xy 333.07617 -120.155966) (xy 333.021327 -120.145836) (xy 332.968543 -120.127829)
			(xy 332.918943 -120.102328) (xy 332.873585 -120.069877) (xy 332.833436 -120.031168) (xy 332.79935 -119.987025)
			(xy 332.772054 -119.93839) (xy 332.752131 -119.886299) (xy 332.740005 -119.831862) (xy 332.735934 -119.77624)
			(xy 332.426164 -119.77624) (xy 332.412371 -119.787719) (xy 332.364765 -119.816773) (xy 332.313436 -119.838585)
			(xy 332.259479 -119.852691) (xy 332.204042 -119.858791) (xy 332.148308 -119.856754) (xy 332.093465 -119.846624)
			(xy 332.040681 -119.828617) (xy 331.991081 -119.803116) (xy 331.945723 -119.770665) (xy 331.905574 -119.731956)
			(xy 331.871488 -119.687813) (xy 331.844192 -119.639178) (xy 331.824269 -119.587087) (xy 331.812143 -119.53265)
			(xy 331.808072 -119.477028) (xy 328.084258 -119.477028) (xy 328.073469 -119.513772) (xy 328.050833 -119.563341)
			(xy 328.021372 -119.609185) (xy 327.985688 -119.65037) (xy 327.944506 -119.686057) (xy 327.898664 -119.71552)
			(xy 327.849096 -119.73816) (xy 327.796811 -119.753515) (xy 327.742873 -119.761274) (xy 327.715626 -119.761762)
			(xy 327.688256 -119.76129) (xy 327.634077 -119.753475) (xy 327.581573 -119.737988) (xy 327.531826 -119.715147)
			(xy 327.48586 -119.685423) (xy 327.464928 -119.667782) (xy 327.464674 -119.667528) (xy 327.457577 -119.661958)
			(xy 327.440668 -119.655703) (xy 327.431654 -119.655336) (xy 327.364598 -119.655336) (xy 327.35558 -119.655684)
			(xy 327.338663 -119.661937) (xy 327.331578 -119.667528) (xy 327.331578 -119.667782) (xy 327.331324 -119.667782)
			(xy 327.310391 -119.685421) (xy 327.264419 -119.715133) (xy 327.214672 -119.737969) (xy 327.162171 -119.753461)
			(xy 327.107995 -119.761288) (xy 327.080626 -119.761762) (xy 327.053369 -119.761393) (xy 326.999408 -119.753638)
			(xy 326.947101 -119.738282) (xy 326.897512 -119.715638) (xy 326.85165 -119.686168) (xy 326.810449 -119.65047)
			(xy 326.774748 -119.609271) (xy 326.745274 -119.563411) (xy 326.722627 -119.513823) (xy 326.707268 -119.461517)
			(xy 326.699509 -119.407557) (xy 318.847257 -119.407557) (xy 319.574005 -119.89308) (xy 329.76896 -119.89308)
			(xy 329.773031 -119.837458) (xy 329.785157 -119.783021) (xy 329.80508 -119.73093) (xy 329.832376 -119.682295)
			(xy 329.866462 -119.638152) (xy 329.906611 -119.599443) (xy 329.951969 -119.566992) (xy 330.001569 -119.541491)
			(xy 330.054353 -119.523484) (xy 330.109196 -119.513354) (xy 330.16493 -119.511317) (xy 330.220367 -119.517417)
			(xy 330.274324 -119.531523) (xy 330.325653 -119.553335) (xy 330.373259 -119.582389) (xy 330.416127 -119.618064)
			(xy 330.453344 -119.659601) (xy 330.484117 -119.706114) (xy 330.507789 -119.756611) (xy 330.523857 -119.810018)
			(xy 330.531977 -119.865194) (xy 330.532486 -119.89308) (xy 330.531977 -119.920966) (xy 330.523857 -119.976142)
			(xy 330.507789 -120.029549) (xy 330.484117 -120.080046) (xy 330.453344 -120.126559) (xy 330.416127 -120.168096)
			(xy 330.373259 -120.203771) (xy 330.325653 -120.232825) (xy 330.274324 -120.254637) (xy 330.220367 -120.268743)
			(xy 330.16493 -120.274843) (xy 330.109196 -120.272806) (xy 330.054353 -120.262676) (xy 330.001569 -120.244669)
			(xy 329.951969 -120.219168) (xy 329.906611 -120.186717) (xy 329.866462 -120.148008) (xy 329.832376 -120.103865)
			(xy 329.80508 -120.05523) (xy 329.785157 -120.003139) (xy 329.773031 -119.948702) (xy 329.76896 -119.89308)
			(xy 319.574005 -119.89308) (xy 319.919604 -120.123966) (xy 319.954281 -120.147628) (xy 320.019949 -120.199938)
			(xy 320.080983 -120.257587) (xy 320.136951 -120.320166) (xy 320.187457 -120.387232) (xy 320.232142 -120.458309)
			(xy 320.270689 -120.532893) (xy 320.287142 -120.571514) (xy 320.958305 -122.192034) (xy 321.650614 -122.192034)
			(xy 321.651097 -122.164664) (xy 321.65891 -122.110486) (xy 321.674395 -122.057983) (xy 321.697233 -122.008236)
			(xy 321.726954 -121.962268) (xy 321.744594 -121.941336) (xy 321.744848 -121.941082) (xy 321.750454 -121.934009)
			(xy 321.756688 -121.917082) (xy 321.75704 -121.908062) (xy 321.75704 -121.841006) (xy 321.756693 -121.831988)
			(xy 321.75044 -121.81507) (xy 321.744848 -121.807986) (xy 321.744594 -121.807986) (xy 321.744594 -121.807732)
			(xy 321.726988 -121.786772) (xy 321.697264 -121.740808) (xy 321.674419 -121.691066) (xy 321.658922 -121.638568)
			(xy 321.65109 -121.584394) (xy 321.651087 -121.529657) (xy 321.658911 -121.475482) (xy 321.674401 -121.422982)
			(xy 321.69724 -121.373237) (xy 321.726957 -121.327269) (xy 321.744594 -121.306336) (xy 321.744848 -121.306082)
			(xy 321.750454 -121.299009) (xy 321.756688 -121.282082) (xy 321.75704 -121.273062) (xy 321.75704 -121.206006)
			(xy 321.756693 -121.196988) (xy 321.75044 -121.18007) (xy 321.744848 -121.172986) (xy 321.744594 -121.172986)
			(xy 321.744594 -121.172732) (xy 321.726988 -121.151772) (xy 321.697264 -121.105808) (xy 321.674419 -121.056066)
			(xy 321.658922 -121.003568) (xy 321.65109 -120.949394) (xy 321.651087 -120.894657) (xy 321.658911 -120.840482)
			(xy 321.674401 -120.787982) (xy 321.69724 -120.738237) (xy 321.726957 -120.692269) (xy 321.744594 -120.671336)
			(xy 321.744848 -120.671082) (xy 321.750454 -120.664009) (xy 321.756688 -120.647082) (xy 321.75704 -120.638062)
			(xy 321.75704 -120.571006) (xy 321.756693 -120.561988) (xy 321.75044 -120.54507) (xy 321.744848 -120.537986)
			(xy 321.744594 -120.537986) (xy 321.744594 -120.537732) (xy 321.726956 -120.516799) (xy 321.697244 -120.470827)
			(xy 321.674408 -120.421079) (xy 321.658917 -120.368579) (xy 321.651088 -120.314403) (xy 321.650614 -120.287034)
			(xy 321.6511 -120.259783) (xy 321.658856 -120.205835) (xy 321.674211 -120.15354) (xy 321.696853 -120.103963)
			(xy 321.726319 -120.058113) (xy 321.76201 -120.016922) (xy 321.803201 -119.981231) (xy 321.849051 -119.951765)
			(xy 321.898628 -119.929123) (xy 321.950923 -119.913768) (xy 322.004871 -119.906012) (xy 322.059373 -119.906012)
			(xy 322.113321 -119.913768) (xy 322.165616 -119.929123) (xy 322.215193 -119.951765) (xy 322.261043 -119.981231)
			(xy 322.302234 -120.016922) (xy 322.337925 -120.058113) (xy 322.367391 -120.103963) (xy 322.390033 -120.15354)
			(xy 322.405388 -120.205835) (xy 322.413144 -120.259783) (xy 322.41363 -120.287034) (xy 322.413201 -120.314406)
			(xy 322.405377 -120.368587) (xy 322.38988 -120.421091) (xy 322.36703 -120.470838) (xy 322.352675 -120.493028)
			(xy 331.804008 -120.493028) (xy 331.808079 -120.437406) (xy 331.820205 -120.382969) (xy 331.840128 -120.330878)
			(xy 331.867424 -120.282243) (xy 331.90151 -120.2381) (xy 331.941659 -120.199391) (xy 331.987017 -120.16694)
			(xy 332.036617 -120.141439) (xy 332.089401 -120.123432) (xy 332.144244 -120.113302) (xy 332.199978 -120.111265)
			(xy 332.255415 -120.117365) (xy 332.309372 -120.131471) (xy 332.360701 -120.153283) (xy 332.408307 -120.182337)
			(xy 332.451175 -120.218012) (xy 332.488392 -120.259549) (xy 332.519165 -120.306062) (xy 332.542837 -120.356559)
			(xy 332.558905 -120.409966) (xy 332.567025 -120.465142) (xy 332.567534 -120.493028) (xy 332.567025 -120.520914)
			(xy 332.558905 -120.57609) (xy 332.542837 -120.629497) (xy 332.519165 -120.679994) (xy 332.488392 -120.726507)
			(xy 332.451175 -120.768044) (xy 332.4221 -120.79224) (xy 332.735934 -120.79224) (xy 332.740005 -120.736618)
			(xy 332.752131 -120.682181) (xy 332.772054 -120.63009) (xy 332.79935 -120.581455) (xy 332.833436 -120.537312)
			(xy 332.873585 -120.498603) (xy 332.918943 -120.466152) (xy 332.968543 -120.440651) (xy 333.021327 -120.422644)
			(xy 333.07617 -120.412514) (xy 333.131904 -120.410477) (xy 333.187341 -120.416577) (xy 333.241298 -120.430683)
			(xy 333.292627 -120.452495) (xy 333.340233 -120.481549) (xy 333.383101 -120.517224) (xy 333.420318 -120.558761)
			(xy 333.451091 -120.605274) (xy 333.474763 -120.655771) (xy 333.490831 -120.709178) (xy 333.498951 -120.764354)
			(xy 333.49946 -120.79224) (xy 334.891378 -120.79224) (xy 334.895449 -120.736618) (xy 334.907575 -120.682181)
			(xy 334.927498 -120.63009) (xy 334.954794 -120.581455) (xy 334.98888 -120.537312) (xy 335.029029 -120.498603)
			(xy 335.074387 -120.466152) (xy 335.123987 -120.440651) (xy 335.176771 -120.422644) (xy 335.231614 -120.412514)
			(xy 335.287348 -120.410477) (xy 335.342785 -120.416577) (xy 335.396742 -120.430683) (xy 335.448071 -120.452495)
			(xy 335.495677 -120.481549) (xy 335.538545 -120.517224) (xy 335.546679 -120.526302) (xy 338.193378 -120.526302)
			(xy 338.197449 -120.47068) (xy 338.209575 -120.416243) (xy 338.229498 -120.364152) (xy 338.256794 -120.315517)
			(xy 338.29088 -120.271374) (xy 338.331029 -120.232665) (xy 338.376387 -120.200214) (xy 338.425987 -120.174713)
			(xy 338.478771 -120.156706) (xy 338.533614 -120.146576) (xy 338.589348 -120.144539) (xy 338.644785 -120.150639)
			(xy 338.698742 -120.164745) (xy 338.750071 -120.186557) (xy 338.797677 -120.215611) (xy 338.840545 -120.251286)
			(xy 338.877762 -120.292823) (xy 338.908535 -120.339336) (xy 338.932207 -120.389833) (xy 338.948275 -120.44324)
			(xy 338.956395 -120.498416) (xy 338.956904 -120.526302) (xy 338.956395 -120.554188) (xy 338.948275 -120.609364)
			(xy 338.932207 -120.662771) (xy 338.908535 -120.713268) (xy 338.877762 -120.759781) (xy 338.840545 -120.801318)
			(xy 338.797677 -120.836993) (xy 338.750071 -120.866047) (xy 338.698742 -120.887859) (xy 338.644785 -120.901965)
			(xy 338.589348 -120.908065) (xy 338.533614 -120.906028) (xy 338.478771 -120.895898) (xy 338.425987 -120.877891)
			(xy 338.376387 -120.85239) (xy 338.331029 -120.819939) (xy 338.29088 -120.78123) (xy 338.256794 -120.737087)
			(xy 338.229498 -120.688452) (xy 338.209575 -120.636361) (xy 338.197449 -120.581924) (xy 338.193378 -120.526302)
			(xy 335.546679 -120.526302) (xy 335.575762 -120.558761) (xy 335.606535 -120.605274) (xy 335.630207 -120.655771)
			(xy 335.646275 -120.709178) (xy 335.654395 -120.764354) (xy 335.654904 -120.79224) (xy 335.654395 -120.820126)
			(xy 335.646275 -120.875302) (xy 335.630207 -120.928709) (xy 335.606535 -120.979206) (xy 335.575762 -121.025719)
			(xy 335.538545 -121.067256) (xy 335.495677 -121.102931) (xy 335.448071 -121.131985) (xy 335.396742 -121.153797)
			(xy 335.342785 -121.167903) (xy 335.287348 -121.174003) (xy 335.231614 -121.171966) (xy 335.176771 -121.161836)
			(xy 335.123987 -121.143829) (xy 335.074387 -121.118328) (xy 335.029029 -121.085877) (xy 334.98888 -121.047168)
			(xy 334.954794 -121.003025) (xy 334.927498 -120.95439) (xy 334.907575 -120.902299) (xy 334.895449 -120.847862)
			(xy 334.891378 -120.79224) (xy 333.49946 -120.79224) (xy 333.498951 -120.820126) (xy 333.490831 -120.875302)
			(xy 333.474763 -120.928709) (xy 333.451091 -120.979206) (xy 333.420318 -121.025719) (xy 333.383101 -121.067256)
			(xy 333.340233 -121.102931) (xy 333.292627 -121.131985) (xy 333.241298 -121.153797) (xy 333.187341 -121.167903)
			(xy 333.131904 -121.174003) (xy 333.07617 -121.171966) (xy 333.021327 -121.161836) (xy 332.968543 -121.143829)
			(xy 332.918943 -121.118328) (xy 332.873585 -121.085877) (xy 332.833436 -121.047168) (xy 332.79935 -121.003025)
			(xy 332.772054 -120.95439) (xy 332.752131 -120.902299) (xy 332.740005 -120.847862) (xy 332.735934 -120.79224)
			(xy 332.4221 -120.79224) (xy 332.408307 -120.803719) (xy 332.360701 -120.832773) (xy 332.309372 -120.854585)
			(xy 332.255415 -120.868691) (xy 332.199978 -120.874791) (xy 332.144244 -120.872754) (xy 332.089401 -120.862624)
			(xy 332.036617 -120.844617) (xy 331.987017 -120.819116) (xy 331.941659 -120.786665) (xy 331.90151 -120.747956)
			(xy 331.867424 -120.703813) (xy 331.840128 -120.655178) (xy 331.820205 -120.603087) (xy 331.808079 -120.54865)
			(xy 331.804008 -120.493028) (xy 322.352675 -120.493028) (xy 322.337296 -120.516802) (xy 322.31965 -120.537732)
			(xy 322.319396 -120.537986) (xy 322.313809 -120.545072) (xy 322.307563 -120.561989) (xy 322.307204 -120.571006)
			(xy 322.307204 -120.638062) (xy 322.307579 -120.647077) (xy 322.313814 -120.663994) (xy 322.319396 -120.671082)
			(xy 322.31965 -120.671082) (xy 322.31965 -120.671336) (xy 322.337325 -120.692241) (xy 322.36705 -120.738213)
			(xy 322.389895 -120.787964) (xy 322.40539 -120.84047) (xy 322.413215 -120.894653) (xy 322.413212 -120.949398)
			(xy 322.405379 -121.00358) (xy 322.389877 -121.056084) (xy 322.367025 -121.105832) (xy 322.337294 -121.1518)
			(xy 322.31965 -121.172732) (xy 322.319396 -121.172986) (xy 322.313809 -121.180072) (xy 322.307563 -121.196989)
			(xy 322.307493 -121.198756) (xy 322.685317 -121.198756) (xy 322.685317 -121.144244) (xy 322.693075 -121.090287)
			(xy 322.708433 -121.037983) (xy 322.731079 -120.988397) (xy 322.76055 -120.942539) (xy 322.796249 -120.901342)
			(xy 322.837447 -120.865644) (xy 322.883306 -120.836174) (xy 322.932892 -120.81353) (xy 322.985196 -120.798173)
			(xy 323.039154 -120.790416) (xy 323.06641 -120.789954) (xy 323.093781 -120.790401) (xy 323.147962 -120.798221)
			(xy 323.200465 -120.813714) (xy 323.250212 -120.836561) (xy 323.296177 -120.86629) (xy 323.317108 -120.883934)
			(xy 323.317362 -120.884188) (xy 323.324456 -120.889763) (xy 323.341367 -120.896017) (xy 323.350382 -120.89638)
			(xy 323.417438 -120.89638) (xy 323.426457 -120.896045) (xy 323.443374 -120.889783) (xy 323.450458 -120.884188)
			(xy 323.450458 -120.883934) (xy 323.450712 -120.883934) (xy 323.471671 -120.866328) (xy 323.517636 -120.83661)
			(xy 323.567376 -120.813767) (xy 323.619871 -120.798268) (xy 323.674043 -120.790432) (xy 323.70141 -120.789954)
			(xy 323.728658 -120.790517) (xy 323.782599 -120.798274) (xy 323.834888 -120.813628) (xy 323.884458 -120.836268)
			(xy 323.930303 -120.865731) (xy 323.971488 -120.901419) (xy 324.007175 -120.942605) (xy 324.036637 -120.98845)
			(xy 324.059275 -121.038022) (xy 324.074628 -121.090311) (xy 324.082384 -121.144252) (xy 324.082384 -121.198748)
			(xy 324.074628 -121.252689) (xy 324.059275 -121.304978) (xy 324.036637 -121.35455) (xy 324.007175 -121.400395)
			(xy 323.971488 -121.441581) (xy 323.930303 -121.477269) (xy 323.884458 -121.506732) (xy 323.834888 -121.529372)
			(xy 323.782599 -121.544726) (xy 323.728658 -121.552483) (xy 323.70141 -121.55297) (xy 323.67404 -121.552505)
			(xy 323.61986 -121.544688) (xy 323.567357 -121.529199) (xy 323.51761 -121.506357) (xy 323.471643 -121.476632)
			(xy 323.450712 -121.45899) (xy 323.450458 -121.458736) (xy 323.443364 -121.45316) (xy 323.426453 -121.446909)
			(xy 323.417438 -121.446544) (xy 323.350382 -121.446544) (xy 323.341363 -121.446883) (xy 323.324446 -121.453142)
			(xy 323.317362 -121.458736) (xy 323.317362 -121.45899) (xy 323.317108 -121.45899) (xy 323.296182 -121.476637)
			(xy 323.250208 -121.506348) (xy 323.200459 -121.529183) (xy 323.147957 -121.544672) (xy 323.09378 -121.552497)
			(xy 323.06641 -121.55297) (xy 323.039154 -121.552584) (xy 322.985197 -121.544827) (xy 322.932892 -121.52947)
			(xy 322.883306 -121.506826) (xy 322.837447 -121.477356) (xy 322.796249 -121.441658) (xy 322.76055 -121.400461)
			(xy 322.731079 -121.354603) (xy 322.708433 -121.305017) (xy 322.693075 -121.252713) (xy 322.685317 -121.198756)
			(xy 322.307493 -121.198756) (xy 322.307204 -121.206006) (xy 322.307204 -121.273062) (xy 322.307579 -121.282077)
			(xy 322.313814 -121.298994) (xy 322.319396 -121.306082) (xy 322.31965 -121.306082) (xy 322.31965 -121.306336)
			(xy 322.337325 -121.327241) (xy 322.36705 -121.373213) (xy 322.389895 -121.422964) (xy 322.40539 -121.47547)
			(xy 322.413215 -121.529653) (xy 322.413212 -121.584398) (xy 322.405968 -121.634504) (xy 324.20433 -121.634504)
			(xy 324.204791 -121.607134) (xy 324.212609 -121.552954) (xy 324.228099 -121.50045) (xy 324.250942 -121.450704)
			(xy 324.280668 -121.404737) (xy 324.29831 -121.383806) (xy 324.298564 -121.383552) (xy 324.304143 -121.37646)
			(xy 324.310392 -121.359547) (xy 324.310756 -121.350532) (xy 324.310756 -121.283476) (xy 324.31042 -121.274457)
			(xy 324.304159 -121.257539) (xy 324.298564 -121.250456) (xy 324.29831 -121.250456) (xy 324.29831 -121.250202)
			(xy 324.28066 -121.229279) (xy 324.250949 -121.183304) (xy 324.228115 -121.133554) (xy 324.212627 -121.081051)
			(xy 324.204802 -121.026874) (xy 324.20433 -120.999504) (xy 324.204759 -120.97225) (xy 324.212517 -120.918295)
			(xy 324.227874 -120.865995) (xy 324.250519 -120.816412) (xy 324.27999 -120.770557) (xy 324.315687 -120.729363)
			(xy 324.356884 -120.69367) (xy 324.402742 -120.664203) (xy 324.452326 -120.641562) (xy 324.504629 -120.626209)
			(xy 324.558583 -120.618457) (xy 324.585838 -120.617996) (xy 324.61496 -120.618546) (xy 324.672531 -120.627378)
			(xy 324.72809 -120.64486) (xy 324.780344 -120.670586) (xy 324.82808 -120.703959) (xy 324.870186 -120.744201)
			(xy 324.905684 -120.790378) (xy 324.933748 -120.841415) (xy 324.953726 -120.896126) (xy 324.95998 -120.924574)
			(xy 324.962266 -120.936258) (xy 324.976744 -120.955054) (xy 325.060818 -120.99544) (xy 325.071632 -121.000003)
			(xy 325.095071 -120.999743) (xy 325.105776 -120.994932) (xy 325.106284 -120.994932) (xy 325.13334 -120.981644)
			(xy 325.190617 -120.962868) (xy 325.250136 -120.953351) (xy 325.280274 -120.952768) (xy 325.307525 -120.953279)
			(xy 325.361473 -120.961032) (xy 325.413769 -120.976384) (xy 325.463347 -120.999021) (xy 325.509199 -121.028485)
			(xy 325.550391 -121.064173) (xy 325.586085 -121.105361) (xy 325.615555 -121.151209) (xy 325.638199 -121.200785)
			(xy 325.649355 -121.238772) (xy 329.7842 -121.238772) (xy 329.788271 -121.18315) (xy 329.800397 -121.128713)
			(xy 329.82032 -121.076622) (xy 329.847616 -121.027987) (xy 329.881702 -120.983844) (xy 329.921851 -120.945135)
			(xy 329.967209 -120.912684) (xy 330.016809 -120.887183) (xy 330.069593 -120.869176) (xy 330.124436 -120.859046)
			(xy 330.18017 -120.857009) (xy 330.235607 -120.863109) (xy 330.289564 -120.877215) (xy 330.340893 -120.899027)
			(xy 330.388499 -120.928081) (xy 330.431367 -120.963756) (xy 330.468584 -121.005293) (xy 330.499357 -121.051806)
			(xy 330.523029 -121.102303) (xy 330.539097 -121.15571) (xy 330.547217 -121.210886) (xy 330.547726 -121.238772)
			(xy 330.547217 -121.266658) (xy 330.539097 -121.321834) (xy 330.523029 -121.375241) (xy 330.499357 -121.425738)
			(xy 330.468584 -121.472251) (xy 330.431367 -121.513788) (xy 330.388499 -121.549463) (xy 330.340893 -121.578517)
			(xy 330.289564 -121.600329) (xy 330.235607 -121.614435) (xy 330.18017 -121.620535) (xy 330.124436 -121.618498)
			(xy 330.069593 -121.608368) (xy 330.016809 -121.590361) (xy 329.967209 -121.56486) (xy 329.921851 -121.532409)
			(xy 329.881702 -121.4937) (xy 329.847616 -121.449557) (xy 329.82032 -121.400922) (xy 329.800397 -121.348831)
			(xy 329.788271 -121.294394) (xy 329.7842 -121.238772) (xy 325.649355 -121.238772) (xy 325.653557 -121.253078)
			(xy 325.661317 -121.307025) (xy 325.661782 -121.334276) (xy 325.661306 -121.361646) (xy 325.653491 -121.415825)
			(xy 325.638005 -121.468328) (xy 325.615165 -121.518075) (xy 325.585442 -121.564042) (xy 325.567802 -121.584974)
			(xy 325.567548 -121.585228) (xy 325.561979 -121.592327) (xy 325.555723 -121.609234) (xy 325.555356 -121.618248)
			(xy 325.555356 -121.685304) (xy 325.555699 -121.694323) (xy 325.561955 -121.71124) (xy 325.567548 -121.718324)
			(xy 325.567802 -121.718324) (xy 325.567802 -121.718578) (xy 325.585445 -121.739507) (xy 325.615156 -121.785481)
			(xy 325.637991 -121.835229) (xy 325.653481 -121.88773) (xy 325.661309 -121.941907) (xy 325.661782 -121.969276)
			(xy 325.661322 -121.996529) (xy 325.653568 -122.050482) (xy 325.638214 -122.102781) (xy 325.615572 -122.152363)
			(xy 325.586104 -122.198218) (xy 325.55041 -122.239411) (xy 325.509216 -122.275105) (xy 325.463361 -122.304573)
			(xy 325.413779 -122.327214) (xy 325.36148 -122.342568) (xy 325.307527 -122.350322) (xy 325.280274 -122.350784)
			(xy 325.251151 -122.350239) (xy 325.193579 -122.341409) (xy 325.13802 -122.323927) (xy 325.085764 -122.2982)
			(xy 325.038028 -122.264827) (xy 324.995922 -122.224584) (xy 324.960424 -122.178406) (xy 324.932361 -122.127367)
			(xy 324.912385 -122.072655) (xy 324.906132 -122.044206) (xy 324.903846 -122.032522) (xy 324.889368 -122.013726)
			(xy 324.805294 -121.97334) (xy 324.794479 -121.968779) (xy 324.77104 -121.969034) (xy 324.760336 -121.973848)
			(xy 324.759828 -121.973848) (xy 324.732769 -121.98713) (xy 324.675494 -122.005909) (xy 324.615975 -122.015428)
			(xy 324.585838 -122.016012) (xy 324.558586 -122.015509) (xy 324.504637 -122.007758) (xy 324.45234 -121.992407)
			(xy 324.40276 -121.969769) (xy 324.356907 -121.940305) (xy 324.315714 -121.904616) (xy 324.28002 -121.863426)
			(xy 324.250551 -121.817577) (xy 324.227908 -121.767999) (xy 324.212551 -121.715704) (xy 324.204794 -121.661756)
			(xy 324.20433 -121.634504) (xy 322.405968 -121.634504) (xy 322.405379 -121.63858) (xy 322.389877 -121.691084)
			(xy 322.367025 -121.740832) (xy 322.337294 -121.7868) (xy 322.31965 -121.807732) (xy 322.319396 -121.807986)
			(xy 322.313809 -121.815072) (xy 322.307563 -121.831989) (xy 322.307204 -121.841006) (xy 322.307204 -121.908062)
			(xy 322.307579 -121.917077) (xy 322.313814 -121.933994) (xy 322.319396 -121.941082) (xy 322.31965 -121.941082)
			(xy 322.31965 -121.941336) (xy 322.337265 -121.962288) (xy 322.366982 -122.008254) (xy 322.389823 -122.057997)
			(xy 322.40532 -122.110493) (xy 322.413153 -122.164666) (xy 322.41363 -122.192034) (xy 322.413144 -122.219285)
			(xy 322.405388 -122.273233) (xy 322.390033 -122.325528) (xy 322.367391 -122.375105) (xy 322.337925 -122.420955)
			(xy 322.302234 -122.462146) (xy 322.261043 -122.497837) (xy 322.215193 -122.527303) (xy 322.165616 -122.549945)
			(xy 322.113321 -122.5653) (xy 322.059373 -122.573056) (xy 322.004871 -122.573056) (xy 321.950923 -122.5653)
			(xy 321.898628 -122.549945) (xy 321.849051 -122.527303) (xy 321.803201 -122.497837) (xy 321.76201 -122.462146)
			(xy 321.726319 -122.420955) (xy 321.696853 -122.375105) (xy 321.674211 -122.325528) (xy 321.658856 -122.273233)
			(xy 321.6511 -122.219285) (xy 321.650614 -122.192034) (xy 320.958305 -122.192034) (xy 321.443919 -123.364548)
			(xy 326.264298 -123.364548) (xy 326.264298 -123.310052) (xy 326.272053 -123.256109) (xy 326.287406 -123.20382)
			(xy 326.310044 -123.154247) (xy 326.339506 -123.108401) (xy 326.375192 -123.067214) (xy 326.416377 -123.031524)
			(xy 326.462221 -123.002058) (xy 326.511792 -122.979417) (xy 326.56408 -122.96406) (xy 326.618022 -122.9563)
			(xy 326.64527 -122.955812) (xy 326.67264 -122.956293) (xy 326.726818 -122.964107) (xy 326.779321 -122.979592)
			(xy 326.829068 -123.002431) (xy 326.875036 -123.032152) (xy 326.895968 -123.049792) (xy 326.896222 -123.050046)
			(xy 326.903294 -123.055653) (xy 326.920222 -123.061886) (xy 326.929242 -123.062238) (xy 326.996298 -123.062238)
			(xy 327.005314 -123.061872) (xy 327.02223 -123.055629) (xy 327.029318 -123.050046) (xy 327.029318 -123.049792)
			(xy 327.029572 -123.049792) (xy 327.050505 -123.032151) (xy 327.096473 -123.002427) (xy 327.146219 -122.979581)
			(xy 327.198721 -122.964085) (xy 327.252899 -122.956256) (xy 327.307641 -122.956256) (xy 327.361819 -122.964085)
			(xy 327.414321 -122.979581) (xy 327.464067 -123.002427) (xy 327.510035 -123.032151) (xy 327.530968 -123.049792)
			(xy 327.531222 -123.050046) (xy 327.538294 -123.055653) (xy 327.555222 -123.061886) (xy 327.564242 -123.062238)
			(xy 327.631298 -123.062238) (xy 327.640314 -123.061872) (xy 327.65723 -123.055629) (xy 327.664318 -123.050046)
			(xy 327.664318 -123.049792) (xy 327.664572 -123.049792) (xy 327.685503 -123.032151) (xy 327.731476 -123.00244)
			(xy 327.781224 -122.979604) (xy 327.833725 -122.964114) (xy 327.887901 -122.956286) (xy 327.91527 -122.955812)
			(xy 327.942526 -122.956233) (xy 327.996483 -122.963987) (xy 328.048787 -122.979341) (xy 328.098374 -123.001983)
			(xy 328.144233 -123.031452) (xy 328.185431 -123.067147) (xy 328.22113 -123.108343) (xy 328.250603 -123.1542)
			(xy 328.273248 -123.203785) (xy 328.288607 -123.256088) (xy 328.296365 -123.310044) (xy 328.296365 -123.364556)
			(xy 328.288607 -123.418512) (xy 328.273248 -123.470815) (xy 328.250603 -123.5204) (xy 328.22113 -123.566257)
			(xy 328.185431 -123.607453) (xy 328.144233 -123.643148) (xy 328.098374 -123.672617) (xy 328.048787 -123.695259)
			(xy 327.996483 -123.710613) (xy 327.942526 -123.718367) (xy 327.91527 -123.718828) (xy 327.887898 -123.718397)
			(xy 327.833717 -123.710573) (xy 327.781213 -123.695077) (xy 327.731466 -123.672227) (xy 327.685502 -123.642494)
			(xy 327.664572 -123.624848) (xy 327.664318 -123.624594) (xy 327.657231 -123.619008) (xy 327.640315 -123.612761)
			(xy 327.631298 -123.612402) (xy 327.564242 -123.612402) (xy 327.555227 -123.612779) (xy 327.53831 -123.619013)
			(xy 327.531222 -123.624594) (xy 327.531222 -123.624848) (xy 327.530968 -123.624848) (xy 327.510035 -123.642489)
			(xy 327.464067 -123.672213) (xy 327.414321 -123.695059) (xy 327.361819 -123.710555) (xy 327.307641 -123.718384)
			(xy 327.252899 -123.718384) (xy 327.198721 -123.710555) (xy 327.146219 -123.695059) (xy 327.096473 -123.672213)
			(xy 327.050505 -123.642489) (xy 327.029572 -123.624848) (xy 327.029318 -123.624594) (xy 327.022231 -123.619008)
			(xy 327.005315 -123.612761) (xy 326.996298 -123.612402) (xy 326.929242 -123.612402) (xy 326.920227 -123.612779)
			(xy 326.90331 -123.619013) (xy 326.896222 -123.624594) (xy 326.896222 -123.624848) (xy 326.895968 -123.624848)
			(xy 326.875014 -123.642461) (xy 326.829048 -123.672178) (xy 326.779306 -123.69502) (xy 326.72681 -123.710517)
			(xy 326.672638 -123.718351) (xy 326.64527 -123.718828) (xy 326.618022 -123.7183) (xy 326.56408 -123.71054)
			(xy 326.511792 -123.695183) (xy 326.462221 -123.672542) (xy 326.416377 -123.643076) (xy 326.375192 -123.607386)
			(xy 326.339506 -123.566199) (xy 326.310044 -123.520353) (xy 326.287406 -123.47078) (xy 326.272053 -123.418491)
			(xy 326.264298 -123.364548) (xy 321.443919 -123.364548) (xy 321.633474 -123.822229) (xy 329.642205 -123.822229)
			(xy 329.642208 -123.767731) (xy 329.649966 -123.713788) (xy 329.665323 -123.661498) (xy 329.687965 -123.611926)
			(xy 329.717431 -123.566081) (xy 329.753121 -123.524896) (xy 329.79431 -123.489209) (xy 329.840158 -123.459747)
			(xy 329.889732 -123.43711) (xy 329.942023 -123.421759) (xy 329.995967 -123.414005) (xy 330.023216 -123.41352)
			(xy 330.023724 -123.41352) (xy 330.034096 -123.4136) (xy 330.054808 -123.414744) (xy 330.065126 -123.415806)
			(xy 330.079675 -123.416857) (xy 330.108365 -123.411664) (xy 330.134422 -123.398584) (xy 330.155726 -123.378679)
			(xy 330.170544 -123.35357) (xy 330.177672 -123.325299) (xy 330.176529 -123.296165) (xy 330.172314 -123.282202)
			(xy 330.162954 -123.252595) (xy 330.152876 -123.191327) (xy 330.152248 -123.160282) (xy 330.152248 -123.160028)
			(xy 330.152725 -123.132772) (xy 330.160479 -123.078814) (xy 330.175834 -123.02651) (xy 330.198476 -122.976922)
			(xy 330.227945 -122.931063) (xy 330.263641 -122.889864) (xy 330.304837 -122.854164) (xy 330.350694 -122.824691)
			(xy 330.40028 -122.802045) (xy 330.452583 -122.786686) (xy 330.50654 -122.778927) (xy 330.561052 -122.778927)
			(xy 330.615009 -122.786684) (xy 330.667313 -122.802042) (xy 330.716899 -122.824688) (xy 330.762757 -122.85416)
			(xy 330.803953 -122.889858) (xy 330.83965 -122.931056) (xy 330.86912 -122.976915) (xy 330.891763 -123.026502)
			(xy 330.907119 -123.078807) (xy 330.914874 -123.132764) (xy 330.914872 -123.187276) (xy 330.907111 -123.241233)
			(xy 330.891749 -123.293535) (xy 330.869101 -123.34312) (xy 330.839626 -123.388976) (xy 330.803925 -123.43017)
			(xy 330.762725 -123.465864) (xy 330.716863 -123.495332) (xy 330.667275 -123.517972) (xy 330.61497 -123.533324)
			(xy 330.561012 -123.541076) (xy 330.533756 -123.541536) (xy 330.533248 -123.541536) (xy 330.522876 -123.541459)
			(xy 330.502164 -123.540313) (xy 330.491846 -123.53925) (xy 330.477298 -123.538232) (xy 330.448617 -123.543429)
			(xy 330.422569 -123.556508) (xy 330.40127 -123.576406) (xy 330.386452 -123.601506) (xy 330.379319 -123.629767)
			(xy 330.380451 -123.658893) (xy 330.384658 -123.672854) (xy 330.39401 -123.702463) (xy 330.404093 -123.763729)
			(xy 330.404724 -123.794774) (xy 330.404724 -123.795028) (xy 330.404192 -123.822277) (xy 330.396432 -123.87622)
			(xy 330.381074 -123.928509) (xy 330.358432 -123.978081) (xy 330.328965 -124.023925) (xy 330.293273 -124.06511)
			(xy 330.252084 -124.100796) (xy 330.206235 -124.130257) (xy 330.15666 -124.152893) (xy 330.104369 -124.168243)
			(xy 330.050425 -124.175996) (xy 329.995927 -124.175992) (xy 329.941984 -124.168233) (xy 329.889695 -124.152876)
			(xy 329.840123 -124.130234) (xy 329.794278 -124.100767) (xy 329.753093 -124.065076) (xy 329.717407 -124.023887)
			(xy 329.687945 -123.978039) (xy 329.665309 -123.928464) (xy 329.649958 -123.876173) (xy 329.642205 -123.822229)
			(xy 321.633474 -123.822229) (xy 321.796206 -124.215144) (xy 326.806558 -124.215144) (xy 326.810629 -124.159522)
			(xy 326.822755 -124.105085) (xy 326.842678 -124.052994) (xy 326.869974 -124.004359) (xy 326.90406 -123.960216)
			(xy 326.944209 -123.921507) (xy 326.989567 -123.889056) (xy 327.039167 -123.863555) (xy 327.091951 -123.845548)
			(xy 327.146794 -123.835418) (xy 327.202528 -123.833381) (xy 327.257965 -123.839481) (xy 327.311922 -123.853587)
			(xy 327.363251 -123.875399) (xy 327.410857 -123.904453) (xy 327.453725 -123.940128) (xy 327.490942 -123.981665)
			(xy 327.521715 -124.028178) (xy 327.545387 -124.078675) (xy 327.561455 -124.132082) (xy 327.569575 -124.187258)
			(xy 327.570084 -124.215144) (xy 327.569575 -124.24303) (xy 327.561455 -124.298206) (xy 327.545387 -124.351613)
			(xy 327.521715 -124.40211) (xy 327.490942 -124.448623) (xy 327.453725 -124.49016) (xy 327.410857 -124.525835)
			(xy 327.363251 -124.554889) (xy 327.311922 -124.576701) (xy 327.257965 -124.590807) (xy 327.202528 -124.596907)
			(xy 327.146794 -124.59487) (xy 327.091951 -124.58474) (xy 327.039167 -124.566733) (xy 326.989567 -124.541232)
			(xy 326.944209 -124.508781) (xy 326.90406 -124.470072) (xy 326.869974 -124.425929) (xy 326.842678 -124.377294)
			(xy 326.822755 -124.325203) (xy 326.810629 -124.270766) (xy 326.806558 -124.215144) (xy 321.796206 -124.215144)
			(xy 322.120006 -124.996956) (xy 322.136262 -125.011942) (xy 322.142104 -125.01372) (xy 322.167731 -125.021924)
			(xy 322.216559 -125.044532) (xy 322.261727 -125.073775) (xy 322.302339 -125.109073) (xy 322.33759 -125.149726)
			(xy 322.366781 -125.194928) (xy 322.389333 -125.243782) (xy 322.404798 -125.295319) (xy 322.412871 -125.348518)
			(xy 322.41363 -125.375416) (xy 322.41363 -125.385068) (xy 322.413415 -125.395382) (xy 322.412018 -125.415967)
			(xy 322.410836 -125.426216) (xy 322.407453 -125.450219) (xy 322.395399 -125.497172) (xy 322.377508 -125.542224)
			(xy 322.366132 -125.56363) (xy 322.365116 -125.565154) (xy 322.364354 -125.586998) (xy 322.490514 -125.891544)
			(xy 327.375012 -125.891544) (xy 327.375438 -125.865229) (xy 327.382681 -125.813098) (xy 327.397008 -125.762454)
			(xy 327.418148 -125.714256) (xy 327.445702 -125.669413) (xy 327.479147 -125.628775) (xy 327.498202 -125.61062)
			(xy 327.505597 -125.603093) (xy 327.514125 -125.583817) (xy 327.514712 -125.573282) (xy 327.514712 -125.498606)
			(xy 327.51419 -125.488056) (xy 327.505649 -125.46876) (xy 327.498202 -125.461268) (xy 327.479138 -125.443121)
			(xy 327.445682 -125.402489) (xy 327.418124 -125.357647) (xy 327.396987 -125.309445) (xy 327.382671 -125.258796)
			(xy 327.375449 -125.206661) (xy 327.375012 -125.180344) (xy 327.375498 -125.153093) (xy 327.383254 -125.099145)
			(xy 327.398609 -125.04685) (xy 327.421251 -124.997273) (xy 327.450717 -124.951423) (xy 327.486408 -124.910232)
			(xy 327.527599 -124.874541) (xy 327.573449 -124.845075) (xy 327.623026 -124.822433) (xy 327.675321 -124.807078)
			(xy 327.729269 -124.799322) (xy 327.783771 -124.799322) (xy 327.837719 -124.807078) (xy 327.890014 -124.822433)
			(xy 327.939591 -124.845075) (xy 327.985441 -124.874541) (xy 328.026632 -124.910232) (xy 328.062323 -124.951423)
			(xy 328.091789 -124.997273) (xy 328.114431 -125.04685) (xy 328.129786 -125.099145) (xy 328.137542 -125.153093)
			(xy 328.138028 -125.180344) (xy 328.137581 -125.206659) (xy 328.130341 -125.258788) (xy 328.116017 -125.30943)
			(xy 328.094881 -125.357629) (xy 328.067331 -125.402472) (xy 328.03389 -125.443111) (xy 328.014838 -125.461268)
			(xy 328.007454 -125.468805) (xy 327.998919 -125.488073) (xy 327.998328 -125.498606) (xy 327.998328 -125.573282)
			(xy 327.998845 -125.583833) (xy 328.007388 -125.603129) (xy 328.014838 -125.61062) (xy 328.033903 -125.628765)
			(xy 328.067358 -125.669398) (xy 328.094915 -125.714241) (xy 328.116052 -125.762443) (xy 328.130367 -125.813092)
			(xy 328.13759 -125.865227) (xy 328.138028 -125.891544) (xy 328.137542 -125.918795) (xy 328.129786 -125.972743)
			(xy 328.114431 -126.025038) (xy 328.091789 -126.074615) (xy 328.062323 -126.120465) (xy 328.026632 -126.161656)
			(xy 327.985441 -126.197347) (xy 327.939591 -126.226813) (xy 327.890014 -126.249455) (xy 327.837719 -126.26481)
			(xy 327.783771 -126.272566) (xy 327.729269 -126.272566) (xy 327.675321 -126.26481) (xy 327.623026 -126.249455)
			(xy 327.573449 -126.226813) (xy 327.527599 -126.197347) (xy 327.486408 -126.161656) (xy 327.450717 -126.120465)
			(xy 327.421251 -126.074615) (xy 327.398609 -126.025038) (xy 327.383254 -125.972743) (xy 327.375498 -125.918795)
			(xy 327.375012 -125.891544) (xy 322.490514 -125.891544) (xy 324.273164 -130.194812) (xy 324.27517 -130.199377)
			(xy 324.280666 -130.207694) (xy 324.284086 -130.211322) (xy 324.45198 -130.37947) (xy 324.486198 -130.41449)
			(xy 324.548371 -130.490136) (xy 324.602833 -130.571509) (xy 324.649061 -130.657826) (xy 324.668388 -130.702812)
			(xy 325.560589 -132.856732) (xy 334.376522 -132.856732) (xy 334.37699 -132.829866) (xy 334.384514 -132.776664)
			(xy 334.399431 -132.725045) (xy 334.421446 -132.67603) (xy 334.450122 -132.630591) (xy 334.484893 -132.589627)
			(xy 334.52507 -132.553949) (xy 334.54721 -132.538724) (xy 334.557116 -132.53212) (xy 334.569054 -132.512054)
			(xy 334.575658 -132.419852) (xy 334.575959 -132.408145) (xy 334.567209 -132.386445) (xy 334.558894 -132.378196)
			(xy 334.55864 -132.378196) (xy 334.538953 -132.360013) (xy 334.504355 -132.319088) (xy 334.475824 -132.273724)
			(xy 334.45392 -132.224814) (xy 334.439076 -132.173321) (xy 334.431583 -132.120257) (xy 334.431132 -132.093462)
			(xy 334.43152 -132.066206) (xy 334.439283 -132.012251) (xy 334.454646 -131.959949) (xy 334.477296 -131.910366)
			(xy 334.506771 -131.864511) (xy 334.542473 -131.823318) (xy 334.583673 -131.787625) (xy 334.629534 -131.758158)
			(xy 334.679122 -131.735518) (xy 334.731427 -131.720166) (xy 334.785384 -131.712414) (xy 334.81264 -131.711954)
			(xy 334.83921 -131.712399) (xy 334.891838 -131.719755) (xy 334.942935 -131.734347) (xy 334.991512 -131.755891)
			(xy 335.036627 -131.783971) (xy 335.077406 -131.818043) (xy 335.11306 -131.857446) (xy 335.142897 -131.901419)
			(xy 335.155032 -131.92506) (xy 335.159221 -131.932932) (xy 335.172043 -131.945312) (xy 335.188329 -131.952554)
			(xy 335.197196 -131.953508) (xy 335.29905 -131.960112) (xy 335.32318 -131.948174) (xy 335.3308 -131.936744)
			(xy 335.346033 -131.914676) (xy 335.381682 -131.87462) (xy 335.422592 -131.839955) (xy 335.467957 -131.811365)
			(xy 335.51688 -131.789413) (xy 335.568396 -131.774534) (xy 335.621489 -131.76702) (xy 335.6483 -131.766564)
			(xy 335.67555 -131.767078) (xy 335.729495 -131.774833) (xy 335.781788 -131.790187) (xy 335.831363 -131.812826)
			(xy 335.877212 -131.84229) (xy 335.918402 -131.877978) (xy 335.954093 -131.919165) (xy 335.98356 -131.965012)
			(xy 336.006203 -132.014586) (xy 336.021561 -132.066877) (xy 336.02932 -132.120822) (xy 336.029808 -132.148072)
			(xy 336.02942 -132.174168) (xy 336.022308 -132.225873) (xy 336.008212 -132.276126) (xy 335.987397 -132.323988)
			(xy 335.960251 -132.368565) (xy 335.92728 -132.409024) (xy 335.889101 -132.44461) (xy 335.86801 -132.459984)
			(xy 335.858866 -132.466334) (xy 335.84769 -132.485384) (xy 335.839054 -132.57276) (xy 335.838439 -132.583664)
			(xy 335.845421 -132.604335) (xy 335.852516 -132.612638) (xy 335.85277 -132.612892) (xy 335.872282 -132.634241)
			(xy 335.905237 -132.68177) (xy 335.930637 -132.733729) (xy 335.9479 -132.788929) (xy 335.95663 -132.846102)
			(xy 335.957164 -132.87502) (xy 335.956764 -132.902275) (xy 335.949003 -132.956231) (xy 335.933642 -133.008533)
			(xy 335.910994 -133.058116) (xy 335.88152 -133.103971) (xy 335.845819 -133.145165) (xy 335.80462 -133.180858)
			(xy 335.75876 -133.210325) (xy 335.709173 -133.232964) (xy 335.656868 -133.248316) (xy 335.602911 -133.256068)
			(xy 335.575656 -133.256528) (xy 335.547526 -133.256047) (xy 335.491876 -133.247779) (xy 335.438044 -133.231429)
			(xy 335.387197 -133.207351) (xy 335.340436 -133.176068) (xy 335.298776 -133.138257) (xy 335.26312 -133.094738)
			(xy 335.24825 -133.070854) (xy 335.243565 -133.06368) (xy 335.230426 -133.052701) (xy 335.214385 -133.046713)
			(xy 335.205832 -133.046216) (xy 335.119726 -133.044184) (xy 335.111156 -133.044304) (xy 335.094879 -133.049653)
			(xy 335.081274 -133.060067) (xy 335.076292 -133.067044) (xy 335.061094 -133.08925) (xy 335.025422 -133.129536)
			(xy 334.984442 -133.164408) (xy 334.938966 -133.193173) (xy 334.889897 -133.215259) (xy 334.838212 -133.230228)
			(xy 334.784935 -133.237783) (xy 334.75803 -133.23824) (xy 334.730781 -133.237694) (xy 334.676837 -133.229942)
			(xy 334.624545 -133.214593) (xy 334.574971 -133.191957) (xy 334.529122 -133.162497) (xy 334.487932 -133.126812)
			(xy 334.45224 -133.085628) (xy 334.422772 -133.039784) (xy 334.400129 -132.990213) (xy 334.384771 -132.937924)
			(xy 334.37701 -132.883981) (xy 334.376522 -132.856732) (xy 325.560589 -132.856732) (xy 329.109401 -141.424152)
			(xy 336.674204 -141.424152) (xy 336.678275 -141.36853) (xy 336.690401 -141.314093) (xy 336.710324 -141.262002)
			(xy 336.73762 -141.213367) (xy 336.771706 -141.169224) (xy 336.811855 -141.130515) (xy 336.857213 -141.098064)
			(xy 336.906813 -141.072563) (xy 336.959597 -141.054556) (xy 337.01444 -141.044426) (xy 337.070174 -141.042389)
			(xy 337.125611 -141.048489) (xy 337.179568 -141.062595) (xy 337.230897 -141.084407) (xy 337.278503 -141.113461)
			(xy 337.321371 -141.149136) (xy 337.358588 -141.190673) (xy 337.389361 -141.237186) (xy 337.413033 -141.287683)
			(xy 337.429101 -141.34109) (xy 337.437221 -141.396266) (xy 337.43773 -141.424152) (xy 337.437221 -141.452038)
			(xy 337.429101 -141.507214) (xy 337.413033 -141.560621) (xy 337.389361 -141.611118) (xy 337.358588 -141.657631)
			(xy 337.321371 -141.699168) (xy 337.278503 -141.734843) (xy 337.230897 -141.763897) (xy 337.179568 -141.785709)
			(xy 337.125611 -141.799815) (xy 337.070174 -141.805915) (xy 337.01444 -141.803878) (xy 336.959597 -141.793748)
			(xy 336.906813 -141.775741) (xy 336.857213 -141.75024) (xy 336.811855 -141.717789) (xy 336.771706 -141.67908)
			(xy 336.73762 -141.634937) (xy 336.710324 -141.586302) (xy 336.690401 -141.534211) (xy 336.678275 -141.479774)
			(xy 336.674204 -141.424152) (xy 329.109401 -141.424152) (xy 329.289525 -141.859) (xy 334.643982 -141.859)
			(xy 334.648053 -141.803378) (xy 334.660179 -141.748941) (xy 334.680102 -141.69685) (xy 334.707398 -141.648215)
			(xy 334.741484 -141.604072) (xy 334.781633 -141.565363) (xy 334.826991 -141.532912) (xy 334.876591 -141.507411)
			(xy 334.929375 -141.489404) (xy 334.984218 -141.479274) (xy 335.039952 -141.477237) (xy 335.095389 -141.483337)
			(xy 335.149346 -141.497443) (xy 335.200675 -141.519255) (xy 335.248281 -141.548309) (xy 335.291149 -141.583984)
			(xy 335.328366 -141.625521) (xy 335.359139 -141.672034) (xy 335.382811 -141.722531) (xy 335.398879 -141.775938)
			(xy 335.406999 -141.831114) (xy 335.407508 -141.859) (xy 335.406999 -141.886886) (xy 335.398879 -141.942062)
			(xy 335.382811 -141.995469) (xy 335.359139 -142.045966) (xy 335.328366 -142.092479) (xy 335.291149 -142.134016)
			(xy 335.248281 -142.169691) (xy 335.200675 -142.198745) (xy 335.149346 -142.220557) (xy 335.095389 -142.234663)
			(xy 335.039952 -142.240763) (xy 334.984218 -142.238726) (xy 334.929375 -142.228596) (xy 334.876591 -142.210589)
			(xy 334.826991 -142.185088) (xy 334.781633 -142.152637) (xy 334.741484 -142.113928) (xy 334.707398 -142.069785)
			(xy 334.680102 -142.02115) (xy 334.660179 -141.969059) (xy 334.648053 -141.914622) (xy 334.643982 -141.859)
			(xy 329.289525 -141.859) (xy 329.710374 -142.875) (xy 334.643982 -142.875) (xy 334.648053 -142.819378)
			(xy 334.660179 -142.764941) (xy 334.680102 -142.71285) (xy 334.707398 -142.664215) (xy 334.741484 -142.620072)
			(xy 334.781633 -142.581363) (xy 334.826991 -142.548912) (xy 334.876591 -142.523411) (xy 334.929375 -142.505404)
			(xy 334.984218 -142.495274) (xy 335.039952 -142.493237) (xy 335.095389 -142.499337) (xy 335.149346 -142.513443)
			(xy 335.200675 -142.535255) (xy 335.248281 -142.564309) (xy 335.291149 -142.599984) (xy 335.328366 -142.641521)
			(xy 335.359139 -142.688034) (xy 335.382811 -142.738531) (xy 335.398879 -142.791938) (xy 335.406999 -142.847114)
			(xy 335.407508 -142.875) (xy 336.675982 -142.875) (xy 336.680053 -142.819378) (xy 336.692179 -142.764941)
			(xy 336.712102 -142.71285) (xy 336.739398 -142.664215) (xy 336.773484 -142.620072) (xy 336.813633 -142.581363)
			(xy 336.858991 -142.548912) (xy 336.908591 -142.523411) (xy 336.961375 -142.505404) (xy 337.016218 -142.495274)
			(xy 337.071952 -142.493237) (xy 337.127389 -142.499337) (xy 337.181346 -142.513443) (xy 337.232675 -142.535255)
			(xy 337.280281 -142.564309) (xy 337.323149 -142.599984) (xy 337.360366 -142.641521) (xy 337.391139 -142.688034)
			(xy 337.414811 -142.738531) (xy 337.430879 -142.791938) (xy 337.438999 -142.847114) (xy 337.439508 -142.875)
			(xy 337.438999 -142.902886) (xy 337.430879 -142.958062) (xy 337.414811 -143.011469) (xy 337.391139 -143.061966)
			(xy 337.360366 -143.108479) (xy 337.323149 -143.150016) (xy 337.280281 -143.185691) (xy 337.232675 -143.214745)
			(xy 337.181346 -143.236557) (xy 337.127389 -143.250663) (xy 337.071952 -143.256763) (xy 337.016218 -143.254726)
			(xy 336.961375 -143.244596) (xy 336.908591 -143.226589) (xy 336.858991 -143.201088) (xy 336.813633 -143.168637)
			(xy 336.773484 -143.129928) (xy 336.739398 -143.085785) (xy 336.712102 -143.03715) (xy 336.692179 -142.985059)
			(xy 336.680053 -142.930622) (xy 336.675982 -142.875) (xy 335.407508 -142.875) (xy 335.406999 -142.902886)
			(xy 335.398879 -142.958062) (xy 335.382811 -143.011469) (xy 335.359139 -143.061966) (xy 335.328366 -143.108479)
			(xy 335.291149 -143.150016) (xy 335.248281 -143.185691) (xy 335.200675 -143.214745) (xy 335.149346 -143.236557)
			(xy 335.095389 -143.250663) (xy 335.039952 -143.256763) (xy 334.984218 -143.254726) (xy 334.929375 -143.244596)
			(xy 334.876591 -143.226589) (xy 334.826991 -143.201088) (xy 334.781633 -143.168637) (xy 334.741484 -143.129928)
			(xy 334.707398 -143.085785) (xy 334.680102 -143.03715) (xy 334.660179 -142.985059) (xy 334.648053 -142.930622)
			(xy 334.643982 -142.875) (xy 329.710374 -142.875) (xy 329.965304 -143.490442) (xy 329.969552 -143.499494)
			(xy 329.983632 -143.513664) (xy 330.002055 -143.521386) (xy 330.01204 -143.521938) (xy 330.121006 -143.522446)
			(xy 330.146406 -143.505682) (xy 330.152502 -143.491458) (xy 330.163912 -143.466072) (xy 330.193008 -143.418628)
			(xy 330.22869 -143.375916) (xy 330.2702 -143.338842) (xy 330.316657 -143.308194) (xy 330.367074 -143.284624)
			(xy 330.420382 -143.26863) (xy 330.475448 -143.260553) (xy 330.503276 -143.260064) (xy 330.531012 -143.260567)
			(xy 330.585898 -143.268609) (xy 330.639041 -143.284512) (xy 330.689322 -143.307942) (xy 330.735682 -143.338404)
			(xy 330.777142 -143.375258) (xy 330.812831 -143.417725) (xy 330.841995 -143.464912) (xy 330.86402 -143.515824)
			(xy 330.878443 -143.569388) (xy 330.882244 -143.596868) (xy 330.883768 -143.610584) (xy 330.885038 -143.641572)
			(xy 330.885038 -143.661892) (xy 330.883768 -143.67383) (xy 330.881106 -143.700028) (xy 330.869486 -143.751388)
			(xy 330.850905 -143.800659) (xy 330.825718 -143.846903) (xy 330.794405 -143.88924) (xy 330.757562 -143.926862)
			(xy 330.71589 -143.959054) (xy 330.693268 -143.972534) (xy 330.687426 -143.97609) (xy 330.68387 -143.978122)
			(xy 330.67752 -143.982948) (xy 330.674472 -143.985234) (xy 330.66609 -143.993616) (xy 330.663104 -143.996647)
			(xy 330.658121 -144.003543) (xy 330.656184 -144.007332) (xy 330.652628 -144.014952) (xy 330.651612 -144.023588)
			(xy 330.648056 -144.05356) (xy 330.648056 -144.054068) (xy 330.643738 -144.089628) (xy 330.64323 -144.095724)
			(xy 330.64323 -144.11071) (xy 330.652628 -144.131792) (xy 330.653136 -144.132808) (xy 330.655168 -144.13738)
			(xy 330.66609 -144.152366) (xy 330.669646 -144.155668) (xy 330.688171 -144.173733) (xy 330.720665 -144.214001)
			(xy 330.747411 -144.258295) (xy 330.767918 -144.305802) (xy 330.781808 -144.355646) (xy 330.788825 -144.406911)
			(xy 330.78928 -144.432782) (xy 330.78928 -144.43329) (xy 330.788762 -144.461688) (xy 330.780358 -144.517858)
			(xy 330.763734 -144.572166) (xy 330.739256 -144.623416) (xy 330.707462 -144.670479) (xy 330.669054 -144.712319)
			(xy 330.624877 -144.748014) (xy 330.575904 -144.776778) (xy 330.549758 -144.787874) (xy 330.548742 -144.788382)
			(xy 330.536804 -144.793462) (xy 330.520802 -144.83207) (xy 330.972717 -145.923) (xy 334.643982 -145.923)
			(xy 334.648053 -145.867378) (xy 334.660179 -145.812941) (xy 334.680102 -145.76085) (xy 334.707398 -145.712215)
			(xy 334.741484 -145.668072) (xy 334.781633 -145.629363) (xy 334.826991 -145.596912) (xy 334.876591 -145.571411)
			(xy 334.929375 -145.553404) (xy 334.984218 -145.543274) (xy 335.039952 -145.541237) (xy 335.095389 -145.547337)
			(xy 335.149346 -145.561443) (xy 335.200675 -145.583255) (xy 335.248281 -145.612309) (xy 335.291149 -145.647984)
			(xy 335.328366 -145.689521) (xy 335.359139 -145.736034) (xy 335.382811 -145.786531) (xy 335.398879 -145.839938)
			(xy 335.406999 -145.895114) (xy 335.407508 -145.923) (xy 335.406999 -145.950886) (xy 335.398879 -146.006062)
			(xy 335.382811 -146.059469) (xy 335.359139 -146.109966) (xy 335.328366 -146.156479) (xy 335.291149 -146.198016)
			(xy 335.248281 -146.233691) (xy 335.200675 -146.262745) (xy 335.149346 -146.284557) (xy 335.095389 -146.298663)
			(xy 335.039952 -146.304763) (xy 334.984218 -146.302726) (xy 334.929375 -146.292596) (xy 334.876591 -146.274589)
			(xy 334.826991 -146.249088) (xy 334.781633 -146.216637) (xy 334.741484 -146.177928) (xy 334.707398 -146.133785)
			(xy 334.680102 -146.08515) (xy 334.660179 -146.033059) (xy 334.648053 -145.978622) (xy 334.643982 -145.923)
			(xy 330.972717 -145.923) (xy 331.393592 -146.939) (xy 334.643982 -146.939) (xy 334.648053 -146.883378)
			(xy 334.660179 -146.828941) (xy 334.680102 -146.77685) (xy 334.707398 -146.728215) (xy 334.741484 -146.684072)
			(xy 334.781633 -146.645363) (xy 334.826991 -146.612912) (xy 334.876591 -146.587411) (xy 334.929375 -146.569404)
			(xy 334.984218 -146.559274) (xy 335.039952 -146.557237) (xy 335.095389 -146.563337) (xy 335.149346 -146.577443)
			(xy 335.200675 -146.599255) (xy 335.248281 -146.628309) (xy 335.291149 -146.663984) (xy 335.328366 -146.705521)
			(xy 335.359139 -146.752034) (xy 335.382811 -146.802531) (xy 335.398879 -146.855938) (xy 335.406999 -146.911114)
			(xy 335.407508 -146.939) (xy 335.406999 -146.966886) (xy 335.398879 -147.022062) (xy 335.382811 -147.075469)
			(xy 335.359139 -147.125966) (xy 335.328366 -147.172479) (xy 335.291149 -147.214016) (xy 335.248281 -147.249691)
			(xy 335.200675 -147.278745) (xy 335.149346 -147.300557) (xy 335.095389 -147.314663) (xy 335.039952 -147.320763)
			(xy 334.984218 -147.318726) (xy 334.929375 -147.308596) (xy 334.876591 -147.290589) (xy 334.826991 -147.265088)
			(xy 334.781633 -147.232637) (xy 334.741484 -147.193928) (xy 334.707398 -147.149785) (xy 334.680102 -147.10115)
			(xy 334.660179 -147.049059) (xy 334.648053 -146.994622) (xy 334.643982 -146.939) (xy 331.393592 -146.939)
			(xy 332.235343 -148.971) (xy 334.643982 -148.971) (xy 334.648053 -148.915378) (xy 334.660179 -148.860941)
			(xy 334.680102 -148.80885) (xy 334.707398 -148.760215) (xy 334.741484 -148.716072) (xy 334.781633 -148.677363)
			(xy 334.826991 -148.644912) (xy 334.876591 -148.619411) (xy 334.929375 -148.601404) (xy 334.984218 -148.591274)
			(xy 335.039952 -148.589237) (xy 335.095389 -148.595337) (xy 335.149346 -148.609443) (xy 335.200675 -148.631255)
			(xy 335.248281 -148.660309) (xy 335.291149 -148.695984) (xy 335.328366 -148.737521) (xy 335.359139 -148.784034)
			(xy 335.382811 -148.834531) (xy 335.398879 -148.887938) (xy 335.406999 -148.943114) (xy 335.407508 -148.971)
			(xy 335.406999 -148.998886) (xy 335.398879 -149.054062) (xy 335.382811 -149.107469) (xy 335.359139 -149.157966)
			(xy 335.328366 -149.204479) (xy 335.291149 -149.246016) (xy 335.248281 -149.281691) (xy 335.200675 -149.310745)
			(xy 335.149346 -149.332557) (xy 335.095389 -149.346663) (xy 335.039952 -149.352763) (xy 334.984218 -149.350726)
			(xy 334.929375 -149.340596) (xy 334.876591 -149.322589) (xy 334.826991 -149.297088) (xy 334.781633 -149.264637)
			(xy 334.741484 -149.225928) (xy 334.707398 -149.181785) (xy 334.680102 -149.13315) (xy 334.660179 -149.081059)
			(xy 334.648053 -149.026622) (xy 334.643982 -148.971) (xy 332.235343 -148.971) (xy 333.180944 -151.253698)
			(xy 333.185176 -151.26279) (xy 333.199373 -151.276933) (xy 333.217912 -151.284541) (xy 333.227934 -151.28494)
			(xy 333.922116 -151.28494) (xy 333.929482 -151.284432) (xy 334.470756 -150.742904) (xy 334.484503 -150.729543)
			(xy 334.514549 -150.705733) (xy 334.5307 -150.695406) (xy 334.53578 -150.692358) (xy 334.793844 -150.434294)
			(xy 334.800762 -150.426653) (xy 334.808368 -150.407515) (xy 334.808576 -150.39721) (xy 334.808576 -150.396448)
			(xy 334.804512 -150.319994) (xy 334.804114 -150.314712) (xy 334.801431 -150.304468) (xy 334.799178 -150.299674)
			(xy 334.794606 -150.290784) (xy 334.785716 -150.283672) (xy 334.764026 -150.265441) (xy 334.725751 -150.223665)
			(xy 334.69407 -150.176691) (xy 334.66968 -150.12555) (xy 334.653116 -150.071366) (xy 334.644742 -150.015329)
			(xy 334.644238 -149.987) (xy 334.645254 -149.959314) (xy 334.646016 -149.952964) (xy 334.649005 -149.92511)
			(xy 334.662105 -149.870644) (xy 334.683027 -149.818679) (xy 334.711322 -149.770331) (xy 334.74638 -149.726639)
			(xy 334.78745 -149.688542) (xy 334.833649 -149.656858) (xy 334.883983 -149.63227) (xy 334.937371 -149.615304)
			(xy 334.992666 -149.606326) (xy 335.020666 -149.605492) (xy 335.026 -149.605492) (xy 335.05432 -149.605986)
			(xy 335.110345 -149.614313) (xy 335.164523 -149.630831) (xy 335.215665 -149.655175) (xy 335.262646 -149.68681)
			(xy 335.304436 -149.725043) (xy 335.322672 -149.746716) (xy 335.322926 -149.74697) (xy 335.326419 -149.751173)
			(xy 335.334882 -149.758085) (xy 335.33969 -149.760686) (xy 335.348326 -149.765004) (xy 335.434686 -149.769576)
			(xy 335.435448 -149.769576) (xy 335.436464 -149.769576) (xy 335.446549 -149.769296) (xy 335.465276 -149.761834)
			(xy 335.472786 -149.755098) (xy 336.061558 -149.166326) (xy 336.065876 -149.161246) (xy 336.065876 -148.081746)
			(xy 336.066366 -148.055661) (xy 336.074541 -148.004134) (xy 336.090681 -147.954523) (xy 336.114387 -147.908049)
			(xy 336.145076 -147.865859) (xy 336.163158 -147.84705) (xy 336.624676 -147.385532) (xy 336.646488 -147.364654)
			(xy 336.696204 -147.330404) (xy 336.723482 -147.31746) (xy 336.73415 -147.312634) (xy 336.74939 -147.294346)
			(xy 336.753962 -147.275042) (xy 336.753962 -147.274788) (xy 336.767424 -147.217638) (xy 336.768574 -147.212114)
			(xy 336.768701 -147.200835) (xy 336.767678 -147.195286) (xy 336.765392 -147.18411) (xy 336.758026 -147.174966)
			(xy 336.742927 -147.155086) (xy 336.717469 -147.112145) (xy 336.697825 -147.066252) (xy 336.684328 -147.01819)
			(xy 336.67721 -146.968779) (xy 336.676492 -146.943826) (xy 336.676492 -146.932904) (xy 336.67739 -146.90594)
			(xy 336.685844 -146.852655) (xy 336.701722 -146.801094) (xy 336.724706 -146.752284) (xy 336.754338 -146.7072)
			(xy 336.790027 -146.66674) (xy 336.831061 -146.631713) (xy 336.876621 -146.602817) (xy 336.925798 -146.580629)
			(xy 336.97761 -146.565591) (xy 337.031025 -146.558003) (xy 337.058 -146.557492) (xy 337.062826 -146.557492)
			(xy 337.086907 -146.55815) (xy 337.134623 -146.564787) (xy 337.181125 -146.577371) (xy 337.203542 -146.586194)
			(xy 337.207606 -146.587972) (xy 337.21675 -146.590004) (xy 337.225376 -146.591632) (xy 337.242795 -146.589569)
			(xy 337.250786 -146.58594) (xy 337.256628 -146.582892) (xy 337.267804 -146.575272) (xy 337.268312 -146.575272)
			(xy 337.326224 -146.536918) (xy 337.329831 -146.534429) (xy 337.336214 -146.528425) (xy 337.338924 -146.52498)
			(xy 337.338924 -146.046698) (xy 337.3374 -146.043904) (xy 337.326986 -146.036792) (xy 337.326478 -146.036792)
			(xy 337.290664 -146.012408) (xy 337.25485 -145.988024) (xy 337.250278 -145.985738) (xy 337.24652 -145.98405)
			(xy 337.238607 -145.981761) (xy 337.23453 -145.981166) (xy 337.221322 -145.979642) (xy 337.197226 -145.989676)
			(xy 337.146979 -146.003806) (xy 337.095274 -146.01095) (xy 337.069176 -146.011392) (xy 337.05546 -146.011392)
			(xy 337.048602 -146.010884) (xy 337.048094 -146.010884) (xy 337.0206 -146.008897) (xy 336.966564 -145.998002)
			(xy 336.914658 -145.979444) (xy 336.865963 -145.95361) (xy 336.821493 -145.921038) (xy 336.782172 -145.882405)
			(xy 336.74882 -145.838516) (xy 336.722132 -145.790284) (xy 336.702661 -145.738714) (xy 336.690814 -145.684879)
			(xy 336.686838 -145.629899) (xy 336.690814 -145.574919) (xy 336.702662 -145.521084) (xy 336.722132 -145.469514)
			(xy 336.748821 -145.421283) (xy 336.782173 -145.377394) (xy 336.821494 -145.338761) (xy 336.865965 -145.306189)
			(xy 336.91466 -145.280355) (xy 336.966566 -145.261798) (xy 337.020601 -145.250903) (xy 337.048094 -145.248884)
			(xy 337.048602 -145.248884) (xy 337.05546 -145.248376) (xy 337.069176 -145.248376) (xy 337.092479 -145.248741)
			(xy 337.138734 -145.254447) (xy 337.183951 -145.265741) (xy 337.205828 -145.273776) (xy 337.214464 -145.276062)
			(xy 337.228942 -145.278856) (xy 337.235828 -145.278588) (xy 337.249086 -145.274848) (xy 337.255104 -145.27149)
			(xy 337.283298 -145.25244) (xy 337.326732 -145.222976) (xy 337.32724 -145.222468) (xy 337.328764 -145.221452)
			(xy 337.331612 -145.219239) (xy 337.336713 -145.214142) (xy 337.338924 -145.211292) (xy 337.338924 -144.74317)
			(xy 337.338496 -144.733102) (xy 337.330777 -144.714503) (xy 337.323938 -144.707102) (xy 337.214972 -144.598136)
			(xy 337.210654 -144.596866) (xy 337.189318 -144.601184) (xy 337.179412 -144.604994) (xy 337.146826 -144.616513)
			(xy 337.078839 -144.628915) (xy 337.044284 -144.629632) (xy 337.041998 -144.629632) (xy 337.014854 -144.62899)
			(xy 336.961154 -144.620968) (xy 336.909133 -144.605415) (xy 336.859843 -144.582644) (xy 336.814279 -144.553116)
			(xy 336.773361 -144.517426) (xy 336.737916 -144.476296) (xy 336.70866 -144.430556) (xy 336.686184 -144.381131)
			(xy 336.670942 -144.329019) (xy 336.663241 -144.275272) (xy 336.662776 -144.248124) (xy 336.663237 -144.22087)
			(xy 336.670991 -144.166915) (xy 336.686345 -144.114613) (xy 336.708986 -144.065029) (xy 336.738453 -144.019172)
			(xy 336.774147 -143.977975) (xy 336.81534 -143.942277) (xy 336.861194 -143.912805) (xy 336.910776 -143.890159)
			(xy 336.963076 -143.8748) (xy 337.01703 -143.86704) (xy 337.044284 -143.866616) (xy 337.075668 -143.867292)
			(xy 337.137578 -143.877644) (xy 337.196958 -143.897988) (xy 337.224878 -143.912336) (xy 337.233006 -143.9164)
			(xy 337.334606 -143.9164) (xy 337.360628 -143.916931) (xy 337.412028 -143.925105) (xy 337.461521 -143.941204)
			(xy 337.507894 -143.964833) (xy 337.550009 -143.995412) (xy 337.568794 -144.013428) (xy 337.641692 -144.086326)
			(xy 337.645502 -144.087596) (xy 337.64601 -144.087596) (xy 337.66101 -144.091578) (xy 337.692028 -144.091264)
			(xy 337.721518 -144.081643) (xy 337.746752 -144.063604) (xy 337.7565 -144.051528) (xy 337.761178 -144.04479)
			(xy 337.766379 -144.029244) (xy 337.76666 -144.021048) (xy 337.76666 -139.871196) (xy 337.764628 -139.867386)
			(xy 337.74963 -139.838895) (xy 337.72835 -139.778133) (xy 337.717552 -139.714664) (xy 337.716876 -139.682474)
			(xy 337.717362 -139.655223) (xy 337.725118 -139.601275) (xy 337.740473 -139.54898) (xy 337.763115 -139.499403)
			(xy 337.792581 -139.453553) (xy 337.828272 -139.412362) (xy 337.869463 -139.376671) (xy 337.915313 -139.347205)
			(xy 337.96489 -139.324563) (xy 338.017185 -139.309208) (xy 338.071133 -139.301452) (xy 338.125635 -139.301452)
			(xy 338.179583 -139.309208) (xy 338.231878 -139.324563) (xy 338.281455 -139.347205) (xy 338.327305 -139.376671)
			(xy 338.368496 -139.412362) (xy 338.404187 -139.453553) (xy 338.433653 -139.499403) (xy 338.456295 -139.54898)
			(xy 338.47165 -139.601275) (xy 338.479406 -139.655223) (xy 338.479892 -139.682474) (xy 338.479343 -139.71331)
			(xy 338.469512 -139.774192) (xy 338.450021 -139.832702) (xy 338.436204 -139.860274) (xy 338.433156 -139.865862)
			(xy 338.430108 -139.8778) (xy 338.430108 -142.875) (xy 339.469982 -142.875) (xy 339.474053 -142.819378)
			(xy 339.486179 -142.764941) (xy 339.506102 -142.71285) (xy 339.533398 -142.664215) (xy 339.567484 -142.620072)
			(xy 339.607633 -142.581363) (xy 339.652991 -142.548912) (xy 339.702591 -142.523411) (xy 339.755375 -142.505404)
			(xy 339.810218 -142.495274) (xy 339.865952 -142.493237) (xy 339.921389 -142.499337) (xy 339.975346 -142.513443)
			(xy 340.026675 -142.535255) (xy 340.074281 -142.564309) (xy 340.117149 -142.599984) (xy 340.154366 -142.641521)
			(xy 340.185139 -142.688034) (xy 340.208811 -142.738531) (xy 340.224879 -142.791938) (xy 340.232999 -142.847114)
			(xy 340.233508 -142.875) (xy 340.232999 -142.902886) (xy 340.224879 -142.958062) (xy 340.208811 -143.011469)
			(xy 340.185139 -143.061966) (xy 340.154366 -143.108479) (xy 340.117149 -143.150016) (xy 340.074281 -143.185691)
			(xy 340.026675 -143.214745) (xy 339.975346 -143.236557) (xy 339.921389 -143.250663) (xy 339.865952 -143.256763)
			(xy 339.810218 -143.254726) (xy 339.755375 -143.244596) (xy 339.702591 -143.226589) (xy 339.652991 -143.201088)
			(xy 339.607633 -143.168637) (xy 339.567484 -143.129928) (xy 339.533398 -143.085785) (xy 339.506102 -143.03715)
			(xy 339.486179 -142.985059) (xy 339.474053 -142.930622) (xy 339.469982 -142.875) (xy 338.430108 -142.875)
			(xy 338.430108 -143.380968) (xy 341.689434 -143.380968) (xy 341.693505 -143.325346) (xy 341.705631 -143.270909)
			(xy 341.725554 -143.218818) (xy 341.75285 -143.170183) (xy 341.786936 -143.12604) (xy 341.827085 -143.087331)
			(xy 341.872443 -143.05488) (xy 341.922043 -143.029379) (xy 341.974827 -143.011372) (xy 342.02967 -143.001242)
			(xy 342.085404 -142.999205) (xy 342.140841 -143.005305) (xy 342.194798 -143.019411) (xy 342.246127 -143.041223)
			(xy 342.293733 -143.070277) (xy 342.336601 -143.105952) (xy 342.373818 -143.147489) (xy 342.404591 -143.194002)
			(xy 342.428263 -143.244499) (xy 342.444331 -143.297906) (xy 342.452451 -143.353082) (xy 342.45296 -143.380968)
			(xy 342.452451 -143.408854) (xy 342.444331 -143.46403) (xy 342.428263 -143.517437) (xy 342.404591 -143.567934)
			(xy 342.373818 -143.614447) (xy 342.336601 -143.655984) (xy 342.293733 -143.691659) (xy 342.246127 -143.720713)
			(xy 342.194798 -143.742525) (xy 342.140841 -143.756631) (xy 342.085404 -143.762731) (xy 342.02967 -143.760694)
			(xy 341.974827 -143.750564) (xy 341.922043 -143.732557) (xy 341.872443 -143.707056) (xy 341.827085 -143.674605)
			(xy 341.786936 -143.635896) (xy 341.75285 -143.591753) (xy 341.725554 -143.543118) (xy 341.705631 -143.491027)
			(xy 341.693505 -143.43659) (xy 341.689434 -143.380968) (xy 338.430108 -143.380968) (xy 338.430108 -144.389094)
			(xy 339.797388 -144.389094) (xy 339.801459 -144.333472) (xy 339.813585 -144.279035) (xy 339.833508 -144.226944)
			(xy 339.860804 -144.178309) (xy 339.89489 -144.134166) (xy 339.935039 -144.095457) (xy 339.980397 -144.063006)
			(xy 340.029997 -144.037505) (xy 340.082781 -144.019498) (xy 340.137624 -144.009368) (xy 340.193358 -144.007331)
			(xy 340.248795 -144.013431) (xy 340.302752 -144.027537) (xy 340.354081 -144.049349) (xy 340.401687 -144.078403)
			(xy 340.444555 -144.114078) (xy 340.481772 -144.155615) (xy 340.512545 -144.202128) (xy 340.536217 -144.252625)
			(xy 340.552285 -144.306032) (xy 340.560405 -144.361208) (xy 340.560914 -144.389094) (xy 340.560405 -144.41698)
			(xy 340.552285 -144.472156) (xy 340.536217 -144.525563) (xy 340.512545 -144.57606) (xy 340.481772 -144.622573)
			(xy 340.444555 -144.66411) (xy 340.401687 -144.699785) (xy 340.354081 -144.728839) (xy 340.302752 -144.750651)
			(xy 340.248795 -144.764757) (xy 340.193358 -144.770857) (xy 340.137624 -144.76882) (xy 340.082781 -144.75869)
			(xy 340.029997 -144.740683) (xy 339.980397 -144.715182) (xy 339.935039 -144.682731) (xy 339.89489 -144.644022)
			(xy 339.860804 -144.599879) (xy 339.833508 -144.551244) (xy 339.813585 -144.499153) (xy 339.801459 -144.444716)
			(xy 339.797388 -144.389094) (xy 338.430108 -144.389094) (xy 338.430108 -146.50212) (xy 341.637364 -146.50212)
			(xy 341.641435 -146.446498) (xy 341.653561 -146.392061) (xy 341.673484 -146.33997) (xy 341.70078 -146.291335)
			(xy 341.734866 -146.247192) (xy 341.775015 -146.208483) (xy 341.820373 -146.176032) (xy 341.869973 -146.150531)
			(xy 341.922757 -146.132524) (xy 341.9776 -146.122394) (xy 342.033334 -146.120357) (xy 342.088771 -146.126457)
			(xy 342.142728 -146.140563) (xy 342.194057 -146.162375) (xy 342.241663 -146.191429) (xy 342.284531 -146.227104)
			(xy 342.321748 -146.268641) (xy 342.352521 -146.315154) (xy 342.376193 -146.365651) (xy 342.392261 -146.419058)
			(xy 342.400381 -146.474234) (xy 342.40089 -146.50212) (xy 342.400381 -146.530006) (xy 342.392261 -146.585182)
			(xy 342.376193 -146.638589) (xy 342.352521 -146.689086) (xy 342.321748 -146.735599) (xy 342.284531 -146.777136)
			(xy 342.241663 -146.812811) (xy 342.194057 -146.841865) (xy 342.142728 -146.863677) (xy 342.088771 -146.877783)
			(xy 342.033334 -146.883883) (xy 341.9776 -146.881846) (xy 341.922757 -146.871716) (xy 341.869973 -146.853709)
			(xy 341.820373 -146.828208) (xy 341.775015 -146.795757) (xy 341.734866 -146.757048) (xy 341.70078 -146.712905)
			(xy 341.673484 -146.66427) (xy 341.653561 -146.612179) (xy 341.641435 -146.557742) (xy 341.637364 -146.50212)
			(xy 338.430108 -146.50212) (xy 338.430108 -147.152106) (xy 340.499444 -147.152106) (xy 340.503515 -147.096484)
			(xy 340.515641 -147.042047) (xy 340.535564 -146.989956) (xy 340.56286 -146.941321) (xy 340.596946 -146.897178)
			(xy 340.637095 -146.858469) (xy 340.682453 -146.826018) (xy 340.732053 -146.800517) (xy 340.784837 -146.78251)
			(xy 340.83968 -146.77238) (xy 340.895414 -146.770343) (xy 340.950851 -146.776443) (xy 341.004808 -146.790549)
			(xy 341.056137 -146.812361) (xy 341.103743 -146.841415) (xy 341.146611 -146.87709) (xy 341.183828 -146.918627)
			(xy 341.214601 -146.96514) (xy 341.238273 -147.015637) (xy 341.254341 -147.069044) (xy 341.262461 -147.12422)
			(xy 341.26297 -147.152106) (xy 341.262461 -147.179992) (xy 341.254341 -147.235168) (xy 341.238273 -147.288575)
			(xy 341.214601 -147.339072) (xy 341.183828 -147.385585) (xy 341.146611 -147.427122) (xy 341.103743 -147.462797)
			(xy 341.056137 -147.491851) (xy 341.004808 -147.513663) (xy 340.950851 -147.527769) (xy 340.895414 -147.533869)
			(xy 340.83968 -147.531832) (xy 340.784837 -147.521702) (xy 340.732053 -147.503695) (xy 340.682453 -147.478194)
			(xy 340.637095 -147.445743) (xy 340.596946 -147.407034) (xy 340.56286 -147.362891) (xy 340.535564 -147.314256)
			(xy 340.515641 -147.262165) (xy 340.503515 -147.207728) (xy 340.499444 -147.152106) (xy 338.430108 -147.152106)
			(xy 338.430108 -147.802092) (xy 341.637364 -147.802092) (xy 341.641435 -147.74647) (xy 341.653561 -147.692033)
			(xy 341.673484 -147.639942) (xy 341.70078 -147.591307) (xy 341.734866 -147.547164) (xy 341.775015 -147.508455)
			(xy 341.820373 -147.476004) (xy 341.869973 -147.450503) (xy 341.922757 -147.432496) (xy 341.9776 -147.422366)
			(xy 342.033334 -147.420329) (xy 342.088771 -147.426429) (xy 342.142728 -147.440535) (xy 342.194057 -147.462347)
			(xy 342.241663 -147.491401) (xy 342.284531 -147.527076) (xy 342.321748 -147.568613) (xy 342.352521 -147.615126)
			(xy 342.376193 -147.665623) (xy 342.392261 -147.71903) (xy 342.400381 -147.774206) (xy 342.40089 -147.802092)
			(xy 342.400381 -147.829978) (xy 342.392261 -147.885154) (xy 342.376193 -147.938561) (xy 342.352521 -147.989058)
			(xy 342.321748 -148.035571) (xy 342.284531 -148.077108) (xy 342.241663 -148.112783) (xy 342.194057 -148.141837)
			(xy 342.142728 -148.163649) (xy 342.088771 -148.177755) (xy 342.033334 -148.183855) (xy 341.9776 -148.181818)
			(xy 341.922757 -148.171688) (xy 341.869973 -148.153681) (xy 341.820373 -148.12818) (xy 341.775015 -148.095729)
			(xy 341.734866 -148.05702) (xy 341.70078 -148.012877) (xy 341.673484 -147.964242) (xy 341.653561 -147.912151)
			(xy 341.641435 -147.857714) (xy 341.637364 -147.802092) (xy 338.430108 -147.802092) (xy 338.430108 -148.877782)
			(xy 340.11057 -148.877782) (xy 340.114641 -148.82216) (xy 340.126767 -148.767723) (xy 340.14669 -148.715632)
			(xy 340.173986 -148.666997) (xy 340.208072 -148.622854) (xy 340.248221 -148.584145) (xy 340.293579 -148.551694)
			(xy 340.343179 -148.526193) (xy 340.395963 -148.508186) (xy 340.450806 -148.498056) (xy 340.50654 -148.496019)
			(xy 340.561977 -148.502119) (xy 340.615934 -148.516225) (xy 340.667263 -148.538037) (xy 340.714869 -148.567091)
			(xy 340.757737 -148.602766) (xy 340.794954 -148.644303) (xy 340.825727 -148.690816) (xy 340.849399 -148.741313)
			(xy 340.865467 -148.79472) (xy 340.873587 -148.849896) (xy 340.874096 -148.877782) (xy 340.873587 -148.905668)
			(xy 340.865467 -148.960844) (xy 340.849399 -149.014251) (xy 340.825727 -149.064748) (xy 340.794954 -149.111261)
			(xy 340.757737 -149.152798) (xy 340.714869 -149.188473) (xy 340.667263 -149.217527) (xy 340.615934 -149.239339)
			(xy 340.561977 -149.253445) (xy 340.50654 -149.259545) (xy 340.450806 -149.257508) (xy 340.395963 -149.247378)
			(xy 340.343179 -149.229371) (xy 340.293579 -149.20387) (xy 340.248221 -149.171419) (xy 340.208072 -149.13271)
			(xy 340.173986 -149.088567) (xy 340.14669 -149.039932) (xy 340.126767 -148.987841) (xy 340.114641 -148.933404)
			(xy 340.11057 -148.877782) (xy 338.430108 -148.877782) (xy 338.430108 -149.153118) (xy 338.429583 -149.179143)
			(xy 338.421422 -149.23055) (xy 338.405334 -149.280052) (xy 338.381713 -149.326435) (xy 338.35114 -149.368561)
			(xy 338.33308 -149.387306) (xy 337.744054 -149.976332) (xy 340.739982 -149.976332) (xy 340.744053 -149.92071)
			(xy 340.756179 -149.866273) (xy 340.776102 -149.814182) (xy 340.803398 -149.765547) (xy 340.837484 -149.721404)
			(xy 340.877633 -149.682695) (xy 340.922991 -149.650244) (xy 340.972591 -149.624743) (xy 341.025375 -149.606736)
			(xy 341.080218 -149.596606) (xy 341.135952 -149.594569) (xy 341.191389 -149.600669) (xy 341.245346 -149.614775)
			(xy 341.296675 -149.636587) (xy 341.344281 -149.665641) (xy 341.387149 -149.701316) (xy 341.424366 -149.742853)
			(xy 341.455139 -149.789366) (xy 341.478811 -149.839863) (xy 341.494879 -149.89327) (xy 341.502999 -149.948446)
			(xy 341.503508 -149.976332) (xy 341.502999 -150.004218) (xy 341.494879 -150.059394) (xy 341.478811 -150.112801)
			(xy 341.455139 -150.163298) (xy 341.424366 -150.209811) (xy 341.387149 -150.251348) (xy 341.344281 -150.287023)
			(xy 341.296675 -150.316077) (xy 341.245346 -150.337889) (xy 341.191389 -150.351995) (xy 341.135952 -150.358095)
			(xy 341.080218 -150.356058) (xy 341.025375 -150.345928) (xy 340.972591 -150.327921) (xy 340.922991 -150.30242)
			(xy 340.877633 -150.269969) (xy 340.837484 -150.23126) (xy 340.803398 -150.187117) (xy 340.776102 -150.138482)
			(xy 340.756179 -150.086391) (xy 340.744053 -150.031954) (xy 340.739982 -149.976332) (xy 337.744054 -149.976332)
			(xy 337.191096 -150.52929) (xy 337.191096 -150.544276) (xy 337.194652 -150.567136) (xy 337.203796 -150.625302)
			(xy 337.204908 -150.631244) (xy 337.209525 -150.642412) (xy 337.21294 -150.6474) (xy 337.21294 -150.647654)
			(xy 337.214972 -150.650448) (xy 337.240179 -150.662188) (xy 337.287217 -150.691841) (xy 337.329512 -150.727939)
			(xy 337.366187 -150.769735) (xy 337.396482 -150.816362) (xy 337.419771 -150.866855) (xy 337.43557 -150.920168)
			(xy 337.443552 -150.975198) (xy 337.44408 -151.003) (xy 337.44359 -151.030934) (xy 337.435535 -151.086219)
			(xy 337.41958 -151.139761) (xy 337.408266 -151.165306) (xy 337.40852 -151.16937) (xy 337.40979 -151.182324)
			(xy 337.46567 -151.264874) (xy 337.472722 -151.27331) (xy 337.492081 -151.28369) (xy 337.503008 -151.28494)
			(xy 338.640674 -151.28494) (xy 338.650326 -151.283924) (xy 338.657571 -151.282298) (xy 338.67074 -151.275457)
			(xy 338.676234 -151.270462) (xy 338.683346 -151.26335) (xy 338.731098 -151.193246) (xy 338.734768 -151.187567)
			(xy 338.73927 -151.174823) (xy 338.739988 -151.1681) (xy 338.739988 -151.16556) (xy 338.728643 -151.139975)
			(xy 338.712611 -151.086354) (xy 338.704467 -151.030983) (xy 338.70392 -151.003) (xy 338.704412 -150.975422)
			(xy 338.712261 -150.920828) (xy 338.727801 -150.867907) (xy 338.750713 -150.817735) (xy 338.780532 -150.771335)
			(xy 338.816652 -150.729652) (xy 338.858335 -150.693532) (xy 338.904735 -150.663713) (xy 338.954907 -150.640801)
			(xy 339.007828 -150.625261) (xy 339.062422 -150.617412) (xy 339.117578 -150.617412) (xy 339.172172 -150.625261)
			(xy 339.225093 -150.640801) (xy 339.275265 -150.663713) (xy 339.321665 -150.693532) (xy 339.363348 -150.729652)
			(xy 339.399468 -150.771335) (xy 339.429287 -150.817735) (xy 339.452199 -150.867907) (xy 339.467739 -150.920828)
			(xy 339.475588 -150.975422) (xy 339.47608 -151.003) (xy 339.47559 -151.030934) (xy 339.467535 -151.086219)
			(xy 339.45158 -151.139761) (xy 339.440266 -151.165306) (xy 339.44052 -151.16937) (xy 339.44179 -151.182324)
			(xy 339.49767 -151.264874) (xy 339.504722 -151.27331) (xy 339.524081 -151.28369) (xy 339.535008 -151.28494)
			(xy 342.740742 -151.28494) (xy 342.74887 -151.284178) (xy 342.749378 -151.284178) (xy 342.7569 -151.282583)
			(xy 342.770596 -151.275615) (xy 342.776302 -151.270462) (xy 343.168986 -150.877778) (xy 343.174187 -150.87203)
			(xy 343.181171 -150.858199) (xy 343.182702 -150.8506) (xy 343.183464 -150.842218) (xy 343.183464 -142.305278)
			(xy 343.183893 -142.295211) (xy 343.19162 -142.276618) (xy 343.19845 -142.26921) (xy 344.00109 -141.46657)
			(xy 344.007933 -141.45917) (xy 344.015658 -141.440572) (xy 344.016076 -141.430502) (xy 344.016076 -139.267946)
			(xy 344.016604 -139.241923) (xy 344.024772 -139.19052) (xy 344.040867 -139.141024) (xy 344.064495 -139.094649)
			(xy 344.095076 -139.052533) (xy 344.113104 -139.033758) (xy 345.14409 -138.003026) (xy 345.150926 -137.995624)
			(xy 345.158635 -137.977026) (xy 345.159076 -137.966958) (xy 345.159076 -122.478038) (xy 345.159604 -122.452015)
			(xy 345.167773 -122.400613) (xy 345.18387 -122.351118) (xy 345.207499 -122.304743) (xy 345.23808 -122.262629)
			(xy 345.256104 -122.24385) (xy 346.54109 -120.959118) (xy 346.547925 -120.951715) (xy 346.555631 -120.933117)
			(xy 346.556076 -120.92305) (xy 346.556076 -100.44303) (xy 346.55564 -100.432966) (xy 346.547905 -100.414382)
			(xy 346.54109 -100.406962) (xy 341.130128 -94.996) (xy 341.1264 -94.992475) (xy 341.117829 -94.986838)
			(xy 341.11311 -94.984824) (xy 341.104474 -94.981268) (xy 340.202266 -94.981268) (xy 340.19131 -94.981845)
			(xy 340.171422 -94.991052) (xy 340.163912 -94.999048) (xy 340.152736 -95.01251) (xy 340.149942 -95.019622)
			(xy 340.137996 -95.047096) (xy 340.107987 -95.098947) (xy 340.071472 -95.146442) (xy 340.029075 -95.18877)
			(xy 339.98152 -95.225206) (xy 339.929619 -95.25513) (xy 339.874259 -95.278029) (xy 339.816385 -95.293513)
			(xy 339.756987 -95.301317) (xy 339.727032 -95.301816) (xy 338.863178 -95.301816) (xy 338.84455 -95.301617)
			(xy 338.80742 -95.298564) (xy 338.78901 -95.29572) (xy 338.788502 -95.29572) (xy 338.774024 -95.293434)
			(xy 338.769706 -95.293434) (xy 338.720176 -95.343218) (xy 338.72043 -95.351092) (xy 343.869518 -100.50018)
			(xy 343.887628 -100.518962) (xy 343.918306 -100.56116) (xy 343.941999 -100.607642) (xy 343.958123 -100.65726)
			(xy 343.96628 -100.70879) (xy 343.9668 -100.734876) (xy 343.9668 -105.836974) (xy 343.967237 -105.847038)
			(xy 343.97497 -105.865623) (xy 343.981786 -105.873042) (xy 345.136724 -107.02798) (xy 345.154759 -107.046749)
			(xy 345.185344 -107.088865) (xy 345.208975 -107.135241) (xy 345.225071 -107.184739) (xy 345.233238 -107.236144)
			(xy 345.233752 -107.262168) (xy 345.233752 -107.499404) (xy 345.234514 -107.500928) (xy 345.242134 -107.507278)
			(xy 345.251532 -107.513374) (xy 345.281504 -107.527852) (xy 345.312492 -107.542838) (xy 345.317716 -107.545177)
			(xy 345.328869 -107.547735) (xy 345.33459 -107.547918) (xy 345.369896 -107.547918) (xy 345.376125 -107.547702)
			(xy 345.388197 -107.544611) (xy 345.393772 -107.541822) (xy 345.399106 -107.539028) (xy 345.403932 -107.53598)
			(xy 345.428069 -107.519791) (xy 345.480207 -107.494119) (xy 345.53563 -107.476633) (xy 345.593061 -107.467736)
			(xy 345.622118 -107.467146) (xy 345.622626 -107.467146) (xy 345.649879 -107.467634) (xy 345.703831 -107.475394)
			(xy 345.756129 -107.490753) (xy 345.805709 -107.513399) (xy 345.851561 -107.542869) (xy 345.892753 -107.578565)
			(xy 345.928446 -107.61976) (xy 345.957914 -107.665614) (xy 345.980556 -107.715196) (xy 345.995911 -107.767495)
			(xy 346.003668 -107.821447) (xy 346.003668 -107.875953) (xy 345.995911 -107.929905) (xy 345.980556 -107.982204)
			(xy 345.957914 -108.031786) (xy 345.928446 -108.07764) (xy 345.892753 -108.118835) (xy 345.851561 -108.154531)
			(xy 345.805709 -108.184001) (xy 345.756129 -108.206647) (xy 345.703831 -108.222006) (xy 345.649879 -108.229766)
			(xy 345.622626 -108.230162) (xy 345.597336 -108.229746) (xy 345.547202 -108.223052) (xy 345.498392 -108.209791)
			(xy 345.451762 -108.190196) (xy 345.408131 -108.164611) (xy 345.38793 -108.14939) (xy 345.382342 -108.145072)
			(xy 345.369134 -108.139738) (xy 345.362276 -108.138976) (xy 345.355221 -108.138457) (xy 345.341296 -108.140902)
			(xy 345.334844 -108.143802) (xy 345.252294 -108.18368) (xy 345.246912 -108.186479) (xy 345.237543 -108.194183)
			(xy 345.233752 -108.19892) (xy 345.233752 -115.288568) (xy 345.233223 -115.314591) (xy 345.225054 -115.365993)
			(xy 345.208958 -115.415489) (xy 345.18533 -115.461863) (xy 345.15475 -115.503979) (xy 345.136724 -115.522756)
			(xy 343.798906 -116.860574) (xy 343.780127 -116.878691) (xy 343.737932 -116.909384) (xy 343.691452 -116.933093)
			(xy 343.641833 -116.949232) (xy 343.590299 -116.957403) (xy 343.56421 -116.957856) (xy 342.76284 -116.957856)
			(xy 342.75268 -116.967762) (xy 342.719914 -117.0178) (xy 342.704166 -117.04193) (xy 342.701626 -117.046248)
			(xy 342.697301 -117.055699) (xy 342.695874 -117.076414) (xy 342.698832 -117.08638) (xy 342.70061 -117.090444)
			(xy 342.711041 -117.114633) (xy 342.725904 -117.165171) (xy 342.733677 -117.217273) (xy 342.734392 -117.243606)
			(xy 342.734392 -117.253258) (xy 342.733564 -117.280273) (xy 342.725228 -117.333673) (xy 342.709439 -117.385363)
			(xy 342.686514 -117.434307) (xy 342.65691 -117.479526) (xy 342.621222 -117.520114) (xy 342.580162 -117.55526)
			(xy 342.534554 -117.584259) (xy 342.485309 -117.606532) (xy 342.433414 -117.621632) (xy 342.379908 -117.629257)
			(xy 342.352884 -117.629686) (xy 342.326003 -117.629226) (xy 342.272774 -117.62168) (xy 342.221131 -117.606739)
			(xy 342.172095 -117.584699) (xy 342.126637 -117.555996) (xy 342.085656 -117.521199) (xy 342.049964 -117.480995)
			(xy 342.020267 -117.43618) (xy 341.997152 -117.387642) (xy 341.981077 -117.33634) (xy 341.976202 -117.3099)
			(xy 341.974932 -117.303042) (xy 341.972392 -117.2972) (xy 341.96528 -117.286024) (xy 341.949786 -117.26672)
			(xy 341.945136 -117.261378) (xy 341.933534 -117.253267) (xy 341.926926 -117.250718) (xy 341.854282 -117.225826)
			(xy 341.84862 -117.224048) (xy 341.836813 -117.222892) (xy 341.830914 -117.22354) (xy 341.709502 -117.344698)
			(xy 341.703152 -117.35562) (xy 341.701374 -117.361462) (xy 341.692925 -117.387027) (xy 341.669844 -117.435672)
			(xy 341.640157 -117.480592) (xy 341.604453 -117.520894) (xy 341.56344 -117.55578) (xy 341.517932 -117.584556)
			(xy 341.468832 -117.606653) (xy 341.417115 -117.621632) (xy 341.363805 -117.629195) (xy 341.336884 -117.629686)
			(xy 341.309632 -117.629222) (xy 341.255684 -117.621463) (xy 341.20339 -117.606105) (xy 341.153813 -117.583461)
			(xy 341.107964 -117.553992) (xy 341.066775 -117.518299) (xy 341.031085 -117.477106) (xy 341.00162 -117.431254)
			(xy 340.978982 -117.381675) (xy 340.963629 -117.329378) (xy 340.955876 -117.27543) (xy 340.955376 -117.248178)
			(xy 340.955855 -117.220949) (xy 340.963587 -117.167042) (xy 340.978906 -117.114783) (xy 341.001501 -117.065233)
			(xy 341.030912 -117.019399) (xy 341.066541 -116.978213) (xy 341.107664 -116.942512) (xy 341.153446 -116.913022)
			(xy 341.202957 -116.89034) (xy 341.228934 -116.882164) (xy 341.235538 -116.880132) (xy 341.724488 -116.391182)
			(xy 341.743268 -116.373067) (xy 341.785464 -116.342377) (xy 341.831944 -116.31867) (xy 341.881563 -116.302533)
			(xy 341.933096 -116.294362) (xy 341.959184 -116.2939) (xy 343.405714 -116.2939) (xy 343.415783 -116.293474)
			(xy 343.434384 -116.285756) (xy 343.441782 -116.278914) (xy 344.555318 -115.165632) (xy 344.562163 -115.158234)
			(xy 344.569885 -115.139635) (xy 344.570304 -115.129564) (xy 344.570304 -107.421172) (xy 344.569876 -107.411104)
			(xy 344.562155 -107.392507) (xy 344.555318 -107.385104) (xy 343.400126 -106.230166) (xy 343.382011 -106.211386)
			(xy 343.351323 -106.16919) (xy 343.32762 -106.122709) (xy 343.311487 -106.073091) (xy 343.303323 -106.021558)
			(xy 343.302844 -105.99547) (xy 343.302844 -100.893372) (xy 343.302414 -100.883305) (xy 343.294686 -100.864714)
			(xy 343.287858 -100.857304) (xy 338.255356 -95.824802) (xy 338.247955 -95.817962) (xy 338.229357 -95.810244)
			(xy 338.219288 -95.809816) (xy 333.627984 -95.809816) (xy 333.601898 -95.809329) (xy 333.550368 -95.801159)
			(xy 333.500753 -95.785023) (xy 333.454275 -95.76132) (xy 333.412081 -95.730633) (xy 333.393288 -95.712534)
			(xy 333.18323 -95.502222) (xy 333.175829 -95.495384) (xy 333.15723 -95.487672) (xy 333.147162 -95.487236)
			(xy 332.03388 -95.487236) (xy 332.01991 -95.4913) (xy 332.016862 -95.493332) (xy 332.015084 -95.497396)
			(xy 332.010766 -95.507302) (xy 331.97292 -95.591122) (xy 331.971142 -95.595948) (xy 331.968909 -95.603455)
			(xy 331.968653 -95.619105) (xy 331.970634 -95.626682) (xy 331.971142 -95.627952) (xy 331.975968 -95.640652)
			(xy 331.982318 -95.647764) (xy 332.001032 -95.668929) (xy 332.032656 -95.715743) (xy 332.057034 -95.766707)
			(xy 332.073634 -95.820708) (xy 332.082091 -95.876566) (xy 332.082648 -95.904812) (xy 332.082648 -95.906082)
			(xy 332.082573 -95.916454) (xy 332.081431 -95.937167) (xy 332.080362 -95.947484) (xy 332.078838 -95.960692)
			(xy 332.083664 -95.972376) (xy 332.086337 -95.978164) (xy 332.094044 -95.988315) (xy 332.098904 -95.992442)
			(xy 332.164944 -96.045528) (xy 332.173525 -96.051789) (xy 332.194007 -96.057322) (xy 332.204568 -96.056196)
			(xy 332.213204 -96.054926) (xy 332.217776 -96.053402) (xy 332.246509 -96.044613) (xy 332.305844 -96.035165)
			(xy 332.335886 -96.034606) (xy 332.337918 -96.034606) (xy 332.365084 -96.035216) (xy 332.418834 -96.043182)
			(xy 332.47091 -96.058694) (xy 332.520258 -96.081438) (xy 332.56588 -96.110954) (xy 332.606852 -96.146645)
			(xy 332.642346 -96.187788) (xy 332.671642 -96.233551) (xy 332.694149 -96.283008) (xy 332.709411 -96.335158)
			(xy 332.717119 -96.388945) (xy 332.717648 -96.416114) (xy 332.717161 -96.443366) (xy 332.709403 -96.497314)
			(xy 332.694047 -96.549609) (xy 332.671406 -96.599187) (xy 332.64194 -96.645039) (xy 332.606249 -96.686231)
			(xy 332.56506 -96.721924) (xy 332.51921 -96.751394) (xy 332.469634 -96.774038) (xy 332.417339 -96.789398)
			(xy 332.363392 -96.797159) (xy 332.33614 -96.797622) (xy 332.308933 -96.797142) (xy 332.255069 -96.789417)
			(xy 332.20285 -96.774116) (xy 332.153334 -96.751552) (xy 332.107527 -96.722181) (xy 332.066358 -96.6866)
			(xy 332.030661 -96.645531) (xy 332.001162 -96.599806) (xy 331.978459 -96.550354) (xy 331.963012 -96.498178)
			(xy 331.955135 -96.444336) (xy 331.954632 -96.41713) (xy 331.954632 -96.415606) (xy 331.954708 -96.405234)
			(xy 331.95585 -96.384521) (xy 331.956918 -96.374204) (xy 331.958442 -96.360996) (xy 331.953616 -96.349312)
			(xy 331.950941 -96.343525) (xy 331.94323 -96.333379) (xy 331.938376 -96.329246) (xy 331.872336 -96.27616)
			(xy 331.863754 -96.269904) (xy 331.843273 -96.264381) (xy 331.832712 -96.265492) (xy 331.824076 -96.266762)
			(xy 331.819504 -96.268286) (xy 331.790771 -96.277074) (xy 331.731435 -96.286518) (xy 331.701394 -96.287082)
			(xy 331.699362 -96.287082) (xy 331.672193 -96.286478) (xy 331.618434 -96.278521) (xy 331.566349 -96.263015)
			(xy 331.516992 -96.240275) (xy 331.471361 -96.210761) (xy 331.430381 -96.17507) (xy 331.39488 -96.133925)
			(xy 331.365577 -96.088158) (xy 331.343066 -96.038696) (xy 331.327801 -95.98654) (xy 331.320093 -95.932746)
			(xy 331.319632 -95.905574) (xy 331.319632 -95.90532) (xy 331.320102 -95.877879) (xy 331.327962 -95.823563)
			(xy 331.343537 -95.770938) (xy 331.366504 -95.721093) (xy 331.396387 -95.675061) (xy 331.41412 -95.654114)
			(xy 331.419962 -95.64751) (xy 331.427836 -95.627444) (xy 331.430984 -95.618448) (xy 331.431105 -95.599402)
			(xy 331.42809 -95.59036) (xy 331.427328 -95.588582) (xy 331.427074 -95.588328) (xy 331.402182 -95.53194)
			(xy 331.38999 -95.504254) (xy 331.387173 -95.499319) (xy 331.379739 -95.49073) (xy 331.375258 -95.487236)
			(xy 329.93584 -95.487236) (xy 329.909817 -95.486708) (xy 329.858414 -95.478539) (xy 329.808919 -95.462444)
			(xy 329.762544 -95.438815) (xy 329.720428 -95.408235) (xy 329.701652 -95.390208) (xy 328.94143 -94.629986)
			(xy 328.937076 -94.625819) (xy 328.926799 -94.61953) (xy 328.92111 -94.61754) (xy 328.920856 -94.61754)
			(xy 328.916792 -94.61627) (xy 328.915776 -94.616016) (xy 328.891616 -94.607695) (xy 328.845598 -94.585485)
			(xy 328.802961 -94.557322) (xy 328.783442 -94.540832) (xy 328.763902 -94.523205) (xy 328.729368 -94.483497)
			(xy 328.700609 -94.439426) (xy 328.678171 -94.391826) (xy 328.669904 -94.366842) (xy 328.669904 -94.366334)
			(xy 328.667855 -94.360674) (xy 328.661564 -94.350416) (xy 328.657458 -94.346014) (xy 328.540364 -94.228666)
			(xy 328.534353 -94.227878) (xy 328.522277 -94.228899) (xy 328.516488 -94.230698) (xy 328.444352 -94.255082)
			(xy 328.436478 -94.258384) (xy 328.433224 -94.26022) (xy 328.42723 -94.264681) (xy 328.42454 -94.267274)
			(xy 328.420984 -94.27083) (xy 328.405236 -94.289626) (xy 328.39787 -94.301818) (xy 328.39533 -94.307406)
			(xy 328.39406 -94.313756) (xy 328.38909 -94.340019) (xy 328.372769 -94.390919) (xy 328.349505 -94.439042)
			(xy 328.319753 -94.483448) (xy 328.284094 -94.523267) (xy 328.243228 -94.55772) (xy 328.197953 -94.586132)
			(xy 328.149156 -94.607948) (xy 328.097792 -94.62274) (xy 328.044866 -94.630219) (xy 328.01814 -94.630748)
			(xy 327.990886 -94.630265) (xy 327.936932 -94.622513) (xy 327.88463 -94.607162) (xy 327.835045 -94.584524)
			(xy 327.789187 -94.555059) (xy 327.747988 -94.519368) (xy 327.712289 -94.478177) (xy 327.682815 -94.432325)
			(xy 327.660166 -94.382745) (xy 327.644804 -94.330447) (xy 327.637041 -94.276494) (xy 327.636632 -94.24924)
			(xy 327.637079 -94.22251) (xy 327.644542 -94.169572) (xy 327.659326 -94.118197) (xy 327.681143 -94.06939)
			(xy 327.709564 -94.02411) (xy 327.744031 -93.983244) (xy 327.783869 -93.947593) (xy 327.828297 -93.917858)
			(xy 327.876443 -93.89462) (xy 327.927363 -93.878336) (xy 327.953624 -93.87332) (xy 327.959974 -93.87205)
			(xy 327.965562 -93.86951) (xy 327.968831 -93.868061) (xy 327.974949 -93.864361) (xy 327.977754 -93.862144)
			(xy 327.997312 -93.845888) (xy 328.001579 -93.841978) (xy 328.008375 -93.832613) (xy 328.010774 -93.827346)
			(xy 328.01179 -93.824298) (xy 328.028046 -93.777054) (xy 328.036936 -93.751146) (xy 328.038712 -93.745484)
			(xy 328.03986 -93.733678) (xy 328.039222 -93.727778) (xy 327.744328 -93.432884) (xy 327.726298 -93.414113)
			(xy 327.695721 -93.371995) (xy 327.672099 -93.325618) (xy 327.65601 -93.276121) (xy 327.647851 -93.224719)
			(xy 327.6473 -93.198696) (xy 327.6473 -91.864942) (xy 327.646866 -91.854877) (xy 327.639137 -91.836287)
			(xy 327.632314 -91.828874) (xy 326.33031 -90.52687) (xy 326.322915 -90.520014) (xy 326.304317 -90.512265)
			(xy 326.294242 -90.511884) (xy 319.118996 -90.511884) (xy 319.092974 -90.511353) (xy 319.041574 -90.503179)
			(xy 318.992081 -90.48708) (xy 318.945709 -90.463451) (xy 318.903595 -90.43287) (xy 318.884808 -90.414856)
			(xy 312.829956 -84.360004) (xy 312.822241 -84.353038) (xy 312.802914 -84.345442) (xy 312.78216 -84.34613)
			(xy 312.772552 -84.350098) (xy 312.686192 -84.390484) (xy 312.676976 -84.395377) (xy 312.663201 -84.411023)
			(xy 312.656787 -84.430856) (xy 312.657236 -84.441284) (xy 312.65876 -84.476336) (xy 312.658271 -84.503582)
			(xy 312.650511 -84.55752) (xy 312.635155 -84.609805) (xy 312.612514 -84.659372) (xy 312.58305 -84.705212)
			(xy 312.547362 -84.746393) (xy 312.506177 -84.782076) (xy 312.460333 -84.811535) (xy 312.410763 -84.83417)
			(xy 312.358477 -84.849521) (xy 312.304539 -84.857275) (xy 312.250045 -84.857273) (xy 312.196107 -84.849517)
			(xy 312.143822 -84.834165) (xy 312.094253 -84.811527) (xy 312.04841 -84.782066) (xy 312.007227 -84.746382)
			(xy 311.971541 -84.705199) (xy 311.942078 -84.659357) (xy 311.91944 -84.60979) (xy 311.904085 -84.557505)
			(xy 311.896327 -84.503566) (xy 311.896325 -84.449073) (xy 311.904077 -84.395135) (xy 311.919426 -84.342848)
			(xy 311.942059 -84.293278) (xy 311.971517 -84.247433) (xy 312.007199 -84.206247) (xy 312.048378 -84.170558)
			(xy 312.094218 -84.141092) (xy 312.143784 -84.118449) (xy 312.196068 -84.103091) (xy 312.250006 -84.095329)
			(xy 312.277252 -84.094828) (xy 312.312304 -84.096352) (xy 312.322728 -84.096837) (xy 312.342553 -84.090393)
			(xy 312.358183 -84.0766) (xy 312.363104 -84.067396) (xy 312.40349 -83.981036) (xy 312.407459 -83.971428)
			(xy 312.408139 -83.950671) (xy 312.400562 -83.931335) (xy 312.393584 -83.923632) (xy 311.87644 -83.406234)
			(xy 311.86904 -83.399393) (xy 311.850441 -83.391675) (xy 311.840372 -83.391248) (xy 311.381394 -83.391248)
			(xy 311.355372 -83.390716) (xy 311.303973 -83.382542) (xy 311.254482 -83.366441) (xy 311.208111 -83.34281)
			(xy 311.166 -83.312227) (xy 311.147206 -83.29422) (xy 310.614314 -82.761074) (xy 310.606914 -82.754233)
			(xy 310.588315 -82.746518) (xy 310.578246 -82.746088) (xy 310.252364 -82.746088) (xy 310.248554 -82.74812)
			(xy 310.220062 -82.763114) (xy 310.159299 -82.784386) (xy 310.095831 -82.795178) (xy 310.063642 -82.795872)
			(xy 310.03639 -82.795412) (xy 309.982439 -82.78766) (xy 309.930141 -82.772309) (xy 309.880561 -82.749671)
			(xy 309.834707 -82.720207) (xy 309.793513 -82.684517) (xy 309.757818 -82.643327) (xy 309.728349 -82.597476)
			(xy 309.705705 -82.547898) (xy 309.690349 -82.495602) (xy 309.682591 -82.441652) (xy 309.682591 -82.387148)
			(xy 309.690349 -82.333198) (xy 309.705705 -82.280902) (xy 309.728349 -82.231324) (xy 309.757818 -82.185473)
			(xy 309.793513 -82.144283) (xy 309.834707 -82.108593) (xy 309.880561 -82.079129) (xy 309.930141 -82.056491)
			(xy 309.982439 -82.04114) (xy 310.03639 -82.033388) (xy 310.063642 -82.032856) (xy 310.094477 -82.03341)
			(xy 310.155354 -82.043253) (xy 310.213857 -82.062755) (xy 310.241442 -82.076544) (xy 310.24703 -82.079592)
			(xy 310.258968 -82.08264) (xy 310.463946 -82.08264) (xy 310.472137 -82.082324) (xy 310.487677 -82.077135)
			(xy 310.494426 -82.07248) (xy 310.504845 -82.064137) (xy 310.521271 -82.043109) (xy 310.531679 -82.018539)
			(xy 310.535354 -81.99211) (xy 310.532047 -81.965632) (xy 310.527446 -81.9531) (xy 310.52501 -81.94743)
			(xy 310.517816 -81.937408) (xy 310.513222 -81.933288) (xy 310.493156 -81.915) (xy 308.537102 -79.958946)
			(xy 308.531514 -79.95666) (xy 305.564286 -79.95666) (xy 305.554838 -79.957143) (xy 305.537236 -79.964035)
			(xy 305.529996 -79.970122) (xy 305.483006 -80.013302) (xy 305.482498 -80.01381) (xy 305.479704 -80.01635)
			(xy 305.476246 -80.019599) (xy 305.47049 -80.02714) (xy 305.468274 -80.031336) (xy 305.463956 -80.039972)
			(xy 305.463194 -80.049878) (xy 305.460588 -80.076889) (xy 305.448708 -80.129836) (xy 305.429448 -80.180567)
			(xy 305.403197 -80.228059) (xy 305.370484 -80.271354) (xy 305.331969 -80.309579) (xy 305.288429 -80.341964)
			(xy 305.24074 -80.367856) (xy 305.189865 -80.386732) (xy 305.136829 -80.398212) (xy 305.082702 -80.402064)
			(xy 305.028575 -80.398212) (xy 304.975539 -80.386732) (xy 304.924664 -80.367856) (xy 304.876975 -80.341964)
			(xy 304.833435 -80.309579) (xy 304.79492 -80.271354) (xy 304.762207 -80.228059) (xy 304.735956 -80.180567)
			(xy 304.716696 -80.129836) (xy 304.704816 -80.076889) (xy 304.70221 -80.049878) (xy 304.701448 -80.039972)
			(xy 304.69713 -80.031336) (xy 304.694902 -80.027148) (xy 304.689146 -80.01961) (xy 304.6857 -80.01635)
			(xy 304.682906 -80.01381) (xy 304.682398 -80.013302) (xy 304.635408 -79.970122) (xy 304.630062 -79.965457)
			(xy 304.617433 -79.959) (xy 304.610516 -79.957422) (xy 304.577496 -79.990696) (xy 304.558724 -80.008726)
			(xy 304.516606 -80.039302) (xy 304.47023 -80.062924) (xy 304.420733 -80.079013) (xy 304.369331 -80.087174)
			(xy 304.343308 -80.087724) (xy 300.5455 -80.087724) (xy 300.534303 -80.088312) (xy 300.514017 -80.097799)
			(xy 300.506384 -80.106012) (xy 300.449234 -80.174846) (xy 300.443392 -80.196182) (xy 300.44517 -80.206088)
			(xy 300.448233 -80.223453) (xy 300.451541 -80.258561) (xy 300.451774 -80.276192) (xy 300.451774 -80.280764)
			(xy 300.450999 -80.307815) (xy 300.442753 -80.3613) (xy 300.427032 -80.413083) (xy 300.40415 -80.462125)
			(xy 300.374568 -80.507441) (xy 300.338878 -80.548121) (xy 300.297798 -80.58335) (xy 300.252152 -80.61242)
			(xy 300.202856 -80.634748) (xy 300.150899 -80.649885) (xy 300.097324 -80.657528) (xy 300.070266 -80.657954)
			(xy 300.043088 -80.657479) (xy 299.989281 -80.649781) (xy 299.937109 -80.63453) (xy 299.887627 -80.612035)
			(xy 299.841835 -80.582751) (xy 299.800659 -80.547269) (xy 299.76493 -80.506307) (xy 299.73537 -80.460692)
			(xy 299.723556 -80.436212) (xy 299.723302 -80.435196) (xy 299.72127 -80.430624) (xy 299.721016 -80.430116)
			(xy 299.716952 -80.420718) (xy 299.710348 -80.414368) (xy 299.704846 -80.409386) (xy 299.691678 -80.402553)
			(xy 299.68444 -80.400906) (xy 299.60189 -80.384904) (xy 299.597803 -80.384165) (xy 299.589503 -80.383904)
			(xy 299.58538 -80.384396) (xy 298.804584 -81.164938) (xy 298.798234 -81.17586) (xy 298.796456 -81.181702)
			(xy 298.78801 -81.20727) (xy 298.764933 -81.25592) (xy 298.735249 -81.300845) (xy 298.699546 -81.341152)
			(xy 298.658533 -81.376041) (xy 298.613023 -81.404821) (xy 298.563921 -81.42692) (xy 298.512201 -81.441899)
			(xy 298.458889 -81.449461) (xy 298.431966 -81.449926) (xy 298.404716 -81.449438) (xy 298.350771 -81.441678)
			(xy 298.298479 -81.42632) (xy 298.248905 -81.403677) (xy 298.203058 -81.37421) (xy 298.16187 -81.338519)
			(xy 298.12618 -81.29733) (xy 298.096715 -81.251481) (xy 298.074075 -81.201906) (xy 298.058719 -81.149613)
			(xy 298.050961 -81.095668) (xy 298.050458 -81.068418) (xy 298.050934 -81.041187) (xy 298.058662 -80.987276)
			(xy 298.073977 -80.935011) (xy 298.096568 -80.885456) (xy 298.125977 -80.839616) (xy 298.161605 -80.798424)
			(xy 298.202728 -80.762717) (xy 298.248511 -80.73322) (xy 298.298023 -80.710534) (xy 298.324016 -80.702404)
			(xy 298.33062 -80.700372) (xy 299.216572 -79.81442) (xy 299.217154 -79.809123) (xy 299.216392 -79.798495)
			(xy 299.215048 -79.793338) (xy 299.19041 -79.713074) (xy 299.187108 -79.707486) (xy 299.181266 -79.70012)
			(xy 299.160946 -79.681578) (xy 299.15993 -79.680562) (xy 299.149008 -79.672942) (xy 299.14342 -79.670148)
			(xy 299.141896 -79.669894) (xy 299.132244 -79.667608) (xy 299.13199 -79.667608) (xy 299.104752 -79.660348)
			(xy 299.052619 -79.638909) (xy 299.004205 -79.610037) (xy 298.960563 -79.574361) (xy 298.92264 -79.532655)
			(xy 298.891262 -79.485826) (xy 298.867111 -79.434893) (xy 298.850711 -79.380962) (xy 298.84242 -79.325207)
			(xy 298.841922 -79.297022) (xy 298.842384 -79.269769) (xy 298.850138 -79.215817) (xy 298.865493 -79.163518)
			(xy 298.888135 -79.113937) (xy 298.917602 -79.068084) (xy 298.953297 -79.026891) (xy 298.99449 -78.991198)
			(xy 299.040344 -78.961731) (xy 299.089926 -78.93909) (xy 299.142225 -78.923737) (xy 299.196177 -78.915983)
			(xy 299.22343 -78.915514) (xy 299.224954 -78.915514) (xy 299.256466 -78.916134) (xy 299.318641 -78.926442)
			(xy 299.378274 -78.946833) (xy 299.40631 -78.961234) (xy 299.41393 -78.965044) (xy 299.513498 -78.965044)
			(xy 299.520102 -78.959456) (xy 299.522134 -78.957424) (xy 299.573442 -78.897988) (xy 299.578776 -78.889606)
			(xy 299.57522 -78.86827) (xy 299.571613 -78.844688) (xy 299.567798 -78.79713) (xy 299.5676 -78.773274)
			(xy 299.568156 -78.736454) (xy 299.577392 -78.663394) (xy 299.595715 -78.592069) (xy 299.608748 -78.557628)
			(xy 299.61713 -78.536546) (xy 299.615962 -78.531939) (xy 299.612117 -78.523249) (xy 299.60951 -78.519274)
			(xy 299.580554 -78.476856) (xy 299.563028 -78.451202) (xy 299.557115 -78.443378) (xy 299.54078 -78.432556)
			(xy 299.531278 -78.43012) (xy 299.521118 -78.429104) (xy 278.132286 -78.429104) (xy 278.125247 -78.429327)
			(xy 278.11171 -78.433194) (xy 278.105616 -78.436724) (xy 278.099774 -78.44028) (xy 278.090376 -78.45044)
			(xy 278.087074 -78.457044) (xy 278.051514 -78.527402) (xy 278.050752 -78.528164) (xy 278.04618 -78.537308)
			(xy 278.043717 -78.542633) (xy 278.041017 -78.554049) (xy 278.040846 -78.559914) (xy 278.040846 -78.569058)
			(xy 278.045926 -78.584298) (xy 278.050752 -78.590902) (xy 278.06822 -78.615621) (xy 278.095938 -78.669426)
			(xy 278.11481 -78.726933) (xy 278.124361 -78.7867) (xy 278.12492 -78.816962) (xy 278.12492 -78.825344)
			(xy 278.124666 -78.831948) (xy 278.123102 -78.85977) (xy 278.11291 -78.914552) (xy 278.094858 -78.967269)
			(xy 278.069329 -79.0168) (xy 278.036866 -79.062089) (xy 277.998161 -79.102175) (xy 277.954036 -79.136204)
			(xy 277.90543 -79.163453) (xy 277.853378 -79.183341) (xy 277.798986 -79.195446) (xy 277.743412 -79.199509)
			(xy 277.687838 -79.195446) (xy 277.633446 -79.183341) (xy 277.581394 -79.163453) (xy 277.532788 -79.136204)
			(xy 277.488663 -79.102175) (xy 277.449958 -79.062089) (xy 277.417495 -79.0168) (xy 277.391966 -78.967269)
			(xy 277.373914 -78.914552) (xy 277.363722 -78.85977) (xy 277.362158 -78.831948) (xy 277.361904 -78.825344)
			(xy 277.361904 -78.817216) (xy 277.362487 -78.786913) (xy 277.372077 -78.72707) (xy 277.391017 -78.6695)
			(xy 277.418831 -78.615652) (xy 277.436326 -78.590902) (xy 277.440399 -78.585081) (xy 277.445419 -78.571798)
			(xy 277.446232 -78.56474) (xy 277.447248 -78.55077) (xy 277.43531 -78.527148) (xy 277.39975 -78.457044)
			(xy 277.399496 -78.45679) (xy 277.396186 -78.450751) (xy 277.386915 -78.440577) (xy 277.381208 -78.436724)
			(xy 277.375366 -78.432914) (xy 277.36165 -78.429104) (xy 273.776694 -78.429104) (xy 273.769049 -78.429363)
			(xy 273.754445 -78.433887) (xy 273.747992 -78.437994) (xy 273.741896 -78.442312) (xy 273.732498 -78.453996)
			(xy 273.72945 -78.461362) (xy 273.703288 -78.527656) (xy 273.703288 -78.528164) (xy 273.695668 -78.547976)
			(xy 273.69343 -78.556406) (xy 273.694204 -78.573818) (xy 273.697192 -78.582012) (xy 273.707352 -78.604872)
			(xy 273.714718 -78.611984) (xy 273.732693 -78.630017) (xy 273.76419 -78.670021) (xy 273.790085 -78.713861)
			(xy 273.809916 -78.760756) (xy 273.823332 -78.809873) (xy 273.830093 -78.860338) (xy 273.830542 -78.885796)
			(xy 273.830056 -78.913047) (xy 273.8223 -78.966995) (xy 273.806945 -79.01929) (xy 273.784303 -79.068867)
			(xy 273.754837 -79.114717) (xy 273.719146 -79.155908) (xy 273.677955 -79.191599) (xy 273.632105 -79.221065)
			(xy 273.582528 -79.243707) (xy 273.530233 -79.259062) (xy 273.476285 -79.266818) (xy 273.421783 -79.266818)
			(xy 273.367835 -79.259062) (xy 273.31554 -79.243707) (xy 273.265963 -79.221065) (xy 273.220113 -79.191599)
			(xy 273.178922 -79.155908) (xy 273.143231 -79.114717) (xy 273.113765 -79.068867) (xy 273.091123 -79.01929)
			(xy 273.075768 -78.966995) (xy 273.068012 -78.913047) (xy 273.067526 -78.885796) (xy 273.067949 -78.860337)
			(xy 273.074721 -78.809873) (xy 273.088144 -78.760757) (xy 273.107981 -78.713863) (xy 273.133878 -78.670023)
			(xy 273.165375 -78.630017) (xy 273.18335 -78.611984) (xy 273.190716 -78.604872) (xy 273.200114 -78.584044)
			(xy 273.203948 -78.574547) (xy 273.204488 -78.554094) (xy 273.20113 -78.54442) (xy 273.19478 -78.528164)
			(xy 273.19478 -78.527656) (xy 273.168618 -78.461362) (xy 273.168618 -78.461108) (xy 273.165535 -78.454129)
			(xy 273.155979 -78.442246) (xy 273.149822 -78.43774) (xy 273.143726 -78.433422) (xy 273.129248 -78.429104)
			(xy 268.04366 -78.429104) (xy 268.030349 -78.429492) (xy 268.004631 -78.436367) (xy 267.981569 -78.449664)
			(xy 267.962734 -78.468478) (xy 267.949411 -78.491525) (xy 267.945616 -78.504288) (xy 267.943679 -78.513012)
			(xy 267.945232 -78.530801) (xy 267.952776 -78.546985) (xy 267.958824 -78.553564) (xy 270.203422 -80.798162)
			(xy 270.21082 -80.805009) (xy 270.229418 -80.812742) (xy 270.23949 -80.813148) (xy 273.214338 -80.813148)
			(xy 273.222369 -80.812914) (xy 273.237658 -80.808001) (xy 273.24431 -80.803496) (xy 273.254216 -80.79613)
			(xy 273.258788 -80.790288) (xy 273.263868 -80.783938) (xy 273.266662 -80.776572) (xy 273.277542 -80.750133)
			(xy 273.306066 -80.700587) (xy 273.341666 -80.655853) (xy 273.383544 -80.616934) (xy 273.430762 -80.584701)
			(xy 273.482262 -80.559877) (xy 273.53689 -80.543017) (xy 273.593423 -80.5345) (xy 273.622008 -80.534002)
			(xy 273.648242 -80.534438) (xy 273.700214 -80.541627) (xy 273.750711 -80.555869) (xy 273.798781 -80.576895)
			(xy 273.843517 -80.604307) (xy 273.86407 -80.620616) (xy 273.866864 -80.622902) (xy 273.87804 -80.628744)
			(xy 273.886422 -80.632046) (xy 273.899376 -80.635094) (xy 273.899884 -80.635094) (xy 273.908012 -80.635348)
			(xy 273.92503 -80.623664) (xy 273.954423 -80.604387) (xy 274.016901 -80.572176) (xy 274.082755 -80.547593)
			(xy 274.151057 -80.530985) (xy 274.220846 -80.522586) (xy 274.255992 -80.522064) (xy 274.289156 -80.522512)
			(xy 274.355066 -80.529939) (xy 274.41973 -80.544701) (xy 274.482334 -80.566612) (xy 274.54209 -80.595396)
			(xy 274.598246 -80.630691) (xy 274.650097 -80.672054) (xy 274.696989 -80.718963) (xy 274.738332 -80.770828)
			(xy 274.773607 -80.826998) (xy 274.80237 -80.886764) (xy 274.824258 -80.949376) (xy 274.838997 -81.014045)
			(xy 274.8464 -81.079958) (xy 274.846796 -81.113122) (xy 274.846373 -81.145427) (xy 274.839347 -81.209652)
			(xy 274.82536 -81.272729) (xy 274.804579 -81.333904) (xy 274.777251 -81.392449) (xy 274.743703 -81.447665)
			(xy 274.724368 -81.473548) (xy 274.713954 -81.486756) (xy 274.7137 -81.491074) (xy 274.7137 -81.593944)
			(xy 274.719288 -81.609692) (xy 274.724368 -81.616296) (xy 274.743698 -81.642133) (xy 274.777232 -81.697264)
			(xy 274.804554 -81.755724) (xy 274.825339 -81.816814) (xy 274.839338 -81.879806) (xy 274.846384 -81.943949)
			(xy 274.846796 -81.976214) (xy 274.846796 -81.976722) (xy 274.846256 -82.012432) (xy 274.837648 -82.083331)
			(xy 274.820559 -82.152677) (xy 274.795238 -82.219458) (xy 274.762056 -82.282701) (xy 274.727993 -82.332068)
			(xy 301.91024 -82.332068) (xy 301.914311 -82.276446) (xy 301.926437 -82.222009) (xy 301.94636 -82.169918)
			(xy 301.973656 -82.121283) (xy 302.007742 -82.07714) (xy 302.047891 -82.038431) (xy 302.093249 -82.00598)
			(xy 302.142849 -81.980479) (xy 302.195633 -81.962472) (xy 302.250476 -81.952342) (xy 302.30621 -81.950305)
			(xy 302.361647 -81.956405) (xy 302.415604 -81.970511) (xy 302.466933 -81.992323) (xy 302.514539 -82.021377)
			(xy 302.557407 -82.057052) (xy 302.594624 -82.098589) (xy 302.625397 -82.145102) (xy 302.649069 -82.195599)
			(xy 302.665137 -82.249006) (xy 302.672053 -82.296) (xy 303.351182 -82.296) (xy 303.355253 -82.240378)
			(xy 303.367379 -82.185941) (xy 303.387302 -82.13385) (xy 303.414598 -82.085215) (xy 303.448684 -82.041072)
			(xy 303.488833 -82.002363) (xy 303.534191 -81.969912) (xy 303.583791 -81.944411) (xy 303.636575 -81.926404)
			(xy 303.691418 -81.916274) (xy 303.747152 -81.914237) (xy 303.802589 -81.920337) (xy 303.856546 -81.934443)
			(xy 303.907875 -81.956255) (xy 303.955481 -81.985309) (xy 303.998349 -82.020984) (xy 304.035566 -82.062521)
			(xy 304.066339 -82.109034) (xy 304.090011 -82.159531) (xy 304.106079 -82.212938) (xy 304.114199 -82.268114)
			(xy 304.114708 -82.296) (xy 304.114199 -82.323886) (xy 304.106079 -82.379062) (xy 304.090011 -82.432469)
			(xy 304.066339 -82.482966) (xy 304.035566 -82.529479) (xy 303.998349 -82.571016) (xy 303.955481 -82.606691)
			(xy 303.907875 -82.635745) (xy 303.856546 -82.657557) (xy 303.802589 -82.671663) (xy 303.747152 -82.677763)
			(xy 303.691418 -82.675726) (xy 303.636575 -82.665596) (xy 303.583791 -82.647589) (xy 303.534191 -82.622088)
			(xy 303.488833 -82.589637) (xy 303.448684 -82.550928) (xy 303.414598 -82.506785) (xy 303.387302 -82.45815)
			(xy 303.367379 -82.406059) (xy 303.355253 -82.351622) (xy 303.351182 -82.296) (xy 302.672053 -82.296)
			(xy 302.673257 -82.304182) (xy 302.673766 -82.332068) (xy 302.673257 -82.359954) (xy 302.665137 -82.41513)
			(xy 302.649069 -82.468537) (xy 302.625397 -82.519034) (xy 302.594624 -82.565547) (xy 302.557407 -82.607084)
			(xy 302.514539 -82.642759) (xy 302.466933 -82.671813) (xy 302.415604 -82.693625) (xy 302.361647 -82.707731)
			(xy 302.30621 -82.713831) (xy 302.250476 -82.711794) (xy 302.195633 -82.701664) (xy 302.142849 -82.683657)
			(xy 302.093249 -82.658156) (xy 302.047891 -82.625705) (xy 302.007742 -82.586996) (xy 301.973656 -82.542853)
			(xy 301.94636 -82.494218) (xy 301.926437 -82.442127) (xy 301.914311 -82.38769) (xy 301.91024 -82.332068)
			(xy 274.727993 -82.332068) (xy 274.721495 -82.341486) (xy 274.674145 -82.394954) (xy 274.620698 -82.442328)
			(xy 274.561933 -82.482916) (xy 274.498704 -82.516128) (xy 274.431935 -82.541478) (xy 274.362597 -82.558599)
			(xy 274.291702 -82.56724) (xy 274.255992 -82.56778) (xy 274.220843 -82.567267) (xy 274.151045 -82.558904)
			(xy 274.082734 -82.542311) (xy 274.016877 -82.517722) (xy 273.954407 -82.485485) (xy 273.92503 -82.46618)
			(xy 273.907758 -82.454496) (xy 273.900392 -82.45475) (xy 273.899884 -82.45475) (xy 273.88693 -82.457798)
			(xy 273.878548 -82.4611) (xy 273.8751 -82.462467) (xy 273.868597 -82.466035) (xy 273.865594 -82.468212)
			(xy 273.859752 -82.472784) (xy 273.851116 -82.479388) (xy 273.826437 -82.497181) (xy 273.772609 -82.525532)
			(xy 273.714963 -82.544981) (xy 273.654962 -82.555036) (xy 273.624548 -82.555842) (xy 273.622008 -82.555842)
			(xy 273.620484 -82.555842) (xy 273.619722 -82.555842) (xy 273.607557 -82.555699) (xy 273.583281 -82.554045)
			(xy 273.571208 -82.55254) (xy 273.545019 -82.548562) (xy 273.494 -82.534313) (xy 273.44544 -82.513149)
			(xy 273.400272 -82.485476) (xy 273.359362 -82.451826) (xy 273.341084 -82.432652) (xy 273.336766 -82.42808)
			(xy 273.336766 -82.427826) (xy 273.314785 -82.401983) (xy 273.279396 -82.344107) (xy 273.266408 -82.312764)
			(xy 273.263614 -82.305652) (xy 273.258788 -82.299556) (xy 273.258534 -82.299048) (xy 273.248628 -82.28965)
			(xy 273.24431 -82.286348) (xy 273.237622 -82.281914) (xy 273.222357 -82.277002) (xy 273.214338 -82.276696)
			(xy 269.856712 -82.276696) (xy 269.823557 -82.276233) (xy 269.757663 -82.268814) (xy 269.693012 -82.254069)
			(xy 269.630418 -82.232181) (xy 269.570667 -82.203427) (xy 269.514508 -82.168168) (xy 269.462647 -82.126846)
			(xy 269.438882 -82.103722) (xy 266.86129 -79.52613) (xy 266.853892 -79.519282) (xy 266.835294 -79.511546)
			(xy 266.825222 -79.511144) (xy 262.13689 -79.511144) (xy 262.126198 -79.511706) (xy 262.106644 -79.520367)
			(xy 262.099044 -79.527908) (xy 262.067802 -79.562706) (xy 262.064286 -79.566799) (xy 262.058914 -79.576154)
			(xy 262.057134 -79.581248) (xy 262.053832 -79.591154) (xy 262.055493 -79.60398) (xy 262.057271 -79.629784)
			(xy 262.057388 -79.642716) (xy 262.056924 -79.669968) (xy 262.049165 -79.723916) (xy 262.033807 -79.77621)
			(xy 262.011163 -79.825787) (xy 261.981695 -79.871637) (xy 261.946001 -79.912826) (xy 261.904808 -79.948516)
			(xy 261.858956 -79.977981) (xy 261.809377 -80.00062) (xy 261.75708 -80.015972) (xy 261.703132 -80.023726)
			(xy 261.67588 -80.024224) (xy 261.64814 -80.023725) (xy 261.593243 -80.01569) (xy 261.540089 -79.999793)
			(xy 261.489795 -79.976369) (xy 261.443423 -79.94591) (xy 261.401948 -79.909059) (xy 261.366245 -79.866592)
			(xy 261.337066 -79.819404) (xy 261.315026 -79.768489) (xy 261.300589 -79.714919) (xy 261.296912 -79.68742)
			(xy 261.295388 -79.673704) (xy 261.293532 -79.644369) (xy 261.297783 -79.585745) (xy 261.310978 -79.528468)
			(xy 261.332804 -79.473893) (xy 261.362745 -79.423313) (xy 261.400091 -79.377926) (xy 261.443959 -79.338805)
			(xy 261.468362 -79.322422) (xy 261.469886 -79.321406) (xy 261.473442 -79.31912) (xy 261.482586 -79.309976)
			(xy 261.48831 -79.303692) (xy 261.49569 -79.288393) (xy 261.497064 -79.280004) (xy 261.503414 -79.224886)
			(xy 261.503414 -79.224378) (xy 261.503668 -79.223108) (xy 260.40969 -78.12913) (xy 260.402292 -78.122282)
			(xy 260.383694 -78.114546) (xy 260.373622 -78.114144) (xy 257.425444 -78.114144) (xy 257.42392 -78.1177)
			(xy 257.402076 -78.174596) (xy 257.402076 -78.175104) (xy 257.391408 -78.202282) (xy 257.388745 -78.211445)
			(xy 257.389676 -78.230491) (xy 257.393186 -78.239366) (xy 257.39344 -78.240128) (xy 257.407664 -78.252574)
			(xy 257.423158 -78.267052) (xy 257.99669 -78.840584) (xy 259.167884 -78.840584) (xy 259.16837 -78.813333)
			(xy 259.176126 -78.759385) (xy 259.191481 -78.70709) (xy 259.214123 -78.657513) (xy 259.243589 -78.611663)
			(xy 259.27928 -78.570472) (xy 259.320471 -78.534781) (xy 259.366321 -78.505315) (xy 259.415898 -78.482673)
			(xy 259.468193 -78.467318) (xy 259.522141 -78.459562) (xy 259.576643 -78.459562) (xy 259.630591 -78.467318)
			(xy 259.682886 -78.482673) (xy 259.732463 -78.505315) (xy 259.778313 -78.534781) (xy 259.819504 -78.570472)
			(xy 259.855195 -78.611663) (xy 259.884661 -78.657513) (xy 259.907303 -78.70709) (xy 259.922658 -78.759385)
			(xy 259.930414 -78.813333) (xy 259.9309 -78.840584) (xy 259.930263 -78.872204) (xy 259.919821 -78.934576)
			(xy 259.89922 -78.994367) (xy 259.884672 -79.022448) (xy 259.880642 -79.030795) (xy 259.878307 -79.049168)
			(xy 259.8801 -79.058262) (xy 259.89788 -79.133446) (xy 259.908548 -79.149194) (xy 259.916168 -79.154274)
			(xy 259.937487 -79.169642) (xy 259.976117 -79.205275) (xy 260.009493 -79.24587) (xy 260.036983 -79.290661)
			(xy 260.058069 -79.338799) (xy 260.072352 -79.389376) (xy 260.07956 -79.441433) (xy 260.079998 -79.46771)
			(xy 260.079512 -79.494961) (xy 260.071756 -79.548909) (xy 260.056401 -79.601204) (xy 260.033759 -79.650781)
			(xy 260.004293 -79.696631) (xy 259.968602 -79.737822) (xy 259.927411 -79.773513) (xy 259.881561 -79.802979)
			(xy 259.831984 -79.825621) (xy 259.779689 -79.840976) (xy 259.725741 -79.848732) (xy 259.671239 -79.848732)
			(xy 259.617291 -79.840976) (xy 259.564996 -79.825621) (xy 259.515419 -79.802979) (xy 259.469569 -79.773513)
			(xy 259.428378 -79.737822) (xy 259.392687 -79.696631) (xy 259.363221 -79.650781) (xy 259.340579 -79.601204)
			(xy 259.325224 -79.548909) (xy 259.317468 -79.494961) (xy 259.316982 -79.46771) (xy 259.317618 -79.43609)
			(xy 259.328061 -79.373718) (xy 259.348662 -79.313927) (xy 259.36321 -79.285846) (xy 259.367243 -79.2775)
			(xy 259.369576 -79.259127) (xy 259.367782 -79.250032) (xy 259.350002 -79.174848) (xy 259.339334 -79.1591)
			(xy 259.331714 -79.15402) (xy 259.310388 -79.138661) (xy 259.271759 -79.103026) (xy 259.238385 -79.062429)
			(xy 259.210895 -79.017637) (xy 259.18981 -78.969497) (xy 259.175529 -78.91892) (xy 259.168321 -78.866861)
			(xy 259.167884 -78.840584) (xy 257.99669 -78.840584) (xy 259.440172 -80.284066) (xy 259.447573 -80.290905)
			(xy 259.466171 -80.298618) (xy 259.47624 -80.299052) (xy 266.582144 -80.299052) (xy 266.60823 -80.299541)
			(xy 266.659758 -80.307714) (xy 266.709371 -80.323852) (xy 266.755847 -80.347556) (xy 266.79804 -80.378243)
			(xy 266.81684 -80.396334) (xy 270.660876 -84.24037) (xy 273.951192 -84.24037) (xy 273.951192 -83.37677)
			(xy 273.951682 -83.346786) (xy 273.95951 -83.28733) (xy 273.975031 -83.229405) (xy 273.99798 -83.174001)
			(xy 274.027964 -83.122067) (xy 274.06447 -83.074491) (xy 274.106875 -83.032086) (xy 274.154451 -82.99558)
			(xy 274.206385 -82.965596) (xy 274.261789 -82.942647) (xy 274.319714 -82.927126) (xy 274.37917 -82.919298)
			(xy 274.439138 -82.919298) (xy 274.498594 -82.927126) (xy 274.556519 -82.942647) (xy 274.611923 -82.965596)
			(xy 274.663857 -82.99558) (xy 274.711433 -83.032086) (xy 274.753838 -83.074491) (xy 274.790344 -83.122067)
			(xy 274.820328 -83.174001) (xy 274.843277 -83.229405) (xy 274.858798 -83.28733) (xy 274.866626 -83.346786)
			(xy 274.867116 -83.37677) (xy 274.867116 -84.24037) (xy 274.866626 -84.270354) (xy 274.858798 -84.32981)
			(xy 274.843277 -84.387735) (xy 274.820328 -84.443139) (xy 274.790344 -84.495073) (xy 274.753838 -84.542649)
			(xy 274.711433 -84.585054) (xy 274.663857 -84.62156) (xy 274.611923 -84.651544) (xy 274.556519 -84.674493)
			(xy 274.498594 -84.690014) (xy 274.439138 -84.697842) (xy 274.37917 -84.697842) (xy 274.319714 -84.690014)
			(xy 274.261789 -84.674493) (xy 274.206385 -84.651544) (xy 274.154451 -84.62156) (xy 274.106875 -84.585054)
			(xy 274.06447 -84.542649) (xy 274.027964 -84.495073) (xy 273.99798 -84.443139) (xy 273.975031 -84.387735)
			(xy 273.95951 -84.32981) (xy 273.951682 -84.270354) (xy 273.951192 -84.24037) (xy 270.660876 -84.24037)
			(xy 271.329404 -84.908898) (xy 271.336803 -84.915744) (xy 271.355401 -84.923478) (xy 271.365472 -84.923884)
			(xy 279.452578 -84.923884) (xy 279.462642 -84.923446) (xy 279.481224 -84.91571) (xy 279.488646 -84.908898)
			(xy 281.257248 -83.14055) (xy 281.263598 -83.129628) (xy 281.265376 -83.123786) (xy 281.273822 -83.098216)
			(xy 281.296898 -83.049563) (xy 281.326582 -83.004634) (xy 281.362284 -82.964322) (xy 281.403296 -82.929426)
			(xy 281.448804 -82.90064) (xy 281.497907 -82.878534) (xy 281.549628 -82.863546) (xy 281.602942 -82.855975)
			(xy 281.629866 -82.855562) (xy 281.657121 -82.856022) (xy 281.711078 -82.863775) (xy 281.763381 -82.879128)
			(xy 281.812968 -82.901768) (xy 281.858827 -82.931235) (xy 281.900026 -82.966928) (xy 281.935727 -83.008122)
			(xy 281.965201 -83.053976) (xy 281.987849 -83.103559) (xy 282.003211 -83.15586) (xy 282.010973 -83.209815)
			(xy 282.011374 -83.23707) (xy 282.010892 -83.264298) (xy 282.003154 -83.318202) (xy 281.987832 -83.370458)
			(xy 281.965235 -83.420005) (xy 281.935824 -83.465836) (xy 281.900196 -83.50702) (xy 281.859075 -83.542721)
			(xy 281.822939 -83.566) (xy 282.827982 -83.566) (xy 282.832053 -83.510378) (xy 282.844179 -83.455941)
			(xy 282.864102 -83.40385) (xy 282.891398 -83.355215) (xy 282.925484 -83.311072) (xy 282.965633 -83.272363)
			(xy 283.010991 -83.239912) (xy 283.060591 -83.214411) (xy 283.113375 -83.196404) (xy 283.168218 -83.186274)
			(xy 283.223952 -83.184237) (xy 283.279389 -83.190337) (xy 283.333346 -83.204443) (xy 283.384675 -83.226255)
			(xy 283.432281 -83.255309) (xy 283.475149 -83.290984) (xy 283.512366 -83.332521) (xy 283.543139 -83.379034)
			(xy 283.566811 -83.429531) (xy 283.582879 -83.482938) (xy 283.590999 -83.538114) (xy 283.591508 -83.566)
			(xy 283.590999 -83.593886) (xy 283.582879 -83.649062) (xy 283.566811 -83.702469) (xy 283.543139 -83.752966)
			(xy 283.512366 -83.799479) (xy 283.475149 -83.841016) (xy 283.432281 -83.876691) (xy 283.384675 -83.905745)
			(xy 283.333346 -83.927557) (xy 283.279389 -83.941663) (xy 283.223952 -83.947763) (xy 283.168218 -83.945726)
			(xy 283.113375 -83.935596) (xy 283.060591 -83.917589) (xy 283.010991 -83.892088) (xy 282.965633 -83.859637)
			(xy 282.925484 -83.820928) (xy 282.891398 -83.776785) (xy 282.864102 -83.72815) (xy 282.844179 -83.676059)
			(xy 282.832053 -83.621622) (xy 282.827982 -83.566) (xy 281.822939 -83.566) (xy 281.813296 -83.572212)
			(xy 281.763789 -83.594896) (xy 281.737816 -83.603084) (xy 281.731212 -83.605116) (xy 281.01036 -84.325968)
			(xy 301.368966 -84.325968) (xy 301.373037 -84.270346) (xy 301.385163 -84.215909) (xy 301.405086 -84.163818)
			(xy 301.432382 -84.115183) (xy 301.466468 -84.07104) (xy 301.506617 -84.032331) (xy 301.551975 -83.99988)
			(xy 301.601575 -83.974379) (xy 301.654359 -83.956372) (xy 301.709202 -83.946242) (xy 301.764936 -83.944205)
			(xy 301.820373 -83.950305) (xy 301.87433 -83.964411) (xy 301.925659 -83.986223) (xy 301.973265 -84.015277)
			(xy 302.016133 -84.050952) (xy 302.05317 -84.092288) (xy 308.425086 -84.092288) (xy 308.429157 -84.036666)
			(xy 308.441283 -83.982229) (xy 308.461206 -83.930138) (xy 308.488502 -83.881503) (xy 308.522588 -83.83736)
			(xy 308.562737 -83.798651) (xy 308.608095 -83.7662) (xy 308.657695 -83.740699) (xy 308.710479 -83.722692)
			(xy 308.765322 -83.712562) (xy 308.821056 -83.710525) (xy 308.876493 -83.716625) (xy 308.93045 -83.730731)
			(xy 308.981779 -83.752543) (xy 309.029385 -83.781597) (xy 309.072253 -83.817272) (xy 309.10947 -83.858809)
			(xy 309.140243 -83.905322) (xy 309.163915 -83.955819) (xy 309.179983 -84.009226) (xy 309.188103 -84.064402)
			(xy 309.188612 -84.092288) (xy 309.188103 -84.120174) (xy 309.179983 -84.17535) (xy 309.163915 -84.228757)
			(xy 309.140243 -84.279254) (xy 309.10947 -84.325767) (xy 309.072253 -84.367304) (xy 309.029385 -84.402979)
			(xy 308.981779 -84.432033) (xy 308.93045 -84.453845) (xy 308.876493 -84.467951) (xy 308.821056 -84.474051)
			(xy 308.765322 -84.472014) (xy 308.710479 -84.461884) (xy 308.657695 -84.443877) (xy 308.608095 -84.418376)
			(xy 308.562737 -84.385925) (xy 308.522588 -84.347216) (xy 308.488502 -84.303073) (xy 308.461206 -84.254438)
			(xy 308.441283 -84.202347) (xy 308.429157 -84.14791) (xy 308.425086 -84.092288) (xy 302.05317 -84.092288)
			(xy 302.05335 -84.092489) (xy 302.084123 -84.139002) (xy 302.107795 -84.189499) (xy 302.123863 -84.242906)
			(xy 302.131983 -84.298082) (xy 302.132492 -84.325968) (xy 302.131983 -84.353854) (xy 302.123863 -84.40903)
			(xy 302.107795 -84.462437) (xy 302.084123 -84.512934) (xy 302.05335 -84.559447) (xy 302.016133 -84.600984)
			(xy 301.973265 -84.636659) (xy 301.925659 -84.665713) (xy 301.87433 -84.687525) (xy 301.820373 -84.701631)
			(xy 301.764936 -84.707731) (xy 301.709202 -84.705694) (xy 301.654359 -84.695564) (xy 301.601575 -84.677557)
			(xy 301.551975 -84.652056) (xy 301.506617 -84.619605) (xy 301.466468 -84.580896) (xy 301.432382 -84.536753)
			(xy 301.405086 -84.488118) (xy 301.385163 -84.436027) (xy 301.373037 -84.38159) (xy 301.368966 -84.325968)
			(xy 281.01036 -84.325968) (xy 280.500328 -84.836) (xy 282.827982 -84.836) (xy 282.832053 -84.780378)
			(xy 282.844179 -84.725941) (xy 282.864102 -84.67385) (xy 282.891398 -84.625215) (xy 282.925484 -84.581072)
			(xy 282.965633 -84.542363) (xy 283.010991 -84.509912) (xy 283.060591 -84.484411) (xy 283.113375 -84.466404)
			(xy 283.168218 -84.456274) (xy 283.223952 -84.454237) (xy 283.279389 -84.460337) (xy 283.333346 -84.474443)
			(xy 283.384675 -84.496255) (xy 283.432281 -84.525309) (xy 283.475149 -84.560984) (xy 283.512366 -84.602521)
			(xy 283.543139 -84.649034) (xy 283.566811 -84.699531) (xy 283.582879 -84.752938) (xy 283.590999 -84.808114)
			(xy 283.591508 -84.836) (xy 283.590999 -84.863886) (xy 283.582879 -84.919062) (xy 283.566811 -84.972469)
			(xy 283.543139 -85.022966) (xy 283.512366 -85.069479) (xy 283.475149 -85.111016) (xy 283.432281 -85.146691)
			(xy 283.384675 -85.175745) (xy 283.333346 -85.197557) (xy 283.279389 -85.211663) (xy 283.223952 -85.217763)
			(xy 283.168218 -85.215726) (xy 283.113375 -85.205596) (xy 283.060591 -85.187589) (xy 283.010991 -85.162088)
			(xy 282.965633 -85.129637) (xy 282.925484 -85.090928) (xy 282.891398 -85.046785) (xy 282.864102 -84.99815)
			(xy 282.844179 -84.946059) (xy 282.832053 -84.891622) (xy 282.827982 -84.836) (xy 280.500328 -84.836)
			(xy 279.933908 -85.40242) (xy 288.626802 -85.40242) (xy 288.630873 -85.346798) (xy 288.642999 -85.292361)
			(xy 288.662922 -85.24027) (xy 288.690218 -85.191635) (xy 288.724304 -85.147492) (xy 288.764453 -85.108783)
			(xy 288.809811 -85.076332) (xy 288.859411 -85.050831) (xy 288.912195 -85.032824) (xy 288.967038 -85.022694)
			(xy 289.022772 -85.020657) (xy 289.078209 -85.026757) (xy 289.132166 -85.040863) (xy 289.183495 -85.062675)
			(xy 289.231101 -85.091729) (xy 289.273969 -85.127404) (xy 289.311186 -85.168941) (xy 289.341959 -85.215454)
			(xy 289.365631 -85.265951) (xy 289.381699 -85.319358) (xy 289.389819 -85.374534) (xy 289.390328 -85.40242)
			(xy 289.389819 -85.430306) (xy 289.388316 -85.44052) (xy 299.277276 -85.44052) (xy 299.281347 -85.384898)
			(xy 299.293473 -85.330461) (xy 299.313396 -85.27837) (xy 299.340692 -85.229735) (xy 299.374778 -85.185592)
			(xy 299.414927 -85.146883) (xy 299.460285 -85.114432) (xy 299.509885 -85.088931) (xy 299.562669 -85.070924)
			(xy 299.617512 -85.060794) (xy 299.673246 -85.058757) (xy 299.728683 -85.064857) (xy 299.78264 -85.078963)
			(xy 299.833969 -85.100775) (xy 299.881575 -85.129829) (xy 299.924443 -85.165504) (xy 299.96166 -85.207041)
			(xy 299.992433 -85.253554) (xy 300.016105 -85.304051) (xy 300.032173 -85.357458) (xy 300.040293 -85.412634)
			(xy 300.040802 -85.44052) (xy 300.040293 -85.468406) (xy 300.032173 -85.523582) (xy 300.016105 -85.576989)
			(xy 299.992433 -85.627486) (xy 299.96166 -85.673999) (xy 299.924443 -85.715536) (xy 299.881575 -85.751211)
			(xy 299.833969 -85.780265) (xy 299.78264 -85.802077) (xy 299.728683 -85.816183) (xy 299.673246 -85.822283)
			(xy 299.617512 -85.820246) (xy 299.562669 -85.810116) (xy 299.509885 -85.792109) (xy 299.460285 -85.766608)
			(xy 299.414927 -85.734157) (xy 299.374778 -85.695448) (xy 299.340692 -85.651305) (xy 299.313396 -85.60267)
			(xy 299.293473 -85.550579) (xy 299.281347 -85.496142) (xy 299.277276 -85.44052) (xy 289.388316 -85.44052)
			(xy 289.381699 -85.485482) (xy 289.365631 -85.538889) (xy 289.341959 -85.589386) (xy 289.311186 -85.635899)
			(xy 289.273969 -85.677436) (xy 289.231101 -85.713111) (xy 289.183495 -85.742165) (xy 289.132166 -85.763977)
			(xy 289.078209 -85.778083) (xy 289.022772 -85.784183) (xy 288.967038 -85.782146) (xy 288.912195 -85.772016)
			(xy 288.859411 -85.754009) (xy 288.809811 -85.728508) (xy 288.764453 -85.696057) (xy 288.724304 -85.657348)
			(xy 288.690218 -85.613205) (xy 288.662922 -85.56457) (xy 288.642999 -85.512479) (xy 288.630873 -85.458042)
			(xy 288.626802 -85.40242) (xy 279.933908 -85.40242) (xy 279.84577 -85.490558) (xy 279.826991 -85.508674)
			(xy 279.784795 -85.539364) (xy 279.738315 -85.563068) (xy 279.688696 -85.579203) (xy 279.637162 -85.587369)
			(xy 279.611074 -85.58784) (xy 271.206976 -85.58784) (xy 271.18089 -85.587352) (xy 271.12936 -85.579182)
			(xy 271.079745 -85.563046) (xy 271.033268 -85.539343) (xy 270.991073 -85.508657) (xy 270.97228 -85.490558)
			(xy 266.459716 -80.977994) (xy 266.452313 -80.971162) (xy 266.433714 -80.963459) (xy 266.423648 -80.963008)
			(xy 259.317744 -80.963008) (xy 259.291658 -80.962518) (xy 259.24013 -80.954344) (xy 259.190516 -80.938208)
			(xy 259.144039 -80.914505) (xy 259.101844 -80.883822) (xy 259.083048 -80.865726) (xy 257.066034 -78.848458)
			(xy 257.058635 -78.841616) (xy 257.040036 -78.833896) (xy 257.029966 -78.833472) (xy 256.855468 -78.833472)
			(xy 256.84734 -78.837536) (xy 256.819414 -78.85187) (xy 256.760036 -78.872214) (xy 256.698128 -78.882562)
			(xy 256.666746 -78.883256) (xy 256.639491 -78.882773) (xy 256.585536 -78.875022) (xy 256.533233 -78.859672)
			(xy 256.483647 -78.837034) (xy 256.437787 -78.80757) (xy 256.396588 -78.771879) (xy 256.360887 -78.730688)
			(xy 256.331411 -78.684836) (xy 256.308761 -78.635255) (xy 256.293398 -78.582956) (xy 256.285633 -78.529003)
			(xy 256.285238 -78.501748) (xy 256.285238 -78.50124) (xy 256.285683 -78.474773) (xy 256.292992 -78.422345)
			(xy 256.307489 -78.371434) (xy 256.328895 -78.323021) (xy 256.356798 -78.278037) (xy 256.373376 -78.2574)
			(xy 256.377186 -78.252828) (xy 256.38252 -78.242668) (xy 256.384899 -78.23739) (xy 256.387471 -78.226104)
			(xy 256.3876 -78.220316) (xy 256.3876 -78.215744) (xy 256.386076 -78.203298) (xy 256.383028 -78.194662)
			(xy 256.346452 -78.114906) (xy 256.346452 -78.114652) (xy 256.346198 -78.114144) (xy 251.888244 -78.114144)
			(xy 251.849568 -78.113509) (xy 251.77288 -78.103407) (xy 251.698165 -78.083385) (xy 251.662184 -78.069186)
			(xy 250.755658 -77.693774) (xy 250.75097 -77.69198) (xy 250.741118 -77.690071) (xy 250.7361 -77.689964)
			(xy 244.297708 -77.689964) (xy 244.297708 -77.682344) (xy 242.52936 -77.682344) (xy 242.496206 -77.681878)
			(xy 242.430314 -77.674455) (xy 242.365666 -77.659705) (xy 242.303075 -77.637815) (xy 242.243325 -77.60906)
			(xy 242.187169 -77.573799) (xy 242.13531 -77.532477) (xy 242.11153 -77.50937) (xy 239.96269 -75.36053)
			(xy 239.955292 -75.353682) (xy 239.936694 -75.345946) (xy 239.926622 -75.345544) (xy 224.59696 -75.345544)
			(xy 224.563806 -75.345078) (xy 224.497914 -75.337655) (xy 224.433266 -75.322905) (xy 224.370675 -75.301015)
			(xy 224.310925 -75.27226) (xy 224.254769 -75.236999) (xy 224.20291 -75.195677) (xy 224.17913 -75.17257)
			(xy 223.52889 -74.52233) (xy 223.521492 -74.515482) (xy 223.502894 -74.507746) (xy 223.492822 -74.507344)
			(xy 223.145096 -74.507344) (xy 223.13513 -74.50782) (xy 223.116693 -74.515397) (xy 223.109282 -74.522076)
			(xy 223.058482 -74.572622) (xy 223.05176 -74.57995) (xy 223.044035 -74.598253) (xy 223.043496 -74.608182)
			(xy 223.042803 -74.635291) (xy 223.034696 -74.688909) (xy 223.019079 -74.740839) (xy 222.996266 -74.790034)
			(xy 222.966717 -74.835504) (xy 222.931027 -74.876331) (xy 222.889916 -74.911693) (xy 222.844212 -74.940878)
			(xy 222.794836 -74.963298) (xy 222.742783 -74.9785) (xy 222.689102 -74.986178) (xy 222.634874 -74.986178)
			(xy 222.581193 -74.9785) (xy 222.52914 -74.963298) (xy 222.479764 -74.940878) (xy 222.43406 -74.911693)
			(xy 222.392949 -74.876331) (xy 222.357259 -74.835504) (xy 222.32771 -74.790034) (xy 222.304897 -74.740839)
			(xy 222.28928 -74.688909) (xy 222.281173 -74.635291) (xy 222.28048 -74.608182) (xy 222.28048 -74.598022)
			(xy 222.272606 -74.579734) (xy 222.214694 -74.522076) (xy 222.207283 -74.515395) (xy 222.188847 -74.507819)
			(xy 222.17888 -74.507344) (xy 221.845378 -74.507344) (xy 221.835311 -74.507772) (xy 221.816716 -74.515497)
			(xy 221.80931 -74.52233) (xy 220.39707 -75.93457) (xy 220.373291 -75.95768) (xy 220.321438 -75.999013)
			(xy 220.265284 -76.034282) (xy 220.205535 -76.063042) (xy 220.142941 -76.084933) (xy 220.078291 -76.09968)
			(xy 220.012396 -76.107096) (xy 219.97924 -76.107544) (xy 196.953378 -76.107544) (xy 196.943311 -76.107972)
			(xy 196.924716 -76.115697) (xy 196.91731 -76.12253) (xy 196.41439 -76.62545) (xy 204.32979 -76.62545)
			(xy 204.333861 -76.569828) (xy 204.345987 -76.515391) (xy 204.36591 -76.4633) (xy 204.393206 -76.414665)
			(xy 204.427292 -76.370522) (xy 204.467441 -76.331813) (xy 204.512799 -76.299362) (xy 204.562399 -76.273861)
			(xy 204.615183 -76.255854) (xy 204.670026 -76.245724) (xy 204.72576 -76.243687) (xy 204.781197 -76.249787)
			(xy 204.835154 -76.263893) (xy 204.886483 -76.285705) (xy 204.934089 -76.314759) (xy 204.976957 -76.350434)
			(xy 205.014174 -76.391971) (xy 205.044947 -76.438484) (xy 205.068619 -76.488981) (xy 205.084687 -76.542388)
			(xy 205.092807 -76.597564) (xy 205.093316 -76.62545) (xy 205.092807 -76.653336) (xy 205.084687 -76.708512)
			(xy 205.068619 -76.761919) (xy 205.044947 -76.812416) (xy 205.014174 -76.858929) (xy 205.002842 -76.871576)
			(xy 221.119192 -76.871576) (xy 221.119673 -76.844139) (xy 221.127512 -76.789829) (xy 221.143054 -76.737203)
			(xy 221.165977 -76.687347) (xy 221.195808 -76.641291) (xy 221.231932 -76.599986) (xy 221.273602 -76.564284)
			(xy 221.319959 -76.534922) (xy 221.370046 -76.512507) (xy 221.396306 -76.504546) (xy 221.407228 -76.501498)
			(xy 221.423738 -76.487274) (xy 221.465648 -76.397358) (xy 221.465648 -76.375006) (xy 221.461076 -76.3651)
			(xy 221.450328 -76.340252) (xy 221.435172 -76.288281) (xy 221.427515 -76.234688) (xy 221.42704 -76.20762)
			(xy 221.427526 -76.180369) (xy 221.435282 -76.126421) (xy 221.450637 -76.074126) (xy 221.473279 -76.024549)
			(xy 221.502745 -75.978699) (xy 221.538436 -75.937508) (xy 221.579627 -75.901817) (xy 221.625477 -75.872351)
			(xy 221.675054 -75.849709) (xy 221.727349 -75.834354) (xy 221.781297 -75.826598) (xy 221.835799 -75.826598)
			(xy 221.889747 -75.834354) (xy 221.942042 -75.849709) (xy 221.991619 -75.872351) (xy 222.037469 -75.901817)
			(xy 222.07866 -75.937508) (xy 222.114351 -75.978699) (xy 222.143817 -76.024549) (xy 222.166459 -76.074126)
			(xy 222.181814 -76.126421) (xy 222.18957 -76.180369) (xy 222.190056 -76.20762) (xy 222.189609 -76.235058)
			(xy 222.181769 -76.289372) (xy 222.166226 -76.342001) (xy 222.1433 -76.391859) (xy 222.113464 -76.437916)
			(xy 222.077335 -76.479222) (xy 222.035659 -76.514922) (xy 221.989297 -76.544281) (xy 221.939205 -76.566691)
			(xy 221.912942 -76.57465) (xy 221.90202 -76.577698) (xy 221.88551 -76.591922) (xy 221.8436 -76.681838)
			(xy 221.8436 -76.70419) (xy 221.848172 -76.714096) (xy 221.858915 -76.738945) (xy 221.874075 -76.790916)
			(xy 221.881733 -76.844508) (xy 221.882208 -76.871576) (xy 221.881722 -76.898827) (xy 221.873966 -76.952775)
			(xy 221.858611 -77.00507) (xy 221.835969 -77.054647) (xy 221.806503 -77.100497) (xy 221.770812 -77.141688)
			(xy 221.729621 -77.177379) (xy 221.683771 -77.206845) (xy 221.634194 -77.229487) (xy 221.581899 -77.244842)
			(xy 221.527951 -77.252598) (xy 221.473449 -77.252598) (xy 221.419501 -77.244842) (xy 221.367206 -77.229487)
			(xy 221.317629 -77.206845) (xy 221.271779 -77.177379) (xy 221.230588 -77.141688) (xy 221.194897 -77.100497)
			(xy 221.165431 -77.054647) (xy 221.142789 -77.00507) (xy 221.127434 -76.952775) (xy 221.119678 -76.898827)
			(xy 221.119192 -76.871576) (xy 205.002842 -76.871576) (xy 204.976957 -76.900466) (xy 204.934089 -76.936141)
			(xy 204.886483 -76.965195) (xy 204.835154 -76.987007) (xy 204.781197 -77.001113) (xy 204.72576 -77.007213)
			(xy 204.670026 -77.005176) (xy 204.615183 -76.995046) (xy 204.562399 -76.977039) (xy 204.512799 -76.951538)
			(xy 204.467441 -76.919087) (xy 204.427292 -76.880378) (xy 204.393206 -76.836235) (xy 204.36591 -76.7876)
			(xy 204.345987 -76.735509) (xy 204.333861 -76.681072) (xy 204.32979 -76.62545) (xy 196.41439 -76.62545)
			(xy 195.833492 -77.206348) (xy 198.783954 -77.206348) (xy 198.788025 -77.150726) (xy 198.800151 -77.096289)
			(xy 198.820074 -77.044198) (xy 198.84737 -76.995563) (xy 198.881456 -76.95142) (xy 198.921605 -76.912711)
			(xy 198.966963 -76.88026) (xy 199.016563 -76.854759) (xy 199.069347 -76.836752) (xy 199.12419 -76.826622)
			(xy 199.179924 -76.824585) (xy 199.235361 -76.830685) (xy 199.289318 -76.844791) (xy 199.340647 -76.866603)
			(xy 199.388253 -76.895657) (xy 199.431121 -76.931332) (xy 199.468338 -76.972869) (xy 199.499111 -77.019382)
			(xy 199.522783 -77.069879) (xy 199.538851 -77.123286) (xy 199.546971 -77.178462) (xy 199.54748 -77.206348)
			(xy 199.546971 -77.234234) (xy 199.538851 -77.28941) (xy 199.522783 -77.342817) (xy 199.499111 -77.393314)
			(xy 199.468338 -77.439827) (xy 199.431121 -77.481364) (xy 199.388253 -77.517039) (xy 199.340647 -77.546093)
			(xy 199.29975 -77.563472) (xy 205.228442 -77.563472) (xy 205.232513 -77.50785) (xy 205.244639 -77.453413)
			(xy 205.264562 -77.401322) (xy 205.291858 -77.352687) (xy 205.325944 -77.308544) (xy 205.366093 -77.269835)
			(xy 205.411451 -77.237384) (xy 205.461051 -77.211883) (xy 205.513835 -77.193876) (xy 205.568678 -77.183746)
			(xy 205.624412 -77.181709) (xy 205.679849 -77.187809) (xy 205.733806 -77.201915) (xy 205.785135 -77.223727)
			(xy 205.832741 -77.252781) (xy 205.875609 -77.288456) (xy 205.912826 -77.329993) (xy 205.943599 -77.376506)
			(xy 205.967271 -77.427003) (xy 205.983339 -77.48041) (xy 205.991459 -77.535586) (xy 205.991968 -77.563472)
			(xy 207.251806 -77.563472) (xy 207.255877 -77.50785) (xy 207.268003 -77.453413) (xy 207.287926 -77.401322)
			(xy 207.315222 -77.352687) (xy 207.349308 -77.308544) (xy 207.389457 -77.269835) (xy 207.434815 -77.237384)
			(xy 207.484415 -77.211883) (xy 207.537199 -77.193876) (xy 207.592042 -77.183746) (xy 207.647776 -77.181709)
			(xy 207.703213 -77.187809) (xy 207.75717 -77.201915) (xy 207.808499 -77.223727) (xy 207.856105 -77.252781)
			(xy 207.898973 -77.288456) (xy 207.93619 -77.329993) (xy 207.966963 -77.376506) (xy 207.990635 -77.427003)
			(xy 208.006703 -77.48041) (xy 208.014823 -77.535586) (xy 208.015332 -77.563472) (xy 220.578678 -77.563472)
			(xy 220.582749 -77.50785) (xy 220.594875 -77.453413) (xy 220.614798 -77.401322) (xy 220.642094 -77.352687)
			(xy 220.67618 -77.308544) (xy 220.716329 -77.269835) (xy 220.761687 -77.237384) (xy 220.811287 -77.211883)
			(xy 220.864071 -77.193876) (xy 220.918914 -77.183746) (xy 220.974648 -77.181709) (xy 221.030085 -77.187809)
			(xy 221.084042 -77.201915) (xy 221.135371 -77.223727) (xy 221.182977 -77.252781) (xy 221.225845 -77.288456)
			(xy 221.263062 -77.329993) (xy 221.293835 -77.376506) (xy 221.317507 -77.427003) (xy 221.333575 -77.48041)
			(xy 221.341695 -77.535586) (xy 221.342204 -77.563472) (xy 222.62465 -77.563472) (xy 222.625214 -77.534544)
			(xy 222.633953 -77.477352) (xy 222.651228 -77.422136) (xy 222.676641 -77.37016) (xy 222.709611 -77.322618)
			(xy 222.749381 -77.280599) (xy 222.79504 -77.245066) (xy 222.84554 -77.216834) (xy 222.899723 -77.196551)
			(xy 222.927926 -77.190092) (xy 222.942126 -77.186685) (xy 222.967846 -77.172874) (xy 222.988617 -77.152358)
			(xy 223.002745 -77.126811) (xy 223.009079 -77.098312) (xy 223.007103 -77.069185) (xy 222.996978 -77.041803)
			(xy 222.988632 -77.029818) (xy 222.970842 -77.004942) (xy 222.942568 -76.950716) (xy 222.923305 -76.892674)
			(xy 222.913547 -76.832303) (xy 222.91294 -76.801726) (xy 222.913426 -76.774475) (xy 222.921182 -76.720527)
			(xy 222.936537 -76.668232) (xy 222.959179 -76.618655) (xy 222.988645 -76.572805) (xy 223.024336 -76.531614)
			(xy 223.065527 -76.495923) (xy 223.111377 -76.466457) (xy 223.160954 -76.443815) (xy 223.213249 -76.42846)
			(xy 223.267197 -76.420704) (xy 223.321699 -76.420704) (xy 223.375647 -76.42846) (xy 223.427942 -76.443815)
			(xy 223.477519 -76.466457) (xy 223.523369 -76.495923) (xy 223.56456 -76.531614) (xy 223.600251 -76.572805)
			(xy 223.629717 -76.618655) (xy 223.652359 -76.668232) (xy 223.667714 -76.720527) (xy 223.67547 -76.774475)
			(xy 223.675956 -76.801726) (xy 223.675476 -76.826085) (xy 229.640845 -76.826085) (xy 229.640845 -76.766115)
			(xy 229.648673 -76.706658) (xy 229.664196 -76.648731) (xy 229.687147 -76.593327) (xy 229.717134 -76.541392)
			(xy 229.753643 -76.493816) (xy 229.796051 -76.451413) (xy 229.84363 -76.414908) (xy 229.895568 -76.384926)
			(xy 229.950975 -76.361981) (xy 230.008903 -76.346464) (xy 230.068361 -76.338642) (xy 230.098346 -76.338176)
			(xy 230.961946 -76.338176) (xy 230.991931 -76.338593) (xy 231.051387 -76.346426) (xy 231.109312 -76.361952)
			(xy 231.164715 -76.384906) (xy 231.216648 -76.414894) (xy 231.264223 -76.451404) (xy 231.306626 -76.493811)
			(xy 231.343131 -76.54139) (xy 231.373114 -76.593326) (xy 231.396063 -76.648732) (xy 231.411583 -76.706658)
			(xy 231.41941 -76.766115) (xy 231.41941 -76.826085) (xy 231.415862 -76.853034) (xy 236.02264 -76.853034)
			(xy 236.026711 -76.797412) (xy 236.038837 -76.742975) (xy 236.05876 -76.690884) (xy 236.086056 -76.642249)
			(xy 236.120142 -76.598106) (xy 236.160291 -76.559397) (xy 236.205649 -76.526946) (xy 236.255249 -76.501445)
			(xy 236.308033 -76.483438) (xy 236.362876 -76.473308) (xy 236.41861 -76.471271) (xy 236.474047 -76.477371)
			(xy 236.528004 -76.491477) (xy 236.579333 -76.513289) (xy 236.626939 -76.542343) (xy 236.669807 -76.578018)
			(xy 236.707024 -76.619555) (xy 236.737797 -76.666068) (xy 236.761469 -76.716565) (xy 236.777537 -76.769972)
			(xy 236.785657 -76.825148) (xy 236.786166 -76.853034) (xy 236.785657 -76.88092) (xy 236.777537 -76.936096)
			(xy 236.761469 -76.989503) (xy 236.737797 -77.04) (xy 236.707024 -77.086513) (xy 236.669807 -77.12805)
			(xy 236.626939 -77.163725) (xy 236.579333 -77.192779) (xy 236.528004 -77.214591) (xy 236.474047 -77.228697)
			(xy 236.41861 -77.234797) (xy 236.362876 -77.23276) (xy 236.308033 -77.22263) (xy 236.255249 -77.204623)
			(xy 236.205649 -77.179122) (xy 236.160291 -77.146671) (xy 236.120142 -77.107962) (xy 236.086056 -77.063819)
			(xy 236.05876 -77.015184) (xy 236.038837 -76.963093) (xy 236.026711 -76.908656) (xy 236.02264 -76.853034)
			(xy 231.415862 -76.853034) (xy 231.411583 -76.885542) (xy 231.396063 -76.943468) (xy 231.373114 -76.998874)
			(xy 231.343131 -77.05081) (xy 231.306626 -77.098389) (xy 231.264223 -77.140796) (xy 231.216648 -77.177306)
			(xy 231.164715 -77.207294) (xy 231.109312 -77.230248) (xy 231.051387 -77.245774) (xy 230.991931 -77.253607)
			(xy 230.961946 -77.2541) (xy 230.098346 -77.2541) (xy 230.068361 -77.253558) (xy 230.008903 -77.245736)
			(xy 229.950975 -77.230219) (xy 229.895568 -77.207274) (xy 229.84363 -77.177292) (xy 229.796051 -77.140787)
			(xy 229.753643 -77.098384) (xy 229.717134 -77.050808) (xy 229.687147 -76.998873) (xy 229.664196 -76.943469)
			(xy 229.648673 -76.885542) (xy 229.640845 -76.826085) (xy 223.675476 -76.826085) (xy 223.675386 -76.830654)
			(xy 223.666647 -76.887845) (xy 223.649373 -76.943061) (xy 223.62396 -76.995036) (xy 223.590991 -77.042578)
			(xy 223.551222 -77.084598) (xy 223.505564 -77.120131) (xy 223.455065 -77.148363) (xy 223.400882 -77.168647)
			(xy 223.37268 -77.175106) (xy 223.358481 -77.178519) (xy 223.332761 -77.192328) (xy 223.31199 -77.212843)
			(xy 223.297862 -77.238389) (xy 223.291528 -77.266887) (xy 223.293503 -77.296014) (xy 223.303628 -77.323395)
			(xy 223.311974 -77.33538) (xy 223.329764 -77.360257) (xy 223.358038 -77.414483) (xy 223.377301 -77.472524)
			(xy 223.387059 -77.532895) (xy 223.387666 -77.563472) (xy 224.659188 -77.563472) (xy 224.663259 -77.50785)
			(xy 224.675385 -77.453413) (xy 224.695308 -77.401322) (xy 224.722604 -77.352687) (xy 224.75669 -77.308544)
			(xy 224.796839 -77.269835) (xy 224.842197 -77.237384) (xy 224.891797 -77.211883) (xy 224.944581 -77.193876)
			(xy 224.999424 -77.183746) (xy 225.055158 -77.181709) (xy 225.110595 -77.187809) (xy 225.164552 -77.201915)
			(xy 225.215881 -77.223727) (xy 225.263487 -77.252781) (xy 225.306355 -77.288456) (xy 225.343572 -77.329993)
			(xy 225.366461 -77.36459) (xy 234.24591 -77.36459) (xy 234.249981 -77.308968) (xy 234.262107 -77.254531)
			(xy 234.28203 -77.20244) (xy 234.309326 -77.153805) (xy 234.343412 -77.109662) (xy 234.383561 -77.070953)
			(xy 234.428919 -77.038502) (xy 234.478519 -77.013001) (xy 234.531303 -76.994994) (xy 234.586146 -76.984864)
			(xy 234.64188 -76.982827) (xy 234.697317 -76.988927) (xy 234.751274 -77.003033) (xy 234.802603 -77.024845)
			(xy 234.850209 -77.053899) (xy 234.893077 -77.089574) (xy 234.930294 -77.131111) (xy 234.961067 -77.177624)
			(xy 234.984739 -77.228121) (xy 235.000807 -77.281528) (xy 235.008927 -77.336704) (xy 235.009436 -77.36459)
			(xy 235.008927 -77.392476) (xy 235.000807 -77.447652) (xy 234.984739 -77.501059) (xy 234.961067 -77.551556)
			(xy 234.930294 -77.598069) (xy 234.893077 -77.639606) (xy 234.850209 -77.675281) (xy 234.802603 -77.704335)
			(xy 234.751274 -77.726147) (xy 234.697317 -77.740253) (xy 234.64188 -77.746353) (xy 234.586146 -77.744316)
			(xy 234.531303 -77.734186) (xy 234.478519 -77.716179) (xy 234.428919 -77.690678) (xy 234.383561 -77.658227)
			(xy 234.343412 -77.619518) (xy 234.309326 -77.575375) (xy 234.28203 -77.52674) (xy 234.262107 -77.474649)
			(xy 234.249981 -77.420212) (xy 234.24591 -77.36459) (xy 225.366461 -77.36459) (xy 225.374345 -77.376506)
			(xy 225.398017 -77.427003) (xy 225.414085 -77.48041) (xy 225.422205 -77.535586) (xy 225.422714 -77.563472)
			(xy 225.422205 -77.591358) (xy 225.414085 -77.646534) (xy 225.398017 -77.699941) (xy 225.374345 -77.750438)
			(xy 225.343572 -77.796951) (xy 225.306355 -77.838488) (xy 225.263487 -77.874163) (xy 225.215881 -77.903217)
			(xy 225.164552 -77.925029) (xy 225.110595 -77.939135) (xy 225.055158 -77.945235) (xy 224.999424 -77.943198)
			(xy 224.944581 -77.933068) (xy 224.891797 -77.915061) (xy 224.842197 -77.88956) (xy 224.796839 -77.857109)
			(xy 224.75669 -77.8184) (xy 224.722604 -77.774257) (xy 224.695308 -77.725622) (xy 224.675385 -77.673531)
			(xy 224.663259 -77.619094) (xy 224.659188 -77.563472) (xy 223.387666 -77.563472) (xy 223.38718 -77.590723)
			(xy 223.379424 -77.644671) (xy 223.364069 -77.696966) (xy 223.341427 -77.746543) (xy 223.311961 -77.792393)
			(xy 223.27627 -77.833584) (xy 223.235079 -77.869275) (xy 223.189229 -77.898741) (xy 223.139652 -77.921383)
			(xy 223.087357 -77.936738) (xy 223.033409 -77.944494) (xy 222.978907 -77.944494) (xy 222.924959 -77.936738)
			(xy 222.872664 -77.921383) (xy 222.823087 -77.898741) (xy 222.777237 -77.869275) (xy 222.736046 -77.833584)
			(xy 222.700355 -77.792393) (xy 222.670889 -77.746543) (xy 222.648247 -77.696966) (xy 222.632892 -77.644671)
			(xy 222.625136 -77.590723) (xy 222.62465 -77.563472) (xy 221.342204 -77.563472) (xy 221.341695 -77.591358)
			(xy 221.333575 -77.646534) (xy 221.317507 -77.699941) (xy 221.293835 -77.750438) (xy 221.263062 -77.796951)
			(xy 221.225845 -77.838488) (xy 221.182977 -77.874163) (xy 221.135371 -77.903217) (xy 221.084042 -77.925029)
			(xy 221.030085 -77.939135) (xy 220.974648 -77.945235) (xy 220.918914 -77.943198) (xy 220.864071 -77.933068)
			(xy 220.811287 -77.915061) (xy 220.761687 -77.88956) (xy 220.716329 -77.857109) (xy 220.67618 -77.8184)
			(xy 220.642094 -77.774257) (xy 220.614798 -77.725622) (xy 220.594875 -77.673531) (xy 220.582749 -77.619094)
			(xy 220.578678 -77.563472) (xy 208.015332 -77.563472) (xy 208.014823 -77.591358) (xy 208.006703 -77.646534)
			(xy 207.990635 -77.699941) (xy 207.966963 -77.750438) (xy 207.93619 -77.796951) (xy 207.898973 -77.838488)
			(xy 207.856105 -77.874163) (xy 207.808499 -77.903217) (xy 207.75717 -77.925029) (xy 207.703213 -77.939135)
			(xy 207.647776 -77.945235) (xy 207.592042 -77.943198) (xy 207.537199 -77.933068) (xy 207.484415 -77.915061)
			(xy 207.434815 -77.88956) (xy 207.389457 -77.857109) (xy 207.349308 -77.8184) (xy 207.315222 -77.774257)
			(xy 207.287926 -77.725622) (xy 207.268003 -77.673531) (xy 207.255877 -77.619094) (xy 207.251806 -77.563472)
			(xy 205.991968 -77.563472) (xy 205.991459 -77.591358) (xy 205.983339 -77.646534) (xy 205.967271 -77.699941)
			(xy 205.943599 -77.750438) (xy 205.912826 -77.796951) (xy 205.875609 -77.838488) (xy 205.832741 -77.874163)
			(xy 205.785135 -77.903217) (xy 205.733806 -77.925029) (xy 205.679849 -77.939135) (xy 205.624412 -77.945235)
			(xy 205.568678 -77.943198) (xy 205.513835 -77.933068) (xy 205.461051 -77.915061) (xy 205.411451 -77.88956)
			(xy 205.366093 -77.857109) (xy 205.325944 -77.8184) (xy 205.291858 -77.774257) (xy 205.264562 -77.725622)
			(xy 205.244639 -77.673531) (xy 205.232513 -77.619094) (xy 205.228442 -77.563472) (xy 199.29975 -77.563472)
			(xy 199.289318 -77.567905) (xy 199.235361 -77.582011) (xy 199.179924 -77.588111) (xy 199.12419 -77.586074)
			(xy 199.069347 -77.575944) (xy 199.016563 -77.557937) (xy 198.966963 -77.532436) (xy 198.921605 -77.499985)
			(xy 198.881456 -77.461276) (xy 198.84737 -77.417133) (xy 198.820074 -77.368498) (xy 198.800151 -77.316407)
			(xy 198.788025 -77.26197) (xy 198.783954 -77.206348) (xy 195.833492 -77.206348) (xy 193.85788 -79.18196)
			(xy 195.691506 -79.18196) (xy 195.691992 -79.154709) (xy 195.699748 -79.100761) (xy 195.715103 -79.048466)
			(xy 195.737745 -78.998889) (xy 195.767211 -78.953039) (xy 195.802902 -78.911848) (xy 195.844093 -78.876157)
			(xy 195.889943 -78.846691) (xy 195.93952 -78.824049) (xy 195.991815 -78.808694) (xy 196.045763 -78.800938)
			(xy 196.100265 -78.800938) (xy 196.154213 -78.808694) (xy 196.206508 -78.824049) (xy 196.256085 -78.846691)
			(xy 196.301935 -78.876157) (xy 196.321854 -78.893416) (xy 205.222856 -78.893416) (xy 205.223342 -78.866165)
			(xy 205.231098 -78.812217) (xy 205.246453 -78.759922) (xy 205.269095 -78.710345) (xy 205.298561 -78.664495)
			(xy 205.334252 -78.623304) (xy 205.375443 -78.587613) (xy 205.421293 -78.558147) (xy 205.47087 -78.535505)
			(xy 205.523165 -78.52015) (xy 205.577113 -78.512394) (xy 205.631615 -78.512394) (xy 205.685563 -78.52015)
			(xy 205.737858 -78.535505) (xy 205.787435 -78.558147) (xy 205.820617 -78.579472) (xy 208.52714 -78.579472)
			(xy 208.531211 -78.52385) (xy 208.543337 -78.469413) (xy 208.56326 -78.417322) (xy 208.590556 -78.368687)
			(xy 208.624642 -78.324544) (xy 208.664791 -78.285835) (xy 208.710149 -78.253384) (xy 208.759749 -78.227883)
			(xy 208.812533 -78.209876) (xy 208.867376 -78.199746) (xy 208.92311 -78.197709) (xy 208.978547 -78.203809)
			(xy 209.032504 -78.217915) (xy 209.083833 -78.239727) (xy 209.131439 -78.268781) (xy 209.174307 -78.304456)
			(xy 209.211524 -78.345993) (xy 209.242297 -78.392506) (xy 209.265969 -78.443003) (xy 209.282037 -78.49641)
			(xy 209.290157 -78.551586) (xy 209.290666 -78.579472) (xy 218.929202 -78.579472) (xy 218.933273 -78.52385)
			(xy 218.945399 -78.469413) (xy 218.965322 -78.417322) (xy 218.992618 -78.368687) (xy 219.026704 -78.324544)
			(xy 219.066853 -78.285835) (xy 219.112211 -78.253384) (xy 219.161811 -78.227883) (xy 219.214595 -78.209876)
			(xy 219.269438 -78.199746) (xy 219.325172 -78.197709) (xy 219.380609 -78.203809) (xy 219.434566 -78.217915)
			(xy 219.485895 -78.239727) (xy 219.533501 -78.268781) (xy 219.576369 -78.304456) (xy 219.613586 -78.345993)
			(xy 219.644359 -78.392506) (xy 219.668031 -78.443003) (xy 219.684099 -78.49641) (xy 219.692219 -78.551586)
			(xy 219.692728 -78.579472) (xy 222.62414 -78.579472) (xy 222.628211 -78.52385) (xy 222.640337 -78.469413)
			(xy 222.66026 -78.417322) (xy 222.687556 -78.368687) (xy 222.721642 -78.324544) (xy 222.761791 -78.285835)
			(xy 222.807149 -78.253384) (xy 222.856749 -78.227883) (xy 222.909533 -78.209876) (xy 222.964376 -78.199746)
			(xy 223.02011 -78.197709) (xy 223.075547 -78.203809) (xy 223.129504 -78.217915) (xy 223.180833 -78.239727)
			(xy 223.228439 -78.268781) (xy 223.271307 -78.304456) (xy 223.308524 -78.345993) (xy 223.339297 -78.392506)
			(xy 223.362969 -78.443003) (xy 223.379037 -78.49641) (xy 223.387157 -78.551586) (xy 223.387666 -78.579472)
			(xy 224.659188 -78.579472) (xy 224.663259 -78.52385) (xy 224.675385 -78.469413) (xy 224.695308 -78.417322)
			(xy 224.722604 -78.368687) (xy 224.75669 -78.324544) (xy 224.796839 -78.285835) (xy 224.842197 -78.253384)
			(xy 224.891797 -78.227883) (xy 224.944581 -78.209876) (xy 224.999424 -78.199746) (xy 225.055158 -78.197709)
			(xy 225.110595 -78.203809) (xy 225.164552 -78.217915) (xy 225.215881 -78.239727) (xy 225.263487 -78.268781)
			(xy 225.306355 -78.304456) (xy 225.343572 -78.345993) (xy 225.374345 -78.392506) (xy 225.398017 -78.443003)
			(xy 225.414085 -78.49641) (xy 225.422205 -78.551586) (xy 225.422714 -78.579472) (xy 225.422205 -78.607358)
			(xy 225.414085 -78.662534) (xy 225.398017 -78.715941) (xy 225.374345 -78.766438) (xy 225.343572 -78.812951)
			(xy 225.306355 -78.854488) (xy 225.263487 -78.890163) (xy 225.215881 -78.919217) (xy 225.164552 -78.941029)
			(xy 225.110595 -78.955135) (xy 225.055158 -78.961235) (xy 224.999424 -78.959198) (xy 224.944581 -78.949068)
			(xy 224.891797 -78.931061) (xy 224.842197 -78.90556) (xy 224.796839 -78.873109) (xy 224.75669 -78.8344)
			(xy 224.722604 -78.790257) (xy 224.695308 -78.741622) (xy 224.675385 -78.689531) (xy 224.663259 -78.635094)
			(xy 224.659188 -78.579472) (xy 223.387666 -78.579472) (xy 223.387157 -78.607358) (xy 223.379037 -78.662534)
			(xy 223.362969 -78.715941) (xy 223.339297 -78.766438) (xy 223.308524 -78.812951) (xy 223.271307 -78.854488)
			(xy 223.228439 -78.890163) (xy 223.180833 -78.919217) (xy 223.129504 -78.941029) (xy 223.075547 -78.955135)
			(xy 223.02011 -78.961235) (xy 222.964376 -78.959198) (xy 222.909533 -78.949068) (xy 222.856749 -78.931061)
			(xy 222.807149 -78.90556) (xy 222.761791 -78.873109) (xy 222.721642 -78.8344) (xy 222.687556 -78.790257)
			(xy 222.66026 -78.741622) (xy 222.640337 -78.689531) (xy 222.628211 -78.635094) (xy 222.62414 -78.579472)
			(xy 219.692728 -78.579472) (xy 219.692219 -78.607358) (xy 219.684099 -78.662534) (xy 219.668031 -78.715941)
			(xy 219.644359 -78.766438) (xy 219.613586 -78.812951) (xy 219.576369 -78.854488) (xy 219.533501 -78.890163)
			(xy 219.485895 -78.919217) (xy 219.434566 -78.941029) (xy 219.380609 -78.955135) (xy 219.325172 -78.961235)
			(xy 219.269438 -78.959198) (xy 219.214595 -78.949068) (xy 219.161811 -78.931061) (xy 219.112211 -78.90556)
			(xy 219.066853 -78.873109) (xy 219.026704 -78.8344) (xy 218.992618 -78.790257) (xy 218.965322 -78.741622)
			(xy 218.945399 -78.689531) (xy 218.933273 -78.635094) (xy 218.929202 -78.579472) (xy 209.290666 -78.579472)
			(xy 209.290157 -78.607358) (xy 209.282037 -78.662534) (xy 209.265969 -78.715941) (xy 209.242297 -78.766438)
			(xy 209.211524 -78.812951) (xy 209.174307 -78.854488) (xy 209.131439 -78.890163) (xy 209.083833 -78.919217)
			(xy 209.032504 -78.941029) (xy 208.978547 -78.955135) (xy 208.92311 -78.961235) (xy 208.867376 -78.959198)
			(xy 208.812533 -78.949068) (xy 208.759749 -78.931061) (xy 208.710149 -78.90556) (xy 208.664791 -78.873109)
			(xy 208.624642 -78.8344) (xy 208.590556 -78.790257) (xy 208.56326 -78.741622) (xy 208.543337 -78.689531)
			(xy 208.531211 -78.635094) (xy 208.52714 -78.579472) (xy 205.820617 -78.579472) (xy 205.833285 -78.587613)
			(xy 205.874476 -78.623304) (xy 205.910167 -78.664495) (xy 205.939633 -78.710345) (xy 205.962275 -78.759922)
			(xy 205.97763 -78.812217) (xy 205.985386 -78.866165) (xy 205.985872 -78.893416) (xy 205.985368 -78.920818)
			(xy 205.977525 -78.975057) (xy 205.962002 -79.027617) (xy 205.939119 -79.077414) (xy 205.909346 -79.123425)
			(xy 205.873296 -79.164703) (xy 205.831712 -79.200399) (xy 205.808834 -79.215488) (xy 205.796619 -79.223762)
			(xy 205.77725 -79.246004) (xy 205.765038 -79.27285) (xy 205.761002 -79.302066) (xy 205.765476 -79.331218)
			(xy 205.778088 -79.357878) (xy 205.797789 -79.379827) (xy 205.810104 -79.387954) (xy 205.833506 -79.402938)
			(xy 205.876109 -79.438611) (xy 205.913087 -79.480087) (xy 205.943657 -79.526489) (xy 205.967172 -79.576835)
			(xy 205.972761 -79.595472) (xy 207.251806 -79.595472) (xy 207.255877 -79.53985) (xy 207.268003 -79.485413)
			(xy 207.287926 -79.433322) (xy 207.315222 -79.384687) (xy 207.349308 -79.340544) (xy 207.389457 -79.301835)
			(xy 207.434815 -79.269384) (xy 207.484415 -79.243883) (xy 207.537199 -79.225876) (xy 207.592042 -79.215746)
			(xy 207.647776 -79.213709) (xy 207.703213 -79.219809) (xy 207.75717 -79.233915) (xy 207.808499 -79.255727)
			(xy 207.856105 -79.284781) (xy 207.898973 -79.320456) (xy 207.93619 -79.361993) (xy 207.966963 -79.408506)
			(xy 207.990635 -79.459003) (xy 208.006703 -79.51241) (xy 208.014823 -79.567586) (xy 208.015332 -79.595472)
			(xy 220.578678 -79.595472) (xy 220.582749 -79.53985) (xy 220.594875 -79.485413) (xy 220.614798 -79.433322)
			(xy 220.642094 -79.384687) (xy 220.67618 -79.340544) (xy 220.716329 -79.301835) (xy 220.761687 -79.269384)
			(xy 220.811287 -79.243883) (xy 220.864071 -79.225876) (xy 220.918914 -79.215746) (xy 220.974648 -79.213709)
			(xy 221.030085 -79.219809) (xy 221.084042 -79.233915) (xy 221.135371 -79.255727) (xy 221.182977 -79.284781)
			(xy 221.225845 -79.320456) (xy 221.263062 -79.361993) (xy 221.293835 -79.408506) (xy 221.317507 -79.459003)
			(xy 221.333575 -79.51241) (xy 221.341695 -79.567586) (xy 221.342204 -79.595472) (xy 222.62414 -79.595472)
			(xy 222.628211 -79.53985) (xy 222.640337 -79.485413) (xy 222.66026 -79.433322) (xy 222.687556 -79.384687)
			(xy 222.721642 -79.340544) (xy 222.761791 -79.301835) (xy 222.807149 -79.269384) (xy 222.856749 -79.243883)
			(xy 222.909533 -79.225876) (xy 222.964376 -79.215746) (xy 223.02011 -79.213709) (xy 223.075547 -79.219809)
			(xy 223.129504 -79.233915) (xy 223.180833 -79.255727) (xy 223.228439 -79.284781) (xy 223.271307 -79.320456)
			(xy 223.308524 -79.361993) (xy 223.339297 -79.408506) (xy 223.362969 -79.459003) (xy 223.379037 -79.51241)
			(xy 223.387157 -79.567586) (xy 223.387666 -79.595472) (xy 224.659188 -79.595472) (xy 224.663259 -79.53985)
			(xy 224.675385 -79.485413) (xy 224.695308 -79.433322) (xy 224.722604 -79.384687) (xy 224.75669 -79.340544)
			(xy 224.796839 -79.301835) (xy 224.842197 -79.269384) (xy 224.891797 -79.243883) (xy 224.944581 -79.225876)
			(xy 224.999424 -79.215746) (xy 225.055158 -79.213709) (xy 225.110595 -79.219809) (xy 225.164552 -79.233915)
			(xy 225.174386 -79.238094) (xy 227.9777 -79.238094) (xy 227.9777 -78.374494) (xy 227.97819 -78.344526)
			(xy 227.986013 -78.285104) (xy 228.001526 -78.227211) (xy 228.024462 -78.171838) (xy 228.054429 -78.119932)
			(xy 228.090916 -78.072382) (xy 228.133296 -78.030002) (xy 228.180846 -77.993515) (xy 228.232752 -77.963548)
			(xy 228.288125 -77.940612) (xy 228.346018 -77.925099) (xy 228.40544 -77.917276) (xy 228.465376 -77.917276)
			(xy 228.524798 -77.925099) (xy 228.582691 -77.940612) (xy 228.638064 -77.963548) (xy 228.68997 -77.993515)
			(xy 228.73752 -78.030002) (xy 228.7799 -78.072382) (xy 228.792845 -78.089252) (xy 232.193844 -78.089252)
			(xy 232.197915 -78.03363) (xy 232.210041 -77.979193) (xy 232.229964 -77.927102) (xy 232.25726 -77.878467)
			(xy 232.291346 -77.834324) (xy 232.331495 -77.795615) (xy 232.376853 -77.763164) (xy 232.426453 -77.737663)
			(xy 232.479237 -77.719656) (xy 232.53408 -77.709526) (xy 232.589814 -77.707489) (xy 232.645251 -77.713589)
			(xy 232.699208 -77.727695) (xy 232.750537 -77.749507) (xy 232.798143 -77.778561) (xy 232.841011 -77.814236)
			(xy 232.878228 -77.855773) (xy 232.909001 -77.902286) (xy 232.932673 -77.952783) (xy 232.948741 -78.00619)
			(xy 232.956861 -78.061366) (xy 232.95737 -78.089252) (xy 232.956861 -78.117138) (xy 232.948741 -78.172314)
			(xy 232.932673 -78.225721) (xy 232.909001 -78.276218) (xy 232.878228 -78.322731) (xy 232.841011 -78.364268)
			(xy 232.798143 -78.399943) (xy 232.750537 -78.428997) (xy 232.699208 -78.450809) (xy 232.645251 -78.464915)
			(xy 232.589814 -78.471015) (xy 232.53408 -78.468978) (xy 232.479237 -78.458848) (xy 232.426453 -78.440841)
			(xy 232.376853 -78.41534) (xy 232.331495 -78.382889) (xy 232.291346 -78.34418) (xy 232.25726 -78.300037)
			(xy 232.229964 -78.251402) (xy 232.210041 -78.199311) (xy 232.197915 -78.144874) (xy 232.193844 -78.089252)
			(xy 228.792845 -78.089252) (xy 228.816387 -78.119932) (xy 228.846354 -78.171838) (xy 228.86929 -78.227211)
			(xy 228.884803 -78.285104) (xy 228.892626 -78.344526) (xy 228.893116 -78.374494) (xy 228.893116 -79.005684)
			(xy 231.53446 -79.005684) (xy 231.538531 -78.950062) (xy 231.550657 -78.895625) (xy 231.57058 -78.843534)
			(xy 231.597876 -78.794899) (xy 231.631962 -78.750756) (xy 231.672111 -78.712047) (xy 231.717469 -78.679596)
			(xy 231.767069 -78.654095) (xy 231.819853 -78.636088) (xy 231.874696 -78.625958) (xy 231.93043 -78.623921)
			(xy 231.985867 -78.630021) (xy 232.036378 -78.643226) (xy 254.273302 -78.643226) (xy 254.277373 -78.587604)
			(xy 254.289499 -78.533167) (xy 254.309422 -78.481076) (xy 254.336718 -78.432441) (xy 254.370804 -78.388298)
			(xy 254.410953 -78.349589) (xy 254.456311 -78.317138) (xy 254.505911 -78.291637) (xy 254.558695 -78.27363)
			(xy 254.613538 -78.2635) (xy 254.669272 -78.261463) (xy 254.724709 -78.267563) (xy 254.778666 -78.281669)
			(xy 254.829995 -78.303481) (xy 254.877601 -78.332535) (xy 254.920469 -78.36821) (xy 254.957686 -78.409747)
			(xy 254.988459 -78.45626) (xy 255.012131 -78.506757) (xy 255.028199 -78.560164) (xy 255.036319 -78.61534)
			(xy 255.036828 -78.643226) (xy 255.036319 -78.671112) (xy 255.028199 -78.726288) (xy 255.012131 -78.779695)
			(xy 254.988459 -78.830192) (xy 254.957686 -78.876705) (xy 254.920469 -78.918242) (xy 254.877601 -78.953917)
			(xy 254.829995 -78.982971) (xy 254.778666 -79.004783) (xy 254.724709 -79.018889) (xy 254.669272 -79.024989)
			(xy 254.613538 -79.022952) (xy 254.558695 -79.012822) (xy 254.505911 -78.994815) (xy 254.456311 -78.969314)
			(xy 254.410953 -78.936863) (xy 254.370804 -78.898154) (xy 254.336718 -78.854011) (xy 254.309422 -78.805376)
			(xy 254.289499 -78.753285) (xy 254.277373 -78.698848) (xy 254.273302 -78.643226) (xy 232.036378 -78.643226)
			(xy 232.039824 -78.644127) (xy 232.091153 -78.665939) (xy 232.138759 -78.694993) (xy 232.181627 -78.730668)
			(xy 232.218844 -78.772205) (xy 232.249617 -78.818718) (xy 232.273289 -78.869215) (xy 232.289357 -78.922622)
			(xy 232.297477 -78.977798) (xy 232.297986 -79.005684) (xy 232.297477 -79.03357) (xy 232.289357 -79.088746)
			(xy 232.273289 -79.142153) (xy 232.249617 -79.19265) (xy 232.218844 -79.239163) (xy 232.181627 -79.2807)
			(xy 232.138759 -79.316375) (xy 232.091153 -79.345429) (xy 232.039824 -79.367241) (xy 231.985867 -79.381347)
			(xy 231.93043 -79.387447) (xy 231.874696 -79.38541) (xy 231.819853 -79.37528) (xy 231.767069 -79.357273)
			(xy 231.717469 -79.331772) (xy 231.672111 -79.299321) (xy 231.631962 -79.260612) (xy 231.597876 -79.216469)
			(xy 231.57058 -79.167834) (xy 231.550657 -79.115743) (xy 231.538531 -79.061306) (xy 231.53446 -79.005684)
			(xy 228.893116 -79.005684) (xy 228.893116 -79.238094) (xy 228.892626 -79.268062) (xy 228.884803 -79.327484)
			(xy 228.86929 -79.385377) (xy 228.846354 -79.44075) (xy 228.816387 -79.492656) (xy 228.7799 -79.540206)
			(xy 228.73752 -79.582586) (xy 228.68997 -79.619073) (xy 228.638064 -79.64904) (xy 228.582691 -79.671976)
			(xy 228.524798 -79.687489) (xy 228.465376 -79.695312) (xy 228.40544 -79.695312) (xy 228.346018 -79.687489)
			(xy 228.288125 -79.671976) (xy 228.232752 -79.64904) (xy 228.180846 -79.619073) (xy 228.133296 -79.582586)
			(xy 228.090916 -79.540206) (xy 228.054429 -79.492656) (xy 228.024462 -79.44075) (xy 228.001526 -79.385377)
			(xy 227.986013 -79.327484) (xy 227.97819 -79.268062) (xy 227.9777 -79.238094) (xy 225.174386 -79.238094)
			(xy 225.215881 -79.255727) (xy 225.263487 -79.284781) (xy 225.306355 -79.320456) (xy 225.343572 -79.361993)
			(xy 225.374345 -79.408506) (xy 225.398017 -79.459003) (xy 225.414085 -79.51241) (xy 225.422205 -79.567586)
			(xy 225.422714 -79.595472) (xy 225.422205 -79.623358) (xy 225.414085 -79.678534) (xy 225.398017 -79.731941)
			(xy 225.374345 -79.782438) (xy 225.343572 -79.828951) (xy 225.306355 -79.870488) (xy 225.263487 -79.906163)
			(xy 225.215881 -79.935217) (xy 225.164552 -79.957029) (xy 225.110595 -79.971135) (xy 225.055158 -79.977235)
			(xy 224.999424 -79.975198) (xy 224.944581 -79.965068) (xy 224.891797 -79.947061) (xy 224.842197 -79.92156)
			(xy 224.796839 -79.889109) (xy 224.75669 -79.8504) (xy 224.722604 -79.806257) (xy 224.695308 -79.757622)
			(xy 224.675385 -79.705531) (xy 224.663259 -79.651094) (xy 224.659188 -79.595472) (xy 223.387666 -79.595472)
			(xy 223.387157 -79.623358) (xy 223.379037 -79.678534) (xy 223.362969 -79.731941) (xy 223.339297 -79.782438)
			(xy 223.308524 -79.828951) (xy 223.271307 -79.870488) (xy 223.228439 -79.906163) (xy 223.180833 -79.935217)
			(xy 223.129504 -79.957029) (xy 223.075547 -79.971135) (xy 223.02011 -79.977235) (xy 222.964376 -79.975198)
			(xy 222.909533 -79.965068) (xy 222.856749 -79.947061) (xy 222.807149 -79.92156) (xy 222.761791 -79.889109)
			(xy 222.721642 -79.8504) (xy 222.687556 -79.806257) (xy 222.66026 -79.757622) (xy 222.640337 -79.705531)
			(xy 222.628211 -79.651094) (xy 222.62414 -79.595472) (xy 221.342204 -79.595472) (xy 221.341695 -79.623358)
			(xy 221.333575 -79.678534) (xy 221.317507 -79.731941) (xy 221.293835 -79.782438) (xy 221.263062 -79.828951)
			(xy 221.225845 -79.870488) (xy 221.182977 -79.906163) (xy 221.135371 -79.935217) (xy 221.084042 -79.957029)
			(xy 221.030085 -79.971135) (xy 220.974648 -79.977235) (xy 220.918914 -79.975198) (xy 220.864071 -79.965068)
			(xy 220.811287 -79.947061) (xy 220.761687 -79.92156) (xy 220.716329 -79.889109) (xy 220.67618 -79.8504)
			(xy 220.642094 -79.806257) (xy 220.614798 -79.757622) (xy 220.594875 -79.705531) (xy 220.582749 -79.651094)
			(xy 220.578678 -79.595472) (xy 208.015332 -79.595472) (xy 208.014823 -79.623358) (xy 208.006703 -79.678534)
			(xy 207.990635 -79.731941) (xy 207.966963 -79.782438) (xy 207.93619 -79.828951) (xy 207.898973 -79.870488)
			(xy 207.856105 -79.906163) (xy 207.808499 -79.935217) (xy 207.75717 -79.957029) (xy 207.703213 -79.971135)
			(xy 207.647776 -79.977235) (xy 207.592042 -79.975198) (xy 207.537199 -79.965068) (xy 207.484415 -79.947061)
			(xy 207.434815 -79.92156) (xy 207.389457 -79.889109) (xy 207.349308 -79.8504) (xy 207.315222 -79.806257)
			(xy 207.287926 -79.757622) (xy 207.268003 -79.705531) (xy 207.255877 -79.651094) (xy 207.251806 -79.595472)
			(xy 205.972761 -79.595472) (xy 205.983134 -79.63006) (xy 205.991207 -79.685037) (xy 205.991714 -79.71282)
			(xy 205.991228 -79.740071) (xy 205.983472 -79.794019) (xy 205.968117 -79.846314) (xy 205.945475 -79.895891)
			(xy 205.916009 -79.941741) (xy 205.880318 -79.982932) (xy 205.839127 -80.018623) (xy 205.793277 -80.048089)
			(xy 205.7437 -80.070731) (xy 205.691405 -80.086086) (xy 205.637457 -80.093842) (xy 205.582955 -80.093842)
			(xy 205.529007 -80.086086) (xy 205.476712 -80.070731) (xy 205.427135 -80.048089) (xy 205.381285 -80.018623)
			(xy 205.340094 -79.982932) (xy 205.304403 -79.941741) (xy 205.274937 -79.895891) (xy 205.252295 -79.846314)
			(xy 205.23694 -79.794019) (xy 205.229184 -79.740071) (xy 205.228698 -79.71282) (xy 205.22912 -79.685415)
			(xy 205.236974 -79.63117) (xy 205.252509 -79.578608) (xy 205.275405 -79.528809) (xy 205.305191 -79.482798)
			(xy 205.341254 -79.441523) (xy 205.382852 -79.405833) (xy 205.405736 -79.390748) (xy 205.417919 -79.382429)
			(xy 205.437292 -79.360199) (xy 205.449509 -79.333362) (xy 205.453552 -79.304153) (xy 205.449083 -79.275007)
			(xy 205.436475 -79.248351) (xy 205.416779 -79.226407) (xy 205.404466 -79.218282) (xy 205.381051 -79.203317)
			(xy 205.338444 -79.167644) (xy 205.301465 -79.126165) (xy 205.270895 -79.07976) (xy 205.247382 -79.02941)
			(xy 205.231425 -78.976181) (xy 205.223359 -78.921201) (xy 205.222856 -78.893416) (xy 196.321854 -78.893416)
			(xy 196.343126 -78.911848) (xy 196.378817 -78.953039) (xy 196.408283 -78.998889) (xy 196.430925 -79.048466)
			(xy 196.44628 -79.100761) (xy 196.454036 -79.154709) (xy 196.454522 -79.18196) (xy 196.453958 -79.210843)
			(xy 196.445242 -79.267948) (xy 196.428018 -79.323087) (xy 196.402681 -79.375) (xy 196.369808 -79.422501)
			(xy 196.33015 -79.464504) (xy 196.30771 -79.482696) (xy 196.296786 -79.491858) (xy 196.280033 -79.51491)
			(xy 196.270293 -79.541691) (xy 196.268324 -79.57012) (xy 196.274279 -79.597987) (xy 196.287695 -79.623129)
			(xy 196.307529 -79.64359) (xy 196.319648 -79.651098) (xy 196.344249 -79.665763) (xy 196.389122 -79.701351)
			(xy 196.42817 -79.743248) (xy 196.460515 -79.790512) (xy 196.48543 -79.84208) (xy 196.502355 -79.896794)
			(xy 196.510909 -79.953424) (xy 196.511418 -79.98206) (xy 196.510932 -80.009311) (xy 196.503176 -80.063259)
			(xy 196.487821 -80.115554) (xy 196.465179 -80.165131) (xy 196.435713 -80.210981) (xy 196.400022 -80.252172)
			(xy 196.358831 -80.287863) (xy 196.312981 -80.317329) (xy 196.263404 -80.339971) (xy 196.211109 -80.355326)
			(xy 196.157161 -80.363082) (xy 196.102659 -80.363082) (xy 196.048711 -80.355326) (xy 195.996416 -80.339971)
			(xy 195.946839 -80.317329) (xy 195.900989 -80.287863) (xy 195.859798 -80.252172) (xy 195.824107 -80.210981)
			(xy 195.794641 -80.165131) (xy 195.771999 -80.115554) (xy 195.756644 -80.063259) (xy 195.748888 -80.009311)
			(xy 195.748402 -79.98206) (xy 195.7489 -79.953174) (xy 195.757628 -79.896066) (xy 195.774865 -79.840925)
			(xy 195.800215 -79.789012) (xy 195.8331 -79.741513) (xy 195.872768 -79.699514) (xy 195.895214 -79.681324)
			(xy 195.906112 -79.672135) (xy 195.922862 -79.649089) (xy 195.9326 -79.622315) (xy 195.934571 -79.593893)
			(xy 195.928622 -79.566031) (xy 195.915215 -79.540893) (xy 195.89539 -79.520431) (xy 195.883276 -79.512922)
			(xy 195.858667 -79.498271) (xy 195.813797 -79.462678) (xy 195.774752 -79.420778) (xy 195.74241 -79.373511)
			(xy 195.717496 -79.321941) (xy 195.700572 -79.267226) (xy 195.692016 -79.210596) (xy 195.691506 -79.18196)
			(xy 193.85788 -79.18196) (xy 192.428368 -80.611472) (xy 205.228442 -80.611472) (xy 205.232513 -80.55585)
			(xy 205.244639 -80.501413) (xy 205.264562 -80.449322) (xy 205.291858 -80.400687) (xy 205.325944 -80.356544)
			(xy 205.366093 -80.317835) (xy 205.411451 -80.285384) (xy 205.461051 -80.259883) (xy 205.513835 -80.241876)
			(xy 205.568678 -80.231746) (xy 205.624412 -80.229709) (xy 205.679849 -80.235809) (xy 205.733806 -80.249915)
			(xy 205.785135 -80.271727) (xy 205.832741 -80.300781) (xy 205.875609 -80.336456) (xy 205.912826 -80.377993)
			(xy 205.943599 -80.424506) (xy 205.967271 -80.475003) (xy 205.977915 -80.51038) (xy 218.929202 -80.51038)
			(xy 218.933273 -80.454758) (xy 218.945399 -80.400321) (xy 218.965322 -80.34823) (xy 218.992618 -80.299595)
			(xy 219.026704 -80.255452) (xy 219.066853 -80.216743) (xy 219.112211 -80.184292) (xy 219.161811 -80.158791)
			(xy 219.214595 -80.140784) (xy 219.269438 -80.130654) (xy 219.325172 -80.128617) (xy 219.380609 -80.134717)
			(xy 219.434566 -80.148823) (xy 219.485895 -80.170635) (xy 219.533501 -80.199689) (xy 219.576369 -80.235364)
			(xy 219.613586 -80.276901) (xy 219.644359 -80.323414) (xy 219.668031 -80.373911) (xy 219.684099 -80.427318)
			(xy 219.692219 -80.482494) (xy 219.692728 -80.51038) (xy 219.692219 -80.538266) (xy 219.684099 -80.593442)
			(xy 219.678675 -80.611472) (xy 222.62414 -80.611472) (xy 222.628211 -80.55585) (xy 222.640337 -80.501413)
			(xy 222.66026 -80.449322) (xy 222.687556 -80.400687) (xy 222.721642 -80.356544) (xy 222.761791 -80.317835)
			(xy 222.807149 -80.285384) (xy 222.856749 -80.259883) (xy 222.909533 -80.241876) (xy 222.964376 -80.231746)
			(xy 223.02011 -80.229709) (xy 223.075547 -80.235809) (xy 223.129504 -80.249915) (xy 223.180833 -80.271727)
			(xy 223.228439 -80.300781) (xy 223.271307 -80.336456) (xy 223.308524 -80.377993) (xy 223.339297 -80.424506)
			(xy 223.362969 -80.475003) (xy 223.379037 -80.52841) (xy 223.387157 -80.583586) (xy 223.387666 -80.611472)
			(xy 224.659188 -80.611472) (xy 224.663259 -80.55585) (xy 224.675385 -80.501413) (xy 224.695308 -80.449322)
			(xy 224.722604 -80.400687) (xy 224.75669 -80.356544) (xy 224.796839 -80.317835) (xy 224.842197 -80.285384)
			(xy 224.891797 -80.259883) (xy 224.944581 -80.241876) (xy 224.999424 -80.231746) (xy 225.055158 -80.229709)
			(xy 225.110595 -80.235809) (xy 225.164552 -80.249915) (xy 225.215881 -80.271727) (xy 225.263487 -80.300781)
			(xy 225.306355 -80.336456) (xy 225.343572 -80.377993) (xy 225.374345 -80.424506) (xy 225.398017 -80.475003)
			(xy 225.414085 -80.52841) (xy 225.422205 -80.583586) (xy 225.422714 -80.611472) (xy 225.422205 -80.639358)
			(xy 225.414085 -80.694534) (xy 225.398017 -80.747941) (xy 225.374345 -80.798438) (xy 225.343572 -80.844951)
			(xy 225.306355 -80.886488) (xy 225.263487 -80.922163) (xy 225.215881 -80.951217) (xy 225.164552 -80.973029)
			(xy 225.110595 -80.987135) (xy 225.055158 -80.993235) (xy 224.999424 -80.991198) (xy 224.944581 -80.981068)
			(xy 224.891797 -80.963061) (xy 224.842197 -80.93756) (xy 224.796839 -80.905109) (xy 224.75669 -80.8664)
			(xy 224.722604 -80.822257) (xy 224.695308 -80.773622) (xy 224.675385 -80.721531) (xy 224.663259 -80.667094)
			(xy 224.659188 -80.611472) (xy 223.387666 -80.611472) (xy 223.387157 -80.639358) (xy 223.379037 -80.694534)
			(xy 223.362969 -80.747941) (xy 223.339297 -80.798438) (xy 223.308524 -80.844951) (xy 223.271307 -80.886488)
			(xy 223.228439 -80.922163) (xy 223.180833 -80.951217) (xy 223.129504 -80.973029) (xy 223.075547 -80.987135)
			(xy 223.02011 -80.993235) (xy 222.964376 -80.991198) (xy 222.909533 -80.981068) (xy 222.856749 -80.963061)
			(xy 222.807149 -80.93756) (xy 222.761791 -80.905109) (xy 222.721642 -80.8664) (xy 222.687556 -80.822257)
			(xy 222.66026 -80.773622) (xy 222.640337 -80.721531) (xy 222.628211 -80.667094) (xy 222.62414 -80.611472)
			(xy 219.678675 -80.611472) (xy 219.668031 -80.646849) (xy 219.644359 -80.697346) (xy 219.613586 -80.743859)
			(xy 219.576369 -80.785396) (xy 219.533501 -80.821071) (xy 219.485895 -80.850125) (xy 219.434566 -80.871937)
			(xy 219.380609 -80.886043) (xy 219.325172 -80.892143) (xy 219.269438 -80.890106) (xy 219.214595 -80.879976)
			(xy 219.161811 -80.861969) (xy 219.112211 -80.836468) (xy 219.066853 -80.804017) (xy 219.026704 -80.765308)
			(xy 218.992618 -80.721165) (xy 218.965322 -80.67253) (xy 218.945399 -80.620439) (xy 218.933273 -80.566002)
			(xy 218.929202 -80.51038) (xy 205.977915 -80.51038) (xy 205.983339 -80.52841) (xy 205.991459 -80.583586)
			(xy 205.991968 -80.611472) (xy 205.991459 -80.639358) (xy 205.983339 -80.694534) (xy 205.967271 -80.747941)
			(xy 205.943599 -80.798438) (xy 205.912826 -80.844951) (xy 205.875609 -80.886488) (xy 205.832741 -80.922163)
			(xy 205.785135 -80.951217) (xy 205.733806 -80.973029) (xy 205.679849 -80.987135) (xy 205.624412 -80.993235)
			(xy 205.568678 -80.991198) (xy 205.513835 -80.981068) (xy 205.461051 -80.963061) (xy 205.411451 -80.93756)
			(xy 205.366093 -80.905109) (xy 205.325944 -80.8664) (xy 205.291858 -80.822257) (xy 205.264562 -80.773622)
			(xy 205.244639 -80.721531) (xy 205.232513 -80.667094) (xy 205.228442 -80.611472) (xy 192.428368 -80.611472)
			(xy 191.86144 -81.1784) (xy 207.161382 -81.1784) (xy 207.165453 -81.122778) (xy 207.177579 -81.068341)
			(xy 207.197502 -81.01625) (xy 207.224798 -80.967615) (xy 207.258884 -80.923472) (xy 207.299033 -80.884763)
			(xy 207.344391 -80.852312) (xy 207.393991 -80.826811) (xy 207.446775 -80.808804) (xy 207.501618 -80.798674)
			(xy 207.557352 -80.796637) (xy 207.612789 -80.802737) (xy 207.666746 -80.816843) (xy 207.718075 -80.838655)
			(xy 207.765681 -80.867709) (xy 207.808549 -80.903384) (xy 207.845766 -80.944921) (xy 207.876539 -80.991434)
			(xy 207.900211 -81.041931) (xy 207.916279 -81.095338) (xy 207.924399 -81.150514) (xy 207.924908 -81.1784)
			(xy 207.924399 -81.206286) (xy 207.916279 -81.261462) (xy 207.900211 -81.314869) (xy 207.876539 -81.365366)
			(xy 207.845766 -81.411879) (xy 207.808549 -81.453416) (xy 207.765681 -81.489091) (xy 207.718075 -81.518145)
			(xy 207.666746 -81.539957) (xy 207.612789 -81.554063) (xy 207.557352 -81.560163) (xy 207.501618 -81.558126)
			(xy 207.446775 -81.547996) (xy 207.393991 -81.529989) (xy 207.344391 -81.504488) (xy 207.299033 -81.472037)
			(xy 207.258884 -81.433328) (xy 207.224798 -81.389185) (xy 207.197502 -81.34055) (xy 207.177579 -81.288459)
			(xy 207.165453 -81.234022) (xy 207.161382 -81.1784) (xy 191.86144 -81.1784) (xy 191.412368 -81.627472)
			(xy 205.228442 -81.627472) (xy 205.232513 -81.57185) (xy 205.244639 -81.517413) (xy 205.264562 -81.465322)
			(xy 205.291858 -81.416687) (xy 205.325944 -81.372544) (xy 205.366093 -81.333835) (xy 205.411451 -81.301384)
			(xy 205.461051 -81.275883) (xy 205.513835 -81.257876) (xy 205.568678 -81.247746) (xy 205.624412 -81.245709)
			(xy 205.679849 -81.251809) (xy 205.733806 -81.265915) (xy 205.785135 -81.287727) (xy 205.832741 -81.316781)
			(xy 205.875609 -81.352456) (xy 205.912826 -81.393993) (xy 205.943599 -81.440506) (xy 205.967271 -81.491003)
			(xy 205.983339 -81.54441) (xy 205.991459 -81.599586) (xy 205.991968 -81.627472) (xy 220.578678 -81.627472)
			(xy 220.582749 -81.57185) (xy 220.594875 -81.517413) (xy 220.614798 -81.465322) (xy 220.642094 -81.416687)
			(xy 220.67618 -81.372544) (xy 220.716329 -81.333835) (xy 220.761687 -81.301384) (xy 220.811287 -81.275883)
			(xy 220.864071 -81.257876) (xy 220.918914 -81.247746) (xy 220.974648 -81.245709) (xy 221.030085 -81.251809)
			(xy 221.084042 -81.265915) (xy 221.135371 -81.287727) (xy 221.182977 -81.316781) (xy 221.225845 -81.352456)
			(xy 221.263062 -81.393993) (xy 221.293835 -81.440506) (xy 221.317507 -81.491003) (xy 221.333575 -81.54441)
			(xy 221.341695 -81.599586) (xy 221.342204 -81.627472) (xy 222.62414 -81.627472) (xy 222.628211 -81.57185)
			(xy 222.640337 -81.517413) (xy 222.66026 -81.465322) (xy 222.687556 -81.416687) (xy 222.721642 -81.372544)
			(xy 222.761791 -81.333835) (xy 222.807149 -81.301384) (xy 222.856749 -81.275883) (xy 222.909533 -81.257876)
			(xy 222.964376 -81.247746) (xy 223.02011 -81.245709) (xy 223.075547 -81.251809) (xy 223.129504 -81.265915)
			(xy 223.180833 -81.287727) (xy 223.228439 -81.316781) (xy 223.271307 -81.352456) (xy 223.308524 -81.393993)
			(xy 223.339297 -81.440506) (xy 223.362969 -81.491003) (xy 223.379037 -81.54441) (xy 223.387157 -81.599586)
			(xy 223.387666 -81.627472) (xy 224.650044 -81.627472) (xy 224.654115 -81.57185) (xy 224.666241 -81.517413)
			(xy 224.686164 -81.465322) (xy 224.71346 -81.416687) (xy 224.747546 -81.372544) (xy 224.787695 -81.333835)
			(xy 224.833053 -81.301384) (xy 224.882653 -81.275883) (xy 224.935437 -81.257876) (xy 224.99028 -81.247746)
			(xy 225.046014 -81.245709) (xy 225.101451 -81.251809) (xy 225.155408 -81.265915) (xy 225.206737 -81.287727)
			(xy 225.254343 -81.316781) (xy 225.297211 -81.352456) (xy 225.334428 -81.393993) (xy 225.365201 -81.440506)
			(xy 225.388873 -81.491003) (xy 225.404941 -81.54441) (xy 225.413061 -81.599586) (xy 225.41357 -81.627472)
			(xy 225.413061 -81.655358) (xy 225.404941 -81.710534) (xy 225.388873 -81.763941) (xy 225.365201 -81.814438)
			(xy 225.334428 -81.860951) (xy 225.297211 -81.902488) (xy 225.254343 -81.938163) (xy 225.206737 -81.967217)
			(xy 225.155408 -81.989029) (xy 225.101451 -82.003135) (xy 225.046014 -82.009235) (xy 224.99028 -82.007198)
			(xy 224.935437 -81.997068) (xy 224.882653 -81.979061) (xy 224.833053 -81.95356) (xy 224.787695 -81.921109)
			(xy 224.747546 -81.8824) (xy 224.71346 -81.838257) (xy 224.686164 -81.789622) (xy 224.666241 -81.737531)
			(xy 224.654115 -81.683094) (xy 224.650044 -81.627472) (xy 223.387666 -81.627472) (xy 223.387157 -81.655358)
			(xy 223.379037 -81.710534) (xy 223.362969 -81.763941) (xy 223.339297 -81.814438) (xy 223.308524 -81.860951)
			(xy 223.271307 -81.902488) (xy 223.228439 -81.938163) (xy 223.180833 -81.967217) (xy 223.129504 -81.989029)
			(xy 223.075547 -82.003135) (xy 223.02011 -82.009235) (xy 222.964376 -82.007198) (xy 222.909533 -81.997068)
			(xy 222.856749 -81.979061) (xy 222.807149 -81.95356) (xy 222.761791 -81.921109) (xy 222.721642 -81.8824)
			(xy 222.687556 -81.838257) (xy 222.66026 -81.789622) (xy 222.640337 -81.737531) (xy 222.628211 -81.683094)
			(xy 222.62414 -81.627472) (xy 221.342204 -81.627472) (xy 221.341695 -81.655358) (xy 221.333575 -81.710534)
			(xy 221.317507 -81.763941) (xy 221.293835 -81.814438) (xy 221.263062 -81.860951) (xy 221.225845 -81.902488)
			(xy 221.182977 -81.938163) (xy 221.135371 -81.967217) (xy 221.084042 -81.989029) (xy 221.030085 -82.003135)
			(xy 220.974648 -82.009235) (xy 220.918914 -82.007198) (xy 220.864071 -81.997068) (xy 220.811287 -81.979061)
			(xy 220.761687 -81.95356) (xy 220.716329 -81.921109) (xy 220.67618 -81.8824) (xy 220.642094 -81.838257)
			(xy 220.614798 -81.789622) (xy 220.594875 -81.737531) (xy 220.582749 -81.683094) (xy 220.578678 -81.627472)
			(xy 205.991968 -81.627472) (xy 205.991459 -81.655358) (xy 205.983339 -81.710534) (xy 205.967271 -81.763941)
			(xy 205.943599 -81.814438) (xy 205.912826 -81.860951) (xy 205.875609 -81.902488) (xy 205.832741 -81.938163)
			(xy 205.785135 -81.967217) (xy 205.733806 -81.989029) (xy 205.679849 -82.003135) (xy 205.624412 -82.009235)
			(xy 205.568678 -82.007198) (xy 205.513835 -81.997068) (xy 205.461051 -81.979061) (xy 205.411451 -81.95356)
			(xy 205.366093 -81.921109) (xy 205.325944 -81.8824) (xy 205.291858 -81.838257) (xy 205.264562 -81.789622)
			(xy 205.244639 -81.737531) (xy 205.232513 -81.683094) (xy 205.228442 -81.627472) (xy 191.412368 -81.627472)
			(xy 190.80607 -82.23377) (xy 190.782291 -82.25688) (xy 190.730438 -82.298213) (xy 190.674284 -82.333482)
			(xy 190.614535 -82.362242) (xy 190.551941 -82.384133) (xy 190.487291 -82.39888) (xy 190.421396 -82.406296)
			(xy 190.38824 -82.406744) (xy 118.180866 -82.406744) (xy 118.14219 -82.40611) (xy 118.0655 -82.396011)
			(xy 117.990784 -82.375991) (xy 117.954806 -82.361786) (xy 117.79123 -82.294222) (xy 117.778276 -82.294222)
			(xy 117.561106 -82.204306) (xy 117.546628 -82.19821) (xy 117.516148 -82.20456) (xy 117.505226 -82.215736)
			(xy 117.504718 -82.216244) (xy 117.484398 -82.237072) (xy 117.479826 -82.26933) (xy 117.487446 -82.284062)
			(xy 117.499727 -82.308558) (xy 117.519015 -82.35985) (xy 117.532038 -82.413079) (xy 117.533789 -82.427572)
			(xy 195.032628 -82.427572) (xy 195.036699 -82.37195) (xy 195.048825 -82.317513) (xy 195.068748 -82.265422)
			(xy 195.096044 -82.216787) (xy 195.13013 -82.172644) (xy 195.170279 -82.133935) (xy 195.215637 -82.101484)
			(xy 195.265237 -82.075983) (xy 195.318021 -82.057976) (xy 195.372864 -82.047846) (xy 195.428598 -82.045809)
			(xy 195.484035 -82.051909) (xy 195.537992 -82.066015) (xy 195.589321 -82.087827) (xy 195.636927 -82.116881)
			(xy 195.679795 -82.152556) (xy 195.717012 -82.194093) (xy 195.747785 -82.240606) (xy 195.771457 -82.291103)
			(xy 195.787525 -82.34451) (xy 195.795645 -82.399686) (xy 195.796154 -82.427572) (xy 195.795645 -82.455458)
			(xy 195.787525 -82.510634) (xy 195.771457 -82.564041) (xy 195.747785 -82.614538) (xy 195.717012 -82.661051)
			(xy 195.679795 -82.702588) (xy 195.636927 -82.738263) (xy 195.589321 -82.767317) (xy 195.587874 -82.767932)
			(xy 203.09662 -82.767932) (xy 203.100691 -82.71231) (xy 203.112817 -82.657873) (xy 203.13274 -82.605782)
			(xy 203.160036 -82.557147) (xy 203.194122 -82.513004) (xy 203.234271 -82.474295) (xy 203.279629 -82.441844)
			(xy 203.329229 -82.416343) (xy 203.382013 -82.398336) (xy 203.436856 -82.388206) (xy 203.49259 -82.386169)
			(xy 203.548027 -82.392269) (xy 203.601984 -82.406375) (xy 203.653313 -82.428187) (xy 203.700919 -82.457241)
			(xy 203.743787 -82.492916) (xy 203.781004 -82.534453) (xy 203.811777 -82.580966) (xy 203.835449 -82.631463)
			(xy 203.839062 -82.643472) (xy 205.228442 -82.643472) (xy 205.232513 -82.58785) (xy 205.244639 -82.533413)
			(xy 205.264562 -82.481322) (xy 205.291858 -82.432687) (xy 205.325944 -82.388544) (xy 205.366093 -82.349835)
			(xy 205.411451 -82.317384) (xy 205.461051 -82.291883) (xy 205.513835 -82.273876) (xy 205.568678 -82.263746)
			(xy 205.624412 -82.261709) (xy 205.679849 -82.267809) (xy 205.733806 -82.281915) (xy 205.785135 -82.303727)
			(xy 205.832741 -82.332781) (xy 205.875609 -82.368456) (xy 205.912826 -82.409993) (xy 205.943599 -82.456506)
			(xy 205.967271 -82.507003) (xy 205.96905 -82.512916) (xy 213.546942 -82.512916) (xy 213.551013 -82.457294)
			(xy 213.563139 -82.402857) (xy 213.583062 -82.350766) (xy 213.610358 -82.302131) (xy 213.644444 -82.257988)
			(xy 213.684593 -82.219279) (xy 213.729951 -82.186828) (xy 213.779551 -82.161327) (xy 213.832335 -82.14332)
			(xy 213.887178 -82.13319) (xy 213.942912 -82.131153) (xy 213.998349 -82.137253) (xy 214.052306 -82.151359)
			(xy 214.103635 -82.173171) (xy 214.151241 -82.202225) (xy 214.194109 -82.2379) (xy 214.231326 -82.279437)
			(xy 214.262099 -82.32595) (xy 214.285771 -82.376447) (xy 214.300159 -82.42427) (xy 218.848938 -82.42427)
			(xy 218.853009 -82.368648) (xy 218.865135 -82.314211) (xy 218.885058 -82.26212) (xy 218.912354 -82.213485)
			(xy 218.94644 -82.169342) (xy 218.986589 -82.130633) (xy 219.031947 -82.098182) (xy 219.081547 -82.072681)
			(xy 219.134331 -82.054674) (xy 219.189174 -82.044544) (xy 219.244908 -82.042507) (xy 219.300345 -82.048607)
			(xy 219.354302 -82.062713) (xy 219.405631 -82.084525) (xy 219.453237 -82.113579) (xy 219.496105 -82.149254)
			(xy 219.533322 -82.190791) (xy 219.564095 -82.237304) (xy 219.587767 -82.287801) (xy 219.603835 -82.341208)
			(xy 219.611955 -82.396384) (xy 219.612464 -82.42427) (xy 219.611955 -82.452156) (xy 219.603835 -82.507332)
			(xy 219.587767 -82.560739) (xy 219.564095 -82.611236) (xy 219.542768 -82.643472) (xy 222.62414 -82.643472)
			(xy 222.628211 -82.58785) (xy 222.640337 -82.533413) (xy 222.66026 -82.481322) (xy 222.687556 -82.432687)
			(xy 222.721642 -82.388544) (xy 222.761791 -82.349835) (xy 222.807149 -82.317384) (xy 222.856749 -82.291883)
			(xy 222.909533 -82.273876) (xy 222.964376 -82.263746) (xy 223.02011 -82.261709) (xy 223.075547 -82.267809)
			(xy 223.129504 -82.281915) (xy 223.180833 -82.303727) (xy 223.228439 -82.332781) (xy 223.271307 -82.368456)
			(xy 223.308524 -82.409993) (xy 223.339297 -82.456506) (xy 223.362969 -82.507003) (xy 223.379037 -82.56041)
			(xy 223.387157 -82.615586) (xy 223.387666 -82.643472) (xy 224.650044 -82.643472) (xy 224.654115 -82.58785)
			(xy 224.666241 -82.533413) (xy 224.686164 -82.481322) (xy 224.71346 -82.432687) (xy 224.747546 -82.388544)
			(xy 224.787695 -82.349835) (xy 224.833053 -82.317384) (xy 224.882653 -82.291883) (xy 224.935437 -82.273876)
			(xy 224.99028 -82.263746) (xy 225.046014 -82.261709) (xy 225.101451 -82.267809) (xy 225.155408 -82.281915)
			(xy 225.206737 -82.303727) (xy 225.254343 -82.332781) (xy 225.297211 -82.368456) (xy 225.334428 -82.409993)
			(xy 225.365201 -82.456506) (xy 225.388873 -82.507003) (xy 225.404941 -82.56041) (xy 225.413061 -82.615586)
			(xy 225.41357 -82.643472) (xy 225.413061 -82.671358) (xy 225.404941 -82.726534) (xy 225.388873 -82.779941)
			(xy 225.365201 -82.830438) (xy 225.334428 -82.876951) (xy 225.297211 -82.918488) (xy 225.254343 -82.954163)
			(xy 225.206737 -82.983217) (xy 225.155408 -83.005029) (xy 225.101451 -83.019135) (xy 225.046014 -83.025235)
			(xy 224.99028 -83.023198) (xy 224.935437 -83.013068) (xy 224.882653 -82.995061) (xy 224.833053 -82.96956)
			(xy 224.787695 -82.937109) (xy 224.747546 -82.8984) (xy 224.71346 -82.854257) (xy 224.686164 -82.805622)
			(xy 224.666241 -82.753531) (xy 224.654115 -82.699094) (xy 224.650044 -82.643472) (xy 223.387666 -82.643472)
			(xy 223.387157 -82.671358) (xy 223.379037 -82.726534) (xy 223.362969 -82.779941) (xy 223.339297 -82.830438)
			(xy 223.308524 -82.876951) (xy 223.271307 -82.918488) (xy 223.228439 -82.954163) (xy 223.180833 -82.983217)
			(xy 223.129504 -83.005029) (xy 223.075547 -83.019135) (xy 223.02011 -83.025235) (xy 222.964376 -83.023198)
			(xy 222.909533 -83.013068) (xy 222.856749 -82.995061) (xy 222.807149 -82.96956) (xy 222.761791 -82.937109)
			(xy 222.721642 -82.8984) (xy 222.687556 -82.854257) (xy 222.66026 -82.805622) (xy 222.640337 -82.753531)
			(xy 222.628211 -82.699094) (xy 222.62414 -82.643472) (xy 219.542768 -82.643472) (xy 219.533322 -82.657749)
			(xy 219.496105 -82.699286) (xy 219.453237 -82.734961) (xy 219.405631 -82.764015) (xy 219.354302 -82.785827)
			(xy 219.300345 -82.799933) (xy 219.244908 -82.806033) (xy 219.189174 -82.803996) (xy 219.134331 -82.793866)
			(xy 219.081547 -82.775859) (xy 219.031947 -82.750358) (xy 218.986589 -82.717907) (xy 218.94644 -82.679198)
			(xy 218.912354 -82.635055) (xy 218.885058 -82.58642) (xy 218.865135 -82.534329) (xy 218.853009 -82.479892)
			(xy 218.848938 -82.42427) (xy 214.300159 -82.42427) (xy 214.301839 -82.429854) (xy 214.309959 -82.48503)
			(xy 214.310468 -82.512916) (xy 214.309959 -82.540802) (xy 214.301839 -82.595978) (xy 214.285771 -82.649385)
			(xy 214.262099 -82.699882) (xy 214.231326 -82.746395) (xy 214.194109 -82.787932) (xy 214.151241 -82.823607)
			(xy 214.103635 -82.852661) (xy 214.052306 -82.874473) (xy 213.998349 -82.888579) (xy 213.942912 -82.894679)
			(xy 213.887178 -82.892642) (xy 213.832335 -82.882512) (xy 213.779551 -82.864505) (xy 213.729951 -82.839004)
			(xy 213.684593 -82.806553) (xy 213.644444 -82.767844) (xy 213.610358 -82.723701) (xy 213.583062 -82.675066)
			(xy 213.563139 -82.622975) (xy 213.551013 -82.568538) (xy 213.546942 -82.512916) (xy 205.96905 -82.512916)
			(xy 205.983339 -82.56041) (xy 205.991459 -82.615586) (xy 205.991968 -82.643472) (xy 205.991459 -82.671358)
			(xy 205.983339 -82.726534) (xy 205.967271 -82.779941) (xy 205.943599 -82.830438) (xy 205.912826 -82.876951)
			(xy 205.875609 -82.918488) (xy 205.832741 -82.954163) (xy 205.785135 -82.983217) (xy 205.733806 -83.005029)
			(xy 205.679849 -83.019135) (xy 205.624412 -83.025235) (xy 205.568678 -83.023198) (xy 205.513835 -83.013068)
			(xy 205.461051 -82.995061) (xy 205.411451 -82.96956) (xy 205.366093 -82.937109) (xy 205.325944 -82.8984)
			(xy 205.291858 -82.854257) (xy 205.264562 -82.805622) (xy 205.244639 -82.753531) (xy 205.232513 -82.699094)
			(xy 205.228442 -82.643472) (xy 203.839062 -82.643472) (xy 203.851517 -82.68487) (xy 203.859637 -82.740046)
			(xy 203.860146 -82.767932) (xy 203.859637 -82.795818) (xy 203.851517 -82.850994) (xy 203.835449 -82.904401)
			(xy 203.811777 -82.954898) (xy 203.781004 -83.001411) (xy 203.743787 -83.042948) (xy 203.700919 -83.078623)
			(xy 203.653313 -83.107677) (xy 203.601984 -83.129489) (xy 203.548027 -83.143595) (xy 203.49259 -83.149695)
			(xy 203.436856 -83.147658) (xy 203.382013 -83.137528) (xy 203.329229 -83.119521) (xy 203.279629 -83.09402)
			(xy 203.234271 -83.061569) (xy 203.194122 -83.02286) (xy 203.160036 -82.978717) (xy 203.13274 -82.930082)
			(xy 203.112817 -82.877991) (xy 203.100691 -82.823554) (xy 203.09662 -82.767932) (xy 195.587874 -82.767932)
			(xy 195.537992 -82.789129) (xy 195.484035 -82.803235) (xy 195.428598 -82.809335) (xy 195.372864 -82.807298)
			(xy 195.318021 -82.797168) (xy 195.265237 -82.779161) (xy 195.215637 -82.75366) (xy 195.170279 -82.721209)
			(xy 195.13013 -82.6825) (xy 195.096044 -82.638357) (xy 195.068748 -82.589722) (xy 195.048825 -82.537631)
			(xy 195.036699 -82.483194) (xy 195.032628 -82.427572) (xy 117.533789 -82.427572) (xy 117.53861 -82.467483)
			(xy 117.539008 -82.494882) (xy 117.539008 -83.35899) (xy 117.538518 -83.388958) (xy 117.530695 -83.44838)
			(xy 117.515182 -83.506273) (xy 117.504435 -83.532218) (xy 192.411348 -83.532218) (xy 192.415419 -83.476596)
			(xy 192.427545 -83.422159) (xy 192.447468 -83.370068) (xy 192.474764 -83.321433) (xy 192.50885 -83.27729)
			(xy 192.548999 -83.238581) (xy 192.594357 -83.20613) (xy 192.643957 -83.180629) (xy 192.696741 -83.162622)
			(xy 192.751584 -83.152492) (xy 192.807318 -83.150455) (xy 192.862755 -83.156555) (xy 192.916712 -83.170661)
			(xy 192.968041 -83.192473) (xy 193.015647 -83.221527) (xy 193.058515 -83.257202) (xy 193.095732 -83.298739)
			(xy 193.126505 -83.345252) (xy 193.150177 -83.395749) (xy 193.166245 -83.449156) (xy 193.174365 -83.504332)
			(xy 193.174874 -83.532218) (xy 193.174365 -83.560104) (xy 193.166245 -83.61528) (xy 193.150177 -83.668687)
			(xy 193.126505 -83.719184) (xy 193.095732 -83.765697) (xy 193.058515 -83.807234) (xy 193.015647 -83.842909)
			(xy 192.968041 -83.871963) (xy 192.916712 -83.893775) (xy 192.862755 -83.907881) (xy 192.807318 -83.913981)
			(xy 192.751584 -83.911944) (xy 192.696741 -83.901814) (xy 192.643957 -83.883807) (xy 192.594357 -83.858306)
			(xy 192.548999 -83.825855) (xy 192.50885 -83.787146) (xy 192.474764 -83.743003) (xy 192.447468 -83.694368)
			(xy 192.427545 -83.642277) (xy 192.415419 -83.58784) (xy 192.411348 -83.532218) (xy 117.504435 -83.532218)
			(xy 117.492246 -83.561646) (xy 117.462279 -83.613552) (xy 117.425792 -83.661102) (xy 117.383412 -83.703482)
			(xy 117.335862 -83.739969) (xy 117.283956 -83.769936) (xy 117.228583 -83.792872) (xy 117.17069 -83.808385)
			(xy 117.111268 -83.816208) (xy 117.051332 -83.816208) (xy 116.99191 -83.808385) (xy 116.934017 -83.792872)
			(xy 116.878644 -83.769936) (xy 116.826738 -83.739969) (xy 116.779188 -83.703482) (xy 116.736808 -83.661102)
			(xy 116.700321 -83.613552) (xy 116.670354 -83.561646) (xy 116.647418 -83.506273) (xy 116.631905 -83.44838)
			(xy 116.624082 -83.388958) (xy 116.623592 -83.35899) (xy 116.623592 -82.49539) (xy 116.624032 -82.466416)
			(xy 116.631333 -82.408931) (xy 116.64583 -82.352827) (xy 116.667291 -82.299) (xy 116.695373 -82.248312)
			(xy 116.729626 -82.201573) (xy 116.769504 -82.15953) (xy 116.814369 -82.122856) (xy 116.863503 -82.092136)
			(xy 116.916121 -82.067862) (xy 116.943632 -82.058764) (xy 116.959634 -82.053684) (xy 116.978938 -82.027522)
			(xy 116.979192 -81.998058) (xy 116.979192 -81.99755) (xy 116.979446 -81.982056) (xy 116.962428 -81.956148)
			(xy 116.397786 -81.722214) (xy 116.393099 -81.720417) (xy 116.383247 -81.718501) (xy 116.378228 -81.718404)
			(xy 111.375698 -81.718404) (xy 111.364035 -81.718979) (xy 111.343125 -81.729313) (xy 111.335566 -81.738216)
			(xy 111.28375 -81.805272) (xy 111.279178 -81.827878) (xy 111.282226 -81.839562) (xy 111.288062 -81.863264)
			(xy 111.294309 -81.911675) (xy 111.294672 -81.936082) (xy 111.294186 -81.963333) (xy 111.28643 -82.017281)
			(xy 111.271075 -82.069576) (xy 111.248433 -82.119153) (xy 111.218967 -82.165003) (xy 111.183276 -82.206194)
			(xy 111.142085 -82.241885) (xy 111.096235 -82.271351) (xy 111.046658 -82.293993) (xy 110.994363 -82.309348)
			(xy 110.940415 -82.317104) (xy 110.885913 -82.317104) (xy 110.831965 -82.309348) (xy 110.77967 -82.293993)
			(xy 110.730093 -82.271351) (xy 110.684243 -82.241885) (xy 110.643052 -82.206194) (xy 110.607361 -82.165003)
			(xy 110.577895 -82.119153) (xy 110.555253 -82.069576) (xy 110.539898 -82.017281) (xy 110.532142 -81.963333)
			(xy 110.531656 -81.936082) (xy 110.532065 -81.911679) (xy 110.538311 -81.863272) (xy 110.544102 -81.839562)
			(xy 110.54715 -81.827878) (xy 110.542578 -81.805272) (xy 110.490762 -81.738216) (xy 110.483179 -81.729349)
			(xy 110.46228 -81.719027) (xy 110.45063 -81.718404) (xy 109.70514 -81.718404) (xy 109.695904 -81.718796)
			(xy 109.678627 -81.725333) (xy 109.664792 -81.737571) (xy 109.660182 -81.745582) (xy 109.630718 -81.801716)
			(xy 109.628025 -81.807248) (xy 109.625077 -81.819189) (xy 109.624876 -81.825338) (xy 109.624876 -81.855564)
			(xy 109.625103 -81.862835) (xy 109.629232 -81.876776) (xy 109.633004 -81.882996) (xy 109.633004 -81.88325)
			(xy 109.647262 -81.906424) (xy 109.669786 -81.955953) (xy 109.685054 -82.008177) (xy 109.692756 -82.062039)
			(xy 109.693202 -82.089244) (xy 109.693202 -82.089498) (xy 109.692739 -82.116751) (xy 109.684982 -82.170702)
			(xy 109.669626 -82.222999) (xy 109.646984 -82.272579) (xy 109.617516 -82.318432) (xy 109.581822 -82.359625)
			(xy 109.540629 -82.395318) (xy 109.494776 -82.424786) (xy 109.445196 -82.447428) (xy 109.392898 -82.462783)
			(xy 109.338947 -82.470539) (xy 109.311694 -82.471006) (xy 109.283973 -82.470508) (xy 109.229116 -82.46248)
			(xy 109.175999 -82.446594) (xy 109.125742 -82.423186) (xy 109.079403 -82.392747) (xy 109.03796 -82.35592)
			(xy 109.002286 -82.313481) (xy 108.973131 -82.266323) (xy 108.951112 -82.215442) (xy 108.943394 -82.188812)
			(xy 108.943394 -82.188558) (xy 108.939893 -82.177929) (xy 108.925403 -82.160911) (xy 108.915454 -82.155792)
			(xy 108.85678 -82.128614) (xy 108.851714 -82.12646) (xy 108.840949 -82.124165) (xy 108.835444 -82.124042)
			(xy 108.802678 -82.124042) (xy 108.792772 -82.12836) (xy 108.792518 -82.12836) (xy 108.768235 -82.138535)
			(xy 108.717575 -82.152878) (xy 108.665427 -82.160139) (xy 108.639102 -82.160618) (xy 108.611772 -82.160143)
			(xy 108.557673 -82.152333) (xy 108.505242 -82.136886) (xy 108.455549 -82.114118) (xy 108.409613 -82.084495)
			(xy 108.368371 -82.048623) (xy 108.332668 -82.007235) (xy 108.303233 -81.961177) (xy 108.280669 -81.911392)
			(xy 108.27258 -81.885282) (xy 108.27004 -81.876138) (xy 108.264198 -81.868518) (xy 108.261343 -81.864948)
			(xy 108.254574 -81.858808) (xy 108.250736 -81.856326) (xy 108.191808 -81.81975) (xy 108.1913 -81.81975)
			(xy 108.189522 -81.818734) (xy 108.171488 -81.815686) (xy 107.842812 -81.88071) (xy 107.831233 -81.883678)
			(xy 107.812434 -81.89839) (xy 107.806744 -81.908904) (xy 107.792266 -81.939384) (xy 107.792266 -81.939892)
			(xy 107.76966 -81.987898) (xy 107.770168 -82.01152) (xy 107.77601 -82.022188) (xy 107.79002 -82.049889)
			(xy 107.809843 -82.10871) (xy 107.819863 -82.169968) (xy 107.82046 -82.201004) (xy 107.82046 -82.201258)
			(xy 107.819974 -82.228509) (xy 107.812218 -82.282457) (xy 107.796863 -82.334752) (xy 107.774221 -82.384329)
			(xy 107.744755 -82.430179) (xy 107.709064 -82.47137) (xy 107.667873 -82.507061) (xy 107.622023 -82.536527)
			(xy 107.572446 -82.559169) (xy 107.550905 -82.565494) (xy 111.707166 -82.565494) (xy 111.711237 -82.509872)
			(xy 111.723363 -82.455435) (xy 111.743286 -82.403344) (xy 111.770582 -82.354709) (xy 111.804668 -82.310566)
			(xy 111.844817 -82.271857) (xy 111.890175 -82.239406) (xy 111.939775 -82.213905) (xy 111.992559 -82.195898)
			(xy 112.047402 -82.185768) (xy 112.103136 -82.183731) (xy 112.158573 -82.189831) (xy 112.21253 -82.203937)
			(xy 112.263859 -82.225749) (xy 112.311465 -82.254803) (xy 112.354333 -82.290478) (xy 112.39155 -82.332015)
			(xy 112.422323 -82.378528) (xy 112.445995 -82.429025) (xy 112.462063 -82.482432) (xy 112.470183 -82.537608)
			(xy 112.470692 -82.565494) (xy 112.470183 -82.59338) (xy 112.462063 -82.648556) (xy 112.445995 -82.701963)
			(xy 112.422323 -82.75246) (xy 112.39155 -82.798973) (xy 112.354333 -82.84051) (xy 112.311465 -82.876185)
			(xy 112.263859 -82.905239) (xy 112.21253 -82.927051) (xy 112.158573 -82.941157) (xy 112.103136 -82.947257)
			(xy 112.047402 -82.94522) (xy 111.992559 -82.93509) (xy 111.939775 -82.917083) (xy 111.890175 -82.891582)
			(xy 111.844817 -82.859131) (xy 111.804668 -82.820422) (xy 111.770582 -82.776279) (xy 111.743286 -82.727644)
			(xy 111.723363 -82.675553) (xy 111.711237 -82.621116) (xy 111.707166 -82.565494) (xy 107.550905 -82.565494)
			(xy 107.520151 -82.574524) (xy 107.466203 -82.58228) (xy 107.411701 -82.58228) (xy 107.357753 -82.574524)
			(xy 107.305458 -82.559169) (xy 107.255881 -82.536527) (xy 107.210031 -82.507061) (xy 107.16884 -82.47137)
			(xy 107.133149 -82.430179) (xy 107.103683 -82.384329) (xy 107.081041 -82.334752) (xy 107.065686 -82.282457)
			(xy 107.05793 -82.228509) (xy 107.057444 -82.201258) (xy 107.059222 -82.164682) (xy 107.060492 -82.152744)
			(xy 107.051856 -82.130138) (xy 106.98734 -82.071972) (xy 106.978063 -82.064551) (xy 106.955159 -82.058344)
			(xy 106.943398 -82.060034) (xy 105.847896 -82.277458) (xy 105.836421 -82.280429) (xy 105.817753 -82.29499)
			(xy 105.812082 -82.305398) (xy 105.77449 -82.383884) (xy 105.774998 -82.407506) (xy 105.780586 -82.418174)
			(xy 105.79419 -82.445376) (xy 105.813543 -82.503032) (xy 105.823502 -82.563029) (xy 105.824274 -82.593434)
			(xy 105.824274 -82.601562) (xy 105.823302 -82.631011) (xy 105.813401 -82.689094) (xy 105.794678 -82.744961)
			(xy 105.767581 -82.79728) (xy 105.732754 -82.844806) (xy 105.71226 -82.865976) (xy 105.693238 -82.884308)
			(xy 105.651042 -82.916093) (xy 105.604866 -82.941756) (xy 105.555593 -82.960808) (xy 105.504164 -82.972885)
			(xy 105.451561 -82.977756) (xy 105.398789 -82.975328) (xy 105.346855 -82.965648) (xy 105.296753 -82.9489)
			(xy 105.249437 -82.925405) (xy 105.205813 -82.89561) (xy 105.185972 -82.878168) (xy 105.181654 -82.874104)
			(xy 105.170732 -82.868008) (xy 105.164776 -82.864943) (xy 105.151776 -82.861737) (xy 105.145078 -82.861658)
			(xy 105.089198 -82.862928) (xy 105.079472 -82.86361) (xy 105.061583 -82.871321) (xy 105.0544 -82.877914)
			(xy 104.191816 -83.740244) (xy 104.188381 -83.743861) (xy 104.182876 -83.752177) (xy 104.180894 -83.756754)
			(xy 104.162352 -83.801458) (xy 104.158952 -83.810852) (xy 104.158884 -83.830809) (xy 104.166457 -83.849274)
			(xy 104.180518 -83.863437) (xy 104.18953 -83.867752) (xy 104.190292 -83.868006) (xy 104.1908 -83.868006)
			(xy 104.222403 -83.881073) (xy 104.280672 -83.916856) (xy 104.306624 -83.939126) (xy 104.313482 -83.945222)
			(xy 104.32669 -83.950302) (xy 104.331154 -83.951926) (xy 104.340484 -83.953712) (xy 104.345232 -83.953858)
			(xy 104.365552 -83.953858) (xy 104.369358 -83.953789) (xy 104.376883 -83.952637) (xy 104.380538 -83.951572)
			(xy 104.447086 -83.930744) (xy 104.447848 -83.930744) (xy 104.456135 -83.92773) (xy 104.470125 -83.917018)
			(xy 104.479634 -83.902184) (xy 104.481884 -83.89366) (xy 104.481884 -83.893406) (xy 104.488628 -83.865552)
			(xy 104.509337 -83.812116) (xy 104.537807 -83.762379) (xy 104.573396 -83.71746) (xy 104.615304 -83.678371)
			(xy 104.662587 -83.64599) (xy 104.714183 -83.621046) (xy 104.768929 -83.604101) (xy 104.825594 -83.595535)
			(xy 104.854248 -83.594956) (xy 104.854756 -83.594956) (xy 104.888538 -83.59648) (xy 104.898952 -83.59775)
			(xy 104.926444 -83.601492) (xy 104.980024 -83.615901) (xy 105.030951 -83.637919) (xy 105.078151 -83.667083)
			(xy 105.120629 -83.702776) (xy 105.157487 -83.744247) (xy 105.187949 -83.79062) (xy 105.211372 -83.840917)
			(xy 105.227261 -83.894076) (xy 105.233509 -83.93684) (xy 205.22057 -83.93684) (xy 205.22057 -83.936586)
			(xy 205.221056 -83.909335) (xy 205.228812 -83.855387) (xy 205.244167 -83.803092) (xy 205.266809 -83.753515)
			(xy 205.296275 -83.707665) (xy 205.331966 -83.666474) (xy 205.373157 -83.630783) (xy 205.419007 -83.601317)
			(xy 205.468584 -83.578675) (xy 205.520879 -83.56332) (xy 205.574827 -83.555564) (xy 205.629329 -83.555564)
			(xy 205.683277 -83.56332) (xy 205.735572 -83.578675) (xy 205.785149 -83.601317) (xy 205.830999 -83.630783)
			(xy 205.87219 -83.666474) (xy 205.907881 -83.707665) (xy 205.937347 -83.753515) (xy 205.959989 -83.803092)
			(xy 205.975344 -83.855387) (xy 205.975369 -83.85556) (xy 218.830142 -83.85556) (xy 218.834213 -83.799938)
			(xy 218.846339 -83.745501) (xy 218.866262 -83.69341) (xy 218.893558 -83.644775) (xy 218.927644 -83.600632)
			(xy 218.967793 -83.561923) (xy 219.013151 -83.529472) (xy 219.062751 -83.503971) (xy 219.115535 -83.485964)
			(xy 219.170378 -83.475834) (xy 219.226112 -83.473797) (xy 219.281549 -83.479897) (xy 219.335506 -83.494003)
			(xy 219.338765 -83.495388) (xy 220.578678 -83.495388) (xy 220.582749 -83.439766) (xy 220.594875 -83.385329)
			(xy 220.614798 -83.333238) (xy 220.642094 -83.284603) (xy 220.67618 -83.24046) (xy 220.716329 -83.201751)
			(xy 220.761687 -83.1693) (xy 220.811287 -83.143799) (xy 220.864071 -83.125792) (xy 220.918914 -83.115662)
			(xy 220.974648 -83.113625) (xy 221.030085 -83.119725) (xy 221.084042 -83.133831) (xy 221.135371 -83.155643)
			(xy 221.182977 -83.184697) (xy 221.225845 -83.220372) (xy 221.263062 -83.261909) (xy 221.293835 -83.308422)
			(xy 221.317507 -83.358919) (xy 221.333575 -83.412326) (xy 221.341695 -83.467502) (xy 221.342204 -83.495388)
			(xy 221.341695 -83.523274) (xy 221.333575 -83.57845) (xy 221.317507 -83.631857) (xy 221.304562 -83.659472)
			(xy 222.62414 -83.659472) (xy 222.628211 -83.60385) (xy 222.640337 -83.549413) (xy 222.66026 -83.497322)
			(xy 222.687556 -83.448687) (xy 222.721642 -83.404544) (xy 222.761791 -83.365835) (xy 222.807149 -83.333384)
			(xy 222.856749 -83.307883) (xy 222.909533 -83.289876) (xy 222.964376 -83.279746) (xy 223.02011 -83.277709)
			(xy 223.075547 -83.283809) (xy 223.129504 -83.297915) (xy 223.180833 -83.319727) (xy 223.228439 -83.348781)
			(xy 223.271307 -83.384456) (xy 223.308524 -83.425993) (xy 223.339297 -83.472506) (xy 223.362969 -83.523003)
			(xy 223.379037 -83.57641) (xy 223.387157 -83.631586) (xy 223.387666 -83.659472) (xy 224.650044 -83.659472)
			(xy 224.654115 -83.60385) (xy 224.666241 -83.549413) (xy 224.686164 -83.497322) (xy 224.71346 -83.448687)
			(xy 224.747546 -83.404544) (xy 224.787695 -83.365835) (xy 224.833053 -83.333384) (xy 224.882653 -83.307883)
			(xy 224.935437 -83.289876) (xy 224.99028 -83.279746) (xy 225.046014 -83.277709) (xy 225.101451 -83.283809)
			(xy 225.155408 -83.297915) (xy 225.206737 -83.319727) (xy 225.254343 -83.348781) (xy 225.297211 -83.384456)
			(xy 225.334428 -83.425993) (xy 225.365201 -83.472506) (xy 225.388873 -83.523003) (xy 225.404941 -83.57641)
			(xy 225.413061 -83.631586) (xy 225.41357 -83.659472) (xy 225.413061 -83.687358) (xy 225.404941 -83.742534)
			(xy 225.388873 -83.795941) (xy 225.365201 -83.846438) (xy 225.334428 -83.892951) (xy 225.297211 -83.934488)
			(xy 225.254343 -83.970163) (xy 225.206737 -83.999217) (xy 225.155408 -84.021029) (xy 225.101451 -84.035135)
			(xy 225.046014 -84.041235) (xy 224.99028 -84.039198) (xy 224.935437 -84.029068) (xy 224.882653 -84.011061)
			(xy 224.833053 -83.98556) (xy 224.787695 -83.953109) (xy 224.747546 -83.9144) (xy 224.71346 -83.870257)
			(xy 224.686164 -83.821622) (xy 224.666241 -83.769531) (xy 224.654115 -83.715094) (xy 224.650044 -83.659472)
			(xy 223.387666 -83.659472) (xy 223.387157 -83.687358) (xy 223.379037 -83.742534) (xy 223.362969 -83.795941)
			(xy 223.339297 -83.846438) (xy 223.308524 -83.892951) (xy 223.271307 -83.934488) (xy 223.228439 -83.970163)
			(xy 223.180833 -83.999217) (xy 223.129504 -84.021029) (xy 223.075547 -84.035135) (xy 223.02011 -84.041235)
			(xy 222.964376 -84.039198) (xy 222.909533 -84.029068) (xy 222.856749 -84.011061) (xy 222.807149 -83.98556)
			(xy 222.761791 -83.953109) (xy 222.721642 -83.9144) (xy 222.687556 -83.870257) (xy 222.66026 -83.821622)
			(xy 222.640337 -83.769531) (xy 222.628211 -83.715094) (xy 222.62414 -83.659472) (xy 221.304562 -83.659472)
			(xy 221.293835 -83.682354) (xy 221.263062 -83.728867) (xy 221.225845 -83.770404) (xy 221.182977 -83.806079)
			(xy 221.135371 -83.835133) (xy 221.084042 -83.856945) (xy 221.030085 -83.871051) (xy 220.974648 -83.877151)
			(xy 220.918914 -83.875114) (xy 220.864071 -83.864984) (xy 220.811287 -83.846977) (xy 220.761687 -83.821476)
			(xy 220.716329 -83.789025) (xy 220.67618 -83.750316) (xy 220.642094 -83.706173) (xy 220.614798 -83.657538)
			(xy 220.594875 -83.605447) (xy 220.582749 -83.55101) (xy 220.578678 -83.495388) (xy 219.338765 -83.495388)
			(xy 219.386835 -83.515815) (xy 219.434441 -83.544869) (xy 219.477309 -83.580544) (xy 219.514526 -83.622081)
			(xy 219.545299 -83.668594) (xy 219.568971 -83.719091) (xy 219.585039 -83.772498) (xy 219.593159 -83.827674)
			(xy 219.593668 -83.85556) (xy 219.593159 -83.883446) (xy 219.585039 -83.938622) (xy 219.568971 -83.992029)
			(xy 219.545299 -84.042526) (xy 219.514526 -84.089039) (xy 219.477309 -84.130576) (xy 219.434441 -84.166251)
			(xy 219.386835 -84.195305) (xy 219.335506 -84.217117) (xy 219.281549 -84.231223) (xy 219.226112 -84.237323)
			(xy 219.170378 -84.235286) (xy 219.115535 -84.225156) (xy 219.062751 -84.207149) (xy 219.013151 -84.181648)
			(xy 218.967793 -84.149197) (xy 218.927644 -84.110488) (xy 218.893558 -84.066345) (xy 218.866262 -84.01771)
			(xy 218.846339 -83.965619) (xy 218.834213 -83.911182) (xy 218.830142 -83.85556) (xy 205.975369 -83.85556)
			(xy 205.9831 -83.909335) (xy 205.983586 -83.936586) (xy 205.98313 -83.963925) (xy 205.975343 -84.018044)
			(xy 205.95991 -84.070498) (xy 205.937149 -84.120212) (xy 205.907526 -84.166168) (xy 205.871646 -84.207426)
			(xy 205.851252 -84.225638) (xy 205.842616 -84.23275) (xy 205.833472 -84.253324) (xy 205.834488 -84.353654)
			(xy 205.84414 -84.373466) (xy 205.85303 -84.380832) (xy 205.874382 -84.399018) (xy 205.911993 -84.440622)
			(xy 205.943101 -84.487289) (xy 205.967035 -84.538011) (xy 205.983278 -84.591693) (xy 205.99148 -84.647175)
			(xy 205.991968 -84.675218) (xy 205.991968 -84.675472) (xy 205.991482 -84.702723) (xy 205.983726 -84.756671)
			(xy 205.968371 -84.808966) (xy 205.945729 -84.858543) (xy 205.916263 -84.904393) (xy 205.880572 -84.945584)
			(xy 205.839381 -84.981275) (xy 205.793531 -85.010741) (xy 205.743954 -85.033383) (xy 205.691659 -85.048738)
			(xy 205.637711 -85.056494) (xy 205.583209 -85.056494) (xy 205.529261 -85.048738) (xy 205.476966 -85.033383)
			(xy 205.427389 -85.010741) (xy 205.381539 -84.981275) (xy 205.340348 -84.945584) (xy 205.304657 -84.904393)
			(xy 205.275191 -84.858543) (xy 205.252549 -84.808966) (xy 205.237194 -84.756671) (xy 205.229438 -84.702723)
			(xy 205.228952 -84.675472) (xy 205.2294 -84.648133) (xy 205.237192 -84.594015) (xy 205.252628 -84.541562)
			(xy 205.27539 -84.491848) (xy 205.305014 -84.445892) (xy 205.340893 -84.404633) (xy 205.361286 -84.38642)
			(xy 205.369922 -84.379308) (xy 205.379066 -84.358734) (xy 205.37805 -84.258404) (xy 205.368398 -84.238592)
			(xy 205.359508 -84.231226) (xy 205.338172 -84.213024) (xy 205.300562 -84.171421) (xy 205.269454 -84.124757)
			(xy 205.245517 -84.074038) (xy 205.22927 -84.02036) (xy 205.221062 -83.964881) (xy 205.22057 -83.93684)
			(xy 105.233509 -83.93684) (xy 105.235282 -83.948976) (xy 105.235756 -83.976718) (xy 105.235284 -84.004191)
			(xy 105.227416 -84.058571) (xy 105.211831 -84.11126) (xy 105.188852 -84.16117) (xy 105.158953 -84.207269)
			(xy 105.122752 -84.248604) (xy 105.102152 -84.266786) (xy 105.100628 -84.268056) (xy 105.100374 -84.26831)
			(xy 105.097072 -84.271104) (xy 105.089449 -84.278199) (xy 105.080162 -84.296817) (xy 105.079038 -84.307172)
			(xy 105.075228 -84.380578) (xy 105.074466 -84.393532) (xy 105.084372 -84.41436) (xy 105.090468 -84.420456)
			(xy 105.110845 -84.441977) (xy 105.145365 -84.490148) (xy 105.172022 -84.543077) (xy 105.183567 -84.578952)
			(xy 112.247678 -84.578952) (xy 112.251749 -84.52333) (xy 112.263875 -84.468893) (xy 112.283798 -84.416802)
			(xy 112.311094 -84.368167) (xy 112.34518 -84.324024) (xy 112.385329 -84.285315) (xy 112.430687 -84.252864)
			(xy 112.480287 -84.227363) (xy 112.533071 -84.209356) (xy 112.587914 -84.199226) (xy 112.643648 -84.197189)
			(xy 112.699085 -84.203289) (xy 112.753042 -84.217395) (xy 112.804371 -84.239207) (xy 112.851977 -84.268261)
			(xy 112.894845 -84.303936) (xy 112.932062 -84.345473) (xy 112.962835 -84.391986) (xy 112.986507 -84.442483)
			(xy 113.002575 -84.49589) (xy 113.010695 -84.551066) (xy 113.011204 -84.578952) (xy 113.010695 -84.606838)
			(xy 113.002575 -84.662014) (xy 112.986507 -84.715421) (xy 112.962835 -84.765918) (xy 112.932062 -84.812431)
			(xy 112.894845 -84.853968) (xy 112.851977 -84.889643) (xy 112.804371 -84.918697) (xy 112.753042 -84.940509)
			(xy 112.699085 -84.954615) (xy 112.643648 -84.960715) (xy 112.587914 -84.958678) (xy 112.533071 -84.948548)
			(xy 112.480287 -84.930541) (xy 112.430687 -84.90504) (xy 112.385329 -84.872589) (xy 112.34518 -84.83388)
			(xy 112.311094 -84.789737) (xy 112.283798 -84.741102) (xy 112.263875 -84.689011) (xy 112.251749 -84.634574)
			(xy 112.247678 -84.578952) (xy 105.183567 -84.578952) (xy 105.190176 -84.599491) (xy 105.19939 -84.658033)
			(xy 105.199942 -84.687664) (xy 105.199942 -84.688172) (xy 105.199456 -84.715423) (xy 105.1917 -84.769371)
			(xy 105.176345 -84.821666) (xy 105.153703 -84.871243) (xy 105.124237 -84.917093) (xy 105.088546 -84.958284)
			(xy 105.047355 -84.993975) (xy 105.001505 -85.023441) (xy 104.951928 -85.046083) (xy 104.899633 -85.061438)
			(xy 104.845685 -85.069194) (xy 104.791183 -85.069194) (xy 104.737235 -85.061438) (xy 104.68494 -85.046083)
			(xy 104.635363 -85.023441) (xy 104.589513 -84.993975) (xy 104.548322 -84.958284) (xy 104.512631 -84.917093)
			(xy 104.483165 -84.871243) (xy 104.460523 -84.821666) (xy 104.445168 -84.769371) (xy 104.437412 -84.715423)
			(xy 104.436926 -84.688172) (xy 104.437429 -84.660404) (xy 104.445486 -84.605454) (xy 104.461426 -84.552254)
			(xy 104.484912 -84.501927) (xy 104.515448 -84.455538) (xy 104.552387 -84.414067) (xy 104.573324 -84.395818)
			(xy 104.573578 -84.395564) (xy 104.583738 -84.386928) (xy 104.592882 -84.368132) (xy 104.59339 -84.357718)
			(xy 104.597454 -84.28609) (xy 104.597454 -84.280502) (xy 104.596934 -84.270604) (xy 104.589349 -84.252313)
			(xy 104.582722 -84.244942) (xy 104.58069 -84.242656) (xy 104.568239 -84.229518) (xy 104.545594 -84.201278)
			(xy 104.535478 -84.186268) (xy 104.533954 -84.183982) (xy 104.524302 -84.17179) (xy 104.515666 -84.166964)
			(xy 104.511094 -84.16417) (xy 104.500983 -84.158495) (xy 104.477948 -84.156092) (xy 104.466898 -84.159598)
			(xy 104.45623 -84.163662) (xy 104.440228 -84.179918) (xy 104.43337 -84.199984) (xy 104.433624 -84.209382)
			(xy 104.433624 -84.210652) (xy 104.433878 -84.223606) (xy 104.433402 -84.25072) (xy 104.425723 -84.304403)
			(xy 104.410522 -84.356457) (xy 104.388104 -84.405836) (xy 104.358921 -84.451542) (xy 104.323561 -84.492657)
			(xy 104.282736 -84.528351) (xy 104.237269 -84.557906) (xy 104.188075 -84.580726) (xy 104.136146 -84.596352)
			(xy 104.082528 -84.604468) (xy 104.055418 -84.605114) (xy 104.051608 -84.605114) (xy 104.019355 -84.604439)
			(xy 103.955768 -84.593584) (xy 103.925116 -84.583524) (xy 103.915972 -84.580222) (xy 103.896668 -84.581238)
			(xy 103.844598 -84.604352) (xy 103.836039 -84.608716) (xy 103.822744 -84.622564) (xy 103.81869 -84.631276)
			(xy 103.43966 -85.54593) (xy 103.779826 -85.54593) (xy 103.783897 -85.490308) (xy 103.796023 -85.435871)
			(xy 103.815946 -85.38378) (xy 103.843242 -85.335145) (xy 103.877328 -85.291002) (xy 103.917477 -85.252293)
			(xy 103.962835 -85.219842) (xy 104.012435 -85.194341) (xy 104.065219 -85.176334) (xy 104.120062 -85.166204)
			(xy 104.175796 -85.164167) (xy 104.231233 -85.170267) (xy 104.28519 -85.184373) (xy 104.336519 -85.206185)
			(xy 104.384125 -85.235239) (xy 104.426993 -85.270914) (xy 104.46421 -85.312451) (xy 104.494983 -85.358964)
			(xy 104.494993 -85.358986) (xy 117.385592 -85.358986) (xy 117.385592 -84.495386) (xy 117.386082 -84.465418)
			(xy 117.393905 -84.405996) (xy 117.409418 -84.348103) (xy 117.432354 -84.29273) (xy 117.462321 -84.240824)
			(xy 117.498808 -84.193274) (xy 117.541188 -84.150894) (xy 117.588738 -84.114407) (xy 117.640644 -84.08444)
			(xy 117.696017 -84.061504) (xy 117.75391 -84.045991) (xy 117.813332 -84.038168) (xy 117.873268 -84.038168)
			(xy 117.93269 -84.045991) (xy 117.990583 -84.061504) (xy 118.045956 -84.08444) (xy 118.097862 -84.114407)
			(xy 118.145412 -84.150894) (xy 118.187792 -84.193274) (xy 118.224279 -84.240824) (xy 118.254246 -84.29273)
			(xy 118.277182 -84.348103) (xy 118.292695 -84.405996) (xy 118.300518 -84.465418) (xy 118.300697 -84.476336)
			(xy 195.74713 -84.476336) (xy 195.751201 -84.420714) (xy 195.763327 -84.366277) (xy 195.78325 -84.314186)
			(xy 195.810546 -84.265551) (xy 195.844632 -84.221408) (xy 195.884781 -84.182699) (xy 195.930139 -84.150248)
			(xy 195.979739 -84.124747) (xy 196.032523 -84.10674) (xy 196.087366 -84.09661) (xy 196.1431 -84.094573)
			(xy 196.198537 -84.100673) (xy 196.252494 -84.114779) (xy 196.303823 -84.136591) (xy 196.351429 -84.165645)
			(xy 196.394297 -84.20132) (xy 196.431514 -84.242857) (xy 196.462287 -84.28937) (xy 196.485959 -84.339867)
			(xy 196.502027 -84.393274) (xy 196.510147 -84.44845) (xy 196.510656 -84.476336) (xy 196.510147 -84.504222)
			(xy 196.502027 -84.559398) (xy 196.485959 -84.612805) (xy 196.462287 -84.663302) (xy 196.454235 -84.675472)
			(xy 202.825348 -84.675472) (xy 202.829419 -84.61985) (xy 202.841545 -84.565413) (xy 202.861468 -84.513322)
			(xy 202.888764 -84.464687) (xy 202.92285 -84.420544) (xy 202.962999 -84.381835) (xy 203.008357 -84.349384)
			(xy 203.057957 -84.323883) (xy 203.110741 -84.305876) (xy 203.165584 -84.295746) (xy 203.221318 -84.293709)
			(xy 203.276755 -84.299809) (xy 203.330712 -84.313915) (xy 203.382041 -84.335727) (xy 203.429647 -84.364781)
			(xy 203.472515 -84.400456) (xy 203.509732 -84.441993) (xy 203.540505 -84.488506) (xy 203.564177 -84.539003)
			(xy 203.580245 -84.59241) (xy 203.588365 -84.647586) (xy 203.588874 -84.675472) (xy 203.588365 -84.703358)
			(xy 203.580245 -84.758534) (xy 203.564177 -84.811941) (xy 203.540505 -84.862438) (xy 203.509732 -84.908951)
			(xy 203.472515 -84.950488) (xy 203.429647 -84.986163) (xy 203.382041 -85.015217) (xy 203.330712 -85.037029)
			(xy 203.276755 -85.051135) (xy 203.221318 -85.057235) (xy 203.165584 -85.055198) (xy 203.110741 -85.045068)
			(xy 203.057957 -85.027061) (xy 203.008357 -85.00156) (xy 202.962999 -84.969109) (xy 202.92285 -84.9304)
			(xy 202.888764 -84.886257) (xy 202.861468 -84.837622) (xy 202.841545 -84.785531) (xy 202.829419 -84.731094)
			(xy 202.825348 -84.675472) (xy 196.454235 -84.675472) (xy 196.431514 -84.709815) (xy 196.394297 -84.751352)
			(xy 196.351429 -84.787027) (xy 196.303823 -84.816081) (xy 196.252494 -84.837893) (xy 196.198537 -84.851999)
			(xy 196.1431 -84.858099) (xy 196.087366 -84.856062) (xy 196.032523 -84.845932) (xy 195.979739 -84.827925)
			(xy 195.930139 -84.802424) (xy 195.884781 -84.769973) (xy 195.844632 -84.731264) (xy 195.810546 -84.687121)
			(xy 195.78325 -84.638486) (xy 195.763327 -84.586395) (xy 195.751201 -84.531958) (xy 195.74713 -84.476336)
			(xy 118.300697 -84.476336) (xy 118.301008 -84.495386) (xy 118.301008 -85.358986) (xy 118.300518 -85.388954)
			(xy 118.293361 -85.443314) (xy 146.479004 -85.443314) (xy 146.483075 -85.387692) (xy 146.495201 -85.333255)
			(xy 146.515124 -85.281164) (xy 146.54242 -85.232529) (xy 146.576506 -85.188386) (xy 146.616655 -85.149677)
			(xy 146.662013 -85.117226) (xy 146.711613 -85.091725) (xy 146.764397 -85.073718) (xy 146.81924 -85.063588)
			(xy 146.874974 -85.061551) (xy 146.930411 -85.067651) (xy 146.984368 -85.081757) (xy 147.035697 -85.103569)
			(xy 147.083303 -85.132623) (xy 147.126171 -85.168298) (xy 147.163388 -85.209835) (xy 147.194161 -85.256348)
			(xy 147.217833 -85.306845) (xy 147.233901 -85.360252) (xy 147.242021 -85.415428) (xy 147.242039 -85.41639)
			(xy 148.126448 -85.41639) (xy 148.130519 -85.360768) (xy 148.142645 -85.306331) (xy 148.162568 -85.25424)
			(xy 148.189864 -85.205605) (xy 148.22395 -85.161462) (xy 148.264099 -85.122753) (xy 148.309457 -85.090302)
			(xy 148.359057 -85.064801) (xy 148.411841 -85.046794) (xy 148.466684 -85.036664) (xy 148.522418 -85.034627)
			(xy 148.577855 -85.040727) (xy 148.631812 -85.054833) (xy 148.683141 -85.076645) (xy 148.730747 -85.105699)
			(xy 148.773615 -85.141374) (xy 148.810832 -85.182911) (xy 148.841605 -85.229424) (xy 148.865277 -85.279921)
			(xy 148.881345 -85.333328) (xy 148.889465 -85.388504) (xy 148.889974 -85.41639) (xy 148.889465 -85.444276)
			(xy 148.881345 -85.499452) (xy 148.865277 -85.552859) (xy 148.841605 -85.603356) (xy 148.810832 -85.649869)
			(xy 148.773615 -85.691406) (xy 148.773536 -85.691472) (xy 202.857352 -85.691472) (xy 202.861423 -85.63585)
			(xy 202.873549 -85.581413) (xy 202.893472 -85.529322) (xy 202.920768 -85.480687) (xy 202.954854 -85.436544)
			(xy 202.995003 -85.397835) (xy 203.040361 -85.365384) (xy 203.089961 -85.339883) (xy 203.142745 -85.321876)
			(xy 203.197588 -85.311746) (xy 203.253322 -85.309709) (xy 203.308759 -85.315809) (xy 203.362716 -85.329915)
			(xy 203.414045 -85.351727) (xy 203.461651 -85.380781) (xy 203.504519 -85.416456) (xy 203.541736 -85.457993)
			(xy 203.572509 -85.504506) (xy 203.596181 -85.555003) (xy 203.612249 -85.60841) (xy 203.620369 -85.663586)
			(xy 203.620878 -85.691472) (xy 203.620369 -85.719358) (xy 203.612249 -85.774534) (xy 203.596181 -85.827941)
			(xy 203.572509 -85.878438) (xy 203.541736 -85.924951) (xy 203.504519 -85.966488) (xy 203.461651 -86.002163)
			(xy 203.414045 -86.031217) (xy 203.362716 -86.053029) (xy 203.308759 -86.067135) (xy 203.253322 -86.073235)
			(xy 203.197588 -86.071198) (xy 203.142745 -86.061068) (xy 203.089961 -86.043061) (xy 203.040361 -86.01756)
			(xy 202.995003 -85.985109) (xy 202.954854 -85.9464) (xy 202.920768 -85.902257) (xy 202.893472 -85.853622)
			(xy 202.873549 -85.801531) (xy 202.861423 -85.747094) (xy 202.857352 -85.691472) (xy 148.773536 -85.691472)
			(xy 148.730747 -85.727081) (xy 148.683141 -85.756135) (xy 148.631812 -85.777947) (xy 148.577855 -85.792053)
			(xy 148.522418 -85.798153) (xy 148.466684 -85.796116) (xy 148.411841 -85.785986) (xy 148.359057 -85.767979)
			(xy 148.309457 -85.742478) (xy 148.264099 -85.710027) (xy 148.22395 -85.671318) (xy 148.189864 -85.627175)
			(xy 148.162568 -85.57854) (xy 148.142645 -85.526449) (xy 148.130519 -85.472012) (xy 148.126448 -85.41639)
			(xy 147.242039 -85.41639) (xy 147.24253 -85.443314) (xy 147.242021 -85.4712) (xy 147.233901 -85.526376)
			(xy 147.217833 -85.579783) (xy 147.194161 -85.63028) (xy 147.163388 -85.676793) (xy 147.126171 -85.71833)
			(xy 147.083303 -85.754005) (xy 147.035697 -85.783059) (xy 146.984368 -85.804871) (xy 146.930411 -85.818977)
			(xy 146.874974 -85.825077) (xy 146.81924 -85.82304) (xy 146.764397 -85.81291) (xy 146.711613 -85.794903)
			(xy 146.662013 -85.769402) (xy 146.616655 -85.736951) (xy 146.576506 -85.698242) (xy 146.54242 -85.654099)
			(xy 146.515124 -85.605464) (xy 146.495201 -85.553373) (xy 146.483075 -85.498936) (xy 146.479004 -85.443314)
			(xy 118.293361 -85.443314) (xy 118.292695 -85.448376) (xy 118.277182 -85.506269) (xy 118.254246 -85.561642)
			(xy 118.224279 -85.613548) (xy 118.187792 -85.661098) (xy 118.145412 -85.703478) (xy 118.097862 -85.739965)
			(xy 118.045956 -85.769932) (xy 117.990583 -85.792868) (xy 117.93269 -85.808381) (xy 117.873268 -85.816204)
			(xy 117.813332 -85.816204) (xy 117.75391 -85.808381) (xy 117.696017 -85.792868) (xy 117.640644 -85.769932)
			(xy 117.588738 -85.739965) (xy 117.541188 -85.703478) (xy 117.498808 -85.661098) (xy 117.462321 -85.613548)
			(xy 117.432354 -85.561642) (xy 117.409418 -85.506269) (xy 117.393905 -85.448376) (xy 117.386082 -85.388954)
			(xy 117.385592 -85.358986) (xy 104.494993 -85.358986) (xy 104.518655 -85.409461) (xy 104.534723 -85.462868)
			(xy 104.542843 -85.518044) (xy 104.543352 -85.54593) (xy 104.542843 -85.573816) (xy 104.534723 -85.628992)
			(xy 104.518655 -85.682399) (xy 104.494983 -85.732896) (xy 104.46421 -85.779409) (xy 104.440067 -85.806354)
			(xy 112.269957 -85.806354) (xy 112.269957 -85.751846) (xy 112.277715 -85.697892) (xy 112.293073 -85.645592)
			(xy 112.315717 -85.59601) (xy 112.345188 -85.550156) (xy 112.380885 -85.508963) (xy 112.422082 -85.473269)
			(xy 112.467938 -85.443802) (xy 112.517522 -85.421162) (xy 112.569824 -85.405808) (xy 112.623778 -85.398055)
			(xy 112.651032 -85.397594) (xy 112.678396 -85.398103) (xy 112.732566 -85.405903) (xy 112.785065 -85.421366)
			(xy 112.834814 -85.444174) (xy 112.880791 -85.473861) (xy 112.922053 -85.509815) (xy 112.957751 -85.551297)
			(xy 112.97285 -85.574124) (xy 112.980505 -85.585403) (xy 113.000689 -85.603712) (xy 113.025001 -85.616022)
			(xy 113.051705 -85.621454) (xy 113.078894 -85.619621) (xy 113.104626 -85.610653) (xy 113.127066 -85.595191)
			(xy 113.136172 -85.585046) (xy 113.154392 -85.564206) (xy 113.195801 -85.527471) (xy 113.242087 -85.497111)
			(xy 113.292276 -85.473762) (xy 113.345315 -85.457917) (xy 113.400087 -85.449907) (xy 113.427764 -85.44941)
			(xy 113.45502 -85.449834) (xy 113.508977 -85.457588) (xy 113.561282 -85.472941) (xy 113.610869 -85.495583)
			(xy 113.656729 -85.525051) (xy 113.697928 -85.560747) (xy 113.733627 -85.601942) (xy 113.7631 -85.647799)
			(xy 113.785746 -85.697384) (xy 113.801105 -85.749687) (xy 113.808863 -85.803644) (xy 113.808863 -85.858156)
			(xy 113.801105 -85.912113) (xy 113.785746 -85.964416) (xy 113.7631 -86.014001) (xy 113.733627 -86.059858)
			(xy 113.697928 -86.101053) (xy 113.656729 -86.136749) (xy 113.610869 -86.166217) (xy 113.561282 -86.188859)
			(xy 113.508977 -86.204212) (xy 113.45502 -86.211966) (xy 113.427764 -86.212426) (xy 113.400398 -86.211957)
			(xy 113.346225 -86.204155) (xy 113.293723 -86.188688) (xy 113.243973 -86.165873) (xy 113.197996 -86.13618)
			(xy 113.156736 -86.100218) (xy 113.121042 -86.058727) (xy 113.105946 -86.035896) (xy 113.098295 -86.024613)
			(xy 113.078112 -86.006301) (xy 113.053799 -85.993988) (xy 113.027093 -85.988555) (xy 112.999902 -85.99039)
			(xy 112.974168 -85.999361) (xy 112.951729 -86.014827) (xy 112.942624 -86.024974) (xy 112.924388 -86.0458)
			(xy 112.882984 -86.082539) (xy 112.836703 -86.112904) (xy 112.786516 -86.136255) (xy 112.733479 -86.152103)
			(xy 112.678709 -86.160113) (xy 112.651032 -86.16061) (xy 112.623778 -86.160145) (xy 112.569824 -86.152392)
			(xy 112.517522 -86.137038) (xy 112.467938 -86.114398) (xy 112.422081 -86.084931) (xy 112.380885 -86.049237)
			(xy 112.345188 -86.008044) (xy 112.315717 -85.96219) (xy 112.293073 -85.912608) (xy 112.277715 -85.860308)
			(xy 112.269957 -85.806354) (xy 104.440067 -85.806354) (xy 104.426993 -85.820946) (xy 104.384125 -85.856621)
			(xy 104.336519 -85.885675) (xy 104.28519 -85.907487) (xy 104.231233 -85.921593) (xy 104.175796 -85.927693)
			(xy 104.120062 -85.925656) (xy 104.065219 -85.915526) (xy 104.012435 -85.897519) (xy 103.962835 -85.872018)
			(xy 103.917477 -85.839567) (xy 103.877328 -85.800858) (xy 103.843242 -85.756715) (xy 103.815946 -85.70808)
			(xy 103.796023 -85.655989) (xy 103.783897 -85.601552) (xy 103.779826 -85.54593) (xy 103.43966 -85.54593)
			(xy 103.27767 -85.936836) (xy 103.26403 -85.968558) (xy 103.230386 -86.02886) (xy 103.18993 -86.084821)
			(xy 103.166926 -86.110572) (xy 103.164386 -86.11362) (xy 103.153517 -86.127233) (xy 103.130388 -86.153285)
			(xy 103.118158 -86.16569) (xy 102.357174 -86.926674) (xy 102.336419 -86.946967) (xy 102.291506 -86.983745)
			(xy 102.267512 -87.00008) (xy 102.265988 -87.001096) (xy 102.235843 -87.021973) (xy 102.171376 -87.056919)
			(xy 102.10308 -87.083619) (xy 102.032006 -87.101662) (xy 101.959244 -87.110771) (xy 101.92258 -87.111332)
			(xy 100.85705 -87.111332) (xy 100.846985 -87.111765) (xy 100.828396 -87.119496) (xy 100.820982 -87.126318)
			(xy 100.718112 -87.229188) (xy 100.694354 -87.252331) (xy 100.642512 -87.293705) (xy 100.586363 -87.329015)
			(xy 100.526614 -87.357814) (xy 100.464015 -87.379743) (xy 100.399355 -87.394523) (xy 100.333446 -87.401971)
			(xy 100.300282 -87.402416) (xy 100.264563 -87.401897) (xy 100.193645 -87.393284) (xy 100.124282 -87.376185)
			(xy 100.057487 -87.350849) (xy 99.994232 -87.317647) (xy 99.935441 -87.277063) (xy 99.88197 -87.229687)
			(xy 99.8346 -87.176212) (xy 99.794022 -87.117417) (xy 99.760826 -87.054159) (xy 99.735497 -86.98736)
			(xy 99.718406 -86.917996) (xy 99.709799 -86.847078) (xy 99.709224 -86.811358) (xy 99.709661 -86.779046)
			(xy 99.716719 -86.714809) (xy 99.730745 -86.651726) (xy 99.751573 -86.59055) (xy 99.778953 -86.532014)
			(xy 99.812558 -86.476815) (xy 99.831906 -86.450932) (xy 99.836986 -86.444582) (xy 99.84232 -86.42858)
			(xy 99.84232 -86.330536) (xy 99.836986 -86.314534) (xy 99.831906 -86.308184) (xy 99.812537 -86.282316)
			(xy 99.778934 -86.227113) (xy 99.751556 -86.168573) (xy 99.730729 -86.107395) (xy 99.716703 -86.04431)
			(xy 99.709644 -85.980071) (xy 99.709224 -85.947758) (xy 99.709766 -85.912039) (xy 99.718381 -85.841124)
			(xy 99.735481 -85.771763) (xy 99.760816 -85.70497) (xy 99.794017 -85.641716) (xy 99.8346 -85.582926)
			(xy 99.881973 -85.529456) (xy 99.935445 -85.482085) (xy 99.994237 -85.441505) (xy 100.057492 -85.408306)
			(xy 100.124286 -85.382974) (xy 100.193647 -85.365877) (xy 100.264563 -85.357264) (xy 100.300282 -85.3567)
			(xy 100.333444 -85.35718) (xy 100.399347 -85.364634) (xy 100.464003 -85.379418) (xy 100.526597 -85.401345)
			(xy 100.586344 -85.43014) (xy 100.642493 -85.46544) (xy 100.694338 -85.506804) (xy 100.718112 -85.529928)
			(xy 100.820982 -85.632798) (xy 100.828385 -85.639632) (xy 100.846983 -85.647336) (xy 100.85705 -85.647784)
			(xy 101.539294 -85.647784) (xy 101.549364 -85.647362) (xy 101.567969 -85.639647) (xy 101.575362 -85.632798)
			(xy 101.605588 -85.602572) (xy 101.612261 -85.59516) (xy 101.61984 -85.576733) (xy 101.619828 -85.556808)
			(xy 101.612228 -85.53839) (xy 101.605588 -85.530944) (xy 101.604064 -85.52942) (xy 101.602794 -85.528404)
			(xy 101.582443 -85.510192) (xy 101.546642 -85.46895) (xy 101.517082 -85.423028) (xy 101.494368 -85.373363)
			(xy 101.478963 -85.320968) (xy 101.47118 -85.266912) (xy 101.470714 -85.239606) (xy 101.471179 -85.212331)
			(xy 101.478948 -85.158336) (xy 101.494329 -85.105999) (xy 101.517008 -85.056387) (xy 101.546522 -85.01051)
			(xy 101.58227 -84.969306) (xy 101.623523 -84.933613) (xy 101.669439 -84.904161) (xy 101.719083 -84.881549)
			(xy 101.77144 -84.866238) (xy 101.798374 -84.861908) (xy 101.822504 -84.858606) (xy 101.829616 -84.858098)
			(xy 101.852984 -84.858098) (xy 101.880754 -84.858593) (xy 101.935708 -84.866647) (xy 101.988907 -84.8826)
			(xy 102.014274 -84.893912) (xy 102.018592 -84.895944) (xy 102.040944 -84.901786) (xy 102.051866 -84.899754)
			(xy 102.056692 -84.898992) (xy 102.115112 -84.876894) (xy 102.124691 -84.872722) (xy 102.13965 -84.858167)
			(xy 102.144068 -84.8487) (xy 102.898956 -83.026758) (xy 102.9143 -82.991232) (xy 102.95296 -82.924196)
			(xy 103.000053 -82.862789) (xy 103.026972 -82.834988) (xy 104.75849 -81.10347) (xy 104.783458 -81.079196)
			(xy 104.838129 -81.036063) (xy 104.897493 -80.999658) (xy 104.960726 -80.970487) (xy 105.026952 -80.948954)
			(xy 105.061004 -80.941672) (xy 108.457746 -80.266032) (xy 108.486283 -80.260768) (xy 108.544045 -80.255167)
			(xy 108.573062 -80.254856) (xy 116.575078 -80.254856) (xy 116.613755 -80.255486) (xy 116.690447 -80.265578)
			(xy 116.765166 -80.285592) (xy 116.801138 -80.299814) (xy 116.953214 -80.362806) (xy 187.844936 -80.362806)
			(xy 187.849007 -80.307184) (xy 187.861133 -80.252747) (xy 187.881056 -80.200656) (xy 187.908352 -80.152021)
			(xy 187.942438 -80.107878) (xy 187.982587 -80.069169) (xy 188.027945 -80.036718) (xy 188.077545 -80.011217)
			(xy 188.130329 -79.99321) (xy 188.185172 -79.98308) (xy 188.240906 -79.981043) (xy 188.296343 -79.987143)
			(xy 188.3503 -80.001249) (xy 188.401629 -80.023061) (xy 188.449235 -80.052115) (xy 188.492103 -80.08779)
			(xy 188.52932 -80.129327) (xy 188.560093 -80.17584) (xy 188.583765 -80.226337) (xy 188.599833 -80.279744)
			(xy 188.607953 -80.33492) (xy 188.608462 -80.362806) (xy 188.607953 -80.390692) (xy 188.599833 -80.445868)
			(xy 188.583765 -80.499275) (xy 188.560093 -80.549772) (xy 188.52932 -80.596285) (xy 188.492103 -80.637822)
			(xy 188.449235 -80.673497) (xy 188.401629 -80.702551) (xy 188.3503 -80.724363) (xy 188.296343 -80.738469)
			(xy 188.240906 -80.744569) (xy 188.185172 -80.742532) (xy 188.130329 -80.732402) (xy 188.077545 -80.714395)
			(xy 188.027945 -80.688894) (xy 187.982587 -80.656443) (xy 187.942438 -80.617734) (xy 187.908352 -80.573591)
			(xy 187.881056 -80.524956) (xy 187.861133 -80.472865) (xy 187.849007 -80.418428) (xy 187.844936 -80.362806)
			(xy 116.953214 -80.362806) (xy 118.345204 -80.939386) (xy 118.349891 -80.941184) (xy 118.359743 -80.943102)
			(xy 118.364762 -80.943196) (xy 190.005462 -80.943196) (xy 190.015527 -80.942761) (xy 190.034115 -80.935031)
			(xy 190.04153 -80.92821) (xy 196.15277 -74.81697) (xy 196.176548 -74.79386) (xy 196.228401 -74.752528)
			(xy 196.284556 -74.717261) (xy 196.344306 -74.688502) (xy 196.406899 -74.666614) (xy 196.47155 -74.651871)
			(xy 196.537445 -74.644458) (xy 196.5706 -74.643996) (xy 199.291448 -74.643996) (xy 199.302978 -74.643443)
			(xy 199.323733 -74.633388) (xy 199.331326 -74.624692) (xy 199.387968 -74.552556) (xy 199.393048 -74.529696)
			(xy 199.390254 -74.51852) (xy 199.385259 -74.496507) (xy 199.379912 -74.451683) (xy 199.379586 -74.429112)
			(xy 199.380072 -74.401861) (xy 199.387828 -74.347913) (xy 199.403183 -74.295618) (xy 199.425825 -74.246041)
			(xy 199.455291 -74.200191) (xy 199.490982 -74.159) (xy 199.532173 -74.123309) (xy 199.578023 -74.093843)
			(xy 199.6276 -74.071201) (xy 199.679895 -74.055846) (xy 199.733843 -74.04809) (xy 199.788345 -74.04809)
			(xy 199.842293 -74.055846) (xy 199.894588 -74.071201) (xy 199.944165 -74.093843) (xy 199.990015 -74.123309)
			(xy 200.031206 -74.159) (xy 200.066897 -74.200191) (xy 200.096363 -74.246041) (xy 200.119005 -74.295618)
			(xy 200.13436 -74.347913) (xy 200.142116 -74.401861) (xy 200.142602 -74.429112) (xy 200.142255 -74.451681)
			(xy 200.136909 -74.496503) (xy 200.131934 -74.51852) (xy 200.12914 -74.529696) (xy 200.13422 -74.552556)
			(xy 200.190862 -74.624692) (xy 200.198436 -74.633414) (xy 200.219201 -74.643478) (xy 200.23074 -74.643996)
			(xy 219.596462 -74.643996) (xy 219.606527 -74.643561) (xy 219.625115 -74.635831) (xy 219.63253 -74.62901)
			(xy 221.04477 -73.21677) (xy 221.068548 -73.19366) (xy 221.120401 -73.152328) (xy 221.176556 -73.117061)
			(xy 221.236306 -73.088302) (xy 221.298899 -73.066414) (xy 221.36355 -73.051671) (xy 221.429445 -73.044258)
			(xy 221.4626 -73.043796) (xy 223.8756 -73.043796) (xy 223.908755 -73.04426) (xy 223.974649 -73.05168)
			(xy 224.039298 -73.066426) (xy 224.101892 -73.088314) (xy 224.161643 -73.117069) (xy 224.217801 -73.152328)
			(xy 224.269661 -73.193651) (xy 224.29343 -73.21677) (xy 224.502726 -73.426066) (xy 224.512177 -73.4345)
			(xy 224.536432 -73.441694) (xy 224.548954 -73.439782) (xy 224.632012 -73.422764) (xy 224.644235 -73.419524)
			(xy 224.663562 -73.403266) (xy 224.668842 -73.391776) (xy 224.679854 -73.365571) (xy 224.708503 -73.316479)
			(xy 224.744118 -73.27218) (xy 224.78591 -73.233654) (xy 224.832955 -73.201754) (xy 224.88421 -73.177185)
			(xy 224.938544 -73.16049) (xy 224.994752 -73.15204) (xy 225.023172 -73.151492) (xy 225.050426 -73.151953)
			(xy 225.10438 -73.159707) (xy 225.156681 -73.175061) (xy 225.206265 -73.197702) (xy 225.252122 -73.227169)
			(xy 225.293318 -73.262863) (xy 225.329014 -73.304056) (xy 225.358485 -73.34991) (xy 225.381129 -73.399492)
			(xy 225.396487 -73.451792) (xy 225.404245 -73.505746) (xy 225.40468 -73.533) (xy 225.404262 -73.558645)
			(xy 225.397383 -73.609471) (xy 225.383748 -73.658915) (xy 225.363605 -73.706084) (xy 225.350832 -73.728326)
			(xy 225.343974 -73.740264) (xy 225.34372 -73.767442) (xy 225.394012 -73.856342) (xy 225.398742 -73.863957)
			(xy 225.41242 -73.875528) (xy 225.429249 -73.881671) (xy 225.438208 -73.881996) (xy 240.3094 -73.881996)
			(xy 240.342555 -73.88246) (xy 240.408449 -73.88988) (xy 240.473098 -73.904626) (xy 240.535692 -73.926514)
			(xy 240.595443 -73.955269) (xy 240.651601 -73.990528) (xy 240.703461 -74.031851) (xy 240.72723 -74.05497)
			(xy 240.741708 -74.069448) (xy 240.748695 -74.075936) (xy 240.766126 -74.083627) (xy 240.785163 -74.084406)
			(xy 240.794286 -74.08164) (xy 240.894616 -74.046842) (xy 240.912904 -74.023982) (xy 240.914428 -74.009758)
			(xy 240.918212 -73.982291) (xy 240.932687 -73.928769) (xy 240.954751 -73.877903) (xy 240.983938 -73.830763)
			(xy 241.019636 -73.788339) (xy 241.061094 -73.751524) (xy 241.10744 -73.721091) (xy 241.157699 -73.697681)
			(xy 241.210816 -73.681785) (xy 241.265674 -73.673737) (xy 241.293396 -73.673208) (xy 241.320649 -73.673671)
			(xy 241.374599 -73.681428) (xy 241.426897 -73.696784) (xy 241.476476 -73.719426) (xy 241.522329 -73.748894)
			(xy 241.56352 -73.784588) (xy 241.599213 -73.825781) (xy 241.62868 -73.871634) (xy 241.651321 -73.921215)
			(xy 241.666675 -73.973513) (xy 241.67443 -74.027463) (xy 241.674904 -74.054716) (xy 241.674413 -74.082443)
			(xy 241.666396 -74.137316) (xy 241.650519 -74.190449) (xy 241.627117 -74.240724) (xy 241.596682 -74.287081)
			(xy 241.559857 -74.328543) (xy 241.517416 -74.364237) (xy 241.470255 -74.39341) (xy 241.419368 -74.415448)
			(xy 241.365825 -74.429886) (xy 241.338354 -74.433684) (xy 241.32413 -74.435208) (xy 241.30127 -74.453496)
			(xy 241.266472 -74.553826) (xy 241.263764 -74.562953) (xy 241.264576 -74.581962) (xy 241.272238 -74.599376)
			(xy 241.278664 -74.606404) (xy 242.87607 -76.20381) (xy 242.883468 -76.210655) (xy 242.902067 -76.218378)
			(xy 242.912138 -76.218796) (xy 250.901708 -76.218796) (xy 250.940384 -76.219428) (xy 251.017075 -76.229524)
			(xy 251.091792 -76.249543) (xy 251.127768 -76.263754) (xy 252.0442 -76.64323) (xy 252.048887 -76.645027)
			(xy 252.058739 -76.646944) (xy 252.063758 -76.64704) (xy 252.561344 -76.64704) (xy 252.570996 -76.646024)
			(xy 252.578236 -76.644389) (xy 252.591393 -76.637535) (xy 252.596904 -76.632562) (xy 252.714506 -76.51496)
			(xy 252.719492 -76.50946) (xy 252.726331 -76.496293) (xy 252.727968 -76.489052) (xy 252.728984 -76.4794)
			(xy 252.728984 -71.248778) (xy 252.72882 -71.242768) (xy 252.726001 -71.231083) (xy 252.723396 -71.225664)
			(xy 252.721555 -71.222191) (xy 252.71696 -71.215814) (xy 252.714252 -71.212964) (xy 252.126496 -70.625208)
			(xy 252.122767 -70.621685) (xy 252.114194 -70.616051) (xy 252.109478 -70.614032) (xy 252.100842 -70.610476)
			(xy 234.133136 -70.610476) (xy 234.123071 -70.610041) (xy 234.104486 -70.602307) (xy 234.097068 -70.59549)
			(xy 233.939842 -70.438264) (xy 233.933238 -70.4342) (xy 233.924856 -70.429628) (xy 233.916728 -70.428104)
			(xy 233.888211 -70.422187) (xy 233.833983 -70.400961) (xy 233.809032 -70.38594) (xy 233.803444 -70.38467)
			(xy 233.780838 -70.365874) (xy 233.78033 -70.365366) (xy 233.772156 -70.358665) (xy 233.756646 -70.344303)
			(xy 233.749342 -70.336664) (xy 233.737711 -70.32394) (xy 233.717083 -70.296316) (xy 233.708194 -70.281546)
			(xy 233.70794 -70.281038) (xy 233.707178 -70.279768) (xy 233.707178 -70.279514) (xy 233.700574 -70.267576)
			(xy 233.699812 -70.266814) (xy 233.698796 -70.264528) (xy 233.69397 -70.254368) (xy 233.69397 -70.254114)
			(xy 233.693208 -70.25259) (xy 233.693208 -70.252336) (xy 233.670348 -70.198742) (xy 233.668062 -70.193408)
			(xy 233.666284 -70.18909) (xy 233.66603 -70.188582) (xy 233.652314 -70.15607) (xy 233.650306 -70.151563)
			(xy 233.644812 -70.143369) (xy 233.641392 -70.139814) (xy 233.634534 -70.132956) (xy 233.616754 -70.125082)
			(xy 233.613706 -70.124828) (xy 233.606086 -70.124828) (xy 233.579303 -70.124016) (xy 233.526352 -70.115809)
			(xy 233.475071 -70.100275) (xy 233.426467 -70.077718) (xy 233.381497 -70.048584) (xy 233.341045 -70.013445)
			(xy 233.305907 -69.972992) (xy 233.276775 -69.928021) (xy 233.25422 -69.879416) (xy 233.238688 -69.828134)
			(xy 233.230483 -69.775183) (xy 233.229658 -69.7484) (xy 233.229404 -69.72808) (xy 233.22661 -69.725032)
			(xy 233.208576 -69.706998) (xy 233.201722 -69.699603) (xy 233.193976 -69.681004) (xy 233.19359 -69.67093)
			(xy 233.19359 -69.052186) (xy 233.193082 -69.048884) (xy 233.191629 -69.036745) (xy 233.190104 -69.012342)
			(xy 233.190034 -69.000116) (xy 233.190118 -68.987891) (xy 233.19164 -68.963488) (xy 233.193082 -68.951348)
			(xy 233.19359 -68.948046) (xy 233.19359 -67.879214) (xy 233.193422 -67.873349) (xy 233.190722 -67.861933)
			(xy 233.188256 -67.856608) (xy 233.18724 -67.854576) (xy 233.18597 -67.851528) (xy 233.185208 -67.850004)
			(xy 233.175131 -67.828828) (xy 233.160882 -67.784149) (xy 233.153643 -67.737815) (xy 233.153204 -67.714368)
			(xy 233.153204 -67.67703) (xy 233.15371 -67.652595) (xy 233.161529 -67.604353) (xy 233.176908 -67.557965)
			(xy 233.187748 -67.53606) (xy 233.19105 -67.529964) (xy 233.19359 -67.519296) (xy 233.19359 -67.252088)
			(xy 233.193082 -67.248786) (xy 233.191629 -67.236647) (xy 233.190104 -67.212244) (xy 233.190034 -67.200018)
			(xy 233.190117 -67.187793) (xy 233.19164 -67.16339) (xy 233.193082 -67.15125) (xy 233.19359 -67.147948)
			(xy 233.19359 -66.889122) (xy 233.193082 -66.882772) (xy 233.191304 -66.873628) (xy 233.190583 -66.870133)
			(xy 233.188288 -66.863377) (xy 233.186732 -66.860166) (xy 233.181906 -66.85026) (xy 233.172858 -66.829964)
			(xy 233.160077 -66.787407) (xy 233.153608 -66.743445) (xy 233.153204 -66.721228) (xy 233.153204 -66.477134)
			(xy 233.15371 -66.452699) (xy 233.161528 -66.404457) (xy 233.176907 -66.358069) (xy 233.187748 -66.336164)
			(xy 233.19105 -66.330068) (xy 233.19359 -66.3194) (xy 233.19359 -66.052192) (xy 233.193082 -66.04889)
			(xy 233.191629 -66.036751) (xy 233.190103 -66.012348) (xy 233.190034 -66.000122) (xy 233.19012 -65.987897)
			(xy 233.191649 -65.963495) (xy 233.193082 -65.951354) (xy 233.19359 -65.948052) (xy 233.19359 -65.689226)
			(xy 233.193082 -65.682876) (xy 233.190034 -65.66662) (xy 233.189272 -65.66535) (xy 233.189272 -65.665096)
			(xy 233.184192 -65.654682) (xy 233.173823 -65.632312) (xy 233.15966 -65.585085) (xy 233.155998 -65.560702)
			(xy 233.154739 -65.550843) (xy 233.153339 -65.531016) (xy 233.153204 -65.521078) (xy 233.153204 -65.276984)
			(xy 233.153706 -65.252548) (xy 233.161517 -65.204303) (xy 233.176889 -65.15791) (xy 233.187748 -65.136014)
			(xy 233.19105 -65.129918) (xy 233.19359 -65.11925) (xy 233.19359 -64.852042) (xy 233.193082 -64.84874)
			(xy 233.191631 -64.836601) (xy 233.190108 -64.812198) (xy 233.190034 -64.799972) (xy 233.190119 -64.787747)
			(xy 233.191644 -64.763345) (xy 233.193082 -64.751204) (xy 233.19359 -64.747902) (xy 233.19359 -64.489076)
			(xy 233.193082 -64.482726) (xy 233.190034 -64.46647) (xy 233.189272 -64.4652) (xy 233.189272 -64.464946)
			(xy 233.184192 -64.454532) (xy 233.173819 -64.432163) (xy 233.159649 -64.384937) (xy 233.155998 -64.360552)
			(xy 233.15474 -64.350693) (xy 233.153344 -64.330866) (xy 233.153204 -64.320928) (xy 233.153204 -64.077088)
			(xy 233.153706 -64.052652) (xy 233.161516 -64.004407) (xy 233.176888 -63.958014) (xy 233.187748 -63.936118)
			(xy 233.19105 -63.930022) (xy 233.19359 -63.919354) (xy 233.19359 -63.652146) (xy 233.193082 -63.648844)
			(xy 233.191631 -63.636705) (xy 233.190108 -63.612302) (xy 233.190034 -63.600076) (xy 233.190119 -63.587851)
			(xy 233.191643 -63.563448) (xy 233.193082 -63.551308) (xy 233.19359 -63.548006) (xy 233.19359 -63.28918)
			(xy 233.193082 -63.28283) (xy 233.190034 -63.266574) (xy 233.189272 -63.265304) (xy 233.189272 -63.26505)
			(xy 233.184192 -63.254636) (xy 233.173819 -63.232267) (xy 233.159648 -63.185042) (xy 233.155998 -63.160656)
			(xy 233.15474 -63.150797) (xy 233.153344 -63.13097) (xy 233.153204 -63.121032) (xy 233.153204 -62.876938)
			(xy 233.15371 -62.852503) (xy 233.161527 -62.804261) (xy 233.176906 -62.757872) (xy 233.187748 -62.735968)
			(xy 233.19105 -62.729872) (xy 233.19359 -62.719204) (xy 233.19359 -62.451996) (xy 233.193082 -62.448694)
			(xy 233.191629 -62.436555) (xy 233.190103 -62.412152) (xy 233.190034 -62.399926) (xy 233.19012 -62.387701)
			(xy 233.191648 -62.363299) (xy 233.193082 -62.351158) (xy 233.19359 -62.347856) (xy 233.19359 -61.2521)
			(xy 233.193082 -61.248798) (xy 233.191629 -61.236659) (xy 233.190103 -61.212256) (xy 233.190034 -61.20003)
			(xy 233.19012 -61.187805) (xy 233.191648 -61.163403) (xy 233.193082 -61.151262) (xy 233.19359 -61.14796)
			(xy 233.19359 -59.452002) (xy 233.193082 -59.4487) (xy 233.191629 -59.436561) (xy 233.190102 -59.412158)
			(xy 233.190034 -59.399932) (xy 233.19012 -59.387707) (xy 233.191648 -59.363305) (xy 233.193082 -59.351164)
			(xy 233.19359 -59.347862) (xy 233.19359 -43.033442) (xy 233.193118 -43.023807) (xy 233.18593 -43.00592)
			(xy 233.172688 -42.99191) (xy 233.164126 -42.987468) (xy 233.122216 -42.968164) (xy 233.077258 -42.94759)
			(xy 233.065814 -42.943752) (xy 233.041818 -42.946012) (xy 233.031284 -42.951908) (xy 233.026204 -42.956226)
			(xy 233.005422 -42.973313) (xy 232.95996 -43.002084) (xy 232.910905 -43.024177) (xy 232.85923 -43.039152)
			(xy 232.805963 -43.046712) (xy 232.779062 -43.047158) (xy 232.751809 -43.04667) (xy 232.697858 -43.038908)
			(xy 232.645561 -43.023547) (xy 232.595982 -43.000901) (xy 232.550131 -42.97143) (xy 232.50894 -42.935734)
			(xy 232.473247 -42.894539) (xy 232.443781 -42.848684) (xy 232.42114 -42.799103) (xy 232.405784 -42.746805)
			(xy 232.398028 -42.692853) (xy 232.398028 -42.638347) (xy 232.405784 -42.584395) (xy 232.42114 -42.532097)
			(xy 232.443781 -42.482516) (xy 232.473247 -42.436661) (xy 232.50894 -42.395466) (xy 232.550131 -42.35977)
			(xy 232.595982 -42.330299) (xy 232.645561 -42.307653) (xy 232.697858 -42.292292) (xy 232.751809 -42.28453)
			(xy 232.779062 -42.284142) (xy 232.80596 -42.284608) (xy 232.859222 -42.292177) (xy 232.910891 -42.307156)
			(xy 232.959942 -42.329248) (xy 233.005402 -42.358014) (xy 233.026204 -42.375074) (xy 233.026458 -42.375328)
			(xy 233.032058 -42.379748) (xy 233.045079 -42.385563) (xy 233.052112 -42.386758) (xy 233.059478 -42.387774)
			(xy 233.073448 -42.385742) (xy 233.118152 -42.365168) (xy 233.166158 -42.342816) (xy 233.174208 -42.338215)
			(xy 233.186574 -42.32442) (xy 233.193204 -42.307121) (xy 233.19359 -42.297858) (xy 233.19359 -41.422574)
			(xy 233.193468 -41.417761) (xy 233.191677 -41.408303) (xy 233.190034 -41.403778) (xy 233.186732 -41.39565)
			(xy 233.159808 -41.366186) (xy 233.15168 -41.362122) (xy 233.129582 -41.350692) (xy 233.120946 -41.349422)
			(xy 233.094087 -41.344998) (xy 233.041895 -41.329535) (xy 232.992429 -41.306815) (xy 232.946692 -41.277299)
			(xy 232.905611 -41.241585) (xy 232.87002 -41.200398) (xy 232.84064 -41.154574) (xy 232.818067 -41.10504)
			(xy 232.802759 -41.052803) (xy 232.795027 -40.998921) (xy 232.795026 -40.944486) (xy 232.802758 -40.890604)
			(xy 232.818065 -40.838366) (xy 232.840637 -40.788833) (xy 232.870016 -40.743007) (xy 232.905606 -40.70182)
			(xy 232.946686 -40.666106) (xy 232.992423 -40.636589) (xy 233.041888 -40.613868) (xy 233.09408 -40.598404)
			(xy 233.120946 -40.594026) (xy 233.129582 -40.592756) (xy 233.15168 -40.581326) (xy 233.160062 -40.577008)
			(xy 233.181398 -40.55364) (xy 233.186957 -40.54661) (xy 233.19321 -40.529827) (xy 233.19359 -40.520874)
			(xy 233.19359 -38.432232) (xy 233.193176 -38.422207) (xy 233.185511 -38.403681) (xy 233.171338 -38.389501)
			(xy 233.152815 -38.381828) (xy 233.14279 -38.381432) (xy 231.490012 -38.381432) (xy 231.478582 -38.382702)
			(xy 231.469692 -38.384734) (xy 231.460394 -38.387692) (xy 231.444853 -38.399458) (xy 231.439466 -38.407594)
			(xy 231.411018 -38.460934) (xy 231.411018 -38.461442) (xy 231.397302 -38.487604) (xy 231.394276 -38.493764)
			(xy 231.391308 -38.507159) (xy 231.39146 -38.51402) (xy 231.392222 -38.527736) (xy 231.400096 -38.53942)
			(xy 231.400604 -38.540182) (xy 231.407462 -38.551358) (xy 231.418384 -38.570408) (xy 231.428036 -38.589712)
			(xy 231.430322 -38.594284) (xy 231.437434 -38.611048) (xy 231.439212 -38.616382) (xy 231.439466 -38.617398)
			(xy 231.43972 -38.617652) (xy 231.450828 -38.649669) (xy 231.462835 -38.716359) (xy 231.463596 -38.75024)
			(xy 231.463596 -38.750748) (xy 231.463596 -38.756336) (xy 231.462736 -38.783326) (xy 231.454345 -38.83667)
			(xy 231.438514 -38.888297) (xy 231.415561 -38.937176) (xy 231.385943 -38.982328) (xy 231.350254 -39.022853)
			(xy 231.309205 -39.057938) (xy 231.263619 -39.086884) (xy 231.214406 -39.109111) (xy 231.16255 -39.124175)
			(xy 231.109088 -39.131776) (xy 231.082088 -39.132256) (xy 231.055036 -39.131792) (xy 231.001473 -39.124167)
			(xy 230.949521 -39.109059) (xy 230.900223 -39.086768) (xy 230.854564 -39.057743) (xy 230.81346 -39.022563)
			(xy 230.777732 -38.981934) (xy 230.762556 -38.959536) (xy 230.756714 -38.950392) (xy 230.749094 -38.942518)
			(xy 230.744014 -38.93947) (xy 230.723694 -38.92677) (xy 230.718244 -38.923481) (xy 230.706155 -38.919503)
			(xy 230.699818 -38.918896) (xy 230.62946 -38.914324) (xy 230.623186 -38.91413) (xy 230.61085 -38.916434)
			(xy 230.605076 -38.918896) (xy 230.599657 -38.921556) (xy 230.590158 -38.929001) (xy 230.58628 -38.933628)
			(xy 230.583232 -38.937438) (xy 230.582978 -38.937692) (xy 230.580184 -38.941248) (xy 230.56194 -38.963139)
			(xy 230.520069 -39.001791) (xy 230.472923 -39.033798) (xy 230.421549 -39.058452) (xy 230.367083 -39.075205)
			(xy 230.310734 -39.083685) (xy 230.282242 -39.08425) (xy 230.281988 -39.08425) (xy 230.254736 -39.083763)
			(xy 230.200788 -39.076006) (xy 230.148492 -39.06065) (xy 230.098913 -39.038009) (xy 230.053062 -39.008543)
			(xy 230.011869 -38.972852) (xy 229.976175 -38.931663) (xy 229.946706 -38.885813) (xy 229.92406 -38.836236)
			(xy 229.908701 -38.783942) (xy 229.900939 -38.729994) (xy 229.90048 -38.702742) (xy 229.90048 -38.702488)
			(xy 229.901036 -38.672498) (xy 229.910432 -38.613259) (xy 229.929005 -38.556228) (xy 229.942136 -38.52926)
			(xy 229.94239 -38.528752) (xy 229.945158 -38.522849) (xy 229.947984 -38.510126) (xy 229.947978 -38.503606)
			(xy 229.94747 -38.491414) (xy 229.89413 -38.404038) (xy 229.890828 -38.400482) (xy 229.8832 -38.39196)
			(xy 229.862623 -38.382051) (xy 229.851204 -38.381432) (xy 227.485702 -38.381432) (xy 227.475735 -38.381906)
			(xy 227.457296 -38.38948) (xy 227.449888 -38.396164) (xy 227.165154 -38.680898) (xy 227.16363 -38.682168)
			(xy 227.162106 -38.683692) (xy 227.138228 -38.706621) (xy 227.085568 -38.746737) (xy 227.028145 -38.779675)
			(xy 226.96693 -38.804877) (xy 226.90296 -38.821915) (xy 226.83732 -38.830502) (xy 226.80422 -38.831012)
			(xy 225.18878 -38.831012) (xy 225.155502 -38.830467) (xy 225.089517 -38.82178) (xy 225.025228 -38.804557)
			(xy 224.963737 -38.779092) (xy 224.906095 -38.745821) (xy 224.853287 -38.705312) (xy 224.82937 -38.682168)
			(xy 223.981772 -37.83457) (xy 223.958639 -37.810671) (xy 223.918143 -37.757905) (xy 223.884879 -37.700306)
			(xy 223.859417 -37.638859) (xy 223.842191 -37.574614) (xy 223.833496 -37.508671) (xy 223.832928 -37.475414)
			(xy 223.832928 -37.47389) (xy 223.832928 -37.465762) (xy 223.832928 -37.461698) (xy 223.833182 -37.456618)
			(xy 223.833182 -37.451538) (xy 223.833944 -37.439346) (xy 223.833944 -37.439092) (xy 223.836648 -37.407732)
			(xy 223.84883 -37.345975) (xy 223.868539 -37.286194) (xy 223.895475 -37.229302) (xy 223.929225 -37.176168)
			(xy 223.969273 -37.127605) (xy 224.015008 -37.084355) (xy 224.06573 -37.047079) (xy 224.120665 -37.016347)
			(xy 224.178971 -36.992628) (xy 224.239759 -36.976286) (xy 224.302099 -36.967569) (xy 224.333562 -36.966652)
			(xy 224.342706 -36.966652) (xy 224.374555 -36.967243) (xy 224.437733 -36.975399) (xy 224.46869 -36.982908)
			(xy 224.487843 -36.988101) (xy 224.52535 -37.001071) (xy 224.54362 -37.008816) (xy 224.559859 -37.016028)
			(xy 224.591386 -37.032424) (xy 224.606612 -37.041582) (xy 224.629726 -37.056568) (xy 224.639612 -37.063471)
			(xy 224.658797 -37.078083) (xy 224.66808 -37.085778) (xy 224.700846 -37.11575) (xy 225.179636 -37.59454)
			(xy 225.385376 -37.800534) (xy 225.391556 -37.805973) (xy 225.406454 -37.812957) (xy 225.414586 -37.81425)
			(xy 225.420428 -37.814504) (xy 226.04984 -37.814504) (xy 226.060505 -37.814057) (xy 226.079991 -37.80539)
			(xy 226.087432 -37.79774) (xy 226.137978 -37.741606) (xy 226.1415 -37.737445) (xy 226.146884 -37.727968)
			(xy 226.148646 -37.72281) (xy 226.151948 -37.712142) (xy 226.151186 -37.703506) (xy 226.149154 -37.67836)
			(xy 226.149154 -37.677852) (xy 226.1489 -37.667946) (xy 226.1489 -37.660072) (xy 226.149544 -37.63293)
			(xy 226.157569 -37.579234) (xy 226.173124 -37.527219) (xy 226.195897 -37.477934) (xy 226.225427 -37.432375)
			(xy 226.261117 -37.391463) (xy 226.302247 -37.356024) (xy 226.347986 -37.326774) (xy 226.397409 -37.304303)
			(xy 226.449519 -37.289066) (xy 226.503262 -37.281371) (xy 226.530408 -37.28085) (xy 226.559188 -37.281375)
			(xy 226.616093 -37.290024) (xy 226.671053 -37.307125) (xy 226.72282 -37.332289) (xy 226.770219 -37.364946)
			(xy 226.812173 -37.404353) (xy 226.830382 -37.426646) (xy 226.83216 -37.428932) (xy 226.836986 -37.433758)
			(xy 226.842871 -37.439158) (xy 226.857096 -37.446403) (xy 226.864926 -37.447982) (xy 226.884992 -37.451284)
			(xy 226.889564 -37.451538) (xy 226.953826 -37.451538) (xy 226.957636 -37.451284) (xy 226.961754 -37.450918)
			(xy 226.969795 -37.448998) (xy 226.973638 -37.447474) (xy 226.979226 -37.444934) (xy 226.983036 -37.442648)
			(xy 226.983544 -37.442394) (xy 226.998279 -37.433295) (xy 227.028785 -37.416895) (xy 227.044504 -37.409628)
			(xy 227.055369 -37.404795) (xy 227.077476 -37.396028) (xy 227.0887 -37.392102) (xy 227.090478 -37.391594)
			(xy 227.09505 -37.389562) (xy 227.10013 -37.388038) (xy 227.107496 -37.385752) (xy 227.145702 -37.37509)
			(xy 227.224294 -37.36438) (xy 227.26396 -37.364416) (xy 233.14279 -37.364416) (xy 233.1528 -37.36393)
			(xy 233.171298 -37.356273) (xy 233.185458 -37.34212) (xy 233.193125 -37.323626) (xy 233.19359 -37.313616)
			(xy 233.19359 -30.662626) (xy 233.193336 -30.656784) (xy 233.192066 -30.649672) (xy 233.188256 -30.636718)
			(xy 233.185462 -30.630622) (xy 233.180636 -30.625034) (xy 233.163426 -30.60419) (xy 233.134438 -30.558568)
			(xy 233.112171 -30.509314) (xy 233.097071 -30.457414) (xy 233.08944 -30.403902) (xy 233.088942 -30.376876)
			(xy 233.089424 -30.349401) (xy 233.097318 -30.295022) (xy 233.112939 -30.242339) (xy 233.135964 -30.192446)
			(xy 233.165914 -30.146376) (xy 233.183684 -30.125416) (xy 233.18759 -30.119667) (xy 233.192469 -30.106659)
			(xy 233.193336 -30.099762) (xy 233.19359 -30.09519) (xy 233.19359 -29.900626) (xy 233.193336 -29.894784)
			(xy 233.192066 -29.887672) (xy 233.188256 -29.874718) (xy 233.185462 -29.868622) (xy 233.180636 -29.863034)
			(xy 233.163426 -29.84219) (xy 233.134438 -29.796568) (xy 233.112171 -29.747314) (xy 233.097071 -29.695414)
			(xy 233.08944 -29.641902) (xy 233.088942 -29.614876) (xy 233.089424 -29.587401) (xy 233.097318 -29.533022)
			(xy 233.112939 -29.480339) (xy 233.135964 -29.430446) (xy 233.165914 -29.384376) (xy 233.183684 -29.363416)
			(xy 233.18759 -29.357667) (xy 233.192469 -29.344659) (xy 233.193336 -29.337762) (xy 233.19359 -29.33319)
			(xy 233.19359 -29.087826) (xy 233.193336 -29.081984) (xy 233.192066 -29.074872) (xy 233.188256 -29.061918)
			(xy 233.185462 -29.055822) (xy 233.180636 -29.050234) (xy 233.163426 -29.02939) (xy 233.134438 -28.983768)
			(xy 233.112171 -28.934514) (xy 233.097071 -28.882614) (xy 233.08944 -28.829102) (xy 233.088942 -28.802076)
			(xy 233.089424 -28.774601) (xy 233.097318 -28.720222) (xy 233.112939 -28.667539) (xy 233.135964 -28.617646)
			(xy 233.165914 -28.571576) (xy 233.183684 -28.550616) (xy 233.18759 -28.544867) (xy 233.192469 -28.531859)
			(xy 233.193336 -28.524962) (xy 233.19359 -28.52039) (xy 233.19359 -13.290296) (xy 233.193488 -13.28542)
			(xy 233.191689 -13.275835) (xy 233.190034 -13.271246) (xy 233.186224 -13.262102) (xy 232.309416 -12.385294)
			(xy 232.305687 -12.38177) (xy 232.297115 -12.376135) (xy 232.292398 -12.374118) (xy 232.283762 -12.370562)
			(xy 223.716342 -12.370562) (xy 223.711465 -12.370659) (xy 223.701876 -12.372449) (xy 223.697292 -12.374118)
			(xy 223.688148 -12.377928) (xy 221.794832 -14.271244) (xy 221.79131 -14.274974) (xy 221.78568 -14.283548)
			(xy 221.783656 -14.288262) (xy 221.7801 -14.296898) (xy 221.7801 -21.847048) (xy 222.172782 -21.847048)
			(xy 222.176853 -21.791426) (xy 222.188979 -21.736989) (xy 222.208902 -21.684898) (xy 222.236198 -21.636263)
			(xy 222.270284 -21.59212) (xy 222.310433 -21.553411) (xy 222.355791 -21.52096) (xy 222.405391 -21.495459)
			(xy 222.458175 -21.477452) (xy 222.513018 -21.467322) (xy 222.568752 -21.465285) (xy 222.624189 -21.471385)
			(xy 222.678146 -21.485491) (xy 222.729475 -21.507303) (xy 222.777081 -21.536357) (xy 222.819949 -21.572032)
			(xy 222.857166 -21.613569) (xy 222.887939 -21.660082) (xy 222.911611 -21.710579) (xy 222.927679 -21.763986)
			(xy 222.935799 -21.819162) (xy 222.936308 -21.847048) (xy 222.935799 -21.874934) (xy 222.927679 -21.93011)
			(xy 222.911611 -21.983517) (xy 222.887939 -22.034014) (xy 222.857166 -22.080527) (xy 222.819949 -22.122064)
			(xy 222.777081 -22.157739) (xy 222.729475 -22.186793) (xy 222.678146 -22.208605) (xy 222.624189 -22.222711)
			(xy 222.568752 -22.228811) (xy 222.513018 -22.226774) (xy 222.458175 -22.216644) (xy 222.405391 -22.198637)
			(xy 222.355791 -22.173136) (xy 222.310433 -22.140685) (xy 222.270284 -22.101976) (xy 222.236198 -22.057833)
			(xy 222.208902 -22.009198) (xy 222.188979 -21.957107) (xy 222.176853 -21.90267) (xy 222.172782 -21.847048)
			(xy 221.7801 -21.847048) (xy 221.7801 -23.596092) (xy 221.780218 -23.601047) (xy 221.782135 -23.610769)
			(xy 221.78391 -23.615396) (xy 221.785688 -23.61946) (xy 221.792038 -23.632414) (xy 221.795086 -23.638256)
			(xy 221.807278 -23.65375) (xy 221.811088 -23.657052) (xy 221.831488 -23.675179) (xy 221.867409 -23.716261)
			(xy 221.897118 -23.762038) (xy 221.920007 -23.811577) (xy 221.935613 -23.86387) (xy 221.943616 -23.917851)
			(xy 221.943848 -23.970996) (xy 222.172782 -23.970996) (xy 222.176853 -23.915374) (xy 222.188979 -23.860937)
			(xy 222.208902 -23.808846) (xy 222.236198 -23.760211) (xy 222.270284 -23.716068) (xy 222.310433 -23.677359)
			(xy 222.355791 -23.644908) (xy 222.405391 -23.619407) (xy 222.458175 -23.6014) (xy 222.513018 -23.59127)
			(xy 222.568752 -23.589233) (xy 222.624189 -23.595333) (xy 222.678146 -23.609439) (xy 222.729475 -23.631251)
			(xy 222.777081 -23.660305) (xy 222.819949 -23.69598) (xy 222.857166 -23.737517) (xy 222.887939 -23.78403)
			(xy 222.911611 -23.834527) (xy 222.927679 -23.887934) (xy 222.935799 -23.94311) (xy 222.936308 -23.970996)
			(xy 222.935799 -23.998882) (xy 222.927679 -24.054058) (xy 222.911611 -24.107465) (xy 222.887939 -24.157962)
			(xy 222.857166 -24.204475) (xy 222.819949 -24.246012) (xy 222.777081 -24.281687) (xy 222.729475 -24.310741)
			(xy 222.678146 -24.332553) (xy 222.624189 -24.346659) (xy 222.568752 -24.352759) (xy 222.513018 -24.350722)
			(xy 222.458175 -24.340592) (xy 222.405391 -24.322585) (xy 222.355791 -24.297084) (xy 222.310433 -24.264633)
			(xy 222.270284 -24.225924) (xy 222.236198 -24.181781) (xy 222.208902 -24.133146) (xy 222.188979 -24.081055)
			(xy 222.176853 -24.026618) (xy 222.172782 -23.970996) (xy 221.943848 -23.970996) (xy 221.943854 -23.972423)
			(xy 221.936322 -24.026472) (xy 221.921173 -24.078899) (xy 221.898716 -24.128636) (xy 221.869408 -24.17467)
			(xy 221.833846 -24.216063) (xy 221.813628 -24.234394) (xy 221.812104 -24.235918) (xy 221.806008 -24.242014)
			(xy 221.80296 -24.24557) (xy 221.795086 -24.255476) (xy 221.792038 -24.261318) (xy 221.78518 -24.275796)
			(xy 221.782861 -24.280959) (xy 221.780305 -24.291983) (xy 221.7801 -24.29764) (xy 221.7801 -35.876738)
			(xy 224.917252 -35.876738) (xy 224.921323 -35.821116) (xy 224.933449 -35.766679) (xy 224.953372 -35.714588)
			(xy 224.980668 -35.665953) (xy 225.014754 -35.62181) (xy 225.054903 -35.583101) (xy 225.100261 -35.55065)
			(xy 225.149861 -35.525149) (xy 225.202645 -35.507142) (xy 225.257488 -35.497012) (xy 225.313222 -35.494975)
			(xy 225.368659 -35.501075) (xy 225.422616 -35.515181) (xy 225.473945 -35.536993) (xy 225.521551 -35.566047)
			(xy 225.564419 -35.601722) (xy 225.601636 -35.643259) (xy 225.632409 -35.689772) (xy 225.656081 -35.740269)
			(xy 225.672149 -35.793676) (xy 225.680269 -35.848852) (xy 225.680778 -35.876738) (xy 228.988872 -35.876738)
			(xy 228.992943 -35.821116) (xy 229.005069 -35.766679) (xy 229.024992 -35.714588) (xy 229.052288 -35.665953)
			(xy 229.086374 -35.62181) (xy 229.126523 -35.583101) (xy 229.171881 -35.55065) (xy 229.221481 -35.525149)
			(xy 229.274265 -35.507142) (xy 229.329108 -35.497012) (xy 229.384842 -35.494975) (xy 229.440279 -35.501075)
			(xy 229.494236 -35.515181) (xy 229.545565 -35.536993) (xy 229.593171 -35.566047) (xy 229.636039 -35.601722)
			(xy 229.673256 -35.643259) (xy 229.704029 -35.689772) (xy 229.727701 -35.740269) (xy 229.743769 -35.793676)
			(xy 229.751889 -35.848852) (xy 229.752398 -35.876738) (xy 229.751889 -35.904624) (xy 229.743769 -35.9598)
			(xy 229.727701 -36.013207) (xy 229.704029 -36.063704) (xy 229.673256 -36.110217) (xy 229.636039 -36.151754)
			(xy 229.593171 -36.187429) (xy 229.545565 -36.216483) (xy 229.494236 -36.238295) (xy 229.440279 -36.252401)
			(xy 229.384842 -36.258501) (xy 229.329108 -36.256464) (xy 229.274265 -36.246334) (xy 229.221481 -36.228327)
			(xy 229.171881 -36.202826) (xy 229.126523 -36.170375) (xy 229.086374 -36.131666) (xy 229.052288 -36.087523)
			(xy 229.024992 -36.038888) (xy 229.005069 -35.986797) (xy 228.992943 -35.93236) (xy 228.988872 -35.876738)
			(xy 225.680778 -35.876738) (xy 225.680269 -35.904624) (xy 225.672149 -35.9598) (xy 225.656081 -36.013207)
			(xy 225.632409 -36.063704) (xy 225.601636 -36.110217) (xy 225.564419 -36.151754) (xy 225.521551 -36.187429)
			(xy 225.473945 -36.216483) (xy 225.422616 -36.238295) (xy 225.368659 -36.252401) (xy 225.313222 -36.258501)
			(xy 225.257488 -36.256464) (xy 225.202645 -36.246334) (xy 225.149861 -36.228327) (xy 225.100261 -36.202826)
			(xy 225.054903 -36.170375) (xy 225.014754 -36.131666) (xy 224.980668 -36.087523) (xy 224.953372 -36.038888)
			(xy 224.933449 -35.986797) (xy 224.921323 -35.93236) (xy 224.917252 -35.876738) (xy 221.7801 -35.876738)
			(xy 221.7801 -36.50996) (xy 226.81387 -36.50996) (xy 226.817941 -36.454338) (xy 226.830067 -36.399901)
			(xy 226.84999 -36.34781) (xy 226.877286 -36.299175) (xy 226.911372 -36.255032) (xy 226.951521 -36.216323)
			(xy 226.996879 -36.183872) (xy 227.046479 -36.158371) (xy 227.099263 -36.140364) (xy 227.154106 -36.130234)
			(xy 227.20984 -36.128197) (xy 227.265277 -36.134297) (xy 227.319234 -36.148403) (xy 227.370563 -36.170215)
			(xy 227.418169 -36.199269) (xy 227.461037 -36.234944) (xy 227.498254 -36.276481) (xy 227.529027 -36.322994)
			(xy 227.552699 -36.373491) (xy 227.568767 -36.426898) (xy 227.572692 -36.453572) (xy 230.12857 -36.453572)
			(xy 230.132641 -36.39795) (xy 230.144767 -36.343513) (xy 230.16469 -36.291422) (xy 230.191986 -36.242787)
			(xy 230.226072 -36.198644) (xy 230.266221 -36.159935) (xy 230.311579 -36.127484) (xy 230.361179 -36.101983)
			(xy 230.413963 -36.083976) (xy 230.468806 -36.073846) (xy 230.52454 -36.071809) (xy 230.579977 -36.077909)
			(xy 230.633934 -36.092015) (xy 230.685263 -36.113827) (xy 230.732869 -36.142881) (xy 230.775737 -36.178556)
			(xy 230.812954 -36.220093) (xy 230.843727 -36.266606) (xy 230.867399 -36.317103) (xy 230.883467 -36.37051)
			(xy 230.891587 -36.425686) (xy 230.892096 -36.453572) (xy 230.891587 -36.481458) (xy 230.883467 -36.536634)
			(xy 230.867399 -36.590041) (xy 230.843727 -36.640538) (xy 230.812954 -36.687051) (xy 230.775737 -36.728588)
			(xy 230.732869 -36.764263) (xy 230.685263 -36.793317) (xy 230.633934 -36.815129) (xy 230.579977 -36.829235)
			(xy 230.52454 -36.835335) (xy 230.468806 -36.833298) (xy 230.413963 -36.823168) (xy 230.361179 -36.805161)
			(xy 230.311579 -36.77966) (xy 230.266221 -36.747209) (xy 230.226072 -36.7085) (xy 230.191986 -36.664357)
			(xy 230.16469 -36.615722) (xy 230.144767 -36.563631) (xy 230.132641 -36.509194) (xy 230.12857 -36.453572)
			(xy 227.572692 -36.453572) (xy 227.576887 -36.482074) (xy 227.577396 -36.50996) (xy 227.576887 -36.537846)
			(xy 227.568767 -36.593022) (xy 227.552699 -36.646429) (xy 227.529027 -36.696926) (xy 227.498254 -36.743439)
			(xy 227.461037 -36.784976) (xy 227.418169 -36.820651) (xy 227.370563 -36.849705) (xy 227.319234 -36.871517)
			(xy 227.265277 -36.885623) (xy 227.20984 -36.891723) (xy 227.154106 -36.889686) (xy 227.099263 -36.879556)
			(xy 227.046479 -36.861549) (xy 226.996879 -36.836048) (xy 226.951521 -36.803597) (xy 226.911372 -36.764888)
			(xy 226.877286 -36.720745) (xy 226.84999 -36.67211) (xy 226.830067 -36.620019) (xy 226.817941 -36.565582)
			(xy 226.81387 -36.50996) (xy 221.7801 -36.50996) (xy 221.7801 -40.18153) (xy 228.109524 -40.18153)
			(xy 228.113595 -40.125908) (xy 228.125721 -40.071471) (xy 228.145644 -40.01938) (xy 228.17294 -39.970745)
			(xy 228.207026 -39.926602) (xy 228.247175 -39.887893) (xy 228.292533 -39.855442) (xy 228.342133 -39.829941)
			(xy 228.394917 -39.811934) (xy 228.44976 -39.801804) (xy 228.505494 -39.799767) (xy 228.560931 -39.805867)
			(xy 228.614888 -39.819973) (xy 228.666217 -39.841785) (xy 228.713823 -39.870839) (xy 228.756691 -39.906514)
			(xy 228.793908 -39.948051) (xy 228.809739 -39.97198) (xy 232.0958 -39.97198) (xy 232.099871 -39.916358)
			(xy 232.111997 -39.861921) (xy 232.13192 -39.80983) (xy 232.159216 -39.761195) (xy 232.193302 -39.717052)
			(xy 232.233451 -39.678343) (xy 232.278809 -39.645892) (xy 232.328409 -39.620391) (xy 232.381193 -39.602384)
			(xy 232.436036 -39.592254) (xy 232.49177 -39.590217) (xy 232.547207 -39.596317) (xy 232.601164 -39.610423)
			(xy 232.652493 -39.632235) (xy 232.700099 -39.661289) (xy 232.742967 -39.696964) (xy 232.780184 -39.738501)
			(xy 232.810957 -39.785014) (xy 232.834629 -39.835511) (xy 232.850697 -39.888918) (xy 232.858817 -39.944094)
			(xy 232.859326 -39.97198) (xy 232.858817 -39.999866) (xy 232.850697 -40.055042) (xy 232.834629 -40.108449)
			(xy 232.810957 -40.158946) (xy 232.780184 -40.205459) (xy 232.742967 -40.246996) (xy 232.700099 -40.282671)
			(xy 232.652493 -40.311725) (xy 232.601164 -40.333537) (xy 232.547207 -40.347643) (xy 232.49177 -40.353743)
			(xy 232.436036 -40.351706) (xy 232.381193 -40.341576) (xy 232.328409 -40.323569) (xy 232.278809 -40.298068)
			(xy 232.233451 -40.265617) (xy 232.193302 -40.226908) (xy 232.159216 -40.182765) (xy 232.13192 -40.13413)
			(xy 232.111997 -40.082039) (xy 232.099871 -40.027602) (xy 232.0958 -39.97198) (xy 228.809739 -39.97198)
			(xy 228.824681 -39.994564) (xy 228.848353 -40.045061) (xy 228.864421 -40.098468) (xy 228.872541 -40.153644)
			(xy 228.87305 -40.18153) (xy 228.872541 -40.209416) (xy 228.864421 -40.264592) (xy 228.848353 -40.317999)
			(xy 228.824681 -40.368496) (xy 228.793908 -40.415009) (xy 228.756691 -40.456546) (xy 228.713823 -40.492221)
			(xy 228.666217 -40.521275) (xy 228.614888 -40.543087) (xy 228.560931 -40.557193) (xy 228.505494 -40.563293)
			(xy 228.44976 -40.561256) (xy 228.394917 -40.551126) (xy 228.342133 -40.533119) (xy 228.292533 -40.507618)
			(xy 228.247175 -40.475167) (xy 228.207026 -40.436458) (xy 228.17294 -40.392315) (xy 228.145644 -40.34368)
			(xy 228.125721 -40.291589) (xy 228.113595 -40.237152) (xy 228.109524 -40.18153) (xy 221.7801 -40.18153)
			(xy 221.7801 -42.722292) (xy 221.782132 -42.735246) (xy 221.782894 -42.73804) (xy 221.786946 -42.753364)
			(xy 221.792794 -42.78452) (xy 221.794578 -42.80027) (xy 221.796664 -42.823038) (xy 221.796027 -42.868755)
			(xy 221.793308 -42.891456) (xy 221.791276 -42.904664) (xy 221.789478 -42.914928) (xy 221.784901 -42.935259)
			(xy 221.782132 -42.945304) (xy 221.7801 -42.952162) (xy 221.7801 -43.738292) (xy 221.782132 -43.751246)
			(xy 221.782894 -43.75404) (xy 221.786946 -43.769364) (xy 221.792794 -43.80052) (xy 221.794578 -43.81627)
			(xy 221.796664 -43.839038) (xy 221.796027 -43.884755) (xy 221.793308 -43.907456) (xy 221.791276 -43.920664)
			(xy 221.789478 -43.930928) (xy 221.784901 -43.951259) (xy 221.782132 -43.961304) (xy 221.7801 -43.968162)
			(xy 221.7801 -44.754292) (xy 221.782132 -44.767246) (xy 221.782894 -44.77004) (xy 221.786946 -44.785364)
			(xy 221.792794 -44.81652) (xy 221.794578 -44.83227) (xy 221.796664 -44.855038) (xy 221.796027 -44.900755)
			(xy 221.793308 -44.923456) (xy 221.791276 -44.936664) (xy 221.789478 -44.946928) (xy 221.784901 -44.967259)
			(xy 221.782132 -44.977304) (xy 221.7801 -44.984162) (xy 221.7801 -45.770292) (xy 221.782132 -45.783246)
			(xy 221.782894 -45.78604) (xy 221.786946 -45.801364) (xy 221.792794 -45.83252) (xy 221.794578 -45.84827)
			(xy 221.796664 -45.871038) (xy 221.796027 -45.916755) (xy 221.793308 -45.939456) (xy 221.791276 -45.952664)
			(xy 221.789478 -45.962928) (xy 221.784901 -45.983259) (xy 221.782132 -45.993304) (xy 221.7801 -46.000162)
			(xy 221.7801 -47.247556) (xy 221.78019 -47.2515) (xy 221.781471 -47.259283) (xy 221.78264 -47.26305)
			(xy 221.784926 -47.269908) (xy 221.789498 -47.27956) (xy 221.800509 -47.304226) (xy 221.816239 -47.3559)
			(xy 221.824508 -47.409278) (xy 221.825312 -47.436278) (xy 221.825312 -47.440342) (xy 221.824876 -47.469869)
			(xy 221.816021 -47.528253) (xy 221.798297 -47.584581) (xy 221.785688 -47.611284) (xy 221.785434 -47.611792)
			(xy 221.78264 -47.617634) (xy 221.7801 -47.628302) (xy 221.7801 -48.818292) (xy 221.782132 -48.831246)
			(xy 221.782894 -48.83404) (xy 221.786946 -48.849364) (xy 221.792794 -48.88052) (xy 221.794578 -48.89627)
			(xy 221.796664 -48.919038) (xy 221.796027 -48.964755) (xy 221.793308 -48.987456) (xy 221.791276 -49.000664)
			(xy 221.789478 -49.010928) (xy 221.784901 -49.031259) (xy 221.782132 -49.041304) (xy 221.7801 -49.048162)
			(xy 221.7801 -49.834292) (xy 221.782132 -49.847246) (xy 221.782894 -49.85004) (xy 221.786946 -49.865364)
			(xy 221.792794 -49.89652) (xy 221.794578 -49.91227) (xy 221.796664 -49.935038) (xy 221.796027 -49.980755)
			(xy 221.793308 -50.003456) (xy 221.791276 -50.016664) (xy 221.789478 -50.026928) (xy 221.784901 -50.047259)
			(xy 221.782132 -50.057304) (xy 221.7801 -50.064162) (xy 221.7801 -50.884328) (xy 221.782894 -50.892456)
			(xy 221.793039 -50.923159) (xy 221.804026 -50.986875) (xy 221.804738 -51.019202) (xy 221.804738 -51.01971)
			(xy 221.804016 -51.052037) (xy 221.793036 -51.115753) (xy 221.782894 -51.146456) (xy 221.7801 -51.154584)
			(xy 221.7801 -51.900328) (xy 221.782894 -51.908456) (xy 221.793039 -51.939159) (xy 221.804026 -52.002875)
			(xy 221.804738 -52.035202) (xy 221.804738 -52.03571) (xy 221.804016 -52.068037) (xy 221.793036 -52.131753)
			(xy 221.782894 -52.162456) (xy 221.7801 -52.170584) (xy 221.7801 -52.916328) (xy 221.782894 -52.924456)
			(xy 221.793039 -52.955159) (xy 221.804026 -53.018875) (xy 221.804738 -53.051202) (xy 221.804738 -53.05171)
			(xy 221.804016 -53.084037) (xy 221.793036 -53.147753) (xy 221.782894 -53.178456) (xy 221.7801 -53.186584)
			(xy 221.7801 -53.932328) (xy 221.782894 -53.940456) (xy 221.793039 -53.971159) (xy 221.804026 -54.034875)
			(xy 221.804738 -54.067202) (xy 221.804738 -54.06771) (xy 221.804016 -54.100037) (xy 221.793036 -54.163753)
			(xy 221.782894 -54.194456) (xy 221.7801 -54.202584) (xy 221.7801 -54.948328) (xy 221.782894 -54.956456)
			(xy 221.793039 -54.987159) (xy 221.804026 -55.050875) (xy 221.804738 -55.083202) (xy 221.804738 -55.08371)
			(xy 221.804016 -55.116037) (xy 221.793036 -55.179753) (xy 221.782894 -55.210456) (xy 221.7801 -55.218584)
			(xy 221.7801 -56.218328) (xy 221.782894 -56.226456) (xy 221.793039 -56.257159) (xy 221.804026 -56.320875)
			(xy 221.804738 -56.353202) (xy 221.804738 -56.35371) (xy 221.804016 -56.386037) (xy 221.793036 -56.449753)
			(xy 221.782894 -56.480456) (xy 221.7801 -56.488584) (xy 221.7801 -58.698481) (xy 229.80827 -58.698481)
			(xy 229.80827 -58.601767) (xy 229.816256 -58.505383) (xy 229.832175 -58.409987) (xy 229.855917 -58.316232)
			(xy 229.88732 -58.224758) (xy 229.92617 -58.136189) (xy 229.972201 -58.051131) (xy 230.025099 -57.970165)
			(xy 230.084502 -57.893844) (xy 230.150005 -57.822689) (xy 230.22116 -57.757186) (xy 230.297481 -57.697783)
			(xy 230.378447 -57.644885) (xy 230.463505 -57.598854) (xy 230.552074 -57.560004) (xy 230.643548 -57.528601)
			(xy 230.737303 -57.504859) (xy 230.832699 -57.48894) (xy 230.929083 -57.480954) (xy 231.025797 -57.480954)
			(xy 231.122181 -57.48894) (xy 231.217577 -57.504859) (xy 231.311332 -57.528601) (xy 231.402806 -57.560004)
			(xy 231.491375 -57.598854) (xy 231.576433 -57.644885) (xy 231.657399 -57.697783) (xy 231.73372 -57.757186)
			(xy 231.804875 -57.822689) (xy 231.870378 -57.893844) (xy 231.929781 -57.970165) (xy 231.982679 -58.051131)
			(xy 232.02871 -58.136189) (xy 232.06756 -58.224758) (xy 232.098963 -58.316232) (xy 232.122705 -58.409987)
			(xy 232.138624 -58.505383) (xy 232.14661 -58.601767) (xy 232.14711 -58.650124) (xy 232.14661 -58.698481)
			(xy 232.138624 -58.794865) (xy 232.122705 -58.890261) (xy 232.098963 -58.984016) (xy 232.06756 -59.07549)
			(xy 232.02871 -59.164059) (xy 231.982679 -59.249117) (xy 231.929781 -59.330083) (xy 231.870378 -59.406404)
			(xy 231.804875 -59.477559) (xy 231.73372 -59.543062) (xy 231.657399 -59.602465) (xy 231.576433 -59.655363)
			(xy 231.491375 -59.701394) (xy 231.402806 -59.740244) (xy 231.311332 -59.771647) (xy 231.217577 -59.795389)
			(xy 231.122181 -59.811308) (xy 231.025797 -59.819294) (xy 230.929083 -59.819294) (xy 230.832699 -59.811308)
			(xy 230.737303 -59.795389) (xy 230.643548 -59.771647) (xy 230.552074 -59.740244) (xy 230.463505 -59.701394)
			(xy 230.378447 -59.655363) (xy 230.297481 -59.602465) (xy 230.22116 -59.543062) (xy 230.150005 -59.477559)
			(xy 230.084502 -59.406404) (xy 230.025099 -59.330083) (xy 229.972201 -59.249117) (xy 229.92617 -59.164059)
			(xy 229.88732 -59.07549) (xy 229.855917 -58.984016) (xy 229.832175 -58.890261) (xy 229.816256 -58.794865)
			(xy 229.80827 -58.698481) (xy 221.7801 -58.698481) (xy 221.7801 -60.13196) (xy 226.436428 -60.13196)
			(xy 226.436428 -59.26836) (xy 226.436918 -59.238392) (xy 226.444741 -59.17897) (xy 226.460254 -59.121077)
			(xy 226.48319 -59.065704) (xy 226.513157 -59.013798) (xy 226.549644 -58.966248) (xy 226.592024 -58.923868)
			(xy 226.639574 -58.887381) (xy 226.69148 -58.857414) (xy 226.746853 -58.834478) (xy 226.804746 -58.818965)
			(xy 226.864168 -58.811142) (xy 226.924104 -58.811142) (xy 226.983526 -58.818965) (xy 227.041419 -58.834478)
			(xy 227.096792 -58.857414) (xy 227.148698 -58.887381) (xy 227.196248 -58.923868) (xy 227.238628 -58.966248)
			(xy 227.275115 -59.013798) (xy 227.305082 -59.065704) (xy 227.328018 -59.121077) (xy 227.343531 -59.17897)
			(xy 227.351354 -59.238392) (xy 227.351844 -59.26836) (xy 227.351844 -60.13196) (xy 227.351354 -60.161928)
			(xy 227.343531 -60.22135) (xy 227.328018 -60.279243) (xy 227.305082 -60.334616) (xy 227.275115 -60.386522)
			(xy 227.238628 -60.434072) (xy 227.196248 -60.476452) (xy 227.148698 -60.512939) (xy 227.096792 -60.542906)
			(xy 227.041419 -60.565842) (xy 226.983526 -60.581355) (xy 226.924104 -60.589178) (xy 226.864168 -60.589178)
			(xy 226.804746 -60.581355) (xy 226.746853 -60.565842) (xy 226.69148 -60.542906) (xy 226.639574 -60.512939)
			(xy 226.592024 -60.476452) (xy 226.549644 -60.434072) (xy 226.513157 -60.386522) (xy 226.48319 -60.334616)
			(xy 226.460254 -60.279243) (xy 226.444741 -60.22135) (xy 226.436918 -60.161928) (xy 226.436428 -60.13196)
			(xy 221.7801 -60.13196) (xy 221.7801 -61.773562) (xy 226.029264 -61.773562) (xy 226.033335 -61.71794)
			(xy 226.045461 -61.663503) (xy 226.065384 -61.611412) (xy 226.09268 -61.562777) (xy 226.126766 -61.518634)
			(xy 226.166915 -61.479925) (xy 226.212273 -61.447474) (xy 226.261873 -61.421973) (xy 226.314657 -61.403966)
			(xy 226.3695 -61.393836) (xy 226.425234 -61.391799) (xy 226.480671 -61.397899) (xy 226.534628 -61.412005)
			(xy 226.585957 -61.433817) (xy 226.633563 -61.462871) (xy 226.676431 -61.498546) (xy 226.713648 -61.540083)
			(xy 226.744421 -61.586596) (xy 226.768093 -61.637093) (xy 226.784161 -61.6905) (xy 226.792281 -61.745676)
			(xy 226.79279 -61.773562) (xy 226.792308 -61.799978) (xy 227.210618 -61.799978) (xy 227.214689 -61.744356)
			(xy 227.226815 -61.689919) (xy 227.246738 -61.637828) (xy 227.274034 -61.589193) (xy 227.30812 -61.54505)
			(xy 227.348269 -61.506341) (xy 227.393627 -61.47389) (xy 227.443227 -61.448389) (xy 227.496011 -61.430382)
			(xy 227.550854 -61.420252) (xy 227.606588 -61.418215) (xy 227.662025 -61.424315) (xy 227.715982 -61.438421)
			(xy 227.767311 -61.460233) (xy 227.814917 -61.489287) (xy 227.857785 -61.524962) (xy 227.895002 -61.566499)
			(xy 227.925775 -61.613012) (xy 227.949447 -61.663509) (xy 227.965515 -61.716916) (xy 227.973635 -61.772092)
			(xy 227.974144 -61.799978) (xy 231.00614 -61.799978) (xy 231.010211 -61.744356) (xy 231.022337 -61.689919)
			(xy 231.04226 -61.637828) (xy 231.069556 -61.589193) (xy 231.103642 -61.54505) (xy 231.143791 -61.506341)
			(xy 231.189149 -61.47389) (xy 231.238749 -61.448389) (xy 231.291533 -61.430382) (xy 231.346376 -61.420252)
			(xy 231.40211 -61.418215) (xy 231.457547 -61.424315) (xy 231.511504 -61.438421) (xy 231.562833 -61.460233)
			(xy 231.610439 -61.489287) (xy 231.653307 -61.524962) (xy 231.690524 -61.566499) (xy 231.721297 -61.613012)
			(xy 231.744969 -61.663509) (xy 231.761037 -61.716916) (xy 231.769157 -61.772092) (xy 231.769666 -61.799978)
			(xy 231.769157 -61.827864) (xy 231.761037 -61.88304) (xy 231.744969 -61.936447) (xy 231.721297 -61.986944)
			(xy 231.690524 -62.033457) (xy 231.653307 -62.074994) (xy 231.610439 -62.110669) (xy 231.562833 -62.139723)
			(xy 231.511504 -62.161535) (xy 231.457547 -62.175641) (xy 231.40211 -62.181741) (xy 231.346376 -62.179704)
			(xy 231.291533 -62.169574) (xy 231.238749 -62.151567) (xy 231.189149 -62.126066) (xy 231.143791 -62.093615)
			(xy 231.103642 -62.054906) (xy 231.069556 -62.010763) (xy 231.04226 -61.962128) (xy 231.022337 -61.910037)
			(xy 231.010211 -61.8556) (xy 231.00614 -61.799978) (xy 227.974144 -61.799978) (xy 227.973635 -61.827864)
			(xy 227.965515 -61.88304) (xy 227.949447 -61.936447) (xy 227.925775 -61.986944) (xy 227.895002 -62.033457)
			(xy 227.857785 -62.074994) (xy 227.814917 -62.110669) (xy 227.767311 -62.139723) (xy 227.715982 -62.161535)
			(xy 227.662025 -62.175641) (xy 227.606588 -62.181741) (xy 227.550854 -62.179704) (xy 227.496011 -62.169574)
			(xy 227.443227 -62.151567) (xy 227.393627 -62.126066) (xy 227.348269 -62.093615) (xy 227.30812 -62.054906)
			(xy 227.274034 -62.010763) (xy 227.246738 -61.962128) (xy 227.226815 -61.910037) (xy 227.214689 -61.8556)
			(xy 227.210618 -61.799978) (xy 226.792308 -61.799978) (xy 226.792281 -61.801448) (xy 226.784161 -61.856624)
			(xy 226.768093 -61.910031) (xy 226.744421 -61.960528) (xy 226.713648 -62.007041) (xy 226.676431 -62.048578)
			(xy 226.633563 -62.084253) (xy 226.585957 -62.113307) (xy 226.534628 -62.135119) (xy 226.480671 -62.149225)
			(xy 226.425234 -62.155325) (xy 226.3695 -62.153288) (xy 226.314657 -62.143158) (xy 226.261873 -62.125151)
			(xy 226.212273 -62.09965) (xy 226.166915 -62.067199) (xy 226.126766 -62.02849) (xy 226.09268 -61.984347)
			(xy 226.065384 -61.935712) (xy 226.045461 -61.883621) (xy 226.033335 -61.829184) (xy 226.029264 -61.773562)
			(xy 221.7801 -61.773562) (xy 221.7801 -63.000128) (xy 231.00614 -63.000128) (xy 231.010211 -62.944506)
			(xy 231.022337 -62.890069) (xy 231.04226 -62.837978) (xy 231.069556 -62.789343) (xy 231.103642 -62.7452)
			(xy 231.143791 -62.706491) (xy 231.189149 -62.67404) (xy 231.238749 -62.648539) (xy 231.291533 -62.630532)
			(xy 231.346376 -62.620402) (xy 231.40211 -62.618365) (xy 231.457547 -62.624465) (xy 231.511504 -62.638571)
			(xy 231.562833 -62.660383) (xy 231.610439 -62.689437) (xy 231.653307 -62.725112) (xy 231.690524 -62.766649)
			(xy 231.721297 -62.813162) (xy 231.744969 -62.863659) (xy 231.761037 -62.917066) (xy 231.769157 -62.972242)
			(xy 231.769666 -63.000128) (xy 231.769157 -63.028014) (xy 231.761037 -63.08319) (xy 231.744969 -63.136597)
			(xy 231.721297 -63.187094) (xy 231.690524 -63.233607) (xy 231.653307 -63.275144) (xy 231.610439 -63.310819)
			(xy 231.562833 -63.339873) (xy 231.511504 -63.361685) (xy 231.457547 -63.375791) (xy 231.40211 -63.381891)
			(xy 231.346376 -63.379854) (xy 231.291533 -63.369724) (xy 231.238749 -63.351717) (xy 231.189149 -63.326216)
			(xy 231.143791 -63.293765) (xy 231.103642 -63.255056) (xy 231.069556 -63.210913) (xy 231.04226 -63.162278)
			(xy 231.022337 -63.110187) (xy 231.010211 -63.05575) (xy 231.00614 -63.000128) (xy 221.7801 -63.000128)
			(xy 221.7801 -63.41618) (xy 224.953574 -63.41618) (xy 224.957645 -63.360558) (xy 224.969771 -63.306121)
			(xy 224.989694 -63.25403) (xy 225.01699 -63.205395) (xy 225.051076 -63.161252) (xy 225.091225 -63.122543)
			(xy 225.136583 -63.090092) (xy 225.186183 -63.064591) (xy 225.238967 -63.046584) (xy 225.29381 -63.036454)
			(xy 225.349544 -63.034417) (xy 225.404981 -63.040517) (xy 225.458938 -63.054623) (xy 225.510267 -63.076435)
			(xy 225.557873 -63.105489) (xy 225.600741 -63.141164) (xy 225.637958 -63.182701) (xy 225.668731 -63.229214)
			(xy 225.692403 -63.279711) (xy 225.708471 -63.333118) (xy 225.716591 -63.388294) (xy 225.7171 -63.41618)
			(xy 225.716591 -63.444066) (xy 225.708471 -63.499242) (xy 225.694029 -63.547244) (xy 226.964238 -63.547244)
			(xy 226.968309 -63.491622) (xy 226.980435 -63.437185) (xy 227.000358 -63.385094) (xy 227.027654 -63.336459)
			(xy 227.06174 -63.292316) (xy 227.101889 -63.253607) (xy 227.147247 -63.221156) (xy 227.196847 -63.195655)
			(xy 227.249631 -63.177648) (xy 227.304474 -63.167518) (xy 227.360208 -63.165481) (xy 227.415645 -63.171581)
			(xy 227.469602 -63.185687) (xy 227.520931 -63.207499) (xy 227.568537 -63.236553) (xy 227.611405 -63.272228)
			(xy 227.648622 -63.313765) (xy 227.679395 -63.360278) (xy 227.703067 -63.410775) (xy 227.719135 -63.464182)
			(xy 227.727255 -63.519358) (xy 227.727764 -63.547244) (xy 227.727255 -63.57513) (xy 227.719135 -63.630306)
			(xy 227.703067 -63.683713) (xy 227.679395 -63.73421) (xy 227.648622 -63.780723) (xy 227.611405 -63.82226)
			(xy 227.568537 -63.857935) (xy 227.520931 -63.886989) (xy 227.469602 -63.908801) (xy 227.415645 -63.922907)
			(xy 227.360208 -63.929007) (xy 227.304474 -63.92697) (xy 227.249631 -63.91684) (xy 227.196847 -63.898833)
			(xy 227.147247 -63.873332) (xy 227.101889 -63.840881) (xy 227.06174 -63.802172) (xy 227.027654 -63.758029)
			(xy 227.000358 -63.709394) (xy 226.980435 -63.657303) (xy 226.968309 -63.602866) (xy 226.964238 -63.547244)
			(xy 225.694029 -63.547244) (xy 225.692403 -63.552649) (xy 225.668731 -63.603146) (xy 225.637958 -63.649659)
			(xy 225.600741 -63.691196) (xy 225.557873 -63.726871) (xy 225.510267 -63.755925) (xy 225.458938 -63.777737)
			(xy 225.404981 -63.791843) (xy 225.349544 -63.797943) (xy 225.29381 -63.795906) (xy 225.238967 -63.785776)
			(xy 225.186183 -63.767769) (xy 225.136583 -63.742268) (xy 225.091225 -63.709817) (xy 225.051076 -63.671108)
			(xy 225.01699 -63.626965) (xy 224.989694 -63.57833) (xy 224.969771 -63.526239) (xy 224.957645 -63.471802)
			(xy 224.953574 -63.41618) (xy 221.7801 -63.41618) (xy 221.7801 -64.799972) (xy 224.632518 -64.799972)
			(xy 224.636589 -64.74435) (xy 224.648715 -64.689913) (xy 224.668638 -64.637822) (xy 224.695934 -64.589187)
			(xy 224.73002 -64.545044) (xy 224.770169 -64.506335) (xy 224.815527 -64.473884) (xy 224.865127 -64.448383)
			(xy 224.917911 -64.430376) (xy 224.972754 -64.420246) (xy 225.028488 -64.418209) (xy 225.083925 -64.424309)
			(xy 225.137882 -64.438415) (xy 225.189211 -64.460227) (xy 225.236817 -64.489281) (xy 225.279685 -64.524956)
			(xy 225.316902 -64.566493) (xy 225.347675 -64.613006) (xy 225.371347 -64.663503) (xy 225.387415 -64.71691)
			(xy 225.395535 -64.772086) (xy 225.396044 -64.799972) (xy 225.395535 -64.827858) (xy 225.387415 -64.883034)
			(xy 225.371347 -64.936441) (xy 225.347675 -64.986938) (xy 225.316902 -65.033451) (xy 225.279685 -65.074988)
			(xy 225.236817 -65.110663) (xy 225.189211 -65.139717) (xy 225.137882 -65.161529) (xy 225.083925 -65.175635)
			(xy 225.028488 -65.181735) (xy 224.972754 -65.179698) (xy 224.917911 -65.169568) (xy 224.865127 -65.151561)
			(xy 224.815527 -65.12606) (xy 224.770169 -65.093609) (xy 224.73002 -65.0549) (xy 224.695934 -65.010757)
			(xy 224.668638 -64.962122) (xy 224.648715 -64.910031) (xy 224.636589 -64.855594) (xy 224.632518 -64.799972)
			(xy 221.7801 -64.799972) (xy 221.7801 -65.39992) (xy 227.456998 -65.39992) (xy 227.461069 -65.344298)
			(xy 227.473195 -65.289861) (xy 227.493118 -65.23777) (xy 227.520414 -65.189135) (xy 227.5545 -65.144992)
			(xy 227.594649 -65.106283) (xy 227.640007 -65.073832) (xy 227.689607 -65.048331) (xy 227.742391 -65.030324)
			(xy 227.797234 -65.020194) (xy 227.852968 -65.018157) (xy 227.908405 -65.024257) (xy 227.962362 -65.038363)
			(xy 228.013691 -65.060175) (xy 228.061297 -65.089229) (xy 228.104165 -65.124904) (xy 228.141382 -65.166441)
			(xy 228.172155 -65.212954) (xy 228.195827 -65.263451) (xy 228.211895 -65.316858) (xy 228.220015 -65.372034)
			(xy 228.220524 -65.39992) (xy 228.220015 -65.427806) (xy 228.211895 -65.482982) (xy 228.195827 -65.536389)
			(xy 228.172155 -65.586886) (xy 228.141382 -65.633399) (xy 228.104165 -65.674936) (xy 228.061297 -65.710611)
			(xy 228.013691 -65.739665) (xy 227.962362 -65.761477) (xy 227.908405 -65.775583) (xy 227.852968 -65.781683)
			(xy 227.797234 -65.779646) (xy 227.742391 -65.769516) (xy 227.689607 -65.751509) (xy 227.640007 -65.726008)
			(xy 227.594649 -65.693557) (xy 227.5545 -65.654848) (xy 227.520414 -65.610705) (xy 227.493118 -65.56207)
			(xy 227.473195 -65.509979) (xy 227.461069 -65.455542) (xy 227.456998 -65.39992) (xy 221.7801 -65.39992)
			(xy 221.7801 -66.25844) (xy 226.308918 -66.25844) (xy 226.312989 -66.202818) (xy 226.325115 -66.148381)
			(xy 226.345038 -66.09629) (xy 226.372334 -66.047655) (xy 226.40642 -66.003512) (xy 226.446569 -65.964803)
			(xy 226.491927 -65.932352) (xy 226.541527 -65.906851) (xy 226.594311 -65.888844) (xy 226.649154 -65.878714)
			(xy 226.704888 -65.876677) (xy 226.760325 -65.882777) (xy 226.814282 -65.896883) (xy 226.865611 -65.918695)
			(xy 226.913217 -65.947749) (xy 226.956085 -65.983424) (xy 226.993302 -66.024961) (xy 227.024075 -66.071474)
			(xy 227.047747 -66.121971) (xy 227.063815 -66.175378) (xy 227.071935 -66.230554) (xy 227.072444 -66.25844)
			(xy 227.071935 -66.286326) (xy 227.063815 -66.341502) (xy 227.047747 -66.394909) (xy 227.024075 -66.445406)
			(xy 226.993302 -66.491919) (xy 226.956085 -66.533456) (xy 226.913217 -66.569131) (xy 226.865611 -66.598185)
			(xy 226.861175 -66.60007) (xy 231.00614 -66.60007) (xy 231.010211 -66.544448) (xy 231.022337 -66.490011)
			(xy 231.04226 -66.43792) (xy 231.069556 -66.389285) (xy 231.103642 -66.345142) (xy 231.143791 -66.306433)
			(xy 231.189149 -66.273982) (xy 231.238749 -66.248481) (xy 231.291533 -66.230474) (xy 231.346376 -66.220344)
			(xy 231.40211 -66.218307) (xy 231.457547 -66.224407) (xy 231.511504 -66.238513) (xy 231.562833 -66.260325)
			(xy 231.610439 -66.289379) (xy 231.653307 -66.325054) (xy 231.690524 -66.366591) (xy 231.721297 -66.413104)
			(xy 231.744969 -66.463601) (xy 231.761037 -66.517008) (xy 231.769157 -66.572184) (xy 231.769666 -66.60007)
			(xy 231.769157 -66.627956) (xy 231.761037 -66.683132) (xy 231.744969 -66.736539) (xy 231.721297 -66.787036)
			(xy 231.690524 -66.833549) (xy 231.653307 -66.875086) (xy 231.610439 -66.910761) (xy 231.562833 -66.939815)
			(xy 231.511504 -66.961627) (xy 231.457547 -66.975733) (xy 231.40211 -66.981833) (xy 231.346376 -66.979796)
			(xy 231.291533 -66.969666) (xy 231.238749 -66.951659) (xy 231.189149 -66.926158) (xy 231.143791 -66.893707)
			(xy 231.103642 -66.854998) (xy 231.069556 -66.810855) (xy 231.04226 -66.76222) (xy 231.022337 -66.710129)
			(xy 231.010211 -66.655692) (xy 231.00614 -66.60007) (xy 226.861175 -66.60007) (xy 226.814282 -66.619997)
			(xy 226.760325 -66.634103) (xy 226.704888 -66.640203) (xy 226.649154 -66.638166) (xy 226.594311 -66.628036)
			(xy 226.541527 -66.610029) (xy 226.491927 -66.584528) (xy 226.446569 -66.552077) (xy 226.40642 -66.513368)
			(xy 226.372334 -66.469225) (xy 226.345038 -66.42059) (xy 226.325115 -66.368499) (xy 226.312989 -66.314062)
			(xy 226.308918 -66.25844) (xy 221.7801 -66.25844) (xy 221.7801 -66.722498) (xy 223.929954 -66.722498)
			(xy 223.934025 -66.666876) (xy 223.946151 -66.612439) (xy 223.966074 -66.560348) (xy 223.99337 -66.511713)
			(xy 224.027456 -66.46757) (xy 224.067605 -66.428861) (xy 224.112963 -66.39641) (xy 224.162563 -66.370909)
			(xy 224.215347 -66.352902) (xy 224.27019 -66.342772) (xy 224.325924 -66.340735) (xy 224.381361 -66.346835)
			(xy 224.435318 -66.360941) (xy 224.486647 -66.382753) (xy 224.534253 -66.411807) (xy 224.577121 -66.447482)
			(xy 224.614338 -66.489019) (xy 224.645111 -66.535532) (xy 224.668783 -66.586029) (xy 224.684851 -66.639436)
			(xy 224.692971 -66.694612) (xy 224.69348 -66.722498) (xy 224.692971 -66.750384) (xy 224.684851 -66.80556)
			(xy 224.668783 -66.858967) (xy 224.645111 -66.909464) (xy 224.614338 -66.955977) (xy 224.577121 -66.997514)
			(xy 224.534253 -67.033189) (xy 224.486647 -67.062243) (xy 224.435318 -67.084055) (xy 224.381361 -67.098161)
			(xy 224.325924 -67.104261) (xy 224.27019 -67.102224) (xy 224.215347 -67.092094) (xy 224.162563 -67.074087)
			(xy 224.112963 -67.048586) (xy 224.067605 -67.016135) (xy 224.027456 -66.977426) (xy 223.99337 -66.933283)
			(xy 223.966074 -66.884648) (xy 223.946151 -66.832557) (xy 223.934025 -66.77812) (xy 223.929954 -66.722498)
			(xy 221.7801 -66.722498) (xy 221.7801 -67.369944) (xy 226.983542 -67.369944) (xy 226.987613 -67.314322)
			(xy 226.999739 -67.259885) (xy 227.019662 -67.207794) (xy 227.046958 -67.159159) (xy 227.081044 -67.115016)
			(xy 227.121193 -67.076307) (xy 227.166551 -67.043856) (xy 227.216151 -67.018355) (xy 227.268935 -67.000348)
			(xy 227.323778 -66.990218) (xy 227.379512 -66.988181) (xy 227.434949 -66.994281) (xy 227.488906 -67.008387)
			(xy 227.540235 -67.030199) (xy 227.587841 -67.059253) (xy 227.630709 -67.094928) (xy 227.667926 -67.136465)
			(xy 227.698699 -67.182978) (xy 227.722371 -67.233475) (xy 227.738439 -67.286882) (xy 227.746559 -67.342058)
			(xy 227.747068 -67.369944) (xy 227.746559 -67.39783) (xy 227.738439 -67.453006) (xy 227.722371 -67.506413)
			(xy 227.698699 -67.55691) (xy 227.667926 -67.603423) (xy 227.630709 -67.64496) (xy 227.587841 -67.680635)
			(xy 227.540235 -67.709689) (xy 227.488906 -67.731501) (xy 227.434949 -67.745607) (xy 227.379512 -67.751707)
			(xy 227.323778 -67.74967) (xy 227.268935 -67.73954) (xy 227.216151 -67.721533) (xy 227.166551 -67.696032)
			(xy 227.121193 -67.663581) (xy 227.081044 -67.624872) (xy 227.046958 -67.580729) (xy 227.019662 -67.532094)
			(xy 226.999739 -67.480003) (xy 226.987613 -67.425566) (xy 226.983542 -67.369944) (xy 221.7801 -67.369944)
			(xy 221.7801 -68.317872) (xy 224.787966 -68.317872) (xy 224.792037 -68.26225) (xy 224.804163 -68.207813)
			(xy 224.824086 -68.155722) (xy 224.851382 -68.107087) (xy 224.885468 -68.062944) (xy 224.925617 -68.024235)
			(xy 224.970975 -67.991784) (xy 225.020575 -67.966283) (xy 225.073359 -67.948276) (xy 225.128202 -67.938146)
			(xy 225.183936 -67.936109) (xy 225.239373 -67.942209) (xy 225.29333 -67.956315) (xy 225.344659 -67.978127)
			(xy 225.392265 -68.007181) (xy 225.435133 -68.042856) (xy 225.47235 -68.084393) (xy 225.503123 -68.130906)
			(xy 225.526795 -68.181403) (xy 225.542863 -68.23481) (xy 225.550983 -68.289986) (xy 225.551492 -68.317872)
			(xy 225.550983 -68.345758) (xy 225.542863 -68.400934) (xy 225.526795 -68.454341) (xy 225.503123 -68.504838)
			(xy 225.47235 -68.551351) (xy 225.435133 -68.592888) (xy 225.392265 -68.628563) (xy 225.344659 -68.657617)
			(xy 225.29333 -68.679429) (xy 225.239373 -68.693535) (xy 225.183936 -68.699635) (xy 225.128202 -68.697598)
			(xy 225.073359 -68.687468) (xy 225.020575 -68.669461) (xy 224.970975 -68.64396) (xy 224.925617 -68.611509)
			(xy 224.885468 -68.5728) (xy 224.851382 -68.528657) (xy 224.824086 -68.480022) (xy 224.804163 -68.427931)
			(xy 224.792037 -68.373494) (xy 224.787966 -68.317872) (xy 221.7801 -68.317872) (xy 221.7801 -69.091048)
			(xy 227.444554 -69.091048) (xy 227.445004 -69.064761) (xy 227.452209 -69.012684) (xy 227.466505 -68.962092)
			(xy 227.487618 -68.913945) (xy 227.515148 -68.869156) (xy 227.548573 -68.828577) (xy 227.587259 -68.792976)
			(xy 227.63047 -68.763031) (xy 227.677387 -68.739309) (xy 227.70211 -68.730368) (xy 227.702364 -68.730368)
			(xy 227.712221 -68.726236) (xy 227.727715 -68.711555) (xy 227.732336 -68.70192) (xy 227.765864 -68.621402)
			(xy 227.765102 -68.599812) (xy 227.76053 -68.59016) (xy 227.748579 -68.564207) (xy 227.731715 -68.509616)
			(xy 227.723191 -68.45312) (xy 227.722684 -68.424552) (xy 227.722684 -68.424298) (xy 227.72317 -68.397047)
			(xy 227.730926 -68.343099) (xy 227.746281 -68.290804) (xy 227.768923 -68.241227) (xy 227.798389 -68.195377)
			(xy 227.83408 -68.154186) (xy 227.875271 -68.118495) (xy 227.921121 -68.089029) (xy 227.970698 -68.066387)
			(xy 228.022993 -68.051032) (xy 228.076941 -68.043276) (xy 228.131443 -68.043276) (xy 228.185391 -68.051032)
			(xy 228.237686 -68.066387) (xy 228.287263 -68.089029) (xy 228.333113 -68.118495) (xy 228.374304 -68.154186)
			(xy 228.409995 -68.195377) (xy 228.439461 -68.241227) (xy 228.462103 -68.290804) (xy 228.477458 -68.343099)
			(xy 228.485214 -68.397047) (xy 228.4857 -68.424298) (xy 228.485254 -68.450584) (xy 228.478044 -68.50266)
			(xy 228.463745 -68.553251) (xy 228.44263 -68.601396) (xy 228.415099 -68.646183) (xy 228.381674 -68.686762)
			(xy 228.34299 -68.722363) (xy 228.299781 -68.75231) (xy 228.252866 -68.776035) (xy 228.228144 -68.784978)
			(xy 228.22789 -68.784978) (xy 228.218015 -68.789074) (xy 228.202529 -68.80378) (xy 228.197918 -68.813426)
			(xy 228.16439 -68.893944) (xy 228.165152 -68.915534) (xy 228.169724 -68.925186) (xy 228.181687 -68.951134)
			(xy 228.198548 -69.005727) (xy 228.207066 -69.062225) (xy 228.20757 -69.090794) (xy 228.20757 -69.091048)
			(xy 228.207084 -69.118299) (xy 228.199328 -69.172247) (xy 228.183973 -69.224542) (xy 228.161331 -69.274119)
			(xy 228.131865 -69.319969) (xy 228.096174 -69.36116) (xy 228.054983 -69.396851) (xy 228.009133 -69.426317)
			(xy 227.959556 -69.448959) (xy 227.907261 -69.464314) (xy 227.853313 -69.47207) (xy 227.798811 -69.47207)
			(xy 227.744863 -69.464314) (xy 227.692568 -69.448959) (xy 227.642991 -69.426317) (xy 227.597141 -69.396851)
			(xy 227.55595 -69.36116) (xy 227.520259 -69.319969) (xy 227.490793 -69.274119) (xy 227.468151 -69.224542)
			(xy 227.452796 -69.172247) (xy 227.44504 -69.118299) (xy 227.444554 -69.091048) (xy 221.7801 -69.091048)
			(xy 221.7801 -69.798281) (xy 229.80827 -69.798281) (xy 229.80827 -69.701567) (xy 229.816256 -69.605183)
			(xy 229.832175 -69.509787) (xy 229.855917 -69.416032) (xy 229.88732 -69.324558) (xy 229.92617 -69.235989)
			(xy 229.972201 -69.150931) (xy 230.025099 -69.069965) (xy 230.084502 -68.993644) (xy 230.150005 -68.922489)
			(xy 230.22116 -68.856986) (xy 230.297481 -68.797583) (xy 230.378447 -68.744685) (xy 230.463505 -68.698654)
			(xy 230.552074 -68.659804) (xy 230.643548 -68.628401) (xy 230.737303 -68.604659) (xy 230.832699 -68.58874)
			(xy 230.929083 -68.580754) (xy 231.025797 -68.580754) (xy 231.122181 -68.58874) (xy 231.217577 -68.604659)
			(xy 231.311332 -68.628401) (xy 231.402806 -68.659804) (xy 231.491375 -68.698654) (xy 231.576433 -68.744685)
			(xy 231.657399 -68.797583) (xy 231.73372 -68.856986) (xy 231.804875 -68.922489) (xy 231.870378 -68.993644)
			(xy 231.929781 -69.069965) (xy 231.982679 -69.150931) (xy 232.02871 -69.235989) (xy 232.06756 -69.324558)
			(xy 232.098963 -69.416032) (xy 232.122705 -69.509787) (xy 232.138624 -69.605183) (xy 232.14661 -69.701567)
			(xy 232.14711 -69.749924) (xy 232.14661 -69.798281) (xy 232.138624 -69.894665) (xy 232.122705 -69.990061)
			(xy 232.098963 -70.083816) (xy 232.06756 -70.17529) (xy 232.02871 -70.263859) (xy 231.982679 -70.348917)
			(xy 231.929781 -70.429883) (xy 231.870378 -70.506204) (xy 231.804875 -70.577359) (xy 231.73372 -70.642862)
			(xy 231.657399 -70.702265) (xy 231.576433 -70.755163) (xy 231.491375 -70.801194) (xy 231.402806 -70.840044)
			(xy 231.311332 -70.871447) (xy 231.217577 -70.895189) (xy 231.122181 -70.911108) (xy 231.025797 -70.919094)
			(xy 230.929083 -70.919094) (xy 230.832699 -70.911108) (xy 230.737303 -70.895189) (xy 230.643548 -70.871447)
			(xy 230.552074 -70.840044) (xy 230.463505 -70.801194) (xy 230.378447 -70.755163) (xy 230.297481 -70.702265)
			(xy 230.22116 -70.642862) (xy 230.150005 -70.577359) (xy 230.084502 -70.506204) (xy 230.025099 -70.429883)
			(xy 229.972201 -70.348917) (xy 229.92617 -70.263859) (xy 229.88732 -70.17529) (xy 229.855917 -70.083816)
			(xy 229.832175 -69.990061) (xy 229.816256 -69.894665) (xy 229.80827 -69.798281) (xy 221.7801 -69.798281)
			(xy 221.7801 -70.061074) (xy 221.779663 -70.071138) (xy 221.77193 -70.089723) (xy 221.765114 -70.097142)
			(xy 220.322648 -71.539608) (xy 239.186464 -71.539608) (xy 239.190535 -71.483986) (xy 239.202661 -71.429549)
			(xy 239.222584 -71.377458) (xy 239.24988 -71.328823) (xy 239.283966 -71.28468) (xy 239.324115 -71.245971)
			(xy 239.369473 -71.21352) (xy 239.419073 -71.188019) (xy 239.471857 -71.170012) (xy 239.5267 -71.159882)
			(xy 239.582434 -71.157845) (xy 239.637871 -71.163945) (xy 239.691828 -71.178051) (xy 239.743157 -71.199863)
			(xy 239.790763 -71.228917) (xy 239.833631 -71.264592) (xy 239.870848 -71.306129) (xy 239.901621 -71.352642)
			(xy 239.925293 -71.403139) (xy 239.941361 -71.456546) (xy 239.949481 -71.511722) (xy 239.94999 -71.539608)
			(xy 239.949693 -71.555864) (xy 251.394466 -71.555864) (xy 251.398537 -71.500242) (xy 251.410663 -71.445805)
			(xy 251.430586 -71.393714) (xy 251.457882 -71.345079) (xy 251.491968 -71.300936) (xy 251.532117 -71.262227)
			(xy 251.577475 -71.229776) (xy 251.627075 -71.204275) (xy 251.679859 -71.186268) (xy 251.734702 -71.176138)
			(xy 251.790436 -71.174101) (xy 251.845873 -71.180201) (xy 251.89983 -71.194307) (xy 251.951159 -71.216119)
			(xy 251.998765 -71.245173) (xy 252.041633 -71.280848) (xy 252.07885 -71.322385) (xy 252.109623 -71.368898)
			(xy 252.133295 -71.419395) (xy 252.149363 -71.472802) (xy 252.157483 -71.527978) (xy 252.157992 -71.555864)
			(xy 252.157483 -71.58375) (xy 252.149363 -71.638926) (xy 252.133295 -71.692333) (xy 252.109623 -71.74283)
			(xy 252.07885 -71.789343) (xy 252.041633 -71.83088) (xy 251.998765 -71.866555) (xy 251.951159 -71.895609)
			(xy 251.89983 -71.917421) (xy 251.845873 -71.931527) (xy 251.790436 -71.937627) (xy 251.734702 -71.93559)
			(xy 251.679859 -71.92546) (xy 251.627075 -71.907453) (xy 251.577475 -71.881952) (xy 251.532117 -71.849501)
			(xy 251.491968 -71.810792) (xy 251.457882 -71.766649) (xy 251.430586 -71.718014) (xy 251.410663 -71.665923)
			(xy 251.398537 -71.611486) (xy 251.394466 -71.555864) (xy 239.949693 -71.555864) (xy 239.949481 -71.567494)
			(xy 239.941361 -71.62267) (xy 239.925293 -71.676077) (xy 239.901621 -71.726574) (xy 239.870848 -71.773087)
			(xy 239.833631 -71.814624) (xy 239.790763 -71.850299) (xy 239.743157 -71.879353) (xy 239.691828 -71.901165)
			(xy 239.637871 -71.915271) (xy 239.582434 -71.921371) (xy 239.5267 -71.919334) (xy 239.471857 -71.909204)
			(xy 239.419073 -71.891197) (xy 239.369473 -71.865696) (xy 239.324115 -71.833245) (xy 239.283966 -71.794536)
			(xy 239.24988 -71.750393) (xy 239.222584 -71.701758) (xy 239.202661 -71.649667) (xy 239.190535 -71.59523)
			(xy 239.186464 -71.539608) (xy 220.322648 -71.539608) (xy 220.270324 -71.591932) (xy 220.262925 -71.598774)
			(xy 220.244326 -71.606491) (xy 220.234256 -71.606918) (xy 217.31478 -71.606918) (xy 217.311478 -71.606918)
			(xy 217.302913 -71.607793) (xy 217.287079 -71.61452) (xy 217.274392 -71.626141) (xy 217.270076 -71.633588)
			(xy 217.25509 -71.658988) (xy 217.241882 -71.678038) (xy 217.22519 -71.699915) (xy 217.186553 -71.739096)
			(xy 217.142689 -71.772321) (xy 217.094508 -71.798901) (xy 217.043008 -71.818285) (xy 216.989258 -71.830071)
			(xy 216.934373 -71.834015) (xy 216.87949 -71.830035) (xy 216.825748 -71.818213) (xy 216.774262 -71.798794)
			(xy 216.726098 -71.772182) (xy 216.682256 -71.738928) (xy 216.643645 -71.699722) (xy 216.611066 -71.655376)
			(xy 216.597738 -71.631302) (xy 216.590661 -71.620935) (xy 216.569081 -71.608175) (xy 216.55659 -71.606918)
			(xy 215.63584 -71.606918) (xy 215.631229 -71.607023) (xy 215.622158 -71.608692) (xy 215.617806 -71.61022)
			(xy 215.60917 -71.613522) (xy 215.586564 -71.634604) (xy 215.579706 -71.6407) (xy 215.568022 -71.663052)
			(xy 215.566752 -71.667624) (xy 215.563196 -71.6788) (xy 215.562434 -71.68261) (xy 215.56218 -71.683626)
			(xy 215.561926 -71.685658) (xy 215.561926 -71.686166) (xy 215.556996 -71.712861) (xy 215.540579 -71.764603)
			(xy 215.516994 -71.813496) (xy 215.502236 -71.83628) (xy 215.485923 -71.859618) (xy 215.447501 -71.901639)
			(xy 215.403261 -71.937483) (xy 215.354186 -71.966356) (xy 215.301366 -71.987616) (xy 215.245973 -72.000791)
			(xy 215.189237 -72.005589) (xy 215.132418 -72.001902) (xy 215.076777 -71.989813) (xy 215.023551 -71.96959)
			(xy 214.973921 -71.941682) (xy 214.928989 -71.906709) (xy 214.889752 -71.865448) (xy 214.857083 -71.818814)
			(xy 214.831706 -71.767844) (xy 214.814184 -71.713668) (xy 214.80907 -71.685658) (xy 214.80907 -71.68515)
			(xy 214.808816 -71.684388) (xy 214.8078 -71.6788) (xy 214.804244 -71.667624) (xy 214.802974 -71.663052)
			(xy 214.79129 -71.6407) (xy 214.784432 -71.634604) (xy 214.769192 -71.62038) (xy 214.765524 -71.617111)
			(xy 214.757211 -71.611873) (xy 214.752682 -71.609966) (xy 214.744554 -71.606918) (xy 214.114634 -71.606918)
			(xy 214.106277 -71.607302) (xy 214.09047 -71.612746) (xy 214.083646 -71.617586) (xy 214.060532 -71.635874)
			(xy 214.05756 -71.638372) (xy 214.052335 -71.644116) (xy 214.050118 -71.647304) (xy 214.046054 -71.653146)
			(xy 214.043514 -71.661528) (xy 214.035412 -71.687789) (xy 214.012719 -71.737843) (xy 213.983092 -71.78413)
			(xy 213.947141 -71.825697) (xy 213.905606 -71.861686) (xy 213.882732 -71.87692) (xy 213.85869 -71.89178)
			(xy 213.807169 -71.915017) (xy 213.752784 -71.930404) (xy 213.696726 -71.937602) (xy 213.640218 -71.936457)
			(xy 213.584498 -71.926991) (xy 213.530782 -71.909413) (xy 213.480245 -71.884107) (xy 213.433992 -71.851625)
			(xy 213.393034 -71.812678) (xy 213.358267 -71.768118) (xy 213.33045 -71.718918) (xy 213.310192 -71.666155)
			(xy 213.303612 -71.638668) (xy 213.301326 -71.628762) (xy 213.287356 -71.61784) (xy 213.28053 -71.61284)
			(xy 213.264568 -71.607251) (xy 213.256114 -71.606918) (xy 191.314832 -71.606918) (xy 191.31153 -71.606918)
			(xy 191.30297 -71.6078) (xy 191.287147 -71.614536) (xy 191.274473 -71.62616) (xy 191.270128 -71.633588)
			(xy 191.255142 -71.658988) (xy 191.241934 -71.678038) (xy 191.225242 -71.699911) (xy 191.186606 -71.739085)
			(xy 191.142745 -71.772303) (xy 191.094567 -71.798877) (xy 191.043072 -71.818255) (xy 190.989327 -71.830037)
			(xy 190.934447 -71.833976) (xy 190.879571 -71.829993) (xy 190.825836 -71.818169) (xy 190.774356 -71.798749)
			(xy 190.726199 -71.772137) (xy 190.682364 -71.738883) (xy 190.64376 -71.699679) (xy 190.611187 -71.655336)
			(xy 190.59779 -71.631302) (xy 190.590717 -71.620927) (xy 190.569139 -71.608145) (xy 190.556642 -71.606918)
			(xy 189.635892 -71.606918) (xy 189.63128 -71.607018) (xy 189.622206 -71.608678) (xy 189.617858 -71.61022)
			(xy 189.609222 -71.613522) (xy 189.586616 -71.634604) (xy 189.579758 -71.6407) (xy 189.568074 -71.663052)
			(xy 189.566804 -71.667624) (xy 189.563248 -71.6788) (xy 189.562486 -71.68261) (xy 189.562232 -71.683626)
			(xy 189.561978 -71.685658) (xy 189.561978 -71.686166) (xy 189.557047 -71.71286) (xy 189.540629 -71.764602)
			(xy 189.517041 -71.813493) (xy 189.502288 -71.83628) (xy 189.485975 -71.859614) (xy 189.447555 -71.901627)
			(xy 189.403319 -71.937464) (xy 189.354248 -71.966331) (xy 189.301433 -71.987585) (xy 189.246046 -72.000755)
			(xy 189.189317 -72.005549) (xy 189.132505 -72.00186) (xy 189.076873 -71.98977) (xy 189.023654 -71.969547)
			(xy 188.974031 -71.941641) (xy 188.929106 -71.906671) (xy 188.889875 -71.865414) (xy 188.857211 -71.818785)
			(xy 188.831839 -71.76782) (xy 188.814321 -71.713651) (xy 188.809122 -71.685658) (xy 188.809122 -71.68515)
			(xy 188.808868 -71.684388) (xy 188.807852 -71.6788) (xy 188.804296 -71.667624) (xy 188.803026 -71.663052)
			(xy 188.791342 -71.6407) (xy 188.784484 -71.634604) (xy 188.769244 -71.62038) (xy 188.765577 -71.617107)
			(xy 188.757268 -71.611862) (xy 188.752734 -71.609966) (xy 188.744606 -71.606918) (xy 188.114686 -71.606918)
			(xy 188.106326 -71.607294) (xy 188.090509 -71.612726) (xy 188.083698 -71.617586) (xy 188.060584 -71.635874)
			(xy 188.057605 -71.638367) (xy 188.052368 -71.644102) (xy 188.05017 -71.647304) (xy 188.046106 -71.653146)
			(xy 188.043566 -71.661528) (xy 188.035464 -71.68779) (xy 188.012774 -71.737846) (xy 187.98315 -71.784137)
			(xy 187.947201 -71.825708) (xy 187.905669 -71.861702) (xy 187.882784 -71.87692) (xy 187.858743 -71.891776)
			(xy 187.807225 -71.915006) (xy 187.752845 -71.930385) (xy 187.696792 -71.937578) (xy 187.640291 -71.936428)
			(xy 187.584577 -71.926959) (xy 187.530868 -71.909379) (xy 187.480338 -71.884073) (xy 187.434092 -71.851592)
			(xy 187.393141 -71.812647) (xy 187.358379 -71.76809) (xy 187.330568 -71.718895) (xy 187.310313 -71.666136)
			(xy 187.303664 -71.638668) (xy 187.301378 -71.628762) (xy 187.287408 -71.61784) (xy 187.28058 -71.612846)
			(xy 187.264618 -71.607273) (xy 187.256166 -71.606918) (xy 165.314884 -71.606918) (xy 165.311582 -71.606918)
			(xy 165.303017 -71.607792) (xy 165.287181 -71.614518) (xy 165.274494 -71.626139) (xy 165.27018 -71.633588)
			(xy 165.255194 -71.658988) (xy 165.241986 -71.678038) (xy 165.225294 -71.699915) (xy 165.186657 -71.739096)
			(xy 165.142793 -71.772322) (xy 165.094611 -71.798903) (xy 165.043111 -71.818287) (xy 164.989361 -71.830074)
			(xy 164.934475 -71.834018) (xy 164.879592 -71.830038) (xy 164.82585 -71.818216) (xy 164.774362 -71.798798)
			(xy 164.726198 -71.772186) (xy 164.682356 -71.738932) (xy 164.643744 -71.699725) (xy 164.611164 -71.655379)
			(xy 164.597842 -71.631302) (xy 164.590766 -71.620935) (xy 164.569186 -71.608173) (xy 164.556694 -71.606918)
			(xy 163.635944 -71.606918) (xy 163.631333 -71.607023) (xy 163.622262 -71.608691) (xy 163.61791 -71.61022)
			(xy 163.609274 -71.613522) (xy 163.586668 -71.634604) (xy 163.57981 -71.6407) (xy 163.564316 -71.670926)
			(xy 163.563046 -71.679308) (xy 163.558591 -71.70612) (xy 163.543083 -71.758211) (xy 163.52034 -71.807574)
			(xy 163.490822 -71.85321) (xy 163.455127 -71.894196) (xy 163.413978 -71.929701) (xy 163.368206 -71.959009)
			(xy 163.318739 -71.981525) (xy 163.266577 -71.996793) (xy 163.212777 -72.004506) (xy 163.158427 -72.004506)
			(xy 163.104627 -71.996793) (xy 163.052465 -71.981525) (xy 163.002998 -71.959009) (xy 162.957226 -71.929701)
			(xy 162.916077 -71.894196) (xy 162.880382 -71.85321) (xy 162.850864 -71.807574) (xy 162.828121 -71.758211)
			(xy 162.812613 -71.70612) (xy 162.808158 -71.679308) (xy 162.806888 -71.670926) (xy 162.791394 -71.6407)
			(xy 162.784536 -71.634604) (xy 162.769296 -71.62038) (xy 162.765628 -71.61711) (xy 162.757315 -71.611872)
			(xy 162.752786 -71.609966) (xy 162.744658 -71.606918) (xy 162.114738 -71.606918) (xy 162.106381 -71.607302)
			(xy 162.090573 -71.612745) (xy 162.08375 -71.617586) (xy 162.060636 -71.635874) (xy 162.057659 -71.638369)
			(xy 162.052426 -71.644107) (xy 162.050222 -71.647304) (xy 162.046158 -71.653146) (xy 162.043618 -71.661528)
			(xy 162.035516 -71.687789) (xy 162.012824 -71.737843) (xy 161.983197 -71.784131) (xy 161.947245 -71.825698)
			(xy 161.905711 -71.861687) (xy 161.882836 -71.87692) (xy 161.858794 -71.891781) (xy 161.807272 -71.915018)
			(xy 161.752888 -71.930405) (xy 161.696828 -71.937604) (xy 161.640321 -71.936459) (xy 161.584599 -71.926994)
			(xy 161.530883 -71.909416) (xy 161.480345 -71.88411) (xy 161.434092 -71.851628) (xy 161.393134 -71.812681)
			(xy 161.358366 -71.76812) (xy 161.330549 -71.71892) (xy 161.31029 -71.666156) (xy 161.303716 -71.638668)
			(xy 161.30143 -71.628762) (xy 161.28746 -71.61784) (xy 161.280634 -71.612839) (xy 161.264673 -71.607249)
			(xy 161.256218 -71.606918) (xy 139.314936 -71.606918) (xy 139.311634 -71.606918) (xy 139.303074 -71.607799)
			(xy 139.28725 -71.614535) (xy 139.274575 -71.626159) (xy 139.270232 -71.633588) (xy 139.255246 -71.658988)
			(xy 139.242038 -71.678038) (xy 139.225346 -71.699912) (xy 139.18671 -71.739086) (xy 139.142849 -71.772305)
			(xy 139.09467 -71.798879) (xy 139.043175 -71.818258) (xy 138.989429 -71.83004) (xy 138.934549 -71.83398)
			(xy 138.879672 -71.829996) (xy 138.825937 -71.818172) (xy 138.774456 -71.798753) (xy 138.726299 -71.77214)
			(xy 138.682463 -71.738887) (xy 138.643858 -71.699682) (xy 138.611285 -71.655339) (xy 138.597894 -71.631302)
			(xy 138.590822 -71.620926) (xy 138.569243 -71.608142) (xy 138.556746 -71.606918) (xy 137.635996 -71.606918)
			(xy 137.631384 -71.607018) (xy 137.62231 -71.608677) (xy 137.617962 -71.61022) (xy 137.609326 -71.613522)
			(xy 137.58672 -71.634604) (xy 137.579862 -71.6407) (xy 137.564368 -71.670926) (xy 137.563098 -71.679308)
			(xy 137.558643 -71.70612) (xy 137.543135 -71.758211) (xy 137.520392 -71.807574) (xy 137.490874 -71.85321)
			(xy 137.455179 -71.894196) (xy 137.41403 -71.929701) (xy 137.368258 -71.959009) (xy 137.318791 -71.981525)
			(xy 137.266629 -71.996793) (xy 137.212829 -72.004506) (xy 137.158479 -72.004506) (xy 137.104679 -71.996793)
			(xy 137.052517 -71.981525) (xy 137.00305 -71.959009) (xy 136.957278 -71.929701) (xy 136.916129 -71.894196)
			(xy 136.880434 -71.85321) (xy 136.850916 -71.807574) (xy 136.828173 -71.758211) (xy 136.812665 -71.70612)
			(xy 136.80821 -71.679308) (xy 136.80694 -71.670926) (xy 136.791446 -71.6407) (xy 136.784588 -71.634604)
			(xy 136.769348 -71.62038) (xy 136.765682 -71.617107) (xy 136.757372 -71.611861) (xy 136.752838 -71.609966)
			(xy 136.74471 -71.606918) (xy 136.11479 -71.606918) (xy 136.10643 -71.607294) (xy 136.090612 -71.612724)
			(xy 136.083802 -71.617586) (xy 136.060688 -71.635874) (xy 136.057713 -71.63837) (xy 136.052484 -71.644111)
			(xy 136.050274 -71.647304) (xy 136.04621 -71.653146) (xy 136.04367 -71.661528) (xy 136.035569 -71.68779)
			(xy 136.012879 -71.737847) (xy 135.983254 -71.784137) (xy 135.947305 -71.825709) (xy 135.905774 -71.861703)
			(xy 135.882888 -71.87692) (xy 135.858847 -71.891777) (xy 135.807329 -71.915007) (xy 135.752948 -71.930387)
			(xy 135.696895 -71.93758) (xy 135.640393 -71.93643) (xy 135.584679 -71.926962) (xy 135.530969 -71.909382)
			(xy 135.480439 -71.884075) (xy 135.434192 -71.851595) (xy 135.39324 -71.81265) (xy 135.358478 -71.768092)
			(xy 135.330666 -71.718897) (xy 135.310412 -71.666138) (xy 135.303768 -71.638668) (xy 135.301482 -71.628762)
			(xy 135.287512 -71.61784) (xy 135.280684 -71.612846) (xy 135.264722 -71.607271) (xy 135.25627 -71.606918)
			(xy 122.968258 -71.606918) (xy 122.962248 -71.607084) (xy 122.950565 -71.609908) (xy 122.945144 -71.612506)
			(xy 122.941672 -71.614348) (xy 122.935296 -71.618945) (xy 122.932444 -71.62165) (xy 122.928634 -71.62546)
			(xy 122.878596 -71.686674) (xy 122.873595 -71.6935) (xy 122.86801 -71.709462) (xy 122.867674 -71.717916)
			(xy 122.867674 -71.72579) (xy 122.876727 -71.774292) (xy 122.893238 -71.871581) (xy 122.900694 -71.920354)
			(xy 122.902472 -71.932546) (xy 122.916339 -72.029572) (xy 122.937725 -72.224423) (xy 122.943149 -72.299576)
			(xy 224.676968 -72.299576) (xy 224.681039 -72.243954) (xy 224.693165 -72.189517) (xy 224.713088 -72.137426)
			(xy 224.740384 -72.088791) (xy 224.77447 -72.044648) (xy 224.814619 -72.005939) (xy 224.859977 -71.973488)
			(xy 224.909577 -71.947987) (xy 224.962361 -71.92998) (xy 225.017204 -71.91985) (xy 225.072938 -71.917813)
			(xy 225.128375 -71.923913) (xy 225.182332 -71.938019) (xy 225.233661 -71.959831) (xy 225.281267 -71.988885)
			(xy 225.324135 -72.02456) (xy 225.361352 -72.066097) (xy 225.392125 -72.11261) (xy 225.415797 -72.163107)
			(xy 225.431865 -72.216514) (xy 225.439985 -72.27169) (xy 225.440494 -72.299576) (xy 225.439985 -72.327462)
			(xy 225.431865 -72.382638) (xy 225.415797 -72.436045) (xy 225.392125 -72.486542) (xy 225.361352 -72.533055)
			(xy 225.324135 -72.574592) (xy 225.281267 -72.610267) (xy 225.233661 -72.639321) (xy 225.182332 -72.661133)
			(xy 225.128375 -72.675239) (xy 225.072938 -72.681339) (xy 225.017204 -72.679302) (xy 224.962361 -72.669172)
			(xy 224.909577 -72.651165) (xy 224.859977 -72.625664) (xy 224.814619 -72.593213) (xy 224.77447 -72.554504)
			(xy 224.740384 -72.510361) (xy 224.713088 -72.461726) (xy 224.693165 -72.409635) (xy 224.681039 -72.355198)
			(xy 224.676968 -72.299576) (xy 122.943149 -72.299576) (xy 122.951836 -72.419936) (xy 122.958654 -72.615839)
			(xy 122.95886 -72.71385) (xy 122.95886 -72.719438) (xy 122.958606 -72.755252) (xy 122.958606 -72.75703)
			(xy 122.956957 -72.861555) (xy 122.9497 -73.004934) (xy 200.349102 -73.004934) (xy 200.353173 -72.949312)
			(xy 200.365299 -72.894875) (xy 200.385222 -72.842784) (xy 200.412518 -72.794149) (xy 200.446604 -72.750006)
			(xy 200.486753 -72.711297) (xy 200.532111 -72.678846) (xy 200.581711 -72.653345) (xy 200.634495 -72.635338)
			(xy 200.689338 -72.625208) (xy 200.745072 -72.623171) (xy 200.800509 -72.629271) (xy 200.854466 -72.643377)
			(xy 200.905795 -72.665189) (xy 200.953401 -72.694243) (xy 200.996269 -72.729918) (xy 201.033486 -72.771455)
			(xy 201.064259 -72.817968) (xy 201.087931 -72.868465) (xy 201.103999 -72.921872) (xy 201.112119 -72.977048)
			(xy 201.112628 -73.004934) (xy 201.112119 -73.03282) (xy 201.103999 -73.087996) (xy 201.087931 -73.141403)
			(xy 201.064259 -73.1919) (xy 201.033486 -73.238413) (xy 200.996269 -73.27995) (xy 200.953401 -73.315625)
			(xy 200.905795 -73.344679) (xy 200.854466 -73.366491) (xy 200.800509 -73.380597) (xy 200.745072 -73.386697)
			(xy 200.689338 -73.38466) (xy 200.634495 -73.37453) (xy 200.581711 -73.356523) (xy 200.532111 -73.331022)
			(xy 200.486753 -73.298571) (xy 200.446604 -73.259862) (xy 200.412518 -73.215719) (xy 200.385222 -73.167084)
			(xy 200.365299 -73.114993) (xy 200.353173 -73.060556) (xy 200.349102 -73.004934) (xy 122.9497 -73.004934)
			(xy 122.946389 -73.070361) (xy 122.92753 -73.278582) (xy 122.900408 -73.485889) (xy 122.865068 -73.691953)
			(xy 122.821565 -73.896451) (xy 122.769967 -74.099057) (xy 122.710357 -74.299452) (xy 122.642829 -74.49732)
			(xy 122.567488 -74.692347) (xy 122.484455 -74.884225) (xy 122.39386 -75.07265) (xy 122.295847 -75.257326)
			(xy 122.190571 -75.43796) (xy 122.078198 -75.614266) (xy 121.958906 -75.785967) (xy 121.832883 -75.952789)
			(xy 121.700328 -76.114471) (xy 121.561452 -76.270756) (xy 121.416473 -76.421397) (xy 121.341388 -76.494132)
			(xy 121.341388 -76.494386) (xy 121.298432 -76.535315) (xy 121.210921 -76.61546) (xy 121.166382 -76.65466)
			(xy 121.16435 -76.656438) (xy 121.162064 -76.65847) (xy 121.16181 -76.658724) (xy 121.159016 -76.66101)
			(xy 121.152412 -76.666852) (xy 121.14276 -76.688442) (xy 121.143268 -76.698348) (xy 121.147586 -76.771246)
			(xy 121.148165 -76.775265) (xy 121.150457 -76.783054) (xy 121.152158 -76.78674) (xy 121.170446 -76.820268)
			(xy 121.17832 -76.825602) (xy 121.178574 -76.825856) (xy 121.181622 -76.828142) (xy 121.202876 -76.845085)
			(xy 121.240474 -76.884335) (xy 121.271658 -76.928853) (xy 121.295699 -76.977599) (xy 121.312038 -77.029438)
			(xy 121.320294 -77.08316) (xy 121.320814 -77.110336) (xy 121.320262 -77.138317) (xy 121.311503 -77.193591)
			(xy 121.294205 -77.246813) (xy 121.268795 -77.296675) (xy 121.235899 -77.341948) (xy 121.196325 -77.381518)
			(xy 121.151049 -77.414411) (xy 121.101185 -77.439817) (xy 121.047961 -77.45711) (xy 120.992687 -77.465865)
			(xy 120.964706 -77.466444) (xy 120.93679 -77.465902) (xy 120.88164 -77.457198) (xy 120.828522 -77.440001)
			(xy 120.778734 -77.414733) (xy 120.733496 -77.382011) (xy 120.693912 -77.342636) (xy 120.660952 -77.29757)
			(xy 120.635422 -77.247917) (xy 120.626124 -77.221588) (xy 120.624092 -77.215238) (xy 120.620536 -77.20965)
			(xy 120.612916 -77.200252) (xy 120.60301 -77.191108) (xy 120.599573 -77.187957) (xy 120.591778 -77.182839)
			(xy 120.587516 -77.180948) (xy 120.579642 -77.177646) (xy 120.56999 -77.177138) (xy 120.566031 -77.176902)
			(xy 120.558248 -77.175377) (xy 120.554496 -77.17409) (xy 120.540526 -77.16901) (xy 120.536519 -77.167727)
			(xy 120.528222 -77.166325) (xy 120.524016 -77.166216) (xy 120.49125 -77.166216) (xy 120.485384 -77.16638)
			(xy 120.473964 -77.169073) (xy 120.468644 -77.17155) (xy 120.464072 -77.173836) (xy 120.46204 -77.175106)
			(xy 120.367091 -77.233006) (xy 120.173035 -77.34169) (xy 119.974556 -77.442068) (xy 119.873522 -77.488542)
			(xy 119.773676 -77.533239) (xy 119.759221 -77.539088) (xy 182.075834 -77.539088) (xy 182.079905 -77.483466)
			(xy 182.092031 -77.429029) (xy 182.111954 -77.376938) (xy 182.13925 -77.328303) (xy 182.173336 -77.28416)
			(xy 182.213485 -77.245451) (xy 182.258843 -77.213) (xy 182.308443 -77.187499) (xy 182.361227 -77.169492)
			(xy 182.41607 -77.159362) (xy 182.471804 -77.157325) (xy 182.527241 -77.163425) (xy 182.581198 -77.177531)
			(xy 182.632527 -77.199343) (xy 182.680133 -77.228397) (xy 182.723001 -77.264072) (xy 182.760218 -77.305609)
			(xy 182.790991 -77.352122) (xy 182.814663 -77.402619) (xy 182.830731 -77.456026) (xy 182.838851 -77.511202)
			(xy 182.83936 -77.539088) (xy 182.838851 -77.566974) (xy 182.830731 -77.62215) (xy 182.814663 -77.675557)
			(xy 182.790991 -77.726054) (xy 182.760218 -77.772567) (xy 182.723001 -77.814104) (xy 182.680133 -77.849779)
			(xy 182.632527 -77.878833) (xy 182.581198 -77.900645) (xy 182.527241 -77.914751) (xy 182.471804 -77.920851)
			(xy 182.41607 -77.918814) (xy 182.361227 -77.908684) (xy 182.308443 -77.890677) (xy 182.258843 -77.865176)
			(xy 182.213485 -77.832725) (xy 182.173336 -77.794016) (xy 182.13925 -77.749873) (xy 182.111954 -77.701238)
			(xy 182.092031 -77.649147) (xy 182.079905 -77.59471) (xy 182.075834 -77.539088) (xy 119.759221 -77.539088)
			(xy 119.570866 -77.615304) (xy 119.364818 -77.688863) (xy 119.155888 -77.753788) (xy 119.050308 -77.78242)
			(xy 118.955937 -77.807021) (xy 118.765698 -77.85007) (xy 118.573994 -77.886037) (xy 118.381089 -77.914874)
			(xy 118.187248 -77.936539) (xy 117.992736 -77.951005) (xy 117.797822 -77.95825) (xy 117.700298 -77.958696)
			(xy 117.597873 -77.958199) (xy 117.393179 -77.950222) (xy 117.18895 -77.934279) (xy 116.985498 -77.910395)
			(xy 116.783129 -77.878606) (xy 116.582153 -77.838961) (xy 116.382872 -77.791519) (xy 116.18559 -77.736353)
			(xy 115.990607 -77.673545) (xy 115.798217 -77.603193) (xy 115.608712 -77.525401) (xy 115.422381 -77.440289)
			(xy 115.239506 -77.347985) (xy 115.060364 -77.248629) (xy 114.885227 -77.142372) (xy 114.71436 -77.029376)
			(xy 114.548024 -76.909812) (xy 114.38647 -76.78386) (xy 114.229944 -76.651713) (xy 114.078682 -76.513571)
			(xy 113.932915 -76.369642) (xy 113.792863 -76.220147) (xy 113.658739 -76.065311) (xy 113.594388 -75.985624)
			(xy 113.592102 -75.982576) (xy 113.591848 -75.982322) (xy 113.591594 -75.981814) (xy 113.588292 -75.97775)
			(xy 113.5761 -75.96251) (xy 113.51895 -75.88885) (xy 113.514124 -75.8825) (xy 113.481866 -75.839574)
			(xy 113.421474 -75.757613) (xy 113.306315 -75.589694) (xy 113.197739 -75.417444) (xy 113.09591 -75.241123)
			(xy 113.00098 -75.060993) (xy 112.956594 -74.96937) (xy 112.911051 -74.872926) (xy 112.826881 -74.676925)
			(xy 112.750727 -74.477673) (xy 112.682714 -74.275496) (xy 112.622955 -74.070728) (xy 112.571548 -73.863706)
			(xy 112.528578 -73.654769) (xy 112.494114 -73.444262) (xy 112.468214 -73.23253) (xy 112.450921 -73.019923)
			(xy 112.442263 -72.806789) (xy 112.441736 -72.700134) (xy 112.442223 -72.598803) (xy 112.45003 -72.396292)
			(xy 112.465634 -72.194232) (xy 112.489012 -71.992924) (xy 112.520128 -71.792665) (xy 112.558937 -71.593754)
			(xy 112.605382 -71.396486) (xy 112.659392 -71.201154) (xy 112.720889 -71.008048) (xy 112.789779 -70.817455)
			(xy 112.865963 -70.629658) (xy 112.949325 -70.444935) (xy 113.039743 -70.263562) (xy 113.137081 -70.085807)
			(xy 113.241196 -69.911934) (xy 113.351934 -69.742202) (xy 113.469128 -69.576863) (xy 113.592606 -69.416161)
			(xy 113.722184 -69.260337) (xy 113.85767 -69.109621) (xy 113.998862 -68.964237) (xy 114.14555 -68.824401)
			(xy 114.297518 -68.69032) (xy 114.454538 -68.562194) (xy 114.616379 -68.440214) (xy 114.7828 -68.324559)
			(xy 114.953552 -68.215403) (xy 115.128384 -68.112906) (xy 115.307035 -68.017222) (xy 115.489241 -67.928492)
			(xy 115.674729 -67.846849) (xy 115.863226 -67.772412) (xy 116.05445 -67.705294) (xy 116.248119 -67.645593)
			(xy 116.443944 -67.593398) (xy 116.641634 -67.548788) (xy 116.840897 -67.511827) (xy 116.941092 -67.49669)
			(xy 116.948204 -67.495674) (xy 116.962936 -67.48907) (xy 116.971337 -67.48457) (xy 116.98428 -67.470599)
			(xy 116.99124 -67.452872) (xy 116.991638 -67.44335) (xy 116.991638 -41.382442) (xy 116.991566 -41.378232)
			(xy 116.990166 -41.369929) (xy 116.988844 -41.365932) (xy 116.985014 -41.356309) (xy 116.971118 -41.340977)
			(xy 116.96192 -41.336214) (xy 116.957348 -41.334182) (xy 116.955824 -41.333674) (xy 116.932968 -41.325674)
			(xy 116.889321 -41.3047) (xy 116.848676 -41.278376) (xy 116.811684 -41.247125) (xy 116.795042 -41.229534)
			(xy 116.777024 -41.209181) (xy 116.746337 -41.164314) (xy 116.722331 -41.115544) (xy 116.705492 -41.063861)
			(xy 116.696162 -41.01031) (xy 116.694529 -40.955977) (xy 116.700626 -40.901963) (xy 116.714331 -40.849361)
			(xy 116.735364 -40.799238) (xy 116.763301 -40.752609) (xy 116.797575 -40.710419) (xy 116.837492 -40.673522)
			(xy 116.882243 -40.642666) (xy 116.930921 -40.618477) (xy 116.956586 -40.60952) (xy 116.95684 -40.60952)
			(xy 116.959634 -40.608504) (xy 116.966124 -40.605673) (xy 116.977336 -40.597036) (xy 116.981732 -40.591486)
			(xy 116.986319 -40.584789) (xy 116.991371 -40.569373) (xy 116.991638 -40.56126) (xy 116.991638 -38.432232)
			(xy 116.991156 -38.422217) (xy 116.983504 -38.403708) (xy 116.969351 -38.389536) (xy 116.950852 -38.381858)
			(xy 116.940838 -38.381432) (xy 115.390168 -38.381432) (xy 115.378738 -38.382702) (xy 115.369848 -38.384734)
			(xy 115.360555 -38.387698) (xy 115.345026 -38.399471) (xy 115.339622 -38.407594) (xy 115.311174 -38.460934)
			(xy 115.311174 -38.461442) (xy 115.297458 -38.487604) (xy 115.294434 -38.493765) (xy 115.291468 -38.507159)
			(xy 115.291616 -38.51402) (xy 115.292378 -38.527736) (xy 115.300252 -38.53942) (xy 115.30076 -38.540182)
			(xy 115.307618 -38.551358) (xy 115.31854 -38.570408) (xy 115.332976 -38.598742) (xy 115.353267 -38.659004)
			(xy 115.358926 -38.690296) (xy 115.361168 -38.705181) (xy 115.363587 -38.735188) (xy 115.363752 -38.75024)
			(xy 115.363752 -38.750748) (xy 115.363263 -38.777998) (xy 115.355501 -38.831943) (xy 115.340142 -38.884235)
			(xy 115.317499 -38.933809) (xy 115.288032 -38.979656) (xy 115.252341 -39.020844) (xy 115.211153 -39.056535)
			(xy 115.165305 -39.086001) (xy 115.115731 -39.108644) (xy 115.063439 -39.124002) (xy 115.009494 -39.131763)
			(xy 114.982244 -39.132256) (xy 114.954788 -39.131775) (xy 114.900444 -39.123902) (xy 114.847788 -39.108325)
			(xy 114.797906 -39.085367) (xy 114.751827 -39.0555) (xy 114.710501 -39.019341) (xy 114.674781 -38.977635)
			(xy 114.659664 -38.95471) (xy 114.657886 -38.951662) (xy 114.65486 -38.947762) (xy 114.64757 -38.941108)
			(xy 114.643408 -38.938454) (xy 114.623088 -38.926008) (xy 114.615214 -38.922452) (xy 114.614198 -38.921944)
			(xy 114.610748 -38.920752) (xy 114.60361 -38.91922) (xy 114.599974 -38.918896) (xy 114.529616 -38.914324)
			(xy 114.523343 -38.914135) (xy 114.511011 -38.916449) (xy 114.505232 -38.918896) (xy 114.499816 -38.92156)
			(xy 114.490324 -38.92901) (xy 114.486436 -38.933628) (xy 114.483388 -38.937438) (xy 114.483134 -38.937692)
			(xy 114.48034 -38.941248) (xy 114.462097 -38.963142) (xy 114.420227 -39.0018) (xy 114.373083 -39.033814)
			(xy 114.321709 -39.058475) (xy 114.267242 -39.075236) (xy 114.210891 -39.083725) (xy 114.182398 -39.08425)
			(xy 114.182144 -39.08425) (xy 114.154888 -39.08379) (xy 114.10093 -39.076039) (xy 114.048624 -39.060687)
			(xy 113.999036 -39.038047) (xy 113.953174 -39.008581) (xy 113.911973 -38.972888) (xy 113.876271 -38.931695)
			(xy 113.846794 -38.88584) (xy 113.824143 -38.836256) (xy 113.80878 -38.783954) (xy 113.801016 -38.729998)
			(xy 113.800636 -38.702742) (xy 113.800636 -38.702488) (xy 113.801192 -38.672498) (xy 113.810587 -38.613259)
			(xy 113.829158 -38.556227) (xy 113.842292 -38.52926) (xy 113.842546 -38.528752) (xy 113.845333 -38.522856)
			(xy 113.848162 -38.510128) (xy 113.848134 -38.503606) (xy 113.847626 -38.491414) (xy 113.794286 -38.404038)
			(xy 113.790984 -38.400482) (xy 113.783354 -38.391967) (xy 113.762775 -38.382076) (xy 113.75136 -38.381432)
			(xy 111.385858 -38.381432) (xy 111.375895 -38.381914) (xy 111.357467 -38.389499) (xy 111.350044 -38.396164)
			(xy 111.06531 -38.680898) (xy 111.063786 -38.682168) (xy 111.062262 -38.683692) (xy 111.038384 -38.706619)
			(xy 110.985723 -38.746731) (xy 110.928298 -38.779664) (xy 110.867083 -38.80486) (xy 110.803114 -38.821893)
			(xy 110.737475 -38.830474) (xy 110.704376 -38.831012) (xy 109.088936 -38.831012) (xy 109.05566 -38.830464)
			(xy 108.989677 -38.821772) (xy 108.925392 -38.804544) (xy 108.863905 -38.779075) (xy 108.806267 -38.745802)
			(xy 108.753463 -38.705291) (xy 108.729526 -38.682168) (xy 107.881928 -37.83457) (xy 107.858796 -37.81067)
			(xy 107.818304 -37.757903) (xy 107.785043 -37.700304) (xy 107.759583 -37.638857) (xy 107.742359 -37.574613)
			(xy 107.733665 -37.50867) (xy 107.733084 -37.475414) (xy 107.733084 -37.47389) (xy 107.733084 -37.465762)
			(xy 107.733084 -37.461698) (xy 107.733338 -37.456618) (xy 107.733338 -37.451538) (xy 107.7341 -37.439346)
			(xy 107.7341 -37.439092) (xy 107.736804 -37.407733) (xy 107.748987 -37.345979) (xy 107.768697 -37.286201)
			(xy 107.795633 -37.229312) (xy 107.829384 -37.176182) (xy 107.869433 -37.127623) (xy 107.915169 -37.084378)
			(xy 107.965891 -37.047107) (xy 108.020826 -37.01638) (xy 108.079132 -36.992667) (xy 108.139919 -36.976331)
			(xy 108.202257 -36.967621) (xy 108.233718 -36.966652) (xy 108.242862 -36.966652) (xy 108.274712 -36.967241)
			(xy 108.337891 -36.975391) (xy 108.368846 -36.982908) (xy 108.387999 -36.988099) (xy 108.425507 -37.001067)
			(xy 108.443776 -37.008816) (xy 108.460014 -37.01603) (xy 108.491539 -37.032428) (xy 108.506768 -37.041582)
			(xy 108.51769 -37.04844) (xy 108.522008 -37.051234) (xy 108.53399 -37.059287) (xy 108.557119 -37.076568)
			(xy 108.568236 -37.085778) (xy 108.601002 -37.11575) (xy 109.079792 -37.59454) (xy 109.285532 -37.800534)
			(xy 109.29171 -37.805978) (xy 109.306607 -37.812975) (xy 109.314742 -37.81425) (xy 109.320584 -37.814504)
			(xy 109.944662 -37.814504) (xy 109.957108 -37.81298) (xy 109.963204 -37.811456) (xy 109.969974 -37.809621)
			(xy 109.982219 -37.802793) (xy 109.987334 -37.797994) (xy 110.021878 -37.75964) (xy 110.038134 -37.741606)
			(xy 110.041658 -37.737446) (xy 110.047047 -37.727971) (xy 110.048802 -37.72281) (xy 110.052104 -37.712142)
			(xy 110.051342 -37.703506) (xy 110.04931 -37.67836) (xy 110.04931 -37.677852) (xy 110.049056 -37.667946)
			(xy 110.049056 -37.660072) (xy 110.0497 -37.632928) (xy 110.057724 -37.579231) (xy 110.07328 -37.527213)
			(xy 110.096052 -37.477925) (xy 110.125581 -37.432363) (xy 110.161271 -37.391448) (xy 110.2024 -37.356005)
			(xy 110.248138 -37.32675) (xy 110.297562 -37.304274) (xy 110.349672 -37.289031) (xy 110.403417 -37.28133)
			(xy 110.430564 -37.28085) (xy 110.459345 -37.281372) (xy 110.516254 -37.290015) (xy 110.571219 -37.307111)
			(xy 110.622991 -37.332272) (xy 110.670394 -37.364926) (xy 110.712354 -37.404332) (xy 110.730538 -37.426646)
			(xy 110.732316 -37.428932) (xy 110.737142 -37.433758) (xy 110.74303 -37.439152) (xy 110.757258 -37.446382)
			(xy 110.765082 -37.447982) (xy 110.785148 -37.451284) (xy 110.78972 -37.451538) (xy 110.848394 -37.451538)
			(xy 110.854998 -37.45103) (xy 110.876588 -37.446966) (xy 110.884716 -37.441886) (xy 110.89894 -37.43325)
			(xy 110.92815 -37.417502) (xy 110.939423 -37.411994) (xy 110.96242 -37.401957) (xy 110.974124 -37.397436)
			(xy 110.99292 -37.390832) (xy 110.993936 -37.39007) (xy 110.998254 -37.3888) (xy 110.99927 -37.388546)
			(xy 111.000794 -37.388038) (xy 111.027249 -37.380049) (xy 111.081436 -37.369185) (xy 111.136481 -37.364257)
			(xy 111.164116 -37.364416) (xy 116.940838 -37.364416) (xy 116.950842 -37.363922) (xy 116.969323 -37.356256)
			(xy 116.983468 -37.342105) (xy 116.991126 -37.32362) (xy 116.991638 -37.313616) (xy 116.991638 -30.420818)
			(xy 116.991384 -30.418278) (xy 116.990329 -30.408023) (xy 116.989188 -30.387438) (xy 116.989098 -30.37713)
			(xy 116.989098 -30.376622) (xy 116.98918 -30.366314) (xy 116.990325 -30.345728) (xy 116.991384 -30.335474)
			(xy 116.991638 -30.332934) (xy 116.991638 -29.658818) (xy 116.991384 -29.656278) (xy 116.990329 -29.646023)
			(xy 116.989188 -29.625438) (xy 116.989098 -29.61513) (xy 116.989098 -29.614622) (xy 116.98918 -29.604314)
			(xy 116.990325 -29.583728) (xy 116.991384 -29.573474) (xy 116.991638 -29.570934) (xy 116.991638 -28.846018)
			(xy 116.991384 -28.843478) (xy 116.990329 -28.833223) (xy 116.989188 -28.812638) (xy 116.989098 -28.80233)
			(xy 116.989098 -28.801822) (xy 116.98918 -28.791514) (xy 116.990325 -28.770928) (xy 116.991384 -28.760674)
			(xy 116.991638 -28.758134) (xy 116.991638 -26.190956) (xy 116.991543 -26.186078) (xy 116.989755 -26.176489)
			(xy 116.988082 -26.171906) (xy 116.984272 -26.162762) (xy 114.991134 -24.169624) (xy 114.987407 -24.166097)
			(xy 114.978837 -24.160456) (xy 114.974116 -24.158448) (xy 114.96548 -24.154892) (xy 106.658664 -24.154892)
			(xy 106.653786 -24.154987) (xy 106.644196 -24.156774) (xy 106.639614 -24.158448) (xy 106.63047 -24.162258)
			(xy 105.529888 -25.26284) (xy 105.526368 -25.266571) (xy 105.520742 -25.275147) (xy 105.518712 -25.279858)
			(xy 105.515156 -25.288494) (xy 105.515156 -35.876738) (xy 108.817408 -35.876738) (xy 108.821479 -35.821116)
			(xy 108.833605 -35.766679) (xy 108.853528 -35.714588) (xy 108.880824 -35.665953) (xy 108.91491 -35.62181)
			(xy 108.955059 -35.583101) (xy 109.000417 -35.55065) (xy 109.050017 -35.525149) (xy 109.102801 -35.507142)
			(xy 109.157644 -35.497012) (xy 109.213378 -35.494975) (xy 109.268815 -35.501075) (xy 109.322772 -35.515181)
			(xy 109.374101 -35.536993) (xy 109.421707 -35.566047) (xy 109.464575 -35.601722) (xy 109.501792 -35.643259)
			(xy 109.532565 -35.689772) (xy 109.556237 -35.740269) (xy 109.572305 -35.793676) (xy 109.580425 -35.848852)
			(xy 109.580934 -35.876738) (xy 112.889028 -35.876738) (xy 112.893099 -35.821116) (xy 112.905225 -35.766679)
			(xy 112.925148 -35.714588) (xy 112.952444 -35.665953) (xy 112.98653 -35.62181) (xy 113.026679 -35.583101)
			(xy 113.072037 -35.55065) (xy 113.121637 -35.525149) (xy 113.174421 -35.507142) (xy 113.229264 -35.497012)
			(xy 113.284998 -35.494975) (xy 113.340435 -35.501075) (xy 113.394392 -35.515181) (xy 113.445721 -35.536993)
			(xy 113.493327 -35.566047) (xy 113.536195 -35.601722) (xy 113.573412 -35.643259) (xy 113.604185 -35.689772)
			(xy 113.627857 -35.740269) (xy 113.643925 -35.793676) (xy 113.652045 -35.848852) (xy 113.652554 -35.876738)
			(xy 113.652045 -35.904624) (xy 113.643925 -35.9598) (xy 113.627857 -36.013207) (xy 113.604185 -36.063704)
			(xy 113.573412 -36.110217) (xy 113.536195 -36.151754) (xy 113.493327 -36.187429) (xy 113.445721 -36.216483)
			(xy 113.394392 -36.238295) (xy 113.340435 -36.252401) (xy 113.284998 -36.258501) (xy 113.229264 -36.256464)
			(xy 113.174421 -36.246334) (xy 113.121637 -36.228327) (xy 113.072037 -36.202826) (xy 113.026679 -36.170375)
			(xy 112.98653 -36.131666) (xy 112.952444 -36.087523) (xy 112.925148 -36.038888) (xy 112.905225 -35.986797)
			(xy 112.893099 -35.93236) (xy 112.889028 -35.876738) (xy 109.580934 -35.876738) (xy 109.580425 -35.904624)
			(xy 109.572305 -35.9598) (xy 109.556237 -36.013207) (xy 109.532565 -36.063704) (xy 109.501792 -36.110217)
			(xy 109.464575 -36.151754) (xy 109.421707 -36.187429) (xy 109.374101 -36.216483) (xy 109.322772 -36.238295)
			(xy 109.268815 -36.252401) (xy 109.213378 -36.258501) (xy 109.157644 -36.256464) (xy 109.102801 -36.246334)
			(xy 109.050017 -36.228327) (xy 109.000417 -36.202826) (xy 108.955059 -36.170375) (xy 108.91491 -36.131666)
			(xy 108.880824 -36.087523) (xy 108.853528 -36.038888) (xy 108.833605 -35.986797) (xy 108.821479 -35.93236)
			(xy 108.817408 -35.876738) (xy 105.515156 -35.876738) (xy 105.515156 -36.50996) (xy 110.714026 -36.50996)
			(xy 110.718097 -36.454338) (xy 110.730223 -36.399901) (xy 110.750146 -36.34781) (xy 110.777442 -36.299175)
			(xy 110.811528 -36.255032) (xy 110.851677 -36.216323) (xy 110.897035 -36.183872) (xy 110.946635 -36.158371)
			(xy 110.999419 -36.140364) (xy 111.054262 -36.130234) (xy 111.109996 -36.128197) (xy 111.165433 -36.134297)
			(xy 111.21939 -36.148403) (xy 111.270719 -36.170215) (xy 111.318325 -36.199269) (xy 111.361193 -36.234944)
			(xy 111.39841 -36.276481) (xy 111.429183 -36.322994) (xy 111.452855 -36.373491) (xy 111.468923 -36.426898)
			(xy 111.472848 -36.453572) (xy 114.028726 -36.453572) (xy 114.032797 -36.39795) (xy 114.044923 -36.343513)
			(xy 114.064846 -36.291422) (xy 114.092142 -36.242787) (xy 114.126228 -36.198644) (xy 114.166377 -36.159935)
			(xy 114.211735 -36.127484) (xy 114.261335 -36.101983) (xy 114.314119 -36.083976) (xy 114.368962 -36.073846)
			(xy 114.424696 -36.071809) (xy 114.480133 -36.077909) (xy 114.53409 -36.092015) (xy 114.585419 -36.113827)
			(xy 114.633025 -36.142881) (xy 114.675893 -36.178556) (xy 114.71311 -36.220093) (xy 114.743883 -36.266606)
			(xy 114.767555 -36.317103) (xy 114.783623 -36.37051) (xy 114.791743 -36.425686) (xy 114.792252 -36.453572)
			(xy 114.791743 -36.481458) (xy 114.783623 -36.536634) (xy 114.767555 -36.590041) (xy 114.743883 -36.640538)
			(xy 114.71311 -36.687051) (xy 114.675893 -36.728588) (xy 114.633025 -36.764263) (xy 114.585419 -36.793317)
			(xy 114.53409 -36.815129) (xy 114.480133 -36.829235) (xy 114.424696 -36.835335) (xy 114.368962 -36.833298)
			(xy 114.314119 -36.823168) (xy 114.261335 -36.805161) (xy 114.211735 -36.77966) (xy 114.166377 -36.747209)
			(xy 114.126228 -36.7085) (xy 114.092142 -36.664357) (xy 114.064846 -36.615722) (xy 114.044923 -36.563631)
			(xy 114.032797 -36.509194) (xy 114.028726 -36.453572) (xy 111.472848 -36.453572) (xy 111.477043 -36.482074)
			(xy 111.477552 -36.50996) (xy 111.477043 -36.537846) (xy 111.468923 -36.593022) (xy 111.452855 -36.646429)
			(xy 111.429183 -36.696926) (xy 111.39841 -36.743439) (xy 111.361193 -36.784976) (xy 111.318325 -36.820651)
			(xy 111.270719 -36.849705) (xy 111.21939 -36.871517) (xy 111.165433 -36.885623) (xy 111.109996 -36.891723)
			(xy 111.054262 -36.889686) (xy 110.999419 -36.879556) (xy 110.946635 -36.861549) (xy 110.897035 -36.836048)
			(xy 110.851677 -36.803597) (xy 110.811528 -36.764888) (xy 110.777442 -36.720745) (xy 110.750146 -36.67211)
			(xy 110.730223 -36.620019) (xy 110.718097 -36.565582) (xy 110.714026 -36.50996) (xy 105.515156 -36.50996)
			(xy 105.515156 -39.97198) (xy 115.995956 -39.97198) (xy 116.000027 -39.916358) (xy 116.012153 -39.861921)
			(xy 116.032076 -39.80983) (xy 116.059372 -39.761195) (xy 116.093458 -39.717052) (xy 116.133607 -39.678343)
			(xy 116.178965 -39.645892) (xy 116.228565 -39.620391) (xy 116.281349 -39.602384) (xy 116.336192 -39.592254)
			(xy 116.391926 -39.590217) (xy 116.447363 -39.596317) (xy 116.50132 -39.610423) (xy 116.552649 -39.632235)
			(xy 116.600255 -39.661289) (xy 116.643123 -39.696964) (xy 116.68034 -39.738501) (xy 116.711113 -39.785014)
			(xy 116.734785 -39.835511) (xy 116.750853 -39.888918) (xy 116.758973 -39.944094) (xy 116.759482 -39.97198)
			(xy 116.758973 -39.999866) (xy 116.750853 -40.055042) (xy 116.734785 -40.108449) (xy 116.711113 -40.158946)
			(xy 116.68034 -40.205459) (xy 116.643123 -40.246996) (xy 116.600255 -40.282671) (xy 116.552649 -40.311725)
			(xy 116.50132 -40.333537) (xy 116.447363 -40.347643) (xy 116.391926 -40.353743) (xy 116.336192 -40.351706)
			(xy 116.281349 -40.341576) (xy 116.228565 -40.323569) (xy 116.178965 -40.298068) (xy 116.133607 -40.265617)
			(xy 116.093458 -40.226908) (xy 116.059372 -40.182765) (xy 116.032076 -40.13413) (xy 116.012153 -40.082039)
			(xy 116.000027 -40.027602) (xy 115.995956 -39.97198) (xy 105.515156 -39.97198) (xy 105.515156 -42.485818)
			(xy 105.518204 -42.497756) (xy 105.520998 -42.503344) (xy 105.532936 -42.526712) (xy 105.541318 -42.533316)
			(xy 105.541572 -42.53357) (xy 105.545128 -42.536364) (xy 105.545636 -42.536618) (xy 105.568699 -42.554791)
			(xy 105.609495 -42.597019) (xy 105.643354 -42.644988) (xy 105.669478 -42.697572) (xy 105.687254 -42.753532)
			(xy 105.696262 -42.811552) (xy 105.696766 -42.84091) (xy 105.696359 -42.866522) (xy 105.689518 -42.917286)
			(xy 105.675946 -42.966679) (xy 105.655889 -43.013812) (xy 105.629707 -43.057838) (xy 105.597869 -43.097965)
			(xy 105.579672 -43.115992) (xy 105.571253 -43.123952) (xy 105.553587 -43.138949) (xy 105.544366 -43.145964)
			(xy 105.544112 -43.145964) (xy 105.543604 -43.146472) (xy 105.539032 -43.150028) (xy 105.535222 -43.1546)
			(xy 105.531158 -43.159426) (xy 105.520998 -43.178984) (xy 105.518325 -43.184456) (xy 105.515372 -43.196266)
			(xy 105.515156 -43.202352) (xy 105.515156 -43.501818) (xy 105.518204 -43.513756) (xy 105.520998 -43.519344)
			(xy 105.532936 -43.542712) (xy 105.541318 -43.549316) (xy 105.541572 -43.54957) (xy 105.545128 -43.552364)
			(xy 105.545636 -43.552618) (xy 105.568699 -43.570791) (xy 105.609495 -43.613019) (xy 105.643354 -43.660988)
			(xy 105.669478 -43.713572) (xy 105.687254 -43.769532) (xy 105.696262 -43.827552) (xy 105.696766 -43.85691)
			(xy 105.696359 -43.882522) (xy 105.689518 -43.933286) (xy 105.675946 -43.982679) (xy 105.655889 -44.029812)
			(xy 105.629707 -44.073838) (xy 105.597869 -44.113965) (xy 105.579672 -44.131992) (xy 105.571253 -44.139952)
			(xy 105.553587 -44.154949) (xy 105.544366 -44.161964) (xy 105.544112 -44.161964) (xy 105.543604 -44.162472)
			(xy 105.539032 -44.166028) (xy 105.535222 -44.1706) (xy 105.531158 -44.175426) (xy 105.520998 -44.194984)
			(xy 105.518325 -44.200456) (xy 105.515372 -44.212266) (xy 105.515156 -44.218352) (xy 105.515156 -44.517818)
			(xy 105.518204 -44.529756) (xy 105.520998 -44.535344) (xy 105.532936 -44.558712) (xy 105.541318 -44.565316)
			(xy 105.541572 -44.56557) (xy 105.545128 -44.568364) (xy 105.545636 -44.568618) (xy 105.568699 -44.586791)
			(xy 105.609495 -44.629019) (xy 105.643354 -44.676988) (xy 105.669478 -44.729572) (xy 105.687254 -44.785532)
			(xy 105.696262 -44.843552) (xy 105.696766 -44.87291) (xy 105.696359 -44.898522) (xy 105.689518 -44.949286)
			(xy 105.675946 -44.998679) (xy 105.655889 -45.045812) (xy 105.629707 -45.089838) (xy 105.597869 -45.129965)
			(xy 105.579672 -45.147992) (xy 105.571253 -45.155952) (xy 105.553587 -45.170949) (xy 105.544366 -45.177964)
			(xy 105.544112 -45.177964) (xy 105.543604 -45.178472) (xy 105.539032 -45.182028) (xy 105.535222 -45.1866)
			(xy 105.531158 -45.191426) (xy 105.520998 -45.210984) (xy 105.518325 -45.216456) (xy 105.515372 -45.228266)
			(xy 105.515156 -45.234352) (xy 105.515156 -45.533818) (xy 105.518204 -45.545756) (xy 105.520998 -45.551344)
			(xy 105.532936 -45.574712) (xy 105.541318 -45.581316) (xy 105.541572 -45.58157) (xy 105.545128 -45.584364)
			(xy 105.545636 -45.584618) (xy 105.568699 -45.602791) (xy 105.609495 -45.645019) (xy 105.643354 -45.692988)
			(xy 105.669478 -45.745572) (xy 105.687254 -45.801532) (xy 105.696262 -45.859552) (xy 105.696766 -45.88891)
			(xy 105.696359 -45.914522) (xy 105.689518 -45.965286) (xy 105.675946 -46.014679) (xy 105.655889 -46.061812)
			(xy 105.629707 -46.105838) (xy 105.597869 -46.145965) (xy 105.579672 -46.163992) (xy 105.571253 -46.171952)
			(xy 105.553587 -46.186949) (xy 105.544366 -46.193964) (xy 105.544112 -46.193964) (xy 105.543604 -46.194472)
			(xy 105.539032 -46.198028) (xy 105.535222 -46.2026) (xy 105.531158 -46.207426) (xy 105.520998 -46.226984)
			(xy 105.518325 -46.232456) (xy 105.515372 -46.244266) (xy 105.515156 -46.250352) (xy 105.515156 -47.055024)
			(xy 105.515664 -47.062136) (xy 105.51668 -47.06747) (xy 105.517574 -47.071595) (xy 105.520503 -47.079511)
			(xy 105.522522 -47.083218) (xy 105.536492 -47.10811) (xy 105.54081 -47.112682) (xy 105.544874 -47.117)
			(xy 105.550208 -47.120556) (xy 105.550462 -47.12081) (xy 105.573065 -47.135976) (xy 105.614141 -47.171691)
			(xy 105.649729 -47.212876) (xy 105.679111 -47.258696) (xy 105.70169 -47.308223) (xy 105.717009 -47.360454)
			(xy 105.724758 -47.41433) (xy 105.72478 -47.468761) (xy 105.717075 -47.522644) (xy 105.701798 -47.574887)
			(xy 105.679259 -47.624433) (xy 105.649914 -47.670276) (xy 105.614359 -47.71149) (xy 105.573313 -47.747238)
			(xy 105.550716 -47.762414) (xy 105.545128 -47.76597) (xy 105.536238 -47.775622) (xy 105.531666 -47.784004)
			(xy 105.52176 -47.801784) (xy 105.51668 -47.813722) (xy 105.515156 -47.819818) (xy 105.515156 -48.581818)
			(xy 105.518204 -48.593756) (xy 105.520998 -48.599344) (xy 105.532936 -48.622712) (xy 105.541318 -48.629316)
			(xy 105.541572 -48.62957) (xy 105.545128 -48.632364) (xy 105.545636 -48.632618) (xy 105.568699 -48.650791)
			(xy 105.609495 -48.693019) (xy 105.643354 -48.740988) (xy 105.669478 -48.793572) (xy 105.687254 -48.849532)
			(xy 105.696262 -48.907552) (xy 105.696766 -48.93691) (xy 105.696359 -48.962522) (xy 105.689518 -49.013286)
			(xy 105.675946 -49.062679) (xy 105.655889 -49.109812) (xy 105.629707 -49.153838) (xy 105.597869 -49.193965)
			(xy 105.579672 -49.211992) (xy 105.571253 -49.219952) (xy 105.553587 -49.234949) (xy 105.544366 -49.241964)
			(xy 105.544112 -49.241964) (xy 105.543604 -49.242472) (xy 105.539032 -49.246028) (xy 105.535222 -49.2506)
			(xy 105.531158 -49.255426) (xy 105.520998 -49.274984) (xy 105.518325 -49.280456) (xy 105.515372 -49.292266)
			(xy 105.515156 -49.298352) (xy 105.515156 -49.597818) (xy 105.518204 -49.609756) (xy 105.520998 -49.615344)
			(xy 105.532936 -49.638712) (xy 105.541318 -49.645316) (xy 105.541572 -49.64557) (xy 105.545128 -49.648364)
			(xy 105.545636 -49.648618) (xy 105.568699 -49.666791) (xy 105.609495 -49.709019) (xy 105.643354 -49.756988)
			(xy 105.669478 -49.809572) (xy 105.687254 -49.865532) (xy 105.696262 -49.923552) (xy 105.696766 -49.95291)
			(xy 105.696359 -49.978522) (xy 105.689518 -50.029286) (xy 105.675946 -50.078679) (xy 105.655889 -50.125812)
			(xy 105.629707 -50.169838) (xy 105.597869 -50.209965) (xy 105.579672 -50.227992) (xy 105.571253 -50.235952)
			(xy 105.553587 -50.250949) (xy 105.544366 -50.257964) (xy 105.544112 -50.257964) (xy 105.543604 -50.258472)
			(xy 105.539032 -50.262028) (xy 105.535222 -50.2666) (xy 105.531158 -50.271426) (xy 105.520998 -50.290984)
			(xy 105.518325 -50.296456) (xy 105.515372 -50.308266) (xy 105.515156 -50.314352) (xy 105.515156 -50.649886)
			(xy 105.515349 -50.656554) (xy 105.518818 -50.669431) (xy 105.522014 -50.675286) (xy 105.535476 -50.698908)
			(xy 105.542334 -50.706528) (xy 105.546906 -50.70983) (xy 105.569147 -50.72652) (xy 105.609016 -50.765279)
			(xy 105.642844 -50.809409) (xy 105.669915 -50.857978) (xy 105.689658 -50.909959) (xy 105.701654 -50.964253)
			(xy 105.705651 -51.019713) (xy 105.701563 -51.075167) (xy 105.689478 -51.129442) (xy 105.66965 -51.18139)
			(xy 105.642499 -51.229915) (xy 105.608599 -51.27399) (xy 105.568666 -51.312683) (xy 105.546398 -51.329336)
			(xy 105.541572 -51.332892) (xy 105.538016 -51.336956) (xy 105.531412 -51.346354) (xy 105.521252 -51.365658)
			(xy 105.519499 -51.36909) (xy 105.516954 -51.376363) (xy 105.516172 -51.380136) (xy 105.515156 -51.38928)
			(xy 105.515156 -51.665886) (xy 105.515349 -51.672554) (xy 105.518818 -51.685431) (xy 105.522014 -51.691286)
			(xy 105.535476 -51.714908) (xy 105.542334 -51.722528) (xy 105.546906 -51.72583) (xy 105.569147 -51.74252)
			(xy 105.609016 -51.781279) (xy 105.642844 -51.825409) (xy 105.669915 -51.873978) (xy 105.689658 -51.925959)
			(xy 105.701654 -51.980253) (xy 105.705651 -52.035713) (xy 105.701563 -52.091167) (xy 105.689478 -52.145442)
			(xy 105.66965 -52.19739) (xy 105.642499 -52.245915) (xy 105.608599 -52.28999) (xy 105.568666 -52.328683)
			(xy 105.546398 -52.345336) (xy 105.541572 -52.348892) (xy 105.538016 -52.352956) (xy 105.531412 -52.362354)
			(xy 105.521252 -52.381658) (xy 105.519499 -52.38509) (xy 105.516954 -52.392363) (xy 105.516172 -52.396136)
			(xy 105.515156 -52.40528) (xy 105.515156 -52.681886) (xy 105.515349 -52.688554) (xy 105.518818 -52.701431)
			(xy 105.522014 -52.707286) (xy 105.535476 -52.730908) (xy 105.542334 -52.738528) (xy 105.546906 -52.74183)
			(xy 105.569147 -52.75852) (xy 105.609016 -52.797279) (xy 105.642844 -52.841409) (xy 105.669915 -52.889978)
			(xy 105.689658 -52.941959) (xy 105.701654 -52.996253) (xy 105.705651 -53.051713) (xy 105.701563 -53.107167)
			(xy 105.689478 -53.161442) (xy 105.66965 -53.21339) (xy 105.642499 -53.261915) (xy 105.608599 -53.30599)
			(xy 105.568666 -53.344683) (xy 105.546398 -53.361336) (xy 105.541572 -53.364892) (xy 105.538016 -53.368956)
			(xy 105.531412 -53.378354) (xy 105.521252 -53.397658) (xy 105.519499 -53.40109) (xy 105.516954 -53.408363)
			(xy 105.516172 -53.412136) (xy 105.515156 -53.42128) (xy 105.515156 -53.697886) (xy 105.515349 -53.704554)
			(xy 105.518818 -53.717431) (xy 105.522014 -53.723286) (xy 105.535476 -53.746908) (xy 105.542334 -53.754528)
			(xy 105.546906 -53.75783) (xy 105.569147 -53.77452) (xy 105.609016 -53.813279) (xy 105.642844 -53.857409)
			(xy 105.669915 -53.905978) (xy 105.689658 -53.957959) (xy 105.701654 -54.012253) (xy 105.705651 -54.067713)
			(xy 105.701563 -54.123167) (xy 105.689478 -54.177442) (xy 105.66965 -54.22939) (xy 105.642499 -54.277915)
			(xy 105.608599 -54.32199) (xy 105.568666 -54.360683) (xy 105.546398 -54.377336) (xy 105.541572 -54.380892)
			(xy 105.538016 -54.384956) (xy 105.531412 -54.394354) (xy 105.521252 -54.413658) (xy 105.519499 -54.41709)
			(xy 105.516954 -54.424363) (xy 105.516172 -54.428136) (xy 105.515156 -54.43728) (xy 105.515156 -54.713886)
			(xy 105.515349 -54.720554) (xy 105.518818 -54.733431) (xy 105.522014 -54.739286) (xy 105.535476 -54.762908)
			(xy 105.542334 -54.770528) (xy 105.546906 -54.77383) (xy 105.569147 -54.79052) (xy 105.609016 -54.829279)
			(xy 105.642844 -54.873409) (xy 105.669915 -54.921978) (xy 105.689658 -54.973959) (xy 105.701654 -55.028253)
			(xy 105.705651 -55.083713) (xy 105.701563 -55.139167) (xy 105.689478 -55.193442) (xy 105.66965 -55.24539)
			(xy 105.642499 -55.293915) (xy 105.608599 -55.33799) (xy 105.568666 -55.376683) (xy 105.546398 -55.393336)
			(xy 105.541572 -55.396892) (xy 105.538016 -55.400956) (xy 105.531412 -55.410354) (xy 105.521252 -55.429658)
			(xy 105.519499 -55.43309) (xy 105.516954 -55.440363) (xy 105.516172 -55.444136) (xy 105.515156 -55.45328)
			(xy 105.515156 -55.983886) (xy 105.515349 -55.990554) (xy 105.518818 -56.003431) (xy 105.522014 -56.009286)
			(xy 105.535476 -56.032908) (xy 105.542334 -56.040528) (xy 105.546906 -56.04383) (xy 105.569147 -56.06052)
			(xy 105.609016 -56.099279) (xy 105.642844 -56.143409) (xy 105.669915 -56.191978) (xy 105.689658 -56.243959)
			(xy 105.701654 -56.298253) (xy 105.705651 -56.353713) (xy 105.701563 -56.409167) (xy 105.689478 -56.463442)
			(xy 105.66965 -56.51539) (xy 105.642499 -56.563915) (xy 105.608599 -56.60799) (xy 105.568666 -56.646683)
			(xy 105.546398 -56.663336) (xy 105.541572 -56.666892) (xy 105.538016 -56.670956) (xy 105.531412 -56.680354)
			(xy 105.521252 -56.699658) (xy 105.519499 -56.70309) (xy 105.516954 -56.710363) (xy 105.516172 -56.714136)
			(xy 105.515156 -56.72328) (xy 105.515156 -70.726046) (xy 105.514723 -70.736111) (xy 105.506992 -70.7547)
			(xy 105.50017 -70.762114) (xy 104.670352 -71.591932) (xy 104.662954 -71.598778) (xy 104.644355 -71.606506)
			(xy 104.634284 -71.606918) (xy 101.214682 -71.606918) (xy 101.21138 -71.606918) (xy 101.202815 -71.607792)
			(xy 101.18698 -71.614519) (xy 101.174293 -71.62614) (xy 101.169978 -71.633588) (xy 101.154992 -71.658988)
			(xy 101.141784 -71.678038) (xy 101.123668 -71.701698) (xy 101.081327 -71.743623) (xy 101.032981 -71.778454)
			(xy 100.979808 -71.805345) (xy 100.9231 -71.823641) (xy 100.864237 -71.832897) (xy 100.834444 -71.833486)
			(xy 100.804955 -71.832933) (xy 100.746679 -71.823852) (xy 100.690494 -71.805915) (xy 100.637737 -71.779549)
			(xy 100.589664 -71.745381) (xy 100.547418 -71.704226) (xy 100.512006 -71.657062) (xy 100.49764 -71.631302)
			(xy 100.490563 -71.620935) (xy 100.468984 -71.608174) (xy 100.456492 -71.606918) (xy 99.535742 -71.606918)
			(xy 99.531131 -71.607023) (xy 99.52206 -71.608691) (xy 99.517708 -71.61022) (xy 99.509072 -71.613522)
			(xy 99.486466 -71.634604) (xy 99.479608 -71.6407) (xy 99.464114 -71.670926) (xy 99.462844 -71.679308)
			(xy 99.458389 -71.70612) (xy 99.442881 -71.758211) (xy 99.420138 -71.807574) (xy 99.39062 -71.85321)
			(xy 99.354925 -71.894196) (xy 99.313776 -71.929701) (xy 99.268004 -71.959009) (xy 99.218537 -71.981525)
			(xy 99.166375 -71.996793) (xy 99.112575 -72.004506) (xy 99.058225 -72.004506) (xy 99.004425 -71.996793)
			(xy 98.952263 -71.981525) (xy 98.902796 -71.959009) (xy 98.857024 -71.929701) (xy 98.815875 -71.894196)
			(xy 98.78018 -71.85321) (xy 98.750662 -71.807574) (xy 98.727919 -71.758211) (xy 98.712411 -71.70612)
			(xy 98.707956 -71.679308) (xy 98.706686 -71.670926) (xy 98.691192 -71.6407) (xy 98.684334 -71.634604)
			(xy 98.669094 -71.62038) (xy 98.665426 -71.617111) (xy 98.657113 -71.611872) (xy 98.652584 -71.609966)
			(xy 98.644456 -71.606918) (xy 97.996756 -71.606918) (xy 97.988309 -71.607306) (xy 97.972353 -71.612869)
			(xy 97.965514 -71.61784) (xy 97.951544 -71.628762) (xy 97.949258 -71.638668) (xy 97.942893 -71.665114)
			(xy 97.923688 -71.716003) (xy 97.897458 -71.763653) (xy 97.864733 -71.8071) (xy 97.826175 -71.845465)
			(xy 97.782565 -71.877973) (xy 97.734784 -71.903964) (xy 97.683799 -71.922915) (xy 97.630641 -71.93444)
			(xy 97.576386 -71.938308) (xy 97.522131 -71.93444) (xy 97.468973 -71.922915) (xy 97.417988 -71.903964)
			(xy 97.370207 -71.877973) (xy 97.326597 -71.845465) (xy 97.288039 -71.8071) (xy 97.255314 -71.763653)
			(xy 97.229084 -71.716003) (xy 97.209879 -71.665114) (xy 97.203514 -71.638668) (xy 97.201228 -71.628762)
			(xy 97.187258 -71.61784) (xy 97.180432 -71.612839) (xy 97.164471 -71.60725) (xy 97.156016 -71.606918)
			(xy 75.214734 -71.606918) (xy 75.211432 -71.606918) (xy 75.202872 -71.607799) (xy 75.187049 -71.614536)
			(xy 75.174374 -71.626159) (xy 75.17003 -71.633588) (xy 75.155044 -71.658988) (xy 75.141836 -71.678038)
			(xy 75.123721 -71.7017) (xy 75.081381 -71.743631) (xy 75.033037 -71.778469) (xy 74.979864 -71.805367)
			(xy 74.923155 -71.823671) (xy 74.864291 -71.832935) (xy 74.834496 -71.833486) (xy 74.805009 -71.832929)
			(xy 74.746738 -71.823842) (xy 74.690558 -71.8059) (xy 74.637807 -71.779531) (xy 74.589739 -71.745361)
			(xy 74.547499 -71.704205) (xy 74.512093 -71.657041) (xy 74.497692 -71.631302) (xy 74.490619 -71.620927)
			(xy 74.469041 -71.608144) (xy 74.456544 -71.606918) (xy 73.535794 -71.606918) (xy 73.531182 -71.607018)
			(xy 73.522108 -71.608678) (xy 73.51776 -71.61022) (xy 73.509124 -71.613522) (xy 73.486518 -71.634604)
			(xy 73.47966 -71.6407) (xy 73.464166 -71.670926) (xy 73.462896 -71.679308) (xy 73.458441 -71.70612)
			(xy 73.442933 -71.758211) (xy 73.42019 -71.807574) (xy 73.390672 -71.85321) (xy 73.354977 -71.894196)
			(xy 73.313828 -71.929701) (xy 73.268056 -71.959009) (xy 73.218589 -71.981525) (xy 73.166427 -71.996793)
			(xy 73.112627 -72.004506) (xy 73.058277 -72.004506) (xy 73.004477 -71.996793) (xy 72.952315 -71.981525)
			(xy 72.902848 -71.959009) (xy 72.857076 -71.929701) (xy 72.815927 -71.894196) (xy 72.780232 -71.85321)
			(xy 72.750714 -71.807574) (xy 72.727971 -71.758211) (xy 72.712463 -71.70612) (xy 72.708008 -71.679308)
			(xy 72.706738 -71.670926) (xy 72.691244 -71.6407) (xy 72.684386 -71.634604) (xy 72.669146 -71.62038)
			(xy 72.66548 -71.617107) (xy 72.65717 -71.611861) (xy 72.652636 -71.609966) (xy 72.644508 -71.606918)
			(xy 71.996808 -71.606918) (xy 71.988364 -71.607313) (xy 71.972417 -71.612888) (xy 71.965566 -71.61784)
			(xy 71.951596 -71.628762) (xy 71.94931 -71.638668) (xy 71.942945 -71.665114) (xy 71.92374 -71.716003)
			(xy 71.89751 -71.763653) (xy 71.864785 -71.8071) (xy 71.826227 -71.845465) (xy 71.782617 -71.877973)
			(xy 71.734836 -71.903964) (xy 71.683851 -71.922915) (xy 71.630693 -71.93444) (xy 71.576438 -71.938308)
			(xy 71.522183 -71.93444) (xy 71.469025 -71.922915) (xy 71.41804 -71.903964) (xy 71.370259 -71.877973)
			(xy 71.326649 -71.845465) (xy 71.288091 -71.8071) (xy 71.255366 -71.763653) (xy 71.229136 -71.716003)
			(xy 71.209931 -71.665114) (xy 71.203566 -71.638668) (xy 71.20128 -71.628762) (xy 71.18731 -71.61784)
			(xy 71.180482 -71.612846) (xy 71.16452 -71.607272) (xy 71.156068 -71.606918) (xy 49.226216 -71.606918)
			(xy 49.22027 -71.607106) (xy 49.208716 -71.609926) (xy 49.203356 -71.612506) (xy 49.184052 -71.623682)
			(xy 49.173384 -71.63181) (xy 49.16932 -71.635874) (xy 49.165764 -71.64197) (xy 49.152604 -71.664046)
			(xy 49.121264 -71.70478) (xy 49.084743 -71.740943) (xy 49.043702 -71.77188) (xy 48.998882 -71.797034)
			(xy 48.951094 -71.815949) (xy 48.901201 -71.828283) (xy 48.875696 -71.831454) (xy 48.874934 -71.831454)
			(xy 48.871124 -71.831962) (xy 48.846486 -71.833486) (xy 48.837342 -71.833486) (xy 48.834548 -71.833486)
			(xy 48.834294 -71.833486) (xy 48.804458 -71.832884) (xy 48.745517 -71.823564) (xy 48.716946 -71.814944)
			(xy 48.689211 -71.805394) (xy 48.636831 -71.778992) (xy 48.589108 -71.744887) (xy 48.547162 -71.703884)
			(xy 48.511983 -71.656947) (xy 48.497744 -71.631302) (xy 48.490668 -71.620935) (xy 48.469088 -71.608171)
			(xy 48.456596 -71.606918) (xy 47.535846 -71.606918) (xy 47.531235 -71.607022) (xy 47.522164 -71.60869)
			(xy 47.517812 -71.61022) (xy 47.509176 -71.613522) (xy 47.48657 -71.634604) (xy 47.479712 -71.6407)
			(xy 47.464218 -71.670926) (xy 47.462948 -71.679308) (xy 47.458493 -71.70612) (xy 47.442985 -71.758211)
			(xy 47.420242 -71.807574) (xy 47.390724 -71.85321) (xy 47.355029 -71.894196) (xy 47.31388 -71.929701)
			(xy 47.268108 -71.959009) (xy 47.218641 -71.981525) (xy 47.166479 -71.996793) (xy 47.112679 -72.004506)
			(xy 47.058329 -72.004506) (xy 47.004529 -71.996793) (xy 46.952367 -71.981525) (xy 46.9029 -71.959009)
			(xy 46.857128 -71.929701) (xy 46.815979 -71.894196) (xy 46.780284 -71.85321) (xy 46.750766 -71.807574)
			(xy 46.728023 -71.758211) (xy 46.712515 -71.70612) (xy 46.70806 -71.679308) (xy 46.70679 -71.670926)
			(xy 46.691296 -71.6407) (xy 46.684438 -71.634604) (xy 46.669198 -71.62038) (xy 46.66553 -71.61711)
			(xy 46.657218 -71.611872) (xy 46.652688 -71.609966) (xy 46.64456 -71.606918) (xy 45.99686 -71.606918)
			(xy 45.988413 -71.607305) (xy 45.972456 -71.612867) (xy 45.965618 -71.61784) (xy 45.951648 -71.628762)
			(xy 45.949362 -71.638668) (xy 45.942997 -71.665114) (xy 45.923792 -71.716003) (xy 45.897562 -71.763653)
			(xy 45.864837 -71.8071) (xy 45.826279 -71.845465) (xy 45.782669 -71.877973) (xy 45.734888 -71.903964)
			(xy 45.683903 -71.922915) (xy 45.630745 -71.93444) (xy 45.57649 -71.938308) (xy 45.522235 -71.93444)
			(xy 45.469077 -71.922915) (xy 45.418092 -71.903964) (xy 45.370311 -71.877973) (xy 45.326701 -71.845465)
			(xy 45.288143 -71.8071) (xy 45.255418 -71.763653) (xy 45.229188 -71.716003) (xy 45.209983 -71.665114)
			(xy 45.203618 -71.638668) (xy 45.201332 -71.628762) (xy 45.187362 -71.61784) (xy 45.180536 -71.612839)
			(xy 45.164575 -71.607249) (xy 45.15612 -71.606918) (xy 23.226268 -71.606918) (xy 23.220324 -71.607111)
			(xy 23.208774 -71.609941) (xy 23.203408 -71.612506) (xy 23.184104 -71.623682) (xy 23.173436 -71.63181)
			(xy 23.169372 -71.635874) (xy 23.165816 -71.64197) (xy 23.152655 -71.664045) (xy 23.121313 -71.704775)
			(xy 23.084791 -71.740933) (xy 23.043749 -71.771865) (xy 22.998929 -71.797013) (xy 22.951141 -71.815922)
			(xy 22.901248 -71.82825) (xy 22.875748 -71.831454) (xy 22.874986 -71.831454) (xy 22.871176 -71.831962)
			(xy 22.846538 -71.833486) (xy 22.837394 -71.833486) (xy 22.8346 -71.833486) (xy 22.834346 -71.833486)
			(xy 22.804509 -71.832888) (xy 22.745565 -71.823575) (xy 22.716998 -71.814944) (xy 22.689265 -71.805391)
			(xy 22.636891 -71.778984) (xy 22.589172 -71.744877) (xy 22.547232 -71.703872) (xy 22.512057 -71.656934)
			(xy 22.497796 -71.631302) (xy 22.490724 -71.620926) (xy 22.469146 -71.608141) (xy 22.456648 -71.606918)
			(xy 21.535898 -71.606918) (xy 21.531286 -71.607018) (xy 21.522212 -71.608677) (xy 21.517864 -71.61022)
			(xy 21.509228 -71.613522) (xy 21.486622 -71.634604) (xy 21.479764 -71.6407) (xy 21.46427 -71.670926)
			(xy 21.463 -71.679308) (xy 21.458545 -71.70612) (xy 21.443037 -71.758211) (xy 21.420294 -71.807574)
			(xy 21.390776 -71.85321) (xy 21.355081 -71.894196) (xy 21.313932 -71.929701) (xy 21.26816 -71.959009)
			(xy 21.218693 -71.981525) (xy 21.166531 -71.996793) (xy 21.112731 -72.004506) (xy 21.058381 -72.004506)
			(xy 21.004581 -71.996793) (xy 20.952419 -71.981525) (xy 20.902952 -71.959009) (xy 20.85718 -71.929701)
			(xy 20.816031 -71.894196) (xy 20.780336 -71.85321) (xy 20.750818 -71.807574) (xy 20.728075 -71.758211)
			(xy 20.712567 -71.70612) (xy 20.708112 -71.679308) (xy 20.706842 -71.670926) (xy 20.691348 -71.6407)
			(xy 20.68449 -71.634604) (xy 20.66925 -71.62038) (xy 20.665584 -71.617107) (xy 20.657275 -71.611861)
			(xy 20.65274 -71.609966) (xy 20.644612 -71.606918) (xy 19.996912 -71.606918) (xy 19.988467 -71.607313)
			(xy 19.97252 -71.612886) (xy 19.96567 -71.61784) (xy 19.9517 -71.628762) (xy 19.949414 -71.638668)
			(xy 19.943049 -71.665114) (xy 19.923844 -71.716003) (xy 19.897614 -71.763653) (xy 19.864889 -71.8071)
			(xy 19.826331 -71.845465) (xy 19.782721 -71.877973) (xy 19.73494 -71.903964) (xy 19.683955 -71.922915)
			(xy 19.630797 -71.93444) (xy 19.576542 -71.938308) (xy 19.522287 -71.93444) (xy 19.469129 -71.922915)
			(xy 19.418144 -71.903964) (xy 19.370363 -71.877973) (xy 19.326753 -71.845465) (xy 19.288195 -71.8071)
			(xy 19.25547 -71.763653) (xy 19.22924 -71.716003) (xy 19.210035 -71.665114) (xy 19.20367 -71.638668)
			(xy 19.201384 -71.628762) (xy 19.187414 -71.61784) (xy 19.180586 -71.612845) (xy 19.164625 -71.60727)
			(xy 19.156172 -71.606918) (xy 15.084298 -71.606918) (xy 15.079421 -71.607019) (xy 15.069835 -71.608815)
			(xy 15.065248 -71.610474) (xy 15.056104 -71.614284) (xy 12.86002 -73.810368) (xy 90.899486 -73.810368)
			(xy 90.903557 -73.754746) (xy 90.915683 -73.700309) (xy 90.935606 -73.648218) (xy 90.962902 -73.599583)
			(xy 90.996988 -73.55544) (xy 91.037137 -73.516731) (xy 91.082495 -73.48428) (xy 91.132095 -73.458779)
			(xy 91.184879 -73.440772) (xy 91.239722 -73.430642) (xy 91.295456 -73.428605) (xy 91.350893 -73.434705)
			(xy 91.40485 -73.448811) (xy 91.456179 -73.470623) (xy 91.503785 -73.499677) (xy 91.546653 -73.535352)
			(xy 91.58387 -73.576889) (xy 91.614643 -73.623402) (xy 91.638315 -73.673899) (xy 91.654383 -73.727306)
			(xy 91.662503 -73.782482) (xy 91.663012 -73.810368) (xy 91.662503 -73.838254) (xy 91.654383 -73.89343)
			(xy 91.638315 -73.946837) (xy 91.614643 -73.997334) (xy 91.58387 -74.043847) (xy 91.546653 -74.085384)
			(xy 91.503785 -74.121059) (xy 91.456179 -74.150113) (xy 91.40485 -74.171925) (xy 91.350893 -74.186031)
			(xy 91.295456 -74.192131) (xy 91.239722 -74.190094) (xy 91.184879 -74.179964) (xy 91.132095 -74.161957)
			(xy 91.082495 -74.136456) (xy 91.037137 -74.104005) (xy 90.996988 -74.065296) (xy 90.962902 -74.021153)
			(xy 90.935606 -73.972518) (xy 90.915683 -73.920427) (xy 90.903557 -73.86599) (xy 90.899486 -73.810368)
			(xy 12.86002 -73.810368) (xy 11.952986 -74.717402) (xy 11.945586 -74.724246) (xy 11.926989 -74.731975)
			(xy 11.916918 -74.732388) (xy 7.17677 -74.732388) (xy 7.173214 -74.732642) (xy 7.17042 -74.732642)
			(xy 7.158751 -74.734358) (xy 7.138749 -74.746801) (xy 7.132066 -74.756518) (xy 7.093204 -74.825606)
			(xy 7.093204 -74.826114) (xy 7.088378 -74.834242) (xy 7.085113 -74.841195) (xy 7.082397 -74.856306)
			(xy 7.083044 -74.86396) (xy 7.083044 -74.864214) (xy 7.083552 -74.868786) (xy 7.088632 -74.887074)
			(xy 7.092188 -74.892916) (xy 7.104783 -74.915046) (xy 7.124638 -74.961934) (xy 7.138076 -75.011047)
			(xy 7.144857 -75.061513) (xy 7.145274 -75.086972) (xy 7.145274 -75.087226) (xy 7.144788 -75.114477)
			(xy 7.137032 -75.168425) (xy 7.121677 -75.22072) (xy 7.099035 -75.270297) (xy 7.069569 -75.316147)
			(xy 7.033878 -75.357338) (xy 6.992687 -75.393029) (xy 6.946837 -75.422495) (xy 6.89726 -75.445137)
			(xy 6.844965 -75.460492) (xy 6.791017 -75.468248) (xy 6.736515 -75.468248) (xy 6.682567 -75.460492)
			(xy 6.630272 -75.445137) (xy 6.580695 -75.422495) (xy 6.534845 -75.393029) (xy 6.493654 -75.357338)
			(xy 6.457963 -75.316147) (xy 6.428497 -75.270297) (xy 6.405855 -75.22072) (xy 6.3905 -75.168425)
			(xy 6.382744 -75.114477) (xy 6.382258 -75.087226) (xy 6.382258 -75.086972) (xy 6.382695 -75.061586)
			(xy 6.389459 -75.011267) (xy 6.402826 -74.962286) (xy 6.42256 -74.915506) (xy 6.43509 -74.893424)
			(xy 6.436614 -74.890884) (xy 6.438646 -74.887328) (xy 6.442456 -74.873612) (xy 6.443726 -74.868278)
			(xy 6.444488 -74.864976) (xy 6.444488 -74.864214) (xy 6.445227 -74.856494) (xy 6.44251 -74.841234)
			(xy 6.439154 -74.834242) (xy 6.434328 -74.826114) (xy 6.434328 -74.825606) (xy 6.396482 -74.757788)
			(xy 6.389781 -74.747386) (xy 6.368878 -74.734198) (xy 6.356604 -74.732642) (xy 6.35254 -74.732388)
			(xy 0.91186 -74.732388) (xy 0.906982 -74.732483) (xy 0.897393 -74.734271) (xy 0.89281 -74.735944)
			(xy 0.883666 -74.739754) (xy 0.677418 -74.946002) (xy 0.673894 -74.949731) (xy 0.668259 -74.958303)
			(xy 0.666242 -74.96302) (xy 0.662686 -74.971656) (xy 0.662686 -77.206348) (xy 82.68411 -77.206348)
			(xy 82.688181 -77.150726) (xy 82.700307 -77.096289) (xy 82.72023 -77.044198) (xy 82.747526 -76.995563)
			(xy 82.781612 -76.95142) (xy 82.821761 -76.912711) (xy 82.867119 -76.88026) (xy 82.916719 -76.854759)
			(xy 82.969503 -76.836752) (xy 83.024346 -76.826622) (xy 83.08008 -76.824585) (xy 83.135517 -76.830685)
			(xy 83.189474 -76.844791) (xy 83.240803 -76.866603) (xy 83.288409 -76.895657) (xy 83.331277 -76.931332)
			(xy 83.368494 -76.972869) (xy 83.399267 -77.019382) (xy 83.422939 -77.069879) (xy 83.439007 -77.123286)
			(xy 83.447127 -77.178462) (xy 83.447636 -77.206348) (xy 83.447127 -77.234234) (xy 83.439007 -77.28941)
			(xy 83.422939 -77.342817) (xy 83.412368 -77.365367) (xy 105.150162 -77.365367) (xy 105.150162 -77.305433)
			(xy 105.157985 -77.246011) (xy 105.173496 -77.188119) (xy 105.19643 -77.132746) (xy 105.226396 -77.08084)
			(xy 105.26288 -77.03329) (xy 105.305258 -76.990908) (xy 105.352805 -76.954419) (xy 105.404708 -76.924449)
			(xy 105.460079 -76.901509) (xy 105.51797 -76.885993) (xy 105.577391 -76.878165) (xy 105.607358 -76.877672)
			(xy 106.470958 -76.877672) (xy 106.500928 -76.878178) (xy 106.560354 -76.885997) (xy 106.618252 -76.901506)
			(xy 106.67363 -76.92444) (xy 106.72554 -76.954406) (xy 106.773095 -76.990892) (xy 106.81548 -77.033273)
			(xy 106.851971 -77.080825) (xy 106.881942 -77.132732) (xy 106.904881 -77.188108) (xy 106.920395 -77.246004)
			(xy 106.928219 -77.305431) (xy 106.928219 -77.365367) (xy 109.150162 -77.365367) (xy 109.150162 -77.305433)
			(xy 109.157984 -77.246012) (xy 109.173495 -77.18812) (xy 109.196429 -77.132748) (xy 109.226394 -77.080843)
			(xy 109.262878 -77.033292) (xy 109.305255 -76.990911) (xy 109.352801 -76.954422) (xy 109.404703 -76.924452)
			(xy 109.460073 -76.901511) (xy 109.517963 -76.885994) (xy 109.577383 -76.878165) (xy 109.60735 -76.877672)
			(xy 110.47095 -76.877672) (xy 110.50092 -76.878178) (xy 110.560347 -76.885996) (xy 110.618246 -76.901504)
			(xy 110.673625 -76.924437) (xy 110.725536 -76.954403) (xy 110.773092 -76.990889) (xy 110.815478 -77.03327)
			(xy 110.851969 -77.080822) (xy 110.881941 -77.13273) (xy 110.90488 -77.188107) (xy 110.920395 -77.246003)
			(xy 110.928219 -77.30543) (xy 110.928219 -77.36537) (xy 110.920395 -77.424797) (xy 110.90488 -77.482693)
			(xy 110.881941 -77.53807) (xy 110.851969 -77.589978) (xy 110.815478 -77.63753) (xy 110.773092 -77.679911)
			(xy 110.725536 -77.716397) (xy 110.673625 -77.746363) (xy 110.618246 -77.769296) (xy 110.560347 -77.784804)
			(xy 110.50092 -77.792622) (xy 110.47095 -77.793088) (xy 109.60735 -77.793088) (xy 109.577383 -77.792635)
			(xy 109.517963 -77.784806) (xy 109.460073 -77.769289) (xy 109.404703 -77.746348) (xy 109.352801 -77.716378)
			(xy 109.305255 -77.679889) (xy 109.262878 -77.637508) (xy 109.226394 -77.589957) (xy 109.196429 -77.538052)
			(xy 109.173495 -77.48268) (xy 109.157984 -77.424788) (xy 109.150162 -77.365367) (xy 106.928219 -77.365367)
			(xy 106.928219 -77.365369) (xy 106.920395 -77.424796) (xy 106.904881 -77.482692) (xy 106.881942 -77.538068)
			(xy 106.851971 -77.589975) (xy 106.81548 -77.637527) (xy 106.773095 -77.679908) (xy 106.72554 -77.716394)
			(xy 106.67363 -77.74636) (xy 106.618252 -77.769294) (xy 106.560354 -77.784803) (xy 106.500928 -77.792622)
			(xy 106.470958 -77.793088) (xy 105.607358 -77.793088) (xy 105.577391 -77.792635) (xy 105.51797 -77.784807)
			(xy 105.460079 -77.769291) (xy 105.404708 -77.746351) (xy 105.352805 -77.716381) (xy 105.305258 -77.679892)
			(xy 105.26288 -77.63751) (xy 105.226396 -77.58996) (xy 105.19643 -77.538054) (xy 105.173496 -77.482681)
			(xy 105.157985 -77.424789) (xy 105.150162 -77.365367) (xy 83.412368 -77.365367) (xy 83.399267 -77.393314)
			(xy 83.368494 -77.439827) (xy 83.331277 -77.481364) (xy 83.288409 -77.517039) (xy 83.240803 -77.546093)
			(xy 83.189474 -77.567905) (xy 83.135517 -77.582011) (xy 83.08008 -77.588111) (xy 83.024346 -77.586074)
			(xy 82.969503 -77.575944) (xy 82.916719 -77.557937) (xy 82.867119 -77.532436) (xy 82.821761 -77.499985)
			(xy 82.781612 -77.461276) (xy 82.747526 -77.417133) (xy 82.72023 -77.368498) (xy 82.700307 -77.316407)
			(xy 82.688181 -77.26197) (xy 82.68411 -77.206348) (xy 0.662686 -77.206348) (xy 0.662686 -78.58887)
			(xy 41.399966 -78.58887) (xy 41.404037 -78.533248) (xy 41.416163 -78.478811) (xy 41.436086 -78.42672)
			(xy 41.463382 -78.378085) (xy 41.497468 -78.333942) (xy 41.537617 -78.295233) (xy 41.582975 -78.262782)
			(xy 41.632575 -78.237281) (xy 41.685359 -78.219274) (xy 41.740202 -78.209144) (xy 41.795936 -78.207107)
			(xy 41.851373 -78.213207) (xy 41.90533 -78.227313) (xy 41.912773 -78.230476) (xy 65.148204 -78.230476)
			(xy 65.152275 -78.174854) (xy 65.164401 -78.120417) (xy 65.184324 -78.068326) (xy 65.21162 -78.019691)
			(xy 65.245706 -77.975548) (xy 65.285855 -77.936839) (xy 65.331213 -77.904388) (xy 65.380813 -77.878887)
			(xy 65.433597 -77.86088) (xy 65.48844 -77.85075) (xy 65.544174 -77.848713) (xy 65.599611 -77.854813)
			(xy 65.653568 -77.868919) (xy 65.704897 -77.890731) (xy 65.752503 -77.919785) (xy 65.795371 -77.95546)
			(xy 65.832588 -77.996997) (xy 65.863361 -78.04351) (xy 65.887033 -78.094007) (xy 65.89707 -78.127367)
			(xy 107.150162 -78.127367) (xy 107.150162 -78.067433) (xy 107.157984 -78.008012) (xy 107.173496 -77.950119)
			(xy 107.19643 -77.894747) (xy 107.226395 -77.842842) (xy 107.262879 -77.795291) (xy 107.305256 -77.752909)
			(xy 107.352803 -77.716421) (xy 107.404706 -77.68645) (xy 107.460076 -77.66351) (xy 107.517966 -77.647993)
			(xy 107.577387 -77.640165) (xy 107.607354 -77.639672) (xy 108.470954 -77.639672) (xy 108.500924 -77.640178)
			(xy 108.560351 -77.647996) (xy 108.618249 -77.663505) (xy 108.673627 -77.686438) (xy 108.725538 -77.716405)
			(xy 108.773094 -77.752891) (xy 108.815479 -77.795272) (xy 108.85197 -77.842823) (xy 108.881941 -77.894731)
			(xy 108.90488 -77.950107) (xy 108.920395 -78.008004) (xy 108.928219 -78.06743) (xy 108.928219 -78.12737)
			(xy 108.920395 -78.186796) (xy 108.90488 -78.244693) (xy 108.881941 -78.300069) (xy 108.85197 -78.351977)
			(xy 108.815479 -78.399528) (xy 108.773093 -78.441909) (xy 108.725538 -78.478395) (xy 108.673627 -78.508362)
			(xy 108.618249 -78.531295) (xy 108.560351 -78.546804) (xy 108.500924 -78.554622) (xy 108.470954 -78.555088)
			(xy 107.607354 -78.555088) (xy 107.577387 -78.554635) (xy 107.517966 -78.546807) (xy 107.460076 -78.53129)
			(xy 107.404706 -78.50835) (xy 107.352803 -78.478379) (xy 107.305256 -78.441891) (xy 107.262879 -78.399509)
			(xy 107.226395 -78.351958) (xy 107.19643 -78.300053) (xy 107.173496 -78.244681) (xy 107.157984 -78.186788)
			(xy 107.150162 -78.127367) (xy 65.89707 -78.127367) (xy 65.903101 -78.147414) (xy 65.911221 -78.20259)
			(xy 65.91173 -78.230476) (xy 65.911221 -78.258362) (xy 65.903101 -78.313538) (xy 65.887033 -78.366945)
			(xy 65.863361 -78.417442) (xy 65.832588 -78.463955) (xy 65.795371 -78.505492) (xy 65.752503 -78.541167)
			(xy 65.704897 -78.570221) (xy 65.653568 -78.592033) (xy 65.599611 -78.606139) (xy 65.544174 -78.612239)
			(xy 65.48844 -78.610202) (xy 65.433597 -78.600072) (xy 65.380813 -78.582065) (xy 65.331213 -78.556564)
			(xy 65.285855 -78.524113) (xy 65.245706 -78.485404) (xy 65.21162 -78.441261) (xy 65.184324 -78.392626)
			(xy 65.164401 -78.340535) (xy 65.152275 -78.286098) (xy 65.148204 -78.230476) (xy 41.912773 -78.230476)
			(xy 41.956659 -78.249125) (xy 42.004265 -78.278179) (xy 42.047133 -78.313854) (xy 42.08435 -78.355391)
			(xy 42.115123 -78.401904) (xy 42.138795 -78.452401) (xy 42.154863 -78.505808) (xy 42.162983 -78.560984)
			(xy 42.163492 -78.58887) (xy 42.162983 -78.616756) (xy 42.154863 -78.671932) (xy 42.144242 -78.707234)
			(xy 150.214582 -78.707234) (xy 150.218653 -78.651612) (xy 150.230779 -78.597175) (xy 150.250702 -78.545084)
			(xy 150.277998 -78.496449) (xy 150.312084 -78.452306) (xy 150.352233 -78.413597) (xy 150.397591 -78.381146)
			(xy 150.447191 -78.355645) (xy 150.499975 -78.337638) (xy 150.554818 -78.327508) (xy 150.610552 -78.325471)
			(xy 150.665989 -78.331571) (xy 150.719946 -78.345677) (xy 150.771275 -78.367489) (xy 150.818881 -78.396543)
			(xy 150.861749 -78.432218) (xy 150.898966 -78.473755) (xy 150.929739 -78.520268) (xy 150.953411 -78.570765)
			(xy 150.969479 -78.624172) (xy 150.977599 -78.679348) (xy 150.978108 -78.707234) (xy 150.977599 -78.73512)
			(xy 150.969479 -78.790296) (xy 150.953411 -78.843703) (xy 150.929739 -78.8942) (xy 150.898966 -78.940713)
			(xy 150.861749 -78.98225) (xy 150.818881 -79.017925) (xy 150.771275 -79.046979) (xy 150.719946 -79.068791)
			(xy 150.665989 -79.082897) (xy 150.610552 -79.088997) (xy 150.554818 -79.08696) (xy 150.499975 -79.07683)
			(xy 150.447191 -79.058823) (xy 150.397591 -79.033322) (xy 150.352233 -79.000871) (xy 150.312084 -78.962162)
			(xy 150.277998 -78.918019) (xy 150.250702 -78.869384) (xy 150.230779 -78.817293) (xy 150.218653 -78.762856)
			(xy 150.214582 -78.707234) (xy 42.144242 -78.707234) (xy 42.138795 -78.725339) (xy 42.115123 -78.775836)
			(xy 42.08435 -78.822349) (xy 42.047133 -78.863886) (xy 42.004265 -78.899561) (xy 41.956659 -78.928615)
			(xy 41.90533 -78.950427) (xy 41.851373 -78.964533) (xy 41.795936 -78.970633) (xy 41.740202 -78.968596)
			(xy 41.685359 -78.958466) (xy 41.632575 -78.940459) (xy 41.582975 -78.914958) (xy 41.537617 -78.882507)
			(xy 41.497468 -78.843798) (xy 41.463382 -78.799655) (xy 41.436086 -78.75102) (xy 41.416163 -78.698929)
			(xy 41.404037 -78.644492) (xy 41.399966 -78.58887) (xy 0.662686 -78.58887) (xy 0.662686 -79.164434)
			(xy 42.852592 -79.164434) (xy 42.856663 -79.108812) (xy 42.868789 -79.054375) (xy 42.888712 -79.002284)
			(xy 42.916008 -78.953649) (xy 42.950094 -78.909506) (xy 42.990243 -78.870797) (xy 43.035601 -78.838346)
			(xy 43.085201 -78.812845) (xy 43.137985 -78.794838) (xy 43.192828 -78.784708) (xy 43.248562 -78.782671)
			(xy 43.303999 -78.788771) (xy 43.357956 -78.802877) (xy 43.409285 -78.824689) (xy 43.456891 -78.853743)
			(xy 43.499759 -78.889418) (xy 43.536976 -78.930955) (xy 43.567749 -78.977468) (xy 43.591421 -79.027965)
			(xy 43.607489 -79.081372) (xy 43.615609 -79.136548) (xy 43.616118 -79.164434) (xy 43.615798 -79.18196)
			(xy 79.591662 -79.18196) (xy 79.592148 -79.154709) (xy 79.599904 -79.100761) (xy 79.615259 -79.048466)
			(xy 79.637901 -78.998889) (xy 79.667367 -78.953039) (xy 79.703058 -78.911848) (xy 79.744249 -78.876157)
			(xy 79.790099 -78.846691) (xy 79.839676 -78.824049) (xy 79.891971 -78.808694) (xy 79.945919 -78.800938)
			(xy 80.000421 -78.800938) (xy 80.054369 -78.808694) (xy 80.106664 -78.824049) (xy 80.156241 -78.846691)
			(xy 80.202091 -78.876157) (xy 80.243282 -78.911848) (xy 80.278973 -78.953039) (xy 80.308439 -78.998889)
			(xy 80.331081 -79.048466) (xy 80.346436 -79.100761) (xy 80.354192 -79.154709) (xy 80.354678 -79.18196)
			(xy 80.354093 -79.210842) (xy 80.345378 -79.267945) (xy 80.328157 -79.323083) (xy 80.302823 -79.374995)
			(xy 80.269955 -79.422497) (xy 80.230304 -79.464502) (xy 80.207866 -79.482696) (xy 80.19695 -79.491864)
			(xy 80.180205 -79.514917) (xy 80.17047 -79.541695) (xy 80.168502 -79.570119) (xy 80.174454 -79.597983)
			(xy 80.187863 -79.623123) (xy 80.207689 -79.643587) (xy 80.219804 -79.651098) (xy 80.244418 -79.665742)
			(xy 80.289288 -79.701335) (xy 80.328334 -79.743237) (xy 80.360676 -79.790504) (xy 80.385589 -79.842076)
			(xy 80.402512 -79.896792) (xy 80.411065 -79.953423) (xy 80.411574 -79.98206) (xy 80.411088 -80.009311)
			(xy 80.403332 -80.063259) (xy 80.387977 -80.115554) (xy 80.386651 -80.118458) (xy 88.214706 -80.118458)
			(xy 88.218777 -80.062836) (xy 88.230903 -80.008399) (xy 88.250826 -79.956308) (xy 88.278122 -79.907673)
			(xy 88.312208 -79.86353) (xy 88.352357 -79.824821) (xy 88.397715 -79.79237) (xy 88.447315 -79.766869)
			(xy 88.500099 -79.748862) (xy 88.554942 -79.738732) (xy 88.610676 -79.736695) (xy 88.666113 -79.742795)
			(xy 88.72007 -79.756901) (xy 88.771399 -79.778713) (xy 88.819005 -79.807767) (xy 88.861873 -79.843442)
			(xy 88.89909 -79.884979) (xy 88.929863 -79.931492) (xy 88.953535 -79.981989) (xy 88.969603 -80.035396)
			(xy 88.975777 -80.077352) (xy 102.068087 -80.077352) (xy 102.068087 -80.022848) (xy 102.075844 -79.9689)
			(xy 102.0912 -79.916605) (xy 102.113842 -79.867027) (xy 102.14331 -79.821177) (xy 102.179003 -79.779987)
			(xy 102.220195 -79.744297) (xy 102.266047 -79.714832) (xy 102.315626 -79.692192) (xy 102.367922 -79.67684)
			(xy 102.42187 -79.669086) (xy 102.449122 -79.668624) (xy 102.476493 -79.669071) (xy 102.530673 -79.676893)
			(xy 102.583177 -79.692386) (xy 102.632923 -79.715232) (xy 102.678889 -79.744961) (xy 102.69982 -79.762604)
			(xy 102.700074 -79.762858) (xy 102.707159 -79.768447) (xy 102.724077 -79.774691) (xy 102.733094 -79.77505)
			(xy 102.80015 -79.77505) (xy 102.809166 -79.77468) (xy 102.826083 -79.768443) (xy 102.83317 -79.762858)
			(xy 102.83317 -79.762604) (xy 102.833424 -79.762604) (xy 102.854374 -79.744988) (xy 102.900342 -79.715272)
			(xy 102.950085 -79.692432) (xy 103.002582 -79.676935) (xy 103.056754 -79.669101) (xy 103.084122 -79.668624)
			(xy 103.111375 -79.669047) (xy 103.165324 -79.676807) (xy 103.217621 -79.692165) (xy 103.267199 -79.71481)
			(xy 103.296199 -79.733448) (xy 129.613694 -79.733448) (xy 129.613694 -79.678952) (xy 129.621449 -79.62501)
			(xy 129.636802 -79.572721) (xy 129.659439 -79.523148) (xy 129.6889 -79.477302) (xy 129.724586 -79.436114)
			(xy 129.76577 -79.400424) (xy 129.811613 -79.370958) (xy 129.861183 -79.348316) (xy 129.913471 -79.332958)
			(xy 129.967412 -79.325197) (xy 129.99466 -79.324708) (xy 130.020371 -79.325106) (xy 130.071326 -79.332009)
			(xy 130.120892 -79.345696) (xy 130.16817 -79.365918) (xy 130.212302 -79.392309) (xy 130.232658 -79.40802)
			(xy 130.243716 -79.416334) (xy 130.269185 -79.427123) (xy 130.296614 -79.430678) (xy 130.323992 -79.426739)
			(xy 130.349307 -79.415595) (xy 130.370701 -79.398064) (xy 130.386603 -79.375434) (xy 130.391662 -79.362554)
			(xy 130.402017 -79.335086) (xy 130.429878 -79.283422) (xy 130.465323 -79.236634) (xy 130.507515 -79.195826)
			(xy 130.55546 -79.161962) (xy 130.608025 -79.13584) (xy 130.663971 -79.118076) (xy 130.721977 -79.109091)
			(xy 130.751326 -79.108554) (xy 130.778573 -79.109118) (xy 130.832513 -79.116877) (xy 130.884799 -79.132233)
			(xy 130.934368 -79.154873) (xy 130.980211 -79.184337) (xy 131.021394 -79.220025) (xy 131.057079 -79.26121)
			(xy 131.08654 -79.307055) (xy 131.109177 -79.356625) (xy 131.124529 -79.408913) (xy 131.132284 -79.462853)
			(xy 131.132284 -79.517347) (xy 131.124529 -79.571287) (xy 131.109177 -79.623575) (xy 131.08654 -79.673145)
			(xy 131.057079 -79.71899) (xy 131.021394 -79.760175) (xy 130.980211 -79.795863) (xy 130.934368 -79.825327)
			(xy 130.893738 -79.843884) (xy 131.606034 -79.843884) (xy 131.610105 -79.788262) (xy 131.622231 -79.733825)
			(xy 131.642154 -79.681734) (xy 131.66945 -79.633099) (xy 131.703536 -79.588956) (xy 131.743685 -79.550247)
			(xy 131.789043 -79.517796) (xy 131.838643 -79.492295) (xy 131.891427 -79.474288) (xy 131.94627 -79.464158)
			(xy 132.002004 -79.462121) (xy 132.057441 -79.468221) (xy 132.111398 -79.482327) (xy 132.162727 -79.504139)
			(xy 132.210333 -79.533193) (xy 132.253201 -79.568868) (xy 132.290418 -79.610405) (xy 132.321191 -79.656918)
			(xy 132.344863 -79.707415) (xy 132.360931 -79.760822) (xy 132.369051 -79.815998) (xy 132.36956 -79.843884)
			(xy 132.369051 -79.87177) (xy 132.360931 -79.926946) (xy 132.344863 -79.980353) (xy 132.321191 -80.03085)
			(xy 132.290418 -80.077363) (xy 132.253201 -80.1189) (xy 132.210333 -80.154575) (xy 132.162727 -80.183629)
			(xy 132.111398 -80.205441) (xy 132.057441 -80.219547) (xy 132.002004 -80.225647) (xy 131.94627 -80.22361)
			(xy 131.891427 -80.21348) (xy 131.838643 -80.195473) (xy 131.789043 -80.169972) (xy 131.743685 -80.137521)
			(xy 131.703536 -80.098812) (xy 131.66945 -80.054669) (xy 131.642154 -80.006034) (xy 131.622231 -79.953943)
			(xy 131.610105 -79.899506) (xy 131.606034 -79.843884) (xy 130.893738 -79.843884) (xy 130.884799 -79.847967)
			(xy 130.832513 -79.863323) (xy 130.778573 -79.871082) (xy 130.751326 -79.87157) (xy 130.725617 -79.871129)
			(xy 130.674663 -79.864237) (xy 130.625097 -79.850561) (xy 130.577819 -79.830348) (xy 130.533685 -79.803966)
			(xy 130.513328 -79.788258) (xy 130.502192 -79.780056) (xy 130.476747 -79.769262) (xy 130.449338 -79.765695)
			(xy 130.421978 -79.769617) (xy 130.396675 -79.780741) (xy 130.375287 -79.798249) (xy 130.359385 -79.820856)
			(xy 130.354324 -79.833724) (xy 130.343969 -79.861192) (xy 130.316109 -79.912857) (xy 130.280665 -79.959647)
			(xy 130.238473 -80.000455) (xy 130.190528 -80.03432) (xy 130.137962 -80.060441) (xy 130.082016 -80.078204)
			(xy 130.024009 -80.087188) (xy 129.99466 -80.087724) (xy 129.967412 -80.087203) (xy 129.913471 -80.079442)
			(xy 129.861183 -80.064084) (xy 129.811613 -80.041442) (xy 129.76577 -80.011976) (xy 129.724586 -79.976286)
			(xy 129.6889 -79.935098) (xy 129.659439 -79.889252) (xy 129.636802 -79.839679) (xy 129.621449 -79.78739)
			(xy 129.613694 -79.733448) (xy 103.296199 -79.733448) (xy 103.313051 -79.744279) (xy 103.354242 -79.779974)
			(xy 103.389934 -79.821167) (xy 103.419401 -79.86702) (xy 103.442042 -79.9166) (xy 103.457398 -79.968897)
			(xy 103.465154 -80.022847) (xy 103.465154 -80.077353) (xy 103.457398 -80.131303) (xy 103.442042 -80.1836)
			(xy 103.419401 -80.23318) (xy 103.389934 -80.279033) (xy 103.354242 -80.320226) (xy 103.313051 -80.355921)
			(xy 103.267199 -80.38539) (xy 103.217621 -80.408035) (xy 103.165324 -80.423393) (xy 103.111375 -80.431153)
			(xy 103.084122 -80.43164) (xy 103.056752 -80.431176) (xy 103.002572 -80.42336) (xy 102.950068 -80.407871)
			(xy 102.900321 -80.385028) (xy 102.854355 -80.355302) (xy 102.833424 -80.33766) (xy 102.83317 -80.337406)
			(xy 102.826067 -80.331843) (xy 102.809163 -80.325582) (xy 102.80015 -80.325214) (xy 102.733094 -80.325214)
			(xy 102.724076 -80.325565) (xy 102.707159 -80.331816) (xy 102.700074 -80.337406) (xy 102.700074 -80.33766)
			(xy 102.69982 -80.33766) (xy 102.678886 -80.355297) (xy 102.632914 -80.38501) (xy 102.583167 -80.407847)
			(xy 102.530667 -80.423339) (xy 102.476491 -80.431167) (xy 102.449122 -80.43164) (xy 102.42187 -80.431114)
			(xy 102.367922 -80.42336) (xy 102.315626 -80.408008) (xy 102.266047 -80.385368) (xy 102.220195 -80.355903)
			(xy 102.179003 -80.320213) (xy 102.14331 -80.279023) (xy 102.113842 -80.233173) (xy 102.0912 -80.183595)
			(xy 102.075844 -80.1313) (xy 102.068087 -80.077352) (xy 88.975777 -80.077352) (xy 88.977723 -80.090572)
			(xy 88.978232 -80.118458) (xy 88.977723 -80.146344) (xy 88.969603 -80.20152) (xy 88.953535 -80.254927)
			(xy 88.929863 -80.305424) (xy 88.89909 -80.351937) (xy 88.861873 -80.393474) (xy 88.819005 -80.429149)
			(xy 88.771399 -80.458203) (xy 88.72007 -80.480015) (xy 88.666113 -80.494121) (xy 88.610676 -80.500221)
			(xy 88.554942 -80.498184) (xy 88.500099 -80.488054) (xy 88.447315 -80.470047) (xy 88.397715 -80.444546)
			(xy 88.352357 -80.412095) (xy 88.312208 -80.373386) (xy 88.278122 -80.329243) (xy 88.250826 -80.280608)
			(xy 88.230903 -80.228517) (xy 88.218777 -80.17408) (xy 88.214706 -80.118458) (xy 80.386651 -80.118458)
			(xy 80.365335 -80.165131) (xy 80.335869 -80.210981) (xy 80.300178 -80.252172) (xy 80.258987 -80.287863)
			(xy 80.213137 -80.317329) (xy 80.16356 -80.339971) (xy 80.111265 -80.355326) (xy 80.057317 -80.363082)
			(xy 80.002815 -80.363082) (xy 79.948867 -80.355326) (xy 79.896572 -80.339971) (xy 79.846995 -80.317329)
			(xy 79.801145 -80.287863) (xy 79.759954 -80.252172) (xy 79.724263 -80.210981) (xy 79.694797 -80.165131)
			(xy 79.672155 -80.115554) (xy 79.6568 -80.063259) (xy 79.649044 -80.009311) (xy 79.648558 -79.98206)
			(xy 79.649073 -79.953175) (xy 79.6578 -79.896068) (xy 79.675034 -79.840929) (xy 79.700381 -79.789016)
			(xy 79.733262 -79.741517) (xy 79.772926 -79.699515) (xy 79.79537 -79.681324) (xy 79.806276 -79.672141)
			(xy 79.823033 -79.649095) (xy 79.832777 -79.622319) (xy 79.834749 -79.593893) (xy 79.828797 -79.566027)
			(xy 79.815384 -79.540887) (xy 79.795551 -79.520428) (xy 79.783432 -79.512922) (xy 79.758835 -79.49825)
			(xy 79.713963 -79.462663) (xy 79.674916 -79.420767) (xy 79.64257 -79.373504) (xy 79.617655 -79.321937)
			(xy 79.600729 -79.267224) (xy 79.592172 -79.210596) (xy 79.591662 -79.18196) (xy 43.615798 -79.18196)
			(xy 43.615609 -79.19232) (xy 43.607489 -79.247496) (xy 43.591421 -79.300903) (xy 43.567749 -79.3514)
			(xy 43.536976 -79.397913) (xy 43.499759 -79.43945) (xy 43.456891 -79.475125) (xy 43.409285 -79.504179)
			(xy 43.357956 -79.525991) (xy 43.303999 -79.540097) (xy 43.248562 -79.546197) (xy 43.192828 -79.54416)
			(xy 43.137985 -79.53403) (xy 43.085201 -79.516023) (xy 43.035601 -79.490522) (xy 42.990243 -79.458071)
			(xy 42.950094 -79.419362) (xy 42.916008 -79.375219) (xy 42.888712 -79.326584) (xy 42.868789 -79.274493)
			(xy 42.856663 -79.220056) (xy 42.852592 -79.164434) (xy 0.662686 -79.164434) (xy 0.662686 -79.727552)
			(xy 58.25185 -79.727552) (xy 58.255921 -79.67193) (xy 58.268047 -79.617493) (xy 58.28797 -79.565402)
			(xy 58.315266 -79.516767) (xy 58.349352 -79.472624) (xy 58.389501 -79.433915) (xy 58.434859 -79.401464)
			(xy 58.484459 -79.375963) (xy 58.537243 -79.357956) (xy 58.592086 -79.347826) (xy 58.64782 -79.345789)
			(xy 58.703257 -79.351889) (xy 58.757214 -79.365995) (xy 58.808543 -79.387807) (xy 58.856149 -79.416861)
			(xy 58.899017 -79.452536) (xy 58.936234 -79.494073) (xy 58.967007 -79.540586) (xy 58.990679 -79.591083)
			(xy 59.006747 -79.64449) (xy 59.014867 -79.699666) (xy 59.015376 -79.727552) (xy 59.014867 -79.755438)
			(xy 59.006747 -79.810614) (xy 58.990679 -79.864021) (xy 58.967007 -79.914518) (xy 58.936234 -79.961031)
			(xy 58.899017 -80.002568) (xy 58.878183 -80.019906) (xy 72.500742 -80.019906) (xy 72.504813 -79.964284)
			(xy 72.516939 -79.909847) (xy 72.536862 -79.857756) (xy 72.564158 -79.809121) (xy 72.598244 -79.764978)
			(xy 72.638393 -79.726269) (xy 72.683751 -79.693818) (xy 72.733351 -79.668317) (xy 72.786135 -79.65031)
			(xy 72.840978 -79.64018) (xy 72.896712 -79.638143) (xy 72.952149 -79.644243) (xy 73.006106 -79.658349)
			(xy 73.057435 -79.680161) (xy 73.105041 -79.709215) (xy 73.147909 -79.74489) (xy 73.185126 -79.786427)
			(xy 73.215899 -79.83294) (xy 73.239571 -79.883437) (xy 73.255639 -79.936844) (xy 73.263759 -79.99202)
			(xy 73.264268 -80.019906) (xy 73.263759 -80.047792) (xy 73.255639 -80.102968) (xy 73.239571 -80.156375)
			(xy 73.215899 -80.206872) (xy 73.185126 -80.253385) (xy 73.147909 -80.294922) (xy 73.105041 -80.330597)
			(xy 73.057435 -80.359651) (xy 73.006106 -80.381463) (xy 72.952149 -80.395569) (xy 72.896712 -80.401669)
			(xy 72.840978 -80.399632) (xy 72.786135 -80.389502) (xy 72.733351 -80.371495) (xy 72.683751 -80.345994)
			(xy 72.638393 -80.313543) (xy 72.598244 -80.274834) (xy 72.564158 -80.230691) (xy 72.536862 -80.182056)
			(xy 72.516939 -80.129965) (xy 72.504813 -80.075528) (xy 72.500742 -80.019906) (xy 58.878183 -80.019906)
			(xy 58.856149 -80.038243) (xy 58.808543 -80.067297) (xy 58.757214 -80.089109) (xy 58.703257 -80.103215)
			(xy 58.64782 -80.109315) (xy 58.592086 -80.107278) (xy 58.537243 -80.097148) (xy 58.484459 -80.079141)
			(xy 58.434859 -80.05364) (xy 58.389501 -80.021189) (xy 58.349352 -79.98248) (xy 58.315266 -79.938337)
			(xy 58.28797 -79.889702) (xy 58.268047 -79.837611) (xy 58.255921 -79.783174) (xy 58.25185 -79.727552)
			(xy 0.662686 -79.727552) (xy 0.662686 -81.120488) (xy 88.099136 -81.120488) (xy 88.103207 -81.064866)
			(xy 88.115333 -81.010429) (xy 88.135256 -80.958338) (xy 88.162552 -80.909703) (xy 88.196638 -80.86556)
			(xy 88.236787 -80.826851) (xy 88.282145 -80.7944) (xy 88.331745 -80.768899) (xy 88.384529 -80.750892)
			(xy 88.439372 -80.740762) (xy 88.495106 -80.738725) (xy 88.550543 -80.744825) (xy 88.6045 -80.758931)
			(xy 88.655829 -80.780743) (xy 88.703435 -80.809797) (xy 88.746303 -80.845472) (xy 88.78352 -80.887009)
			(xy 88.814293 -80.933522) (xy 88.837965 -80.984019) (xy 88.854033 -81.037426) (xy 88.862153 -81.092602)
			(xy 88.862662 -81.120488) (xy 88.862153 -81.148374) (xy 88.854033 -81.20355) (xy 88.837965 -81.256957)
			(xy 88.814293 -81.307454) (xy 88.78352 -81.353967) (xy 88.746303 -81.395504) (xy 88.703435 -81.431179)
			(xy 88.655829 -81.460233) (xy 88.6045 -81.482045) (xy 88.550543 -81.496151) (xy 88.495106 -81.502251)
			(xy 88.439372 -81.500214) (xy 88.384529 -81.490084) (xy 88.331745 -81.472077) (xy 88.282145 -81.446576)
			(xy 88.236787 -81.414125) (xy 88.196638 -81.375416) (xy 88.162552 -81.331273) (xy 88.135256 -81.282638)
			(xy 88.115333 -81.230547) (xy 88.103207 -81.17611) (xy 88.099136 -81.120488) (xy 0.662686 -81.120488)
			(xy 0.662686 -81.839308) (xy 88.80551 -81.839308) (xy 88.809581 -81.783686) (xy 88.821707 -81.729249)
			(xy 88.84163 -81.677158) (xy 88.868926 -81.628523) (xy 88.903012 -81.58438) (xy 88.943161 -81.545671)
			(xy 88.988519 -81.51322) (xy 89.038119 -81.487719) (xy 89.090903 -81.469712) (xy 89.145746 -81.459582)
			(xy 89.20148 -81.457545) (xy 89.256917 -81.463645) (xy 89.310874 -81.477751) (xy 89.362203 -81.499563)
			(xy 89.409809 -81.528617) (xy 89.452677 -81.564292) (xy 89.489894 -81.605829) (xy 89.520667 -81.652342)
			(xy 89.544339 -81.702839) (xy 89.560407 -81.756246) (xy 89.568527 -81.811422) (xy 89.569036 -81.839308)
			(xy 89.568527 -81.867194) (xy 89.560407 -81.92237) (xy 89.544339 -81.975777) (xy 89.520667 -82.026274)
			(xy 89.489894 -82.072787) (xy 89.452677 -82.114324) (xy 89.409809 -82.149999) (xy 89.362203 -82.179053)
			(xy 89.310874 -82.200865) (xy 89.256917 -82.214971) (xy 89.20148 -82.221071) (xy 89.145746 -82.219034)
			(xy 89.090903 -82.208904) (xy 89.038119 -82.190897) (xy 88.988519 -82.165396) (xy 88.943161 -82.132945)
			(xy 88.903012 -82.094236) (xy 88.868926 -82.050093) (xy 88.84163 -82.001458) (xy 88.821707 -81.949367)
			(xy 88.809581 -81.89493) (xy 88.80551 -81.839308) (xy 0.662686 -81.839308) (xy 0.662686 -82.427572)
			(xy 78.932784 -82.427572) (xy 78.936855 -82.37195) (xy 78.948981 -82.317513) (xy 78.968904 -82.265422)
			(xy 78.9962 -82.216787) (xy 79.030286 -82.172644) (xy 79.070435 -82.133935) (xy 79.115793 -82.101484)
			(xy 79.165393 -82.075983) (xy 79.218177 -82.057976) (xy 79.27302 -82.047846) (xy 79.328754 -82.045809)
			(xy 79.384191 -82.051909) (xy 79.438148 -82.066015) (xy 79.489477 -82.087827) (xy 79.537083 -82.116881)
			(xy 79.579951 -82.152556) (xy 79.617168 -82.194093) (xy 79.647941 -82.240606) (xy 79.671613 -82.291103)
			(xy 79.687681 -82.34451) (xy 79.692578 -82.377788) (xy 80.519014 -82.377788) (xy 80.523085 -82.322166)
			(xy 80.535211 -82.267729) (xy 80.555134 -82.215638) (xy 80.58243 -82.167003) (xy 80.616516 -82.12286)
			(xy 80.656665 -82.084151) (xy 80.702023 -82.0517) (xy 80.751623 -82.026199) (xy 80.804407 -82.008192)
			(xy 80.85925 -81.998062) (xy 80.914984 -81.996025) (xy 80.970421 -82.002125) (xy 81.024378 -82.016231)
			(xy 81.075707 -82.038043) (xy 81.123313 -82.067097) (xy 81.166181 -82.102772) (xy 81.203398 -82.144309)
			(xy 81.234171 -82.190822) (xy 81.257843 -82.241319) (xy 81.273911 -82.294726) (xy 81.282031 -82.349902)
			(xy 81.28254 -82.377788) (xy 81.282031 -82.405674) (xy 81.273911 -82.46085) (xy 81.257843 -82.514257)
			(xy 81.234171 -82.564754) (xy 81.203398 -82.611267) (xy 81.166181 -82.652804) (xy 81.123313 -82.688479)
			(xy 81.075707 -82.717533) (xy 81.024378 -82.739345) (xy 80.970421 -82.753451) (xy 80.914984 -82.759551)
			(xy 80.85925 -82.757514) (xy 80.804407 -82.747384) (xy 80.751623 -82.729377) (xy 80.702023 -82.703876)
			(xy 80.656665 -82.671425) (xy 80.616516 -82.632716) (xy 80.58243 -82.588573) (xy 80.555134 -82.539938)
			(xy 80.535211 -82.487847) (xy 80.523085 -82.43341) (xy 80.519014 -82.377788) (xy 79.692578 -82.377788)
			(xy 79.695801 -82.399686) (xy 79.69631 -82.427572) (xy 79.695801 -82.455458) (xy 79.687681 -82.510634)
			(xy 79.671613 -82.564041) (xy 79.647941 -82.614538) (xy 79.617168 -82.661051) (xy 79.579951 -82.702588)
			(xy 79.537083 -82.738263) (xy 79.489477 -82.767317) (xy 79.438148 -82.789129) (xy 79.384191 -82.803235)
			(xy 79.328754 -82.809335) (xy 79.27302 -82.807298) (xy 79.218177 -82.797168) (xy 79.165393 -82.779161)
			(xy 79.115793 -82.75366) (xy 79.070435 -82.721209) (xy 79.030286 -82.6825) (xy 78.9962 -82.638357)
			(xy 78.968904 -82.589722) (xy 78.948981 -82.537631) (xy 78.936855 -82.483194) (xy 78.932784 -82.427572)
			(xy 0.662686 -82.427572) (xy 0.662686 -82.69986) (xy 0.663448 -82.708242) (xy 0.664953 -82.715852)
			(xy 0.671923 -82.729702) (xy 0.677164 -82.73542) (xy 2.967282 -85.025538) (xy 44.856389 -85.025538)
			(xy 44.856389 -84.896398) (xy 44.864339 -84.767503) (xy 44.880209 -84.639343) (xy 44.903938 -84.512402)
			(xy 44.935437 -84.387163) (xy 44.974586 -84.2641) (xy 45.021237 -84.143681) (xy 45.075212 -84.026362)
			(xy 45.136307 -83.912588) (xy 45.20429 -83.802791) (xy 45.278904 -83.697388) (xy 45.359865 -83.596778)
			(xy 45.446865 -83.501343) (xy 45.539576 -83.411444) (xy 45.637646 -83.327423) (xy 45.740701 -83.249599)
			(xy 45.848352 -83.178267) (xy 45.960191 -83.113697) (xy 46.075792 -83.056135) (xy 46.194717 -83.005798)
			(xy 46.316516 -82.962878) (xy 46.440726 -82.927537) (xy 46.566875 -82.89991) (xy 46.694487 -82.880101)
			(xy 46.823076 -82.868185) (xy 46.952154 -82.864209) (xy 47.081232 -82.868185) (xy 47.209821 -82.880101)
			(xy 47.337433 -82.89991) (xy 47.463582 -82.927537) (xy 47.587792 -82.962878) (xy 47.709591 -83.005798)
			(xy 47.828516 -83.056135) (xy 47.944117 -83.113697) (xy 48.055956 -83.178267) (xy 48.163607 -83.249599)
			(xy 48.266662 -83.327423) (xy 48.364732 -83.411444) (xy 48.457443 -83.501343) (xy 48.485589 -83.532218)
			(xy 76.311504 -83.532218) (xy 76.315575 -83.476596) (xy 76.327701 -83.422159) (xy 76.347624 -83.370068)
			(xy 76.37492 -83.321433) (xy 76.409006 -83.27729) (xy 76.449155 -83.238581) (xy 76.494513 -83.20613)
			(xy 76.544113 -83.180629) (xy 76.596897 -83.162622) (xy 76.65174 -83.152492) (xy 76.707474 -83.150455)
			(xy 76.762911 -83.156555) (xy 76.816868 -83.170661) (xy 76.868197 -83.192473) (xy 76.915803 -83.221527)
			(xy 76.958671 -83.257202) (xy 76.995888 -83.298739) (xy 77.026661 -83.345252) (xy 77.050333 -83.395749)
			(xy 77.066401 -83.449156) (xy 77.074521 -83.504332) (xy 77.07503 -83.532218) (xy 77.074521 -83.560104)
			(xy 77.066401 -83.61528) (xy 77.050333 -83.668687) (xy 77.026661 -83.719184) (xy 76.995888 -83.765697)
			(xy 76.958671 -83.807234) (xy 76.915803 -83.842909) (xy 76.868197 -83.871963) (xy 76.816868 -83.893775)
			(xy 76.762911 -83.907881) (xy 76.707474 -83.913981) (xy 76.65174 -83.911944) (xy 76.596897 -83.901814)
			(xy 76.544113 -83.883807) (xy 76.494513 -83.858306) (xy 76.449155 -83.825855) (xy 76.409006 -83.787146)
			(xy 76.37492 -83.743003) (xy 76.347624 -83.694368) (xy 76.327701 -83.642277) (xy 76.315575 -83.58784)
			(xy 76.311504 -83.532218) (xy 48.485589 -83.532218) (xy 48.544443 -83.596778) (xy 48.625404 -83.697388)
			(xy 48.700018 -83.802791) (xy 48.768001 -83.912588) (xy 48.829096 -84.026362) (xy 48.883071 -84.143681)
			(xy 48.929722 -84.2641) (xy 48.968871 -84.387163) (xy 48.991299 -84.476336) (xy 79.867758 -84.476336)
			(xy 79.871829 -84.420714) (xy 79.883955 -84.366277) (xy 79.903878 -84.314186) (xy 79.931174 -84.265551)
			(xy 79.96526 -84.221408) (xy 80.005409 -84.182699) (xy 80.050767 -84.150248) (xy 80.100367 -84.124747)
			(xy 80.153151 -84.10674) (xy 80.207994 -84.09661) (xy 80.263728 -84.094573) (xy 80.319165 -84.100673)
			(xy 80.373122 -84.114779) (xy 80.424451 -84.136591) (xy 80.472057 -84.165645) (xy 80.514925 -84.20132)
			(xy 80.534893 -84.223606) (xy 101.470204 -84.223606) (xy 101.474275 -84.167984) (xy 101.486401 -84.113547)
			(xy 101.506324 -84.061456) (xy 101.53362 -84.012821) (xy 101.567706 -83.968678) (xy 101.607855 -83.929969)
			(xy 101.653213 -83.897518) (xy 101.702813 -83.872017) (xy 101.755597 -83.85401) (xy 101.81044 -83.84388)
			(xy 101.866174 -83.841843) (xy 101.921611 -83.847943) (xy 101.975568 -83.862049) (xy 102.026897 -83.883861)
			(xy 102.074503 -83.912915) (xy 102.117371 -83.94859) (xy 102.154588 -83.990127) (xy 102.185361 -84.03664)
			(xy 102.209033 -84.087137) (xy 102.225101 -84.140544) (xy 102.233221 -84.19572) (xy 102.23373 -84.223606)
			(xy 102.233221 -84.251492) (xy 102.225101 -84.306668) (xy 102.209033 -84.360075) (xy 102.185361 -84.410572)
			(xy 102.154588 -84.457085) (xy 102.117371 -84.498622) (xy 102.074503 -84.534297) (xy 102.026897 -84.563351)
			(xy 101.975568 -84.585163) (xy 101.921611 -84.599269) (xy 101.866174 -84.605369) (xy 101.81044 -84.603332)
			(xy 101.755597 -84.593202) (xy 101.702813 -84.575195) (xy 101.653213 -84.549694) (xy 101.607855 -84.517243)
			(xy 101.567706 -84.478534) (xy 101.53362 -84.434391) (xy 101.506324 -84.385756) (xy 101.486401 -84.333665)
			(xy 101.474275 -84.279228) (xy 101.470204 -84.223606) (xy 80.534893 -84.223606) (xy 80.552142 -84.242857)
			(xy 80.582915 -84.28937) (xy 80.606587 -84.339867) (xy 80.622655 -84.393274) (xy 80.630775 -84.44845)
			(xy 80.631284 -84.476336) (xy 80.630775 -84.504222) (xy 80.622655 -84.559398) (xy 80.606587 -84.612805)
			(xy 80.582915 -84.663302) (xy 80.552142 -84.709815) (xy 80.514925 -84.751352) (xy 80.472057 -84.787027)
			(xy 80.424451 -84.816081) (xy 80.373122 -84.837893) (xy 80.319165 -84.851999) (xy 80.263728 -84.858099)
			(xy 80.207994 -84.856062) (xy 80.153151 -84.845932) (xy 80.100367 -84.827925) (xy 80.050767 -84.802424)
			(xy 80.005409 -84.769973) (xy 79.96526 -84.731264) (xy 79.931174 -84.687121) (xy 79.903878 -84.638486)
			(xy 79.883955 -84.586395) (xy 79.871829 -84.531958) (xy 79.867758 -84.476336) (xy 48.991299 -84.476336)
			(xy 49.00037 -84.512402) (xy 49.024099 -84.639343) (xy 49.039969 -84.767503) (xy 49.047919 -84.896398)
			(xy 49.048416 -84.960968) (xy 49.047919 -85.025538) (xy 49.039969 -85.154433) (xy 49.024099 -85.282593)
			(xy 49.004976 -85.384894) (xy 59.304426 -85.384894) (xy 59.308497 -85.329272) (xy 59.320623 -85.274835)
			(xy 59.340546 -85.222744) (xy 59.367842 -85.174109) (xy 59.401928 -85.129966) (xy 59.442077 -85.091257)
			(xy 59.487435 -85.058806) (xy 59.537035 -85.033305) (xy 59.589819 -85.015298) (xy 59.644662 -85.005168)
			(xy 59.700396 -85.003131) (xy 59.755833 -85.009231) (xy 59.80979 -85.023337) (xy 59.861119 -85.045149)
			(xy 59.908725 -85.074203) (xy 59.951593 -85.109878) (xy 59.98881 -85.151415) (xy 60.019583 -85.197928)
			(xy 60.043255 -85.248425) (xy 60.059323 -85.301832) (xy 60.067443 -85.357008) (xy 60.067669 -85.3694)
			(xy 88.294462 -85.3694) (xy 88.298533 -85.313778) (xy 88.310659 -85.259341) (xy 88.330582 -85.20725)
			(xy 88.357878 -85.158615) (xy 88.391964 -85.114472) (xy 88.432113 -85.075763) (xy 88.477471 -85.043312)
			(xy 88.527071 -85.017811) (xy 88.579855 -84.999804) (xy 88.634698 -84.989674) (xy 88.690432 -84.987637)
			(xy 88.745869 -84.993737) (xy 88.799826 -85.007843) (xy 88.851155 -85.029655) (xy 88.898761 -85.058709)
			(xy 88.941629 -85.094384) (xy 88.978846 -85.135921) (xy 89.009619 -85.182434) (xy 89.033291 -85.232931)
			(xy 89.049359 -85.286338) (xy 89.057479 -85.341514) (xy 89.057988 -85.3694) (xy 89.057479 -85.397286)
			(xy 89.049359 -85.452462) (xy 89.033291 -85.505869) (xy 89.009619 -85.556366) (xy 88.978846 -85.602879)
			(xy 88.941629 -85.644416) (xy 88.898761 -85.680091) (xy 88.851155 -85.709145) (xy 88.799826 -85.730957)
			(xy 88.745869 -85.745063) (xy 88.690432 -85.751163) (xy 88.634698 -85.749126) (xy 88.579855 -85.738996)
			(xy 88.527071 -85.720989) (xy 88.477471 -85.695488) (xy 88.432113 -85.663037) (xy 88.391964 -85.624328)
			(xy 88.357878 -85.580185) (xy 88.330582 -85.53155) (xy 88.310659 -85.479459) (xy 88.298533 -85.425022)
			(xy 88.294462 -85.3694) (xy 60.067669 -85.3694) (xy 60.067952 -85.384894) (xy 60.067443 -85.41278)
			(xy 60.059323 -85.467956) (xy 60.043255 -85.521363) (xy 60.019583 -85.57186) (xy 59.98881 -85.618373)
			(xy 59.951593 -85.65991) (xy 59.908725 -85.695585) (xy 59.861119 -85.724639) (xy 59.80979 -85.746451)
			(xy 59.755833 -85.760557) (xy 59.700396 -85.766657) (xy 59.644662 -85.76462) (xy 59.589819 -85.75449)
			(xy 59.537035 -85.736483) (xy 59.487435 -85.710982) (xy 59.442077 -85.678531) (xy 59.401928 -85.639822)
			(xy 59.367842 -85.595679) (xy 59.340546 -85.547044) (xy 59.320623 -85.494953) (xy 59.308497 -85.440516)
			(xy 59.304426 -85.384894) (xy 49.004976 -85.384894) (xy 49.00037 -85.409534) (xy 48.968871 -85.534773)
			(xy 48.929722 -85.657836) (xy 48.883071 -85.778255) (xy 48.829096 -85.895574) (xy 48.768001 -86.009348)
			(xy 48.700018 -86.119145) (xy 48.625404 -86.224548) (xy 48.606543 -86.247986) (xy 75.238608 -86.247986)
			(xy 75.242679 -86.192364) (xy 75.254805 -86.137927) (xy 75.274728 -86.085836) (xy 75.302024 -86.037201)
			(xy 75.33611 -85.993058) (xy 75.376259 -85.954349) (xy 75.421617 -85.921898) (xy 75.471217 -85.896397)
			(xy 75.524001 -85.87839) (xy 75.578844 -85.86826) (xy 75.634578 -85.866223) (xy 75.690015 -85.872323)
			(xy 75.743972 -85.886429) (xy 75.795301 -85.908241) (xy 75.842907 -85.937295) (xy 75.885775 -85.97297)
			(xy 75.922992 -86.014507) (xy 75.953765 -86.06102) (xy 75.977437 -86.111517) (xy 75.993505 -86.164924)
			(xy 76.001625 -86.2201) (xy 76.002134 -86.247986) (xy 76.001625 -86.275872) (xy 75.993505 -86.331048)
			(xy 75.977437 -86.384455) (xy 75.953765 -86.434952) (xy 75.922992 -86.481465) (xy 75.885775 -86.523002)
			(xy 75.842907 -86.558677) (xy 75.795301 -86.587731) (xy 75.743972 -86.609543) (xy 75.690015 -86.623649)
			(xy 75.634578 -86.629749) (xy 75.578844 -86.627712) (xy 75.524001 -86.617582) (xy 75.471217 -86.599575)
			(xy 75.421617 -86.574074) (xy 75.376259 -86.541623) (xy 75.33611 -86.502914) (xy 75.302024 -86.458771)
			(xy 75.274728 -86.410136) (xy 75.254805 -86.358045) (xy 75.242679 -86.303608) (xy 75.238608 -86.247986)
			(xy 48.606543 -86.247986) (xy 48.544443 -86.325158) (xy 48.457443 -86.420593) (xy 48.364732 -86.510492)
			(xy 48.266662 -86.594513) (xy 48.163607 -86.672337) (xy 48.055956 -86.743669) (xy 47.944117 -86.808239)
			(xy 47.828516 -86.865801) (xy 47.709591 -86.916138) (xy 47.587792 -86.959058) (xy 47.466826 -86.993476)
			(xy 59.629038 -86.993476) (xy 59.633109 -86.937854) (xy 59.645235 -86.883417) (xy 59.665158 -86.831326)
			(xy 59.692454 -86.782691) (xy 59.72654 -86.738548) (xy 59.766689 -86.699839) (xy 59.812047 -86.667388)
			(xy 59.861647 -86.641887) (xy 59.914431 -86.62388) (xy 59.969274 -86.61375) (xy 60.025008 -86.611713)
			(xy 60.080445 -86.617813) (xy 60.134402 -86.631919) (xy 60.185731 -86.653731) (xy 60.233337 -86.682785)
			(xy 60.276205 -86.71846) (xy 60.313422 -86.759997) (xy 60.344195 -86.80651) (xy 60.367867 -86.857007)
			(xy 60.383935 -86.910414) (xy 60.392055 -86.96559) (xy 60.392564 -86.993476) (xy 60.392055 -87.021362)
			(xy 60.383935 -87.076538) (xy 60.367867 -87.129945) (xy 60.344195 -87.180442) (xy 60.313422 -87.226955)
			(xy 60.276205 -87.268492) (xy 60.233337 -87.304167) (xy 60.185731 -87.333221) (xy 60.134402 -87.355033)
			(xy 60.080445 -87.369139) (xy 60.025008 -87.375239) (xy 59.969274 -87.373202) (xy 59.914431 -87.363072)
			(xy 59.861647 -87.345065) (xy 59.812047 -87.319564) (xy 59.766689 -87.287113) (xy 59.72654 -87.248404)
			(xy 59.692454 -87.204261) (xy 59.665158 -87.155626) (xy 59.645235 -87.103535) (xy 59.633109 -87.049098)
			(xy 59.629038 -86.993476) (xy 47.466826 -86.993476) (xy 47.463582 -86.994399) (xy 47.337433 -87.022026)
			(xy 47.209821 -87.041835) (xy 47.081232 -87.053751) (xy 46.952154 -87.057728) (xy 46.823076 -87.053751)
			(xy 46.694487 -87.041835) (xy 46.566875 -87.022026) (xy 46.440726 -86.994399) (xy 46.316516 -86.959058)
			(xy 46.194717 -86.916138) (xy 46.075792 -86.865801) (xy 45.960191 -86.808239) (xy 45.848352 -86.743669)
			(xy 45.740701 -86.672337) (xy 45.637646 -86.594513) (xy 45.539576 -86.510492) (xy 45.446865 -86.420593)
			(xy 45.359865 -86.325158) (xy 45.278904 -86.224548) (xy 45.20429 -86.119145) (xy 45.136307 -86.009348)
			(xy 45.075212 -85.895574) (xy 45.021237 -85.778255) (xy 44.974586 -85.657836) (xy 44.935437 -85.534773)
			(xy 44.903938 -85.409534) (xy 44.880209 -85.282593) (xy 44.864339 -85.154433) (xy 44.856389 -85.025538)
			(xy 2.967282 -85.025538) (xy 4.4069 -86.465156) (xy 4.413738 -86.472558) (xy 4.421452 -86.491156)
			(xy 4.421886 -86.501224) (xy 4.421886 -87.562944) (xy 103.932734 -87.562944) (xy 103.936805 -87.507322)
			(xy 103.948931 -87.452885) (xy 103.968854 -87.400794) (xy 103.99615 -87.352159) (xy 104.030236 -87.308016)
			(xy 104.070385 -87.269307) (xy 104.115743 -87.236856) (xy 104.165343 -87.211355) (xy 104.218127 -87.193348)
			(xy 104.27297 -87.183218) (xy 104.328704 -87.181181) (xy 104.384141 -87.187281) (xy 104.438098 -87.201387)
			(xy 104.489427 -87.223199) (xy 104.537033 -87.252253) (xy 104.579901 -87.287928) (xy 104.617118 -87.329465)
			(xy 104.647891 -87.375978) (xy 104.649568 -87.379556) (xy 112.261902 -87.379556) (xy 112.265973 -87.323934)
			(xy 112.278099 -87.269497) (xy 112.298022 -87.217406) (xy 112.325318 -87.168771) (xy 112.359404 -87.124628)
			(xy 112.399553 -87.085919) (xy 112.444911 -87.053468) (xy 112.494511 -87.027967) (xy 112.547295 -87.00996)
			(xy 112.602138 -86.99983) (xy 112.657872 -86.997793) (xy 112.713309 -87.003893) (xy 112.767266 -87.017999)
			(xy 112.818595 -87.039811) (xy 112.866201 -87.068865) (xy 112.909069 -87.10454) (xy 112.946286 -87.146077)
			(xy 112.977059 -87.19259) (xy 113.000731 -87.243087) (xy 113.016799 -87.296494) (xy 113.024919 -87.35167)
			(xy 113.025052 -87.358982) (xy 116.623592 -87.358982) (xy 116.623592 -86.495382) (xy 116.624082 -86.465414)
			(xy 116.631905 -86.405992) (xy 116.647418 -86.348099) (xy 116.670354 -86.292726) (xy 116.700321 -86.24082)
			(xy 116.736808 -86.19327) (xy 116.779188 -86.15089) (xy 116.826738 -86.114403) (xy 116.878644 -86.084436)
			(xy 116.934017 -86.0615) (xy 116.99191 -86.045987) (xy 117.051332 -86.038164) (xy 117.111268 -86.038164)
			(xy 117.17069 -86.045987) (xy 117.228583 -86.0615) (xy 117.283956 -86.084436) (xy 117.335862 -86.114403)
			(xy 117.383412 -86.15089) (xy 117.425792 -86.19327) (xy 117.462279 -86.24082) (xy 117.492246 -86.292726)
			(xy 117.515182 -86.348099) (xy 117.530695 -86.405992) (xy 117.538518 -86.465414) (xy 117.539008 -86.495382)
			(xy 117.539008 -87.358982) (xy 117.538518 -87.38895) (xy 117.530695 -87.448372) (xy 117.515182 -87.506265)
			(xy 117.492246 -87.561638) (xy 117.462279 -87.613544) (xy 117.425792 -87.661094) (xy 117.383412 -87.703474)
			(xy 117.335862 -87.739961) (xy 117.283956 -87.769928) (xy 117.228583 -87.792864) (xy 117.17069 -87.808377)
			(xy 117.111268 -87.8162) (xy 117.051332 -87.8162) (xy 116.99191 -87.808377) (xy 116.934017 -87.792864)
			(xy 116.878644 -87.769928) (xy 116.826738 -87.739961) (xy 116.779188 -87.703474) (xy 116.736808 -87.661094)
			(xy 116.700321 -87.613544) (xy 116.670354 -87.561638) (xy 116.647418 -87.506265) (xy 116.631905 -87.448372)
			(xy 116.624082 -87.38895) (xy 116.623592 -87.358982) (xy 113.025052 -87.358982) (xy 113.025428 -87.379556)
			(xy 113.024919 -87.407442) (xy 113.016799 -87.462618) (xy 113.000731 -87.516025) (xy 112.977059 -87.566522)
			(xy 112.946286 -87.613035) (xy 112.909069 -87.654572) (xy 112.866201 -87.690247) (xy 112.818595 -87.719301)
			(xy 112.767266 -87.741113) (xy 112.713309 -87.755219) (xy 112.657872 -87.761319) (xy 112.602138 -87.759282)
			(xy 112.547295 -87.749152) (xy 112.494511 -87.731145) (xy 112.444911 -87.705644) (xy 112.399553 -87.673193)
			(xy 112.359404 -87.634484) (xy 112.325318 -87.590341) (xy 112.298022 -87.541706) (xy 112.278099 -87.489615)
			(xy 112.265973 -87.435178) (xy 112.261902 -87.379556) (xy 104.649568 -87.379556) (xy 104.671563 -87.426475)
			(xy 104.687631 -87.479882) (xy 104.695751 -87.535058) (xy 104.69626 -87.562944) (xy 104.695751 -87.59083)
			(xy 104.687631 -87.646006) (xy 104.671563 -87.699413) (xy 104.647891 -87.74991) (xy 104.617118 -87.796423)
			(xy 104.579901 -87.83796) (xy 104.537033 -87.873635) (xy 104.489427 -87.902689) (xy 104.438098 -87.924501)
			(xy 104.384141 -87.938607) (xy 104.328704 -87.944707) (xy 104.27297 -87.94267) (xy 104.218127 -87.93254)
			(xy 104.165343 -87.914533) (xy 104.115743 -87.889032) (xy 104.070385 -87.856581) (xy 104.030236 -87.817872)
			(xy 103.99615 -87.773729) (xy 103.968854 -87.725094) (xy 103.948931 -87.673003) (xy 103.936805 -87.618566)
			(xy 103.932734 -87.562944) (xy 4.421886 -87.562944) (xy 4.421886 -88.375998) (xy 79.899 -88.375998)
			(xy 79.903071 -88.320376) (xy 79.915197 -88.265939) (xy 79.93512 -88.213848) (xy 79.962416 -88.165213)
			(xy 79.996502 -88.12107) (xy 80.036651 -88.082361) (xy 80.082009 -88.04991) (xy 80.131609 -88.024409)
			(xy 80.184393 -88.006402) (xy 80.239236 -87.996272) (xy 80.29497 -87.994235) (xy 80.350407 -88.000335)
			(xy 80.404364 -88.014441) (xy 80.455693 -88.036253) (xy 80.503299 -88.065307) (xy 80.546167 -88.100982)
			(xy 80.583384 -88.142519) (xy 80.614157 -88.189032) (xy 80.637829 -88.239529) (xy 80.653897 -88.292936)
			(xy 80.662017 -88.348112) (xy 80.662526 -88.375998) (xy 80.662164 -88.39581) (xy 81.257646 -88.39581)
			(xy 81.261717 -88.340188) (xy 81.273843 -88.285751) (xy 81.293766 -88.23366) (xy 81.321062 -88.185025)
			(xy 81.355148 -88.140882) (xy 81.395297 -88.102173) (xy 81.440655 -88.069722) (xy 81.490255 -88.044221)
			(xy 81.543039 -88.026214) (xy 81.597882 -88.016084) (xy 81.653616 -88.014047) (xy 81.709053 -88.020147)
			(xy 81.76301 -88.034253) (xy 81.814339 -88.056065) (xy 81.861945 -88.085119) (xy 81.904813 -88.120794)
			(xy 81.94203 -88.162331) (xy 81.972803 -88.208844) (xy 81.996475 -88.259341) (xy 82.012543 -88.312748)
			(xy 82.020663 -88.367924) (xy 82.021172 -88.39581) (xy 82.020663 -88.423696) (xy 82.012543 -88.478872)
			(xy 81.996475 -88.532279) (xy 81.972803 -88.582776) (xy 81.94203 -88.629289) (xy 81.904813 -88.670826)
			(xy 81.861945 -88.706501) (xy 81.814339 -88.735555) (xy 81.76301 -88.757367) (xy 81.709053 -88.771473)
			(xy 81.653616 -88.777573) (xy 81.597882 -88.775536) (xy 81.543039 -88.765406) (xy 81.490255 -88.747399)
			(xy 81.440655 -88.721898) (xy 81.395297 -88.689447) (xy 81.355148 -88.650738) (xy 81.321062 -88.606595)
			(xy 81.293766 -88.55796) (xy 81.273843 -88.505869) (xy 81.261717 -88.451432) (xy 81.257646 -88.39581)
			(xy 80.662164 -88.39581) (xy 80.662017 -88.403884) (xy 80.653897 -88.45906) (xy 80.637829 -88.512467)
			(xy 80.614157 -88.562964) (xy 80.583384 -88.609477) (xy 80.546167 -88.651014) (xy 80.503299 -88.686689)
			(xy 80.455693 -88.715743) (xy 80.404364 -88.737555) (xy 80.350407 -88.751661) (xy 80.29497 -88.757761)
			(xy 80.239236 -88.755724) (xy 80.184393 -88.745594) (xy 80.131609 -88.727587) (xy 80.082009 -88.702086)
			(xy 80.036651 -88.669635) (xy 79.996502 -88.630926) (xy 79.962416 -88.586783) (xy 79.93512 -88.538148)
			(xy 79.915197 -88.486057) (xy 79.903071 -88.43162) (xy 79.899 -88.375998) (xy 4.421886 -88.375998)
			(xy 4.421886 -88.956642) (xy 73.632566 -88.956642) (xy 73.636637 -88.90102) (xy 73.648763 -88.846583)
			(xy 73.668686 -88.794492) (xy 73.695982 -88.745857) (xy 73.730068 -88.701714) (xy 73.770217 -88.663005)
			(xy 73.815575 -88.630554) (xy 73.865175 -88.605053) (xy 73.917959 -88.587046) (xy 73.972802 -88.576916)
			(xy 74.028536 -88.574879) (xy 74.083973 -88.580979) (xy 74.13793 -88.595085) (xy 74.189259 -88.616897)
			(xy 74.236865 -88.645951) (xy 74.279733 -88.681626) (xy 74.31695 -88.723163) (xy 74.347723 -88.769676)
			(xy 74.371395 -88.820173) (xy 74.387463 -88.87358) (xy 74.395583 -88.928756) (xy 74.396092 -88.956642)
			(xy 74.395583 -88.984528) (xy 74.387463 -89.039704) (xy 74.371395 -89.093111) (xy 74.347723 -89.143608)
			(xy 74.31695 -89.190121) (xy 74.279733 -89.231658) (xy 74.236865 -89.267333) (xy 74.189259 -89.296387)
			(xy 74.13793 -89.318199) (xy 74.083973 -89.332305) (xy 74.028536 -89.338405) (xy 73.972802 -89.336368)
			(xy 73.917959 -89.326238) (xy 73.865175 -89.308231) (xy 73.815575 -89.28273) (xy 73.770217 -89.250279)
			(xy 73.730068 -89.21157) (xy 73.695982 -89.167427) (xy 73.668686 -89.118792) (xy 73.648763 -89.066701)
			(xy 73.636637 -89.012264) (xy 73.632566 -88.956642) (xy 4.421886 -88.956642) (xy 4.421886 -90.67345)
			(xy 78.092805 -90.67345) (xy 78.092805 -90.61895) (xy 78.100561 -90.565006) (xy 78.115916 -90.512714)
			(xy 78.138556 -90.46314) (xy 78.168021 -90.417292) (xy 78.203711 -90.376105) (xy 78.244899 -90.340416)
			(xy 78.290747 -90.310952) (xy 78.340322 -90.288313) (xy 78.392614 -90.27296) (xy 78.446558 -90.265205)
			(xy 78.473808 -90.264742) (xy 78.502403 -90.265284) (xy 78.558952 -90.273808) (xy 78.613596 -90.29068)
			(xy 78.665108 -90.31552) (xy 78.712334 -90.347773) (xy 78.754216 -90.386715) (xy 78.789815 -90.431473)
			(xy 78.804516 -90.456004) (xy 78.811628 -90.46845) (xy 78.836012 -90.481912) (xy 78.954376 -90.47734)
			(xy 78.977998 -90.461846) (xy 78.984094 -90.449146) (xy 78.99612 -90.425159) (xy 79.025818 -90.38047)
			(xy 79.061486 -90.340385) (xy 79.102419 -90.305692) (xy 79.147809 -90.277078) (xy 79.196761 -90.255107)
			(xy 79.248309 -90.240213) (xy 79.301436 -90.232689) (xy 79.328264 -90.23223) (xy 79.356708 -90.232791)
			(xy 79.412966 -90.24124) (xy 79.467344 -90.257954) (xy 79.518634 -90.282563) (xy 79.565698 -90.314521)
			(xy 79.607491 -90.353118) (xy 79.625698 -90.374978) (xy 79.633364 -90.383659) (xy 79.654258 -90.393588)
			(xy 79.66583 -90.394028) (xy 79.757778 -90.393012) (xy 79.778606 -90.382344) (xy 79.785718 -90.372946)
			(xy 79.803889 -90.350096) (xy 79.84603 -90.309696) (xy 79.893832 -90.276184) (xy 79.94618 -90.250343)
			(xy 80.001852 -90.232776) (xy 80.059551 -90.223892) (xy 80.08874 -90.22334) (xy 80.118546 -90.223887)
			(xy 80.17743 -90.233183) (xy 80.234151 -90.251528) (xy 80.287327 -90.278474) (xy 80.335662 -90.313366)
			(xy 80.377981 -90.355353) (xy 80.39608 -90.379042) (xy 80.39608 -90.379296) (xy 80.401344 -90.385904)
			(xy 80.415284 -90.395435) (xy 80.431577 -90.399872) (xy 80.440022 -90.399616) (xy 80.53832 -90.39352)
			(xy 80.560164 -90.379804) (xy 80.566514 -90.368628) (xy 80.573821 -90.355969) (xy 80.590095 -90.331685)
			(xy 80.599026 -90.320114) (xy 80.59928 -90.31986) (xy 80.604302 -90.31275) (xy 80.609756 -90.296233)
			(xy 80.609391 -90.278843) (xy 80.606646 -90.270584) (xy 80.575404 -90.18905) (xy 80.572004 -90.181)
			(xy 80.560703 -90.167687) (xy 80.545577 -90.158961) (xy 80.53705 -90.157046) (xy 80.536796 -90.157046)
			(xy 80.510611 -90.151994) (xy 80.459872 -90.135581) (xy 80.411913 -90.11226) (xy 80.367671 -90.082486)
			(xy 80.328007 -90.04684) (xy 80.293695 -90.006016) (xy 80.265404 -89.960811) (xy 80.243686 -89.912106)
			(xy 80.228964 -89.86085) (xy 80.221525 -89.808044) (xy 80.221074 -89.78138) (xy 80.22156 -89.754129)
			(xy 80.229316 -89.700181) (xy 80.244671 -89.647886) (xy 80.267313 -89.598309) (xy 80.296779 -89.552459)
			(xy 80.33247 -89.511268) (xy 80.373661 -89.475577) (xy 80.419511 -89.446111) (xy 80.469088 -89.423469)
			(xy 80.521383 -89.408114) (xy 80.575331 -89.400358) (xy 80.629833 -89.400358) (xy 80.683781 -89.408114)
			(xy 80.736076 -89.423469) (xy 80.785653 -89.446111) (xy 80.831503 -89.475577) (xy 80.872694 -89.511268)
			(xy 80.908385 -89.552459) (xy 80.937851 -89.598309) (xy 80.960493 -89.647886) (xy 80.975848 -89.700181)
			(xy 80.983604 -89.754129) (xy 80.98409 -89.78138) (xy 80.983637 -89.806797) (xy 80.97689 -89.857181)
			(xy 80.963512 -89.906223) (xy 80.943741 -89.953054) (xy 80.920664 -89.9922) (xy 92.469968 -89.9922)
			(xy 92.474039 -89.936578) (xy 92.486165 -89.882141) (xy 92.506088 -89.83005) (xy 92.533384 -89.781415)
			(xy 92.56747 -89.737272) (xy 92.607619 -89.698563) (xy 92.652977 -89.666112) (xy 92.702577 -89.640611)
			(xy 92.755361 -89.622604) (xy 92.810204 -89.612474) (xy 92.865938 -89.610437) (xy 92.921375 -89.616537)
			(xy 92.975332 -89.630643) (xy 93.026661 -89.652455) (xy 93.074267 -89.681509) (xy 93.117135 -89.717184)
			(xy 93.154352 -89.758721) (xy 93.185125 -89.805234) (xy 93.208797 -89.855731) (xy 93.213174 -89.87028)
			(xy 93.9579 -89.87028) (xy 93.961971 -89.814658) (xy 93.974097 -89.760221) (xy 93.99402 -89.70813)
			(xy 94.021316 -89.659495) (xy 94.055402 -89.615352) (xy 94.095551 -89.576643) (xy 94.140909 -89.544192)
			(xy 94.190509 -89.518691) (xy 94.243293 -89.500684) (xy 94.298136 -89.490554) (xy 94.35387 -89.488517)
			(xy 94.409307 -89.494617) (xy 94.463264 -89.508723) (xy 94.514593 -89.530535) (xy 94.562199 -89.559589)
			(xy 94.605067 -89.595264) (xy 94.642284 -89.636801) (xy 94.673057 -89.683314) (xy 94.681164 -89.700608)
			(xy 101.402894 -89.700608) (xy 101.406965 -89.644986) (xy 101.419091 -89.590549) (xy 101.439014 -89.538458)
			(xy 101.46631 -89.489823) (xy 101.500396 -89.44568) (xy 101.540545 -89.406971) (xy 101.585903 -89.37452)
			(xy 101.635503 -89.349019) (xy 101.688287 -89.331012) (xy 101.74313 -89.320882) (xy 101.798864 -89.318845)
			(xy 101.854301 -89.324945) (xy 101.908258 -89.339051) (xy 101.955151 -89.358978) (xy 117.385592 -89.358978)
			(xy 117.385592 -88.495378) (xy 117.386082 -88.46541) (xy 117.393905 -88.405988) (xy 117.409418 -88.348095)
			(xy 117.432354 -88.292722) (xy 117.462321 -88.240816) (xy 117.498808 -88.193266) (xy 117.541188 -88.150886)
			(xy 117.588738 -88.114399) (xy 117.640644 -88.084432) (xy 117.696017 -88.061496) (xy 117.75391 -88.045983)
			(xy 117.813332 -88.03816) (xy 117.873268 -88.03816) (xy 117.93269 -88.045983) (xy 117.990583 -88.061496)
			(xy 118.045956 -88.084432) (xy 118.097862 -88.114399) (xy 118.145412 -88.150886) (xy 118.187792 -88.193266)
			(xy 118.224279 -88.240816) (xy 118.254246 -88.292722) (xy 118.277182 -88.348095) (xy 118.288606 -88.39073)
			(xy 119.711722 -88.39073) (xy 119.715793 -88.335108) (xy 119.727919 -88.280671) (xy 119.747842 -88.22858)
			(xy 119.775138 -88.179945) (xy 119.809224 -88.135802) (xy 119.849373 -88.097093) (xy 119.894731 -88.064642)
			(xy 119.944331 -88.039141) (xy 119.997115 -88.021134) (xy 120.051958 -88.011004) (xy 120.107692 -88.008967)
			(xy 120.163129 -88.015067) (xy 120.217086 -88.029173) (xy 120.268415 -88.050985) (xy 120.316021 -88.080039)
			(xy 120.358889 -88.115714) (xy 120.396106 -88.157251) (xy 120.426879 -88.203764) (xy 120.450551 -88.254261)
			(xy 120.466619 -88.307668) (xy 120.474739 -88.362844) (xy 120.475248 -88.39073) (xy 120.474739 -88.418616)
			(xy 120.466619 -88.473792) (xy 120.450551 -88.527199) (xy 120.426879 -88.577696) (xy 120.396106 -88.624209)
			(xy 120.358889 -88.665746) (xy 120.316021 -88.701421) (xy 120.268415 -88.730475) (xy 120.217086 -88.752287)
			(xy 120.163129 -88.766393) (xy 120.107692 -88.772493) (xy 120.051958 -88.770456) (xy 119.997115 -88.760326)
			(xy 119.944331 -88.742319) (xy 119.894731 -88.716818) (xy 119.849373 -88.684367) (xy 119.809224 -88.645658)
			(xy 119.775138 -88.601515) (xy 119.747842 -88.55288) (xy 119.727919 -88.500789) (xy 119.715793 -88.446352)
			(xy 119.711722 -88.39073) (xy 118.288606 -88.39073) (xy 118.292695 -88.405988) (xy 118.300518 -88.46541)
			(xy 118.301008 -88.495378) (xy 118.301008 -89.358978) (xy 118.300518 -89.388946) (xy 118.292695 -89.448368)
			(xy 118.277182 -89.506261) (xy 118.265804 -89.53373) (xy 119.660414 -89.53373) (xy 119.664485 -89.478108)
			(xy 119.676611 -89.423671) (xy 119.696534 -89.37158) (xy 119.72383 -89.322945) (xy 119.757916 -89.278802)
			(xy 119.798065 -89.240093) (xy 119.843423 -89.207642) (xy 119.893023 -89.182141) (xy 119.945807 -89.164134)
			(xy 120.00065 -89.154004) (xy 120.056384 -89.151967) (xy 120.111821 -89.158067) (xy 120.165778 -89.172173)
			(xy 120.17621 -89.176606) (xy 124.546104 -89.176606) (xy 124.550175 -89.120984) (xy 124.562301 -89.066547)
			(xy 124.582224 -89.014456) (xy 124.60952 -88.965821) (xy 124.643606 -88.921678) (xy 124.683755 -88.882969)
			(xy 124.729113 -88.850518) (xy 124.778713 -88.825017) (xy 124.831497 -88.80701) (xy 124.88634 -88.79688)
			(xy 124.942074 -88.794843) (xy 124.997511 -88.800943) (xy 125.051468 -88.815049) (xy 125.102797 -88.836861)
			(xy 125.150403 -88.865915) (xy 125.193271 -88.90159) (xy 125.230488 -88.943127) (xy 125.261261 -88.98964)
			(xy 125.284933 -89.040137) (xy 125.301001 -89.093544) (xy 125.309121 -89.14872) (xy 125.30963 -89.176606)
			(xy 125.309121 -89.204492) (xy 125.301001 -89.259668) (xy 125.284933 -89.313075) (xy 125.261261 -89.363572)
			(xy 125.230488 -89.410085) (xy 125.193271 -89.451622) (xy 125.150403 -89.487297) (xy 125.102797 -89.516351)
			(xy 125.051468 -89.538163) (xy 124.997511 -89.552269) (xy 124.942074 -89.558369) (xy 124.88634 -89.556332)
			(xy 124.831497 -89.546202) (xy 124.778713 -89.528195) (xy 124.729113 -89.502694) (xy 124.683755 -89.470243)
			(xy 124.643606 -89.431534) (xy 124.60952 -89.387391) (xy 124.582224 -89.338756) (xy 124.562301 -89.286665)
			(xy 124.550175 -89.232228) (xy 124.546104 -89.176606) (xy 120.17621 -89.176606) (xy 120.217107 -89.193985)
			(xy 120.264713 -89.223039) (xy 120.307581 -89.258714) (xy 120.344798 -89.300251) (xy 120.375571 -89.346764)
			(xy 120.399243 -89.397261) (xy 120.415311 -89.450668) (xy 120.423431 -89.505844) (xy 120.42394 -89.53373)
			(xy 120.423431 -89.561616) (xy 120.415311 -89.616792) (xy 120.399243 -89.670199) (xy 120.375571 -89.720696)
			(xy 120.344798 -89.767209) (xy 120.307581 -89.808746) (xy 120.264713 -89.844421) (xy 120.217107 -89.873475)
			(xy 120.165778 -89.895287) (xy 120.111821 -89.909393) (xy 120.056384 -89.915493) (xy 120.00065 -89.913456)
			(xy 119.945807 -89.903326) (xy 119.893023 -89.885319) (xy 119.843423 -89.859818) (xy 119.798065 -89.827367)
			(xy 119.757916 -89.788658) (xy 119.72383 -89.744515) (xy 119.696534 -89.69588) (xy 119.676611 -89.643789)
			(xy 119.664485 -89.589352) (xy 119.660414 -89.53373) (xy 118.265804 -89.53373) (xy 118.254246 -89.561634)
			(xy 118.224279 -89.61354) (xy 118.187792 -89.66109) (xy 118.145412 -89.70347) (xy 118.097862 -89.739957)
			(xy 118.045956 -89.769924) (xy 117.990583 -89.79286) (xy 117.93269 -89.808373) (xy 117.873268 -89.816196)
			(xy 117.813332 -89.816196) (xy 117.75391 -89.808373) (xy 117.696017 -89.79286) (xy 117.640644 -89.769924)
			(xy 117.588738 -89.739957) (xy 117.541188 -89.70347) (xy 117.498808 -89.66109) (xy 117.462321 -89.61354)
			(xy 117.432354 -89.561634) (xy 117.409418 -89.506261) (xy 117.393905 -89.448368) (xy 117.386082 -89.388946)
			(xy 117.385592 -89.358978) (xy 101.955151 -89.358978) (xy 101.959587 -89.360863) (xy 102.007193 -89.389917)
			(xy 102.050061 -89.425592) (xy 102.087278 -89.467129) (xy 102.118051 -89.513642) (xy 102.141723 -89.564139)
			(xy 102.157791 -89.617546) (xy 102.165911 -89.672722) (xy 102.16642 -89.700608) (xy 102.165911 -89.728494)
			(xy 102.157791 -89.78367) (xy 102.141723 -89.837077) (xy 102.118051 -89.887574) (xy 102.087278 -89.934087)
			(xy 102.050061 -89.975624) (xy 102.007193 -90.011299) (xy 101.959587 -90.040353) (xy 101.908258 -90.062165)
			(xy 101.854301 -90.076271) (xy 101.798864 -90.082371) (xy 101.74313 -90.080334) (xy 101.688287 -90.070204)
			(xy 101.635503 -90.052197) (xy 101.585903 -90.026696) (xy 101.540545 -89.994245) (xy 101.500396 -89.955536)
			(xy 101.46631 -89.911393) (xy 101.439014 -89.862758) (xy 101.419091 -89.810667) (xy 101.406965 -89.75623)
			(xy 101.402894 -89.700608) (xy 94.681164 -89.700608) (xy 94.696729 -89.733811) (xy 94.712797 -89.787218)
			(xy 94.720917 -89.842394) (xy 94.721426 -89.87028) (xy 94.720917 -89.898166) (xy 94.712797 -89.953342)
			(xy 94.696729 -90.006749) (xy 94.673057 -90.057246) (xy 94.642284 -90.103759) (xy 94.605067 -90.145296)
			(xy 94.562199 -90.180971) (xy 94.514593 -90.210025) (xy 94.497353 -90.217351) (xy 107.858044 -90.217351)
			(xy 107.858044 -90.162849) (xy 107.8658 -90.1089) (xy 107.881154 -90.056605) (xy 107.903793 -90.007026)
			(xy 107.933258 -89.961174) (xy 107.968947 -89.919981) (xy 108.010136 -89.884287) (xy 108.055984 -89.854816)
			(xy 108.10556 -89.832171) (xy 108.157853 -89.81681) (xy 108.211801 -89.809047) (xy 108.239052 -89.808558)
			(xy 108.259989 -89.808846) (xy 108.301612 -89.813425) (xy 108.32211 -89.817702) (xy 108.33227 -89.819988)
			(xy 108.352082 -89.816178) (xy 108.430568 -89.764616) (xy 108.441998 -89.747598) (xy 108.443776 -89.737438)
			(xy 108.449137 -89.711594) (xy 108.466074 -89.661602) (xy 108.489739 -89.614422) (xy 108.51968 -89.570954)
			(xy 108.555326 -89.532027) (xy 108.595998 -89.498385) (xy 108.640917 -89.470669) (xy 108.689228 -89.449408)
			(xy 108.740009 -89.435009) (xy 108.792289 -89.427745) (xy 108.81868 -89.427304) (xy 108.845935 -89.427742)
			(xy 108.89989 -89.435496) (xy 108.952191 -89.450851) (xy 109.001776 -89.473493) (xy 109.047633 -89.502962)
			(xy 109.088829 -89.538657) (xy 109.124526 -89.579851) (xy 109.153997 -89.625707) (xy 109.176642 -89.67529)
			(xy 109.191999 -89.727591) (xy 109.199757 -89.781545) (xy 109.199757 -89.836055) (xy 109.193119 -89.882218)
			(xy 110.333026 -89.882218) (xy 110.337097 -89.826596) (xy 110.349223 -89.772159) (xy 110.369146 -89.720068)
			(xy 110.396442 -89.671433) (xy 110.430528 -89.62729) (xy 110.470677 -89.588581) (xy 110.516035 -89.55613)
			(xy 110.565635 -89.530629) (xy 110.618419 -89.512622) (xy 110.673262 -89.502492) (xy 110.728996 -89.500455)
			(xy 110.784433 -89.506555) (xy 110.83839 -89.520661) (xy 110.889719 -89.542473) (xy 110.937325 -89.571527)
			(xy 110.980193 -89.607202) (xy 111.01741 -89.648739) (xy 111.048183 -89.695252) (xy 111.071855 -89.745749)
			(xy 111.087923 -89.799156) (xy 111.096043 -89.854332) (xy 111.096552 -89.882218) (xy 111.096043 -89.910104)
			(xy 111.087923 -89.96528) (xy 111.071855 -90.018687) (xy 111.048183 -90.069184) (xy 111.01741 -90.115697)
			(xy 110.980193 -90.157234) (xy 110.937325 -90.192909) (xy 110.889719 -90.221963) (xy 110.83839 -90.243775)
			(xy 110.784433 -90.257881) (xy 110.728996 -90.263981) (xy 110.673262 -90.261944) (xy 110.618419 -90.251814)
			(xy 110.565635 -90.233807) (xy 110.516035 -90.208306) (xy 110.470677 -90.175855) (xy 110.430528 -90.137146)
			(xy 110.396442 -90.093003) (xy 110.369146 -90.044368) (xy 110.349223 -89.992277) (xy 110.337097 -89.93784)
			(xy 110.333026 -89.882218) (xy 109.193119 -89.882218) (xy 109.191999 -89.890009) (xy 109.176642 -89.94231)
			(xy 109.153997 -89.991893) (xy 109.124526 -90.037749) (xy 109.088829 -90.078943) (xy 109.047633 -90.114638)
			(xy 109.001776 -90.144107) (xy 108.952191 -90.166749) (xy 108.89989 -90.182104) (xy 108.845935 -90.189858)
			(xy 108.81868 -90.19032) (xy 108.797742 -90.190043) (xy 108.756119 -90.185456) (xy 108.735622 -90.181176)
			(xy 108.725462 -90.17889) (xy 108.70565 -90.1827) (xy 108.627164 -90.234262) (xy 108.615734 -90.25128)
			(xy 108.613956 -90.26144) (xy 108.613318 -90.264488) (xy 111.514634 -90.264488) (xy 111.518705 -90.208866)
			(xy 111.530831 -90.154429) (xy 111.550754 -90.102338) (xy 111.57805 -90.053703) (xy 111.612136 -90.00956)
			(xy 111.652285 -89.970851) (xy 111.697643 -89.9384) (xy 111.747243 -89.912899) (xy 111.800027 -89.894892)
			(xy 111.85487 -89.884762) (xy 111.910604 -89.882725) (xy 111.966041 -89.888825) (xy 112.019998 -89.902931)
			(xy 112.071327 -89.924743) (xy 112.118933 -89.953797) (xy 112.161801 -89.989472) (xy 112.199018 -90.031009)
			(xy 112.229791 -90.077522) (xy 112.253463 -90.128019) (xy 112.269531 -90.181426) (xy 112.277651 -90.236602)
			(xy 112.27816 -90.264488) (xy 112.277651 -90.292374) (xy 112.269531 -90.34755) (xy 112.253463 -90.400957)
			(xy 112.229791 -90.451454) (xy 112.199018 -90.497967) (xy 112.161801 -90.539504) (xy 112.118933 -90.575179)
			(xy 112.071327 -90.604233) (xy 112.019998 -90.626045) (xy 111.966041 -90.640151) (xy 111.910604 -90.646251)
			(xy 111.85487 -90.644214) (xy 111.800027 -90.634084) (xy 111.747243 -90.616077) (xy 111.697643 -90.590576)
			(xy 111.652285 -90.558125) (xy 111.612136 -90.519416) (xy 111.57805 -90.475273) (xy 111.550754 -90.426638)
			(xy 111.530831 -90.374547) (xy 111.518705 -90.32011) (xy 111.514634 -90.264488) (xy 108.613318 -90.264488)
			(xy 108.608549 -90.287274) (xy 108.591617 -90.337263) (xy 108.567957 -90.384442) (xy 108.538021 -90.427909)
			(xy 108.50238 -90.466836) (xy 108.461714 -90.50048) (xy 108.416799 -90.528197) (xy 108.368493 -90.549461)
			(xy 108.317718 -90.563863) (xy 108.265441 -90.571131) (xy 108.239052 -90.571574) (xy 108.211801 -90.571153)
			(xy 108.157853 -90.56339) (xy 108.10556 -90.548029) (xy 108.055984 -90.525384) (xy 108.010136 -90.495913)
			(xy 107.968947 -90.460219) (xy 107.933258 -90.419026) (xy 107.903793 -90.373174) (xy 107.881154 -90.323595)
			(xy 107.8658 -90.2713) (xy 107.858044 -90.217351) (xy 94.497353 -90.217351) (xy 94.463264 -90.231837)
			(xy 94.409307 -90.245943) (xy 94.35387 -90.252043) (xy 94.298136 -90.250006) (xy 94.243293 -90.239876)
			(xy 94.190509 -90.221869) (xy 94.140909 -90.196368) (xy 94.095551 -90.163917) (xy 94.055402 -90.125208)
			(xy 94.021316 -90.081065) (xy 93.99402 -90.03243) (xy 93.974097 -89.980339) (xy 93.961971 -89.925902)
			(xy 93.9579 -89.87028) (xy 93.213174 -89.87028) (xy 93.224865 -89.909138) (xy 93.232985 -89.964314)
			(xy 93.233494 -89.9922) (xy 93.232985 -90.020086) (xy 93.224865 -90.075262) (xy 93.208797 -90.128669)
			(xy 93.185125 -90.179166) (xy 93.154352 -90.225679) (xy 93.117135 -90.267216) (xy 93.074267 -90.302891)
			(xy 93.026661 -90.331945) (xy 92.975332 -90.353757) (xy 92.921375 -90.367863) (xy 92.865938 -90.373963)
			(xy 92.810204 -90.371926) (xy 92.755361 -90.361796) (xy 92.702577 -90.343789) (xy 92.652977 -90.318288)
			(xy 92.607619 -90.285837) (xy 92.56747 -90.247128) (xy 92.533384 -90.202985) (xy 92.506088 -90.15435)
			(xy 92.486165 -90.102259) (xy 92.474039 -90.047822) (xy 92.469968 -89.9922) (xy 80.920664 -89.9922)
			(xy 80.917926 -89.996845) (xy 80.902556 -90.017092) (xy 80.902302 -90.017346) (xy 80.897279 -90.024457)
			(xy 80.891819 -90.040973) (xy 80.892186 -90.058363) (xy 80.894936 -90.066622) (xy 80.926178 -90.148156)
			(xy 80.929587 -90.156201) (xy 80.940885 -90.169514) (xy 80.956007 -90.178243) (xy 80.964532 -90.18016)
			(xy 80.964786 -90.18016) (xy 80.99097 -90.18522) (xy 81.041709 -90.201631) (xy 81.089668 -90.22495)
			(xy 81.133911 -90.254723) (xy 81.173575 -90.290368) (xy 81.207888 -90.331191) (xy 81.236179 -90.376396)
			(xy 81.257897 -90.425101) (xy 81.272619 -90.476356) (xy 81.280058 -90.529162) (xy 81.280508 -90.555826)
			(xy 81.280046 -90.583078) (xy 81.275782 -90.612722) (xy 104.01376 -90.612722) (xy 104.017831 -90.5571)
			(xy 104.029957 -90.502663) (xy 104.04988 -90.450572) (xy 104.077176 -90.401937) (xy 104.111262 -90.357794)
			(xy 104.151411 -90.319085) (xy 104.196769 -90.286634) (xy 104.246369 -90.261133) (xy 104.299153 -90.243126)
			(xy 104.353996 -90.232996) (xy 104.40973 -90.230959) (xy 104.465167 -90.237059) (xy 104.519124 -90.251165)
			(xy 104.570453 -90.272977) (xy 104.618059 -90.302031) (xy 104.660927 -90.337706) (xy 104.698144 -90.379243)
			(xy 104.728917 -90.425756) (xy 104.752589 -90.476253) (xy 104.768657 -90.52966) (xy 104.776777 -90.584836)
			(xy 104.777286 -90.612722) (xy 104.776777 -90.640608) (xy 104.768657 -90.695784) (xy 104.752589 -90.749191)
			(xy 104.728917 -90.799688) (xy 104.720697 -90.812112) (xy 105.427778 -90.812112) (xy 105.431849 -90.75649)
			(xy 105.443975 -90.702053) (xy 105.463898 -90.649962) (xy 105.491194 -90.601327) (xy 105.52528 -90.557184)
			(xy 105.565429 -90.518475) (xy 105.610787 -90.486024) (xy 105.660387 -90.460523) (xy 105.713171 -90.442516)
			(xy 105.768014 -90.432386) (xy 105.823748 -90.430349) (xy 105.879185 -90.436449) (xy 105.933142 -90.450555)
			(xy 105.984471 -90.472367) (xy 106.032077 -90.501421) (xy 106.074945 -90.537096) (xy 106.112162 -90.578633)
			(xy 106.142935 -90.625146) (xy 106.166607 -90.675643) (xy 106.175799 -90.706194) (xy 124.7935 -90.706194)
			(xy 124.797571 -90.650572) (xy 124.809697 -90.596135) (xy 124.82962 -90.544044) (xy 124.856916 -90.495409)
			(xy 124.891002 -90.451266) (xy 124.931151 -90.412557) (xy 124.976509 -90.380106) (xy 125.026109 -90.354605)
			(xy 125.078893 -90.336598) (xy 125.133736 -90.326468) (xy 125.18947 -90.324431) (xy 125.244907 -90.330531)
			(xy 125.298864 -90.344637) (xy 125.350193 -90.366449) (xy 125.397799 -90.395503) (xy 125.440667 -90.431178)
			(xy 125.477884 -90.472715) (xy 125.508657 -90.519228) (xy 125.532329 -90.569725) (xy 125.548397 -90.623132)
			(xy 125.556517 -90.678308) (xy 125.557026 -90.706194) (xy 125.556517 -90.73408) (xy 125.548397 -90.789256)
			(xy 125.532329 -90.842663) (xy 125.508657 -90.89316) (xy 125.477884 -90.939673) (xy 125.440667 -90.98121)
			(xy 125.397799 -91.016885) (xy 125.350193 -91.045939) (xy 125.298864 -91.067751) (xy 125.244907 -91.081857)
			(xy 125.18947 -91.087957) (xy 125.133736 -91.08592) (xy 125.078893 -91.07579) (xy 125.026109 -91.057783)
			(xy 124.976509 -91.032282) (xy 124.931151 -90.999831) (xy 124.891002 -90.961122) (xy 124.856916 -90.916979)
			(xy 124.82962 -90.868344) (xy 124.809697 -90.816253) (xy 124.797571 -90.761816) (xy 124.7935 -90.706194)
			(xy 106.175799 -90.706194) (xy 106.182675 -90.72905) (xy 106.190795 -90.784226) (xy 106.191304 -90.812112)
			(xy 106.190795 -90.839998) (xy 106.182675 -90.895174) (xy 106.166607 -90.948581) (xy 106.142935 -90.999078)
			(xy 106.112162 -91.045591) (xy 106.074945 -91.087128) (xy 106.032077 -91.122803) (xy 105.984471 -91.151857)
			(xy 105.933142 -91.173669) (xy 105.879185 -91.187775) (xy 105.823748 -91.193875) (xy 105.768014 -91.191838)
			(xy 105.713171 -91.181708) (xy 105.660387 -91.163701) (xy 105.610787 -91.1382) (xy 105.565429 -91.105749)
			(xy 105.52528 -91.06704) (xy 105.491194 -91.022897) (xy 105.463898 -90.974262) (xy 105.443975 -90.922171)
			(xy 105.431849 -90.867734) (xy 105.427778 -90.812112) (xy 104.720697 -90.812112) (xy 104.698144 -90.846201)
			(xy 104.660927 -90.887738) (xy 104.618059 -90.923413) (xy 104.570453 -90.952467) (xy 104.519124 -90.974279)
			(xy 104.465167 -90.988385) (xy 104.40973 -90.994485) (xy 104.353996 -90.992448) (xy 104.299153 -90.982318)
			(xy 104.246369 -90.964311) (xy 104.196769 -90.93881) (xy 104.151411 -90.906359) (xy 104.111262 -90.86765)
			(xy 104.077176 -90.823507) (xy 104.04988 -90.774872) (xy 104.029957 -90.722781) (xy 104.017831 -90.668344)
			(xy 104.01376 -90.612722) (xy 81.275782 -90.612722) (xy 81.272286 -90.637026) (xy 81.256928 -90.689322)
			(xy 81.234284 -90.738899) (xy 81.204815 -90.784749) (xy 81.169121 -90.825939) (xy 81.127928 -90.86163)
			(xy 81.082076 -90.891096) (xy 81.032497 -90.913737) (xy 80.980201 -90.929092) (xy 80.926252 -90.936848)
			(xy 80.899 -90.937334) (xy 80.869194 -90.936769) (xy 80.81031 -90.927478) (xy 80.75359 -90.909137)
			(xy 80.700414 -90.882195) (xy 80.652078 -90.847306) (xy 80.609759 -90.805321) (xy 80.59166 -90.781632)
			(xy 80.59166 -90.781378) (xy 80.586379 -90.774786) (xy 80.572446 -90.765254) (xy 80.556161 -90.760808)
			(xy 80.547718 -90.761058) (xy 80.44942 -90.767154) (xy 80.427576 -90.78087) (xy 80.421226 -90.792046)
			(xy 80.406632 -90.816935) (xy 80.371059 -90.86236) (xy 80.329055 -90.901915) (xy 80.281578 -90.934698)
			(xy 80.229708 -90.959964) (xy 80.174626 -90.977136) (xy 80.117588 -90.985825) (xy 80.08874 -90.986356)
			(xy 80.060293 -90.985868) (xy 80.004031 -90.977405) (xy 79.949652 -90.960676) (xy 79.898362 -90.936053)
			(xy 79.8513 -90.904082) (xy 79.809511 -90.865473) (xy 79.791306 -90.843608) (xy 79.783641 -90.834926)
			(xy 79.762746 -90.824998) (xy 79.751174 -90.824558) (xy 79.659226 -90.825574) (xy 79.638398 -90.836242)
			(xy 79.631286 -90.84564) (xy 79.613109 -90.868485) (xy 79.57097 -90.908886) (xy 79.523169 -90.942399)
			(xy 79.470823 -90.968241) (xy 79.415151 -90.985809) (xy 79.357453 -90.994694) (xy 79.328264 -90.995246)
			(xy 79.299668 -90.994733) (xy 79.243117 -90.986204) (xy 79.188472 -90.969328) (xy 79.13696 -90.944483)
			(xy 79.089734 -90.912226) (xy 79.047853 -90.87328) (xy 79.012256 -90.828517) (xy 78.997556 -90.803984)
			(xy 78.990444 -90.791538) (xy 78.96606 -90.778076) (xy 78.847696 -90.782648) (xy 78.824074 -90.798142)
			(xy 78.817978 -90.810842) (xy 78.805968 -90.834838) (xy 78.776268 -90.879527) (xy 78.740599 -90.919614)
			(xy 78.699664 -90.954306) (xy 78.654271 -90.982919) (xy 78.605316 -91.004888) (xy 78.553766 -91.01978)
			(xy 78.500637 -91.027301) (xy 78.473808 -91.027758) (xy 78.446558 -91.027195) (xy 78.392614 -91.01944)
			(xy 78.340322 -91.004087) (xy 78.290747 -90.981448) (xy 78.244899 -90.951984) (xy 78.203711 -90.916295)
			(xy 78.168021 -90.875108) (xy 78.138556 -90.82926) (xy 78.115916 -90.779686) (xy 78.100561 -90.727394)
			(xy 78.092805 -90.67345) (xy 4.421886 -90.67345) (xy 4.421886 -91.315794) (xy 31.655256 -91.315794)
			(xy 31.659327 -91.260172) (xy 31.671453 -91.205735) (xy 31.691376 -91.153644) (xy 31.718672 -91.105009)
			(xy 31.752758 -91.060866) (xy 31.792907 -91.022157) (xy 31.838265 -90.989706) (xy 31.887865 -90.964205)
			(xy 31.940649 -90.946198) (xy 31.995492 -90.936068) (xy 32.051226 -90.934031) (xy 32.106663 -90.940131)
			(xy 32.16062 -90.954237) (xy 32.211949 -90.976049) (xy 32.259555 -91.005103) (xy 32.302423 -91.040778)
			(xy 32.33964 -91.082315) (xy 32.370413 -91.128828) (xy 32.394085 -91.179325) (xy 32.410153 -91.232732)
			(xy 32.410228 -91.233244) (xy 58.865514 -91.233244) (xy 58.869585 -91.177622) (xy 58.881711 -91.123185)
			(xy 58.901634 -91.071094) (xy 58.92893 -91.022459) (xy 58.963016 -90.978316) (xy 59.003165 -90.939607)
			(xy 59.048523 -90.907156) (xy 59.098123 -90.881655) (xy 59.150907 -90.863648) (xy 59.20575 -90.853518)
			(xy 59.261484 -90.851481) (xy 59.316921 -90.857581) (xy 59.370878 -90.871687) (xy 59.422207 -90.893499)
			(xy 59.469813 -90.922553) (xy 59.512681 -90.958228) (xy 59.549898 -90.999765) (xy 59.580671 -91.046278)
			(xy 59.604343 -91.096775) (xy 59.620411 -91.150182) (xy 59.627663 -91.199462) (xy 106.656884 -91.199462)
			(xy 106.660955 -91.14384) (xy 106.673081 -91.089403) (xy 106.693004 -91.037312) (xy 106.7203 -90.988677)
			(xy 106.754386 -90.944534) (xy 106.794535 -90.905825) (xy 106.839893 -90.873374) (xy 106.889493 -90.847873)
			(xy 106.942277 -90.829866) (xy 106.99712 -90.819736) (xy 107.052854 -90.817699) (xy 107.108291 -90.823799)
			(xy 107.162248 -90.837905) (xy 107.213577 -90.859717) (xy 107.261183 -90.888771) (xy 107.304051 -90.924446)
			(xy 107.341268 -90.965983) (xy 107.372041 -91.012496) (xy 107.395713 -91.062993) (xy 107.411781 -91.1164)
			(xy 107.419901 -91.171576) (xy 107.420285 -91.192604) (xy 108.032802 -91.192604) (xy 108.036873 -91.136982)
			(xy 108.048999 -91.082545) (xy 108.068922 -91.030454) (xy 108.096218 -90.981819) (xy 108.130304 -90.937676)
			(xy 108.170453 -90.898967) (xy 108.215811 -90.866516) (xy 108.265411 -90.841015) (xy 108.318195 -90.823008)
			(xy 108.373038 -90.812878) (xy 108.428772 -90.810841) (xy 108.484209 -90.816941) (xy 108.538166 -90.831047)
			(xy 108.589495 -90.852859) (xy 108.637101 -90.881913) (xy 108.679969 -90.917588) (xy 108.717186 -90.959125)
			(xy 108.747959 -91.005638) (xy 108.771631 -91.056135) (xy 108.787699 -91.109542) (xy 108.795819 -91.164718)
			(xy 108.796328 -91.192604) (xy 108.795819 -91.22049) (xy 108.787699 -91.275666) (xy 108.771631 -91.329073)
			(xy 108.747959 -91.37957) (xy 108.717389 -91.425776) (xy 118.321072 -91.425776) (xy 118.325143 -91.370154)
			(xy 118.337269 -91.315717) (xy 118.357192 -91.263626) (xy 118.384488 -91.214991) (xy 118.418574 -91.170848)
			(xy 118.458723 -91.132139) (xy 118.504081 -91.099688) (xy 118.553681 -91.074187) (xy 118.606465 -91.05618)
			(xy 118.661308 -91.04605) (xy 118.717042 -91.044013) (xy 118.772479 -91.050113) (xy 118.826436 -91.064219)
			(xy 118.877765 -91.086031) (xy 118.925371 -91.115085) (xy 118.968239 -91.15076) (xy 119.005456 -91.192297)
			(xy 119.036229 -91.23881) (xy 119.059901 -91.289307) (xy 119.075969 -91.342714) (xy 119.084089 -91.39789)
			(xy 119.084598 -91.425776) (xy 119.084089 -91.453662) (xy 119.082773 -91.462606) (xy 119.737884 -91.462606)
			(xy 119.741955 -91.406984) (xy 119.754081 -91.352547) (xy 119.774004 -91.300456) (xy 119.8013 -91.251821)
			(xy 119.835386 -91.207678) (xy 119.875535 -91.168969) (xy 119.920893 -91.136518) (xy 119.970493 -91.111017)
			(xy 120.023277 -91.09301) (xy 120.07812 -91.08288) (xy 120.133854 -91.080843) (xy 120.189291 -91.086943)
			(xy 120.243248 -91.101049) (xy 120.294577 -91.122861) (xy 120.342183 -91.151915) (xy 120.385051 -91.18759)
			(xy 120.422268 -91.229127) (xy 120.453041 -91.27564) (xy 120.476713 -91.326137) (xy 120.492781 -91.379544)
			(xy 120.500901 -91.43472) (xy 120.50141 -91.462606) (xy 120.500901 -91.490492) (xy 120.492781 -91.545668)
			(xy 120.476713 -91.599075) (xy 120.453041 -91.649572) (xy 120.422268 -91.696085) (xy 120.385051 -91.737622)
			(xy 120.342183 -91.773297) (xy 120.294577 -91.802351) (xy 120.243248 -91.824163) (xy 120.189291 -91.838269)
			(xy 120.133854 -91.844369) (xy 120.07812 -91.842332) (xy 120.023277 -91.832202) (xy 119.970493 -91.814195)
			(xy 119.920893 -91.788694) (xy 119.875535 -91.756243) (xy 119.835386 -91.717534) (xy 119.8013 -91.673391)
			(xy 119.774004 -91.624756) (xy 119.754081 -91.572665) (xy 119.741955 -91.518228) (xy 119.737884 -91.462606)
			(xy 119.082773 -91.462606) (xy 119.075969 -91.508838) (xy 119.059901 -91.562245) (xy 119.036229 -91.612742)
			(xy 119.005456 -91.659255) (xy 118.968239 -91.700792) (xy 118.925371 -91.736467) (xy 118.877765 -91.765521)
			(xy 118.826436 -91.787333) (xy 118.772479 -91.801439) (xy 118.717042 -91.807539) (xy 118.661308 -91.805502)
			(xy 118.606465 -91.795372) (xy 118.553681 -91.777365) (xy 118.504081 -91.751864) (xy 118.458723 -91.719413)
			(xy 118.418574 -91.680704) (xy 118.384488 -91.636561) (xy 118.357192 -91.587926) (xy 118.337269 -91.535835)
			(xy 118.325143 -91.481398) (xy 118.321072 -91.425776) (xy 108.717389 -91.425776) (xy 108.717186 -91.426083)
			(xy 108.679969 -91.46762) (xy 108.637101 -91.503295) (xy 108.589495 -91.532349) (xy 108.538166 -91.554161)
			(xy 108.484209 -91.568267) (xy 108.428772 -91.574367) (xy 108.373038 -91.57233) (xy 108.318195 -91.5622)
			(xy 108.265411 -91.544193) (xy 108.215811 -91.518692) (xy 108.170453 -91.486241) (xy 108.130304 -91.447532)
			(xy 108.096218 -91.403389) (xy 108.068922 -91.354754) (xy 108.048999 -91.302663) (xy 108.036873 -91.248226)
			(xy 108.032802 -91.192604) (xy 107.420285 -91.192604) (xy 107.42041 -91.199462) (xy 107.419901 -91.227348)
			(xy 107.411781 -91.282524) (xy 107.395713 -91.335931) (xy 107.372041 -91.386428) (xy 107.341268 -91.432941)
			(xy 107.304051 -91.474478) (xy 107.261183 -91.510153) (xy 107.213577 -91.539207) (xy 107.162248 -91.561019)
			(xy 107.108291 -91.575125) (xy 107.052854 -91.581225) (xy 106.99712 -91.579188) (xy 106.942277 -91.569058)
			(xy 106.889493 -91.551051) (xy 106.839893 -91.52555) (xy 106.794535 -91.493099) (xy 106.754386 -91.45439)
			(xy 106.7203 -91.410247) (xy 106.693004 -91.361612) (xy 106.673081 -91.309521) (xy 106.660955 -91.255084)
			(xy 106.656884 -91.199462) (xy 59.627663 -91.199462) (xy 59.628531 -91.205358) (xy 59.62904 -91.233244)
			(xy 59.628531 -91.26113) (xy 59.620411 -91.316306) (xy 59.604343 -91.369713) (xy 59.580671 -91.42021)
			(xy 59.549898 -91.466723) (xy 59.512681 -91.50826) (xy 59.469813 -91.543935) (xy 59.422207 -91.572989)
			(xy 59.370878 -91.594801) (xy 59.316921 -91.608907) (xy 59.261484 -91.615007) (xy 59.20575 -91.61297)
			(xy 59.150907 -91.60284) (xy 59.098123 -91.584833) (xy 59.048523 -91.559332) (xy 59.003165 -91.526881)
			(xy 58.963016 -91.488172) (xy 58.92893 -91.444029) (xy 58.901634 -91.395394) (xy 58.881711 -91.343303)
			(xy 58.869585 -91.288866) (xy 58.865514 -91.233244) (xy 32.410228 -91.233244) (xy 32.418273 -91.287908)
			(xy 32.418782 -91.315794) (xy 32.418273 -91.34368) (xy 32.410153 -91.398856) (xy 32.394085 -91.452263)
			(xy 32.370413 -91.50276) (xy 32.33964 -91.549273) (xy 32.302423 -91.59081) (xy 32.259555 -91.626485)
			(xy 32.211949 -91.655539) (xy 32.16062 -91.677351) (xy 32.106663 -91.691457) (xy 32.051226 -91.697557)
			(xy 31.995492 -91.69552) (xy 31.940649 -91.68539) (xy 31.887865 -91.667383) (xy 31.838265 -91.641882)
			(xy 31.792907 -91.609431) (xy 31.752758 -91.570722) (xy 31.718672 -91.526579) (xy 31.691376 -91.477944)
			(xy 31.671453 -91.425853) (xy 31.659327 -91.371416) (xy 31.655256 -91.315794) (xy 4.421886 -91.315794)
			(xy 4.421886 -92.179902) (xy 125.607824 -92.179902) (xy 125.611895 -92.12428) (xy 125.624021 -92.069843)
			(xy 125.643944 -92.017752) (xy 125.67124 -91.969117) (xy 125.705326 -91.924974) (xy 125.745475 -91.886265)
			(xy 125.790833 -91.853814) (xy 125.840433 -91.828313) (xy 125.893217 -91.810306) (xy 125.94806 -91.800176)
			(xy 126.003794 -91.798139) (xy 126.059231 -91.804239) (xy 126.113188 -91.818345) (xy 126.164517 -91.840157)
			(xy 126.212123 -91.869211) (xy 126.254991 -91.904886) (xy 126.292208 -91.946423) (xy 126.322981 -91.992936)
			(xy 126.346653 -92.043433) (xy 126.362721 -92.09684) (xy 126.370841 -92.152016) (xy 126.37135 -92.179902)
			(xy 126.370841 -92.207788) (xy 126.362721 -92.262964) (xy 126.346653 -92.316371) (xy 126.322981 -92.366868)
			(xy 126.292208 -92.413381) (xy 126.254991 -92.454918) (xy 126.212123 -92.490593) (xy 126.164517 -92.519647)
			(xy 126.113188 -92.541459) (xy 126.059231 -92.555565) (xy 126.003794 -92.561665) (xy 125.94806 -92.559628)
			(xy 125.893217 -92.549498) (xy 125.840433 -92.531491) (xy 125.790833 -92.50599) (xy 125.745475 -92.473539)
			(xy 125.705326 -92.43483) (xy 125.67124 -92.390687) (xy 125.643944 -92.342052) (xy 125.624021 -92.289961)
			(xy 125.611895 -92.235524) (xy 125.607824 -92.179902) (xy 4.421886 -92.179902) (xy 4.421886 -92.927424)
			(xy 31.559244 -92.927424) (xy 31.563315 -92.871802) (xy 31.575441 -92.817365) (xy 31.595364 -92.765274)
			(xy 31.62266 -92.716639) (xy 31.656746 -92.672496) (xy 31.696895 -92.633787) (xy 31.742253 -92.601336)
			(xy 31.791853 -92.575835) (xy 31.844637 -92.557828) (xy 31.89948 -92.547698) (xy 31.955214 -92.545661)
			(xy 32.010651 -92.551761) (xy 32.064608 -92.565867) (xy 32.115937 -92.587679) (xy 32.163543 -92.616733)
			(xy 32.206411 -92.652408) (xy 32.243628 -92.693945) (xy 32.274401 -92.740458) (xy 32.298073 -92.790955)
			(xy 32.314141 -92.844362) (xy 32.322261 -92.899538) (xy 32.32277 -92.927424) (xy 32.322261 -92.95531)
			(xy 32.314141 -93.010486) (xy 32.298073 -93.063893) (xy 32.274401 -93.11439) (xy 32.243628 -93.160903)
			(xy 32.206411 -93.20244) (xy 32.163543 -93.238115) (xy 32.115937 -93.267169) (xy 32.064608 -93.288981)
			(xy 32.010651 -93.303087) (xy 31.955214 -93.309187) (xy 31.89948 -93.30715) (xy 31.844637 -93.29702)
			(xy 31.791853 -93.279013) (xy 31.742253 -93.253512) (xy 31.696895 -93.221061) (xy 31.656746 -93.182352)
			(xy 31.62266 -93.138209) (xy 31.595364 -93.089574) (xy 31.575441 -93.037483) (xy 31.563315 -92.983046)
			(xy 31.559244 -92.927424) (xy 4.421886 -92.927424) (xy 4.421886 -93.447362) (xy 104.346754 -93.447362)
			(xy 104.350825 -93.39174) (xy 104.362951 -93.337303) (xy 104.382874 -93.285212) (xy 104.41017 -93.236577)
			(xy 104.444256 -93.192434) (xy 104.484405 -93.153725) (xy 104.529763 -93.121274) (xy 104.579363 -93.095773)
			(xy 104.632147 -93.077766) (xy 104.68699 -93.067636) (xy 104.742724 -93.065599) (xy 104.798161 -93.071699)
			(xy 104.852118 -93.085805) (xy 104.903447 -93.107617) (xy 104.951053 -93.136671) (xy 104.993921 -93.172346)
			(xy 105.031138 -93.213883) (xy 105.061911 -93.260396) (xy 105.085583 -93.310893) (xy 105.101651 -93.3643)
			(xy 105.109771 -93.419476) (xy 105.110076 -93.436186) (xy 106.40517 -93.436186) (xy 106.409241 -93.380564)
			(xy 106.421367 -93.326127) (xy 106.44129 -93.274036) (xy 106.468586 -93.225401) (xy 106.502672 -93.181258)
			(xy 106.542821 -93.142549) (xy 106.588179 -93.110098) (xy 106.637779 -93.084597) (xy 106.690563 -93.06659)
			(xy 106.745406 -93.05646) (xy 106.80114 -93.054423) (xy 106.856577 -93.060523) (xy 106.910534 -93.074629)
			(xy 106.961863 -93.096441) (xy 107.009469 -93.125495) (xy 107.052337 -93.16117) (xy 107.089554 -93.202707)
			(xy 107.120327 -93.24922) (xy 107.143999 -93.299717) (xy 107.160067 -93.353124) (xy 107.166422 -93.396308)
			(xy 115.412772 -93.396308) (xy 115.416843 -93.340686) (xy 115.428969 -93.286249) (xy 115.448892 -93.234158)
			(xy 115.476188 -93.185523) (xy 115.510274 -93.14138) (xy 115.550423 -93.102671) (xy 115.595781 -93.07022)
			(xy 115.645381 -93.044719) (xy 115.698165 -93.026712) (xy 115.753008 -93.016582) (xy 115.808742 -93.014545)
			(xy 115.864179 -93.020645) (xy 115.918136 -93.034751) (xy 115.969465 -93.056563) (xy 116.017071 -93.085617)
			(xy 116.059939 -93.121292) (xy 116.090604 -93.155516) (xy 118.878602 -93.155516) (xy 118.882673 -93.099894)
			(xy 118.894799 -93.045457) (xy 118.914722 -92.993366) (xy 118.942018 -92.944731) (xy 118.976104 -92.900588)
			(xy 119.016253 -92.861879) (xy 119.061611 -92.829428) (xy 119.111211 -92.803927) (xy 119.163995 -92.78592)
			(xy 119.218838 -92.77579) (xy 119.274572 -92.773753) (xy 119.330009 -92.779853) (xy 119.383966 -92.793959)
			(xy 119.435295 -92.815771) (xy 119.438033 -92.817442) (xy 124.345444 -92.817442) (xy 124.349515 -92.76182)
			(xy 124.361641 -92.707383) (xy 124.381564 -92.655292) (xy 124.40886 -92.606657) (xy 124.442946 -92.562514)
			(xy 124.483095 -92.523805) (xy 124.528453 -92.491354) (xy 124.578053 -92.465853) (xy 124.630837 -92.447846)
			(xy 124.68568 -92.437716) (xy 124.741414 -92.435679) (xy 124.796851 -92.441779) (xy 124.850808 -92.455885)
			(xy 124.902137 -92.477697) (xy 124.949743 -92.506751) (xy 124.992611 -92.542426) (xy 125.029828 -92.583963)
			(xy 125.060601 -92.630476) (xy 125.084273 -92.680973) (xy 125.100341 -92.73438) (xy 125.108461 -92.789556)
			(xy 125.10897 -92.817442) (xy 125.108461 -92.845328) (xy 125.100341 -92.900504) (xy 125.084273 -92.953911)
			(xy 125.060601 -93.004408) (xy 125.029828 -93.050921) (xy 124.992611 -93.092458) (xy 124.949743 -93.128133)
			(xy 124.902137 -93.157187) (xy 124.850808 -93.178999) (xy 124.796851 -93.193105) (xy 124.741414 -93.199205)
			(xy 124.68568 -93.197168) (xy 124.630837 -93.187038) (xy 124.578053 -93.169031) (xy 124.528453 -93.14353)
			(xy 124.483095 -93.111079) (xy 124.442946 -93.07237) (xy 124.40886 -93.028227) (xy 124.381564 -92.979592)
			(xy 124.361641 -92.927501) (xy 124.349515 -92.873064) (xy 124.345444 -92.817442) (xy 119.438033 -92.817442)
			(xy 119.482901 -92.844825) (xy 119.525769 -92.8805) (xy 119.562986 -92.922037) (xy 119.593759 -92.96855)
			(xy 119.617431 -93.019047) (xy 119.633499 -93.072454) (xy 119.641619 -93.12763) (xy 119.642128 -93.155516)
			(xy 119.641619 -93.183402) (xy 119.633499 -93.238578) (xy 119.617431 -93.291985) (xy 119.593759 -93.342482)
			(xy 119.562986 -93.388995) (xy 119.525769 -93.430532) (xy 119.482901 -93.466207) (xy 119.435295 -93.495261)
			(xy 119.383966 -93.517073) (xy 119.330009 -93.531179) (xy 119.274572 -93.537279) (xy 119.218838 -93.535242)
			(xy 119.163995 -93.525112) (xy 119.111211 -93.507105) (xy 119.061611 -93.481604) (xy 119.016253 -93.449153)
			(xy 118.976104 -93.410444) (xy 118.942018 -93.366301) (xy 118.914722 -93.317666) (xy 118.894799 -93.265575)
			(xy 118.882673 -93.211138) (xy 118.878602 -93.155516) (xy 116.090604 -93.155516) (xy 116.097156 -93.162829)
			(xy 116.127929 -93.209342) (xy 116.151601 -93.259839) (xy 116.167669 -93.313246) (xy 116.175789 -93.368422)
			(xy 116.176298 -93.396308) (xy 116.175789 -93.424194) (xy 116.167669 -93.47937) (xy 116.151601 -93.532777)
			(xy 116.127929 -93.583274) (xy 116.097156 -93.629787) (xy 116.059939 -93.671324) (xy 116.017071 -93.706999)
			(xy 115.969465 -93.736053) (xy 115.939925 -93.748606) (xy 119.737884 -93.748606) (xy 119.741955 -93.692984)
			(xy 119.754081 -93.638547) (xy 119.774004 -93.586456) (xy 119.8013 -93.537821) (xy 119.835386 -93.493678)
			(xy 119.875535 -93.454969) (xy 119.920893 -93.422518) (xy 119.970493 -93.397017) (xy 120.023277 -93.37901)
			(xy 120.07812 -93.36888) (xy 120.133854 -93.366843) (xy 120.189291 -93.372943) (xy 120.243248 -93.387049)
			(xy 120.294577 -93.408861) (xy 120.342183 -93.437915) (xy 120.385051 -93.47359) (xy 120.422268 -93.515127)
			(xy 120.453041 -93.56164) (xy 120.476713 -93.612137) (xy 120.492781 -93.665544) (xy 120.500901 -93.72072)
			(xy 120.50141 -93.748606) (xy 121.975878 -93.748606) (xy 121.979949 -93.692984) (xy 121.992075 -93.638547)
			(xy 122.011998 -93.586456) (xy 122.039294 -93.537821) (xy 122.07338 -93.493678) (xy 122.113529 -93.454969)
			(xy 122.158887 -93.422518) (xy 122.208487 -93.397017) (xy 122.261271 -93.37901) (xy 122.316114 -93.36888)
			(xy 122.371848 -93.366843) (xy 122.427285 -93.372943) (xy 122.481242 -93.387049) (xy 122.532571 -93.408861)
			(xy 122.580177 -93.437915) (xy 122.623045 -93.47359) (xy 122.660262 -93.515127) (xy 122.691035 -93.56164)
			(xy 122.714707 -93.612137) (xy 122.730775 -93.665544) (xy 122.738895 -93.72072) (xy 122.739404 -93.748606)
			(xy 122.738895 -93.776492) (xy 122.730775 -93.831668) (xy 122.728178 -93.8403) (xy 125.868174 -93.8403)
			(xy 125.872245 -93.784678) (xy 125.884371 -93.730241) (xy 125.904294 -93.67815) (xy 125.93159 -93.629515)
			(xy 125.965676 -93.585372) (xy 126.005825 -93.546663) (xy 126.051183 -93.514212) (xy 126.100783 -93.488711)
			(xy 126.153567 -93.470704) (xy 126.20841 -93.460574) (xy 126.264144 -93.458537) (xy 126.319581 -93.464637)
			(xy 126.373538 -93.478743) (xy 126.424867 -93.500555) (xy 126.472473 -93.529609) (xy 126.515341 -93.565284)
			(xy 126.552558 -93.606821) (xy 126.583331 -93.653334) (xy 126.607003 -93.703831) (xy 126.623071 -93.757238)
			(xy 126.631191 -93.812414) (xy 126.6317 -93.8403) (xy 126.631191 -93.868186) (xy 126.623071 -93.923362)
			(xy 126.607003 -93.976769) (xy 126.583331 -94.027266) (xy 126.552558 -94.073779) (xy 126.515341 -94.115316)
			(xy 126.472473 -94.150991) (xy 126.424867 -94.180045) (xy 126.373538 -94.201857) (xy 126.319581 -94.215963)
			(xy 126.264144 -94.222063) (xy 126.20841 -94.220026) (xy 126.153567 -94.209896) (xy 126.100783 -94.191889)
			(xy 126.051183 -94.166388) (xy 126.005825 -94.133937) (xy 125.965676 -94.095228) (xy 125.93159 -94.051085)
			(xy 125.904294 -94.00245) (xy 125.884371 -93.950359) (xy 125.872245 -93.895922) (xy 125.868174 -93.8403)
			(xy 122.728178 -93.8403) (xy 122.714707 -93.885075) (xy 122.691035 -93.935572) (xy 122.660262 -93.982085)
			(xy 122.623045 -94.023622) (xy 122.580177 -94.059297) (xy 122.532571 -94.088351) (xy 122.481242 -94.110163)
			(xy 122.427285 -94.124269) (xy 122.371848 -94.130369) (xy 122.316114 -94.128332) (xy 122.261271 -94.118202)
			(xy 122.208487 -94.100195) (xy 122.158887 -94.074694) (xy 122.113529 -94.042243) (xy 122.07338 -94.003534)
			(xy 122.039294 -93.959391) (xy 122.011998 -93.910756) (xy 121.992075 -93.858665) (xy 121.979949 -93.804228)
			(xy 121.975878 -93.748606) (xy 120.50141 -93.748606) (xy 120.500901 -93.776492) (xy 120.492781 -93.831668)
			(xy 120.476713 -93.885075) (xy 120.453041 -93.935572) (xy 120.422268 -93.982085) (xy 120.385051 -94.023622)
			(xy 120.342183 -94.059297) (xy 120.294577 -94.088351) (xy 120.243248 -94.110163) (xy 120.189291 -94.124269)
			(xy 120.133854 -94.130369) (xy 120.07812 -94.128332) (xy 120.023277 -94.118202) (xy 119.970493 -94.100195)
			(xy 119.920893 -94.074694) (xy 119.875535 -94.042243) (xy 119.835386 -94.003534) (xy 119.8013 -93.959391)
			(xy 119.774004 -93.910756) (xy 119.754081 -93.858665) (xy 119.741955 -93.804228) (xy 119.737884 -93.748606)
			(xy 115.939925 -93.748606) (xy 115.918136 -93.757865) (xy 115.864179 -93.771971) (xy 115.808742 -93.778071)
			(xy 115.753008 -93.776034) (xy 115.698165 -93.765904) (xy 115.645381 -93.747897) (xy 115.595781 -93.722396)
			(xy 115.550423 -93.689945) (xy 115.510274 -93.651236) (xy 115.476188 -93.607093) (xy 115.448892 -93.558458)
			(xy 115.428969 -93.506367) (xy 115.416843 -93.45193) (xy 115.412772 -93.396308) (xy 107.166422 -93.396308)
			(xy 107.168187 -93.4083) (xy 107.168696 -93.436186) (xy 107.168187 -93.464072) (xy 107.160067 -93.519248)
			(xy 107.143999 -93.572655) (xy 107.120327 -93.623152) (xy 107.089554 -93.669665) (xy 107.052337 -93.711202)
			(xy 107.009469 -93.746877) (xy 106.961863 -93.775931) (xy 106.910534 -93.797743) (xy 106.856577 -93.811849)
			(xy 106.80114 -93.817949) (xy 106.745406 -93.815912) (xy 106.690563 -93.805782) (xy 106.637779 -93.787775)
			(xy 106.588179 -93.762274) (xy 106.542821 -93.729823) (xy 106.502672 -93.691114) (xy 106.468586 -93.646971)
			(xy 106.44129 -93.598336) (xy 106.421367 -93.546245) (xy 106.409241 -93.491808) (xy 106.40517 -93.436186)
			(xy 105.110076 -93.436186) (xy 105.11028 -93.447362) (xy 105.109771 -93.475248) (xy 105.101651 -93.530424)
			(xy 105.085583 -93.583831) (xy 105.061911 -93.634328) (xy 105.031138 -93.680841) (xy 104.993921 -93.722378)
			(xy 104.951053 -93.758053) (xy 104.903447 -93.787107) (xy 104.852118 -93.808919) (xy 104.798161 -93.823025)
			(xy 104.742724 -93.829125) (xy 104.68699 -93.827088) (xy 104.632147 -93.816958) (xy 104.579363 -93.798951)
			(xy 104.529763 -93.77345) (xy 104.484405 -93.740999) (xy 104.444256 -93.70229) (xy 104.41017 -93.658147)
			(xy 104.382874 -93.609512) (xy 104.362951 -93.557421) (xy 104.350825 -93.502984) (xy 104.346754 -93.447362)
			(xy 4.421886 -93.447362) (xy 4.421886 -95.12554) (xy 24.574752 -95.12554) (xy 24.578823 -95.069918)
			(xy 24.590949 -95.015481) (xy 24.610872 -94.96339) (xy 24.638168 -94.914755) (xy 24.672254 -94.870612)
			(xy 24.712403 -94.831903) (xy 24.757761 -94.799452) (xy 24.807361 -94.773951) (xy 24.860145 -94.755944)
			(xy 24.914988 -94.745814) (xy 24.970722 -94.743777) (xy 25.026159 -94.749877) (xy 25.080116 -94.763983)
			(xy 25.131445 -94.785795) (xy 25.179051 -94.814849) (xy 25.221919 -94.850524) (xy 25.259136 -94.892061)
			(xy 25.289909 -94.938574) (xy 25.313581 -94.989071) (xy 25.329649 -95.042478) (xy 25.337769 -95.097654)
			(xy 25.338278 -95.12554) (xy 25.337769 -95.153426) (xy 25.329649 -95.208602) (xy 25.32774 -95.214948)
			(xy 47.273985 -95.214948) (xy 47.277941 -95.123089) (xy 47.289778 -95.03191) (xy 47.30941 -94.942086)
			(xy 47.336691 -94.854283) (xy 47.371419 -94.76915) (xy 47.413337 -94.687317) (xy 47.462135 -94.60939)
			(xy 47.51745 -94.535947) (xy 47.578875 -94.467531) (xy 47.645954 -94.404649) (xy 47.718189 -94.347766)
			(xy 47.795048 -94.297303) (xy 47.87596 -94.253634) (xy 47.960326 -94.217082) (xy 48.047522 -94.187918)
			(xy 48.136903 -94.166358) (xy 48.227806 -94.152562) (xy 48.319559 -94.14663) (xy 48.411481 -94.148609)
			(xy 48.502894 -94.158482) (xy 48.593119 -94.176177) (xy 48.68149 -94.201562) (xy 48.76735 -94.23445)
			(xy 48.850066 -94.274598) (xy 48.929024 -94.321707) (xy 49.003641 -94.37543) (xy 49.073362 -94.435368)
			(xy 49.137673 -94.501078) (xy 49.196098 -94.572074) (xy 49.248203 -94.647828) (xy 49.293602 -94.727782)
			(xy 49.331961 -94.811342) (xy 49.362994 -94.897891) (xy 49.386472 -94.986787) (xy 49.402222 -95.077372)
			(xy 49.410126 -95.168976) (xy 49.41062 -95.214948) (xy 71.638935 -95.214948) (xy 71.642891 -95.123089)
			(xy 71.654728 -95.03191) (xy 71.67436 -94.942086) (xy 71.701641 -94.854283) (xy 71.736369 -94.76915)
			(xy 71.778287 -94.687317) (xy 71.827085 -94.60939) (xy 71.8824 -94.535947) (xy 71.943825 -94.467531)
			(xy 72.010904 -94.404649) (xy 72.083139 -94.347766) (xy 72.159998 -94.297303) (xy 72.24091 -94.253634)
			(xy 72.325276 -94.217082) (xy 72.412472 -94.187918) (xy 72.501853 -94.166358) (xy 72.592756 -94.152562)
			(xy 72.684509 -94.14663) (xy 72.776431 -94.148609) (xy 72.867844 -94.158482) (xy 72.958069 -94.176177)
			(xy 73.04644 -94.201562) (xy 73.1323 -94.23445) (xy 73.215016 -94.274598) (xy 73.293974 -94.321707)
			(xy 73.368591 -94.37543) (xy 73.438312 -94.435368) (xy 73.502623 -94.501078) (xy 73.561048 -94.572074)
			(xy 73.561572 -94.572836) (xy 88.806526 -94.572836) (xy 88.810597 -94.517214) (xy 88.822723 -94.462777)
			(xy 88.842646 -94.410686) (xy 88.869942 -94.362051) (xy 88.904028 -94.317908) (xy 88.944177 -94.279199)
			(xy 88.989535 -94.246748) (xy 89.039135 -94.221247) (xy 89.091919 -94.20324) (xy 89.146762 -94.19311)
			(xy 89.202496 -94.191073) (xy 89.257933 -94.197173) (xy 89.31189 -94.211279) (xy 89.363219 -94.233091)
			(xy 89.38968 -94.24924) (xy 95.43618 -94.24924) (xy 95.440251 -94.193618) (xy 95.452377 -94.139181)
			(xy 95.4723 -94.08709) (xy 95.499596 -94.038455) (xy 95.533682 -93.994312) (xy 95.573831 -93.955603)
			(xy 95.619189 -93.923152) (xy 95.668789 -93.897651) (xy 95.721573 -93.879644) (xy 95.776416 -93.869514)
			(xy 95.83215 -93.867477) (xy 95.887587 -93.873577) (xy 95.941544 -93.887683) (xy 95.992873 -93.909495)
			(xy 96.040479 -93.938549) (xy 96.083347 -93.974224) (xy 96.120564 -94.015761) (xy 96.151337 -94.062274)
			(xy 96.175009 -94.112771) (xy 96.191077 -94.166178) (xy 96.199197 -94.221354) (xy 96.199706 -94.24924)
			(xy 96.199632 -94.253304) (xy 96.45218 -94.253304) (xy 96.456251 -94.197682) (xy 96.468377 -94.143245)
			(xy 96.4883 -94.091154) (xy 96.515596 -94.042519) (xy 96.549682 -93.998376) (xy 96.589831 -93.959667)
			(xy 96.635189 -93.927216) (xy 96.684789 -93.901715) (xy 96.737573 -93.883708) (xy 96.792416 -93.873578)
			(xy 96.84815 -93.871541) (xy 96.903587 -93.877641) (xy 96.957544 -93.891747) (xy 97.008873 -93.913559)
			(xy 97.056479 -93.942613) (xy 97.099347 -93.978288) (xy 97.136564 -94.019825) (xy 97.167337 -94.066338)
			(xy 97.177719 -94.088485) (xy 109.149614 -94.088485) (xy 109.149614 -94.028515) (xy 109.157442 -93.969058)
			(xy 109.172963 -93.911131) (xy 109.195912 -93.855726) (xy 109.225897 -93.80379) (xy 109.262405 -93.756213)
			(xy 109.30481 -93.713807) (xy 109.352387 -93.6773) (xy 109.404322 -93.647314) (xy 109.459727 -93.624364)
			(xy 109.517654 -93.608843) (xy 109.577111 -93.601014) (xy 109.607096 -93.600524) (xy 110.470696 -93.600524)
			(xy 110.500681 -93.601021) (xy 110.560138 -93.608848) (xy 110.618064 -93.624369) (xy 110.673469 -93.647318)
			(xy 110.725405 -93.677303) (xy 110.772982 -93.71381) (xy 110.815388 -93.756215) (xy 110.851895 -93.803792)
			(xy 110.88188 -93.855727) (xy 110.90483 -93.911132) (xy 110.920351 -93.969058) (xy 110.928179 -94.028515)
			(xy 110.928179 -94.088485) (xy 110.920351 -94.147942) (xy 110.90483 -94.205868) (xy 110.88188 -94.261273)
			(xy 110.851895 -94.313208) (xy 110.815388 -94.360785) (xy 110.772982 -94.40319) (xy 110.725405 -94.439697)
			(xy 110.673469 -94.469682) (xy 110.618064 -94.492631) (xy 110.584158 -94.501716) (xy 114.13439 -94.501716)
			(xy 114.138461 -94.446094) (xy 114.150587 -94.391657) (xy 114.17051 -94.339566) (xy 114.197806 -94.290931)
			(xy 114.231892 -94.246788) (xy 114.272041 -94.208079) (xy 114.317399 -94.175628) (xy 114.366999 -94.150127)
			(xy 114.419783 -94.13212) (xy 114.474626 -94.12199) (xy 114.53036 -94.119953) (xy 114.585797 -94.126053)
			(xy 114.639754 -94.140159) (xy 114.691083 -94.161971) (xy 114.738689 -94.191025) (xy 114.781557 -94.2267)
			(xy 114.818774 -94.268237) (xy 114.849547 -94.31475) (xy 114.873219 -94.365247) (xy 114.889287 -94.418654)
			(xy 114.897407 -94.47383) (xy 114.897916 -94.501716) (xy 114.897407 -94.529602) (xy 114.889287 -94.584778)
			(xy 114.873219 -94.638185) (xy 114.849547 -94.688682) (xy 114.818774 -94.735195) (xy 114.781557 -94.776732)
			(xy 114.738689 -94.812407) (xy 114.691083 -94.841461) (xy 114.639754 -94.863273) (xy 114.585797 -94.877379)
			(xy 114.53036 -94.883479) (xy 114.474626 -94.881442) (xy 114.419783 -94.871312) (xy 114.366999 -94.853305)
			(xy 114.317399 -94.827804) (xy 114.272041 -94.795353) (xy 114.231892 -94.756644) (xy 114.197806 -94.712501)
			(xy 114.17051 -94.663866) (xy 114.150587 -94.611775) (xy 114.138461 -94.557338) (xy 114.13439 -94.501716)
			(xy 110.584158 -94.501716) (xy 110.560138 -94.508152) (xy 110.500681 -94.515979) (xy 110.470696 -94.516448)
			(xy 109.607096 -94.516448) (xy 109.577111 -94.515986) (xy 109.517654 -94.508157) (xy 109.459727 -94.492636)
			(xy 109.404322 -94.469686) (xy 109.352387 -94.4397) (xy 109.30481 -94.403193) (xy 109.262405 -94.360787)
			(xy 109.225897 -94.31321) (xy 109.195912 -94.261274) (xy 109.172963 -94.205869) (xy 109.157442 -94.147942)
			(xy 109.149614 -94.088485) (xy 97.177719 -94.088485) (xy 97.191009 -94.116835) (xy 97.207077 -94.170242)
			(xy 97.215197 -94.225418) (xy 97.215706 -94.253304) (xy 97.215197 -94.28119) (xy 97.207077 -94.336366)
			(xy 97.191009 -94.389773) (xy 97.167337 -94.44027) (xy 97.136564 -94.486783) (xy 97.099347 -94.52832)
			(xy 97.056479 -94.563995) (xy 97.008873 -94.593049) (xy 96.957544 -94.614861) (xy 96.903587 -94.628967)
			(xy 96.84815 -94.635067) (xy 96.792416 -94.63303) (xy 96.737573 -94.6229) (xy 96.684789 -94.604893)
			(xy 96.635189 -94.579392) (xy 96.589831 -94.546941) (xy 96.549682 -94.508232) (xy 96.515596 -94.464089)
			(xy 96.4883 -94.415454) (xy 96.468377 -94.363363) (xy 96.456251 -94.308926) (xy 96.45218 -94.253304)
			(xy 96.199632 -94.253304) (xy 96.199197 -94.277126) (xy 96.191077 -94.332302) (xy 96.175009 -94.385709)
			(xy 96.151337 -94.436206) (xy 96.120564 -94.482719) (xy 96.083347 -94.524256) (xy 96.040479 -94.559931)
			(xy 95.992873 -94.588985) (xy 95.941544 -94.610797) (xy 95.887587 -94.624903) (xy 95.83215 -94.631003)
			(xy 95.776416 -94.628966) (xy 95.721573 -94.618836) (xy 95.668789 -94.600829) (xy 95.619189 -94.575328)
			(xy 95.573831 -94.542877) (xy 95.533682 -94.504168) (xy 95.499596 -94.460025) (xy 95.4723 -94.41139)
			(xy 95.452377 -94.359299) (xy 95.440251 -94.304862) (xy 95.43618 -94.24924) (xy 89.38968 -94.24924)
			(xy 89.410825 -94.262145) (xy 89.453693 -94.29782) (xy 89.49091 -94.339357) (xy 89.521683 -94.38587)
			(xy 89.545355 -94.436367) (xy 89.561423 -94.489774) (xy 89.569543 -94.54495) (xy 89.570052 -94.572836)
			(xy 89.569543 -94.600722) (xy 89.561423 -94.655898) (xy 89.545355 -94.709305) (xy 89.521683 -94.759802)
			(xy 89.49091 -94.806315) (xy 89.453693 -94.847852) (xy 89.410825 -94.883527) (xy 89.397587 -94.891606)
			(xy 119.737884 -94.891606) (xy 119.741955 -94.835984) (xy 119.754081 -94.781547) (xy 119.774004 -94.729456)
			(xy 119.8013 -94.680821) (xy 119.835386 -94.636678) (xy 119.875535 -94.597969) (xy 119.920893 -94.565518)
			(xy 119.970493 -94.540017) (xy 120.023277 -94.52201) (xy 120.07812 -94.51188) (xy 120.133854 -94.509843)
			(xy 120.189291 -94.515943) (xy 120.243248 -94.530049) (xy 120.294577 -94.551861) (xy 120.342183 -94.580915)
			(xy 120.385051 -94.61659) (xy 120.422268 -94.658127) (xy 120.453041 -94.70464) (xy 120.476713 -94.755137)
			(xy 120.492781 -94.808544) (xy 120.500901 -94.86372) (xy 120.50141 -94.891606) (xy 121.975878 -94.891606)
			(xy 121.979949 -94.835984) (xy 121.992075 -94.781547) (xy 122.011998 -94.729456) (xy 122.039294 -94.680821)
			(xy 122.07338 -94.636678) (xy 122.113529 -94.597969) (xy 122.158887 -94.565518) (xy 122.208487 -94.540017)
			(xy 122.261271 -94.52201) (xy 122.316114 -94.51188) (xy 122.371848 -94.509843) (xy 122.427285 -94.515943)
			(xy 122.481242 -94.530049) (xy 122.532571 -94.551861) (xy 122.580177 -94.580915) (xy 122.623045 -94.61659)
			(xy 122.660262 -94.658127) (xy 122.691035 -94.70464) (xy 122.714707 -94.755137) (xy 122.730775 -94.808544)
			(xy 122.738895 -94.86372) (xy 122.739404 -94.891606) (xy 124.302772 -94.891606) (xy 124.306843 -94.835984)
			(xy 124.318969 -94.781547) (xy 124.338892 -94.729456) (xy 124.366188 -94.680821) (xy 124.400274 -94.636678)
			(xy 124.440423 -94.597969) (xy 124.485781 -94.565518) (xy 124.535381 -94.540017) (xy 124.588165 -94.52201)
			(xy 124.643008 -94.51188) (xy 124.698742 -94.509843) (xy 124.754179 -94.515943) (xy 124.808136 -94.530049)
			(xy 124.859465 -94.551861) (xy 124.907071 -94.580915) (xy 124.949939 -94.61659) (xy 124.987156 -94.658127)
			(xy 125.017929 -94.70464) (xy 125.041601 -94.755137) (xy 125.057669 -94.808544) (xy 125.065789 -94.86372)
			(xy 125.066298 -94.891606) (xy 125.065789 -94.919492) (xy 125.057669 -94.974668) (xy 125.041601 -95.028075)
			(xy 125.017929 -95.078572) (xy 124.987156 -95.125085) (xy 124.949939 -95.166622) (xy 124.907071 -95.202297)
			(xy 124.859465 -95.231351) (xy 124.808136 -95.253163) (xy 124.754179 -95.267269) (xy 124.698742 -95.273369)
			(xy 124.643008 -95.271332) (xy 124.588165 -95.261202) (xy 124.535381 -95.243195) (xy 124.485781 -95.217694)
			(xy 124.440423 -95.185243) (xy 124.400274 -95.146534) (xy 124.366188 -95.102391) (xy 124.338892 -95.053756)
			(xy 124.318969 -95.001665) (xy 124.306843 -94.947228) (xy 124.302772 -94.891606) (xy 122.739404 -94.891606)
			(xy 122.738895 -94.919492) (xy 122.730775 -94.974668) (xy 122.714707 -95.028075) (xy 122.691035 -95.078572)
			(xy 122.660262 -95.125085) (xy 122.623045 -95.166622) (xy 122.580177 -95.202297) (xy 122.532571 -95.231351)
			(xy 122.481242 -95.253163) (xy 122.427285 -95.267269) (xy 122.371848 -95.273369) (xy 122.316114 -95.271332)
			(xy 122.261271 -95.261202) (xy 122.208487 -95.243195) (xy 122.158887 -95.217694) (xy 122.113529 -95.185243)
			(xy 122.07338 -95.146534) (xy 122.039294 -95.102391) (xy 122.011998 -95.053756) (xy 121.992075 -95.001665)
			(xy 121.979949 -94.947228) (xy 121.975878 -94.891606) (xy 120.50141 -94.891606) (xy 120.500901 -94.919492)
			(xy 120.492781 -94.974668) (xy 120.476713 -95.028075) (xy 120.453041 -95.078572) (xy 120.422268 -95.125085)
			(xy 120.385051 -95.166622) (xy 120.342183 -95.202297) (xy 120.294577 -95.231351) (xy 120.243248 -95.253163)
			(xy 120.189291 -95.267269) (xy 120.133854 -95.273369) (xy 120.07812 -95.271332) (xy 120.023277 -95.261202)
			(xy 119.970493 -95.243195) (xy 119.920893 -95.217694) (xy 119.875535 -95.185243) (xy 119.835386 -95.146534)
			(xy 119.8013 -95.102391) (xy 119.774004 -95.053756) (xy 119.754081 -95.001665) (xy 119.741955 -94.947228)
			(xy 119.737884 -94.891606) (xy 89.397587 -94.891606) (xy 89.363219 -94.912581) (xy 89.31189 -94.934393)
			(xy 89.257933 -94.948499) (xy 89.202496 -94.954599) (xy 89.146762 -94.952562) (xy 89.091919 -94.942432)
			(xy 89.039135 -94.924425) (xy 88.989535 -94.898924) (xy 88.944177 -94.866473) (xy 88.904028 -94.827764)
			(xy 88.869942 -94.783621) (xy 88.842646 -94.734986) (xy 88.822723 -94.682895) (xy 88.810597 -94.628458)
			(xy 88.806526 -94.572836) (xy 73.561572 -94.572836) (xy 73.613153 -94.647828) (xy 73.658552 -94.727782)
			(xy 73.696911 -94.811342) (xy 73.727944 -94.897891) (xy 73.751422 -94.986787) (xy 73.767172 -95.077372)
			(xy 73.775076 -95.168976) (xy 73.77557 -95.214948) (xy 73.775076 -95.26092) (xy 73.767172 -95.352524)
			(xy 73.751422 -95.443109) (xy 73.727944 -95.532005) (xy 73.696911 -95.618554) (xy 73.658552 -95.702114)
			(xy 73.613153 -95.782068) (xy 73.561048 -95.857822) (xy 73.502623 -95.928818) (xy 73.443088 -95.989648)
			(xy 75.563982 -95.989648) (xy 75.568053 -95.934026) (xy 75.580179 -95.879589) (xy 75.600102 -95.827498)
			(xy 75.627398 -95.778863) (xy 75.661484 -95.73472) (xy 75.701633 -95.696011) (xy 75.746991 -95.66356)
			(xy 75.796591 -95.638059) (xy 75.849375 -95.620052) (xy 75.904218 -95.609922) (xy 75.959952 -95.607885)
			(xy 76.015389 -95.613985) (xy 76.069346 -95.628091) (xy 76.120675 -95.649903) (xy 76.168281 -95.678957)
			(xy 76.211149 -95.714632) (xy 76.248366 -95.756169) (xy 76.278649 -95.801942) (xy 88.641426 -95.801942)
			(xy 88.645497 -95.74632) (xy 88.657623 -95.691883) (xy 88.677546 -95.639792) (xy 88.704842 -95.591157)
			(xy 88.738928 -95.547014) (xy 88.779077 -95.508305) (xy 88.824435 -95.475854) (xy 88.874035 -95.450353)
			(xy 88.926819 -95.432346) (xy 88.981662 -95.422216) (xy 89.037396 -95.420179) (xy 89.092833 -95.426279)
			(xy 89.14679 -95.440385) (xy 89.198119 -95.462197) (xy 89.245725 -95.491251) (xy 89.288593 -95.526926)
			(xy 89.32581 -95.568463) (xy 89.356583 -95.614976) (xy 89.380255 -95.665473) (xy 89.396323 -95.71888)
			(xy 89.404443 -95.774056) (xy 89.404952 -95.801942) (xy 90.674696 -95.801942) (xy 90.678767 -95.74632)
			(xy 90.690893 -95.691883) (xy 90.710816 -95.639792) (xy 90.738112 -95.591157) (xy 90.772198 -95.547014)
			(xy 90.812347 -95.508305) (xy 90.857705 -95.475854) (xy 90.907305 -95.450353) (xy 90.960089 -95.432346)
			(xy 91.014932 -95.422216) (xy 91.070666 -95.420179) (xy 91.126103 -95.426279) (xy 91.18006 -95.440385)
			(xy 91.231389 -95.462197) (xy 91.278995 -95.491251) (xy 91.321863 -95.526926) (xy 91.35908 -95.568463)
			(xy 91.389853 -95.614976) (xy 91.413525 -95.665473) (xy 91.429593 -95.71888) (xy 91.437713 -95.774056)
			(xy 91.438222 -95.801942) (xy 92.715586 -95.801942) (xy 92.719657 -95.74632) (xy 92.731783 -95.691883)
			(xy 92.751706 -95.639792) (xy 92.779002 -95.591157) (xy 92.813088 -95.547014) (xy 92.853237 -95.508305)
			(xy 92.898595 -95.475854) (xy 92.948195 -95.450353) (xy 93.000979 -95.432346) (xy 93.055822 -95.422216)
			(xy 93.111556 -95.420179) (xy 93.166993 -95.426279) (xy 93.22095 -95.440385) (xy 93.272279 -95.462197)
			(xy 93.319885 -95.491251) (xy 93.362753 -95.526926) (xy 93.39997 -95.568463) (xy 93.430743 -95.614976)
			(xy 93.454415 -95.665473) (xy 93.470483 -95.71888) (xy 93.478603 -95.774056) (xy 93.479112 -95.801942)
			(xy 93.721426 -95.801942) (xy 93.725497 -95.74632) (xy 93.737623 -95.691883) (xy 93.757546 -95.639792)
			(xy 93.784842 -95.591157) (xy 93.818928 -95.547014) (xy 93.859077 -95.508305) (xy 93.904435 -95.475854)
			(xy 93.954035 -95.450353) (xy 94.006819 -95.432346) (xy 94.061662 -95.422216) (xy 94.117396 -95.420179)
			(xy 94.172833 -95.426279) (xy 94.22679 -95.440385) (xy 94.278119 -95.462197) (xy 94.325725 -95.491251)
			(xy 94.368593 -95.526926) (xy 94.40581 -95.568463) (xy 94.436583 -95.614976) (xy 94.460255 -95.665473)
			(xy 94.476323 -95.71888) (xy 94.484443 -95.774056) (xy 94.484952 -95.801942) (xy 94.484443 -95.829828)
			(xy 94.477301 -95.878357) (xy 99.120179 -95.878357) (xy 99.127934 -95.82441) (xy 99.143288 -95.772116)
			(xy 99.165927 -95.722539) (xy 99.195392 -95.676689) (xy 99.231081 -95.635498) (xy 99.27227 -95.599806)
			(xy 99.318118 -95.570339) (xy 99.367693 -95.547696) (xy 99.419986 -95.53234) (xy 99.473933 -95.524581)
			(xy 99.528434 -95.524579) (xy 99.582381 -95.532332) (xy 99.634675 -95.547685) (xy 99.684253 -95.570323)
			(xy 99.730104 -95.599786) (xy 99.771295 -95.635475) (xy 99.806988 -95.676662) (xy 99.836457 -95.72251)
			(xy 99.8591 -95.772085) (xy 99.874458 -95.824377) (xy 99.882218 -95.878323) (xy 99.882706 -95.905574)
			(xy 99.882706 -95.906082) (xy 99.882623 -95.916454) (xy 99.881481 -95.937166) (xy 99.88042 -95.947484)
			(xy 99.879281 -95.962029) (xy 99.884489 -95.990727) (xy 99.897586 -96.016789) (xy 99.917505 -96.038095)
			(xy 99.942628 -96.052912) (xy 99.970911 -96.060037) (xy 100.000056 -96.05889) (xy 100.014024 -96.054672)
			(xy 100.043635 -96.045328) (xy 100.1049 -96.03524) (xy 100.135944 -96.034606) (xy 100.136198 -96.034606)
			(xy 119.737884 -96.034606) (xy 119.741955 -95.978984) (xy 119.754081 -95.924547) (xy 119.774004 -95.872456)
			(xy 119.8013 -95.823821) (xy 119.835386 -95.779678) (xy 119.875535 -95.740969) (xy 119.920893 -95.708518)
			(xy 119.970493 -95.683017) (xy 120.023277 -95.66501) (xy 120.07812 -95.65488) (xy 120.133854 -95.652843)
			(xy 120.189291 -95.658943) (xy 120.243248 -95.673049) (xy 120.294577 -95.694861) (xy 120.342183 -95.723915)
			(xy 120.385051 -95.75959) (xy 120.422268 -95.801127) (xy 120.453041 -95.84764) (xy 120.476713 -95.898137)
			(xy 120.492781 -95.951544) (xy 120.500901 -96.00672) (xy 120.50141 -96.034606) (xy 121.975878 -96.034606)
			(xy 121.979949 -95.978984) (xy 121.992075 -95.924547) (xy 122.011998 -95.872456) (xy 122.039294 -95.823821)
			(xy 122.07338 -95.779678) (xy 122.113529 -95.740969) (xy 122.158887 -95.708518) (xy 122.208487 -95.683017)
			(xy 122.261271 -95.66501) (xy 122.316114 -95.65488) (xy 122.371848 -95.652843) (xy 122.427285 -95.658943)
			(xy 122.481242 -95.673049) (xy 122.532571 -95.694861) (xy 122.580177 -95.723915) (xy 122.623045 -95.75959)
			(xy 122.660262 -95.801127) (xy 122.691035 -95.84764) (xy 122.71224 -95.892874) (xy 125.538482 -95.892874)
			(xy 125.542553 -95.837252) (xy 125.554679 -95.782815) (xy 125.574602 -95.730724) (xy 125.601898 -95.682089)
			(xy 125.635984 -95.637946) (xy 125.676133 -95.599237) (xy 125.721491 -95.566786) (xy 125.771091 -95.541285)
			(xy 125.823875 -95.523278) (xy 125.878718 -95.513148) (xy 125.934452 -95.511111) (xy 125.989889 -95.517211)
			(xy 126.043846 -95.531317) (xy 126.095175 -95.553129) (xy 126.142781 -95.582183) (xy 126.185649 -95.617858)
			(xy 126.222866 -95.659395) (xy 126.253639 -95.705908) (xy 126.277311 -95.756405) (xy 126.293379 -95.809812)
			(xy 126.301499 -95.864988) (xy 126.302008 -95.892874) (xy 126.301499 -95.92076) (xy 126.293379 -95.975936)
			(xy 126.277311 -96.029343) (xy 126.253639 -96.07984) (xy 126.222866 -96.126353) (xy 126.185649 -96.16789)
			(xy 126.142781 -96.203565) (xy 126.095175 -96.232619) (xy 126.043846 -96.254431) (xy 125.989889 -96.268537)
			(xy 125.934452 -96.274637) (xy 125.878718 -96.2726) (xy 125.823875 -96.26247) (xy 125.771091 -96.244463)
			(xy 125.721491 -96.218962) (xy 125.676133 -96.186511) (xy 125.635984 -96.147802) (xy 125.601898 -96.103659)
			(xy 125.574602 -96.055024) (xy 125.554679 -96.002933) (xy 125.542553 -95.948496) (xy 125.538482 -95.892874)
			(xy 122.71224 -95.892874) (xy 122.714707 -95.898137) (xy 122.730775 -95.951544) (xy 122.738895 -96.00672)
			(xy 122.739404 -96.034606) (xy 122.738895 -96.062492) (xy 122.730775 -96.117668) (xy 122.714707 -96.171075)
			(xy 122.691035 -96.221572) (xy 122.660262 -96.268085) (xy 122.623045 -96.309622) (xy 122.580177 -96.345297)
			(xy 122.532571 -96.374351) (xy 122.481242 -96.396163) (xy 122.427285 -96.410269) (xy 122.371848 -96.416369)
			(xy 122.316114 -96.414332) (xy 122.261271 -96.404202) (xy 122.208487 -96.386195) (xy 122.158887 -96.360694)
			(xy 122.113529 -96.328243) (xy 122.07338 -96.289534) (xy 122.039294 -96.245391) (xy 122.011998 -96.196756)
			(xy 121.992075 -96.144665) (xy 121.979949 -96.090228) (xy 121.975878 -96.034606) (xy 120.50141 -96.034606)
			(xy 120.500901 -96.062492) (xy 120.492781 -96.117668) (xy 120.476713 -96.171075) (xy 120.453041 -96.221572)
			(xy 120.422268 -96.268085) (xy 120.385051 -96.309622) (xy 120.342183 -96.345297) (xy 120.294577 -96.374351)
			(xy 120.243248 -96.396163) (xy 120.189291 -96.410269) (xy 120.133854 -96.416369) (xy 120.07812 -96.414332)
			(xy 120.023277 -96.404202) (xy 119.970493 -96.386195) (xy 119.920893 -96.360694) (xy 119.875535 -96.328243)
			(xy 119.835386 -96.289534) (xy 119.8013 -96.245391) (xy 119.774004 -96.196756) (xy 119.754081 -96.144665)
			(xy 119.741955 -96.090228) (xy 119.737884 -96.034606) (xy 100.136198 -96.034606) (xy 100.163449 -96.035076)
			(xy 100.217397 -96.042832) (xy 100.269692 -96.058187) (xy 100.319269 -96.080827) (xy 100.36512 -96.110293)
			(xy 100.40631 -96.145984) (xy 100.442002 -96.187174) (xy 100.471469 -96.233024) (xy 100.494111 -96.282601)
			(xy 100.509466 -96.334895) (xy 100.517224 -96.388843) (xy 100.517225 -96.429322) (xy 113.492534 -96.429322)
			(xy 113.49302 -96.402071) (xy 113.500776 -96.348123) (xy 113.516131 -96.295828) (xy 113.538773 -96.246251)
			(xy 113.568239 -96.200401) (xy 113.60393 -96.15921) (xy 113.645121 -96.123519) (xy 113.690971 -96.094053)
			(xy 113.740548 -96.071411) (xy 113.792843 -96.056056) (xy 113.846791 -96.0483) (xy 113.901293 -96.0483)
			(xy 113.955241 -96.056056) (xy 114.007536 -96.071411) (xy 114.057113 -96.094053) (xy 114.102963 -96.123519)
			(xy 114.144154 -96.15921) (xy 114.179845 -96.200401) (xy 114.209311 -96.246251) (xy 114.231953 -96.295828)
			(xy 114.247308 -96.348123) (xy 114.255064 -96.402071) (xy 114.25555 -96.429322) (xy 114.255339 -96.440498)
			(xy 128.268982 -96.440498) (xy 128.273053 -96.384876) (xy 128.285179 -96.330439) (xy 128.305102 -96.278348)
			(xy 128.332398 -96.229713) (xy 128.366484 -96.18557) (xy 128.406633 -96.146861) (xy 128.451991 -96.11441)
			(xy 128.501591 -96.088909) (xy 128.554375 -96.070902) (xy 128.609218 -96.060772) (xy 128.664952 -96.058735)
			(xy 128.720389 -96.064835) (xy 128.774346 -96.078941) (xy 128.825675 -96.100753) (xy 128.873281 -96.129807)
			(xy 128.916149 -96.165482) (xy 128.953366 -96.207019) (xy 128.984139 -96.253532) (xy 129.007811 -96.304029)
			(xy 129.023879 -96.357436) (xy 129.031999 -96.412612) (xy 129.032508 -96.440498) (xy 129.031999 -96.468384)
			(xy 129.023879 -96.52356) (xy 129.007811 -96.576967) (xy 128.984139 -96.627464) (xy 128.953366 -96.673977)
			(xy 128.916149 -96.715514) (xy 128.873281 -96.751189) (xy 128.825675 -96.780243) (xy 128.774346 -96.802055)
			(xy 128.720389 -96.816161) (xy 128.664952 -96.822261) (xy 128.609218 -96.820224) (xy 128.554375 -96.810094)
			(xy 128.501591 -96.792087) (xy 128.451991 -96.766586) (xy 128.406633 -96.734135) (xy 128.366484 -96.695426)
			(xy 128.332398 -96.651283) (xy 128.305102 -96.602648) (xy 128.285179 -96.550557) (xy 128.273053 -96.49612)
			(xy 128.268982 -96.440498) (xy 114.255339 -96.440498) (xy 114.255019 -96.457484) (xy 114.246741 -96.513196)
			(xy 114.230369 -96.567087) (xy 114.206258 -96.617989) (xy 114.17493 -96.664796) (xy 114.137067 -96.706494)
			(xy 114.115596 -96.724724) (xy 114.106873 -96.732498) (xy 114.097078 -96.753683) (xy 114.0968 -96.765364)
			(xy 114.099086 -96.857058) (xy 114.109754 -96.877632) (xy 114.119152 -96.884744) (xy 114.142549 -96.902905)
			(xy 114.184018 -96.945187) (xy 114.218455 -96.993369) (xy 114.245034 -97.046293) (xy 114.263115 -97.102689)
			(xy 114.272264 -97.161202) (xy 114.272573 -97.177606) (xy 119.737884 -97.177606) (xy 119.741955 -97.121984)
			(xy 119.754081 -97.067547) (xy 119.774004 -97.015456) (xy 119.8013 -96.966821) (xy 119.835386 -96.922678)
			(xy 119.875535 -96.883969) (xy 119.920893 -96.851518) (xy 119.970493 -96.826017) (xy 120.023277 -96.80801)
			(xy 120.07812 -96.79788) (xy 120.133854 -96.795843) (xy 120.189291 -96.801943) (xy 120.243248 -96.816049)
			(xy 120.294577 -96.837861) (xy 120.342183 -96.866915) (xy 120.385051 -96.90259) (xy 120.422268 -96.944127)
			(xy 120.453041 -96.99064) (xy 120.476713 -97.041137) (xy 120.492781 -97.094544) (xy 120.500901 -97.14972)
			(xy 120.50141 -97.177606) (xy 121.975878 -97.177606) (xy 121.979949 -97.121984) (xy 121.992075 -97.067547)
			(xy 122.011998 -97.015456) (xy 122.039294 -96.966821) (xy 122.07338 -96.922678) (xy 122.113529 -96.883969)
			(xy 122.158887 -96.851518) (xy 122.208487 -96.826017) (xy 122.261271 -96.80801) (xy 122.316114 -96.79788)
			(xy 122.371848 -96.795843) (xy 122.427285 -96.801943) (xy 122.481242 -96.816049) (xy 122.532571 -96.837861)
			(xy 122.580177 -96.866915) (xy 122.623045 -96.90259) (xy 122.660262 -96.944127) (xy 122.691035 -96.99064)
			(xy 122.714707 -97.041137) (xy 122.730775 -97.094544) (xy 122.738895 -97.14972) (xy 122.739316 -97.17278)
			(xy 124.302772 -97.17278) (xy 124.306843 -97.117158) (xy 124.318969 -97.062721) (xy 124.338892 -97.01063)
			(xy 124.366188 -96.961995) (xy 124.400274 -96.917852) (xy 124.440423 -96.879143) (xy 124.485781 -96.846692)
			(xy 124.535381 -96.821191) (xy 124.588165 -96.803184) (xy 124.643008 -96.793054) (xy 124.698742 -96.791017)
			(xy 124.754179 -96.797117) (xy 124.808136 -96.811223) (xy 124.859465 -96.833035) (xy 124.907071 -96.862089)
			(xy 124.949939 -96.897764) (xy 124.987156 -96.939301) (xy 125.017929 -96.985814) (xy 125.041601 -97.036311)
			(xy 125.057669 -97.089718) (xy 125.065789 -97.144894) (xy 125.066298 -97.17278) (xy 125.065789 -97.200666)
			(xy 125.057669 -97.255842) (xy 125.041601 -97.309249) (xy 125.017929 -97.359746) (xy 124.987156 -97.406259)
			(xy 124.949939 -97.447796) (xy 124.907071 -97.483471) (xy 124.859465 -97.512525) (xy 124.808136 -97.534337)
			(xy 124.754179 -97.548443) (xy 124.698742 -97.554543) (xy 124.643008 -97.552506) (xy 124.588165 -97.542376)
			(xy 124.535381 -97.524369) (xy 124.485781 -97.498868) (xy 124.440423 -97.466417) (xy 124.400274 -97.427708)
			(xy 124.366188 -97.383565) (xy 124.338892 -97.33493) (xy 124.318969 -97.282839) (xy 124.306843 -97.228402)
			(xy 124.302772 -97.17278) (xy 122.739316 -97.17278) (xy 122.739404 -97.177606) (xy 122.738895 -97.205492)
			(xy 122.730775 -97.260668) (xy 122.714707 -97.314075) (xy 122.691035 -97.364572) (xy 122.660262 -97.411085)
			(xy 122.623045 -97.452622) (xy 122.580177 -97.488297) (xy 122.532571 -97.517351) (xy 122.481242 -97.539163)
			(xy 122.427285 -97.553269) (xy 122.371848 -97.559369) (xy 122.316114 -97.557332) (xy 122.261271 -97.547202)
			(xy 122.208487 -97.529195) (xy 122.158887 -97.503694) (xy 122.113529 -97.471243) (xy 122.07338 -97.432534)
			(xy 122.039294 -97.388391) (xy 122.011998 -97.339756) (xy 121.992075 -97.287665) (xy 121.979949 -97.233228)
			(xy 121.975878 -97.177606) (xy 120.50141 -97.177606) (xy 120.500901 -97.205492) (xy 120.492781 -97.260668)
			(xy 120.476713 -97.314075) (xy 120.453041 -97.364572) (xy 120.422268 -97.411085) (xy 120.385051 -97.452622)
			(xy 120.342183 -97.488297) (xy 120.294577 -97.517351) (xy 120.243248 -97.539163) (xy 120.189291 -97.553269)
			(xy 120.133854 -97.559369) (xy 120.07812 -97.557332) (xy 120.023277 -97.547202) (xy 119.970493 -97.529195)
			(xy 119.920893 -97.503694) (xy 119.875535 -97.471243) (xy 119.835386 -97.432534) (xy 119.8013 -97.388391)
			(xy 119.774004 -97.339756) (xy 119.754081 -97.287665) (xy 119.741955 -97.233228) (xy 119.737884 -97.177606)
			(xy 114.272573 -97.177606) (xy 114.272822 -97.190814) (xy 114.272336 -97.218065) (xy 114.26458 -97.272013)
			(xy 114.249225 -97.324308) (xy 114.226583 -97.373885) (xy 114.197117 -97.419735) (xy 114.161426 -97.460926)
			(xy 114.120235 -97.496617) (xy 114.074385 -97.526083) (xy 114.024808 -97.548725) (xy 113.972513 -97.56408)
			(xy 113.918565 -97.571836) (xy 113.864063 -97.571836) (xy 113.810115 -97.56408) (xy 113.75782 -97.548725)
			(xy 113.708243 -97.526083) (xy 113.662393 -97.496617) (xy 113.621202 -97.460926) (xy 113.585511 -97.419735)
			(xy 113.556045 -97.373885) (xy 113.533403 -97.324308) (xy 113.518048 -97.272013) (xy 113.510292 -97.218065)
			(xy 113.509806 -97.190814) (xy 113.510272 -97.16265) (xy 113.51856 -97.106934) (xy 113.534944 -97.05304)
			(xy 113.559067 -97.002138) (xy 113.590407 -96.955333) (xy 113.628283 -96.91364) (xy 113.64976 -96.895412)
			(xy 113.658475 -96.887631) (xy 113.668272 -96.866452) (xy 113.668556 -96.854772) (xy 113.66627 -96.763078)
			(xy 113.655602 -96.742504) (xy 113.646204 -96.735392) (xy 113.622768 -96.717281) (xy 113.581303 -96.674987)
			(xy 113.546871 -96.626794) (xy 113.5203 -96.57386) (xy 113.502227 -96.517456) (xy 113.493087 -96.458937)
			(xy 113.492534 -96.429322) (xy 100.517225 -96.429322) (xy 100.517225 -96.443345) (xy 100.509469 -96.497293)
			(xy 100.494115 -96.549588) (xy 100.471475 -96.599166) (xy 100.442009 -96.645016) (xy 100.406319 -96.686207)
			(xy 100.365129 -96.7219) (xy 100.31928 -96.751367) (xy 100.269703 -96.774009) (xy 100.217409 -96.789366)
			(xy 100.163461 -96.797124) (xy 100.108959 -96.797125) (xy 100.055011 -96.78937) (xy 100.002716 -96.774016)
			(xy 99.953138 -96.751377) (xy 99.907287 -96.721912) (xy 99.866095 -96.686222) (xy 99.830403 -96.645032)
			(xy 99.800935 -96.599183) (xy 99.778292 -96.549607) (xy 99.762935 -96.497313) (xy 99.755177 -96.443365)
			(xy 99.75469 -96.416114) (xy 99.75469 -96.415606) (xy 99.754772 -96.405234) (xy 99.755915 -96.384522)
			(xy 99.756976 -96.374204) (xy 99.758131 -96.35966) (xy 99.75292 -96.33096) (xy 99.73982 -96.304898)
			(xy 99.719898 -96.283592) (xy 99.694773 -96.268774) (xy 99.666488 -96.26165) (xy 99.637341 -96.262798)
			(xy 99.623372 -96.267016) (xy 99.593761 -96.276361) (xy 99.532496 -96.286449) (xy 99.501452 -96.287082)
			(xy 99.501198 -96.287082) (xy 99.473947 -96.28662) (xy 99.420001 -96.278864) (xy 99.367707 -96.263509)
			(xy 99.318131 -96.240868) (xy 99.272281 -96.211403) (xy 99.231092 -96.175712) (xy 99.195401 -96.134523)
			(xy 99.165934 -96.088674) (xy 99.143293 -96.039098) (xy 99.127938 -95.986804) (xy 99.12018 -95.932858)
			(xy 99.120179 -95.878357) (xy 94.477301 -95.878357) (xy 94.476323 -95.885004) (xy 94.460255 -95.938411)
			(xy 94.436583 -95.988908) (xy 94.40581 -96.035421) (xy 94.368593 -96.076958) (xy 94.325725 -96.112633)
			(xy 94.278119 -96.141687) (xy 94.22679 -96.163499) (xy 94.172833 -96.177605) (xy 94.117396 -96.183705)
			(xy 94.061662 -96.181668) (xy 94.006819 -96.171538) (xy 93.954035 -96.153531) (xy 93.904435 -96.12803)
			(xy 93.859077 -96.095579) (xy 93.818928 -96.05687) (xy 93.784842 -96.012727) (xy 93.757546 -95.964092)
			(xy 93.737623 -95.912001) (xy 93.725497 -95.857564) (xy 93.721426 -95.801942) (xy 93.479112 -95.801942)
			(xy 93.478603 -95.829828) (xy 93.470483 -95.885004) (xy 93.454415 -95.938411) (xy 93.430743 -95.988908)
			(xy 93.39997 -96.035421) (xy 93.362753 -96.076958) (xy 93.319885 -96.112633) (xy 93.272279 -96.141687)
			(xy 93.22095 -96.163499) (xy 93.166993 -96.177605) (xy 93.111556 -96.183705) (xy 93.055822 -96.181668)
			(xy 93.000979 -96.171538) (xy 92.948195 -96.153531) (xy 92.898595 -96.12803) (xy 92.853237 -96.095579)
			(xy 92.813088 -96.05687) (xy 92.779002 -96.012727) (xy 92.751706 -95.964092) (xy 92.731783 -95.912001)
			(xy 92.719657 -95.857564) (xy 92.715586 -95.801942) (xy 91.438222 -95.801942) (xy 91.437713 -95.829828)
			(xy 91.429593 -95.885004) (xy 91.413525 -95.938411) (xy 91.389853 -95.988908) (xy 91.35908 -96.035421)
			(xy 91.321863 -96.076958) (xy 91.278995 -96.112633) (xy 91.231389 -96.141687) (xy 91.18006 -96.163499)
			(xy 91.126103 -96.177605) (xy 91.070666 -96.183705) (xy 91.014932 -96.181668) (xy 90.960089 -96.171538)
			(xy 90.907305 -96.153531) (xy 90.857705 -96.12803) (xy 90.812347 -96.095579) (xy 90.772198 -96.05687)
			(xy 90.738112 -96.012727) (xy 90.710816 -95.964092) (xy 90.690893 -95.912001) (xy 90.678767 -95.857564)
			(xy 90.674696 -95.801942) (xy 89.404952 -95.801942) (xy 89.404443 -95.829828) (xy 89.396323 -95.885004)
			(xy 89.380255 -95.938411) (xy 89.356583 -95.988908) (xy 89.32581 -96.035421) (xy 89.288593 -96.076958)
			(xy 89.245725 -96.112633) (xy 89.198119 -96.141687) (xy 89.14679 -96.163499) (xy 89.092833 -96.177605)
			(xy 89.037396 -96.183705) (xy 88.981662 -96.181668) (xy 88.926819 -96.171538) (xy 88.874035 -96.153531)
			(xy 88.824435 -96.12803) (xy 88.779077 -96.095579) (xy 88.738928 -96.05687) (xy 88.704842 -96.012727)
			(xy 88.677546 -95.964092) (xy 88.657623 -95.912001) (xy 88.645497 -95.857564) (xy 88.641426 -95.801942)
			(xy 76.278649 -95.801942) (xy 76.279139 -95.802682) (xy 76.302811 -95.853179) (xy 76.318879 -95.906586)
			(xy 76.326999 -95.961762) (xy 76.327508 -95.989648) (xy 76.326999 -96.017534) (xy 76.318879 -96.07271)
			(xy 76.302811 -96.126117) (xy 76.279139 -96.176614) (xy 76.248366 -96.223127) (xy 76.211149 -96.264664)
			(xy 76.168281 -96.300339) (xy 76.120675 -96.329393) (xy 76.069346 -96.351205) (xy 76.015389 -96.365311)
			(xy 75.959952 -96.371411) (xy 75.904218 -96.369374) (xy 75.849375 -96.359244) (xy 75.796591 -96.341237)
			(xy 75.746991 -96.315736) (xy 75.701633 -96.283285) (xy 75.661484 -96.244576) (xy 75.627398 -96.200433)
			(xy 75.600102 -96.151798) (xy 75.580179 -96.099707) (xy 75.568053 -96.04527) (xy 75.563982 -95.989648)
			(xy 73.443088 -95.989648) (xy 73.438312 -95.994528) (xy 73.368591 -96.054466) (xy 73.293974 -96.108189)
			(xy 73.215016 -96.155298) (xy 73.1323 -96.195446) (xy 73.04644 -96.228334) (xy 72.958069 -96.253719)
			(xy 72.867844 -96.271414) (xy 72.776431 -96.281287) (xy 72.684509 -96.283266) (xy 72.592756 -96.277334)
			(xy 72.501853 -96.263538) (xy 72.412472 -96.241978) (xy 72.325276 -96.212814) (xy 72.24091 -96.176262)
			(xy 72.159998 -96.132593) (xy 72.083139 -96.08213) (xy 72.010904 -96.025247) (xy 71.943825 -95.962365)
			(xy 71.8824 -95.893949) (xy 71.827085 -95.820506) (xy 71.778287 -95.742579) (xy 71.736369 -95.660746)
			(xy 71.701641 -95.575613) (xy 71.67436 -95.48781) (xy 71.654728 -95.397986) (xy 71.642891 -95.306807)
			(xy 71.638935 -95.214948) (xy 49.41062 -95.214948) (xy 49.410126 -95.26092) (xy 49.402222 -95.352524)
			(xy 49.386472 -95.443109) (xy 49.362994 -95.532005) (xy 49.331961 -95.618554) (xy 49.293602 -95.702114)
			(xy 49.248203 -95.782068) (xy 49.196098 -95.857822) (xy 49.137673 -95.928818) (xy 49.073362 -95.994528)
			(xy 49.003641 -96.054466) (xy 48.929024 -96.108189) (xy 48.850066 -96.155298) (xy 48.76735 -96.195446)
			(xy 48.68149 -96.228334) (xy 48.593119 -96.253719) (xy 48.502894 -96.271414) (xy 48.411481 -96.281287)
			(xy 48.319559 -96.283266) (xy 48.227806 -96.277334) (xy 48.136903 -96.263538) (xy 48.047522 -96.241978)
			(xy 47.960326 -96.212814) (xy 47.87596 -96.176262) (xy 47.795048 -96.132593) (xy 47.718189 -96.08213)
			(xy 47.645954 -96.025247) (xy 47.578875 -95.962365) (xy 47.51745 -95.893949) (xy 47.462135 -95.820506)
			(xy 47.413337 -95.742579) (xy 47.371419 -95.660746) (xy 47.336691 -95.575613) (xy 47.30941 -95.48781)
			(xy 47.289778 -95.397986) (xy 47.277941 -95.306807) (xy 47.273985 -95.214948) (xy 25.32774 -95.214948)
			(xy 25.313581 -95.262009) (xy 25.289909 -95.312506) (xy 25.259136 -95.359019) (xy 25.221919 -95.400556)
			(xy 25.179051 -95.436231) (xy 25.131445 -95.465285) (xy 25.080116 -95.487097) (xy 25.026159 -95.501203)
			(xy 24.970722 -95.507303) (xy 24.914988 -95.505266) (xy 24.860145 -95.495136) (xy 24.807361 -95.477129)
			(xy 24.757761 -95.451628) (xy 24.712403 -95.419177) (xy 24.672254 -95.380468) (xy 24.638168 -95.336325)
			(xy 24.610872 -95.28769) (xy 24.590949 -95.235599) (xy 24.578823 -95.181162) (xy 24.574752 -95.12554)
			(xy 4.421886 -95.12554) (xy 4.421886 -95.986092) (xy 25.048462 -95.986092) (xy 25.052533 -95.93047)
			(xy 25.064659 -95.876033) (xy 25.084582 -95.823942) (xy 25.111878 -95.775307) (xy 25.145964 -95.731164)
			(xy 25.186113 -95.692455) (xy 25.231471 -95.660004) (xy 25.281071 -95.634503) (xy 25.333855 -95.616496)
			(xy 25.388698 -95.606366) (xy 25.444432 -95.604329) (xy 25.499869 -95.610429) (xy 25.553826 -95.624535)
			(xy 25.605155 -95.646347) (xy 25.652761 -95.675401) (xy 25.695629 -95.711076) (xy 25.732846 -95.752613)
			(xy 25.763619 -95.799126) (xy 25.787291 -95.849623) (xy 25.803359 -95.90303) (xy 25.811479 -95.958206)
			(xy 25.811988 -95.986092) (xy 25.811479 -96.013978) (xy 25.803359 -96.069154) (xy 25.787291 -96.122561)
			(xy 25.763619 -96.173058) (xy 25.732846 -96.219571) (xy 25.695629 -96.261108) (xy 25.652761 -96.296783)
			(xy 25.605155 -96.325837) (xy 25.553826 -96.347649) (xy 25.499869 -96.361755) (xy 25.444432 -96.367855)
			(xy 25.388698 -96.365818) (xy 25.333855 -96.355688) (xy 25.281071 -96.337681) (xy 25.231471 -96.31218)
			(xy 25.186113 -96.279729) (xy 25.145964 -96.24102) (xy 25.111878 -96.196877) (xy 25.084582 -96.148242)
			(xy 25.064659 -96.096151) (xy 25.052533 -96.041714) (xy 25.048462 -95.986092) (xy 4.421886 -95.986092)
			(xy 4.421886 -97.021904) (xy 25.034746 -97.021904) (xy 25.038817 -96.966282) (xy 25.050943 -96.911845)
			(xy 25.070866 -96.859754) (xy 25.098162 -96.811119) (xy 25.132248 -96.766976) (xy 25.172397 -96.728267)
			(xy 25.217755 -96.695816) (xy 25.267355 -96.670315) (xy 25.320139 -96.652308) (xy 25.374982 -96.642178)
			(xy 25.430716 -96.640141) (xy 25.486153 -96.646241) (xy 25.54011 -96.660347) (xy 25.591439 -96.682159)
			(xy 25.639045 -96.711213) (xy 25.681913 -96.746888) (xy 25.71913 -96.788425) (xy 25.749903 -96.834938)
			(xy 25.773575 -96.885435) (xy 25.789643 -96.938842) (xy 25.797763 -96.994018) (xy 25.798272 -97.021904)
			(xy 25.797763 -97.04979) (xy 25.789643 -97.104966) (xy 25.773575 -97.158373) (xy 25.749903 -97.20887)
			(xy 25.71913 -97.255383) (xy 25.681913 -97.29692) (xy 25.639045 -97.332595) (xy 25.591439 -97.361649)
			(xy 25.54011 -97.383461) (xy 25.486153 -97.397567) (xy 25.430716 -97.403667) (xy 25.374982 -97.40163)
			(xy 25.320139 -97.3915) (xy 25.267355 -97.373493) (xy 25.217755 -97.347992) (xy 25.172397 -97.315541)
			(xy 25.132248 -97.276832) (xy 25.098162 -97.232689) (xy 25.070866 -97.184054) (xy 25.050943 -97.131963)
			(xy 25.038817 -97.077526) (xy 25.034746 -97.021904) (xy 4.421886 -97.021904) (xy 4.421886 -112.501426)
			(xy 11.973304 -112.501426) (xy 11.977375 -112.445804) (xy 11.989501 -112.391367) (xy 12.009424 -112.339276)
			(xy 12.03672 -112.290641) (xy 12.070806 -112.246498) (xy 12.110955 -112.207789) (xy 12.156313 -112.175338)
			(xy 12.205913 -112.149837) (xy 12.258697 -112.13183) (xy 12.31354 -112.1217) (xy 12.369274 -112.119663)
			(xy 12.424711 -112.125763) (xy 12.478668 -112.139869) (xy 12.529997 -112.161681) (xy 12.577603 -112.190735)
			(xy 12.620471 -112.22641) (xy 12.657688 -112.267947) (xy 12.688461 -112.31446) (xy 12.712133 -112.364957)
			(xy 12.728201 -112.418364) (xy 12.736321 -112.47354) (xy 12.73683 -112.501426) (xy 12.736321 -112.529312)
			(xy 12.728201 -112.584488) (xy 12.712133 -112.637895) (xy 12.688461 -112.688392) (xy 12.657688 -112.734905)
			(xy 12.620471 -112.776442) (xy 12.577603 -112.812117) (xy 12.529997 -112.841171) (xy 12.478668 -112.862983)
			(xy 12.424711 -112.877089) (xy 12.369274 -112.883189) (xy 12.31354 -112.881152) (xy 12.258697 -112.871022)
			(xy 12.205913 -112.853015) (xy 12.156313 -112.827514) (xy 12.110955 -112.795063) (xy 12.070806 -112.756354)
			(xy 12.03672 -112.712211) (xy 12.009424 -112.663576) (xy 11.989501 -112.611485) (xy 11.977375 -112.557048)
			(xy 11.973304 -112.501426) (xy 4.421886 -112.501426) (xy 4.421886 -113.302034) (xy 14.31366 -113.302034)
			(xy 14.317731 -113.246412) (xy 14.329857 -113.191975) (xy 14.34978 -113.139884) (xy 14.377076 -113.091249)
			(xy 14.411162 -113.047106) (xy 14.451311 -113.008397) (xy 14.496669 -112.975946) (xy 14.546269 -112.950445)
			(xy 14.599053 -112.932438) (xy 14.653896 -112.922308) (xy 14.70963 -112.920271) (xy 14.765067 -112.926371)
			(xy 14.819024 -112.940477) (xy 14.870353 -112.962289) (xy 14.917959 -112.991343) (xy 14.960827 -113.027018)
			(xy 14.998044 -113.068555) (xy 15.028817 -113.115068) (xy 15.052489 -113.165565) (xy 15.057783 -113.183162)
			(xy 16.31518 -113.183162) (xy 16.319251 -113.12754) (xy 16.331377 -113.073103) (xy 16.3513 -113.021012)
			(xy 16.378596 -112.972377) (xy 16.412682 -112.928234) (xy 16.452831 -112.889525) (xy 16.498189 -112.857074)
			(xy 16.547789 -112.831573) (xy 16.600573 -112.813566) (xy 16.655416 -112.803436) (xy 16.71115 -112.801399)
			(xy 16.766587 -112.807499) (xy 16.820544 -112.821605) (xy 16.871873 -112.843417) (xy 16.919479 -112.872471)
			(xy 16.962347 -112.908146) (xy 16.999564 -112.949683) (xy 17.030337 -112.996196) (xy 17.054009 -113.046693)
			(xy 17.070077 -113.1001) (xy 17.078197 -113.155276) (xy 17.078706 -113.183162) (xy 17.078197 -113.211048)
			(xy 17.070077 -113.266224) (xy 17.054009 -113.319631) (xy 17.030337 -113.370128) (xy 16.999564 -113.416641)
			(xy 16.962347 -113.458178) (xy 16.919479 -113.493853) (xy 16.871873 -113.522907) (xy 16.820544 -113.544719)
			(xy 16.766587 -113.558825) (xy 16.71115 -113.564925) (xy 16.655416 -113.562888) (xy 16.600573 -113.552758)
			(xy 16.547789 -113.534751) (xy 16.498189 -113.50925) (xy 16.452831 -113.476799) (xy 16.412682 -113.43809)
			(xy 16.378596 -113.393947) (xy 16.3513 -113.345312) (xy 16.331377 -113.293221) (xy 16.319251 -113.238784)
			(xy 16.31518 -113.183162) (xy 15.057783 -113.183162) (xy 15.068557 -113.218972) (xy 15.076677 -113.274148)
			(xy 15.077186 -113.302034) (xy 15.076677 -113.32992) (xy 15.068557 -113.385096) (xy 15.052489 -113.438503)
			(xy 15.028817 -113.489) (xy 14.998044 -113.535513) (xy 14.960827 -113.57705) (xy 14.917959 -113.612725)
			(xy 14.870353 -113.641779) (xy 14.819024 -113.663591) (xy 14.765067 -113.677697) (xy 14.70963 -113.683797)
			(xy 14.653896 -113.68176) (xy 14.599053 -113.67163) (xy 14.546269 -113.653623) (xy 14.496669 -113.628122)
			(xy 14.451311 -113.595671) (xy 14.411162 -113.556962) (xy 14.377076 -113.512819) (xy 14.34978 -113.464184)
			(xy 14.329857 -113.412093) (xy 14.317731 -113.357656) (xy 14.31366 -113.302034) (xy 4.421886 -113.302034)
			(xy 4.421886 -114.660426) (xy 11.961366 -114.660426) (xy 11.965437 -114.604804) (xy 11.977563 -114.550367)
			(xy 11.997486 -114.498276) (xy 12.024782 -114.449641) (xy 12.058868 -114.405498) (xy 12.099017 -114.366789)
			(xy 12.144375 -114.334338) (xy 12.193975 -114.308837) (xy 12.246759 -114.29083) (xy 12.301602 -114.2807)
			(xy 12.357336 -114.278663) (xy 12.412773 -114.284763) (xy 12.46673 -114.298869) (xy 12.518059 -114.320681)
			(xy 12.565665 -114.349735) (xy 12.608533 -114.38541) (xy 12.64575 -114.426947) (xy 12.676523 -114.47346)
			(xy 12.700195 -114.523957) (xy 12.716263 -114.577364) (xy 12.724383 -114.63254) (xy 12.724892 -114.660426)
			(xy 12.724383 -114.688312) (xy 12.716263 -114.743488) (xy 12.700195 -114.796895) (xy 12.676523 -114.847392)
			(xy 12.64575 -114.893905) (xy 12.608533 -114.935442) (xy 12.565665 -114.971117) (xy 12.518059 -115.000171)
			(xy 12.46673 -115.021983) (xy 12.412773 -115.036089) (xy 12.357336 -115.042189) (xy 12.301602 -115.040152)
			(xy 12.246759 -115.030022) (xy 12.193975 -115.012015) (xy 12.144375 -114.986514) (xy 12.099017 -114.954063)
			(xy 12.058868 -114.915354) (xy 12.024782 -114.871211) (xy 11.997486 -114.822576) (xy 11.977563 -114.770485)
			(xy 11.965437 -114.716048) (xy 11.961366 -114.660426) (xy 4.421886 -114.660426) (xy 4.421886 -117.434106)
			(xy 13.37691 -117.434106) (xy 13.377377 -117.406736) (xy 13.385194 -117.352557) (xy 13.400683 -117.300053)
			(xy 13.423525 -117.250307) (xy 13.453249 -117.20434) (xy 13.47089 -117.183408) (xy 13.471144 -117.183154)
			(xy 13.476719 -117.17606) (xy 13.482972 -117.159149) (xy 13.483336 -117.150134) (xy 13.483336 -117.083078)
			(xy 13.482982 -117.074061) (xy 13.476732 -117.057144) (xy 13.471144 -117.050058) (xy 13.47089 -117.050058)
			(xy 13.47089 -117.049804) (xy 13.453257 -117.028866) (xy 13.423535 -116.982898) (xy 13.400691 -116.933152)
			(xy 13.385196 -116.880652) (xy 13.377368 -116.826474) (xy 13.377367 -116.771735) (xy 13.385194 -116.717557)
			(xy 13.400688 -116.665056) (xy 13.42353 -116.61531) (xy 13.453251 -116.569341) (xy 13.47089 -116.548408)
			(xy 13.471144 -116.548154) (xy 13.476719 -116.54106) (xy 13.482972 -116.524149) (xy 13.483336 -116.515134)
			(xy 13.483336 -116.448078) (xy 13.482982 -116.439061) (xy 13.476732 -116.422144) (xy 13.471144 -116.415058)
			(xy 13.47089 -116.415058) (xy 13.47089 -116.414804) (xy 13.453238 -116.393883) (xy 13.423528 -116.347907)
			(xy 13.400695 -116.298156) (xy 13.385207 -116.245653) (xy 13.377382 -116.191476) (xy 13.37691 -116.164106)
			(xy 13.377361 -116.136852) (xy 13.385118 -116.0829) (xy 13.400474 -116.030601) (xy 13.423117 -115.98102)
			(xy 13.452586 -115.935166) (xy 13.488281 -115.893972) (xy 13.529475 -115.858279) (xy 13.57533 -115.828811)
			(xy 13.624912 -115.80617) (xy 13.677212 -115.790815) (xy 13.731164 -115.78306) (xy 13.758418 -115.782598)
			(xy 13.785789 -115.783054) (xy 13.839968 -115.790874) (xy 13.892471 -115.806366) (xy 13.942218 -115.82921)
			(xy 13.988184 -115.858936) (xy 14.009116 -115.876578) (xy 14.00937 -115.876832) (xy 14.016458 -115.882416)
			(xy 14.033374 -115.888663) (xy 14.04239 -115.889024) (xy 14.109446 -115.889024) (xy 14.11846 -115.888636)
			(xy 14.135377 -115.882409) (xy 14.142466 -115.876832) (xy 14.142466 -115.876578) (xy 14.14272 -115.876578)
			(xy 14.163669 -115.85896) (xy 14.209637 -115.829245) (xy 14.259381 -115.806406) (xy 14.311877 -115.79091)
			(xy 14.36605 -115.783075) (xy 14.393418 -115.782598) (xy 14.42067 -115.783061) (xy 14.474619 -115.79082)
			(xy 14.526914 -115.806178) (xy 14.576492 -115.828822) (xy 14.622343 -115.85829) (xy 14.663533 -115.893984)
			(xy 14.699224 -115.935177) (xy 14.72869 -115.981029) (xy 14.75133 -116.030608) (xy 14.766685 -116.082905)
			(xy 14.774441 -116.136854) (xy 14.774926 -116.164106) (xy 14.774481 -116.191477) (xy 14.766661 -116.245658)
			(xy 14.751168 -116.298162) (xy 14.728321 -116.347909) (xy 14.69859 -116.393874) (xy 14.680946 -116.414804)
			(xy 14.680692 -116.415058) (xy 14.675116 -116.422152) (xy 14.668863 -116.439063) (xy 14.6685 -116.448078)
			(xy 14.6685 -116.515134) (xy 14.668841 -116.524152) (xy 14.6751 -116.541069) (xy 14.680692 -116.548154)
			(xy 14.680946 -116.548154) (xy 14.680946 -116.548408) (xy 14.698594 -116.569335) (xy 14.72832 -116.615303)
			(xy 14.751167 -116.66505) (xy 14.766664 -116.717554) (xy 14.774493 -116.771733) (xy 14.774492 -116.826476)
			(xy 14.766662 -116.880655) (xy 14.751164 -116.933158) (xy 14.728316 -116.982904) (xy 14.698588 -117.028872)
			(xy 14.680946 -117.049804) (xy 14.680692 -117.050058) (xy 14.675116 -117.057152) (xy 14.668863 -117.074063)
			(xy 14.6685 -117.083078) (xy 14.6685 -117.150134) (xy 14.668841 -117.159152) (xy 14.6751 -117.176069)
			(xy 14.680692 -117.183154) (xy 14.680946 -117.183154) (xy 14.680946 -117.183408) (xy 14.698594 -117.204333)
			(xy 14.728306 -117.250307) (xy 14.751141 -117.300056) (xy 14.76663 -117.352559) (xy 14.774454 -117.406736)
			(xy 14.774926 -117.434106) (xy 14.774786 -117.442234) (xy 15.659098 -117.442234) (xy 15.663169 -117.386612)
			(xy 15.675295 -117.332175) (xy 15.695218 -117.280084) (xy 15.722514 -117.231449) (xy 15.7566 -117.187306)
			(xy 15.796749 -117.148597) (xy 15.842107 -117.116146) (xy 15.891707 -117.090645) (xy 15.944491 -117.072638)
			(xy 15.999334 -117.062508) (xy 16.055068 -117.060471) (xy 16.110505 -117.066571) (xy 16.164462 -117.080677)
			(xy 16.215791 -117.102489) (xy 16.263397 -117.131543) (xy 16.306265 -117.167218) (xy 16.343482 -117.208755)
			(xy 16.374255 -117.255268) (xy 16.397927 -117.305765) (xy 16.413995 -117.359172) (xy 16.422115 -117.414348)
			(xy 16.422624 -117.442234) (xy 16.422115 -117.47012) (xy 16.413995 -117.525296) (xy 16.397927 -117.578703)
			(xy 16.374255 -117.6292) (xy 16.343482 -117.675713) (xy 16.306265 -117.71725) (xy 16.263397 -117.752925)
			(xy 16.215791 -117.781979) (xy 16.164462 -117.803791) (xy 16.110505 -117.817897) (xy 16.055068 -117.823997)
			(xy 15.999334 -117.82196) (xy 15.944491 -117.81183) (xy 15.891707 -117.793823) (xy 15.842107 -117.768322)
			(xy 15.796749 -117.735871) (xy 15.7566 -117.697162) (xy 15.722514 -117.653019) (xy 15.695218 -117.604384)
			(xy 15.675295 -117.552293) (xy 15.663169 -117.497856) (xy 15.659098 -117.442234) (xy 14.774786 -117.442234)
			(xy 14.774469 -117.460662) (xy 14.767101 -117.513262) (xy 14.752509 -117.564331) (xy 14.74216 -117.588792)
			(xy 14.737815 -117.600161) (xy 14.739162 -117.624433) (xy 14.7447 -117.635274) (xy 14.786102 -117.706394)
			(xy 14.792839 -117.716462) (xy 14.813244 -117.729453) (xy 14.825218 -117.731286) (xy 14.853196 -117.734495)
			(xy 14.90786 -117.748027) (xy 14.959939 -117.769449) (xy 15.008302 -117.798296) (xy 15.051898 -117.833941)
			(xy 15.089779 -117.875609) (xy 15.121122 -117.922394) (xy 15.145244 -117.973279) (xy 15.161622 -118.027158)
			(xy 15.167063 -118.063772) (xy 16.806162 -118.063772) (xy 16.810233 -118.00815) (xy 16.822359 -117.953713)
			(xy 16.842282 -117.901622) (xy 16.869578 -117.852987) (xy 16.903664 -117.808844) (xy 16.943813 -117.770135)
			(xy 16.989171 -117.737684) (xy 17.038771 -117.712183) (xy 17.091555 -117.694176) (xy 17.146398 -117.684046)
			(xy 17.202132 -117.682009) (xy 17.257569 -117.688109) (xy 17.311526 -117.702215) (xy 17.362855 -117.724027)
			(xy 17.410461 -117.753081) (xy 17.453329 -117.788756) (xy 17.490546 -117.830293) (xy 17.521319 -117.876806)
			(xy 17.544991 -117.927303) (xy 17.561059 -117.98071) (xy 17.567078 -118.021608) (xy 17.685512 -118.021608)
			(xy 17.68598 -117.994238) (xy 17.693797 -117.940059) (xy 17.709285 -117.887555) (xy 17.732127 -117.837809)
			(xy 17.761851 -117.791842) (xy 17.779492 -117.77091) (xy 17.779746 -117.770656) (xy 17.785321 -117.763562)
			(xy 17.791573 -117.746651) (xy 17.791938 -117.737636) (xy 17.791938 -117.67058) (xy 17.791582 -117.661563)
			(xy 17.785333 -117.644647) (xy 17.779746 -117.63756) (xy 17.779492 -117.63756) (xy 17.779492 -117.637306)
			(xy 17.761861 -117.616366) (xy 17.732138 -117.570399) (xy 17.709294 -117.520653) (xy 17.693799 -117.468153)
			(xy 17.68597 -117.413976) (xy 17.68597 -117.359236) (xy 17.693796 -117.305059) (xy 17.70929 -117.252558)
			(xy 17.732132 -117.202812) (xy 17.761853 -117.156843) (xy 17.779492 -117.13591) (xy 17.779746 -117.135656)
			(xy 17.785321 -117.128562) (xy 17.791573 -117.111651) (xy 17.791938 -117.102636) (xy 17.791938 -117.03558)
			(xy 17.791582 -117.026563) (xy 17.785333 -117.009647) (xy 17.779746 -117.00256) (xy 17.779492 -117.00256)
			(xy 17.779492 -117.002306) (xy 17.761841 -116.981384) (xy 17.732131 -116.935408) (xy 17.709298 -116.885658)
			(xy 17.693809 -116.833155) (xy 17.685984 -116.778978) (xy 17.685512 -116.751608) (xy 17.685963 -116.724354)
			(xy 17.693719 -116.670402) (xy 17.709075 -116.618103) (xy 17.731718 -116.568521) (xy 17.761187 -116.522667)
			(xy 17.796882 -116.481474) (xy 17.838077 -116.44578) (xy 17.883932 -116.416313) (xy 17.933514 -116.393671)
			(xy 17.985814 -116.378317) (xy 18.039766 -116.370562) (xy 18.06702 -116.3701) (xy 18.094391 -116.370554)
			(xy 18.14857 -116.378375) (xy 18.201073 -116.393867) (xy 18.25082 -116.416711) (xy 18.296787 -116.446438)
			(xy 18.317718 -116.46408) (xy 18.317972 -116.464334) (xy 18.32506 -116.469919) (xy 18.341976 -116.476165)
			(xy 18.350992 -116.476526) (xy 18.418048 -116.476526) (xy 18.427062 -116.476139) (xy 18.443979 -116.469912)
			(xy 18.451068 -116.464334) (xy 18.451068 -116.46408) (xy 18.451322 -116.46408) (xy 18.47227 -116.446461)
			(xy 18.518239 -116.416747) (xy 18.567982 -116.393907) (xy 18.620479 -116.378411) (xy 18.674652 -116.370577)
			(xy 18.70202 -116.3701) (xy 18.729272 -116.370559) (xy 18.783221 -116.378319) (xy 18.835517 -116.393677)
			(xy 18.885095 -116.416321) (xy 18.930945 -116.44579) (xy 18.972136 -116.481484) (xy 19.007827 -116.522677)
			(xy 19.037293 -116.56853) (xy 19.059933 -116.618109) (xy 19.075287 -116.670406) (xy 19.083043 -116.724356)
			(xy 19.083528 -116.751608) (xy 19.083084 -116.778979) (xy 19.075264 -116.83316) (xy 19.05977 -116.885664)
			(xy 19.036923 -116.935411) (xy 19.007192 -116.981376) (xy 18.989548 -117.002306) (xy 18.989294 -117.00256)
			(xy 18.983717 -117.009653) (xy 18.977465 -117.026565) (xy 18.977102 -117.03558) (xy 18.977102 -117.102636)
			(xy 18.977442 -117.111655) (xy 18.983701 -117.128571) (xy 18.989294 -117.135656) (xy 18.989548 -117.135656)
			(xy 18.989548 -117.13591) (xy 19.007198 -117.156836) (xy 19.036924 -117.202804) (xy 19.05977 -117.252551)
			(xy 19.075267 -117.305055) (xy 19.083095 -117.359235) (xy 19.083095 -117.413977) (xy 19.075265 -117.468157)
			(xy 19.059766 -117.52066) (xy 19.036918 -117.570406) (xy 19.00719 -117.616374) (xy 18.989548 -117.637306)
			(xy 18.989294 -117.63756) (xy 18.983717 -117.644653) (xy 18.977465 -117.661565) (xy 18.977102 -117.67058)
			(xy 18.977102 -117.737636) (xy 18.977442 -117.746655) (xy 18.983701 -117.763571) (xy 18.989294 -117.770656)
			(xy 18.989548 -117.770656) (xy 18.989548 -117.77091) (xy 19.007197 -117.791834) (xy 19.036909 -117.837808)
			(xy 19.059744 -117.887558) (xy 19.075233 -117.94006) (xy 19.083057 -117.994238) (xy 19.083528 -118.021608)
			(xy 19.08303 -118.048859) (xy 19.075273 -118.102805) (xy 19.059918 -118.155098) (xy 19.037277 -118.204674)
			(xy 19.007812 -118.250523) (xy 18.972122 -118.291713) (xy 18.930933 -118.327404) (xy 18.885085 -118.356871)
			(xy 18.835509 -118.379513) (xy 18.783217 -118.39487) (xy 18.729271 -118.402629) (xy 18.70202 -118.403116)
			(xy 18.674649 -118.402659) (xy 18.620469 -118.394842) (xy 18.567965 -118.379352) (xy 18.518218 -118.356508)
			(xy 18.472252 -118.326779) (xy 18.451322 -118.309136) (xy 18.451068 -118.308882) (xy 18.443968 -118.303316)
			(xy 18.427061 -118.297057) (xy 18.418048 -118.29669) (xy 18.350992 -118.29669) (xy 18.341975 -118.297045)
			(xy 18.325058 -118.303294) (xy 18.317972 -118.308882) (xy 18.317972 -118.309136) (xy 18.317718 -118.309136)
			(xy 18.296795 -118.326786) (xy 18.250819 -118.356495) (xy 18.201069 -118.379328) (xy 18.148567 -118.394817)
			(xy 18.09439 -118.402643) (xy 18.06702 -118.403116) (xy 18.039768 -118.402626) (xy 17.985818 -118.394872)
			(xy 17.933522 -118.379519) (xy 17.883942 -118.356879) (xy 17.838089 -118.327414) (xy 17.796897 -118.291723)
			(xy 17.761203 -118.250533) (xy 17.731734 -118.204683) (xy 17.709091 -118.155105) (xy 17.693734 -118.102809)
			(xy 17.685976 -118.04886) (xy 17.685512 -118.021608) (xy 17.567078 -118.021608) (xy 17.569179 -118.035886)
			(xy 17.569688 -118.063772) (xy 17.569179 -118.091658) (xy 17.561059 -118.146834) (xy 17.544991 -118.200241)
			(xy 17.521319 -118.250738) (xy 17.490546 -118.297251) (xy 17.453329 -118.338788) (xy 17.410461 -118.374463)
			(xy 17.362855 -118.403517) (xy 17.311526 -118.425329) (xy 17.257569 -118.439435) (xy 17.202132 -118.445535)
			(xy 17.146398 -118.443498) (xy 17.091555 -118.433368) (xy 17.038771 -118.415361) (xy 16.989171 -118.38986)
			(xy 16.943813 -118.357409) (xy 16.903664 -118.3187) (xy 16.869578 -118.274557) (xy 16.842282 -118.225922)
			(xy 16.822359 -118.173831) (xy 16.810233 -118.119394) (xy 16.806162 -118.063772) (xy 15.167063 -118.063772)
			(xy 15.1699 -118.082859) (xy 15.170404 -118.111016) (xy 15.169918 -118.138267) (xy 15.162162 -118.192215)
			(xy 15.146807 -118.24451) (xy 15.124165 -118.294087) (xy 15.094699 -118.339937) (xy 15.059008 -118.381128)
			(xy 15.017817 -118.416819) (xy 14.971967 -118.446285) (xy 14.92239 -118.468927) (xy 14.870095 -118.484282)
			(xy 14.816147 -118.492038) (xy 14.761645 -118.492038) (xy 14.707697 -118.484282) (xy 14.655402 -118.468927)
			(xy 14.605825 -118.446285) (xy 14.559975 -118.416819) (xy 14.518784 -118.381128) (xy 14.483093 -118.339937)
			(xy 14.453627 -118.294087) (xy 14.430985 -118.24451) (xy 14.41563 -118.192215) (xy 14.407874 -118.138267)
			(xy 14.407388 -118.111016) (xy 14.407851 -118.08446) (xy 14.415217 -118.031861) (xy 14.429807 -117.980792)
			(xy 14.440154 -117.95633) (xy 14.444483 -117.944956) (xy 14.443146 -117.920689) (xy 14.437614 -117.909848)
			(xy 14.396212 -117.838728) (xy 14.389488 -117.828651) (xy 14.369072 -117.815667) (xy 14.357096 -117.813836)
			(xy 14.32762 -117.810473) (xy 14.270151 -117.79575) (xy 14.215655 -117.772305) (xy 14.165446 -117.740706)
			(xy 14.14272 -117.721634) (xy 14.142466 -117.72138) (xy 14.135366 -117.715813) (xy 14.11846 -117.709555)
			(xy 14.109446 -117.709188) (xy 14.04239 -117.709188) (xy 14.033373 -117.709543) (xy 14.016456 -117.715792)
			(xy 14.00937 -117.72138) (xy 14.00937 -117.721634) (xy 14.009116 -117.721634) (xy 13.988193 -117.739284)
			(xy 13.942217 -117.768993) (xy 13.892467 -117.791827) (xy 13.839965 -117.807315) (xy 13.785788 -117.815141)
			(xy 13.758418 -117.815614) (xy 13.731166 -117.815128) (xy 13.677216 -117.807374) (xy 13.624919 -117.79202)
			(xy 13.575339 -117.76938) (xy 13.529486 -117.739915) (xy 13.488294 -117.704223) (xy 13.4526 -117.663033)
			(xy 13.423131 -117.617182) (xy 13.400488 -117.567604) (xy 13.385132 -117.515307) (xy 13.377374 -117.461358)
			(xy 13.37691 -117.434106) (xy 4.421886 -117.434106) (xy 4.421886 -118.089426) (xy 10.195304 -118.089426)
			(xy 10.199375 -118.033804) (xy 10.211501 -117.979367) (xy 10.231424 -117.927276) (xy 10.25872 -117.878641)
			(xy 10.292806 -117.834498) (xy 10.332955 -117.795789) (xy 10.378313 -117.763338) (xy 10.427913 -117.737837)
			(xy 10.480697 -117.71983) (xy 10.53554 -117.7097) (xy 10.591274 -117.707663) (xy 10.646711 -117.713763)
			(xy 10.700668 -117.727869) (xy 10.751997 -117.749681) (xy 10.799603 -117.778735) (xy 10.842471 -117.81441)
			(xy 10.879688 -117.855947) (xy 10.910461 -117.90246) (xy 10.934133 -117.952957) (xy 10.936982 -117.962426)
			(xy 12.227304 -117.962426) (xy 12.231375 -117.906804) (xy 12.243501 -117.852367) (xy 12.263424 -117.800276)
			(xy 12.29072 -117.751641) (xy 12.324806 -117.707498) (xy 12.364955 -117.668789) (xy 12.410313 -117.636338)
			(xy 12.459913 -117.610837) (xy 12.512697 -117.59283) (xy 12.56754 -117.5827) (xy 12.623274 -117.580663)
			(xy 12.678711 -117.586763) (xy 12.732668 -117.600869) (xy 12.783997 -117.622681) (xy 12.831603 -117.651735)
			(xy 12.874471 -117.68741) (xy 12.911688 -117.728947) (xy 12.942461 -117.77546) (xy 12.966133 -117.825957)
			(xy 12.982201 -117.879364) (xy 12.990321 -117.93454) (xy 12.99083 -117.962426) (xy 12.990321 -117.990312)
			(xy 12.982201 -118.045488) (xy 12.966133 -118.098895) (xy 12.942461 -118.149392) (xy 12.911688 -118.195905)
			(xy 12.874471 -118.237442) (xy 12.831603 -118.273117) (xy 12.783997 -118.302171) (xy 12.732668 -118.323983)
			(xy 12.678711 -118.338089) (xy 12.623274 -118.344189) (xy 12.56754 -118.342152) (xy 12.512697 -118.332022)
			(xy 12.459913 -118.314015) (xy 12.410313 -118.288514) (xy 12.364955 -118.256063) (xy 12.324806 -118.217354)
			(xy 12.29072 -118.173211) (xy 12.263424 -118.124576) (xy 12.243501 -118.072485) (xy 12.231375 -118.018048)
			(xy 12.227304 -117.962426) (xy 10.936982 -117.962426) (xy 10.950201 -118.006364) (xy 10.958321 -118.06154)
			(xy 10.95883 -118.089426) (xy 10.958321 -118.117312) (xy 10.950201 -118.172488) (xy 10.934133 -118.225895)
			(xy 10.910461 -118.276392) (xy 10.879688 -118.322905) (xy 10.842471 -118.364442) (xy 10.799603 -118.400117)
			(xy 10.751997 -118.429171) (xy 10.700668 -118.450983) (xy 10.646711 -118.465089) (xy 10.591274 -118.471189)
			(xy 10.53554 -118.469152) (xy 10.480697 -118.459022) (xy 10.427913 -118.441015) (xy 10.378313 -118.415514)
			(xy 10.332955 -118.383063) (xy 10.292806 -118.344354) (xy 10.25872 -118.300211) (xy 10.231424 -118.251576)
			(xy 10.211501 -118.199485) (xy 10.199375 -118.145048) (xy 10.195304 -118.089426) (xy 4.421886 -118.089426)
			(xy 4.421886 -120.248426) (xy 10.195304 -120.248426) (xy 10.199375 -120.192804) (xy 10.211501 -120.138367)
			(xy 10.231424 -120.086276) (xy 10.25872 -120.037641) (xy 10.292806 -119.993498) (xy 10.332955 -119.954789)
			(xy 10.378313 -119.922338) (xy 10.427913 -119.896837) (xy 10.480697 -119.87883) (xy 10.53554 -119.8687)
			(xy 10.591274 -119.866663) (xy 10.646711 -119.872763) (xy 10.700668 -119.886869) (xy 10.751997 -119.908681)
			(xy 10.799603 -119.937735) (xy 10.842471 -119.97341) (xy 10.879688 -120.014947) (xy 10.910461 -120.06146)
			(xy 10.934133 -120.111957) (xy 10.935912 -120.11787) (xy 11.211304 -120.11787) (xy 11.215375 -120.062248)
			(xy 11.227501 -120.007811) (xy 11.247424 -119.95572) (xy 11.27472 -119.907085) (xy 11.308806 -119.862942)
			(xy 11.348955 -119.824233) (xy 11.394313 -119.791782) (xy 11.443913 -119.766281) (xy 11.496697 -119.748274)
			(xy 11.55154 -119.738144) (xy 11.607274 -119.736107) (xy 11.662711 -119.742207) (xy 11.716668 -119.756313)
			(xy 11.767997 -119.778125) (xy 11.815603 -119.807179) (xy 11.858471 -119.842854) (xy 11.895688 -119.884391)
			(xy 11.926461 -119.930904) (xy 11.950133 -119.981401) (xy 11.966201 -120.034808) (xy 11.974321 -120.089984)
			(xy 11.97483 -120.11787) (xy 12.227304 -120.11787) (xy 12.231375 -120.062248) (xy 12.243501 -120.007811)
			(xy 12.263424 -119.95572) (xy 12.29072 -119.907085) (xy 12.324806 -119.862942) (xy 12.364955 -119.824233)
			(xy 12.410313 -119.791782) (xy 12.459913 -119.766281) (xy 12.512697 -119.748274) (xy 12.56754 -119.738144)
			(xy 12.623274 -119.736107) (xy 12.678711 -119.742207) (xy 12.732668 -119.756313) (xy 12.783997 -119.778125)
			(xy 12.831603 -119.807179) (xy 12.874471 -119.842854) (xy 12.911688 -119.884391) (xy 12.942461 -119.930904)
			(xy 12.966133 -119.981401) (xy 12.982201 -120.034808) (xy 12.990321 -120.089984) (xy 12.99083 -120.11787)
			(xy 12.990321 -120.145756) (xy 12.989192 -120.15343) (xy 15.422878 -120.15343) (xy 15.426949 -120.097808)
			(xy 15.439075 -120.043371) (xy 15.458998 -119.99128) (xy 15.486294 -119.942645) (xy 15.52038 -119.898502)
			(xy 15.560529 -119.859793) (xy 15.605887 -119.827342) (xy 15.655487 -119.801841) (xy 15.708271 -119.783834)
			(xy 15.763114 -119.773704) (xy 15.818848 -119.771667) (xy 15.874285 -119.777767) (xy 15.928242 -119.791873)
			(xy 15.979571 -119.813685) (xy 16.027177 -119.842739) (xy 16.070045 -119.878414) (xy 16.107262 -119.919951)
			(xy 16.138035 -119.966464) (xy 16.161707 -120.016961) (xy 16.177775 -120.070368) (xy 16.185895 -120.125544)
			(xy 16.186404 -120.15343) (xy 16.185895 -120.181316) (xy 16.177775 -120.236492) (xy 16.161707 -120.289899)
			(xy 16.138035 -120.340396) (xy 16.107262 -120.386909) (xy 16.070045 -120.428446) (xy 16.027177 -120.464121)
			(xy 15.979571 -120.493175) (xy 15.928242 -120.514987) (xy 15.874285 -120.529093) (xy 15.818848 -120.535193)
			(xy 15.763114 -120.533156) (xy 15.708271 -120.523026) (xy 15.655487 -120.505019) (xy 15.605887 -120.479518)
			(xy 15.560529 -120.447067) (xy 15.52038 -120.408358) (xy 15.486294 -120.364215) (xy 15.458998 -120.31558)
			(xy 15.439075 -120.263489) (xy 15.426949 -120.209052) (xy 15.422878 -120.15343) (xy 12.989192 -120.15343)
			(xy 12.982201 -120.200932) (xy 12.966133 -120.254339) (xy 12.942461 -120.304836) (xy 12.911688 -120.351349)
			(xy 12.874471 -120.392886) (xy 12.831603 -120.428561) (xy 12.783997 -120.457615) (xy 12.732668 -120.479427)
			(xy 12.678711 -120.493533) (xy 12.623274 -120.499633) (xy 12.56754 -120.497596) (xy 12.512697 -120.487466)
			(xy 12.459913 -120.469459) (xy 12.410313 -120.443958) (xy 12.364955 -120.411507) (xy 12.324806 -120.372798)
			(xy 12.29072 -120.328655) (xy 12.263424 -120.28002) (xy 12.243501 -120.227929) (xy 12.231375 -120.173492)
			(xy 12.227304 -120.11787) (xy 11.97483 -120.11787) (xy 11.974321 -120.145756) (xy 11.966201 -120.200932)
			(xy 11.950133 -120.254339) (xy 11.926461 -120.304836) (xy 11.895688 -120.351349) (xy 11.858471 -120.392886)
			(xy 11.815603 -120.428561) (xy 11.767997 -120.457615) (xy 11.716668 -120.479427) (xy 11.662711 -120.493533)
			(xy 11.607274 -120.499633) (xy 11.55154 -120.497596) (xy 11.496697 -120.487466) (xy 11.443913 -120.469459)
			(xy 11.394313 -120.443958) (xy 11.348955 -120.411507) (xy 11.308806 -120.372798) (xy 11.27472 -120.328655)
			(xy 11.247424 -120.28002) (xy 11.227501 -120.227929) (xy 11.215375 -120.173492) (xy 11.211304 -120.11787)
			(xy 10.935912 -120.11787) (xy 10.950201 -120.165364) (xy 10.958321 -120.22054) (xy 10.95883 -120.248426)
			(xy 10.958321 -120.276312) (xy 10.950201 -120.331488) (xy 10.934133 -120.384895) (xy 10.910461 -120.435392)
			(xy 10.879688 -120.481905) (xy 10.842471 -120.523442) (xy 10.799603 -120.559117) (xy 10.751997 -120.588171)
			(xy 10.700668 -120.609983) (xy 10.646711 -120.624089) (xy 10.591274 -120.630189) (xy 10.53554 -120.628152)
			(xy 10.480697 -120.618022) (xy 10.427913 -120.600015) (xy 10.378313 -120.574514) (xy 10.332955 -120.542063)
			(xy 10.292806 -120.503354) (xy 10.25872 -120.459211) (xy 10.231424 -120.410576) (xy 10.211501 -120.358485)
			(xy 10.199375 -120.304048) (xy 10.195304 -120.248426) (xy 4.421886 -120.248426) (xy 4.421886 -121.57075)
			(xy 13.619988 -121.57075) (xy 13.620426 -121.544435) (xy 13.627667 -121.492305) (xy 13.641992 -121.441662)
			(xy 13.66313 -121.393464) (xy 13.690682 -121.348621) (xy 13.724125 -121.307982) (xy 13.743178 -121.289826)
			(xy 13.750567 -121.282294) (xy 13.759099 -121.263022) (xy 13.759688 -121.252488) (xy 13.759688 -121.177812)
			(xy 13.759169 -121.167261) (xy 13.750627 -121.147966) (xy 13.743178 -121.140474) (xy 13.724113 -121.122328)
			(xy 13.690657 -121.081696) (xy 13.6631 -121.036854) (xy 13.641963 -120.988651) (xy 13.627648 -120.938002)
			(xy 13.620425 -120.885867) (xy 13.619988 -120.85955) (xy 13.620474 -120.832299) (xy 13.62823 -120.778351)
			(xy 13.643585 -120.726056) (xy 13.666227 -120.676479) (xy 13.695693 -120.630629) (xy 13.731384 -120.589438)
			(xy 13.772575 -120.553747) (xy 13.818425 -120.524281) (xy 13.868002 -120.501639) (xy 13.920297 -120.486284)
			(xy 13.974245 -120.478528) (xy 14.028747 -120.478528) (xy 14.082695 -120.486284) (xy 14.13499 -120.501639)
			(xy 14.184567 -120.524281) (xy 14.230417 -120.553747) (xy 14.271608 -120.589438) (xy 14.307299 -120.630629)
			(xy 14.336765 -120.676479) (xy 14.359407 -120.726056) (xy 14.374762 -120.778351) (xy 14.382518 -120.832299)
			(xy 14.383004 -120.85955) (xy 14.382569 -120.885865) (xy 14.375327 -120.937995) (xy 14.361002 -120.988638)
			(xy 14.339863 -121.036837) (xy 14.312311 -121.08168) (xy 14.278868 -121.122318) (xy 14.259814 -121.140474)
			(xy 14.252424 -121.148005) (xy 14.243892 -121.167278) (xy 14.243304 -121.177812) (xy 14.243304 -121.252488)
			(xy 14.243825 -121.263039) (xy 14.252366 -121.282334) (xy 14.259814 -121.289826) (xy 14.278878 -121.307973)
			(xy 14.312334 -121.348605) (xy 14.339891 -121.393447) (xy 14.361028 -121.44165) (xy 14.375344 -121.492298)
			(xy 14.382567 -121.544433) (xy 14.383004 -121.57075) (xy 14.382518 -121.598001) (xy 14.374762 -121.651949)
			(xy 14.359407 -121.704244) (xy 14.336765 -121.753821) (xy 14.307299 -121.799671) (xy 14.271608 -121.840862)
			(xy 14.230417 -121.876553) (xy 14.184567 -121.906019) (xy 14.13499 -121.928661) (xy 14.082695 -121.944016)
			(xy 14.028747 -121.951772) (xy 13.974245 -121.951772) (xy 13.920297 -121.944016) (xy 13.868002 -121.928661)
			(xy 13.818425 -121.906019) (xy 13.772575 -121.876553) (xy 13.731384 -121.840862) (xy 13.695693 -121.799671)
			(xy 13.666227 -121.753821) (xy 13.643585 -121.704244) (xy 13.62823 -121.651949) (xy 13.620474 -121.598001)
			(xy 13.619988 -121.57075) (xy 4.421886 -121.57075) (xy 4.421886 -122.292618) (xy 9.780268 -122.292618)
			(xy 9.784339 -122.236996) (xy 9.796465 -122.182559) (xy 9.816388 -122.130468) (xy 9.843684 -122.081833)
			(xy 9.87777 -122.03769) (xy 9.917919 -121.998981) (xy 9.963277 -121.96653) (xy 10.012877 -121.941029)
			(xy 10.065661 -121.923022) (xy 10.120504 -121.912892) (xy 10.176238 -121.910855) (xy 10.231675 -121.916955)
			(xy 10.285632 -121.931061) (xy 10.336961 -121.952873) (xy 10.384567 -121.981927) (xy 10.427435 -122.017602)
			(xy 10.464652 -122.059139) (xy 10.495425 -122.105652) (xy 10.519097 -122.156149) (xy 10.535165 -122.209556)
			(xy 10.543285 -122.264732) (xy 10.543794 -122.292618) (xy 10.543285 -122.320504) (xy 10.535165 -122.37568)
			(xy 10.519097 -122.429087) (xy 10.49996 -122.46991) (xy 10.936984 -122.46991) (xy 10.941055 -122.414288)
			(xy 10.953181 -122.359851) (xy 10.973104 -122.30776) (xy 11.0004 -122.259125) (xy 11.034486 -122.214982)
			(xy 11.074635 -122.176273) (xy 11.119993 -122.143822) (xy 11.169593 -122.118321) (xy 11.222377 -122.100314)
			(xy 11.27722 -122.090184) (xy 11.332954 -122.088147) (xy 11.388391 -122.094247) (xy 11.442348 -122.108353)
			(xy 11.493677 -122.130165) (xy 11.541283 -122.159219) (xy 11.584151 -122.194894) (xy 11.621368 -122.236431)
			(xy 11.652141 -122.282944) (xy 11.675813 -122.333441) (xy 11.691881 -122.386848) (xy 11.700001 -122.442024)
			(xy 11.70051 -122.46991) (xy 11.700001 -122.497796) (xy 11.691881 -122.552972) (xy 11.675813 -122.606379)
			(xy 11.652141 -122.656876) (xy 11.621368 -122.703389) (xy 11.584151 -122.744926) (xy 11.541283 -122.780601)
			(xy 11.493677 -122.809655) (xy 11.442348 -122.831467) (xy 11.388391 -122.845573) (xy 11.332954 -122.851673)
			(xy 11.27722 -122.849636) (xy 11.222377 -122.839506) (xy 11.169593 -122.821499) (xy 11.119993 -122.795998)
			(xy 11.074635 -122.763547) (xy 11.034486 -122.724838) (xy 11.0004 -122.680695) (xy 10.973104 -122.63206)
			(xy 10.953181 -122.579969) (xy 10.941055 -122.525532) (xy 10.936984 -122.46991) (xy 10.49996 -122.46991)
			(xy 10.495425 -122.479584) (xy 10.464652 -122.526097) (xy 10.427435 -122.567634) (xy 10.384567 -122.603309)
			(xy 10.336961 -122.632363) (xy 10.285632 -122.654175) (xy 10.231675 -122.668281) (xy 10.176238 -122.674381)
			(xy 10.120504 -122.672344) (xy 10.065661 -122.662214) (xy 10.012877 -122.644207) (xy 9.963277 -122.618706)
			(xy 9.917919 -122.586255) (xy 9.87777 -122.547546) (xy 9.843684 -122.503403) (xy 9.816388 -122.454768)
			(xy 9.796465 -122.402677) (xy 9.784339 -122.34824) (xy 9.780268 -122.292618) (xy 4.421886 -122.292618)
			(xy 4.421886 -123.249761) (xy 11.91004 -123.249761) (xy 11.91004 -123.195259) (xy 11.917796 -123.141311)
			(xy 11.933151 -123.089017) (xy 11.955792 -123.03944) (xy 11.985258 -122.99359) (xy 12.02095 -122.9524)
			(xy 12.06214 -122.916708) (xy 12.10799 -122.887242) (xy 12.157567 -122.864601) (xy 12.209861 -122.849246)
			(xy 12.263809 -122.84149) (xy 12.29106 -122.841004) (xy 12.318091 -122.841459) (xy 12.371611 -122.849105)
			(xy 12.423513 -122.864236) (xy 12.472757 -122.886548) (xy 12.518354 -122.915593) (xy 12.559391 -122.950789)
			(xy 12.577572 -122.970798) (xy 12.577826 -122.971052) (xy 12.585282 -122.978685) (xy 12.604757 -122.987361)
			(xy 12.615418 -122.987816) (xy 12.703048 -122.988324) (xy 12.722606 -122.979688) (xy 12.729972 -122.971306)
			(xy 12.748153 -122.951603) (xy 12.78905 -122.916937) (xy 12.834401 -122.888346) (xy 12.883312 -122.866393)
			(xy 12.934818 -122.851514) (xy 12.9879 -122.844) (xy 13.014706 -122.843544) (xy 13.042077 -122.843996)
			(xy 13.096257 -122.851815) (xy 13.148761 -122.867307) (xy 13.198507 -122.890152) (xy 13.244473 -122.919881)
			(xy 13.265404 -122.937524) (xy 13.265658 -122.937778) (xy 13.272746 -122.943362) (xy 13.289662 -122.949608)
			(xy 13.298678 -122.94997) (xy 13.365734 -122.94997) (xy 13.374753 -122.949636) (xy 13.39167 -122.943373)
			(xy 13.398754 -122.937778) (xy 13.398754 -122.937524) (xy 13.399008 -122.937524) (xy 13.419941 -122.919883)
			(xy 13.465909 -122.890159) (xy 13.515655 -122.867313) (xy 13.568157 -122.851817) (xy 13.622335 -122.843988)
			(xy 13.677077 -122.843988) (xy 13.731255 -122.851817) (xy 13.783757 -122.867313) (xy 13.833503 -122.890159)
			(xy 13.879471 -122.919883) (xy 13.900404 -122.937524) (xy 13.900658 -122.937778) (xy 13.907746 -122.943362)
			(xy 13.924662 -122.949608) (xy 13.933678 -122.94997) (xy 14.000734 -122.94997) (xy 14.009753 -122.949636)
			(xy 14.02667 -122.943373) (xy 14.033754 -122.937778) (xy 14.034262 -122.937524) (xy 14.046999 -122.926583)
			(xy 14.074088 -122.90674) (xy 14.088364 -122.8979) (xy 14.097254 -122.892566) (xy 14.109446 -122.875548)
			(xy 14.129766 -122.78233) (xy 14.125448 -122.761756) (xy 14.119606 -122.75312) (xy 14.103613 -122.729052)
			(xy 14.078269 -122.677122) (xy 14.061041 -122.621965) (xy 14.052324 -122.564842) (xy 14.051788 -122.53595)
			(xy 14.052274 -122.508699) (xy 14.06003 -122.454751) (xy 14.075385 -122.402456) (xy 14.098027 -122.352879)
			(xy 14.127493 -122.307029) (xy 14.163184 -122.265838) (xy 14.204375 -122.230147) (xy 14.250225 -122.200681)
			(xy 14.299802 -122.178039) (xy 14.352097 -122.162684) (xy 14.406045 -122.154928) (xy 14.460547 -122.154928)
			(xy 14.514495 -122.162684) (xy 14.56679 -122.178039) (xy 14.616367 -122.200681) (xy 14.662217 -122.230147)
			(xy 14.703408 -122.265838) (xy 14.739099 -122.307029) (xy 14.768565 -122.352879) (xy 14.791207 -122.402456)
			(xy 14.806562 -122.454751) (xy 14.814318 -122.508699) (xy 14.814804 -122.53595) (xy 14.814277 -122.56404)
			(xy 14.806056 -122.619616) (xy 14.789771 -122.673385) (xy 14.765774 -122.724183) (xy 14.734584 -122.77091)
			(xy 14.696876 -122.812556) (xy 14.653467 -122.848219) (xy 14.629638 -122.863102) (xy 14.620748 -122.868436)
			(xy 14.608556 -122.885454) (xy 14.588236 -122.978672) (xy 14.592554 -122.999246) (xy 14.598396 -123.007882)
			(xy 14.61439 -123.03195) (xy 14.639734 -123.08388) (xy 14.656962 -123.139036) (xy 14.665678 -123.19616)
			(xy 14.666214 -123.225052) (xy 14.6657 -123.252303) (xy 14.65795 -123.306252) (xy 14.6426 -123.358549)
			(xy 14.619964 -123.408128) (xy 14.590501 -123.453981) (xy 14.554813 -123.495174) (xy 14.513625 -123.530869)
			(xy 14.467776 -123.560338) (xy 14.418199 -123.582981) (xy 14.365905 -123.598338) (xy 14.311957 -123.606096)
			(xy 14.284706 -123.60656) (xy 14.257335 -123.6061) (xy 14.203156 -123.598282) (xy 14.150652 -123.582792)
			(xy 14.100905 -123.559949) (xy 14.054939 -123.530222) (xy 14.034008 -123.51258) (xy 14.033754 -123.512326)
			(xy 14.026662 -123.506747) (xy 14.009749 -123.500498) (xy 14.000734 -123.500134) (xy 13.933678 -123.500134)
			(xy 13.924659 -123.500473) (xy 13.907742 -123.506732) (xy 13.900658 -123.512326) (xy 13.900658 -123.51258)
			(xy 13.900404 -123.51258) (xy 13.879471 -123.530221) (xy 13.833503 -123.559945) (xy 13.783757 -123.582791)
			(xy 13.731255 -123.598287) (xy 13.677077 -123.606116) (xy 13.622335 -123.606116) (xy 13.568157 -123.598287)
			(xy 13.515655 -123.582791) (xy 13.465909 -123.559945) (xy 13.419941 -123.530221) (xy 13.399008 -123.51258)
			(xy 13.398754 -123.512326) (xy 13.391662 -123.506747) (xy 13.374749 -123.500498) (xy 13.365734 -123.500134)
			(xy 13.298678 -123.500134) (xy 13.289659 -123.500473) (xy 13.272742 -123.506732) (xy 13.265658 -123.512326)
			(xy 13.265658 -123.51258) (xy 13.265404 -123.51258) (xy 13.244479 -123.530228) (xy 13.198504 -123.559939)
			(xy 13.148755 -123.582773) (xy 13.096253 -123.598262) (xy 13.042076 -123.606088) (xy 13.014706 -123.60656)
			(xy 12.987675 -123.606107) (xy 12.934156 -123.598457) (xy 12.882255 -123.583325) (xy 12.833012 -123.561012)
			(xy 12.787414 -123.531968) (xy 12.746376 -123.496774) (xy 12.728194 -123.476766) (xy 12.72794 -123.476512)
			(xy 12.720488 -123.468874) (xy 12.70101 -123.460199) (xy 12.690348 -123.459748) (xy 12.602718 -123.45924)
			(xy 12.58316 -123.467876) (xy 12.575794 -123.476258) (xy 12.557643 -123.495991) (xy 12.516739 -123.530651)
			(xy 12.471381 -123.559237) (xy 12.422464 -123.581184) (xy 12.370954 -123.596059) (xy 12.317867 -123.603567)
			(xy 12.29106 -123.60402) (xy 12.263809 -123.60353) (xy 12.209861 -123.595774) (xy 12.157567 -123.580419)
			(xy 12.10799 -123.557778) (xy 12.06214 -123.528312) (xy 12.02095 -123.49262) (xy 11.985258 -123.45143)
			(xy 11.955792 -123.40558) (xy 11.933151 -123.356003) (xy 11.917796 -123.303709) (xy 11.91004 -123.249761)
			(xy 4.421886 -123.249761) (xy 4.421886 -124.963428) (xy 8.673082 -124.963428) (xy 8.677153 -124.907806)
			(xy 8.689279 -124.853369) (xy 8.709202 -124.801278) (xy 8.736498 -124.752643) (xy 8.770584 -124.7085)
			(xy 8.810733 -124.669791) (xy 8.856091 -124.63734) (xy 8.905691 -124.611839) (xy 8.958475 -124.593832)
			(xy 9.013318 -124.583702) (xy 9.069052 -124.581665) (xy 9.124489 -124.587765) (xy 9.178446 -124.601871)
			(xy 9.229775 -124.623683) (xy 9.277381 -124.652737) (xy 9.320249 -124.688412) (xy 9.357466 -124.729949)
			(xy 9.388239 -124.776462) (xy 9.411911 -124.826959) (xy 9.427979 -124.880366) (xy 9.436099 -124.935542)
			(xy 9.436608 -124.963428) (xy 9.436099 -124.991314) (xy 9.435493 -124.995432) (xy 10.780774 -124.995432)
			(xy 10.784845 -124.93981) (xy 10.796971 -124.885373) (xy 10.816894 -124.833282) (xy 10.84419 -124.784647)
			(xy 10.878276 -124.740504) (xy 10.918425 -124.701795) (xy 10.963783 -124.669344) (xy 11.013383 -124.643843)
			(xy 11.066167 -124.625836) (xy 11.12101 -124.615706) (xy 11.176744 -124.613669) (xy 11.232181 -124.619769)
			(xy 11.286138 -124.633875) (xy 11.337467 -124.655687) (xy 11.385073 -124.684741) (xy 11.427941 -124.720416)
			(xy 11.465158 -124.761953) (xy 11.495931 -124.808466) (xy 11.519603 -124.858963) (xy 11.535671 -124.91237)
			(xy 11.543791 -124.967546) (xy 11.5443 -124.995432) (xy 11.543791 -125.023318) (xy 11.535671 -125.078494)
			(xy 11.519603 -125.131901) (xy 11.495931 -125.182398) (xy 11.465158 -125.228911) (xy 11.427941 -125.270448)
			(xy 11.385073 -125.306123) (xy 11.337467 -125.335177) (xy 11.286138 -125.356989) (xy 11.232181 -125.371095)
			(xy 11.176744 -125.377195) (xy 11.12101 -125.375158) (xy 11.066167 -125.365028) (xy 11.013383 -125.347021)
			(xy 10.963783 -125.32152) (xy 10.918425 -125.289069) (xy 10.878276 -125.25036) (xy 10.84419 -125.206217)
			(xy 10.816894 -125.157582) (xy 10.796971 -125.105491) (xy 10.784845 -125.051054) (xy 10.780774 -124.995432)
			(xy 9.435493 -124.995432) (xy 9.427979 -125.04649) (xy 9.411911 -125.099897) (xy 9.388239 -125.150394)
			(xy 9.357466 -125.196907) (xy 9.320249 -125.238444) (xy 9.277381 -125.274119) (xy 9.229775 -125.303173)
			(xy 9.178446 -125.324985) (xy 9.124489 -125.339091) (xy 9.069052 -125.345191) (xy 9.013318 -125.343154)
			(xy 8.958475 -125.333024) (xy 8.905691 -125.315017) (xy 8.856091 -125.289516) (xy 8.810733 -125.257065)
			(xy 8.770584 -125.218356) (xy 8.736498 -125.174213) (xy 8.709202 -125.125578) (xy 8.689279 -125.073487)
			(xy 8.677153 -125.01905) (xy 8.673082 -124.963428) (xy 4.421886 -124.963428) (xy 4.421886 -125.403356)
			(xy 15.544292 -125.403356) (xy 15.544793 -125.375987) (xy 15.552603 -125.32181) (xy 15.568084 -125.269307)
			(xy 15.590918 -125.219559) (xy 15.620634 -125.173591) (xy 15.638272 -125.152658) (xy 15.638526 -125.152404)
			(xy 15.64412 -125.145323) (xy 15.650361 -125.128402) (xy 15.650718 -125.119384) (xy 15.650718 -125.052328)
			(xy 15.650344 -125.043313) (xy 15.644108 -125.026396) (xy 15.638526 -125.019308) (xy 15.638272 -125.019308)
			(xy 15.638272 -125.019054) (xy 15.62064 -124.998116) (xy 15.590928 -124.952144) (xy 15.568091 -124.902398)
			(xy 15.552599 -124.849899) (xy 15.544768 -124.795725) (xy 15.544292 -124.768356) (xy 15.544778 -124.741105)
			(xy 15.552534 -124.687157) (xy 15.567889 -124.634862) (xy 15.590531 -124.585285) (xy 15.619997 -124.539435)
			(xy 15.655688 -124.498244) (xy 15.696879 -124.462553) (xy 15.742729 -124.433087) (xy 15.792306 -124.410445)
			(xy 15.844601 -124.39509) (xy 15.898549 -124.387334) (xy 15.953051 -124.387334) (xy 16.006999 -124.39509)
			(xy 16.059294 -124.410445) (xy 16.108871 -124.433087) (xy 16.154721 -124.462553) (xy 16.195912 -124.498244)
			(xy 16.231603 -124.539435) (xy 16.261069 -124.585285) (xy 16.283711 -124.634862) (xy 16.299066 -124.687157)
			(xy 16.306822 -124.741105) (xy 16.307308 -124.768356) (xy 16.306814 -124.795725) (xy 16.299003 -124.849903)
			(xy 16.28352 -124.902406) (xy 16.260685 -124.952153) (xy 16.230966 -124.998121) (xy 16.213328 -125.019054)
			(xy 16.213074 -125.019308) (xy 16.207475 -125.026386) (xy 16.201237 -125.043309) (xy 16.200882 -125.052328)
			(xy 16.200882 -125.119384) (xy 16.201251 -125.1284) (xy 16.207491 -125.145316) (xy 16.213074 -125.152404)
			(xy 16.213328 -125.152404) (xy 16.213328 -125.152658) (xy 16.230965 -125.173591) (xy 16.260676 -125.219564)
			(xy 16.283512 -125.269312) (xy 16.299004 -125.321812) (xy 16.306833 -125.375987) (xy 16.307308 -125.403356)
			(xy 16.306822 -125.430607) (xy 16.299066 -125.484555) (xy 16.283711 -125.53685) (xy 16.261069 -125.586427)
			(xy 16.231603 -125.632277) (xy 16.195912 -125.673468) (xy 16.154721 -125.709159) (xy 16.108871 -125.738625)
			(xy 16.059294 -125.761267) (xy 16.006999 -125.776622) (xy 15.953051 -125.784378) (xy 15.898549 -125.784378)
			(xy 15.844601 -125.776622) (xy 15.792306 -125.761267) (xy 15.742729 -125.738625) (xy 15.696879 -125.709159)
			(xy 15.655688 -125.673468) (xy 15.619997 -125.632277) (xy 15.590531 -125.586427) (xy 15.567889 -125.53685)
			(xy 15.552534 -125.484555) (xy 15.544778 -125.430607) (xy 15.544292 -125.403356) (xy 4.421886 -125.403356)
			(xy 4.421886 -125.979428) (xy 8.673082 -125.979428) (xy 8.677153 -125.923806) (xy 8.689279 -125.869369)
			(xy 8.709202 -125.817278) (xy 8.736498 -125.768643) (xy 8.770584 -125.7245) (xy 8.810733 -125.685791)
			(xy 8.856091 -125.65334) (xy 8.905691 -125.627839) (xy 8.958475 -125.609832) (xy 9.013318 -125.599702)
			(xy 9.069052 -125.597665) (xy 9.124489 -125.603765) (xy 9.178446 -125.617871) (xy 9.229775 -125.639683)
			(xy 9.277381 -125.668737) (xy 9.320249 -125.704412) (xy 9.357466 -125.745949) (xy 9.388239 -125.792462)
			(xy 9.411911 -125.842959) (xy 9.427979 -125.896366) (xy 9.436099 -125.951542) (xy 9.436608 -125.979428)
			(xy 9.436557 -125.982222) (xy 11.113006 -125.982222) (xy 11.117077 -125.9266) (xy 11.129203 -125.872163)
			(xy 11.149126 -125.820072) (xy 11.176422 -125.771437) (xy 11.210508 -125.727294) (xy 11.250657 -125.688585)
			(xy 11.296015 -125.656134) (xy 11.345615 -125.630633) (xy 11.398399 -125.612626) (xy 11.453242 -125.602496)
			(xy 11.508976 -125.600459) (xy 11.564413 -125.606559) (xy 11.61837 -125.620665) (xy 11.669699 -125.642477)
			(xy 11.717305 -125.671531) (xy 11.760173 -125.707206) (xy 11.79739 -125.748743) (xy 11.828163 -125.795256)
			(xy 11.851835 -125.845753) (xy 11.854225 -125.853698) (xy 16.484854 -125.853698) (xy 16.485306 -125.826327)
			(xy 16.493125 -125.772147) (xy 16.508617 -125.719643) (xy 16.531462 -125.669896) (xy 16.561191 -125.623931)
			(xy 16.578834 -125.603) (xy 16.579088 -125.602746) (xy 16.58466 -125.595649) (xy 16.590916 -125.57874)
			(xy 16.59128 -125.569726) (xy 16.59128 -125.50267) (xy 16.590942 -125.493651) (xy 16.584682 -125.476734)
			(xy 16.579088 -125.46965) (xy 16.578834 -125.46965) (xy 16.578834 -125.469396) (xy 16.561185 -125.448472)
			(xy 16.531473 -125.402497) (xy 16.508639 -125.352748) (xy 16.49315 -125.300245) (xy 16.485326 -125.246068)
			(xy 16.484854 -125.218698) (xy 16.48534 -125.191447) (xy 16.493096 -125.137499) (xy 16.508451 -125.085204)
			(xy 16.531093 -125.035627) (xy 16.560559 -124.989777) (xy 16.59625 -124.948586) (xy 16.637441 -124.912895)
			(xy 16.683291 -124.883429) (xy 16.732868 -124.860787) (xy 16.785163 -124.845432) (xy 16.839111 -124.837676)
			(xy 16.893613 -124.837676) (xy 16.947561 -124.845432) (xy 16.999856 -124.860787) (xy 17.049433 -124.883429)
			(xy 17.095283 -124.912895) (xy 17.136474 -124.948586) (xy 17.172165 -124.989777) (xy 17.201631 -125.035627)
			(xy 17.224273 -125.085204) (xy 17.239628 -125.137499) (xy 17.247384 -125.191447) (xy 17.24787 -125.218698)
			(xy 17.24741 -125.246069) (xy 17.239592 -125.300248) (xy 17.224102 -125.352752) (xy 17.201258 -125.402498)
			(xy 17.171532 -125.448465) (xy 17.15389 -125.469396) (xy 17.153636 -125.46965) (xy 17.148057 -125.476741)
			(xy 17.141807 -125.493655) (xy 17.141444 -125.50267) (xy 17.141444 -125.569726) (xy 17.141779 -125.578745)
			(xy 17.148041 -125.595663) (xy 17.153636 -125.602746) (xy 17.15389 -125.602746) (xy 17.15389 -125.603)
			(xy 17.171541 -125.623923) (xy 17.201251 -125.669898) (xy 17.224085 -125.719648) (xy 17.239573 -125.772151)
			(xy 17.247398 -125.826328) (xy 17.24787 -125.853698) (xy 17.247384 -125.880949) (xy 17.239628 -125.934897)
			(xy 17.224273 -125.987192) (xy 17.201631 -126.036769) (xy 17.172165 -126.082619) (xy 17.136474 -126.12381)
			(xy 17.095283 -126.159501) (xy 17.049433 -126.188967) (xy 16.999856 -126.211609) (xy 16.947561 -126.226964)
			(xy 16.893613 -126.23472) (xy 16.839111 -126.23472) (xy 16.785163 -126.226964) (xy 16.732868 -126.211609)
			(xy 16.683291 -126.188967) (xy 16.637441 -126.159501) (xy 16.59625 -126.12381) (xy 16.560559 -126.082619)
			(xy 16.531093 -126.036769) (xy 16.508451 -125.987192) (xy 16.493096 -125.934897) (xy 16.48534 -125.880949)
			(xy 16.484854 -125.853698) (xy 11.854225 -125.853698) (xy 11.867903 -125.89916) (xy 11.876023 -125.954336)
			(xy 11.876532 -125.982222) (xy 11.876023 -126.010108) (xy 11.867903 -126.065284) (xy 11.851835 -126.118691)
			(xy 11.828163 -126.169188) (xy 11.79739 -126.215701) (xy 11.760173 -126.257238) (xy 11.717305 -126.292913)
			(xy 11.669699 -126.321967) (xy 11.61837 -126.343779) (xy 11.564413 -126.357885) (xy 11.508976 -126.363985)
			(xy 11.453242 -126.361948) (xy 11.398399 -126.351818) (xy 11.345615 -126.333811) (xy 11.296015 -126.30831)
			(xy 11.250657 -126.275859) (xy 11.210508 -126.23715) (xy 11.176422 -126.193007) (xy 11.149126 -126.144372)
			(xy 11.129203 -126.092281) (xy 11.117077 -126.037844) (xy 11.113006 -125.982222) (xy 9.436557 -125.982222)
			(xy 9.436099 -126.007314) (xy 9.427979 -126.06249) (xy 9.411911 -126.115897) (xy 9.388239 -126.166394)
			(xy 9.357466 -126.212907) (xy 9.320249 -126.254444) (xy 9.277381 -126.290119) (xy 9.229775 -126.319173)
			(xy 9.178446 -126.340985) (xy 9.124489 -126.355091) (xy 9.069052 -126.361191) (xy 9.013318 -126.359154)
			(xy 8.958475 -126.349024) (xy 8.905691 -126.331017) (xy 8.856091 -126.305516) (xy 8.810733 -126.273065)
			(xy 8.770584 -126.234356) (xy 8.736498 -126.190213) (xy 8.709202 -126.141578) (xy 8.689279 -126.089487)
			(xy 8.677153 -126.03505) (xy 8.673082 -125.979428) (xy 4.421886 -125.979428) (xy 4.421886 -126.530354)
			(xy 17.769586 -126.530354) (xy 17.770111 -126.501437) (xy 17.778834 -126.444265) (xy 17.796088 -126.389065)
			(xy 17.821479 -126.337102) (xy 17.854423 -126.289568) (xy 17.894166 -126.247553) (xy 17.916652 -126.229364)
			(xy 17.925474 -126.221772) (xy 17.935648 -126.200859) (xy 17.93621 -126.189232) (xy 17.93621 -126.109476)
			(xy 17.935667 -126.097845) (xy 17.92548 -126.076936) (xy 17.916652 -126.069344) (xy 17.89418 -126.05114)
			(xy 17.854446 -126.009122) (xy 17.821507 -125.961589) (xy 17.796117 -125.90963) (xy 17.778858 -125.854436)
			(xy 17.770124 -125.797269) (xy 17.769586 -125.768354) (xy 17.770035 -125.741102) (xy 17.777798 -125.687153)
			(xy 17.793158 -125.634858) (xy 17.815804 -125.585281) (xy 17.845275 -125.539431) (xy 17.88097 -125.498242)
			(xy 17.922163 -125.462551) (xy 17.968016 -125.433085) (xy 18.017596 -125.410444) (xy 18.069892 -125.395089)
			(xy 18.123842 -125.387332) (xy 18.151094 -125.386846) (xy 18.178465 -125.387304) (xy 18.232645 -125.395122)
			(xy 18.285148 -125.410613) (xy 18.334895 -125.433456) (xy 18.380861 -125.463183) (xy 18.401792 -125.480826)
			(xy 18.402046 -125.48108) (xy 18.409137 -125.486659) (xy 18.426051 -125.492908) (xy 18.435066 -125.493272)
			(xy 18.502122 -125.493272) (xy 18.511141 -125.492932) (xy 18.528058 -125.486673) (xy 18.535142 -125.48108)
			(xy 18.535142 -125.480826) (xy 18.535396 -125.480826) (xy 18.556322 -125.463179) (xy 18.602296 -125.433468)
			(xy 18.652045 -125.410633) (xy 18.704547 -125.395144) (xy 18.758724 -125.387318) (xy 18.786094 -125.386846)
			(xy 18.813343 -125.387383) (xy 18.867287 -125.395138) (xy 18.919577 -125.41049) (xy 18.969152 -125.433127)
			(xy 19.015 -125.462588) (xy 19.056189 -125.498274) (xy 19.091881 -125.539458) (xy 19.121348 -125.585303)
			(xy 19.143992 -125.634874) (xy 19.159351 -125.687163) (xy 19.167113 -125.741105) (xy 19.167602 -125.768354)
			(xy 19.16705 -125.79727) (xy 19.158328 -125.854439) (xy 19.141076 -125.909637) (xy 19.115691 -125.961599)
			(xy 19.082754 -126.009134) (xy 19.043019 -126.051153) (xy 19.020536 -126.069344) (xy 19.011708 -126.076931)
			(xy 19.001538 -126.097847) (xy 19.000978 -126.109476) (xy 19.000978 -126.189232) (xy 19.001521 -126.200863)
			(xy 19.011708 -126.221772) (xy 19.020536 -126.229364) (xy 19.04301 -126.247566) (xy 19.082744 -126.289585)
			(xy 19.115683 -126.337118) (xy 19.141073 -126.389077) (xy 19.158332 -126.444272) (xy 19.167065 -126.501439)
			(xy 19.167602 -126.530354) (xy 19.167102 -126.557606) (xy 19.159351 -126.611556) (xy 19.147251 -126.652782)
			(xy 19.438874 -126.652782) (xy 19.439311 -126.625411) (xy 19.447133 -126.571229) (xy 19.462628 -126.518725)
			(xy 19.485477 -126.468979) (xy 19.515209 -126.423014) (xy 19.532854 -126.402084) (xy 19.533108 -126.40183)
			(xy 19.538689 -126.39474) (xy 19.544939 -126.377826) (xy 19.5453 -126.36881) (xy 19.5453 -126.301754)
			(xy 19.544917 -126.29274) (xy 19.538687 -126.275823) (xy 19.533108 -126.268734) (xy 19.532854 -126.268734)
			(xy 19.532854 -126.26848) (xy 19.515195 -126.247562) (xy 19.485468 -126.201592) (xy 19.462622 -126.151844)
			(xy 19.447126 -126.099339) (xy 19.439299 -126.045158) (xy 19.439301 -125.990415) (xy 19.447132 -125.936234)
			(xy 19.462632 -125.883731) (xy 19.485481 -125.833984) (xy 19.515211 -125.788016) (xy 19.532854 -125.767084)
			(xy 19.533108 -125.76683) (xy 19.538689 -125.75974) (xy 19.544939 -125.742826) (xy 19.5453 -125.73381)
			(xy 19.5453 -125.666754) (xy 19.544917 -125.65774) (xy 19.538687 -125.640823) (xy 19.533108 -125.633734)
			(xy 19.532854 -125.633734) (xy 19.532854 -125.63348) (xy 19.515195 -125.612562) (xy 19.485468 -125.566592)
			(xy 19.462622 -125.516844) (xy 19.447126 -125.464339) (xy 19.439299 -125.410158) (xy 19.439301 -125.355415)
			(xy 19.447132 -125.301234) (xy 19.462632 -125.248731) (xy 19.485481 -125.198984) (xy 19.515211 -125.153016)
			(xy 19.532854 -125.132084) (xy 19.533108 -125.13183) (xy 19.538689 -125.12474) (xy 19.544939 -125.107826)
			(xy 19.5453 -125.09881) (xy 19.5453 -125.031754) (xy 19.544917 -125.02274) (xy 19.538687 -125.005823)
			(xy 19.533108 -124.998734) (xy 19.532854 -124.998734) (xy 19.532854 -124.99848) (xy 19.515247 -124.977522)
			(xy 19.485529 -124.931557) (xy 19.462686 -124.881816) (xy 19.447187 -124.829321) (xy 19.439352 -124.77515)
			(xy 19.438874 -124.747782) (xy 19.43936 -124.720531) (xy 19.447116 -124.666583) (xy 19.462471 -124.614288)
			(xy 19.485113 -124.564711) (xy 19.514579 -124.518861) (xy 19.55027 -124.47767) (xy 19.591461 -124.441979)
			(xy 19.637311 -124.412513) (xy 19.686888 -124.389871) (xy 19.739183 -124.374516) (xy 19.793131 -124.36676)
			(xy 19.847633 -124.36676) (xy 19.901581 -124.374516) (xy 19.953876 -124.389871) (xy 20.003453 -124.412513)
			(xy 20.049303 -124.441979) (xy 20.090494 -124.47767) (xy 20.126185 -124.518861) (xy 20.155651 -124.564711)
			(xy 20.178293 -124.614288) (xy 20.193648 -124.666583) (xy 20.201404 -124.720531) (xy 20.20189 -124.747782)
			(xy 20.201416 -124.775152) (xy 20.1936 -124.829331) (xy 20.178113 -124.881834) (xy 20.155273 -124.931581)
			(xy 20.12555 -124.977548) (xy 20.10791 -124.99848) (xy 20.107656 -124.998734) (xy 20.102086 -125.005831)
			(xy 20.09583 -125.02274) (xy 20.095464 -125.031754) (xy 20.095464 -125.09881) (xy 20.095824 -125.107826)
			(xy 20.10207 -125.124743) (xy 20.107656 -125.13183) (xy 20.10791 -125.13183) (xy 20.10791 -125.132084)
			(xy 20.125532 -125.153032) (xy 20.155254 -125.198998) (xy 20.178098 -125.248742) (xy 20.193594 -125.301241)
			(xy 20.201424 -125.355417) (xy 20.201426 -125.410156) (xy 20.1936 -125.464332) (xy 20.178108 -125.516833)
			(xy 20.155267 -125.566578) (xy 20.125548 -125.612547) (xy 20.10791 -125.63348) (xy 20.107656 -125.633734)
			(xy 20.102086 -125.640831) (xy 20.09583 -125.65774) (xy 20.095464 -125.666754) (xy 20.095464 -125.73381)
			(xy 20.095824 -125.742826) (xy 20.10207 -125.759743) (xy 20.107656 -125.76683) (xy 20.10791 -125.76683)
			(xy 20.10791 -125.767084) (xy 20.125532 -125.788032) (xy 20.155254 -125.833998) (xy 20.178098 -125.883742)
			(xy 20.193594 -125.936241) (xy 20.201424 -125.990417) (xy 20.201426 -126.045156) (xy 20.1936 -126.099332)
			(xy 20.178108 -126.151833) (xy 20.155267 -126.201578) (xy 20.125548 -126.247547) (xy 20.10791 -126.26848)
			(xy 20.107656 -126.268734) (xy 20.102086 -126.275831) (xy 20.09583 -126.29274) (xy 20.095464 -126.301754)
			(xy 20.095464 -126.36881) (xy 20.095824 -126.377826) (xy 20.10207 -126.394743) (xy 20.107656 -126.40183)
			(xy 20.10791 -126.40183) (xy 20.10791 -126.402084) (xy 20.125557 -126.42301) (xy 20.155267 -126.468985)
			(xy 20.178101 -126.518734) (xy 20.193591 -126.571236) (xy 20.201417 -126.625412) (xy 20.20189 -126.652782)
			(xy 20.201404 -126.680033) (xy 20.193648 -126.733981) (xy 20.178293 -126.786276) (xy 20.155651 -126.835853)
			(xy 20.126185 -126.881703) (xy 20.090494 -126.922894) (xy 20.049303 -126.958585) (xy 20.003453 -126.988051)
			(xy 19.953876 -127.010693) (xy 19.901581 -127.026048) (xy 19.847633 -127.033804) (xy 19.793131 -127.033804)
			(xy 19.739183 -127.026048) (xy 19.686888 -127.010693) (xy 19.637311 -126.988051) (xy 19.591461 -126.958585)
			(xy 19.55027 -126.922894) (xy 19.514579 -126.881703) (xy 19.485113 -126.835853) (xy 19.462471 -126.786276)
			(xy 19.447116 -126.733981) (xy 19.43936 -126.680033) (xy 19.438874 -126.652782) (xy 19.147251 -126.652782)
			(xy 19.144001 -126.663853) (xy 19.121363 -126.713434) (xy 19.091899 -126.759287) (xy 19.056209 -126.800481)
			(xy 19.01502 -126.836175) (xy 18.969169 -126.865644) (xy 18.919591 -126.888287) (xy 18.867295 -126.903643)
			(xy 18.813346 -126.911399) (xy 18.786094 -126.911862) (xy 18.758723 -126.911409) (xy 18.704543 -126.903589)
			(xy 18.65204 -126.888098) (xy 18.602293 -126.865253) (xy 18.556327 -126.835525) (xy 18.535396 -126.817882)
			(xy 18.535142 -126.817628) (xy 18.528054 -126.812044) (xy 18.511138 -126.805798) (xy 18.502122 -126.805436)
			(xy 18.435066 -126.805436) (xy 18.426047 -126.805769) (xy 18.409129 -126.812032) (xy 18.402046 -126.817628)
			(xy 18.402046 -126.817882) (xy 18.401792 -126.817882) (xy 18.380871 -126.835536) (xy 18.334896 -126.865246)
			(xy 18.285145 -126.888079) (xy 18.232642 -126.903567) (xy 18.178464 -126.911391) (xy 18.151094 -126.911862)
			(xy 18.123839 -126.91145) (xy 18.069884 -126.903691) (xy 18.017582 -126.888332) (xy 17.967999 -126.865685)
			(xy 17.922144 -126.836213) (xy 17.88095 -126.800513) (xy 17.845256 -126.759315) (xy 17.81579 -126.713455)
			(xy 17.79315 -126.663869) (xy 17.777798 -126.611565) (xy 17.770046 -126.557609) (xy 17.769586 -126.530354)
			(xy 4.421886 -126.530354) (xy 4.421886 -127.051308) (xy 10.744198 -127.051308) (xy 10.748269 -126.995686)
			(xy 10.760395 -126.941249) (xy 10.780318 -126.889158) (xy 10.807614 -126.840523) (xy 10.8417 -126.79638)
			(xy 10.881849 -126.757671) (xy 10.927207 -126.72522) (xy 10.976807 -126.699719) (xy 11.029591 -126.681712)
			(xy 11.084434 -126.671582) (xy 11.140168 -126.669545) (xy 11.195605 -126.675645) (xy 11.249562 -126.689751)
			(xy 11.300891 -126.711563) (xy 11.348497 -126.740617) (xy 11.391365 -126.776292) (xy 11.428582 -126.817829)
			(xy 11.459355 -126.864342) (xy 11.483027 -126.914839) (xy 11.499095 -126.968246) (xy 11.507215 -127.023422)
			(xy 11.507724 -127.051308) (xy 11.507215 -127.079194) (xy 11.499095 -127.13437) (xy 11.483027 -127.187777)
			(xy 11.459355 -127.238274) (xy 11.428582 -127.284787) (xy 11.391365 -127.326324) (xy 11.348497 -127.361999)
			(xy 11.300891 -127.391053) (xy 11.249562 -127.412865) (xy 11.195605 -127.426971) (xy 11.140168 -127.433071)
			(xy 11.084434 -127.431034) (xy 11.029591 -127.420904) (xy 10.976807 -127.402897) (xy 10.927207 -127.377396)
			(xy 10.881849 -127.344945) (xy 10.8417 -127.306236) (xy 10.807614 -127.262093) (xy 10.780318 -127.213458)
			(xy 10.760395 -127.161367) (xy 10.748269 -127.10693) (xy 10.744198 -127.051308) (xy 4.421886 -127.051308)
			(xy 4.421886 -128.252803) (xy 9.728405 -128.252803) (xy 9.728405 -128.198297) (xy 9.736162 -128.144346)
			(xy 9.751519 -128.092048) (xy 9.774161 -128.042467) (xy 9.80363 -127.996614) (xy 9.839324 -127.955421)
			(xy 9.880517 -127.919727) (xy 9.926371 -127.89026) (xy 9.975951 -127.867617) (xy 10.02825 -127.852262)
			(xy 10.082201 -127.844505) (xy 10.109454 -127.844042) (xy 10.136824 -127.844525) (xy 10.191003 -127.852337)
			(xy 10.243506 -127.867822) (xy 10.293253 -127.89066) (xy 10.33922 -127.920382) (xy 10.360152 -127.938022)
			(xy 10.360406 -127.938276) (xy 10.36748 -127.94388) (xy 10.384407 -127.950114) (xy 10.393426 -127.950468)
			(xy 10.460482 -127.950468) (xy 10.469499 -127.950109) (xy 10.486416 -127.943863) (xy 10.493502 -127.938276)
			(xy 10.493502 -127.938022) (xy 10.493756 -127.938022) (xy 10.514689 -127.920381) (xy 10.560657 -127.890657)
			(xy 10.610403 -127.867811) (xy 10.662905 -127.852315) (xy 10.717083 -127.844486) (xy 10.771825 -127.844486)
			(xy 10.826003 -127.852315) (xy 10.878505 -127.867811) (xy 10.928251 -127.890657) (xy 10.974219 -127.920381)
			(xy 10.995152 -127.938022) (xy 10.995406 -127.938276) (xy 11.00248 -127.94388) (xy 11.019407 -127.950114)
			(xy 11.028426 -127.950468) (xy 11.095482 -127.950468) (xy 11.104499 -127.950109) (xy 11.121416 -127.943863)
			(xy 11.128502 -127.938276) (xy 11.128502 -127.938022) (xy 11.128756 -127.938022) (xy 11.149697 -127.920393)
			(xy 11.195667 -127.890679) (xy 11.245412 -127.867841) (xy 11.297911 -127.852348) (xy 11.352085 -127.844517)
			(xy 11.379454 -127.844042) (xy 11.406705 -127.844528) (xy 11.460652 -127.852285) (xy 11.512947 -127.867641)
			(xy 11.562523 -127.890282) (xy 11.608373 -127.919748) (xy 11.649563 -127.95544) (xy 11.685254 -127.99663)
			(xy 11.71472 -128.04248) (xy 11.737361 -128.092057) (xy 11.752716 -128.144352) (xy 11.760472 -128.198299)
			(xy 11.760472 -128.252801) (xy 11.752716 -128.306748) (xy 11.737361 -128.359043) (xy 11.71472 -128.40862)
			(xy 11.685254 -128.45447) (xy 11.649563 -128.49566) (xy 11.608373 -128.531352) (xy 11.562523 -128.560818)
			(xy 11.512947 -128.583459) (xy 11.460652 -128.598815) (xy 11.406705 -128.606572) (xy 11.379454 -128.607058)
			(xy 11.352084 -128.606571) (xy 11.297906 -128.598759) (xy 11.245403 -128.583276) (xy 11.195655 -128.560439)
			(xy 11.149688 -128.530718) (xy 11.128756 -128.513078) (xy 11.128502 -128.512824) (xy 11.121425 -128.507223)
			(xy 11.104501 -128.500987) (xy 11.095482 -128.500632) (xy 11.028426 -128.500632) (xy 11.01941 -128.500995)
			(xy 11.002492 -128.507238) (xy 10.995406 -128.512824) (xy 10.995406 -128.513078) (xy 10.995152 -128.513078)
			(xy 10.974219 -128.530719) (xy 10.928251 -128.560443) (xy 10.878505 -128.583289) (xy 10.826003 -128.598785)
			(xy 10.771825 -128.606614) (xy 10.717083 -128.606614) (xy 10.662905 -128.598785) (xy 10.610403 -128.583289)
			(xy 10.560657 -128.560443) (xy 10.514689 -128.530719) (xy 10.493756 -128.513078) (xy 10.493502 -128.512824)
			(xy 10.486425 -128.507223) (xy 10.469501 -128.500987) (xy 10.460482 -128.500632) (xy 10.393426 -128.500632)
			(xy 10.38441 -128.500995) (xy 10.367492 -128.507238) (xy 10.360406 -128.512824) (xy 10.360406 -128.513078)
			(xy 10.360152 -128.513078) (xy 10.339208 -128.530703) (xy 10.293239 -128.560418) (xy 10.243495 -128.583257)
			(xy 10.190996 -128.598751) (xy 10.136822 -128.606582) (xy 10.109454 -128.607058) (xy 10.082201 -128.606595)
			(xy 10.02825 -128.598838) (xy 9.975951 -128.583483) (xy 9.926371 -128.56084) (xy 9.880517 -128.531373)
			(xy 9.839324 -128.495679) (xy 9.80363 -128.454486) (xy 9.774161 -128.408633) (xy 9.751519 -128.359052)
			(xy 9.736162 -128.306754) (xy 9.728405 -128.252803) (xy 4.421886 -128.252803) (xy 4.421886 -131.447101)
			(xy 9.713452 -131.447101) (xy 9.713452 -131.392599) (xy 9.721208 -131.338652) (xy 9.736563 -131.286358)
			(xy 9.759204 -131.236782) (xy 9.78867 -131.190932) (xy 9.824361 -131.149742) (xy 9.86555 -131.114051)
			(xy 9.9114 -131.084585) (xy 9.960976 -131.061944) (xy 10.01327 -131.046589) (xy 10.067217 -131.038832)
			(xy 10.094468 -131.038346) (xy 10.121838 -131.03882) (xy 10.176017 -131.046634) (xy 10.228521 -131.062121)
			(xy 10.278268 -131.084961) (xy 10.324235 -131.114685) (xy 10.345166 -131.132326) (xy 10.34542 -131.13258)
			(xy 10.35249 -131.13819) (xy 10.36942 -131.144421) (xy 10.37844 -131.144772) (xy 10.445496 -131.144772)
			(xy 10.454513 -131.144419) (xy 10.471431 -131.13817) (xy 10.478516 -131.13258) (xy 10.478516 -131.132326)
			(xy 10.47877 -131.132326) (xy 10.499703 -131.114685) (xy 10.545671 -131.084961) (xy 10.595417 -131.062115)
			(xy 10.647919 -131.046619) (xy 10.702097 -131.03879) (xy 10.756839 -131.03879) (xy 10.811017 -131.046619)
			(xy 10.863519 -131.062115) (xy 10.913265 -131.084961) (xy 10.959233 -131.114685) (xy 10.980166 -131.132326)
			(xy 10.98042 -131.13258) (xy 10.98749 -131.13819) (xy 11.00442 -131.144421) (xy 11.01344 -131.144772)
			(xy 11.080496 -131.144772) (xy 11.089513 -131.144419) (xy 11.106431 -131.13817) (xy 11.113516 -131.13258)
			(xy 11.113516 -131.132326) (xy 11.11377 -131.132326) (xy 11.134706 -131.114692) (xy 11.180677 -131.084978)
			(xy 11.230424 -131.062141) (xy 11.282924 -131.046649) (xy 11.337099 -131.03882) (xy 11.364468 -131.038346)
			(xy 11.391721 -131.038801) (xy 11.445673 -131.046558) (xy 11.497972 -131.061914) (xy 11.547552 -131.084557)
			(xy 11.593406 -131.114025) (xy 11.6346 -131.149719) (xy 11.670294 -131.190912) (xy 11.699762 -131.236766)
			(xy 11.722405 -131.286347) (xy 11.737762 -131.338645) (xy 11.745519 -131.392597) (xy 11.745519 -131.447103)
			(xy 11.737762 -131.501055) (xy 11.722405 -131.553353) (xy 11.699762 -131.602934) (xy 11.670294 -131.648788)
			(xy 11.6346 -131.689981) (xy 11.593406 -131.725675) (xy 11.547552 -131.755143) (xy 11.497972 -131.777786)
			(xy 11.445673 -131.793142) (xy 11.391721 -131.800899) (xy 11.364468 -131.801362) (xy 11.337097 -131.800924)
			(xy 11.282916 -131.793101) (xy 11.230412 -131.777606) (xy 11.180666 -131.754757) (xy 11.1347 -131.725026)
			(xy 11.11377 -131.707382) (xy 11.113516 -131.707128) (xy 11.106435 -131.701534) (xy 11.089514 -131.695294)
			(xy 11.080496 -131.694936) (xy 11.01344 -131.694936) (xy 11.004424 -131.695304) (xy 10.987507 -131.701543)
			(xy 10.98042 -131.707128) (xy 10.98042 -131.707382) (xy 10.980166 -131.707382) (xy 10.959233 -131.725023)
			(xy 10.913265 -131.754747) (xy 10.863519 -131.777593) (xy 10.811017 -131.793089) (xy 10.756839 -131.800918)
			(xy 10.702097 -131.800918) (xy 10.647919 -131.793089) (xy 10.595417 -131.777593) (xy 10.545671 -131.754747)
			(xy 10.499703 -131.725023) (xy 10.47877 -131.707382) (xy 10.478516 -131.707128) (xy 10.471435 -131.701534)
			(xy 10.454514 -131.695294) (xy 10.445496 -131.694936) (xy 10.37844 -131.694936) (xy 10.369424 -131.695304)
			(xy 10.352507 -131.701543) (xy 10.34542 -131.707128) (xy 10.34542 -131.707382) (xy 10.345166 -131.707382)
			(xy 10.324218 -131.725001) (xy 10.27825 -131.754716) (xy 10.228506 -131.777556) (xy 10.176009 -131.793052)
			(xy 10.121836 -131.800885) (xy 10.094468 -131.801362) (xy 10.067217 -131.800868) (xy 10.01327 -131.793111)
			(xy 9.960976 -131.777756) (xy 9.9114 -131.755115) (xy 9.86555 -131.725649) (xy 9.824361 -131.689958)
			(xy 9.78867 -131.648768) (xy 9.759204 -131.602918) (xy 9.736563 -131.553342) (xy 9.721208 -131.501048)
			(xy 9.713452 -131.447101) (xy 4.421886 -131.447101) (xy 4.421886 -133.443726) (xy 11.122914 -133.443726)
			(xy 11.123394 -133.417412) (xy 11.130626 -133.365284) (xy 11.144942 -133.314642) (xy 11.166072 -133.266442)
			(xy 11.193616 -133.221599) (xy 11.227053 -133.180959) (xy 11.246104 -133.162802) (xy 11.253507 -133.155282)
			(xy 11.26203 -133.136001) (xy 11.262614 -133.125464) (xy 11.262614 -133.050788) (xy 11.262101 -133.040237)
			(xy 11.253554 -133.020942) (xy 11.246104 -133.01345) (xy 11.227032 -132.995311) (xy 11.193576 -132.954678)
			(xy 11.166019 -132.909834) (xy 11.144884 -132.86163) (xy 11.13057 -132.81098) (xy 11.12335 -132.758843)
			(xy 11.122914 -132.732526) (xy 11.1234 -132.705275) (xy 11.131156 -132.651327) (xy 11.146511 -132.599032)
			(xy 11.169153 -132.549455) (xy 11.198619 -132.503605) (xy 11.23431 -132.462414) (xy 11.275501 -132.426723)
			(xy 11.321351 -132.397257) (xy 11.370928 -132.374615) (xy 11.423223 -132.35926) (xy 11.477171 -132.351504)
			(xy 11.531673 -132.351504) (xy 11.585621 -132.35926) (xy 11.637916 -132.374615) (xy 11.687493 -132.397257)
			(xy 11.733343 -132.426723) (xy 11.774534 -132.462414) (xy 11.810225 -132.503605) (xy 11.839691 -132.549455)
			(xy 11.862333 -132.599032) (xy 11.877688 -132.651327) (xy 11.885444 -132.705275) (xy 11.88593 -132.732526)
			(xy 11.88547 -132.75884) (xy 11.878233 -132.810969) (xy 11.863911 -132.861611) (xy 11.842777 -132.90981)
			(xy 11.81523 -132.954653) (xy 11.781791 -132.995293) (xy 11.76274 -133.01345) (xy 11.75532 -133.020957)
			(xy 11.746805 -133.040248) (xy 11.74623 -133.050788) (xy 11.74623 -133.125464) (xy 11.746756 -133.136014)
			(xy 11.755293 -133.15531) (xy 11.76274 -133.162802) (xy 11.781797 -133.180956) (xy 11.815253 -133.221587)
			(xy 11.84281 -133.266428) (xy 11.863948 -133.314629) (xy 11.878266 -133.365276) (xy 11.885491 -133.41741)
			(xy 11.88593 -133.443726) (xy 11.885444 -133.470977) (xy 11.877688 -133.524925) (xy 11.862333 -133.57722)
			(xy 11.839691 -133.626797) (xy 11.810225 -133.672647) (xy 11.774534 -133.713838) (xy 11.733343 -133.749529)
			(xy 11.687493 -133.778995) (xy 11.637916 -133.801637) (xy 11.585621 -133.816992) (xy 11.531673 -133.824748)
			(xy 11.477171 -133.824748) (xy 11.423223 -133.816992) (xy 11.370928 -133.801637) (xy 11.321351 -133.778995)
			(xy 11.275501 -133.749529) (xy 11.23431 -133.713838) (xy 11.198619 -133.672647) (xy 11.169153 -133.626797)
			(xy 11.146511 -133.57722) (xy 11.131156 -133.524925) (xy 11.1234 -133.470977) (xy 11.122914 -133.443726)
			(xy 4.421886 -133.443726) (xy 4.421886 -134.042404) (xy 6.176008 -134.042404) (xy 6.180079 -133.986782)
			(xy 6.192205 -133.932345) (xy 6.212128 -133.880254) (xy 6.239424 -133.831619) (xy 6.27351 -133.787476)
			(xy 6.313659 -133.748767) (xy 6.359017 -133.716316) (xy 6.408617 -133.690815) (xy 6.461401 -133.672808)
			(xy 6.516244 -133.662678) (xy 6.571978 -133.660641) (xy 6.627415 -133.666741) (xy 6.681372 -133.680847)
			(xy 6.732701 -133.702659) (xy 6.780307 -133.731713) (xy 6.823175 -133.767388) (xy 6.860392 -133.808925)
			(xy 6.891165 -133.855438) (xy 6.914837 -133.905935) (xy 6.930905 -133.959342) (xy 6.939025 -134.014518)
			(xy 6.939534 -134.042404) (xy 6.939025 -134.07029) (xy 6.930905 -134.125466) (xy 6.914837 -134.178873)
			(xy 6.891165 -134.22937) (xy 6.860392 -134.275883) (xy 6.823175 -134.31742) (xy 6.780307 -134.353095)
			(xy 6.732701 -134.382149) (xy 6.681372 -134.403961) (xy 6.627415 -134.418067) (xy 6.571978 -134.424167)
			(xy 6.516244 -134.42213) (xy 6.461401 -134.412) (xy 6.408617 -134.393993) (xy 6.359017 -134.368492)
			(xy 6.313659 -134.336041) (xy 6.27351 -134.297332) (xy 6.239424 -134.253189) (xy 6.212128 -134.204554)
			(xy 6.192205 -134.152463) (xy 6.180079 -134.098026) (xy 6.176008 -134.042404) (xy 4.421886 -134.042404)
			(xy 4.421886 -135.142043) (xy 9.361887 -135.142043) (xy 9.361887 -135.087537) (xy 9.369644 -135.033586)
			(xy 9.385 -134.981289) (xy 9.407643 -134.931709) (xy 9.437111 -134.885856) (xy 9.472805 -134.844663)
			(xy 9.513997 -134.80897) (xy 9.55985 -134.779502) (xy 9.609431 -134.75686) (xy 9.661728 -134.741504)
			(xy 9.715679 -134.733747) (xy 9.742932 -134.733284) (xy 9.771849 -134.733819) (xy 9.82902 -134.74254)
			(xy 9.88422 -134.759793) (xy 9.936183 -134.785181) (xy 9.983717 -134.818123) (xy 10.025733 -134.857864)
			(xy 10.043922 -134.88035) (xy 10.051733 -134.889318) (xy 10.073184 -134.899517) (xy 10.08507 -134.899908)
			(xy 10.178542 -134.897876) (xy 10.199878 -134.8867) (xy 10.206736 -134.876794) (xy 10.22216 -134.855904)
			(xy 10.257734 -134.818076) (xy 10.298108 -134.785422) (xy 10.342538 -134.758545) (xy 10.390203 -134.737942)
			(xy 10.440221 -134.723993) (xy 10.491669 -134.716955) (xy 10.517632 -134.71652) (xy 10.545003 -134.716962)
			(xy 10.599183 -134.724785) (xy 10.651687 -134.74028) (xy 10.701433 -134.763127) (xy 10.747399 -134.792856)
			(xy 10.76833 -134.8105) (xy 10.768584 -134.810754) (xy 10.775666 -134.816346) (xy 10.792587 -134.822588)
			(xy 10.801604 -134.822946) (xy 10.86866 -134.822946) (xy 10.877676 -134.822582) (xy 10.894594 -134.81634)
			(xy 10.90168 -134.810754) (xy 10.90168 -134.8105) (xy 10.901934 -134.8105) (xy 10.922867 -134.792859)
			(xy 10.968835 -134.763135) (xy 11.018581 -134.740289) (xy 11.071083 -134.724793) (xy 11.125261 -134.716964)
			(xy 11.180003 -134.716964) (xy 11.234181 -134.724793) (xy 11.286683 -134.740289) (xy 11.336429 -134.763135)
			(xy 11.382397 -134.792859) (xy 11.40333 -134.8105) (xy 11.403584 -134.810754) (xy 11.410666 -134.816346)
			(xy 11.427587 -134.822588) (xy 11.436604 -134.822946) (xy 11.50366 -134.822946) (xy 11.512676 -134.822582)
			(xy 11.529594 -134.81634) (xy 11.53668 -134.810754) (xy 11.537188 -134.8105) (xy 11.549922 -134.799555)
			(xy 11.577013 -134.779714) (xy 11.59129 -134.770876) (xy 11.60018 -134.765542) (xy 11.612372 -134.748524)
			(xy 11.632692 -134.655306) (xy 11.628374 -134.634732) (xy 11.622532 -134.626096) (xy 11.606532 -134.602032)
			(xy 11.581188 -134.550101) (xy 11.563962 -134.494943) (xy 11.555248 -134.437819) (xy 11.554714 -134.408926)
			(xy 11.5552 -134.381675) (xy 11.562956 -134.327727) (xy 11.578311 -134.275432) (xy 11.600953 -134.225855)
			(xy 11.630419 -134.180005) (xy 11.66611 -134.138814) (xy 11.707301 -134.103123) (xy 11.753151 -134.073657)
			(xy 11.802728 -134.051015) (xy 11.855023 -134.03566) (xy 11.908971 -134.027904) (xy 11.963473 -134.027904)
			(xy 12.017421 -134.03566) (xy 12.069716 -134.051015) (xy 12.119293 -134.073657) (xy 12.165143 -134.103123)
			(xy 12.206334 -134.138814) (xy 12.242025 -134.180005) (xy 12.271491 -134.225855) (xy 12.294133 -134.275432)
			(xy 12.309488 -134.327727) (xy 12.317244 -134.381675) (xy 12.31773 -134.408926) (xy 12.31725 -134.437018)
			(xy 12.309019 -134.492596) (xy 12.292725 -134.546365) (xy 12.26872 -134.597162) (xy 12.237523 -134.643889)
			(xy 12.19981 -134.685533) (xy 12.156395 -134.721196) (xy 12.132564 -134.736078) (xy 12.123674 -134.741412)
			(xy 12.111482 -134.75843) (xy 12.091162 -134.851648) (xy 12.09548 -134.872222) (xy 12.101322 -134.880858)
			(xy 12.117309 -134.90493) (xy 12.142654 -134.956859) (xy 12.159883 -135.012014) (xy 12.168603 -135.069136)
			(xy 12.16914 -135.098028) (xy 12.168648 -135.125278) (xy 12.160889 -135.179224) (xy 12.145532 -135.231517)
			(xy 12.12289 -135.281092) (xy 12.093423 -135.326941) (xy 12.057733 -135.36813) (xy 12.016544 -135.403821)
			(xy 11.970696 -135.433288) (xy 11.921121 -135.45593) (xy 11.868828 -135.471288) (xy 11.814882 -135.479048)
			(xy 11.787632 -135.479536) (xy 11.760262 -135.479067) (xy 11.706082 -135.471252) (xy 11.653578 -135.455765)
			(xy 11.603831 -135.432923) (xy 11.557865 -135.403198) (xy 11.536934 -135.385556) (xy 11.53668 -135.385302)
			(xy 11.529603 -135.379701) (xy 11.512679 -135.373463) (xy 11.50366 -135.37311) (xy 11.436604 -135.37311)
			(xy 11.427587 -135.373467) (xy 11.41067 -135.379714) (xy 11.403584 -135.385302) (xy 11.403584 -135.385556)
			(xy 11.40333 -135.385556) (xy 11.382397 -135.403197) (xy 11.336429 -135.432921) (xy 11.286683 -135.455767)
			(xy 11.234181 -135.471263) (xy 11.180003 -135.479092) (xy 11.125261 -135.479092) (xy 11.071083 -135.471263)
			(xy 11.018581 -135.455767) (xy 10.968835 -135.432921) (xy 10.922867 -135.403197) (xy 10.901934 -135.385556)
			(xy 10.90168 -135.385302) (xy 10.894603 -135.379701) (xy 10.877679 -135.373463) (xy 10.86866 -135.37311)
			(xy 10.801604 -135.37311) (xy 10.792587 -135.373467) (xy 10.77567 -135.379714) (xy 10.768584 -135.385302)
			(xy 10.768584 -135.385556) (xy 10.76833 -135.385556) (xy 10.747392 -135.403188) (xy 10.701421 -135.432902)
			(xy 10.651676 -135.45574) (xy 10.599176 -135.471233) (xy 10.545001 -135.479062) (xy 10.517632 -135.479536)
			(xy 10.488715 -135.479019) (xy 10.431542 -135.470293) (xy 10.376342 -135.453037) (xy 10.32438 -135.427645)
			(xy 10.276847 -135.3947) (xy 10.234831 -135.354957) (xy 10.216642 -135.33247) (xy 10.208844 -135.323489)
			(xy 10.187383 -135.313296) (xy 10.175494 -135.312912) (xy 10.082022 -135.314944) (xy 10.060686 -135.32612)
			(xy 10.053828 -135.336026) (xy 10.038432 -135.356938) (xy 10.002853 -135.394764) (xy 9.962473 -135.427415)
			(xy 9.918038 -135.454289) (xy 9.87037 -135.474889) (xy 9.820348 -135.488834) (xy 9.768897 -135.495867)
			(xy 9.742932 -135.4963) (xy 9.715679 -135.495833) (xy 9.661728 -135.488076) (xy 9.609431 -135.47272)
			(xy 9.55985 -135.450078) (xy 9.513997 -135.42061) (xy 9.472805 -135.384917) (xy 9.437111 -135.343724)
			(xy 9.407643 -135.297871) (xy 9.385 -135.248291) (xy 9.369644 -135.195994) (xy 9.361887 -135.142043)
			(xy 4.421886 -135.142043) (xy 4.421886 -135.689594) (xy 7.28294 -135.689594) (xy 7.287011 -135.633972)
			(xy 7.299137 -135.579535) (xy 7.31906 -135.527444) (xy 7.346356 -135.478809) (xy 7.380442 -135.434666)
			(xy 7.420591 -135.395957) (xy 7.465949 -135.363506) (xy 7.515549 -135.338005) (xy 7.568333 -135.319998)
			(xy 7.623176 -135.309868) (xy 7.67891 -135.307831) (xy 7.734347 -135.313931) (xy 7.788304 -135.328037)
			(xy 7.839633 -135.349849) (xy 7.887239 -135.378903) (xy 7.930107 -135.414578) (xy 7.967324 -135.456115)
			(xy 7.998097 -135.502628) (xy 8.021769 -135.553125) (xy 8.037837 -135.606532) (xy 8.045957 -135.661708)
			(xy 8.046466 -135.689594) (xy 8.045957 -135.71748) (xy 8.037837 -135.772656) (xy 8.021769 -135.826063)
			(xy 8.002632 -135.866886) (xy 8.43991 -135.866886) (xy 8.443981 -135.811264) (xy 8.456107 -135.756827)
			(xy 8.47603 -135.704736) (xy 8.503326 -135.656101) (xy 8.537412 -135.611958) (xy 8.577561 -135.573249)
			(xy 8.622919 -135.540798) (xy 8.672519 -135.515297) (xy 8.725303 -135.49729) (xy 8.780146 -135.48716)
			(xy 8.83588 -135.485123) (xy 8.891317 -135.491223) (xy 8.945274 -135.505329) (xy 8.996603 -135.527141)
			(xy 9.044209 -135.556195) (xy 9.087077 -135.59187) (xy 9.124294 -135.633407) (xy 9.155067 -135.67992)
			(xy 9.178739 -135.730417) (xy 9.194807 -135.783824) (xy 9.202927 -135.839) (xy 9.203436 -135.866886)
			(xy 9.202927 -135.894772) (xy 9.194807 -135.949948) (xy 9.178739 -136.003355) (xy 9.155067 -136.053852)
			(xy 9.124294 -136.100365) (xy 9.087077 -136.141902) (xy 9.044209 -136.177577) (xy 8.996603 -136.206631)
			(xy 8.945274 -136.228443) (xy 8.891317 -136.242549) (xy 8.83588 -136.248649) (xy 8.780146 -136.246612)
			(xy 8.725303 -136.236482) (xy 8.672519 -136.218475) (xy 8.622919 -136.192974) (xy 8.577561 -136.160523)
			(xy 8.537412 -136.121814) (xy 8.503326 -136.077671) (xy 8.47603 -136.029036) (xy 8.456107 -135.976945)
			(xy 8.443981 -135.922508) (xy 8.43991 -135.866886) (xy 8.002632 -135.866886) (xy 7.998097 -135.87656)
			(xy 7.967324 -135.923073) (xy 7.930107 -135.96461) (xy 7.887239 -136.000285) (xy 7.839633 -136.029339)
			(xy 7.788304 -136.051151) (xy 7.734347 -136.065257) (xy 7.67891 -136.071357) (xy 7.623176 -136.06932)
			(xy 7.568333 -136.05919) (xy 7.515549 -136.041183) (xy 7.465949 -136.015682) (xy 7.420591 -135.983231)
			(xy 7.380442 -135.944522) (xy 7.346356 -135.900379) (xy 7.31906 -135.851744) (xy 7.299137 -135.799653)
			(xy 7.287011 -135.745216) (xy 7.28294 -135.689594) (xy 4.421886 -135.689594) (xy 4.421886 -137.44829)
			(xy 8.345168 -137.44829) (xy 8.349239 -137.392668) (xy 8.361365 -137.338231) (xy 8.381288 -137.28614)
			(xy 8.408584 -137.237505) (xy 8.44267 -137.193362) (xy 8.482819 -137.154653) (xy 8.528177 -137.122202)
			(xy 8.577777 -137.096701) (xy 8.630561 -137.078694) (xy 8.685404 -137.068564) (xy 8.741138 -137.066527)
			(xy 8.796575 -137.072627) (xy 8.850532 -137.086733) (xy 8.901861 -137.108545) (xy 8.949467 -137.137599)
			(xy 8.992335 -137.173274) (xy 9.029552 -137.214811) (xy 9.060325 -137.261324) (xy 9.06736 -137.276332)
			(xy 13.047218 -137.276332) (xy 13.047698 -137.248962) (xy 13.055512 -137.194784) (xy 13.070998 -137.14228)
			(xy 13.093836 -137.092533) (xy 13.123558 -137.046566) (xy 13.141198 -137.025634) (xy 13.141452 -137.02538)
			(xy 13.147059 -137.018308) (xy 13.153292 -137.00138) (xy 13.153644 -136.99236) (xy 13.153644 -136.925304)
			(xy 13.153297 -136.916286) (xy 13.147044 -136.899368) (xy 13.141452 -136.892284) (xy 13.141198 -136.892284)
			(xy 13.141198 -136.89203) (xy 13.123559 -136.871098) (xy 13.093847 -136.825125) (xy 13.071011 -136.775377)
			(xy 13.05552 -136.722877) (xy 13.047692 -136.668701) (xy 13.047218 -136.641332) (xy 13.047704 -136.614081)
			(xy 13.05546 -136.560133) (xy 13.070815 -136.507838) (xy 13.093457 -136.458261) (xy 13.122923 -136.412411)
			(xy 13.158614 -136.37122) (xy 13.199805 -136.335529) (xy 13.245655 -136.306063) (xy 13.295232 -136.283421)
			(xy 13.347527 -136.268066) (xy 13.401475 -136.26031) (xy 13.455977 -136.26031) (xy 13.509925 -136.268066)
			(xy 13.56222 -136.283421) (xy 13.611797 -136.306063) (xy 13.657647 -136.335529) (xy 13.698838 -136.37122)
			(xy 13.734529 -136.412411) (xy 13.763995 -136.458261) (xy 13.786637 -136.507838) (xy 13.801992 -136.560133)
			(xy 13.809748 -136.614081) (xy 13.810234 -136.641332) (xy 13.809803 -136.668704) (xy 13.801979 -136.722885)
			(xy 13.786483 -136.775389) (xy 13.763633 -136.825135) (xy 13.7339 -136.8711) (xy 13.716254 -136.89203)
			(xy 13.716 -136.892284) (xy 13.710414 -136.899371) (xy 13.704167 -136.916287) (xy 13.703808 -136.925304)
			(xy 13.703808 -136.99236) (xy 13.704183 -137.001375) (xy 13.710418 -137.018292) (xy 13.716 -137.02538)
			(xy 13.716254 -137.02538) (xy 13.716254 -137.025634) (xy 13.733868 -137.046586) (xy 13.763586 -137.092553)
			(xy 13.786427 -137.142295) (xy 13.801924 -137.194792) (xy 13.809757 -137.248964) (xy 13.810234 -137.276332)
			(xy 13.809748 -137.303583) (xy 13.801992 -137.357531) (xy 13.786637 -137.409826) (xy 13.763995 -137.459403)
			(xy 13.734529 -137.505253) (xy 13.698838 -137.546444) (xy 13.657647 -137.582135) (xy 13.611797 -137.611601)
			(xy 13.56222 -137.634243) (xy 13.509925 -137.649598) (xy 13.455977 -137.657354) (xy 13.401475 -137.657354)
			(xy 13.347527 -137.649598) (xy 13.295232 -137.634243) (xy 13.245655 -137.611601) (xy 13.199805 -137.582135)
			(xy 13.158614 -137.546444) (xy 13.122923 -137.505253) (xy 13.093457 -137.459403) (xy 13.070815 -137.409826)
			(xy 13.05546 -137.357531) (xy 13.047704 -137.303583) (xy 13.047218 -137.276332) (xy 9.06736 -137.276332)
			(xy 9.083997 -137.311821) (xy 9.100065 -137.365228) (xy 9.108185 -137.420404) (xy 9.108694 -137.44829)
			(xy 9.108185 -137.476176) (xy 9.100065 -137.531352) (xy 9.083997 -137.584759) (xy 9.060325 -137.635256)
			(xy 9.029552 -137.681769) (xy 8.992335 -137.723306) (xy 8.988288 -137.726674) (xy 13.98778 -137.726674)
			(xy 13.988211 -137.699302) (xy 13.996035 -137.645121) (xy 14.011531 -137.592617) (xy 14.034381 -137.54287)
			(xy 14.064114 -137.496906) (xy 14.08176 -137.475976) (xy 14.082014 -137.475722) (xy 14.087599 -137.468634)
			(xy 14.093846 -137.451718) (xy 14.094206 -137.442702) (xy 14.094206 -137.375646) (xy 14.093826 -137.366631)
			(xy 14.087594 -137.349714) (xy 14.082014 -137.342626) (xy 14.08176 -137.342626) (xy 14.08176 -137.342372)
			(xy 14.064135 -137.321429) (xy 14.034422 -137.275459) (xy 14.011584 -137.225714) (xy 13.996089 -137.173216)
			(xy 13.988256 -137.119042) (xy 13.98778 -137.091674) (xy 13.988266 -137.064423) (xy 13.996022 -137.010475)
			(xy 14.011377 -136.95818) (xy 14.034019 -136.908603) (xy 14.063485 -136.862753) (xy 14.099176 -136.821562)
			(xy 14.140367 -136.785871) (xy 14.186217 -136.756405) (xy 14.235794 -136.733763) (xy 14.288089 -136.718408)
			(xy 14.342037 -136.710652) (xy 14.396539 -136.710652) (xy 14.450487 -136.718408) (xy 14.502782 -136.733763)
			(xy 14.552359 -136.756405) (xy 14.598209 -136.785871) (xy 14.6394 -136.821562) (xy 14.675091 -136.862753)
			(xy 14.704557 -136.908603) (xy 14.727199 -136.95818) (xy 14.742554 -137.010475) (xy 14.75031 -137.064423)
			(xy 14.750796 -137.091674) (xy 14.750316 -137.119044) (xy 14.742501 -137.173222) (xy 14.727016 -137.225725)
			(xy 14.704177 -137.275472) (xy 14.674456 -137.32144) (xy 14.656816 -137.342372) (xy 14.656562 -137.342626)
			(xy 14.650996 -137.349726) (xy 14.644738 -137.366633) (xy 14.64437 -137.375646) (xy 14.64437 -137.442702)
			(xy 14.644733 -137.451718) (xy 14.650977 -137.468635) (xy 14.656562 -137.475722) (xy 14.656816 -137.475722)
			(xy 14.656816 -137.475976) (xy 14.67446 -137.496904) (xy 14.70417 -137.542878) (xy 14.727005 -137.592627)
			(xy 14.742495 -137.645128) (xy 14.750322 -137.699305) (xy 14.750796 -137.726674) (xy 14.75031 -137.753925)
			(xy 14.742554 -137.807873) (xy 14.727199 -137.860168) (xy 14.704557 -137.909745) (xy 14.675091 -137.955595)
			(xy 14.6394 -137.996786) (xy 14.598209 -138.032477) (xy 14.552359 -138.061943) (xy 14.502782 -138.084585)
			(xy 14.450487 -138.09994) (xy 14.396539 -138.107696) (xy 14.342037 -138.107696) (xy 14.288089 -138.09994)
			(xy 14.235794 -138.084585) (xy 14.186217 -138.061943) (xy 14.140367 -138.032477) (xy 14.099176 -137.996786)
			(xy 14.063485 -137.955595) (xy 14.034019 -137.909745) (xy 14.011377 -137.860168) (xy 13.996022 -137.807873)
			(xy 13.988266 -137.753925) (xy 13.98778 -137.726674) (xy 8.988288 -137.726674) (xy 8.949467 -137.758981)
			(xy 8.901861 -137.788035) (xy 8.850532 -137.809847) (xy 8.796575 -137.823953) (xy 8.741138 -137.830053)
			(xy 8.685404 -137.828016) (xy 8.630561 -137.817886) (xy 8.577777 -137.799879) (xy 8.528177 -137.774378)
			(xy 8.482819 -137.741927) (xy 8.44267 -137.703218) (xy 8.408584 -137.659075) (xy 8.381288 -137.61044)
			(xy 8.361365 -137.558349) (xy 8.349239 -137.503912) (xy 8.345168 -137.44829) (xy 4.421886 -137.44829)
			(xy 4.421886 -138.360404) (xy 6.176008 -138.360404) (xy 6.180079 -138.304782) (xy 6.192205 -138.250345)
			(xy 6.212128 -138.198254) (xy 6.239424 -138.149619) (xy 6.27351 -138.105476) (xy 6.313659 -138.066767)
			(xy 6.359017 -138.034316) (xy 6.408617 -138.008815) (xy 6.461401 -137.990808) (xy 6.516244 -137.980678)
			(xy 6.571978 -137.978641) (xy 6.627415 -137.984741) (xy 6.681372 -137.998847) (xy 6.732701 -138.020659)
			(xy 6.780307 -138.049713) (xy 6.823175 -138.085388) (xy 6.860392 -138.126925) (xy 6.891165 -138.173438)
			(xy 6.914837 -138.223935) (xy 6.930905 -138.277342) (xy 6.939025 -138.332518) (xy 6.939534 -138.360404)
			(xy 6.939025 -138.38829) (xy 6.936812 -138.40333) (xy 15.196312 -138.40333) (xy 15.196842 -138.375665)
			(xy 15.204838 -138.320917) (xy 15.220651 -138.267895) (xy 15.243951 -138.217711) (xy 15.274249 -138.171415)
			(xy 15.310912 -138.129977) (xy 15.353172 -138.094264) (xy 15.376398 -138.079226) (xy 15.386055 -138.072565)
			(xy 15.398512 -138.052722) (xy 15.400274 -138.041126) (xy 15.408148 -137.961116) (xy 15.408763 -137.949478)
			(xy 15.400695 -137.927642) (xy 15.392654 -137.919206) (xy 15.3924 -137.918952) (xy 15.373813 -137.900876)
			(xy 15.341235 -137.860543) (xy 15.314423 -137.816168) (xy 15.293871 -137.768568) (xy 15.279959 -137.718623)
			(xy 15.272943 -137.667253) (xy 15.272512 -137.64133) (xy 15.272983 -137.614077) (xy 15.280737 -137.560125)
			(xy 15.29609 -137.507826) (xy 15.31873 -137.458245) (xy 15.348197 -137.412391) (xy 15.38389 -137.371197)
			(xy 15.425083 -137.335503) (xy 15.470936 -137.306035) (xy 15.520517 -137.283393) (xy 15.572816 -137.268039)
			(xy 15.626767 -137.260284) (xy 15.65402 -137.259822) (xy 15.681391 -137.260271) (xy 15.735571 -137.268092)
			(xy 15.788074 -137.283585) (xy 15.837821 -137.306431) (xy 15.883787 -137.336159) (xy 15.904718 -137.353802)
			(xy 15.904972 -137.354056) (xy 15.912058 -137.359644) (xy 15.928975 -137.365888) (xy 15.937992 -137.366248)
			(xy 16.005048 -137.366248) (xy 16.014064 -137.365877) (xy 16.030981 -137.359641) (xy 16.038068 -137.354056)
			(xy 16.038068 -137.353802) (xy 16.038322 -137.353802) (xy 16.059273 -137.336186) (xy 16.105241 -137.306471)
			(xy 16.154983 -137.28363) (xy 16.20748 -137.268134) (xy 16.261652 -137.260299) (xy 16.28902 -137.259822)
			(xy 16.316275 -137.260236) (xy 16.370229 -137.267997) (xy 16.42253 -137.283357) (xy 16.472112 -137.306004)
			(xy 16.517966 -137.335477) (xy 16.55916 -137.371176) (xy 16.594853 -137.412374) (xy 16.62432 -137.458232)
			(xy 16.646961 -137.507817) (xy 16.662314 -137.56012) (xy 16.670067 -137.614075) (xy 16.670528 -137.64133)
			(xy 16.669987 -137.670246) (xy 16.661266 -137.727418) (xy 16.644015 -137.782617) (xy 16.618627 -137.83458)
			(xy 16.585686 -137.882114) (xy 16.545947 -137.92413) (xy 16.523462 -137.94232) (xy 16.514649 -137.949922)
			(xy 16.50447 -137.970827) (xy 16.503904 -137.982452) (xy 16.503904 -138.062208) (xy 16.504451 -138.073839)
			(xy 16.514634 -138.094749) (xy 16.523462 -138.10234) (xy 16.545957 -138.120518) (xy 16.585693 -138.162539)
			(xy 16.618632 -138.210077) (xy 16.644019 -138.262041) (xy 16.661272 -138.317241) (xy 16.669996 -138.374413)
			(xy 16.670528 -138.40333) (xy 16.67005 -138.430581) (xy 16.66229 -138.484528) (xy 16.646932 -138.536822)
			(xy 16.624289 -138.586398) (xy 16.594821 -138.632247) (xy 16.559129 -138.673436) (xy 16.517939 -138.709127)
			(xy 16.472089 -138.738594) (xy 16.422512 -138.761236) (xy 16.370218 -138.776592) (xy 16.316271 -138.784351)
			(xy 16.28902 -138.784838) (xy 16.262706 -138.784377) (xy 16.210576 -138.777144) (xy 16.159932 -138.762825)
			(xy 16.111733 -138.741691) (xy 16.06689 -138.714143) (xy 16.026251 -138.680701) (xy 16.008096 -138.661648)
			(xy 16.000571 -138.65425) (xy 15.981294 -138.645722) (xy 15.970758 -138.645138) (xy 15.896082 -138.645138)
			(xy 15.885534 -138.645687) (xy 15.866238 -138.654207) (xy 15.858744 -138.661648) (xy 15.840618 -138.680733)
			(xy 15.799981 -138.714185) (xy 15.755134 -138.741739) (xy 15.706928 -138.762872) (xy 15.656276 -138.777184)
			(xy 15.604138 -138.784403) (xy 15.57782 -138.784838) (xy 15.550571 -138.784303) (xy 15.496626 -138.77655)
			(xy 15.444334 -138.761199) (xy 15.394759 -138.738563) (xy 15.34891 -138.709101) (xy 15.307721 -138.673415)
			(xy 15.272029 -138.63223) (xy 15.242561 -138.586385) (xy 15.219918 -138.536813) (xy 15.20456 -138.484523)
			(xy 15.1968 -138.430579) (xy 15.196312 -138.40333) (xy 6.936812 -138.40333) (xy 6.930905 -138.443466)
			(xy 6.914837 -138.496873) (xy 6.891165 -138.54737) (xy 6.860392 -138.593883) (xy 6.823175 -138.63542)
			(xy 6.780307 -138.671095) (xy 6.732701 -138.700149) (xy 6.681372 -138.721961) (xy 6.627415 -138.736067)
			(xy 6.571978 -138.742167) (xy 6.516244 -138.74013) (xy 6.461401 -138.73) (xy 6.408617 -138.711993)
			(xy 6.359017 -138.686492) (xy 6.313659 -138.654041) (xy 6.27351 -138.615332) (xy 6.239424 -138.571189)
			(xy 6.212128 -138.522554) (xy 6.192205 -138.470463) (xy 6.180079 -138.416026) (xy 6.176008 -138.360404)
			(xy 4.421886 -138.360404) (xy 4.421886 -138.824462) (xy 8.361932 -138.824462) (xy 8.366003 -138.76884)
			(xy 8.378129 -138.714403) (xy 8.398052 -138.662312) (xy 8.425348 -138.613677) (xy 8.459434 -138.569534)
			(xy 8.499583 -138.530825) (xy 8.544941 -138.498374) (xy 8.594541 -138.472873) (xy 8.647325 -138.454866)
			(xy 8.702168 -138.444736) (xy 8.757902 -138.442699) (xy 8.813339 -138.448799) (xy 8.867296 -138.462905)
			(xy 8.918625 -138.484717) (xy 8.966231 -138.513771) (xy 9.009099 -138.549446) (xy 9.046316 -138.590983)
			(xy 9.077089 -138.637496) (xy 9.100761 -138.687993) (xy 9.116829 -138.7414) (xy 9.124949 -138.796576)
			(xy 9.125458 -138.824462) (xy 9.124949 -138.852348) (xy 9.116829 -138.907524) (xy 9.100761 -138.960931)
			(xy 9.077089 -139.011428) (xy 9.046316 -139.057941) (xy 9.009099 -139.099478) (xy 8.966231 -139.135153)
			(xy 8.918625 -139.164207) (xy 8.867296 -139.186019) (xy 8.813339 -139.200125) (xy 8.757902 -139.206225)
			(xy 8.702168 -139.204188) (xy 8.647325 -139.194058) (xy 8.594541 -139.176051) (xy 8.544941 -139.15055)
			(xy 8.499583 -139.118099) (xy 8.459434 -139.07939) (xy 8.425348 -139.035247) (xy 8.398052 -138.986612)
			(xy 8.378129 -138.934521) (xy 8.366003 -138.880084) (xy 8.361932 -138.824462) (xy 4.421886 -138.824462)
			(xy 4.421886 -139.376404) (xy 6.176008 -139.376404) (xy 6.180079 -139.320782) (xy 6.192205 -139.266345)
			(xy 6.212128 -139.214254) (xy 6.239424 -139.165619) (xy 6.27351 -139.121476) (xy 6.313659 -139.082767)
			(xy 6.359017 -139.050316) (xy 6.408617 -139.024815) (xy 6.461401 -139.006808) (xy 6.516244 -138.996678)
			(xy 6.571978 -138.994641) (xy 6.627415 -139.000741) (xy 6.681372 -139.014847) (xy 6.732701 -139.036659)
			(xy 6.780307 -139.065713) (xy 6.823175 -139.101388) (xy 6.860392 -139.142925) (xy 6.891165 -139.189438)
			(xy 6.914837 -139.239935) (xy 6.930905 -139.293342) (xy 6.939025 -139.348518) (xy 6.939534 -139.376404)
			(xy 6.939025 -139.40429) (xy 6.930905 -139.459466) (xy 6.914837 -139.512873) (xy 6.891165 -139.56337)
			(xy 6.860392 -139.609883) (xy 6.823175 -139.65142) (xy 6.780307 -139.687095) (xy 6.732701 -139.716149)
			(xy 6.681372 -139.737961) (xy 6.627415 -139.752067) (xy 6.571978 -139.758167) (xy 6.516244 -139.75613)
			(xy 6.461401 -139.746) (xy 6.408617 -139.727993) (xy 6.359017 -139.702492) (xy 6.313659 -139.670041)
			(xy 6.27351 -139.631332) (xy 6.239424 -139.587189) (xy 6.212128 -139.538554) (xy 6.192205 -139.486463)
			(xy 6.180079 -139.432026) (xy 6.176008 -139.376404) (xy 4.421886 -139.376404) (xy 4.421886 -140.392404)
			(xy 8.367774 -140.392404) (xy 8.371845 -140.336782) (xy 8.383971 -140.282345) (xy 8.403894 -140.230254)
			(xy 8.43119 -140.181619) (xy 8.465276 -140.137476) (xy 8.505425 -140.098767) (xy 8.550783 -140.066316)
			(xy 8.600383 -140.040815) (xy 8.653167 -140.022808) (xy 8.70801 -140.012678) (xy 8.763744 -140.010641)
			(xy 8.819181 -140.016741) (xy 8.873138 -140.030847) (xy 8.924467 -140.052659) (xy 8.972073 -140.081713)
			(xy 9.014941 -140.117388) (xy 9.052158 -140.158925) (xy 9.082931 -140.205438) (xy 9.106603 -140.255935)
			(xy 9.122671 -140.309342) (xy 9.130791 -140.364518) (xy 9.1313 -140.392404) (xy 9.130791 -140.42029)
			(xy 9.122671 -140.475466) (xy 9.106603 -140.528873) (xy 9.082931 -140.57937) (xy 9.052158 -140.625883)
			(xy 9.014941 -140.66742) (xy 8.972073 -140.703095) (xy 8.924467 -140.732149) (xy 8.873138 -140.753961)
			(xy 8.819181 -140.768067) (xy 8.763744 -140.774167) (xy 8.70801 -140.77213) (xy 8.653167 -140.762)
			(xy 8.600383 -140.743993) (xy 8.550783 -140.718492) (xy 8.505425 -140.686041) (xy 8.465276 -140.647332)
			(xy 8.43119 -140.603189) (xy 8.403894 -140.554554) (xy 8.383971 -140.502463) (xy 8.371845 -140.448026)
			(xy 8.367774 -140.392404) (xy 4.421886 -140.392404) (xy 4.421886 -141.046533) (xy 10.755071 -141.046533)
			(xy 10.755071 -140.992027) (xy 10.762828 -140.938075) (xy 10.778185 -140.885777) (xy 10.800828 -140.836196)
			(xy 10.830296 -140.790342) (xy 10.86599 -140.749149) (xy 10.907184 -140.713455) (xy 10.953038 -140.683987)
			(xy 11.002618 -140.661344) (xy 11.054917 -140.645988) (xy 11.108869 -140.638231) (xy 11.136122 -140.637768)
			(xy 11.162436 -140.638231) (xy 11.214564 -140.645468) (xy 11.265207 -140.659789) (xy 11.313405 -140.680922)
			(xy 11.358249 -140.708469) (xy 11.398889 -140.741907) (xy 11.417046 -140.760958) (xy 11.424554 -140.768376)
			(xy 11.443844 -140.776892) (xy 11.454384 -140.777468) (xy 11.52906 -140.777468) (xy 11.53961 -140.77694)
			(xy 11.558906 -140.768405) (xy 11.566398 -140.760958) (xy 11.584553 -140.741902) (xy 11.625184 -140.708447)
			(xy 11.670025 -140.680889) (xy 11.718225 -140.659751) (xy 11.768872 -140.645433) (xy 11.821006 -140.638207)
			(xy 11.847322 -140.637768) (xy 11.874573 -140.638262) (xy 11.92852 -140.646019) (xy 11.980814 -140.661374)
			(xy 12.03039 -140.684015) (xy 12.07624 -140.713481) (xy 12.117429 -140.749172) (xy 12.15312 -140.790362)
			(xy 12.182586 -140.836212) (xy 12.205227 -140.885788) (xy 12.220582 -140.938082) (xy 12.228338 -140.992029)
			(xy 12.228338 -141.046531) (xy 12.220582 -141.100478) (xy 12.205227 -141.152772) (xy 12.182586 -141.202348)
			(xy 12.15312 -141.248198) (xy 12.117429 -141.289388) (xy 12.07624 -141.325079) (xy 12.03039 -141.354545)
			(xy 11.980814 -141.377186) (xy 11.92852 -141.392541) (xy 11.874573 -141.400298) (xy 11.847322 -141.400784)
			(xy 11.821008 -141.400307) (xy 11.76888 -141.393075) (xy 11.718237 -141.378758) (xy 11.670038 -141.357627)
			(xy 11.625194 -141.330083) (xy 11.584555 -141.296645) (xy 11.566398 -141.277594) (xy 11.55888 -141.270189)
			(xy 11.539597 -141.261667) (xy 11.52906 -141.261084) (xy 11.454384 -141.261084) (xy 11.443832 -141.261596)
			(xy 11.424538 -141.270144) (xy 11.417046 -141.277594) (xy 11.398909 -141.296668) (xy 11.358275 -141.330123)
			(xy 11.313431 -141.35768) (xy 11.265227 -141.378815) (xy 11.214576 -141.393129) (xy 11.162439 -141.400348)
			(xy 11.136122 -141.400784) (xy 11.108869 -141.400329) (xy 11.054917 -141.392572) (xy 11.002618 -141.377216)
			(xy 10.953038 -141.354573) (xy 10.907184 -141.325105) (xy 10.86599 -141.289411) (xy 10.830296 -141.248218)
			(xy 10.800828 -141.202364) (xy 10.778185 -141.152783) (xy 10.762828 -141.100485) (xy 10.755071 -141.046533)
			(xy 4.421886 -141.046533) (xy 4.421886 -143.078533) (xy 10.755071 -143.078533) (xy 10.755071 -143.024027)
			(xy 10.762828 -142.970075) (xy 10.778185 -142.917777) (xy 10.800828 -142.868196) (xy 10.830296 -142.822342)
			(xy 10.86599 -142.781149) (xy 10.907184 -142.745455) (xy 10.953038 -142.715987) (xy 11.002618 -142.693344)
			(xy 11.054917 -142.677988) (xy 11.108869 -142.670231) (xy 11.136122 -142.669768) (xy 11.162436 -142.670231)
			(xy 11.214564 -142.677468) (xy 11.265207 -142.691789) (xy 11.313405 -142.712922) (xy 11.358249 -142.740469)
			(xy 11.398889 -142.773907) (xy 11.417046 -142.792958) (xy 11.424554 -142.800376) (xy 11.443844 -142.808892)
			(xy 11.454384 -142.809468) (xy 11.52906 -142.809468) (xy 11.53961 -142.80894) (xy 11.558906 -142.800405)
			(xy 11.566398 -142.792958) (xy 11.584553 -142.773902) (xy 11.625184 -142.740447) (xy 11.670025 -142.712889)
			(xy 11.718225 -142.691751) (xy 11.768872 -142.677433) (xy 11.821006 -142.670207) (xy 11.847322 -142.669768)
			(xy 11.874573 -142.670262) (xy 11.92852 -142.678019) (xy 11.980814 -142.693374) (xy 12.03039 -142.716015)
			(xy 12.07624 -142.745481) (xy 12.117429 -142.781172) (xy 12.15312 -142.822362) (xy 12.182586 -142.868212)
			(xy 12.205227 -142.917788) (xy 12.220582 -142.970082) (xy 12.228338 -143.024029) (xy 12.228338 -143.078531)
			(xy 12.220582 -143.132478) (xy 12.205227 -143.184772) (xy 12.182586 -143.234348) (xy 12.15312 -143.280198)
			(xy 12.117429 -143.321388) (xy 12.07624 -143.357079) (xy 12.03039 -143.386545) (xy 11.980814 -143.409186)
			(xy 11.92852 -143.424541) (xy 11.874573 -143.432298) (xy 11.847322 -143.432784) (xy 11.821008 -143.432307)
			(xy 11.76888 -143.425075) (xy 11.718237 -143.410758) (xy 11.670038 -143.389627) (xy 11.625194 -143.362083)
			(xy 11.584555 -143.328645) (xy 11.566398 -143.309594) (xy 11.55888 -143.302189) (xy 11.539597 -143.293667)
			(xy 11.52906 -143.293084) (xy 11.454384 -143.293084) (xy 11.443832 -143.293596) (xy 11.424538 -143.302144)
			(xy 11.417046 -143.309594) (xy 11.398909 -143.328668) (xy 11.358275 -143.362123) (xy 11.313431 -143.38968)
			(xy 11.265227 -143.410815) (xy 11.214576 -143.425129) (xy 11.162439 -143.432348) (xy 11.136122 -143.432784)
			(xy 11.108869 -143.432329) (xy 11.054917 -143.424572) (xy 11.002618 -143.409216) (xy 10.953038 -143.386573)
			(xy 10.907184 -143.357105) (xy 10.86599 -143.321411) (xy 10.830296 -143.280218) (xy 10.800828 -143.234364)
			(xy 10.778185 -143.184783) (xy 10.762828 -143.132485) (xy 10.755071 -143.078533) (xy 4.421886 -143.078533)
			(xy 4.421886 -145.110533) (xy 10.755071 -145.110533) (xy 10.755071 -145.056027) (xy 10.762828 -145.002075)
			(xy 10.778185 -144.949777) (xy 10.800828 -144.900196) (xy 10.830296 -144.854342) (xy 10.86599 -144.813149)
			(xy 10.907184 -144.777455) (xy 10.953038 -144.747987) (xy 11.002618 -144.725344) (xy 11.054917 -144.709988)
			(xy 11.108869 -144.702231) (xy 11.136122 -144.701768) (xy 11.162436 -144.702231) (xy 11.214564 -144.709468)
			(xy 11.265207 -144.723789) (xy 11.313405 -144.744922) (xy 11.358249 -144.772469) (xy 11.398889 -144.805907)
			(xy 11.417046 -144.824958) (xy 11.424554 -144.832376) (xy 11.443844 -144.840892) (xy 11.454384 -144.841468)
			(xy 11.52906 -144.841468) (xy 11.53961 -144.84094) (xy 11.558906 -144.832405) (xy 11.566398 -144.824958)
			(xy 11.584553 -144.805902) (xy 11.625184 -144.772447) (xy 11.670025 -144.744889) (xy 11.718225 -144.723751)
			(xy 11.768872 -144.709433) (xy 11.821006 -144.702207) (xy 11.847322 -144.701768) (xy 11.874573 -144.702262)
			(xy 11.92852 -144.710019) (xy 11.980814 -144.725374) (xy 12.03039 -144.748015) (xy 12.07624 -144.777481)
			(xy 12.117429 -144.813172) (xy 12.15312 -144.854362) (xy 12.182586 -144.900212) (xy 12.205227 -144.949788)
			(xy 12.206535 -144.954244) (xy 17.939004 -144.954244) (xy 17.939496 -144.926992) (xy 17.947248 -144.873041)
			(xy 17.962599 -144.820743) (xy 17.985237 -144.771162) (xy 18.014701 -144.725308) (xy 18.050392 -144.684115)
			(xy 18.091583 -144.648421) (xy 18.137434 -144.618952) (xy 18.187013 -144.59631) (xy 18.23931 -144.580954)
			(xy 18.29326 -144.573199) (xy 18.320512 -144.572736) (xy 18.349288 -144.573223) (xy 18.406184 -144.581882)
			(xy 18.461135 -144.598986) (xy 18.512895 -144.624148) (xy 18.560289 -144.656798) (xy 18.581624 -144.676114)
			(xy 18.589498 -144.68348) (xy 18.60931 -144.690592) (xy 18.705576 -144.683226) (xy 18.724372 -144.67332)
			(xy 18.730976 -144.664938) (xy 18.749179 -144.642735) (xy 18.791119 -144.603525) (xy 18.838459 -144.571041)
			(xy 18.890131 -144.546016) (xy 18.944969 -144.529014) (xy 19.001735 -144.520419) (xy 19.030442 -144.519904)
			(xy 19.057695 -144.520339) (xy 19.111645 -144.528101) (xy 19.163941 -144.543462) (xy 19.21352 -144.566109)
			(xy 19.25937 -144.595581) (xy 19.30056 -144.631278) (xy 19.336251 -144.672473) (xy 19.365717 -144.718328)
			(xy 19.388357 -144.767909) (xy 19.40371 -144.820208) (xy 19.411465 -144.874159) (xy 19.41195 -144.901412)
			(xy 19.411476 -144.928314) (xy 19.403904 -144.981583) (xy 19.388925 -145.03326) (xy 19.366836 -145.082321)
			(xy 19.338076 -145.127793) (xy 19.303214 -145.168775) (xy 19.262942 -145.204455) (xy 19.240754 -145.219674)
			(xy 19.229832 -145.226786) (xy 19.217894 -145.249646) (xy 19.219926 -145.361914) (xy 19.23288 -145.384266)
			(xy 19.244056 -145.391124) (xy 19.267647 -145.406062) (xy 19.310602 -145.441736) (xy 19.347897 -145.483291)
			(xy 19.378737 -145.529838) (xy 19.402462 -145.580383) (xy 19.418566 -145.633847) (xy 19.426704 -145.689088)
			(xy 19.42719 -145.717006) (xy 19.426721 -145.743999) (xy 19.419116 -145.797446) (xy 19.404057 -145.849289)
			(xy 19.381845 -145.898494) (xy 19.352923 -145.944079) (xy 19.33575 -145.96491) (xy 19.328638 -145.973038)
			(xy 19.322542 -145.993612) (xy 19.333464 -146.078956) (xy 19.335269 -146.089493) (xy 19.346303 -146.107777)
			(xy 19.3548 -146.114262) (xy 19.376018 -146.129632) (xy 19.414469 -146.165218) (xy 19.447687 -146.205732)
			(xy 19.475047 -146.250413) (xy 19.496032 -146.298418) (xy 19.510249 -146.348843) (xy 19.517429 -146.40074)
			(xy 19.517868 -146.426936) (xy 19.517382 -146.454187) (xy 19.509626 -146.508135) (xy 19.494271 -146.56043)
			(xy 19.471629 -146.610007) (xy 19.442163 -146.655857) (xy 19.406472 -146.697048) (xy 19.365281 -146.732739)
			(xy 19.319431 -146.762205) (xy 19.269854 -146.784847) (xy 19.217559 -146.800202) (xy 19.163611 -146.807958)
			(xy 19.109109 -146.807958) (xy 19.055161 -146.800202) (xy 19.002866 -146.784847) (xy 18.953289 -146.762205)
			(xy 18.907439 -146.732739) (xy 18.866248 -146.697048) (xy 18.830557 -146.655857) (xy 18.801091 -146.610007)
			(xy 18.778449 -146.56043) (xy 18.763094 -146.508135) (xy 18.755338 -146.454187) (xy 18.754852 -146.426936)
			(xy 18.755335 -146.399943) (xy 18.762936 -146.346496) (xy 18.777991 -146.294653) (xy 18.8002 -146.245448)
			(xy 18.82912 -146.199863) (xy 18.846292 -146.179032) (xy 18.853404 -146.170904) (xy 18.8595 -146.15033)
			(xy 18.848578 -146.064986) (xy 18.846822 -146.054437) (xy 18.835755 -146.036156) (xy 18.827242 -146.02968)
			(xy 18.802936 -146.012074) (xy 18.75968 -145.970474) (xy 18.741136 -145.946876) (xy 18.735294 -145.939002)
			(xy 18.717768 -145.928588) (xy 18.627344 -145.91538) (xy 18.60804 -145.920206) (xy 18.600166 -145.926048)
			(xy 18.599912 -145.926048) (xy 18.575181 -145.943571) (xy 18.521324 -145.97137) (xy 18.463748 -145.990301)
			(xy 18.403902 -145.999887) (xy 18.373598 -146.00047) (xy 18.346343 -146.000046) (xy 18.292389 -145.992288)
			(xy 18.240088 -145.97693) (xy 18.190505 -145.954284) (xy 18.144651 -145.924813) (xy 18.103457 -145.889115)
			(xy 18.067763 -145.847917) (xy 18.038296 -145.802059) (xy 18.015656 -145.752474) (xy 18.000303 -145.700172)
			(xy 17.992551 -145.646217) (xy 17.99209 -145.618962) (xy 17.992513 -145.592928) (xy 17.999606 -145.541344)
			(xy 18.01364 -145.491201) (xy 18.034357 -145.443431) (xy 18.061371 -145.398917) (xy 18.077434 -145.378424)
			(xy 18.08318 -145.37067) (xy 18.088917 -145.352257) (xy 18.08861 -145.34261) (xy 18.08226 -145.262854)
			(xy 18.073624 -145.245074) (xy 18.066258 -145.238724) (xy 18.046611 -145.220544) (xy 18.012087 -145.179638)
			(xy 17.983617 -145.134309) (xy 17.961759 -145.085447) (xy 17.946943 -145.03401) (xy 17.939458 -144.981008)
			(xy 17.939004 -144.954244) (xy 12.206535 -144.954244) (xy 12.220582 -145.002082) (xy 12.228338 -145.056029)
			(xy 12.228338 -145.110531) (xy 12.220582 -145.164478) (xy 12.205227 -145.216772) (xy 12.182586 -145.266348)
			(xy 12.15312 -145.312198) (xy 12.117429 -145.353388) (xy 12.07624 -145.389079) (xy 12.03039 -145.418545)
			(xy 11.980814 -145.441186) (xy 11.92852 -145.456541) (xy 11.874573 -145.464298) (xy 11.847322 -145.464784)
			(xy 11.821008 -145.464307) (xy 11.76888 -145.457075) (xy 11.718237 -145.442758) (xy 11.670038 -145.421627)
			(xy 11.625194 -145.394083) (xy 11.584555 -145.360645) (xy 11.566398 -145.341594) (xy 11.55888 -145.334189)
			(xy 11.539597 -145.325667) (xy 11.52906 -145.325084) (xy 11.454384 -145.325084) (xy 11.443832 -145.325596)
			(xy 11.424538 -145.334144) (xy 11.417046 -145.341594) (xy 11.398909 -145.360668) (xy 11.358275 -145.394123)
			(xy 11.313431 -145.42168) (xy 11.265227 -145.442815) (xy 11.214576 -145.457129) (xy 11.162439 -145.464348)
			(xy 11.136122 -145.464784) (xy 11.108869 -145.464329) (xy 11.054917 -145.456572) (xy 11.002618 -145.441216)
			(xy 10.953038 -145.418573) (xy 10.907184 -145.389105) (xy 10.86599 -145.353411) (xy 10.830296 -145.312218)
			(xy 10.800828 -145.266364) (xy 10.778185 -145.216783) (xy 10.762828 -145.164485) (xy 10.755071 -145.110533)
			(xy 4.421886 -145.110533) (xy 4.421886 -146.91487) (xy 19.616164 -146.91487) (xy 19.620235 -146.859248)
			(xy 19.632361 -146.804811) (xy 19.652284 -146.75272) (xy 19.67958 -146.704085) (xy 19.713666 -146.659942)
			(xy 19.753815 -146.621233) (xy 19.799173 -146.588782) (xy 19.848773 -146.563281) (xy 19.901557 -146.545274)
			(xy 19.9564 -146.535144) (xy 20.012134 -146.533107) (xy 20.067571 -146.539207) (xy 20.121528 -146.553313)
			(xy 20.172857 -146.575125) (xy 20.220463 -146.604179) (xy 20.263331 -146.639854) (xy 20.300548 -146.681391)
			(xy 20.331321 -146.727904) (xy 20.354993 -146.778401) (xy 20.371061 -146.831808) (xy 20.379181 -146.886984)
			(xy 20.37969 -146.91487) (xy 20.379181 -146.942756) (xy 20.371061 -146.997932) (xy 20.354993 -147.051339)
			(xy 20.349787 -147.062444) (xy 20.994368 -147.062444) (xy 20.998439 -147.006822) (xy 21.010565 -146.952385)
			(xy 21.030488 -146.900294) (xy 21.057784 -146.851659) (xy 21.09187 -146.807516) (xy 21.132019 -146.768807)
			(xy 21.177377 -146.736356) (xy 21.226977 -146.710855) (xy 21.279761 -146.692848) (xy 21.334604 -146.682718)
			(xy 21.390338 -146.680681) (xy 21.445775 -146.686781) (xy 21.499732 -146.700887) (xy 21.551061 -146.722699)
			(xy 21.598667 -146.751753) (xy 21.641535 -146.787428) (xy 21.678752 -146.828965) (xy 21.709525 -146.875478)
			(xy 21.733197 -146.925975) (xy 21.749265 -146.979382) (xy 21.757385 -147.034558) (xy 21.757894 -147.062444)
			(xy 21.757385 -147.09033) (xy 21.749265 -147.145506) (xy 21.733197 -147.198913) (xy 21.709525 -147.24941)
			(xy 21.678752 -147.295923) (xy 21.641535 -147.33746) (xy 21.598667 -147.373135) (xy 21.551061 -147.402189)
			(xy 21.499732 -147.424001) (xy 21.445775 -147.438107) (xy 21.390338 -147.444207) (xy 21.334604 -147.44217)
			(xy 21.279761 -147.43204) (xy 21.226977 -147.414033) (xy 21.177377 -147.388532) (xy 21.132019 -147.356081)
			(xy 21.09187 -147.317372) (xy 21.057784 -147.273229) (xy 21.030488 -147.224594) (xy 21.010565 -147.172503)
			(xy 20.998439 -147.118066) (xy 20.994368 -147.062444) (xy 20.349787 -147.062444) (xy 20.331321 -147.101836)
			(xy 20.300548 -147.148349) (xy 20.263331 -147.189886) (xy 20.220463 -147.225561) (xy 20.172857 -147.254615)
			(xy 20.121528 -147.276427) (xy 20.067571 -147.290533) (xy 20.012134 -147.296633) (xy 19.9564 -147.294596)
			(xy 19.901557 -147.284466) (xy 19.848773 -147.266459) (xy 19.799173 -147.240958) (xy 19.753815 -147.208507)
			(xy 19.713666 -147.169798) (xy 19.67958 -147.125655) (xy 19.652284 -147.07702) (xy 19.632361 -147.024929)
			(xy 19.620235 -146.970492) (xy 19.616164 -146.91487) (xy 4.421886 -146.91487) (xy 4.421886 -147.657652)
			(xy 11.150566 -147.657652) (xy 11.150566 -147.603148) (xy 11.158323 -147.549198) (xy 11.173678 -147.496902)
			(xy 11.19632 -147.447323) (xy 11.225787 -147.401471) (xy 11.26148 -147.36028) (xy 11.302671 -147.324587)
			(xy 11.348523 -147.29512) (xy 11.398102 -147.272478) (xy 11.450398 -147.257123) (xy 11.504348 -147.249366)
			(xy 11.5316 -147.24888) (xy 11.557914 -147.249354) (xy 11.610042 -147.256588) (xy 11.660684 -147.270907)
			(xy 11.708883 -147.292038) (xy 11.753727 -147.319582) (xy 11.794367 -147.353019) (xy 11.812524 -147.37207)
			(xy 11.820039 -147.37948) (xy 11.839324 -147.388001) (xy 11.849862 -147.38858) (xy 11.924538 -147.38858)
			(xy 11.935086 -147.388037) (xy 11.954382 -147.379512) (xy 11.961876 -147.37207) (xy 11.981696 -147.351282)
			(xy 12.026468 -147.315307) (xy 12.076126 -147.286447) (xy 12.129548 -147.265354) (xy 12.185527 -147.252505)
			(xy 12.2428 -147.24819) (xy 12.300073 -147.252505) (xy 12.356052 -147.265354) (xy 12.409474 -147.286447)
			(xy 12.459132 -147.315307) (xy 12.503904 -147.351282) (xy 12.523724 -147.37207) (xy 12.531239 -147.37948)
			(xy 12.550524 -147.388001) (xy 12.561062 -147.38858) (xy 12.635738 -147.38858) (xy 12.646286 -147.388037)
			(xy 12.665582 -147.379512) (xy 12.673076 -147.37207) (xy 12.691244 -147.353027) (xy 12.731872 -147.31957)
			(xy 12.77671 -147.29201) (xy 12.824908 -147.27087) (xy 12.875553 -147.256549) (xy 12.927685 -147.249321)
			(xy 12.954 -147.24888) (xy 12.98125 -147.24939) (xy 13.035196 -147.257147) (xy 13.087489 -147.272501)
			(xy 13.137065 -147.295142) (xy 13.182914 -147.324607) (xy 13.224103 -147.360297) (xy 13.259793 -147.401486)
			(xy 13.289258 -147.447335) (xy 13.311899 -147.496911) (xy 13.327253 -147.549204) (xy 13.33501 -147.60315)
			(xy 13.33501 -147.65765) (xy 13.327253 -147.711596) (xy 13.311899 -147.763889) (xy 13.289258 -147.813465)
			(xy 13.259793 -147.859314) (xy 13.224103 -147.900503) (xy 13.182914 -147.936193) (xy 13.137065 -147.965658)
			(xy 13.087489 -147.988299) (xy 13.035196 -148.003653) (xy 12.98125 -148.01141) (xy 12.954 -148.011896)
			(xy 12.927686 -148.01143) (xy 12.875557 -148.004195) (xy 12.824915 -147.989876) (xy 12.776716 -147.968743)
			(xy 12.731872 -147.941197) (xy 12.691233 -147.907758) (xy 12.673076 -147.888706) (xy 12.665564 -147.881293)
			(xy 12.646277 -147.872775) (xy 12.635738 -147.872196) (xy 12.561062 -147.872196) (xy 12.550515 -147.872746)
			(xy 12.531219 -147.881267) (xy 12.523724 -147.888706) (xy 12.503904 -147.909494) (xy 12.459132 -147.945469)
			(xy 12.409474 -147.974329) (xy 12.356052 -147.995422) (xy 12.300073 -148.008271) (xy 12.2428 -148.012586)
			(xy 12.185527 -148.008271) (xy 12.129548 -147.995422) (xy 12.076126 -147.974329) (xy 12.026468 -147.945469)
			(xy 11.981696 -147.909494) (xy 11.961876 -147.888706) (xy 11.954364 -147.881293) (xy 11.935077 -147.872775)
			(xy 11.924538 -147.872196) (xy 11.849862 -147.872196) (xy 11.839315 -147.872746) (xy 11.820019 -147.881267)
			(xy 11.812524 -147.888706) (xy 11.794351 -147.907744) (xy 11.753725 -147.941203) (xy 11.708888 -147.968764)
			(xy 11.660691 -147.989905) (xy 11.610047 -148.004226) (xy 11.557915 -148.011455) (xy 11.5316 -148.011896)
			(xy 11.504348 -148.011434) (xy 11.450398 -148.003677) (xy 11.398102 -147.988322) (xy 11.348523 -147.96568)
			(xy 11.302671 -147.936213) (xy 11.26148 -147.90052) (xy 11.225787 -147.859329) (xy 11.19632 -147.813477)
			(xy 11.173678 -147.763898) (xy 11.158323 -147.711602) (xy 11.150566 -147.657652) (xy 4.421886 -147.657652)
			(xy 4.421886 -148.017738) (xy 15.977614 -148.017738) (xy 15.981685 -147.962116) (xy 15.993811 -147.907679)
			(xy 16.013734 -147.855588) (xy 16.04103 -147.806953) (xy 16.075116 -147.76281) (xy 16.115265 -147.724101)
			(xy 16.160623 -147.69165) (xy 16.210223 -147.666149) (xy 16.263007 -147.648142) (xy 16.31785 -147.638012)
			(xy 16.373584 -147.635975) (xy 16.429021 -147.642075) (xy 16.482978 -147.656181) (xy 16.534307 -147.677993)
			(xy 16.581913 -147.707047) (xy 16.624781 -147.742722) (xy 16.661998 -147.784259) (xy 16.692771 -147.830772)
			(xy 16.716443 -147.881269) (xy 16.732511 -147.934676) (xy 16.740631 -147.989852) (xy 16.74114 -148.017738)
			(xy 16.740631 -148.045624) (xy 16.732511 -148.1008) (xy 16.716443 -148.154207) (xy 16.692771 -148.204704)
			(xy 16.661998 -148.251217) (xy 16.624781 -148.292754) (xy 16.581913 -148.328429) (xy 16.534307 -148.357483)
			(xy 16.482978 -148.379295) (xy 16.429021 -148.393401) (xy 16.373584 -148.399501) (xy 16.31785 -148.397464)
			(xy 16.263007 -148.387334) (xy 16.210223 -148.369327) (xy 16.160623 -148.343826) (xy 16.115265 -148.311375)
			(xy 16.075116 -148.272666) (xy 16.04103 -148.228523) (xy 16.013734 -148.179888) (xy 15.993811 -148.127797)
			(xy 15.981685 -148.07336) (xy 15.977614 -148.017738) (xy 4.421886 -148.017738) (xy 4.421886 -150.19585)
			(xy 11.150588 -150.19585) (xy 11.150588 -150.14135) (xy 11.158345 -150.087403) (xy 11.173699 -150.03511)
			(xy 11.19634 -149.985534) (xy 11.225805 -149.939685) (xy 11.261496 -149.898496) (xy 11.302685 -149.862805)
			(xy 11.348534 -149.83334) (xy 11.39811 -149.810699) (xy 11.450403 -149.795345) (xy 11.50435 -149.787588)
			(xy 11.5316 -149.787102) (xy 11.557914 -149.787569) (xy 11.610043 -149.794804) (xy 11.660685 -149.809123)
			(xy 11.708884 -149.830255) (xy 11.753728 -149.857802) (xy 11.794367 -149.89124) (xy 11.812524 -149.910292)
			(xy 11.820036 -149.917705) (xy 11.839323 -149.926223) (xy 11.849862 -149.926802) (xy 11.924538 -149.926802)
			(xy 11.935085 -149.926252) (xy 11.954381 -149.917732) (xy 11.961876 -149.910292) (xy 11.981696 -149.889504)
			(xy 12.026468 -149.853529) (xy 12.076126 -149.824669) (xy 12.129548 -149.803576) (xy 12.185527 -149.790727)
			(xy 12.2428 -149.786412) (xy 12.300073 -149.790727) (xy 12.356052 -149.803576) (xy 12.409474 -149.824669)
			(xy 12.459132 -149.853529) (xy 12.503904 -149.889504) (xy 12.523724 -149.910292) (xy 12.531236 -149.917705)
			(xy 12.550523 -149.926223) (xy 12.561062 -149.926802) (xy 12.635738 -149.926802) (xy 12.646285 -149.926252)
			(xy 12.665581 -149.917732) (xy 12.673076 -149.910292) (xy 12.691249 -149.891254) (xy 12.731875 -149.857795)
			(xy 12.776712 -149.830234) (xy 12.824909 -149.809093) (xy 12.875553 -149.794772) (xy 12.927685 -149.787543)
			(xy 12.954 -149.787102) (xy 12.981252 -149.787568) (xy 13.035201 -149.795325) (xy 13.087497 -149.81068)
			(xy 13.137076 -149.833322) (xy 13.182927 -149.862789) (xy 13.224119 -149.898481) (xy 13.259811 -149.939673)
			(xy 13.289278 -149.985524) (xy 13.31192 -150.035103) (xy 13.320244 -150.063454) (xy 15.838168 -150.063454)
			(xy 15.842239 -150.007832) (xy 15.854365 -149.953395) (xy 15.874288 -149.901304) (xy 15.901584 -149.852669)
			(xy 15.93567 -149.808526) (xy 15.975819 -149.769817) (xy 16.021177 -149.737366) (xy 16.070777 -149.711865)
			(xy 16.123561 -149.693858) (xy 16.178404 -149.683728) (xy 16.234138 -149.681691) (xy 16.289575 -149.687791)
			(xy 16.343532 -149.701897) (xy 16.394861 -149.723709) (xy 16.442467 -149.752763) (xy 16.485335 -149.788438)
			(xy 16.522552 -149.829975) (xy 16.553325 -149.876488) (xy 16.576997 -149.926985) (xy 16.593065 -149.980392)
			(xy 16.601185 -150.035568) (xy 16.601694 -150.063454) (xy 16.601185 -150.09134) (xy 16.593065 -150.146516)
			(xy 16.576997 -150.199923) (xy 16.553325 -150.25042) (xy 16.522552 -150.296933) (xy 16.485335 -150.33847)
			(xy 16.442467 -150.374145) (xy 16.394861 -150.403199) (xy 16.343532 -150.425011) (xy 16.289575 -150.439117)
			(xy 16.234138 -150.445217) (xy 16.178404 -150.44318) (xy 16.123561 -150.43305) (xy 16.070777 -150.415043)
			(xy 16.021177 -150.389542) (xy 15.975819 -150.357091) (xy 15.93567 -150.318382) (xy 15.901584 -150.274239)
			(xy 15.874288 -150.225604) (xy 15.854365 -150.173513) (xy 15.842239 -150.119076) (xy 15.838168 -150.063454)
			(xy 13.320244 -150.063454) (xy 13.327275 -150.087399) (xy 13.335032 -150.141348) (xy 13.335032 -150.195852)
			(xy 13.327275 -150.249801) (xy 13.31192 -150.302097) (xy 13.289278 -150.351676) (xy 13.259811 -150.397527)
			(xy 13.224119 -150.438719) (xy 13.182927 -150.474411) (xy 13.137076 -150.503878) (xy 13.087497 -150.52652)
			(xy 13.035201 -150.541875) (xy 12.981252 -150.549632) (xy 12.954 -150.550118) (xy 12.927686 -150.549645)
			(xy 12.875558 -150.54241) (xy 12.824916 -150.528092) (xy 12.776717 -150.506961) (xy 12.731873 -150.479416)
			(xy 12.691233 -150.445979) (xy 12.673076 -150.426928) (xy 12.665562 -150.419518) (xy 12.646276 -150.410997)
			(xy 12.635738 -150.410418) (xy 12.561062 -150.410418) (xy 12.550514 -150.410962) (xy 12.531218 -150.419486)
			(xy 12.523724 -150.426928) (xy 12.503904 -150.447716) (xy 12.459132 -150.483691) (xy 12.409474 -150.512551)
			(xy 12.356052 -150.533644) (xy 12.300073 -150.546493) (xy 12.2428 -150.550808) (xy 12.185527 -150.546493)
			(xy 12.129548 -150.533644) (xy 12.076126 -150.512551) (xy 12.026468 -150.483691) (xy 11.981696 -150.447716)
			(xy 11.961876 -150.426928) (xy 11.954362 -150.419518) (xy 11.935076 -150.410997) (xy 11.924538 -150.410418)
			(xy 11.849862 -150.410418) (xy 11.839314 -150.410962) (xy 11.820018 -150.419486) (xy 11.812524 -150.426928)
			(xy 11.794355 -150.44597) (xy 11.753728 -150.479428) (xy 11.70889 -150.506988) (xy 11.660692 -150.528128)
			(xy 11.610047 -150.542449) (xy 11.557915 -150.549677) (xy 11.5316 -150.550118) (xy 11.50435 -150.549612)
			(xy 11.450403 -150.541855) (xy 11.39811 -150.526501) (xy 11.348534 -150.50386) (xy 11.302685 -150.474395)
			(xy 11.261496 -150.438704) (xy 11.225805 -150.397515) (xy 11.19634 -150.351666) (xy 11.173699 -150.30209)
			(xy 11.158345 -150.249797) (xy 11.150588 -150.19585) (xy 4.421886 -150.19585) (xy 4.421886 -151.67102)
			(xy 15.793718 -151.67102) (xy 15.797789 -151.615398) (xy 15.809915 -151.560961) (xy 15.829838 -151.50887)
			(xy 15.857134 -151.460235) (xy 15.89122 -151.416092) (xy 15.931369 -151.377383) (xy 15.976727 -151.344932)
			(xy 16.026327 -151.319431) (xy 16.079111 -151.301424) (xy 16.133954 -151.291294) (xy 16.189688 -151.289257)
			(xy 16.245125 -151.295357) (xy 16.299082 -151.309463) (xy 16.350411 -151.331275) (xy 16.398017 -151.360329)
			(xy 16.440885 -151.396004) (xy 16.478102 -151.437541) (xy 16.508875 -151.484054) (xy 16.532547 -151.534551)
			(xy 16.548615 -151.587958) (xy 16.556735 -151.643134) (xy 16.557244 -151.67102) (xy 16.556771 -151.696928)
			(xy 16.809718 -151.696928) (xy 16.813789 -151.641306) (xy 16.825915 -151.586869) (xy 16.845838 -151.534778)
			(xy 16.873134 -151.486143) (xy 16.90722 -151.442) (xy 16.947369 -151.403291) (xy 16.992727 -151.37084)
			(xy 17.042327 -151.345339) (xy 17.095111 -151.327332) (xy 17.149954 -151.317202) (xy 17.205688 -151.315165)
			(xy 17.261125 -151.321265) (xy 17.315082 -151.335371) (xy 17.366411 -151.357183) (xy 17.414017 -151.386237)
			(xy 17.438493 -151.406606) (xy 18.036792 -151.406606) (xy 18.040863 -151.350984) (xy 18.052989 -151.296547)
			(xy 18.072912 -151.244456) (xy 18.100208 -151.195821) (xy 18.134294 -151.151678) (xy 18.174443 -151.112969)
			(xy 18.219801 -151.080518) (xy 18.269401 -151.055017) (xy 18.322185 -151.03701) (xy 18.377028 -151.02688)
			(xy 18.432762 -151.024843) (xy 18.488199 -151.030943) (xy 18.542156 -151.045049) (xy 18.593485 -151.066861)
			(xy 18.641091 -151.095915) (xy 18.683959 -151.13159) (xy 18.721176 -151.173127) (xy 18.751949 -151.21964)
			(xy 18.775621 -151.270137) (xy 18.791689 -151.323544) (xy 18.799809 -151.37872) (xy 18.800318 -151.406606)
			(xy 18.799809 -151.434492) (xy 18.791689 -151.489668) (xy 18.775621 -151.543075) (xy 18.757079 -151.582628)
			(xy 19.362418 -151.582628) (xy 19.366489 -151.527006) (xy 19.378615 -151.472569) (xy 19.398538 -151.420478)
			(xy 19.425834 -151.371843) (xy 19.45992 -151.3277) (xy 19.500069 -151.288991) (xy 19.545427 -151.25654)
			(xy 19.595027 -151.231039) (xy 19.647811 -151.213032) (xy 19.702654 -151.202902) (xy 19.758388 -151.200865)
			(xy 19.813825 -151.206965) (xy 19.867782 -151.221071) (xy 19.919111 -151.242883) (xy 19.966717 -151.271937)
			(xy 20.009585 -151.307612) (xy 20.046802 -151.349149) (xy 20.077575 -151.395662) (xy 20.101247 -151.446159)
			(xy 20.117315 -151.499566) (xy 20.125435 -151.554742) (xy 20.125698 -151.569166) (xy 20.873718 -151.569166)
			(xy 20.877789 -151.513544) (xy 20.889915 -151.459107) (xy 20.909838 -151.407016) (xy 20.937134 -151.358381)
			(xy 20.97122 -151.314238) (xy 21.011369 -151.275529) (xy 21.056727 -151.243078) (xy 21.106327 -151.217577)
			(xy 21.159111 -151.19957) (xy 21.213954 -151.18944) (xy 21.269688 -151.187403) (xy 21.325125 -151.193503)
			(xy 21.379082 -151.207609) (xy 21.430411 -151.229421) (xy 21.478017 -151.258475) (xy 21.520885 -151.29415)
			(xy 21.558102 -151.335687) (xy 21.588875 -151.3822) (xy 21.612547 -151.432697) (xy 21.628615 -151.486104)
			(xy 21.636735 -151.54128) (xy 21.637244 -151.569166) (xy 21.636735 -151.597052) (xy 21.628615 -151.652228)
			(xy 21.612547 -151.705635) (xy 21.588875 -151.756132) (xy 21.558102 -151.802645) (xy 21.520885 -151.844182)
			(xy 21.478017 -151.879857) (xy 21.430411 -151.908911) (xy 21.379082 -151.930723) (xy 21.325125 -151.944829)
			(xy 21.269688 -151.950929) (xy 21.213954 -151.948892) (xy 21.159111 -151.938762) (xy 21.106327 -151.920755)
			(xy 21.056727 -151.895254) (xy 21.011369 -151.862803) (xy 20.97122 -151.824094) (xy 20.937134 -151.779951)
			(xy 20.909838 -151.731316) (xy 20.889915 -151.679225) (xy 20.877789 -151.624788) (xy 20.873718 -151.569166)
			(xy 20.125698 -151.569166) (xy 20.125944 -151.582628) (xy 20.125435 -151.610514) (xy 20.117315 -151.66569)
			(xy 20.101247 -151.719097) (xy 20.077575 -151.769594) (xy 20.046802 -151.816107) (xy 20.009585 -151.857644)
			(xy 19.966717 -151.893319) (xy 19.919111 -151.922373) (xy 19.867782 -151.944185) (xy 19.813825 -151.958291)
			(xy 19.758388 -151.964391) (xy 19.702654 -151.962354) (xy 19.647811 -151.952224) (xy 19.595027 -151.934217)
			(xy 19.545427 -151.908716) (xy 19.500069 -151.876265) (xy 19.45992 -151.837556) (xy 19.425834 -151.793413)
			(xy 19.398538 -151.744778) (xy 19.378615 -151.692687) (xy 19.366489 -151.63825) (xy 19.362418 -151.582628)
			(xy 18.757079 -151.582628) (xy 18.751949 -151.593572) (xy 18.721176 -151.640085) (xy 18.683959 -151.681622)
			(xy 18.641091 -151.717297) (xy 18.593485 -151.746351) (xy 18.542156 -151.768163) (xy 18.488199 -151.782269)
			(xy 18.432762 -151.788369) (xy 18.377028 -151.786332) (xy 18.322185 -151.776202) (xy 18.269401 -151.758195)
			(xy 18.219801 -151.732694) (xy 18.174443 -151.700243) (xy 18.134294 -151.661534) (xy 18.100208 -151.617391)
			(xy 18.072912 -151.568756) (xy 18.052989 -151.516665) (xy 18.040863 -151.462228) (xy 18.036792 -151.406606)
			(xy 17.438493 -151.406606) (xy 17.456885 -151.421912) (xy 17.494102 -151.463449) (xy 17.524875 -151.509962)
			(xy 17.548547 -151.560459) (xy 17.564615 -151.613866) (xy 17.572735 -151.669042) (xy 17.573244 -151.696928)
			(xy 17.572735 -151.724814) (xy 17.564615 -151.77999) (xy 17.548547 -151.833397) (xy 17.524875 -151.883894)
			(xy 17.494102 -151.930407) (xy 17.456885 -151.971944) (xy 17.414017 -152.007619) (xy 17.366411 -152.036673)
			(xy 17.315082 -152.058485) (xy 17.261125 -152.072591) (xy 17.205688 -152.078691) (xy 17.149954 -152.076654)
			(xy 17.095111 -152.066524) (xy 17.042327 -152.048517) (xy 16.992727 -152.023016) (xy 16.947369 -151.990565)
			(xy 16.90722 -151.951856) (xy 16.873134 -151.907713) (xy 16.845838 -151.859078) (xy 16.825915 -151.806987)
			(xy 16.813789 -151.75255) (xy 16.809718 -151.696928) (xy 16.556771 -151.696928) (xy 16.556735 -151.698906)
			(xy 16.548615 -151.754082) (xy 16.532547 -151.807489) (xy 16.508875 -151.857986) (xy 16.478102 -151.904499)
			(xy 16.440885 -151.946036) (xy 16.398017 -151.981711) (xy 16.350411 -152.010765) (xy 16.299082 -152.032577)
			(xy 16.245125 -152.046683) (xy 16.189688 -152.052783) (xy 16.133954 -152.050746) (xy 16.079111 -152.040616)
			(xy 16.026327 -152.022609) (xy 15.976727 -151.997108) (xy 15.931369 -151.964657) (xy 15.89122 -151.925948)
			(xy 15.857134 -151.881805) (xy 15.829838 -151.83317) (xy 15.809915 -151.781079) (xy 15.797789 -151.726642)
			(xy 15.793718 -151.67102) (xy 4.421886 -151.67102) (xy 4.421886 -153.782522) (xy 14.777718 -153.782522)
			(xy 14.781789 -153.7269) (xy 14.793915 -153.672463) (xy 14.813838 -153.620372) (xy 14.841134 -153.571737)
			(xy 14.87522 -153.527594) (xy 14.915369 -153.488885) (xy 14.960727 -153.456434) (xy 15.010327 -153.430933)
			(xy 15.063111 -153.412926) (xy 15.117954 -153.402796) (xy 15.173688 -153.400759) (xy 15.229125 -153.406859)
			(xy 15.283082 -153.420965) (xy 15.334411 -153.442777) (xy 15.382017 -153.471831) (xy 15.424885 -153.507506)
			(xy 15.462102 -153.549043) (xy 15.492875 -153.595556) (xy 15.516547 -153.646053) (xy 15.532615 -153.69946)
			(xy 15.540735 -153.754636) (xy 15.541244 -153.782522) (xy 15.793718 -153.782522) (xy 15.797789 -153.7269)
			(xy 15.809915 -153.672463) (xy 15.829838 -153.620372) (xy 15.857134 -153.571737) (xy 15.89122 -153.527594)
			(xy 15.931369 -153.488885) (xy 15.976727 -153.456434) (xy 16.026327 -153.430933) (xy 16.079111 -153.412926)
			(xy 16.133954 -153.402796) (xy 16.189688 -153.400759) (xy 16.245125 -153.406859) (xy 16.299082 -153.420965)
			(xy 16.350411 -153.442777) (xy 16.398017 -153.471831) (xy 16.440885 -153.507506) (xy 16.478102 -153.549043)
			(xy 16.508875 -153.595556) (xy 16.532547 -153.646053) (xy 16.548615 -153.69946) (xy 16.556735 -153.754636)
			(xy 16.557244 -153.782522) (xy 16.556735 -153.810408) (xy 16.553587 -153.831798) (xy 16.809718 -153.831798)
			(xy 16.813789 -153.776176) (xy 16.825915 -153.721739) (xy 16.845838 -153.669648) (xy 16.873134 -153.621013)
			(xy 16.90722 -153.57687) (xy 16.947369 -153.538161) (xy 16.992727 -153.50571) (xy 17.042327 -153.480209)
			(xy 17.095111 -153.462202) (xy 17.149954 -153.452072) (xy 17.205688 -153.450035) (xy 17.261125 -153.456135)
			(xy 17.315082 -153.470241) (xy 17.366411 -153.492053) (xy 17.414017 -153.521107) (xy 17.456885 -153.556782)
			(xy 17.494102 -153.598319) (xy 17.524875 -153.644832) (xy 17.548547 -153.695329) (xy 17.564615 -153.748736)
			(xy 17.569587 -153.782522) (xy 19.857718 -153.782522) (xy 19.861789 -153.7269) (xy 19.873915 -153.672463)
			(xy 19.893838 -153.620372) (xy 19.921134 -153.571737) (xy 19.95522 -153.527594) (xy 19.995369 -153.488885)
			(xy 20.040727 -153.456434) (xy 20.090327 -153.430933) (xy 20.143111 -153.412926) (xy 20.197954 -153.402796)
			(xy 20.253688 -153.400759) (xy 20.309125 -153.406859) (xy 20.363082 -153.420965) (xy 20.414411 -153.442777)
			(xy 20.462017 -153.471831) (xy 20.504885 -153.507506) (xy 20.542102 -153.549043) (xy 20.572875 -153.595556)
			(xy 20.596547 -153.646053) (xy 20.612615 -153.69946) (xy 20.620735 -153.754636) (xy 20.621244 -153.782522)
			(xy 20.620735 -153.810408) (xy 20.612615 -153.865584) (xy 20.596547 -153.918991) (xy 20.572875 -153.969488)
			(xy 20.542102 -154.016001) (xy 20.504885 -154.057538) (xy 20.462017 -154.093213) (xy 20.414411 -154.122267)
			(xy 20.363082 -154.144079) (xy 20.309125 -154.158185) (xy 20.253688 -154.164285) (xy 20.197954 -154.162248)
			(xy 20.143111 -154.152118) (xy 20.090327 -154.134111) (xy 20.040727 -154.10861) (xy 19.995369 -154.076159)
			(xy 19.95522 -154.03745) (xy 19.921134 -153.993307) (xy 19.893838 -153.944672) (xy 19.873915 -153.892581)
			(xy 19.861789 -153.838144) (xy 19.857718 -153.782522) (xy 17.569587 -153.782522) (xy 17.572735 -153.803912)
			(xy 17.573244 -153.831798) (xy 17.572735 -153.859684) (xy 17.564615 -153.91486) (xy 17.548547 -153.968267)
			(xy 17.524875 -154.018764) (xy 17.494102 -154.065277) (xy 17.456885 -154.106814) (xy 17.414017 -154.142489)
			(xy 17.366411 -154.171543) (xy 17.315082 -154.193355) (xy 17.261125 -154.207461) (xy 17.205688 -154.213561)
			(xy 17.149954 -154.211524) (xy 17.095111 -154.201394) (xy 17.042327 -154.183387) (xy 16.992727 -154.157886)
			(xy 16.947369 -154.125435) (xy 16.90722 -154.086726) (xy 16.873134 -154.042583) (xy 16.845838 -153.993948)
			(xy 16.825915 -153.941857) (xy 16.813789 -153.88742) (xy 16.809718 -153.831798) (xy 16.553587 -153.831798)
			(xy 16.548615 -153.865584) (xy 16.532547 -153.918991) (xy 16.508875 -153.969488) (xy 16.478102 -154.016001)
			(xy 16.440885 -154.057538) (xy 16.398017 -154.093213) (xy 16.350411 -154.122267) (xy 16.299082 -154.144079)
			(xy 16.245125 -154.158185) (xy 16.189688 -154.164285) (xy 16.133954 -154.162248) (xy 16.079111 -154.152118)
			(xy 16.026327 -154.134111) (xy 15.976727 -154.10861) (xy 15.931369 -154.076159) (xy 15.89122 -154.03745)
			(xy 15.857134 -153.993307) (xy 15.829838 -153.944672) (xy 15.809915 -153.892581) (xy 15.797789 -153.838144)
			(xy 15.793718 -153.782522) (xy 15.541244 -153.782522) (xy 15.540735 -153.810408) (xy 15.532615 -153.865584)
			(xy 15.516547 -153.918991) (xy 15.492875 -153.969488) (xy 15.462102 -154.016001) (xy 15.424885 -154.057538)
			(xy 15.382017 -154.093213) (xy 15.334411 -154.122267) (xy 15.283082 -154.144079) (xy 15.229125 -154.158185)
			(xy 15.173688 -154.164285) (xy 15.117954 -154.162248) (xy 15.063111 -154.152118) (xy 15.010327 -154.134111)
			(xy 14.960727 -154.10861) (xy 14.915369 -154.076159) (xy 14.87522 -154.03745) (xy 14.841134 -153.993307)
			(xy 14.813838 -153.944672) (xy 14.793915 -153.892581) (xy 14.781789 -153.838144) (xy 14.777718 -153.782522)
			(xy 4.421886 -153.782522) (xy 4.421886 -155.212034) (xy 7.269224 -155.212034) (xy 7.273295 -155.156412)
			(xy 7.285421 -155.101975) (xy 7.305344 -155.049884) (xy 7.33264 -155.001249) (xy 7.366726 -154.957106)
			(xy 7.406875 -154.918397) (xy 7.452233 -154.885946) (xy 7.501833 -154.860445) (xy 7.554617 -154.842438)
			(xy 7.60946 -154.832308) (xy 7.665194 -154.830271) (xy 7.720631 -154.836371) (xy 7.774588 -154.850477)
			(xy 7.825917 -154.872289) (xy 7.873523 -154.901343) (xy 7.916391 -154.937018) (xy 7.953608 -154.978555)
			(xy 7.984381 -155.025068) (xy 8.008053 -155.075565) (xy 8.009144 -155.079192) (xy 9.86993 -155.079192)
			(xy 9.874001 -155.02357) (xy 9.886127 -154.969133) (xy 9.90605 -154.917042) (xy 9.933346 -154.868407)
			(xy 9.967432 -154.824264) (xy 10.007581 -154.785555) (xy 10.052939 -154.753104) (xy 10.102539 -154.727603)
			(xy 10.155323 -154.709596) (xy 10.210166 -154.699466) (xy 10.2659 -154.697429) (xy 10.321337 -154.703529)
			(xy 10.375294 -154.717635) (xy 10.426623 -154.739447) (xy 10.474229 -154.768501) (xy 10.517097 -154.804176)
			(xy 10.554314 -154.845713) (xy 10.585087 -154.892226) (xy 10.608759 -154.942723) (xy 10.624827 -154.99613)
			(xy 10.632947 -155.051306) (xy 10.633456 -155.079192) (xy 10.633391 -155.082748) (xy 11.19378 -155.082748)
			(xy 11.194219 -155.056433) (xy 11.201461 -155.004304) (xy 11.215786 -154.953661) (xy 11.236924 -154.905462)
			(xy 11.264474 -154.860619) (xy 11.297917 -154.81998) (xy 11.31697 -154.801824) (xy 11.324359 -154.794291)
			(xy 11.332892 -154.77502) (xy 11.33348 -154.764486) (xy 11.33348 -154.68981) (xy 11.332965 -154.679259)
			(xy 11.32442 -154.659963) (xy 11.31697 -154.652472) (xy 11.297902 -154.634329) (xy 11.264447 -154.593696)
			(xy 11.236891 -154.548853) (xy 11.215755 -154.50065) (xy 11.20144 -154.45) (xy 11.194217 -154.397865)
			(xy 11.19378 -154.371548) (xy 11.1943 -154.344297) (xy 11.20205 -154.290349) (xy 11.217399 -154.238053)
			(xy 11.240035 -154.188473) (xy 11.269497 -154.142621) (xy 11.305185 -154.101428) (xy 11.346372 -154.065733)
			(xy 11.392221 -154.036264) (xy 11.441796 -154.01362) (xy 11.49409 -153.998263) (xy 11.548037 -153.990504)
			(xy 11.575288 -153.99004) (xy 11.601602 -153.990503) (xy 11.653731 -153.997737) (xy 11.704375 -154.012056)
			(xy 11.752574 -154.033189) (xy 11.797417 -154.060737) (xy 11.838056 -154.094177) (xy 11.856212 -154.11323)
			(xy 11.863737 -154.120629) (xy 11.883014 -154.129157) (xy 11.89355 -154.12974) (xy 11.968226 -154.12974)
			(xy 11.978771 -154.129173) (xy 11.998066 -154.120663) (xy 12.005564 -154.11323) (xy 12.025384 -154.092442)
			(xy 12.070156 -154.056467) (xy 12.119814 -154.027607) (xy 12.173236 -154.006514) (xy 12.229215 -153.993665)
			(xy 12.286488 -153.98935) (xy 12.343761 -153.993665) (xy 12.39974 -154.006514) (xy 12.453162 -154.027607)
			(xy 12.50282 -154.056467) (xy 12.547592 -154.092442) (xy 12.567412 -154.11323) (xy 12.574937 -154.120629)
			(xy 12.594214 -154.129157) (xy 12.60475 -154.12974) (xy 12.679426 -154.12974) (xy 12.689971 -154.129173)
			(xy 12.709266 -154.120663) (xy 12.716764 -154.11323) (xy 12.736584 -154.092442) (xy 12.781356 -154.056467)
			(xy 12.831014 -154.027607) (xy 12.884436 -154.006514) (xy 12.940415 -153.993665) (xy 12.997688 -153.98935)
			(xy 13.054961 -153.993665) (xy 13.11094 -154.006514) (xy 13.164362 -154.027607) (xy 13.21402 -154.056467)
			(xy 13.258792 -154.092442) (xy 13.278612 -154.11323) (xy 13.286137 -154.120629) (xy 13.305414 -154.129157)
			(xy 13.31595 -154.12974) (xy 13.390626 -154.12974) (xy 13.401171 -154.129173) (xy 13.420466 -154.120663)
			(xy 13.427964 -154.11323) (xy 13.446101 -154.094156) (xy 13.486734 -154.060699) (xy 13.531578 -154.033142)
			(xy 13.579783 -154.012007) (xy 13.630434 -153.997694) (xy 13.682571 -153.990475) (xy 13.708888 -153.99004)
			(xy 13.736143 -153.990467) (xy 13.790097 -153.998223) (xy 13.842399 -154.01358) (xy 13.891982 -154.036225)
			(xy 13.937838 -154.065696) (xy 13.979032 -154.101394) (xy 14.014726 -154.142591) (xy 14.044193 -154.188449)
			(xy 14.066832 -154.238035) (xy 14.082184 -154.290338) (xy 14.089936 -154.344293) (xy 14.090396 -154.371548)
			(xy 14.089962 -154.397863) (xy 14.08272 -154.449993) (xy 14.068395 -154.500637) (xy 14.047256 -154.548835)
			(xy 14.019704 -154.593678) (xy 13.98626 -154.634316) (xy 13.967206 -154.652472) (xy 13.959816 -154.660003)
			(xy 13.951285 -154.679276) (xy 13.950696 -154.68981) (xy 13.950696 -154.764486) (xy 13.951221 -154.775036)
			(xy 13.959759 -154.794331) (xy 13.967206 -154.801824) (xy 13.986267 -154.819974) (xy 14.019724 -154.860605)
			(xy 14.047282 -154.905446) (xy 14.068419 -154.953648) (xy 14.082735 -155.004297) (xy 14.089958 -155.056432)
			(xy 14.090396 -155.082748) (xy 14.089967 -155.110001) (xy 14.082203 -155.163951) (xy 14.066842 -155.216248)
			(xy 14.044194 -155.265826) (xy 14.014722 -155.311677) (xy 13.979024 -155.352867) (xy 13.937829 -155.388558)
			(xy 13.891973 -155.418023) (xy 13.842392 -155.440663) (xy 13.790093 -155.456016) (xy 13.736141 -155.463771)
			(xy 13.708888 -155.464256) (xy 13.682573 -155.463811) (xy 13.630443 -155.456573) (xy 13.579799 -155.442251)
			(xy 13.5316 -155.421114) (xy 13.486757 -155.393564) (xy 13.446119 -155.36012) (xy 13.427964 -155.341066)
			(xy 13.420449 -155.333656) (xy 13.401164 -155.325134) (xy 13.390626 -155.324556) (xy 13.31595 -155.324556)
			(xy 13.305404 -155.325112) (xy 13.286109 -155.33363) (xy 13.278612 -155.341066) (xy 13.258792 -155.361854)
			(xy 13.21402 -155.397829) (xy 13.164362 -155.426689) (xy 13.11094 -155.447782) (xy 13.054961 -155.460631)
			(xy 12.997688 -155.464946) (xy 12.940415 -155.460631) (xy 12.884436 -155.447782) (xy 12.831014 -155.426689)
			(xy 12.781356 -155.397829) (xy 12.736584 -155.361854) (xy 12.716764 -155.341066) (xy 12.709249 -155.333656)
			(xy 12.689964 -155.325134) (xy 12.679426 -155.324556) (xy 12.60475 -155.324556) (xy 12.594204 -155.325112)
			(xy 12.574909 -155.33363) (xy 12.567412 -155.341066) (xy 12.547592 -155.361854) (xy 12.50282 -155.397829)
			(xy 12.453162 -155.426689) (xy 12.39974 -155.447782) (xy 12.343761 -155.460631) (xy 12.286488 -155.464946)
			(xy 12.229215 -155.460631) (xy 12.173236 -155.447782) (xy 12.119814 -155.426689) (xy 12.070156 -155.397829)
			(xy 12.025384 -155.361854) (xy 12.005564 -155.341066) (xy 11.998049 -155.333656) (xy 11.978764 -155.325134)
			(xy 11.968226 -155.324556) (xy 11.89355 -155.324556) (xy 11.883004 -155.325112) (xy 11.863709 -155.33363)
			(xy 11.856212 -155.341066) (xy 11.838057 -155.360121) (xy 11.797425 -155.393576) (xy 11.752585 -155.421133)
			(xy 11.704384 -155.442271) (xy 11.653737 -155.456589) (xy 11.601604 -155.463816) (xy 11.575288 -155.464256)
			(xy 11.548037 -155.463774) (xy 11.494089 -155.456017) (xy 11.441794 -155.440662) (xy 11.392216 -155.41802)
			(xy 11.346366 -155.388554) (xy 11.305176 -155.352862) (xy 11.269484 -155.311671) (xy 11.240018 -155.26582)
			(xy 11.217377 -155.216243) (xy 11.202022 -155.163947) (xy 11.194266 -155.109999) (xy 11.19378 -155.082748)
			(xy 10.633391 -155.082748) (xy 10.632947 -155.107078) (xy 10.624827 -155.162254) (xy 10.608759 -155.215661)
			(xy 10.585087 -155.266158) (xy 10.554314 -155.312671) (xy 10.517097 -155.354208) (xy 10.474229 -155.389883)
			(xy 10.426623 -155.418937) (xy 10.375294 -155.440749) (xy 10.321337 -155.454855) (xy 10.2659 -155.460955)
			(xy 10.210166 -155.458918) (xy 10.155323 -155.448788) (xy 10.102539 -155.430781) (xy 10.052939 -155.40528)
			(xy 10.007581 -155.372829) (xy 9.967432 -155.33412) (xy 9.933346 -155.289977) (xy 9.90605 -155.241342)
			(xy 9.886127 -155.189251) (xy 9.874001 -155.134814) (xy 9.86993 -155.079192) (xy 8.009144 -155.079192)
			(xy 8.024121 -155.128972) (xy 8.032241 -155.184148) (xy 8.03275 -155.212034) (xy 8.032241 -155.23992)
			(xy 8.024121 -155.295096) (xy 8.008053 -155.348503) (xy 7.984381 -155.399) (xy 7.953608 -155.445513)
			(xy 7.916391 -155.48705) (xy 7.873523 -155.522725) (xy 7.825917 -155.551779) (xy 7.774588 -155.573591)
			(xy 7.720631 -155.587697) (xy 7.665194 -155.593797) (xy 7.60946 -155.59176) (xy 7.554617 -155.58163)
			(xy 7.501833 -155.563623) (xy 7.452233 -155.538122) (xy 7.406875 -155.505671) (xy 7.366726 -155.466962)
			(xy 7.33264 -155.422819) (xy 7.305344 -155.374184) (xy 7.285421 -155.322093) (xy 7.273295 -155.267656)
			(xy 7.269224 -155.212034) (xy 4.421886 -155.212034) (xy 4.421886 -156.69387) (xy 8.887458 -156.69387)
			(xy 8.891529 -156.638248) (xy 8.903655 -156.583811) (xy 8.923578 -156.53172) (xy 8.950874 -156.483085)
			(xy 8.98496 -156.438942) (xy 9.025109 -156.400233) (xy 9.070467 -156.367782) (xy 9.120067 -156.342281)
			(xy 9.172851 -156.324274) (xy 9.227694 -156.314144) (xy 9.283428 -156.312107) (xy 9.338865 -156.318207)
			(xy 9.392822 -156.332313) (xy 9.444151 -156.354125) (xy 9.491757 -156.383179) (xy 9.534625 -156.418854)
			(xy 9.571842 -156.460391) (xy 9.602615 -156.506904) (xy 9.626287 -156.557401) (xy 9.642355 -156.610808)
			(xy 9.650475 -156.665984) (xy 9.650984 -156.69387) (xy 9.650475 -156.721756) (xy 9.642355 -156.776932)
			(xy 9.626287 -156.830339) (xy 9.602615 -156.880836) (xy 9.571842 -156.927349) (xy 9.534625 -156.968886)
			(xy 9.491757 -157.004561) (xy 9.444151 -157.033615) (xy 9.392822 -157.055427) (xy 9.338865 -157.069533)
			(xy 9.283428 -157.075633) (xy 9.227694 -157.073596) (xy 9.172851 -157.063466) (xy 9.120067 -157.045459)
			(xy 9.070467 -157.019958) (xy 9.025109 -156.987507) (xy 8.98496 -156.948798) (xy 8.950874 -156.904655)
			(xy 8.923578 -156.85602) (xy 8.903655 -156.803929) (xy 8.891529 -156.749492) (xy 8.887458 -156.69387)
			(xy 4.421886 -156.69387) (xy 4.421886 -157.812994) (xy 6.650226 -157.812994) (xy 6.654297 -157.757372)
			(xy 6.666423 -157.702935) (xy 6.686346 -157.650844) (xy 6.713642 -157.602209) (xy 6.747728 -157.558066)
			(xy 6.787877 -157.519357) (xy 6.833235 -157.486906) (xy 6.882835 -157.461405) (xy 6.935619 -157.443398)
			(xy 6.990462 -157.433268) (xy 7.046196 -157.431231) (xy 7.101633 -157.437331) (xy 7.15559 -157.451437)
			(xy 7.206919 -157.473249) (xy 7.254525 -157.502303) (xy 7.297393 -157.537978) (xy 7.33461 -157.579515)
			(xy 7.365383 -157.626028) (xy 7.375633 -157.647894) (xy 11.013948 -157.647894) (xy 11.014459 -157.62125)
			(xy 11.022984 -157.568649) (xy 11.039844 -157.518099) (xy 11.064602 -157.470913) (xy 11.096615 -157.428313)
			(xy 11.135053 -157.391407) (xy 11.156696 -157.37586) (xy 11.167989 -157.367504) (xy 11.185848 -157.34583)
			(xy 11.197132 -157.320114) (xy 11.20099 -157.292297) (xy 11.19713 -157.26448) (xy 11.185844 -157.238764)
			(xy 11.167984 -157.217092) (xy 11.156696 -157.208728) (xy 11.135107 -157.193114) (xy 11.096689 -157.156206)
			(xy 11.064685 -157.113615) (xy 11.039924 -157.066445) (xy 11.023047 -157.015914) (xy 11.014491 -156.963331)
			(xy 11.013948 -156.936694) (xy 11.014458 -156.910707) (xy 11.022588 -156.859372) (xy 11.038649 -156.809942)
			(xy 11.062245 -156.763632) (xy 11.092795 -156.721584) (xy 11.129546 -156.684833) (xy 11.171594 -156.654283)
			(xy 11.217904 -156.630687) (xy 11.267334 -156.614626) (xy 11.318669 -156.606496) (xy 11.370643 -156.606496)
			(xy 11.421978 -156.614626) (xy 11.471408 -156.630687) (xy 11.517718 -156.654283) (xy 11.559766 -156.684833)
			(xy 11.596517 -156.721584) (xy 11.627067 -156.763632) (xy 11.650663 -156.809942) (xy 11.666724 -156.859372)
			(xy 11.674854 -156.910707) (xy 11.675364 -156.936694) (xy 11.674839 -156.963337) (xy 11.666316 -157.015937)
			(xy 11.649459 -157.066487) (xy 11.624703 -157.113673) (xy 11.592693 -157.156273) (xy 11.554258 -157.193181)
			(xy 11.532616 -157.208728) (xy 11.521334 -157.217098) (xy 11.503473 -157.238768) (xy 11.492187 -157.264482)
			(xy 11.488327 -157.292297) (xy 11.492185 -157.320112) (xy 11.50347 -157.345826) (xy 11.521328 -157.367497)
			(xy 11.532616 -157.37586) (xy 11.554202 -157.391478) (xy 11.59262 -157.428386) (xy 11.624623 -157.470975)
			(xy 11.649384 -157.518145) (xy 11.666262 -157.568675) (xy 11.674821 -157.621257) (xy 11.675364 -157.647894)
			(xy 11.91387 -157.647894) (xy 11.914371 -157.62125) (xy 11.922897 -157.568648) (xy 11.939758 -157.518097)
			(xy 11.964518 -157.47091) (xy 11.996533 -157.428311) (xy 12.034973 -157.391406) (xy 12.056618 -157.37586)
			(xy 12.067909 -157.367503) (xy 12.085764 -157.345828) (xy 12.097046 -157.320112) (xy 12.100903 -157.292297)
			(xy 12.097044 -157.264481) (xy 12.08576 -157.238766) (xy 12.067904 -157.217092) (xy 12.056618 -157.208728)
			(xy 12.035012 -157.193137) (xy 11.996598 -157.156222) (xy 11.964599 -157.113625) (xy 11.939842 -157.066451)
			(xy 11.922968 -157.015917) (xy 11.914412 -156.963332) (xy 11.91387 -156.936694) (xy 11.91438 -156.910707)
			(xy 11.92251 -156.859372) (xy 11.938571 -156.809942) (xy 11.962167 -156.763632) (xy 11.992717 -156.721584)
			(xy 12.029468 -156.684833) (xy 12.071516 -156.654283) (xy 12.117826 -156.630687) (xy 12.167256 -156.614626)
			(xy 12.218591 -156.606496) (xy 12.270565 -156.606496) (xy 12.3219 -156.614626) (xy 12.37133 -156.630687)
			(xy 12.41764 -156.654283) (xy 12.459688 -156.684833) (xy 12.496439 -156.721584) (xy 12.526989 -156.763632)
			(xy 12.550585 -156.809942) (xy 12.566646 -156.859372) (xy 12.574776 -156.910707) (xy 12.575286 -156.936694)
			(xy 12.574752 -156.963337) (xy 12.56623 -157.015936) (xy 12.549373 -157.066485) (xy 12.52462 -157.113671)
			(xy 12.492611 -157.156271) (xy 12.454179 -157.19318) (xy 12.432538 -157.208728) (xy 12.421262 -157.217102)
			(xy 12.403416 -157.238776) (xy 12.392139 -157.264487) (xy 12.388282 -157.292297) (xy 12.392137 -157.320106)
			(xy 12.403412 -157.345818) (xy 12.421257 -157.367493) (xy 12.432538 -157.37586) (xy 12.454129 -157.391471)
			(xy 12.492545 -157.428381) (xy 12.524548 -157.470973) (xy 12.549308 -157.518144) (xy 12.566185 -157.568674)
			(xy 12.574743 -157.621257) (xy 12.575286 -157.647894) (xy 12.813792 -157.647894) (xy 12.814327 -157.621251)
			(xy 12.82285 -157.568653) (xy 12.839707 -157.518105) (xy 12.864461 -157.470918) (xy 12.896468 -157.428318)
			(xy 12.9349 -157.391409) (xy 12.95654 -157.37586) (xy 12.967829 -157.367502) (xy 12.98568 -157.345826)
			(xy 12.996959 -157.320111) (xy 13.000815 -157.292297) (xy 12.996957 -157.264483) (xy 12.985677 -157.238768)
			(xy 12.967824 -157.217094) (xy 12.95654 -157.208728) (xy 12.934939 -157.193131) (xy 12.896524 -157.156217)
			(xy 12.864523 -157.113623) (xy 12.839765 -157.066449) (xy 12.82289 -157.015916) (xy 12.814334 -156.963332)
			(xy 12.813792 -156.936694) (xy 12.814302 -156.910707) (xy 12.822432 -156.859372) (xy 12.838493 -156.809942)
			(xy 12.862089 -156.763632) (xy 12.892639 -156.721584) (xy 12.92939 -156.684833) (xy 12.971438 -156.654283)
			(xy 13.017748 -156.630687) (xy 13.067178 -156.614626) (xy 13.118513 -156.606496) (xy 13.170487 -156.606496)
			(xy 13.221822 -156.614626) (xy 13.271252 -156.630687) (xy 13.317562 -156.654283) (xy 13.35961 -156.684833)
			(xy 13.396361 -156.721584) (xy 13.426911 -156.763632) (xy 13.450507 -156.809942) (xy 13.466568 -156.859372)
			(xy 13.474698 -156.910707) (xy 13.475208 -156.936694) (xy 13.474664 -156.963336) (xy 13.466143 -157.015935)
			(xy 13.449288 -157.066482) (xy 13.424536 -157.113669) (xy 13.39253 -157.156269) (xy 13.3541 -157.193179)
			(xy 13.33246 -157.208728) (xy 13.321182 -157.217101) (xy 13.303332 -157.238773) (xy 13.292052 -157.264485)
			(xy 13.288195 -157.292297) (xy 13.29205 -157.320108) (xy 13.303328 -157.345821) (xy 13.321177 -157.367494)
			(xy 13.33246 -157.37586) (xy 13.354056 -157.391465) (xy 13.392471 -157.428377) (xy 13.424472 -157.47097)
			(xy 13.449231 -157.518142) (xy 13.466107 -157.568673) (xy 13.474665 -157.621257) (xy 13.475208 -157.647894)
			(xy 13.713968 -157.647894) (xy 13.71447 -157.62125) (xy 13.722996 -157.568648) (xy 13.739857 -157.518098)
			(xy 13.764617 -157.470911) (xy 13.796632 -157.428312) (xy 13.835071 -157.391406) (xy 13.856716 -157.37586)
			(xy 13.868008 -157.367503) (xy 13.885863 -157.345828) (xy 13.897145 -157.320112) (xy 13.901002 -157.292297)
			(xy 13.897143 -157.264481) (xy 13.885859 -157.238766) (xy 13.868002 -157.217092) (xy 13.856716 -157.208728)
			(xy 13.83511 -157.193138) (xy 13.796696 -157.156222) (xy 13.764697 -157.113626) (xy 13.73994 -157.066451)
			(xy 13.723066 -157.015917) (xy 13.71451 -156.963332) (xy 13.713968 -156.936694) (xy 13.714478 -156.910707)
			(xy 13.722608 -156.859372) (xy 13.738669 -156.809942) (xy 13.762265 -156.763632) (xy 13.792815 -156.721584)
			(xy 13.829566 -156.684833) (xy 13.871614 -156.654283) (xy 13.917924 -156.630687) (xy 13.967354 -156.614626)
			(xy 14.018689 -156.606496) (xy 14.070663 -156.606496) (xy 14.121998 -156.614626) (xy 14.171428 -156.630687)
			(xy 14.217738 -156.654283) (xy 14.259786 -156.684833) (xy 14.296537 -156.721584) (xy 14.327087 -156.763632)
			(xy 14.350683 -156.809942) (xy 14.366744 -156.859372) (xy 14.374874 -156.910707) (xy 14.375384 -156.936694)
			(xy 14.374851 -156.963337) (xy 14.366328 -157.015936) (xy 14.349472 -157.066485) (xy 14.324718 -157.113671)
			(xy 14.29271 -157.156271) (xy 14.254277 -157.19318) (xy 14.232636 -157.208728) (xy 14.221352 -157.217097)
			(xy 14.203488 -157.238766) (xy 14.192199 -157.26448) (xy 14.188338 -157.292297) (xy 14.192197 -157.320113)
			(xy 14.203484 -157.345828) (xy 14.221347 -157.367498) (xy 14.232636 -157.37586) (xy 14.254226 -157.391472)
			(xy 14.292643 -157.428382) (xy 14.324645 -157.470973) (xy 14.349405 -157.518144) (xy 14.366283 -157.568674)
			(xy 14.374841 -157.621257) (xy 14.375343 -157.645862) (xy 15.329408 -157.645862) (xy 15.329848 -157.619547)
			(xy 15.337088 -157.567417) (xy 15.351412 -157.516774) (xy 15.37255 -157.468575) (xy 15.400101 -157.423732)
			(xy 15.433544 -157.383094) (xy 15.452598 -157.364938) (xy 15.459984 -157.357404) (xy 15.468517 -157.338133)
			(xy 15.469108 -157.3276) (xy 15.469108 -157.252924) (xy 15.468577 -157.242375) (xy 15.460043 -157.223079)
			(xy 15.452598 -157.215586) (xy 15.433542 -157.197431) (xy 15.400085 -157.156801) (xy 15.372526 -157.111961)
			(xy 15.351388 -157.06376) (xy 15.337071 -157.013112) (xy 15.329846 -156.960978) (xy 15.329408 -156.934662)
			(xy 15.329894 -156.907411) (xy 15.33765 -156.853463) (xy 15.353005 -156.801168) (xy 15.375647 -156.751591)
			(xy 15.405113 -156.705741) (xy 15.440804 -156.66455) (xy 15.481995 -156.628859) (xy 15.527845 -156.599393)
			(xy 15.577422 -156.576751) (xy 15.629717 -156.561396) (xy 15.683665 -156.55364) (xy 15.738167 -156.55364)
			(xy 15.792115 -156.561396) (xy 15.84441 -156.576751) (xy 15.893987 -156.599393) (xy 15.939837 -156.628859)
			(xy 15.958582 -156.645101) (xy 17.31399 -156.645101) (xy 17.318305 -156.587829) (xy 17.331153 -156.531851)
			(xy 17.352244 -156.478429) (xy 17.381102 -156.428772) (xy 17.417075 -156.383999) (xy 17.437862 -156.364178)
			(xy 17.445269 -156.356661) (xy 17.453792 -156.337378) (xy 17.454372 -156.32684) (xy 17.454372 -156.252164)
			(xy 17.45383 -156.241616) (xy 17.445305 -156.22232) (xy 17.437862 -156.214826) (xy 17.418819 -156.196658)
			(xy 17.385362 -156.15603) (xy 17.357802 -156.111192) (xy 17.336662 -156.062994) (xy 17.322342 -156.012349)
			(xy 17.315113 -155.960217) (xy 17.314672 -155.933902) (xy 17.315158 -155.906651) (xy 17.322914 -155.852703)
			(xy 17.338269 -155.800408) (xy 17.360911 -155.750831) (xy 17.390377 -155.704981) (xy 17.426068 -155.66379)
			(xy 17.467259 -155.628099) (xy 17.513109 -155.598633) (xy 17.562686 -155.575991) (xy 17.614981 -155.560636)
			(xy 17.668929 -155.55288) (xy 17.723431 -155.55288) (xy 17.777379 -155.560636) (xy 17.829674 -155.575991)
			(xy 17.879251 -155.598633) (xy 17.925101 -155.628099) (xy 17.966292 -155.66379) (xy 18.001983 -155.704981)
			(xy 18.031449 -155.750831) (xy 18.054091 -155.800408) (xy 18.069446 -155.852703) (xy 18.077202 -155.906651)
			(xy 18.077688 -155.933902) (xy 18.077226 -155.960216) (xy 18.06999 -156.012345) (xy 18.055671 -156.062988)
			(xy 18.034537 -156.111187) (xy 18.00699 -156.15603) (xy 17.97355 -156.19667) (xy 17.954498 -156.214826)
			(xy 17.947083 -156.222336) (xy 17.938566 -156.241625) (xy 17.937988 -156.252164) (xy 17.937988 -156.32684)
			(xy 17.938539 -156.337387) (xy 17.947059 -156.356682) (xy 17.954498 -156.364178) (xy 17.975289 -156.383995)
			(xy 18.011266 -156.428768) (xy 18.040127 -156.478425) (xy 18.061221 -156.531848) (xy 18.07407 -156.587828)
			(xy 18.078386 -156.645101) (xy 18.07407 -156.702375) (xy 18.072934 -156.707322) (xy 20.379798 -156.707322)
			(xy 20.38411 -156.650054) (xy 20.396954 -156.594078) (xy 20.41804 -156.540659) (xy 20.446892 -156.491002)
			(xy 20.482858 -156.446229) (xy 20.503642 -156.426408) (xy 20.511034 -156.418878) (xy 20.519566 -156.399605)
			(xy 20.520152 -156.38907) (xy 20.520152 -156.314394) (xy 20.519654 -156.30384) (xy 20.511098 -156.284544)
			(xy 20.503642 -156.277056) (xy 20.484561 -156.258926) (xy 20.451108 -156.21829) (xy 20.423554 -156.173444)
			(xy 20.402421 -156.125238) (xy 20.388108 -156.074587) (xy 20.380888 -156.022449) (xy 20.380452 -155.996132)
			(xy 20.380938 -155.968881) (xy 20.388694 -155.914933) (xy 20.404049 -155.862638) (xy 20.426691 -155.813061)
			(xy 20.456157 -155.767211) (xy 20.491848 -155.72602) (xy 20.533039 -155.690329) (xy 20.578889 -155.660863)
			(xy 20.628466 -155.638221) (xy 20.680761 -155.622866) (xy 20.734709 -155.61511) (xy 20.789211 -155.61511)
			(xy 20.843159 -155.622866) (xy 20.895454 -155.638221) (xy 20.945031 -155.660863) (xy 20.990881 -155.690329)
			(xy 21.032072 -155.72602) (xy 21.067763 -155.767211) (xy 21.097229 -155.813061) (xy 21.119871 -155.862638)
			(xy 21.135226 -155.914933) (xy 21.142982 -155.968881) (xy 21.143468 -155.996132) (xy 21.143032 -156.022447)
			(xy 21.135792 -156.074577) (xy 21.121468 -156.125221) (xy 21.100329 -156.17342) (xy 21.072777 -156.218263)
			(xy 21.039333 -156.258901) (xy 21.020278 -156.277056) (xy 21.01289 -156.284589) (xy 21.004359 -156.303861)
			(xy 21.003768 -156.314394) (xy 21.003768 -156.38907) (xy 21.004309 -156.399618) (xy 21.012837 -156.418913)
			(xy 21.020278 -156.426408) (xy 21.0411 -156.446195) (xy 21.077078 -156.490971) (xy 21.10594 -156.540633)
			(xy 21.127033 -156.59406) (xy 21.139882 -156.650044) (xy 21.144195 -156.707322) (xy 21.139875 -156.764599)
			(xy 21.12702 -156.820582) (xy 21.105921 -156.874006) (xy 21.077054 -156.923665) (xy 21.04107 -156.968437)
			(xy 21.020278 -156.988256) (xy 21.01289 -156.995789) (xy 21.004359 -157.015061) (xy 21.003768 -157.025594)
			(xy 21.003768 -157.10027) (xy 21.004309 -157.110818) (xy 21.012837 -157.130113) (xy 21.020278 -157.137608)
			(xy 21.039326 -157.155771) (xy 21.072785 -157.196399) (xy 21.100345 -157.241237) (xy 21.121485 -157.289437)
			(xy 21.135804 -157.340083) (xy 21.143029 -157.392216) (xy 21.143468 -157.418532) (xy 21.142982 -157.445783)
			(xy 21.135226 -157.499731) (xy 21.119871 -157.552026) (xy 21.097229 -157.601603) (xy 21.067763 -157.647453)
			(xy 21.032072 -157.688644) (xy 20.990881 -157.724335) (xy 20.945031 -157.753801) (xy 20.895454 -157.776443)
			(xy 20.843159 -157.791798) (xy 20.789211 -157.799554) (xy 20.734709 -157.799554) (xy 20.680761 -157.791798)
			(xy 20.628466 -157.776443) (xy 20.578889 -157.753801) (xy 20.533039 -157.724335) (xy 20.491848 -157.688644)
			(xy 20.456157 -157.647453) (xy 20.426691 -157.601603) (xy 20.404049 -157.552026) (xy 20.388694 -157.499731)
			(xy 20.380938 -157.445783) (xy 20.380452 -157.418532) (xy 20.380857 -157.392216) (xy 20.388103 -157.340084)
			(xy 20.402433 -157.289439) (xy 20.423577 -157.24124) (xy 20.451135 -157.196398) (xy 20.484585 -157.155762)
			(xy 20.503642 -157.137608) (xy 20.511034 -157.130078) (xy 20.519566 -157.110805) (xy 20.520152 -157.10027)
			(xy 20.520152 -157.025594) (xy 20.519654 -157.01504) (xy 20.511098 -156.995744) (xy 20.503642 -156.988256)
			(xy 20.482888 -156.968403) (xy 20.446916 -156.923634) (xy 20.418059 -156.87398) (xy 20.396967 -156.820564)
			(xy 20.384116 -156.764589) (xy 20.379798 -156.707322) (xy 18.072934 -156.707322) (xy 18.06122 -156.758355)
			(xy 18.040126 -156.811777) (xy 18.011264 -156.861435) (xy 17.975287 -156.906207) (xy 17.954498 -156.926026)
			(xy 17.947083 -156.933536) (xy 17.938566 -156.952825) (xy 17.937988 -156.963364) (xy 17.937988 -157.03804)
			(xy 17.938539 -157.048587) (xy 17.947059 -157.067882) (xy 17.954498 -157.075378) (xy 17.973536 -157.093552)
			(xy 18.006994 -157.134177) (xy 18.034556 -157.179014) (xy 18.055697 -157.227211) (xy 18.070018 -157.277855)
			(xy 18.077247 -157.329987) (xy 18.077688 -157.356302) (xy 18.077202 -157.383553) (xy 18.069446 -157.437501)
			(xy 18.054091 -157.489796) (xy 18.031449 -157.539373) (xy 18.001983 -157.585223) (xy 17.966292 -157.626414)
			(xy 17.925101 -157.662105) (xy 17.879251 -157.691571) (xy 17.829674 -157.714213) (xy 17.777379 -157.729568)
			(xy 17.723431 -157.737324) (xy 17.668929 -157.737324) (xy 17.614981 -157.729568) (xy 17.562686 -157.714213)
			(xy 17.513109 -157.691571) (xy 17.467259 -157.662105) (xy 17.426068 -157.626414) (xy 17.390377 -157.585223)
			(xy 17.360911 -157.539373) (xy 17.338269 -157.489796) (xy 17.322914 -157.437501) (xy 17.315158 -157.383553)
			(xy 17.314672 -157.356302) (xy 17.31515 -157.329988) (xy 17.322384 -157.277861) (xy 17.336701 -157.227219)
			(xy 17.357832 -157.17902) (xy 17.385376 -157.134176) (xy 17.418812 -157.093535) (xy 17.437862 -157.075378)
			(xy 17.445269 -157.067861) (xy 17.453792 -157.048578) (xy 17.454372 -157.03804) (xy 17.454372 -156.963364)
			(xy 17.45383 -156.952816) (xy 17.445305 -156.93352) (xy 17.437862 -156.926026) (xy 17.417077 -156.906203)
			(xy 17.381104 -156.861431) (xy 17.352245 -156.811773) (xy 17.331154 -156.758352) (xy 17.318305 -156.702373)
			(xy 17.31399 -156.645101) (xy 15.958582 -156.645101) (xy 15.981028 -156.66455) (xy 16.016719 -156.705741)
			(xy 16.046185 -156.751591) (xy 16.068827 -156.801168) (xy 16.084182 -156.853463) (xy 16.091938 -156.907411)
			(xy 16.092424 -156.934662) (xy 16.09199 -156.960977) (xy 16.084747 -157.013107) (xy 16.070421 -157.06375)
			(xy 16.049282 -157.111948) (xy 16.021731 -157.156791) (xy 15.988288 -157.19743) (xy 15.969234 -157.215586)
			(xy 15.961841 -157.223115) (xy 15.953311 -157.242389) (xy 15.952724 -157.252924) (xy 15.952724 -157.3276)
			(xy 15.953233 -157.338152) (xy 15.961781 -157.357448) (xy 15.969234 -157.364938) (xy 15.988307 -157.383075)
			(xy 16.021762 -157.42371) (xy 16.049317 -157.468554) (xy 16.070453 -157.516758) (xy 16.084766 -157.567409)
			(xy 16.091987 -157.619545) (xy 16.092424 -157.645862) (xy 16.091938 -157.673113) (xy 16.084182 -157.727061)
			(xy 16.068827 -157.779356) (xy 16.046185 -157.828933) (xy 16.016719 -157.874783) (xy 15.981028 -157.915974)
			(xy 15.939837 -157.951665) (xy 15.893987 -157.981131) (xy 15.84441 -158.003773) (xy 15.792115 -158.019128)
			(xy 15.738167 -158.026884) (xy 15.683665 -158.026884) (xy 15.629717 -158.019128) (xy 15.577422 -158.003773)
			(xy 15.527845 -157.981131) (xy 15.481995 -157.951665) (xy 15.440804 -157.915974) (xy 15.405113 -157.874783)
			(xy 15.375647 -157.828933) (xy 15.353005 -157.779356) (xy 15.33765 -157.727061) (xy 15.329894 -157.673113)
			(xy 15.329408 -157.645862) (xy 14.375343 -157.645862) (xy 14.375384 -157.647894) (xy 14.374874 -157.673881)
			(xy 14.366744 -157.725216) (xy 14.350683 -157.774646) (xy 14.327087 -157.820956) (xy 14.296537 -157.863004)
			(xy 14.259786 -157.899755) (xy 14.217738 -157.930305) (xy 14.171428 -157.953901) (xy 14.121998 -157.969962)
			(xy 14.070663 -157.978092) (xy 14.018689 -157.978092) (xy 13.967354 -157.969962) (xy 13.917924 -157.953901)
			(xy 13.871614 -157.930305) (xy 13.829566 -157.899755) (xy 13.792815 -157.863004) (xy 13.762265 -157.820956)
			(xy 13.738669 -157.774646) (xy 13.722608 -157.725216) (xy 13.714478 -157.673881) (xy 13.713968 -157.647894)
			(xy 13.475208 -157.647894) (xy 13.474698 -157.673881) (xy 13.466568 -157.725216) (xy 13.450507 -157.774646)
			(xy 13.426911 -157.820956) (xy 13.396361 -157.863004) (xy 13.35961 -157.899755) (xy 13.317562 -157.930305)
			(xy 13.271252 -157.953901) (xy 13.221822 -157.969962) (xy 13.170487 -157.978092) (xy 13.118513 -157.978092)
			(xy 13.067178 -157.969962) (xy 13.017748 -157.953901) (xy 12.971438 -157.930305) (xy 12.92939 -157.899755)
			(xy 12.892639 -157.863004) (xy 12.862089 -157.820956) (xy 12.838493 -157.774646) (xy 12.822432 -157.725216)
			(xy 12.814302 -157.673881) (xy 12.813792 -157.647894) (xy 12.575286 -157.647894) (xy 12.574776 -157.673881)
			(xy 12.566646 -157.725216) (xy 12.550585 -157.774646) (xy 12.526989 -157.820956) (xy 12.496439 -157.863004)
			(xy 12.459688 -157.899755) (xy 12.41764 -157.930305) (xy 12.37133 -157.953901) (xy 12.3219 -157.969962)
			(xy 12.270565 -157.978092) (xy 12.218591 -157.978092) (xy 12.167256 -157.969962) (xy 12.117826 -157.953901)
			(xy 12.071516 -157.930305) (xy 12.029468 -157.899755) (xy 11.992717 -157.863004) (xy 11.962167 -157.820956)
			(xy 11.938571 -157.774646) (xy 11.92251 -157.725216) (xy 11.91438 -157.673881) (xy 11.91387 -157.647894)
			(xy 11.675364 -157.647894) (xy 11.674854 -157.673881) (xy 11.666724 -157.725216) (xy 11.650663 -157.774646)
			(xy 11.627067 -157.820956) (xy 11.596517 -157.863004) (xy 11.559766 -157.899755) (xy 11.517718 -157.930305)
			(xy 11.471408 -157.953901) (xy 11.421978 -157.969962) (xy 11.370643 -157.978092) (xy 11.318669 -157.978092)
			(xy 11.267334 -157.969962) (xy 11.217904 -157.953901) (xy 11.171594 -157.930305) (xy 11.129546 -157.899755)
			(xy 11.092795 -157.863004) (xy 11.062245 -157.820956) (xy 11.038649 -157.774646) (xy 11.022588 -157.725216)
			(xy 11.014458 -157.673881) (xy 11.013948 -157.647894) (xy 7.375633 -157.647894) (xy 7.389055 -157.676525)
			(xy 7.405123 -157.729932) (xy 7.413243 -157.785108) (xy 7.413752 -157.812994) (xy 7.413243 -157.84088)
			(xy 7.405123 -157.896056) (xy 7.389055 -157.949463) (xy 7.365383 -157.99996) (xy 7.33461 -158.046473)
			(xy 7.32214 -158.06039) (xy 8.839706 -158.06039) (xy 8.843777 -158.004768) (xy 8.855903 -157.950331)
			(xy 8.875826 -157.89824) (xy 8.903122 -157.849605) (xy 8.937208 -157.805462) (xy 8.977357 -157.766753)
			(xy 9.022715 -157.734302) (xy 9.072315 -157.708801) (xy 9.125099 -157.690794) (xy 9.179942 -157.680664)
			(xy 9.235676 -157.678627) (xy 9.291113 -157.684727) (xy 9.34507 -157.698833) (xy 9.396399 -157.720645)
			(xy 9.444005 -157.749699) (xy 9.486873 -157.785374) (xy 9.52409 -157.826911) (xy 9.554863 -157.873424)
			(xy 9.578535 -157.923921) (xy 9.594603 -157.977328) (xy 9.602723 -158.032504) (xy 9.603232 -158.06039)
			(xy 9.602723 -158.088276) (xy 9.594603 -158.143452) (xy 9.578535 -158.196859) (xy 9.554863 -158.247356)
			(xy 9.52409 -158.293869) (xy 9.486873 -158.335406) (xy 9.444005 -158.371081) (xy 9.396399 -158.400135)
			(xy 9.34507 -158.421947) (xy 9.291113 -158.436053) (xy 9.235676 -158.442153) (xy 9.179942 -158.440116)
			(xy 9.125099 -158.429986) (xy 9.072315 -158.411979) (xy 9.022715 -158.386478) (xy 8.977357 -158.354027)
			(xy 8.937208 -158.315318) (xy 8.903122 -158.271175) (xy 8.875826 -158.22254) (xy 8.855903 -158.170449)
			(xy 8.843777 -158.116012) (xy 8.839706 -158.06039) (xy 7.32214 -158.06039) (xy 7.297393 -158.08801)
			(xy 7.254525 -158.123685) (xy 7.206919 -158.152739) (xy 7.15559 -158.174551) (xy 7.101633 -158.188657)
			(xy 7.046196 -158.194757) (xy 6.990462 -158.19272) (xy 6.935619 -158.18259) (xy 6.882835 -158.164583)
			(xy 6.833235 -158.139082) (xy 6.787877 -158.106631) (xy 6.747728 -158.067922) (xy 6.713642 -158.023779)
			(xy 6.686346 -157.975144) (xy 6.666423 -157.923053) (xy 6.654297 -157.868616) (xy 6.650226 -157.812994)
			(xy 4.421886 -157.812994) (xy 4.421886 -158.828994) (xy 6.650226 -158.828994) (xy 6.654297 -158.773372)
			(xy 6.666423 -158.718935) (xy 6.686346 -158.666844) (xy 6.713642 -158.618209) (xy 6.747728 -158.574066)
			(xy 6.787877 -158.535357) (xy 6.833235 -158.502906) (xy 6.882835 -158.477405) (xy 6.935619 -158.459398)
			(xy 6.990462 -158.449268) (xy 7.046196 -158.447231) (xy 7.101633 -158.453331) (xy 7.15559 -158.467437)
			(xy 7.206919 -158.489249) (xy 7.254525 -158.518303) (xy 7.297393 -158.553978) (xy 7.33461 -158.595515)
			(xy 7.365383 -158.642028) (xy 7.389055 -158.692525) (xy 7.405123 -158.745932) (xy 7.406208 -158.753302)
			(xy 16.516602 -158.753302) (xy 16.520673 -158.69768) (xy 16.532799 -158.643243) (xy 16.552722 -158.591152)
			(xy 16.580018 -158.542517) (xy 16.614104 -158.498374) (xy 16.654253 -158.459665) (xy 16.699611 -158.427214)
			(xy 16.749211 -158.401713) (xy 16.801995 -158.383706) (xy 16.856838 -158.373576) (xy 16.912572 -158.371539)
			(xy 16.968009 -158.377639) (xy 17.021966 -158.391745) (xy 17.073295 -158.413557) (xy 17.120901 -158.442611)
			(xy 17.163769 -158.478286) (xy 17.200986 -158.519823) (xy 17.231759 -158.566336) (xy 17.255431 -158.616833)
			(xy 17.271499 -158.67024) (xy 17.279619 -158.725416) (xy 17.280128 -158.753302) (xy 17.279619 -158.781188)
			(xy 17.271499 -158.836364) (xy 17.255431 -158.889771) (xy 17.231759 -158.940268) (xy 17.200986 -158.986781)
			(xy 17.163769 -159.028318) (xy 17.120901 -159.063993) (xy 17.073295 -159.093047) (xy 17.021966 -159.114859)
			(xy 16.968009 -159.128965) (xy 16.912572 -159.135065) (xy 16.856838 -159.133028) (xy 16.801995 -159.122898)
			(xy 16.749211 -159.104891) (xy 16.699611 -159.07939) (xy 16.654253 -159.046939) (xy 16.614104 -159.00823)
			(xy 16.580018 -158.964087) (xy 16.552722 -158.915452) (xy 16.532799 -158.863361) (xy 16.520673 -158.808924)
			(xy 16.516602 -158.753302) (xy 7.406208 -158.753302) (xy 7.413243 -158.801108) (xy 7.413752 -158.828994)
			(xy 7.413243 -158.85688) (xy 7.405123 -158.912056) (xy 7.389055 -158.965463) (xy 7.365383 -159.01596)
			(xy 7.33461 -159.062473) (xy 7.297393 -159.10401) (xy 7.254525 -159.139685) (xy 7.206919 -159.168739)
			(xy 7.15559 -159.190551) (xy 7.101633 -159.204657) (xy 7.046196 -159.210757) (xy 6.990462 -159.20872)
			(xy 6.935619 -159.19859) (xy 6.882835 -159.180583) (xy 6.833235 -159.155082) (xy 6.787877 -159.122631)
			(xy 6.747728 -159.083922) (xy 6.713642 -159.039779) (xy 6.686346 -158.991144) (xy 6.666423 -158.939053)
			(xy 6.654297 -158.884616) (xy 6.650226 -158.828994) (xy 4.421886 -158.828994) (xy 4.421886 -159.439102)
			(xy 8.908032 -159.439102) (xy 8.912103 -159.38348) (xy 8.924229 -159.329043) (xy 8.944152 -159.276952)
			(xy 8.971448 -159.228317) (xy 9.005534 -159.184174) (xy 9.045683 -159.145465) (xy 9.091041 -159.113014)
			(xy 9.140641 -159.087513) (xy 9.193425 -159.069506) (xy 9.248268 -159.059376) (xy 9.304002 -159.057339)
			(xy 9.359439 -159.063439) (xy 9.413396 -159.077545) (xy 9.464725 -159.099357) (xy 9.512331 -159.128411)
			(xy 9.555199 -159.164086) (xy 9.592416 -159.205623) (xy 9.623189 -159.252136) (xy 9.646861 -159.302633)
			(xy 9.662929 -159.35604) (xy 9.671049 -159.411216) (xy 9.671558 -159.439102) (xy 9.671049 -159.466988)
			(xy 9.662929 -159.522164) (xy 9.660026 -159.531812) (xy 12.11275 -159.531812) (xy 12.116821 -159.47619)
			(xy 12.128947 -159.421753) (xy 12.14887 -159.369662) (xy 12.176166 -159.321027) (xy 12.210252 -159.276884)
			(xy 12.250401 -159.238175) (xy 12.295759 -159.205724) (xy 12.345359 -159.180223) (xy 12.398143 -159.162216)
			(xy 12.452986 -159.152086) (xy 12.50872 -159.150049) (xy 12.564157 -159.156149) (xy 12.618114 -159.170255)
			(xy 12.669443 -159.192067) (xy 12.717049 -159.221121) (xy 12.759917 -159.256796) (xy 12.797134 -159.298333)
			(xy 12.827907 -159.344846) (xy 12.851579 -159.395343) (xy 12.867647 -159.44875) (xy 12.873516 -159.488632)
			(xy 14.395956 -159.488632) (xy 14.400027 -159.43301) (xy 14.412153 -159.378573) (xy 14.432076 -159.326482)
			(xy 14.459372 -159.277847) (xy 14.493458 -159.233704) (xy 14.533607 -159.194995) (xy 14.578965 -159.162544)
			(xy 14.628565 -159.137043) (xy 14.681349 -159.119036) (xy 14.736192 -159.108906) (xy 14.791926 -159.106869)
			(xy 14.847363 -159.112969) (xy 14.90132 -159.127075) (xy 14.952649 -159.148887) (xy 15.000255 -159.177941)
			(xy 15.043123 -159.213616) (xy 15.08034 -159.255153) (xy 15.111113 -159.301666) (xy 15.134785 -159.352163)
			(xy 15.150853 -159.40557) (xy 15.158973 -159.460746) (xy 15.159482 -159.488632) (xy 15.158973 -159.516518)
			(xy 15.150853 -159.571694) (xy 15.134785 -159.625101) (xy 15.111113 -159.675598) (xy 15.08034 -159.722111)
			(xy 15.043123 -159.763648) (xy 15.000255 -159.799323) (xy 14.952649 -159.828377) (xy 14.90132 -159.850189)
			(xy 14.847363 -159.864295) (xy 14.791926 -159.870395) (xy 14.736192 -159.868358) (xy 14.681349 -159.858228)
			(xy 14.628565 -159.840221) (xy 14.578965 -159.81472) (xy 14.533607 -159.782269) (xy 14.493458 -159.74356)
			(xy 14.459372 -159.699417) (xy 14.432076 -159.650782) (xy 14.412153 -159.598691) (xy 14.400027 -159.544254)
			(xy 14.395956 -159.488632) (xy 12.873516 -159.488632) (xy 12.875767 -159.503926) (xy 12.876276 -159.531812)
			(xy 12.875767 -159.559698) (xy 12.867647 -159.614874) (xy 12.851579 -159.668281) (xy 12.827907 -159.718778)
			(xy 12.797134 -159.765291) (xy 12.759917 -159.806828) (xy 12.717049 -159.842503) (xy 12.669443 -159.871557)
			(xy 12.618114 -159.893369) (xy 12.564157 -159.907475) (xy 12.50872 -159.913575) (xy 12.452986 -159.911538)
			(xy 12.398143 -159.901408) (xy 12.345359 -159.883401) (xy 12.295759 -159.8579) (xy 12.250401 -159.825449)
			(xy 12.210252 -159.78674) (xy 12.176166 -159.742597) (xy 12.14887 -159.693962) (xy 12.128947 -159.641871)
			(xy 12.116821 -159.587434) (xy 12.11275 -159.531812) (xy 9.660026 -159.531812) (xy 9.646861 -159.575571)
			(xy 9.623189 -159.626068) (xy 9.592416 -159.672581) (xy 9.555199 -159.714118) (xy 9.512331 -159.749793)
			(xy 9.464725 -159.778847) (xy 9.413396 -159.800659) (xy 9.359439 -159.814765) (xy 9.304002 -159.820865)
			(xy 9.248268 -159.818828) (xy 9.193425 -159.808698) (xy 9.140641 -159.790691) (xy 9.091041 -159.76519)
			(xy 9.045683 -159.732739) (xy 9.005534 -159.69403) (xy 8.971448 -159.649887) (xy 8.944152 -159.601252)
			(xy 8.924229 -159.549161) (xy 8.912103 -159.494724) (xy 8.908032 -159.439102) (xy 4.421886 -159.439102)
			(xy 4.421886 -159.844994) (xy 6.650226 -159.844994) (xy 6.654297 -159.789372) (xy 6.666423 -159.734935)
			(xy 6.686346 -159.682844) (xy 6.713642 -159.634209) (xy 6.747728 -159.590066) (xy 6.787877 -159.551357)
			(xy 6.833235 -159.518906) (xy 6.882835 -159.493405) (xy 6.935619 -159.475398) (xy 6.990462 -159.465268)
			(xy 7.046196 -159.463231) (xy 7.101633 -159.469331) (xy 7.15559 -159.483437) (xy 7.206919 -159.505249)
			(xy 7.254525 -159.534303) (xy 7.297393 -159.569978) (xy 7.33461 -159.611515) (xy 7.365383 -159.658028)
			(xy 7.389055 -159.708525) (xy 7.405123 -159.761932) (xy 7.413243 -159.817108) (xy 7.413752 -159.844994)
			(xy 7.413243 -159.87288) (xy 7.405123 -159.928056) (xy 7.389055 -159.981463) (xy 7.365383 -160.03196)
			(xy 7.33461 -160.078473) (xy 7.297393 -160.12001) (xy 7.254525 -160.155685) (xy 7.206919 -160.184739)
			(xy 7.15559 -160.206551) (xy 7.101633 -160.220657) (xy 7.046196 -160.226757) (xy 6.990462 -160.22472)
			(xy 6.935619 -160.21459) (xy 6.882835 -160.196583) (xy 6.833235 -160.171082) (xy 6.787877 -160.138631)
			(xy 6.747728 -160.099922) (xy 6.713642 -160.055779) (xy 6.686346 -160.007144) (xy 6.666423 -159.955053)
			(xy 6.654297 -159.900616) (xy 6.650226 -159.844994) (xy 4.421886 -159.844994) (xy 4.421886 -160.965896)
			(xy 8.93775 -160.965896) (xy 8.941821 -160.910274) (xy 8.953947 -160.855837) (xy 8.97387 -160.803746)
			(xy 9.001166 -160.755111) (xy 9.035252 -160.710968) (xy 9.075401 -160.672259) (xy 9.120759 -160.639808)
			(xy 9.170359 -160.614307) (xy 9.223143 -160.5963) (xy 9.277986 -160.58617) (xy 9.33372 -160.584133)
			(xy 9.389157 -160.590233) (xy 9.443114 -160.604339) (xy 9.494443 -160.626151) (xy 9.542049 -160.655205)
			(xy 9.584917 -160.69088) (xy 9.622134 -160.732417) (xy 9.652907 -160.77893) (xy 9.676579 -160.829427)
			(xy 9.692647 -160.882834) (xy 9.700767 -160.93801) (xy 9.701239 -160.963864) (xy 10.32967 -160.963864)
			(xy 10.333741 -160.908242) (xy 10.345867 -160.853805) (xy 10.36579 -160.801714) (xy 10.393086 -160.753079)
			(xy 10.427172 -160.708936) (xy 10.467321 -160.670227) (xy 10.512679 -160.637776) (xy 10.562279 -160.612275)
			(xy 10.615063 -160.594268) (xy 10.669906 -160.584138) (xy 10.72564 -160.582101) (xy 10.781077 -160.588201)
			(xy 10.835034 -160.602307) (xy 10.886363 -160.624119) (xy 10.933969 -160.653173) (xy 10.976837 -160.688848)
			(xy 11.014054 -160.730385) (xy 11.044827 -160.776898) (xy 11.068499 -160.827395) (xy 11.084567 -160.880802)
			(xy 11.092687 -160.935978) (xy 11.093196 -160.963864) (xy 11.093103 -160.968944) (xy 11.601448 -160.968944)
			(xy 11.605519 -160.913322) (xy 11.617645 -160.858885) (xy 11.637568 -160.806794) (xy 11.664864 -160.758159)
			(xy 11.69895 -160.714016) (xy 11.739099 -160.675307) (xy 11.784457 -160.642856) (xy 11.834057 -160.617355)
			(xy 11.886841 -160.599348) (xy 11.941684 -160.589218) (xy 11.997418 -160.587181) (xy 12.052855 -160.593281)
			(xy 12.106812 -160.607387) (xy 12.158141 -160.629199) (xy 12.205747 -160.658253) (xy 12.248615 -160.693928)
			(xy 12.285832 -160.735465) (xy 12.316605 -160.781978) (xy 12.340277 -160.832475) (xy 12.356345 -160.885882)
			(xy 12.358738 -160.902142) (xy 13.38275 -160.902142) (xy 13.386821 -160.84652) (xy 13.398947 -160.792083)
			(xy 13.41887 -160.739992) (xy 13.446166 -160.691357) (xy 13.480252 -160.647214) (xy 13.520401 -160.608505)
			(xy 13.565759 -160.576054) (xy 13.615359 -160.550553) (xy 13.668143 -160.532546) (xy 13.722986 -160.522416)
			(xy 13.77872 -160.520379) (xy 13.834157 -160.526479) (xy 13.888114 -160.540585) (xy 13.939443 -160.562397)
			(xy 13.987049 -160.591451) (xy 14.029917 -160.627126) (xy 14.067134 -160.668663) (xy 14.097907 -160.715176)
			(xy 14.121579 -160.765673) (xy 14.137647 -160.81908) (xy 14.145767 -160.874256) (xy 14.146276 -160.902142)
			(xy 14.145767 -160.930028) (xy 14.137647 -160.985204) (xy 14.121579 -161.038611) (xy 14.097907 -161.089108)
			(xy 14.067134 -161.135621) (xy 14.029917 -161.177158) (xy 13.987049 -161.212833) (xy 13.939443 -161.241887)
			(xy 13.888114 -161.263699) (xy 13.834157 -161.277805) (xy 13.77872 -161.283905) (xy 13.722986 -161.281868)
			(xy 13.668143 -161.271738) (xy 13.615359 -161.253731) (xy 13.565759 -161.22823) (xy 13.520401 -161.195779)
			(xy 13.480252 -161.15707) (xy 13.446166 -161.112927) (xy 13.41887 -161.064292) (xy 13.398947 -161.012201)
			(xy 13.386821 -160.957764) (xy 13.38275 -160.902142) (xy 12.358738 -160.902142) (xy 12.364465 -160.941058)
			(xy 12.364974 -160.968944) (xy 12.364465 -160.99683) (xy 12.356345 -161.052006) (xy 12.340277 -161.105413)
			(xy 12.316605 -161.15591) (xy 12.285832 -161.202423) (xy 12.248615 -161.24396) (xy 12.205747 -161.279635)
			(xy 12.158141 -161.308689) (xy 12.106812 -161.330501) (xy 12.052855 -161.344607) (xy 11.997418 -161.350707)
			(xy 11.941684 -161.34867) (xy 11.886841 -161.33854) (xy 11.834057 -161.320533) (xy 11.784457 -161.295032)
			(xy 11.739099 -161.262581) (xy 11.69895 -161.223872) (xy 11.664864 -161.179729) (xy 11.637568 -161.131094)
			(xy 11.617645 -161.079003) (xy 11.605519 -161.024566) (xy 11.601448 -160.968944) (xy 11.093103 -160.968944)
			(xy 11.092687 -160.99175) (xy 11.084567 -161.046926) (xy 11.068499 -161.100333) (xy 11.044827 -161.15083)
			(xy 11.014054 -161.197343) (xy 10.976837 -161.23888) (xy 10.933969 -161.274555) (xy 10.886363 -161.303609)
			(xy 10.835034 -161.325421) (xy 10.781077 -161.339527) (xy 10.72564 -161.345627) (xy 10.669906 -161.34359)
			(xy 10.615063 -161.33346) (xy 10.562279 -161.315453) (xy 10.512679 -161.289952) (xy 10.467321 -161.257501)
			(xy 10.427172 -161.218792) (xy 10.393086 -161.174649) (xy 10.36579 -161.126014) (xy 10.345867 -161.073923)
			(xy 10.333741 -161.019486) (xy 10.32967 -160.963864) (xy 9.701239 -160.963864) (xy 9.701276 -160.965896)
			(xy 9.700767 -160.993782) (xy 9.692647 -161.048958) (xy 9.676579 -161.102365) (xy 9.652907 -161.152862)
			(xy 9.622134 -161.199375) (xy 9.584917 -161.240912) (xy 9.542049 -161.276587) (xy 9.494443 -161.305641)
			(xy 9.443114 -161.327453) (xy 9.389157 -161.341559) (xy 9.33372 -161.347659) (xy 9.277986 -161.345622)
			(xy 9.223143 -161.335492) (xy 9.170359 -161.317485) (xy 9.120759 -161.291984) (xy 9.075401 -161.259533)
			(xy 9.035252 -161.220824) (xy 9.001166 -161.176681) (xy 8.97387 -161.128046) (xy 8.953947 -161.075955)
			(xy 8.941821 -161.021518) (xy 8.93775 -160.965896) (xy 4.421886 -160.965896) (xy 4.421886 -163.114736)
			(xy 16.04975 -163.114736) (xy 16.053821 -163.059114) (xy 16.065947 -163.004677) (xy 16.08587 -162.952586)
			(xy 16.113166 -162.903951) (xy 16.147252 -162.859808) (xy 16.187401 -162.821099) (xy 16.232759 -162.788648)
			(xy 16.282359 -162.763147) (xy 16.335143 -162.74514) (xy 16.389986 -162.73501) (xy 16.44572 -162.732973)
			(xy 16.501157 -162.739073) (xy 16.555114 -162.753179) (xy 16.606443 -162.774991) (xy 16.654049 -162.804045)
			(xy 16.696917 -162.83972) (xy 16.734134 -162.881257) (xy 16.764907 -162.92777) (xy 16.788579 -162.978267)
			(xy 16.804647 -163.031674) (xy 16.812767 -163.08685) (xy 16.813276 -163.114736) (xy 16.812767 -163.142622)
			(xy 16.804647 -163.197798) (xy 16.788579 -163.251205) (xy 16.764907 -163.301702) (xy 16.734134 -163.348215)
			(xy 16.696917 -163.389752) (xy 16.654049 -163.425427) (xy 16.606443 -163.454481) (xy 16.555114 -163.476293)
			(xy 16.501157 -163.490399) (xy 16.44572 -163.496499) (xy 16.389986 -163.494462) (xy 16.335143 -163.484332)
			(xy 16.282359 -163.466325) (xy 16.232759 -163.440824) (xy 16.187401 -163.408373) (xy 16.147252 -163.369664)
			(xy 16.113166 -163.325521) (xy 16.08587 -163.276886) (xy 16.065947 -163.224795) (xy 16.053821 -163.170358)
			(xy 16.04975 -163.114736) (xy 4.421886 -163.114736) (xy 4.421886 -167.667178) (xy 18.392138 -167.667178)
			(xy 18.396209 -167.611556) (xy 18.408335 -167.557119) (xy 18.428258 -167.505028) (xy 18.455554 -167.456393)
			(xy 18.48964 -167.41225) (xy 18.529789 -167.373541) (xy 18.575147 -167.34109) (xy 18.624747 -167.315589)
			(xy 18.677531 -167.297582) (xy 18.732374 -167.287452) (xy 18.788108 -167.285415) (xy 18.843545 -167.291515)
			(xy 18.897502 -167.305621) (xy 18.948831 -167.327433) (xy 18.996437 -167.356487) (xy 19.039305 -167.392162)
			(xy 19.076522 -167.433699) (xy 19.107295 -167.480212) (xy 19.130967 -167.530709) (xy 19.147035 -167.584116)
			(xy 19.149914 -167.603678) (xy 21.168612 -167.603678) (xy 21.172683 -167.548056) (xy 21.184809 -167.493619)
			(xy 21.204732 -167.441528) (xy 21.232028 -167.392893) (xy 21.266114 -167.34875) (xy 21.306263 -167.310041)
			(xy 21.351621 -167.27759) (xy 21.401221 -167.252089) (xy 21.454005 -167.234082) (xy 21.508848 -167.223952)
			(xy 21.564582 -167.221915) (xy 21.620019 -167.228015) (xy 21.673976 -167.242121) (xy 21.725305 -167.263933)
			(xy 21.772911 -167.292987) (xy 21.815779 -167.328662) (xy 21.852996 -167.370199) (xy 21.883769 -167.416712)
			(xy 21.907441 -167.467209) (xy 21.923509 -167.520616) (xy 21.931629 -167.575792) (xy 21.932138 -167.603678)
			(xy 21.931629 -167.631564) (xy 21.923509 -167.68674) (xy 21.907441 -167.740147) (xy 21.883769 -167.790644)
			(xy 21.852996 -167.837157) (xy 21.815779 -167.878694) (xy 21.772911 -167.914369) (xy 21.725305 -167.943423)
			(xy 21.673976 -167.965235) (xy 21.620019 -167.979341) (xy 21.564582 -167.985441) (xy 21.508848 -167.983404)
			(xy 21.454005 -167.973274) (xy 21.401221 -167.955267) (xy 21.351621 -167.929766) (xy 21.306263 -167.897315)
			(xy 21.266114 -167.858606) (xy 21.232028 -167.814463) (xy 21.204732 -167.765828) (xy 21.184809 -167.713737)
			(xy 21.172683 -167.6593) (xy 21.168612 -167.603678) (xy 19.149914 -167.603678) (xy 19.155155 -167.639292)
			(xy 19.155664 -167.667178) (xy 19.155155 -167.695064) (xy 19.147035 -167.75024) (xy 19.130967 -167.803647)
			(xy 19.107295 -167.854144) (xy 19.076522 -167.900657) (xy 19.039305 -167.942194) (xy 18.996437 -167.977869)
			(xy 18.948831 -168.006923) (xy 18.897502 -168.028735) (xy 18.843545 -168.042841) (xy 18.788108 -168.048941)
			(xy 18.732374 -168.046904) (xy 18.677531 -168.036774) (xy 18.624747 -168.018767) (xy 18.575147 -167.993266)
			(xy 18.529789 -167.960815) (xy 18.48964 -167.922106) (xy 18.455554 -167.877963) (xy 18.428258 -167.829328)
			(xy 18.408335 -167.777237) (xy 18.396209 -167.7228) (xy 18.392138 -167.667178) (xy 4.421886 -167.667178)
			(xy 4.421886 -168.417063) (xy 8.583373 -168.417063) (xy 8.583373 -168.362557) (xy 8.59113 -168.308606)
			(xy 8.606487 -168.256307) (xy 8.629129 -168.206727) (xy 8.658598 -168.160873) (xy 8.694292 -168.11968)
			(xy 8.735485 -168.083987) (xy 8.781339 -168.054518) (xy 8.830919 -168.031876) (xy 8.883217 -168.01652)
			(xy 8.937169 -168.008763) (xy 8.964422 -168.0083) (xy 8.991897 -168.008773) (xy 9.046277 -168.016668)
			(xy 9.09896 -168.032292) (xy 9.148852 -168.055319) (xy 9.19492 -168.085273) (xy 9.215882 -168.103042)
			(xy 9.223155 -168.108845) (xy 9.240617 -168.115223) (xy 9.249918 -168.115488) (xy 9.32815 -168.114218)
			(xy 9.345422 -168.107106) (xy 9.35228 -168.100756) (xy 9.373594 -168.08147) (xy 9.420959 -168.048905)
			(xy 9.472674 -168.023815) (xy 9.527568 -168.006768) (xy 9.584398 -167.99815) (xy 9.613138 -167.997632)
			(xy 9.640391 -167.998095) (xy 9.694342 -168.005852) (xy 9.74664 -168.021208) (xy 9.796221 -168.04385)
			(xy 9.842074 -168.073318) (xy 9.883267 -168.109012) (xy 9.918961 -168.150204) (xy 9.948429 -168.196058)
			(xy 9.971072 -168.245638) (xy 9.986428 -168.297936) (xy 9.994185 -168.351887) (xy 9.994185 -168.406393)
			(xy 9.986428 -168.460344) (xy 9.971072 -168.512642) (xy 9.948429 -168.562222) (xy 9.918961 -168.608076)
			(xy 9.883267 -168.649268) (xy 9.842074 -168.684962) (xy 9.796221 -168.71443) (xy 9.74664 -168.737072)
			(xy 9.694342 -168.752428) (xy 9.640391 -168.760185) (xy 9.613138 -168.760648) (xy 9.585664 -168.760152)
			(xy 9.531284 -168.752264) (xy 9.478601 -168.736647) (xy 9.428708 -168.713624) (xy 9.38264 -168.683673)
			(xy 9.361678 -168.665906) (xy 9.354383 -168.660134) (xy 9.336938 -168.653736) (xy 9.327642 -168.65346)
			(xy 9.24941 -168.65473) (xy 9.232138 -168.661842) (xy 9.22528 -168.668192) (xy 9.203948 -168.687457)
			(xy 9.156587 -168.720023) (xy 9.104877 -168.745116) (xy 9.049987 -168.762168) (xy 9.008124 -168.768522)
			(xy 23.884888 -168.768522) (xy 23.888959 -168.7129) (xy 23.901085 -168.658463) (xy 23.921008 -168.606372)
			(xy 23.948304 -168.557737) (xy 23.98239 -168.513594) (xy 24.022539 -168.474885) (xy 24.067897 -168.442434)
			(xy 24.117497 -168.416933) (xy 24.170281 -168.398926) (xy 24.225124 -168.388796) (xy 24.280858 -168.386759)
			(xy 24.336295 -168.392859) (xy 24.390252 -168.406965) (xy 24.441581 -168.428777) (xy 24.489187 -168.457831)
			(xy 24.532055 -168.493506) (xy 24.569272 -168.535043) (xy 24.600045 -168.581556) (xy 24.623717 -168.632053)
			(xy 24.639785 -168.68546) (xy 24.647905 -168.740636) (xy 24.648414 -168.768522) (xy 24.647905 -168.796408)
			(xy 24.639785 -168.851584) (xy 24.623717 -168.904991) (xy 24.600045 -168.955488) (xy 24.569272 -169.002001)
			(xy 24.532055 -169.043538) (xy 24.489187 -169.079213) (xy 24.441581 -169.108267) (xy 24.390252 -169.130079)
			(xy 24.336295 -169.144185) (xy 24.280858 -169.150285) (xy 24.225124 -169.148248) (xy 24.170281 -169.138118)
			(xy 24.117497 -169.120111) (xy 24.067897 -169.09461) (xy 24.022539 -169.062159) (xy 23.98239 -169.02345)
			(xy 23.948304 -168.979307) (xy 23.921008 -168.930672) (xy 23.901085 -168.878581) (xy 23.888959 -168.824144)
			(xy 23.884888 -168.768522) (xy 9.008124 -168.768522) (xy 8.993161 -168.770793) (xy 8.964422 -168.771316)
			(xy 8.937169 -168.770857) (xy 8.883217 -168.7631) (xy 8.830919 -168.747744) (xy 8.781339 -168.725102)
			(xy 8.735485 -168.695633) (xy 8.694292 -168.65994) (xy 8.658598 -168.618747) (xy 8.629129 -168.572893)
			(xy 8.606487 -168.523313) (xy 8.59113 -168.471014) (xy 8.583373 -168.417063) (xy 4.421886 -168.417063)
			(xy 4.421886 -169.517314) (xy 19.694904 -169.517314) (xy 19.698975 -169.461692) (xy 19.711101 -169.407255)
			(xy 19.731024 -169.355164) (xy 19.75832 -169.306529) (xy 19.792406 -169.262386) (xy 19.832555 -169.223677)
			(xy 19.877913 -169.191226) (xy 19.927513 -169.165725) (xy 19.980297 -169.147718) (xy 20.03514 -169.137588)
			(xy 20.090874 -169.135551) (xy 20.146311 -169.141651) (xy 20.200268 -169.155757) (xy 20.251597 -169.177569)
			(xy 20.299203 -169.206623) (xy 20.342071 -169.242298) (xy 20.379288 -169.283835) (xy 20.410061 -169.330348)
			(xy 20.433733 -169.380845) (xy 20.449801 -169.434252) (xy 20.457921 -169.489428) (xy 20.45843 -169.517314)
			(xy 20.457921 -169.5452) (xy 20.449801 -169.600376) (xy 20.433733 -169.653783) (xy 20.410061 -169.70428)
			(xy 20.379288 -169.750793) (xy 20.342071 -169.79233) (xy 20.299203 -169.828005) (xy 20.251597 -169.857059)
			(xy 20.200268 -169.878871) (xy 20.146311 -169.892977) (xy 20.090874 -169.899077) (xy 20.03514 -169.89704)
			(xy 19.980297 -169.88691) (xy 19.927513 -169.868903) (xy 19.877913 -169.843402) (xy 19.832555 -169.810951)
			(xy 19.792406 -169.772242) (xy 19.75832 -169.728099) (xy 19.731024 -169.679464) (xy 19.711101 -169.627373)
			(xy 19.698975 -169.572936) (xy 19.694904 -169.517314) (xy 4.421886 -169.517314) (xy 4.421886 -170.590281)
			(xy 8.57248 -170.590281) (xy 8.57248 -170.535779) (xy 8.580236 -170.481831) (xy 8.595591 -170.429537)
			(xy 8.618232 -170.37996) (xy 8.647698 -170.33411) (xy 8.68339 -170.29292) (xy 8.72458 -170.257228)
			(xy 8.77043 -170.227762) (xy 8.820007 -170.205121) (xy 8.872301 -170.189766) (xy 8.926249 -170.18201)
			(xy 8.9535 -170.181524) (xy 8.981589 -170.182012) (xy 9.037157 -170.190259) (xy 9.090913 -170.206574)
			(xy 9.141691 -170.230605) (xy 9.188391 -170.26183) (xy 9.209532 -170.28033) (xy 9.209786 -170.280584)
			(xy 9.216994 -170.286556) (xy 9.234468 -170.293221) (xy 9.243822 -170.293538) (xy 9.311894 -170.293538)
			(xy 9.32123 -170.293116) (xy 9.338682 -170.286482) (xy 9.34593 -170.280584) (xy 9.346184 -170.28033)
			(xy 9.367346 -170.26186) (xy 9.414058 -170.230668) (xy 9.464833 -170.206652) (xy 9.518577 -170.190328)
			(xy 9.574132 -170.182049) (xy 9.602216 -170.181524) (xy 9.629469 -170.181983) (xy 9.683421 -170.18974)
			(xy 9.735719 -170.205095) (xy 9.7853 -170.227738) (xy 9.831154 -170.257206) (xy 9.872348 -170.2929)
			(xy 9.908042 -170.334093) (xy 9.91985 -170.352466) (xy 20.610574 -170.352466) (xy 20.614645 -170.296844)
			(xy 20.626771 -170.242407) (xy 20.646694 -170.190316) (xy 20.67399 -170.141681) (xy 20.708076 -170.097538)
			(xy 20.748225 -170.058829) (xy 20.793583 -170.026378) (xy 20.843183 -170.000877) (xy 20.895967 -169.98287)
			(xy 20.95081 -169.97274) (xy 21.006544 -169.970703) (xy 21.061981 -169.976803) (xy 21.115938 -169.990909)
			(xy 21.167267 -170.012721) (xy 21.214873 -170.041775) (xy 21.257741 -170.07745) (xy 21.294958 -170.118987)
			(xy 21.325731 -170.1655) (xy 21.349403 -170.215997) (xy 21.365471 -170.269404) (xy 21.373591 -170.32458)
			(xy 21.3741 -170.352466) (xy 21.373591 -170.380352) (xy 21.365471 -170.435528) (xy 21.349403 -170.488935)
			(xy 21.325731 -170.539432) (xy 21.294958 -170.585945) (xy 21.257741 -170.627482) (xy 21.214873 -170.663157)
			(xy 21.167267 -170.692211) (xy 21.115938 -170.714023) (xy 21.061981 -170.728129) (xy 21.006544 -170.734229)
			(xy 20.95081 -170.732192) (xy 20.895967 -170.722062) (xy 20.843183 -170.704055) (xy 20.793583 -170.678554)
			(xy 20.748225 -170.646103) (xy 20.708076 -170.607394) (xy 20.67399 -170.563251) (xy 20.646694 -170.514616)
			(xy 20.626771 -170.462525) (xy 20.614645 -170.408088) (xy 20.610574 -170.352466) (xy 9.91985 -170.352466)
			(xy 9.93751 -170.379946) (xy 9.960153 -170.429527) (xy 9.97551 -170.481825) (xy 9.983267 -170.535777)
			(xy 9.983267 -170.590283) (xy 9.97551 -170.644235) (xy 9.960153 -170.696533) (xy 9.93751 -170.746114)
			(xy 9.908042 -170.791967) (xy 9.872348 -170.83316) (xy 9.831154 -170.868854) (xy 9.7853 -170.898322)
			(xy 9.735719 -170.920965) (xy 9.683421 -170.93632) (xy 9.629469 -170.944077) (xy 9.602216 -170.94454)
			(xy 9.574127 -170.944051) (xy 9.518559 -170.935806) (xy 9.464803 -170.919491) (xy 9.414025 -170.89546)
			(xy 9.367325 -170.864235) (xy 9.346184 -170.845734) (xy 9.34593 -170.84548) (xy 9.338721 -170.839511)
			(xy 9.321247 -170.832845) (xy 9.311894 -170.832526) (xy 9.243822 -170.832526) (xy 9.234488 -170.832963)
			(xy 9.217036 -170.839587) (xy 9.209786 -170.84548) (xy 9.209532 -170.845734) (xy 9.188359 -170.864191)
			(xy 9.141651 -170.895386) (xy 9.090878 -170.919405) (xy 9.037136 -170.935732) (xy 8.981583 -170.944014)
			(xy 8.9535 -170.94454) (xy 8.926249 -170.94405) (xy 8.872301 -170.936294) (xy 8.820007 -170.920939)
			(xy 8.77043 -170.898298) (xy 8.72458 -170.868832) (xy 8.68339 -170.83314) (xy 8.647698 -170.79195)
			(xy 8.618232 -170.7461) (xy 8.595591 -170.696523) (xy 8.580236 -170.644229) (xy 8.57248 -170.590281)
			(xy 4.421886 -170.590281) (xy 4.421886 -172.729398) (xy 20.58873 -172.729398) (xy 20.592801 -172.673776)
			(xy 20.604927 -172.619339) (xy 20.62485 -172.567248) (xy 20.652146 -172.518613) (xy 20.686232 -172.47447)
			(xy 20.726381 -172.435761) (xy 20.771739 -172.40331) (xy 20.821339 -172.377809) (xy 20.874123 -172.359802)
			(xy 20.928966 -172.349672) (xy 20.9847 -172.347635) (xy 21.040137 -172.353735) (xy 21.094094 -172.367841)
			(xy 21.145423 -172.389653) (xy 21.193029 -172.418707) (xy 21.235897 -172.454382) (xy 21.273114 -172.495919)
			(xy 21.303887 -172.542432) (xy 21.327559 -172.592929) (xy 21.343627 -172.646336) (xy 21.351747 -172.701512)
			(xy 21.352256 -172.729398) (xy 21.351747 -172.757284) (xy 21.343627 -172.81246) (xy 21.327559 -172.865867)
			(xy 21.303887 -172.916364) (xy 21.273114 -172.962877) (xy 21.235897 -173.004414) (xy 21.193029 -173.040089)
			(xy 21.145423 -173.069143) (xy 21.094094 -173.090955) (xy 21.040137 -173.105061) (xy 20.9847 -173.111161)
			(xy 20.928966 -173.109124) (xy 20.874123 -173.098994) (xy 20.821339 -173.080987) (xy 20.771739 -173.055486)
			(xy 20.726381 -173.023035) (xy 20.686232 -172.984326) (xy 20.652146 -172.940183) (xy 20.62485 -172.891548)
			(xy 20.604927 -172.839457) (xy 20.592801 -172.78502) (xy 20.58873 -172.729398) (xy 4.421886 -172.729398)
			(xy 4.421886 -173.282681) (xy 8.99412 -173.282681) (xy 8.99412 -173.228179) (xy 9.001876 -173.174231)
			(xy 9.017231 -173.121937) (xy 9.039872 -173.07236) (xy 9.069338 -173.02651) (xy 9.10503 -172.98532)
			(xy 9.14622 -172.949628) (xy 9.19207 -172.920162) (xy 9.241647 -172.897521) (xy 9.293941 -172.882166)
			(xy 9.347889 -172.87441) (xy 9.37514 -172.873924) (xy 9.404399 -172.874486) (xy 9.462231 -172.883433)
			(xy 9.518021 -172.901096) (xy 9.570464 -172.927062) (xy 9.618333 -172.960722) (xy 9.639808 -172.980604)
			(xy 9.647174 -172.987716) (xy 9.664954 -172.994828) (xy 9.755632 -172.994828) (xy 9.773412 -172.987716)
			(xy 9.780778 -172.980604) (xy 9.802223 -172.960685) (xy 9.850091 -172.92701) (xy 9.902541 -172.90104)
			(xy 9.958341 -172.883382) (xy 10.016182 -172.874453) (xy 10.045446 -172.873924) (xy 10.072699 -172.874383)
			(xy 10.126651 -172.88214) (xy 10.178949 -172.897495) (xy 10.22853 -172.920138) (xy 10.274384 -172.949606)
			(xy 10.315578 -172.9853) (xy 10.351272 -173.026493) (xy 10.38074 -173.072346) (xy 10.403383 -173.121927)
			(xy 10.41874 -173.174225) (xy 10.426497 -173.228177) (xy 10.426497 -173.282683) (xy 10.41874 -173.336635)
			(xy 10.403383 -173.388933) (xy 10.38074 -173.438514) (xy 10.351272 -173.484367) (xy 10.315578 -173.52556)
			(xy 10.274384 -173.561254) (xy 10.229336 -173.590204) (xy 19.616672 -173.590204) (xy 19.620743 -173.534582)
			(xy 19.632869 -173.480145) (xy 19.652792 -173.428054) (xy 19.680088 -173.379419) (xy 19.714174 -173.335276)
			(xy 19.754323 -173.296567) (xy 19.799681 -173.264116) (xy 19.849281 -173.238615) (xy 19.902065 -173.220608)
			(xy 19.956908 -173.210478) (xy 20.012642 -173.208441) (xy 20.068079 -173.214541) (xy 20.122036 -173.228647)
			(xy 20.173365 -173.250459) (xy 20.220971 -173.279513) (xy 20.263839 -173.315188) (xy 20.301056 -173.356725)
			(xy 20.331829 -173.403238) (xy 20.355501 -173.453735) (xy 20.371569 -173.507142) (xy 20.379689 -173.562318)
			(xy 20.380198 -173.590204) (xy 20.379689 -173.61809) (xy 20.371569 -173.673266) (xy 20.355501 -173.726673)
			(xy 20.331829 -173.77717) (xy 20.301056 -173.823683) (xy 20.263839 -173.86522) (xy 20.220971 -173.900895)
			(xy 20.173365 -173.929949) (xy 20.122036 -173.951761) (xy 20.068079 -173.965867) (xy 20.012642 -173.971967)
			(xy 19.956908 -173.96993) (xy 19.902065 -173.9598) (xy 19.849281 -173.941793) (xy 19.799681 -173.916292)
			(xy 19.754323 -173.883841) (xy 19.714174 -173.845132) (xy 19.680088 -173.800989) (xy 19.652792 -173.752354)
			(xy 19.632869 -173.700263) (xy 19.620743 -173.645826) (xy 19.616672 -173.590204) (xy 10.229336 -173.590204)
			(xy 10.22853 -173.590722) (xy 10.178949 -173.613365) (xy 10.126651 -173.62872) (xy 10.072699 -173.636477)
			(xy 10.045446 -173.63694) (xy 10.016186 -173.636396) (xy 9.958353 -173.627446) (xy 9.902562 -173.60978)
			(xy 9.85012 -173.58381) (xy 9.802252 -173.550144) (xy 9.780778 -173.53026) (xy 9.773412 -173.523148)
			(xy 9.755632 -173.516036) (xy 9.664954 -173.516036) (xy 9.647174 -173.523148) (xy 9.639808 -173.53026)
			(xy 9.618364 -173.550179) (xy 9.570496 -173.583855) (xy 9.518046 -173.609827) (xy 9.462246 -173.627484)
			(xy 9.404404 -173.636412) (xy 9.37514 -173.63694) (xy 9.347889 -173.63645) (xy 9.293941 -173.628694)
			(xy 9.241647 -173.613339) (xy 9.19207 -173.590698) (xy 9.14622 -173.561232) (xy 9.10503 -173.52554)
			(xy 9.069338 -173.48435) (xy 9.039872 -173.4385) (xy 9.017231 -173.388923) (xy 9.001876 -173.336629)
			(xy 8.99412 -173.282681) (xy 4.421886 -173.282681) (xy 4.421886 -174.271178) (xy 21.033738 -174.271178)
			(xy 21.037809 -174.215556) (xy 21.049935 -174.161119) (xy 21.069858 -174.109028) (xy 21.097154 -174.060393)
			(xy 21.13124 -174.01625) (xy 21.171389 -173.977541) (xy 21.216747 -173.94509) (xy 21.266347 -173.919589)
			(xy 21.319131 -173.901582) (xy 21.373974 -173.891452) (xy 21.429708 -173.889415) (xy 21.485145 -173.895515)
			(xy 21.539102 -173.909621) (xy 21.590431 -173.931433) (xy 21.638037 -173.960487) (xy 21.680905 -173.996162)
			(xy 21.718122 -174.037699) (xy 21.748895 -174.084212) (xy 21.772567 -174.134709) (xy 21.788635 -174.188116)
			(xy 21.796755 -174.243292) (xy 21.797264 -174.271178) (xy 21.796755 -174.299064) (xy 21.788635 -174.35424)
			(xy 21.772567 -174.407647) (xy 21.748895 -174.458144) (xy 21.718122 -174.504657) (xy 21.680905 -174.546194)
			(xy 21.638037 -174.581869) (xy 21.590431 -174.610923) (xy 21.539102 -174.632735) (xy 21.485145 -174.646841)
			(xy 21.429708 -174.652941) (xy 21.373974 -174.650904) (xy 21.319131 -174.640774) (xy 21.266347 -174.622767)
			(xy 21.216747 -174.597266) (xy 21.171389 -174.564815) (xy 21.13124 -174.526106) (xy 21.097154 -174.481963)
			(xy 21.069858 -174.433328) (xy 21.049935 -174.381237) (xy 21.037809 -174.3268) (xy 21.033738 -174.271178)
			(xy 4.421886 -174.271178) (xy 4.421886 -177.594081) (xy 8.398486 -177.594081) (xy 8.398486 -177.539579)
			(xy 8.406242 -177.485631) (xy 8.421598 -177.433336) (xy 8.444239 -177.383758) (xy 8.473705 -177.337907)
			(xy 8.509397 -177.296717) (xy 8.550587 -177.261025) (xy 8.596438 -177.231559) (xy 8.646016 -177.208918)
			(xy 8.698311 -177.193562) (xy 8.752259 -177.185806) (xy 8.77951 -177.18532) (xy 8.805824 -177.185774)
			(xy 8.857954 -177.193011) (xy 8.908597 -177.207332) (xy 8.956796 -177.228467) (xy 9.001639 -177.256016)
			(xy 9.042278 -177.289457) (xy 9.060434 -177.30851) (xy 9.06794 -177.31593) (xy 9.087232 -177.324444)
			(xy 9.097772 -177.32502) (xy 9.172448 -177.32502) (xy 9.182995 -177.32447) (xy 9.20229 -177.315949)
			(xy 9.209786 -177.30851) (xy 9.229606 -177.287722) (xy 9.274378 -177.251747) (xy 9.324036 -177.222887)
			(xy 9.377458 -177.201794) (xy 9.433437 -177.188945) (xy 9.49071 -177.18463) (xy 9.547983 -177.188945)
			(xy 9.603962 -177.201794) (xy 9.657384 -177.222887) (xy 9.707042 -177.251747) (xy 9.751814 -177.287722)
			(xy 9.771634 -177.30851) (xy 9.77914 -177.31593) (xy 9.798432 -177.324444) (xy 9.808972 -177.32502)
			(xy 9.883648 -177.32502) (xy 9.894195 -177.32447) (xy 9.91349 -177.315949) (xy 9.920986 -177.30851)
			(xy 9.939157 -177.28947) (xy 9.979783 -177.256011) (xy 10.02462 -177.22845) (xy 10.072818 -177.207309)
			(xy 10.123463 -177.192988) (xy 10.175595 -177.18576) (xy 10.20191 -177.18532) (xy 10.229161 -177.18581)
			(xy 10.283109 -177.193566) (xy 10.335403 -177.208921) (xy 10.38498 -177.231562) (xy 10.43083 -177.261028)
			(xy 10.47202 -177.29672) (xy 10.507712 -177.33791) (xy 10.537178 -177.38376) (xy 10.559819 -177.433337)
			(xy 10.575174 -177.485631) (xy 10.58293 -177.539579) (xy 10.58293 -177.594081) (xy 10.575174 -177.648029)
			(xy 10.559819 -177.700323) (xy 10.537178 -177.7499) (xy 10.507712 -177.79575) (xy 10.47202 -177.83694)
			(xy 10.43083 -177.872632) (xy 10.38498 -177.902098) (xy 10.335403 -177.924739) (xy 10.283109 -177.940094)
			(xy 10.229161 -177.94785) (xy 10.20191 -177.948336) (xy 10.175597 -177.94785) (xy 10.12347 -177.940618)
			(xy 10.072828 -177.926301) (xy 10.024629 -177.905172) (xy 9.979785 -177.87763) (xy 9.939144 -177.844195)
			(xy 9.920986 -177.825146) (xy 9.913465 -177.817743) (xy 9.894185 -177.809218) (xy 9.883648 -177.808636)
			(xy 9.808972 -177.808636) (xy 9.798424 -177.80918) (xy 9.779127 -177.817703) (xy 9.771634 -177.825146)
			(xy 9.751814 -177.845934) (xy 9.707042 -177.881909) (xy 9.657384 -177.910769) (xy 9.603962 -177.931862)
			(xy 9.547983 -177.944711) (xy 9.49071 -177.949026) (xy 9.433437 -177.944711) (xy 9.377458 -177.931862)
			(xy 9.324036 -177.910769) (xy 9.274378 -177.881909) (xy 9.229606 -177.845934) (xy 9.209786 -177.825146)
			(xy 9.202265 -177.817743) (xy 9.182985 -177.809218) (xy 9.172448 -177.808636) (xy 9.097772 -177.808636)
			(xy 9.087224 -177.80918) (xy 9.067927 -177.817703) (xy 9.060434 -177.825146) (xy 9.042313 -177.844235)
			(xy 9.001674 -177.877688) (xy 8.956827 -177.905241) (xy 8.908619 -177.926373) (xy 8.857966 -177.940684)
			(xy 8.805828 -177.947901) (xy 8.77951 -177.948336) (xy 8.752259 -177.947854) (xy 8.698311 -177.940098)
			(xy 8.646016 -177.924742) (xy 8.596438 -177.902101) (xy 8.550587 -177.872635) (xy 8.509397 -177.836943)
			(xy 8.473705 -177.795753) (xy 8.444239 -177.749902) (xy 8.421598 -177.700324) (xy 8.406242 -177.648029)
			(xy 8.398486 -177.594081) (xy 4.421886 -177.594081) (xy 4.421886 -180.365908) (xy 28.064204 -180.365908)
			(xy 28.068275 -180.310286) (xy 28.080401 -180.255849) (xy 28.100324 -180.203758) (xy 28.12762 -180.155123)
			(xy 28.161706 -180.11098) (xy 28.201855 -180.072271) (xy 28.247213 -180.03982) (xy 28.296813 -180.014319)
			(xy 28.349597 -179.996312) (xy 28.40444 -179.986182) (xy 28.460174 -179.984145) (xy 28.515611 -179.990245)
			(xy 28.569568 -180.004351) (xy 28.620897 -180.026163) (xy 28.668503 -180.055217) (xy 28.711371 -180.090892)
			(xy 28.748588 -180.132429) (xy 28.779361 -180.178942) (xy 28.803033 -180.229439) (xy 28.819101 -180.282846)
			(xy 28.827221 -180.338022) (xy 28.82773 -180.365908) (xy 28.827221 -180.393794) (xy 28.819101 -180.44897)
			(xy 28.803033 -180.502377) (xy 28.779361 -180.552874) (xy 28.748588 -180.599387) (xy 28.711371 -180.640924)
			(xy 28.668503 -180.676599) (xy 28.620897 -180.705653) (xy 28.569568 -180.727465) (xy 28.515611 -180.741571)
			(xy 28.460174 -180.747671) (xy 28.40444 -180.745634) (xy 28.349597 -180.735504) (xy 28.296813 -180.717497)
			(xy 28.247213 -180.691996) (xy 28.201855 -180.659545) (xy 28.161706 -180.620836) (xy 28.12762 -180.576693)
			(xy 28.100324 -180.528058) (xy 28.080401 -180.475967) (xy 28.068275 -180.42153) (xy 28.064204 -180.365908)
			(xy 4.421886 -180.365908) (xy 4.421886 -191.783208) (xy 29.869128 -191.783208) (xy 29.873199 -191.727586)
			(xy 29.885325 -191.673149) (xy 29.905248 -191.621058) (xy 29.932544 -191.572423) (xy 29.96663 -191.52828)
			(xy 30.006779 -191.489571) (xy 30.052137 -191.45712) (xy 30.101737 -191.431619) (xy 30.154521 -191.413612)
			(xy 30.209364 -191.403482) (xy 30.265098 -191.401445) (xy 30.320535 -191.407545) (xy 30.374492 -191.421651)
			(xy 30.425821 -191.443463) (xy 30.473427 -191.472517) (xy 30.516295 -191.508192) (xy 30.553512 -191.549729)
			(xy 30.584285 -191.596242) (xy 30.607957 -191.646739) (xy 30.624025 -191.700146) (xy 30.632145 -191.755322)
			(xy 30.632654 -191.783208) (xy 30.632145 -191.811094) (xy 30.624025 -191.86627) (xy 30.607957 -191.919677)
			(xy 30.584285 -191.970174) (xy 30.553512 -192.016687) (xy 30.516295 -192.058224) (xy 30.473427 -192.093899)
			(xy 30.425821 -192.122953) (xy 30.374492 -192.144765) (xy 30.320535 -192.158871) (xy 30.265098 -192.164971)
			(xy 30.209364 -192.162934) (xy 30.154521 -192.152804) (xy 30.101737 -192.134797) (xy 30.052137 -192.109296)
			(xy 30.006779 -192.076845) (xy 29.96663 -192.038136) (xy 29.932544 -191.993993) (xy 29.905248 -191.945358)
			(xy 29.885325 -191.893267) (xy 29.873199 -191.83883) (xy 29.869128 -191.783208) (xy 4.421886 -191.783208)
			(xy 4.421886 -192.745614) (xy 30.161482 -192.745614) (xy 30.165553 -192.689992) (xy 30.177679 -192.635555)
			(xy 30.197602 -192.583464) (xy 30.224898 -192.534829) (xy 30.258984 -192.490686) (xy 30.299133 -192.451977)
			(xy 30.344491 -192.419526) (xy 30.394091 -192.394025) (xy 30.446875 -192.376018) (xy 30.501718 -192.365888)
			(xy 30.557452 -192.363851) (xy 30.612889 -192.369951) (xy 30.666846 -192.384057) (xy 30.718175 -192.405869)
			(xy 30.765781 -192.434923) (xy 30.808649 -192.470598) (xy 30.845866 -192.512135) (xy 30.876639 -192.558648)
			(xy 30.900311 -192.609145) (xy 30.916379 -192.662552) (xy 30.924499 -192.717728) (xy 30.925008 -192.745614)
			(xy 30.924499 -192.7735) (xy 30.916379 -192.828676) (xy 30.900311 -192.882083) (xy 30.876639 -192.93258)
			(xy 30.845866 -192.979093) (xy 30.808649 -193.02063) (xy 30.765781 -193.056305) (xy 30.718175 -193.085359)
			(xy 30.666846 -193.107171) (xy 30.612889 -193.121277) (xy 30.557452 -193.127377) (xy 30.501718 -193.12534)
			(xy 30.446875 -193.11521) (xy 30.394091 -193.097203) (xy 30.344491 -193.071702) (xy 30.299133 -193.039251)
			(xy 30.258984 -193.000542) (xy 30.224898 -192.956399) (xy 30.197602 -192.907764) (xy 30.177679 -192.855673)
			(xy 30.165553 -192.801236) (xy 30.161482 -192.745614) (xy 4.421886 -192.745614) (xy 4.421886 -202.41387)
			(xy 27.454096 -202.41387) (xy 27.458167 -202.358248) (xy 27.470293 -202.303811) (xy 27.490216 -202.25172)
			(xy 27.517512 -202.203085) (xy 27.551598 -202.158942) (xy 27.591747 -202.120233) (xy 27.637105 -202.087782)
			(xy 27.686705 -202.062281) (xy 27.739489 -202.044274) (xy 27.794332 -202.034144) (xy 27.850066 -202.032107)
			(xy 27.905503 -202.038207) (xy 27.95946 -202.052313) (xy 28.010789 -202.074125) (xy 28.058395 -202.103179)
			(xy 28.101263 -202.138854) (xy 28.13848 -202.180391) (xy 28.169253 -202.226904) (xy 28.192925 -202.277401)
			(xy 28.208993 -202.330808) (xy 28.217113 -202.385984) (xy 28.217395 -202.401424) (xy 28.448252 -202.401424)
			(xy 28.452323 -202.345802) (xy 28.464449 -202.291365) (xy 28.484372 -202.239274) (xy 28.511668 -202.190639)
			(xy 28.545754 -202.146496) (xy 28.585903 -202.107787) (xy 28.631261 -202.075336) (xy 28.680861 -202.049835)
			(xy 28.733645 -202.031828) (xy 28.788488 -202.021698) (xy 28.844222 -202.019661) (xy 28.899659 -202.025761)
			(xy 28.953616 -202.039867) (xy 29.004945 -202.061679) (xy 29.052551 -202.090733) (xy 29.095419 -202.126408)
			(xy 29.132636 -202.167945) (xy 29.163409 -202.214458) (xy 29.187081 -202.264955) (xy 29.203149 -202.318362)
			(xy 29.211269 -202.373538) (xy 29.211449 -202.38339) (xy 29.7086 -202.38339) (xy 29.712671 -202.327768)
			(xy 29.724797 -202.273331) (xy 29.74472 -202.22124) (xy 29.772016 -202.172605) (xy 29.806102 -202.128462)
			(xy 29.846251 -202.089753) (xy 29.891609 -202.057302) (xy 29.941209 -202.031801) (xy 29.993993 -202.013794)
			(xy 30.048836 -202.003664) (xy 30.10457 -202.001627) (xy 30.160007 -202.007727) (xy 30.213964 -202.021833)
			(xy 30.265293 -202.043645) (xy 30.312899 -202.072699) (xy 30.355767 -202.108374) (xy 30.392984 -202.149911)
			(xy 30.423757 -202.196424) (xy 30.447429 -202.246921) (xy 30.463497 -202.300328) (xy 30.471617 -202.355504)
			(xy 30.472126 -202.38339) (xy 30.471617 -202.411276) (xy 30.463497 -202.466452) (xy 30.447429 -202.519859)
			(xy 30.423757 -202.570356) (xy 30.392984 -202.616869) (xy 30.355767 -202.658406) (xy 30.312899 -202.694081)
			(xy 30.265293 -202.723135) (xy 30.213964 -202.744947) (xy 30.160007 -202.759053) (xy 30.10457 -202.765153)
			(xy 30.048836 -202.763116) (xy 29.993993 -202.752986) (xy 29.941209 -202.734979) (xy 29.891609 -202.709478)
			(xy 29.846251 -202.677027) (xy 29.806102 -202.638318) (xy 29.772016 -202.594175) (xy 29.74472 -202.54554)
			(xy 29.724797 -202.493449) (xy 29.712671 -202.439012) (xy 29.7086 -202.38339) (xy 29.211449 -202.38339)
			(xy 29.211778 -202.401424) (xy 29.211269 -202.42931) (xy 29.203149 -202.484486) (xy 29.187081 -202.537893)
			(xy 29.163409 -202.58839) (xy 29.132636 -202.634903) (xy 29.095419 -202.67644) (xy 29.052551 -202.712115)
			(xy 29.004945 -202.741169) (xy 28.953616 -202.762981) (xy 28.899659 -202.777087) (xy 28.844222 -202.783187)
			(xy 28.788488 -202.78115) (xy 28.733645 -202.77102) (xy 28.680861 -202.753013) (xy 28.631261 -202.727512)
			(xy 28.585903 -202.695061) (xy 28.545754 -202.656352) (xy 28.511668 -202.612209) (xy 28.484372 -202.563574)
			(xy 28.464449 -202.511483) (xy 28.452323 -202.457046) (xy 28.448252 -202.401424) (xy 28.217395 -202.401424)
			(xy 28.217622 -202.41387) (xy 28.217113 -202.441756) (xy 28.208993 -202.496932) (xy 28.192925 -202.550339)
			(xy 28.169253 -202.600836) (xy 28.13848 -202.647349) (xy 28.101263 -202.688886) (xy 28.058395 -202.724561)
			(xy 28.010789 -202.753615) (xy 27.95946 -202.775427) (xy 27.905503 -202.789533) (xy 27.850066 -202.795633)
			(xy 27.794332 -202.793596) (xy 27.739489 -202.783466) (xy 27.686705 -202.765459) (xy 27.637105 -202.739958)
			(xy 27.591747 -202.707507) (xy 27.551598 -202.668798) (xy 27.517512 -202.624655) (xy 27.490216 -202.57602)
			(xy 27.470293 -202.523929) (xy 27.458167 -202.469492) (xy 27.454096 -202.41387) (xy 4.421886 -202.41387)
			(xy 4.421886 -209.478372) (xy 18.503138 -209.478372) (xy 18.503575 -209.452057) (xy 18.510814 -209.399927)
			(xy 18.525138 -209.349283) (xy 18.546277 -209.301084) (xy 18.573829 -209.256241) (xy 18.607273 -209.215603)
			(xy 18.626328 -209.197448) (xy 18.633744 -209.189938) (xy 18.642263 -209.17065) (xy 18.642838 -209.16011)
			(xy 18.642838 -209.085434) (xy 18.642293 -209.074886) (xy 18.633768 -209.055592) (xy 18.626328 -209.048096)
			(xy 18.607283 -209.02993) (xy 18.573824 -208.989303) (xy 18.546263 -208.944465) (xy 18.525122 -208.896266)
			(xy 18.510803 -208.84562) (xy 18.503577 -208.793488) (xy 18.503138 -208.767172) (xy 18.503624 -208.739921)
			(xy 18.51138 -208.685973) (xy 18.526735 -208.633678) (xy 18.549377 -208.584101) (xy 18.578843 -208.538251)
			(xy 18.614534 -208.49706) (xy 18.655725 -208.461369) (xy 18.701575 -208.431903) (xy 18.751152 -208.409261)
			(xy 18.803447 -208.393906) (xy 18.857395 -208.38615) (xy 18.911897 -208.38615) (xy 18.965845 -208.393906)
			(xy 19.01814 -208.409261) (xy 19.067717 -208.431903) (xy 19.113567 -208.461369) (xy 19.154758 -208.49706)
			(xy 19.190449 -208.538251) (xy 19.219915 -208.584101) (xy 19.242557 -208.633678) (xy 19.257912 -208.685973)
			(xy 19.265668 -208.739921) (xy 19.266154 -208.767172) (xy 19.265749 -208.793488) (xy 19.263405 -208.810352)
			(xy 21.535388 -208.810352) (xy 21.539459 -208.75473) (xy 21.551585 -208.700293) (xy 21.571508 -208.648202)
			(xy 21.598804 -208.599567) (xy 21.63289 -208.555424) (xy 21.673039 -208.516715) (xy 21.718397 -208.484264)
			(xy 21.767997 -208.458763) (xy 21.820781 -208.440756) (xy 21.875624 -208.430626) (xy 21.931358 -208.428589)
			(xy 21.986795 -208.434689) (xy 22.040752 -208.448795) (xy 22.092081 -208.470607) (xy 22.139687 -208.499661)
			(xy 22.182555 -208.535336) (xy 22.219772 -208.576873) (xy 22.250545 -208.623386) (xy 22.274217 -208.673883)
			(xy 22.290285 -208.72729) (xy 22.298405 -208.782466) (xy 22.298914 -208.810352) (xy 22.298405 -208.838238)
			(xy 22.290285 -208.893414) (xy 22.274217 -208.946821) (xy 22.250545 -208.997318) (xy 22.219772 -209.043831)
			(xy 22.182555 -209.085368) (xy 22.139687 -209.121043) (xy 22.092081 -209.150097) (xy 22.040752 -209.171909)
			(xy 21.986795 -209.186015) (xy 21.931358 -209.192115) (xy 21.875624 -209.190078) (xy 21.820781 -209.179948)
			(xy 21.767997 -209.161941) (xy 21.718397 -209.13644) (xy 21.673039 -209.103989) (xy 21.63289 -209.06528)
			(xy 21.598804 -209.021137) (xy 21.571508 -208.972502) (xy 21.551585 -208.920411) (xy 21.539459 -208.865974)
			(xy 21.535388 -208.810352) (xy 19.263405 -208.810352) (xy 19.258504 -208.84562) (xy 19.244173 -208.896265)
			(xy 19.223029 -208.944464) (xy 19.195471 -208.989305) (xy 19.162021 -209.029942) (xy 19.142964 -209.048096)
			(xy 19.135572 -209.055626) (xy 19.12704 -209.074899) (xy 19.126454 -209.085434) (xy 19.126454 -209.16011)
			(xy 19.126978 -209.17066) (xy 19.135518 -209.189954) (xy 19.142964 -209.197448) (xy 19.162048 -209.215575)
			(xy 19.1955 -209.256212) (xy 19.223054 -209.301059) (xy 19.244187 -209.349265) (xy 19.258499 -209.399917)
			(xy 19.265718 -209.452054) (xy 19.266154 -209.478372) (xy 19.265668 -209.505623) (xy 19.257912 -209.559571)
			(xy 19.242557 -209.611866) (xy 19.219915 -209.661443) (xy 19.190449 -209.707293) (xy 19.154758 -209.748484)
			(xy 19.113567 -209.784175) (xy 19.067717 -209.813641) (xy 19.01814 -209.836283) (xy 18.965845 -209.851638)
			(xy 18.911897 -209.859394) (xy 18.857395 -209.859394) (xy 18.803447 -209.851638) (xy 18.751152 -209.836283)
			(xy 18.701575 -209.813641) (xy 18.655725 -209.784175) (xy 18.614534 -209.748484) (xy 18.578843 -209.707293)
			(xy 18.549377 -209.661443) (xy 18.526735 -209.611866) (xy 18.51138 -209.559571) (xy 18.503624 -209.505623)
			(xy 18.503138 -209.478372) (xy 4.421886 -209.478372) (xy 4.421886 -210.113372) (xy 13.854428 -210.113372)
			(xy 13.858499 -210.05775) (xy 13.870625 -210.003313) (xy 13.890548 -209.951222) (xy 13.917844 -209.902587)
			(xy 13.95193 -209.858444) (xy 13.992079 -209.819735) (xy 14.037437 -209.787284) (xy 14.087037 -209.761783)
			(xy 14.139821 -209.743776) (xy 14.194664 -209.733646) (xy 14.250398 -209.731609) (xy 14.305835 -209.737709)
			(xy 14.359792 -209.751815) (xy 14.411121 -209.773627) (xy 14.458727 -209.802681) (xy 14.501595 -209.838356)
			(xy 14.538812 -209.879893) (xy 14.569585 -209.926406) (xy 14.593257 -209.976903) (xy 14.609325 -210.03031)
			(xy 14.617445 -210.085486) (xy 14.617954 -210.113372) (xy 17.054828 -210.113372) (xy 17.058899 -210.05775)
			(xy 17.071025 -210.003313) (xy 17.090948 -209.951222) (xy 17.118244 -209.902587) (xy 17.15233 -209.858444)
			(xy 17.192479 -209.819735) (xy 17.237837 -209.787284) (xy 17.287437 -209.761783) (xy 17.340221 -209.743776)
			(xy 17.395064 -209.733646) (xy 17.450798 -209.731609) (xy 17.506235 -209.737709) (xy 17.560192 -209.751815)
			(xy 17.611521 -209.773627) (xy 17.659127 -209.802681) (xy 17.701995 -209.838356) (xy 17.739212 -209.879893)
			(xy 17.769985 -209.926406) (xy 17.793657 -209.976903) (xy 17.809725 -210.03031) (xy 17.817845 -210.085486)
			(xy 17.818354 -210.113372) (xy 17.81789 -210.138772) (xy 17.943828 -210.138772) (xy 17.947899 -210.08315)
			(xy 17.960025 -210.028713) (xy 17.979948 -209.976622) (xy 18.007244 -209.927987) (xy 18.04133 -209.883844)
			(xy 18.081479 -209.845135) (xy 18.126837 -209.812684) (xy 18.176437 -209.787183) (xy 18.229221 -209.769176)
			(xy 18.284064 -209.759046) (xy 18.339798 -209.757009) (xy 18.395235 -209.763109) (xy 18.449192 -209.777215)
			(xy 18.500521 -209.799027) (xy 18.548127 -209.828081) (xy 18.590995 -209.863756) (xy 18.628212 -209.905293)
			(xy 18.658985 -209.951806) (xy 18.682657 -210.002303) (xy 18.698725 -210.05571) (xy 18.706845 -210.110886)
			(xy 18.707354 -210.138772) (xy 18.706845 -210.166658) (xy 18.698725 -210.221834) (xy 18.682657 -210.275241)
			(xy 18.658985 -210.325738) (xy 18.628212 -210.372251) (xy 18.590995 -210.413788) (xy 18.548127 -210.449463)
			(xy 18.500521 -210.478517) (xy 18.449192 -210.500329) (xy 18.395235 -210.514435) (xy 18.339798 -210.520535)
			(xy 18.284064 -210.518498) (xy 18.229221 -210.508368) (xy 18.176437 -210.490361) (xy 18.126837 -210.46486)
			(xy 18.081479 -210.432409) (xy 18.04133 -210.3937) (xy 18.007244 -210.349557) (xy 17.979948 -210.300922)
			(xy 17.960025 -210.248831) (xy 17.947899 -210.194394) (xy 17.943828 -210.138772) (xy 17.81789 -210.138772)
			(xy 17.817845 -210.141258) (xy 17.809725 -210.196434) (xy 17.793657 -210.249841) (xy 17.769985 -210.300338)
			(xy 17.739212 -210.346851) (xy 17.701995 -210.388388) (xy 17.659127 -210.424063) (xy 17.611521 -210.453117)
			(xy 17.560192 -210.474929) (xy 17.506235 -210.489035) (xy 17.450798 -210.495135) (xy 17.395064 -210.493098)
			(xy 17.340221 -210.482968) (xy 17.287437 -210.464961) (xy 17.237837 -210.43946) (xy 17.192479 -210.407009)
			(xy 17.15233 -210.3683) (xy 17.118244 -210.324157) (xy 17.090948 -210.275522) (xy 17.071025 -210.223431)
			(xy 17.058899 -210.168994) (xy 17.054828 -210.113372) (xy 14.617954 -210.113372) (xy 14.617445 -210.141258)
			(xy 14.609325 -210.196434) (xy 14.593257 -210.249841) (xy 14.569585 -210.300338) (xy 14.538812 -210.346851)
			(xy 14.501595 -210.388388) (xy 14.458727 -210.424063) (xy 14.411121 -210.453117) (xy 14.359792 -210.474929)
			(xy 14.305835 -210.489035) (xy 14.250398 -210.495135) (xy 14.194664 -210.493098) (xy 14.139821 -210.482968)
			(xy 14.087037 -210.464961) (xy 14.037437 -210.43946) (xy 13.992079 -210.407009) (xy 13.95193 -210.3683)
			(xy 13.917844 -210.324157) (xy 13.890548 -210.275522) (xy 13.870625 -210.223431) (xy 13.858499 -210.168994)
			(xy 13.854428 -210.113372) (xy 4.421886 -210.113372) (xy 4.421886 -212.807621) (xy 11.31543 -212.807621)
			(xy 11.31543 -212.753119) (xy 11.323186 -212.699172) (xy 11.338541 -212.646878) (xy 11.361182 -212.597301)
			(xy 11.390647 -212.551451) (xy 11.426338 -212.510261) (xy 11.467528 -212.47457) (xy 11.513378 -212.445104)
			(xy 11.562954 -212.422462) (xy 11.615248 -212.407107) (xy 11.669195 -212.39935) (xy 11.696446 -212.398864)
			(xy 11.723692 -212.399293) (xy 11.777628 -212.407058) (xy 11.82991 -212.422422) (xy 11.879471 -212.445072)
			(xy 11.925303 -212.474548) (xy 11.966472 -212.510248) (xy 12.002139 -212.551446) (xy 12.017248 -212.574124)
			(xy 12.022086 -212.581157) (xy 12.035497 -212.591704) (xy 12.051641 -212.597224) (xy 12.060174 -212.597492)
			(xy 12.145518 -212.597492) (xy 12.154038 -212.597173) (xy 12.17015 -212.591625) (xy 12.18356 -212.581112)
			(xy 12.188444 -212.574124) (xy 12.203523 -212.551427) (xy 12.239196 -212.510233) (xy 12.280371 -212.474539)
			(xy 12.326209 -212.445071) (xy 12.375776 -212.42243) (xy 12.428061 -212.407077) (xy 12.482 -212.399324)
			(xy 12.509246 -212.398864) (xy 12.535223 -212.399266) (xy 12.586696 -212.406315) (xy 12.636734 -212.42029)
			(xy 12.684411 -212.440933) (xy 12.728842 -212.467859) (xy 12.769204 -212.500572) (xy 12.804749 -212.538463)
			(xy 12.820142 -212.559392) (xy 12.827792 -212.568866) (xy 12.84939 -212.580023) (xy 12.861544 -212.580728)
			(xy 12.944348 -212.580728) (xy 12.956512 -212.580046) (xy 12.978134 -212.568901) (xy 12.98575 -212.559392)
			(xy 13.001177 -212.538491) (xy 13.036724 -212.500612) (xy 13.077084 -212.467909) (xy 13.121509 -212.440987)
			(xy 13.169179 -212.420345) (xy 13.219208 -212.406366) (xy 13.270673 -212.399307) (xy 13.296646 -212.398864)
			(xy 13.323899 -212.399323) (xy 13.377851 -212.40708) (xy 13.430149 -212.422435) (xy 13.47973 -212.445078)
			(xy 13.525584 -212.474546) (xy 13.566778 -212.51024) (xy 13.602472 -212.551433) (xy 13.63194 -212.597286)
			(xy 13.654583 -212.646867) (xy 13.66994 -212.699165) (xy 13.677697 -212.753117) (xy 13.677697 -212.807623)
			(xy 13.66994 -212.861575) (xy 13.654583 -212.913873) (xy 13.63194 -212.963454) (xy 13.602472 -213.009307)
			(xy 13.566778 -213.0505) (xy 13.525584 -213.086194) (xy 13.47973 -213.115662) (xy 13.430149 -213.138305)
			(xy 13.377851 -213.15366) (xy 13.323899 -213.161417) (xy 13.296646 -213.16188) (xy 13.27067 -213.161466)
			(xy 13.219198 -213.154416) (xy 13.169161 -213.140442) (xy 13.121485 -213.119801) (xy 13.077054 -213.092877)
			(xy 13.036691 -213.060167) (xy 13.001144 -213.02228) (xy 12.98575 -213.001352) (xy 12.978115 -212.991864)
			(xy 12.956505 -212.980717) (xy 12.944348 -212.980016) (xy 12.861544 -212.980016) (xy 12.849383 -212.980715)
			(xy 12.827762 -212.99185) (xy 12.820142 -213.001352) (xy 12.804733 -213.022266) (xy 12.769182 -213.060143)
			(xy 12.728818 -213.092844) (xy 12.684389 -213.119763) (xy 12.636718 -213.140403) (xy 12.586686 -213.154381)
			(xy 12.53522 -213.161438) (xy 12.509246 -213.16188) (xy 12.482001 -213.161437) (xy 12.428066 -213.153672)
			(xy 12.375786 -213.138309) (xy 12.326225 -213.115661) (xy 12.280393 -213.086187) (xy 12.239223 -213.05049)
			(xy 12.203555 -213.009296) (xy 12.188444 -212.98662) (xy 12.183567 -212.979618) (xy 12.170172 -212.96907)
			(xy 12.154045 -212.963533) (xy 12.145518 -212.963252) (xy 12.060174 -212.963252) (xy 12.051656 -212.96359)
			(xy 12.035548 -212.969134) (xy 12.022136 -212.979637) (xy 12.017248 -212.98662) (xy 12.002156 -213.009308)
			(xy 11.966487 -213.050504) (xy 11.925315 -213.086201) (xy 11.879479 -213.115671) (xy 11.829914 -213.138314)
			(xy 11.77763 -213.153668) (xy 11.723692 -213.16142) (xy 11.696446 -213.16188) (xy 11.669195 -213.16139)
			(xy 11.615248 -213.153633) (xy 11.562954 -213.138278) (xy 11.513378 -213.115636) (xy 11.467528 -213.08617)
			(xy 11.426338 -213.050479) (xy 11.390647 -213.009289) (xy 11.361182 -212.963439) (xy 11.338541 -212.913862)
			(xy 11.323186 -212.861568) (xy 11.31543 -212.807621) (xy 4.421886 -212.807621) (xy 4.421886 -214.151972)
			(xy 13.219428 -214.151972) (xy 13.223499 -214.09635) (xy 13.235625 -214.041913) (xy 13.255548 -213.989822)
			(xy 13.282844 -213.941187) (xy 13.31693 -213.897044) (xy 13.357079 -213.858335) (xy 13.402437 -213.825884)
			(xy 13.452037 -213.800383) (xy 13.504821 -213.782376) (xy 13.559664 -213.772246) (xy 13.615398 -213.770209)
			(xy 13.670835 -213.776309) (xy 13.724792 -213.790415) (xy 13.776121 -213.812227) (xy 13.823727 -213.841281)
			(xy 13.866595 -213.876956) (xy 13.903812 -213.918493) (xy 13.934585 -213.965006) (xy 13.958257 -214.015503)
			(xy 13.974325 -214.06891) (xy 13.978026 -214.09406) (xy 18.591782 -214.09406) (xy 18.595853 -214.038438)
			(xy 18.607979 -213.984001) (xy 18.627902 -213.93191) (xy 18.655198 -213.883275) (xy 18.689284 -213.839132)
			(xy 18.729433 -213.800423) (xy 18.774791 -213.767972) (xy 18.824391 -213.742471) (xy 18.877175 -213.724464)
			(xy 18.932018 -213.714334) (xy 18.987752 -213.712297) (xy 19.043189 -213.718397) (xy 19.097146 -213.732503)
			(xy 19.148475 -213.754315) (xy 19.196081 -213.783369) (xy 19.238949 -213.819044) (xy 19.276166 -213.860581)
			(xy 19.306939 -213.907094) (xy 19.330611 -213.957591) (xy 19.346679 -214.010998) (xy 19.354799 -214.066174)
			(xy 19.355308 -214.09406) (xy 19.354799 -214.121946) (xy 19.346679 -214.177122) (xy 19.330611 -214.230529)
			(xy 19.306939 -214.281026) (xy 19.276166 -214.327539) (xy 19.238949 -214.369076) (xy 19.196081 -214.404751)
			(xy 19.148475 -214.433805) (xy 19.097146 -214.455617) (xy 19.043189 -214.469723) (xy 18.987752 -214.475823)
			(xy 18.932018 -214.473786) (xy 18.877175 -214.463656) (xy 18.824391 -214.445649) (xy 18.774791 -214.420148)
			(xy 18.729433 -214.387697) (xy 18.689284 -214.348988) (xy 18.655198 -214.304845) (xy 18.627902 -214.25621)
			(xy 18.607979 -214.204119) (xy 18.595853 -214.149682) (xy 18.591782 -214.09406) (xy 13.978026 -214.09406)
			(xy 13.982445 -214.124086) (xy 13.982954 -214.151972) (xy 13.982445 -214.179858) (xy 13.974325 -214.235034)
			(xy 13.958257 -214.288441) (xy 13.934585 -214.338938) (xy 13.903812 -214.385451) (xy 13.866595 -214.426988)
			(xy 13.823727 -214.462663) (xy 13.776121 -214.491717) (xy 13.724792 -214.513529) (xy 13.670835 -214.527635)
			(xy 13.615398 -214.533735) (xy 13.559664 -214.531698) (xy 13.504821 -214.521568) (xy 13.452037 -214.503561)
			(xy 13.402437 -214.47806) (xy 13.357079 -214.445609) (xy 13.31693 -214.4069) (xy 13.282844 -214.362757)
			(xy 13.255548 -214.314122) (xy 13.235625 -214.262031) (xy 13.223499 -214.207594) (xy 13.219428 -214.151972)
			(xy 4.421886 -214.151972) (xy 4.421886 -215.320372) (xy 17.156428 -215.320372) (xy 17.160499 -215.26475)
			(xy 17.172625 -215.210313) (xy 17.192548 -215.158222) (xy 17.219844 -215.109587) (xy 17.25393 -215.065444)
			(xy 17.294079 -215.026735) (xy 17.339437 -214.994284) (xy 17.389037 -214.968783) (xy 17.441821 -214.950776)
			(xy 17.496664 -214.940646) (xy 17.552398 -214.938609) (xy 17.607835 -214.944709) (xy 17.661792 -214.958815)
			(xy 17.713121 -214.980627) (xy 17.760727 -215.009681) (xy 17.803595 -215.045356) (xy 17.840812 -215.086893)
			(xy 17.871585 -215.133406) (xy 17.895257 -215.183903) (xy 17.911325 -215.23731) (xy 17.919445 -215.292486)
			(xy 17.919954 -215.320372) (xy 17.919445 -215.348258) (xy 17.911325 -215.403434) (xy 17.908193 -215.413844)
			(xy 21.5552 -215.413844) (xy 21.559271 -215.358222) (xy 21.571397 -215.303785) (xy 21.59132 -215.251694)
			(xy 21.618616 -215.203059) (xy 21.652702 -215.158916) (xy 21.692851 -215.120207) (xy 21.738209 -215.087756)
			(xy 21.787809 -215.062255) (xy 21.840593 -215.044248) (xy 21.895436 -215.034118) (xy 21.95117 -215.032081)
			(xy 22.006607 -215.038181) (xy 22.060564 -215.052287) (xy 22.111893 -215.074099) (xy 22.159499 -215.103153)
			(xy 22.202367 -215.138828) (xy 22.239584 -215.180365) (xy 22.270357 -215.226878) (xy 22.294029 -215.277375)
			(xy 22.310097 -215.330782) (xy 22.318217 -215.385958) (xy 22.318726 -215.413844) (xy 22.318217 -215.44173)
			(xy 22.310097 -215.496906) (xy 22.294029 -215.550313) (xy 22.270357 -215.60081) (xy 22.239584 -215.647323)
			(xy 22.202367 -215.68886) (xy 22.159499 -215.724535) (xy 22.111893 -215.753589) (xy 22.060564 -215.775401)
			(xy 22.006607 -215.789507) (xy 21.95117 -215.795607) (xy 21.895436 -215.79357) (xy 21.840593 -215.78344)
			(xy 21.787809 -215.765433) (xy 21.738209 -215.739932) (xy 21.692851 -215.707481) (xy 21.652702 -215.668772)
			(xy 21.618616 -215.624629) (xy 21.59132 -215.575994) (xy 21.571397 -215.523903) (xy 21.559271 -215.469466)
			(xy 21.5552 -215.413844) (xy 17.908193 -215.413844) (xy 17.895257 -215.456841) (xy 17.871585 -215.507338)
			(xy 17.840812 -215.553851) (xy 17.803595 -215.595388) (xy 17.760727 -215.631063) (xy 17.713121 -215.660117)
			(xy 17.661792 -215.681929) (xy 17.607835 -215.696035) (xy 17.552398 -215.702135) (xy 17.496664 -215.700098)
			(xy 17.441821 -215.689968) (xy 17.389037 -215.671961) (xy 17.339437 -215.64646) (xy 17.294079 -215.614009)
			(xy 17.25393 -215.5753) (xy 17.219844 -215.531157) (xy 17.192548 -215.482522) (xy 17.172625 -215.430431)
			(xy 17.160499 -215.375994) (xy 17.156428 -215.320372) (xy 4.421886 -215.320372) (xy 4.421886 -216.082372)
			(xy 16.267428 -216.082372) (xy 16.271499 -216.02675) (xy 16.283625 -215.972313) (xy 16.303548 -215.920222)
			(xy 16.330844 -215.871587) (xy 16.36493 -215.827444) (xy 16.405079 -215.788735) (xy 16.450437 -215.756284)
			(xy 16.500037 -215.730783) (xy 16.552821 -215.712776) (xy 16.607664 -215.702646) (xy 16.663398 -215.700609)
			(xy 16.718835 -215.706709) (xy 16.772792 -215.720815) (xy 16.824121 -215.742627) (xy 16.871727 -215.771681)
			(xy 16.914595 -215.807356) (xy 16.951812 -215.848893) (xy 16.982585 -215.895406) (xy 17.006257 -215.945903)
			(xy 17.022325 -215.99931) (xy 17.030445 -216.054486) (xy 17.030954 -216.082372) (xy 17.030445 -216.110258)
			(xy 17.022325 -216.165434) (xy 17.006257 -216.218841) (xy 16.982585 -216.269338) (xy 16.951812 -216.315851)
			(xy 16.914595 -216.357388) (xy 16.871727 -216.393063) (xy 16.824121 -216.422117) (xy 16.772792 -216.443929)
			(xy 16.718835 -216.458035) (xy 16.663398 -216.464135) (xy 16.607664 -216.462098) (xy 16.552821 -216.451968)
			(xy 16.500037 -216.433961) (xy 16.450437 -216.40846) (xy 16.405079 -216.376009) (xy 16.36493 -216.3373)
			(xy 16.330844 -216.293157) (xy 16.303548 -216.244522) (xy 16.283625 -216.192431) (xy 16.271499 -216.137994)
			(xy 16.267428 -216.082372) (xy 4.421886 -216.082372) (xy 4.421886 -217.81516) (xy 30.71622 -217.81516)
			(xy 30.716641 -217.787906) (xy 30.724403 -217.733955) (xy 30.739765 -217.681657) (xy 30.762413 -217.632078)
			(xy 30.791886 -217.586227) (xy 30.827584 -217.545036) (xy 30.868781 -217.509345) (xy 30.914638 -217.47988)
			(xy 30.964221 -217.457241) (xy 31.016522 -217.441889) (xy 31.070474 -217.434136) (xy 31.097728 -217.433652)
			(xy 31.125673 -217.434113) (xy 31.180965 -217.442279) (xy 31.234476 -217.458416) (xy 31.285063 -217.482181)
			(xy 31.331646 -217.513066) (xy 31.373229 -217.55041) (xy 31.408925 -217.593418) (xy 31.423864 -217.61704)
			(xy 31.428709 -217.624326) (xy 31.442307 -217.63532) (xy 31.458807 -217.64111) (xy 31.467552 -217.641424)
			(xy 31.554928 -217.640916) (xy 31.563671 -217.640477) (xy 31.580114 -217.634513) (xy 31.593587 -217.623359)
			(xy 31.598362 -217.616024) (xy 31.598362 -217.61577) (xy 31.613144 -217.591569) (xy 31.648752 -217.547435)
			(xy 31.690503 -217.509062) (xy 31.737477 -217.477295) (xy 31.788638 -217.452835) (xy 31.842857 -217.436222)
			(xy 31.898938 -217.427822) (xy 31.927292 -217.427302) (xy 31.954546 -217.427744) (xy 32.008499 -217.435501)
			(xy 32.060799 -217.450856) (xy 32.110382 -217.473499) (xy 32.156237 -217.502968) (xy 32.197432 -217.538662)
			(xy 32.233128 -217.579856) (xy 32.262597 -217.625711) (xy 32.285241 -217.675293) (xy 32.300598 -217.727593)
			(xy 32.308355 -217.781546) (xy 32.308355 -217.808556) (xy 32.553146 -217.808556) (xy 32.557217 -217.752934)
			(xy 32.569343 -217.698497) (xy 32.589266 -217.646406) (xy 32.616562 -217.597771) (xy 32.650648 -217.553628)
			(xy 32.690797 -217.514919) (xy 32.736155 -217.482468) (xy 32.785755 -217.456967) (xy 32.838539 -217.43896)
			(xy 32.893382 -217.42883) (xy 32.949116 -217.426793) (xy 33.004553 -217.432893) (xy 33.05851 -217.446999)
			(xy 33.109839 -217.468811) (xy 33.157445 -217.497865) (xy 33.200313 -217.53354) (xy 33.23753 -217.575077)
			(xy 33.268303 -217.62159) (xy 33.291975 -217.672087) (xy 33.308043 -217.725494) (xy 33.31238 -217.754962)
			(xy 33.507678 -217.754962) (xy 33.511749 -217.69934) (xy 33.523875 -217.644903) (xy 33.543798 -217.592812)
			(xy 33.571094 -217.544177) (xy 33.60518 -217.500034) (xy 33.645329 -217.461325) (xy 33.690687 -217.428874)
			(xy 33.740287 -217.403373) (xy 33.793071 -217.385366) (xy 33.847914 -217.375236) (xy 33.903648 -217.373199)
			(xy 33.959085 -217.379299) (xy 34.013042 -217.393405) (xy 34.064371 -217.415217) (xy 34.111977 -217.444271)
			(xy 34.154845 -217.479946) (xy 34.192062 -217.521483) (xy 34.222835 -217.567996) (xy 34.246507 -217.618493)
			(xy 34.262575 -217.6719) (xy 34.270695 -217.727076) (xy 34.27093 -217.739976) (xy 34.38093 -217.739976)
			(xy 34.385001 -217.684354) (xy 34.397127 -217.629917) (xy 34.41705 -217.577826) (xy 34.444346 -217.529191)
			(xy 34.478432 -217.485048) (xy 34.518581 -217.446339) (xy 34.563939 -217.413888) (xy 34.613539 -217.388387)
			(xy 34.666323 -217.37038) (xy 34.721166 -217.36025) (xy 34.7769 -217.358213) (xy 34.832337 -217.364313)
			(xy 34.886294 -217.378419) (xy 34.937623 -217.400231) (xy 34.985229 -217.429285) (xy 35.028097 -217.46496)
			(xy 35.065314 -217.506497) (xy 35.096087 -217.55301) (xy 35.119759 -217.603507) (xy 35.135827 -217.656914)
			(xy 35.143947 -217.71209) (xy 35.144456 -217.739976) (xy 35.143947 -217.767862) (xy 35.135827 -217.823038)
			(xy 35.119759 -217.876445) (xy 35.096087 -217.926942) (xy 35.065314 -217.973455) (xy 35.028097 -218.014992)
			(xy 34.985229 -218.050667) (xy 34.937623 -218.079721) (xy 34.886294 -218.101533) (xy 34.832337 -218.115639)
			(xy 34.7769 -218.121739) (xy 34.721166 -218.119702) (xy 34.666323 -218.109572) (xy 34.613539 -218.091565)
			(xy 34.563939 -218.066064) (xy 34.518581 -218.033613) (xy 34.478432 -217.994904) (xy 34.444346 -217.950761)
			(xy 34.41705 -217.902126) (xy 34.397127 -217.850035) (xy 34.385001 -217.795598) (xy 34.38093 -217.739976)
			(xy 34.27093 -217.739976) (xy 34.271204 -217.754962) (xy 34.270695 -217.782848) (xy 34.262575 -217.838024)
			(xy 34.246507 -217.891431) (xy 34.222835 -217.941928) (xy 34.192062 -217.988441) (xy 34.154845 -218.029978)
			(xy 34.111977 -218.065653) (xy 34.064371 -218.094707) (xy 34.013042 -218.116519) (xy 33.959085 -218.130625)
			(xy 33.903648 -218.136725) (xy 33.847914 -218.134688) (xy 33.793071 -218.124558) (xy 33.740287 -218.106551)
			(xy 33.690687 -218.08105) (xy 33.645329 -218.048599) (xy 33.60518 -218.00989) (xy 33.571094 -217.965747)
			(xy 33.543798 -217.917112) (xy 33.523875 -217.865021) (xy 33.511749 -217.810584) (xy 33.507678 -217.754962)
			(xy 33.31238 -217.754962) (xy 33.316163 -217.78067) (xy 33.316672 -217.808556) (xy 33.316163 -217.836442)
			(xy 33.308043 -217.891618) (xy 33.291975 -217.945025) (xy 33.268303 -217.995522) (xy 33.23753 -218.042035)
			(xy 33.200313 -218.083572) (xy 33.157445 -218.119247) (xy 33.109839 -218.148301) (xy 33.05851 -218.170113)
			(xy 33.004553 -218.184219) (xy 32.949116 -218.190319) (xy 32.893382 -218.188282) (xy 32.838539 -218.178152)
			(xy 32.785755 -218.160145) (xy 32.736155 -218.134644) (xy 32.690797 -218.102193) (xy 32.650648 -218.063484)
			(xy 32.616562 -218.019341) (xy 32.589266 -217.970706) (xy 32.569343 -217.918615) (xy 32.557217 -217.864178)
			(xy 32.553146 -217.808556) (xy 32.308355 -217.808556) (xy 32.308355 -217.836054) (xy 32.300598 -217.890007)
			(xy 32.285241 -217.942307) (xy 32.262597 -217.991889) (xy 32.233128 -218.037744) (xy 32.197432 -218.078938)
			(xy 32.156237 -218.114632) (xy 32.110382 -218.144101) (xy 32.060799 -218.166744) (xy 32.008499 -218.182099)
			(xy 31.954546 -218.189856) (xy 31.927292 -218.190318) (xy 31.899346 -218.189855) (xy 31.844054 -218.181692)
			(xy 31.790543 -218.165556) (xy 31.739955 -218.141792) (xy 31.693372 -218.110907) (xy 31.651789 -218.073561)
			(xy 31.616094 -218.030553) (xy 31.601156 -218.00693) (xy 31.596308 -217.999647) (xy 31.58271 -217.988655)
			(xy 31.566212 -217.982863) (xy 31.557468 -217.982546) (xy 31.470092 -217.983054) (xy 31.461345 -217.983451)
			(xy 31.444903 -217.989437) (xy 31.431432 -218.000605) (xy 31.426658 -218.007946) (xy 31.426658 -218.0082)
			(xy 31.410572 -218.034504) (xy 31.371249 -218.08199) (xy 31.32478 -218.12251) (xy 31.298896 -218.139264)
			(xy 31.291714 -218.144076) (xy 31.280856 -218.157514) (xy 31.275105 -218.173805) (xy 31.274766 -218.182444)
			(xy 31.27502 -218.282266) (xy 31.28772 -218.305126) (xy 31.29915 -218.311984) (xy 31.322518 -218.327)
			(xy 31.365081 -218.362688) (xy 31.402018 -218.404171) (xy 31.432549 -218.450571) (xy 31.456029 -218.500909)
			(xy 31.471961 -218.554119) (xy 31.480009 -218.609078) (xy 31.480506 -218.63685) (xy 31.48002 -218.664101)
			(xy 31.472264 -218.718049) (xy 31.456909 -218.770344) (xy 31.434267 -218.819921) (xy 31.404801 -218.865771)
			(xy 31.36911 -218.906962) (xy 31.327919 -218.942653) (xy 31.282069 -218.972119) (xy 31.232492 -218.994761)
			(xy 31.180197 -219.010116) (xy 31.126249 -219.017872) (xy 31.071747 -219.017872) (xy 31.017799 -219.010116)
			(xy 30.965504 -218.994761) (xy 30.915927 -218.972119) (xy 30.870077 -218.942653) (xy 30.828886 -218.906962)
			(xy 30.793195 -218.865771) (xy 30.763729 -218.819921) (xy 30.741087 -218.770344) (xy 30.725732 -218.718049)
			(xy 30.717976 -218.664101) (xy 30.71749 -218.63685) (xy 30.717963 -218.609171) (xy 30.725982 -218.554398)
			(xy 30.741831 -218.501358) (xy 30.765176 -218.451164) (xy 30.795529 -218.404869) (xy 30.832251 -218.363446)
			(xy 30.874573 -218.327762) (xy 30.89783 -218.312746) (xy 30.905013 -218.307936) (xy 30.915869 -218.294496)
			(xy 30.921621 -218.278205) (xy 30.92196 -218.269566) (xy 30.921706 -218.169744) (xy 30.909006 -218.146884)
			(xy 30.897576 -218.140026) (xy 30.874195 -218.125029) (xy 30.831636 -218.089335) (xy 30.794702 -218.047848)
			(xy 30.764174 -218.001444) (xy 30.740696 -217.951104) (xy 30.724765 -217.897892) (xy 30.716717 -217.842933)
			(xy 30.71622 -217.81516) (xy 4.421886 -217.81516) (xy 4.421886 -218.29141) (xy 17.041874 -218.29141)
			(xy 17.045945 -218.235788) (xy 17.058071 -218.181351) (xy 17.077994 -218.12926) (xy 17.10529 -218.080625)
			(xy 17.139376 -218.036482) (xy 17.179525 -217.997773) (xy 17.224883 -217.965322) (xy 17.274483 -217.939821)
			(xy 17.327267 -217.921814) (xy 17.38211 -217.911684) (xy 17.437844 -217.909647) (xy 17.493281 -217.915747)
			(xy 17.547238 -217.929853) (xy 17.598567 -217.951665) (xy 17.646173 -217.980719) (xy 17.689041 -218.016394)
			(xy 17.726258 -218.057931) (xy 17.757031 -218.104444) (xy 17.780703 -218.154941) (xy 17.796771 -218.208348)
			(xy 17.804891 -218.263524) (xy 17.8054 -218.29141) (xy 17.804891 -218.319296) (xy 17.796771 -218.374472)
			(xy 17.780703 -218.427879) (xy 17.757031 -218.478376) (xy 17.726258 -218.524889) (xy 17.689041 -218.566426)
			(xy 17.646173 -218.602101) (xy 17.598567 -218.631155) (xy 17.547238 -218.652967) (xy 17.493281 -218.667073)
			(xy 17.437844 -218.673173) (xy 17.38211 -218.671136) (xy 17.327267 -218.661006) (xy 17.274483 -218.642999)
			(xy 17.224883 -218.617498) (xy 17.179525 -218.585047) (xy 17.139376 -218.546338) (xy 17.10529 -218.502195)
			(xy 17.077994 -218.45356) (xy 17.058071 -218.401469) (xy 17.045945 -218.347032) (xy 17.041874 -218.29141)
			(xy 4.421886 -218.29141) (xy 4.421886 -220.84665) (xy 15.866108 -220.84665) (xy 15.870179 -220.791028)
			(xy 15.882305 -220.736591) (xy 15.902228 -220.6845) (xy 15.929524 -220.635865) (xy 15.96361 -220.591722)
			(xy 16.003759 -220.553013) (xy 16.049117 -220.520562) (xy 16.098717 -220.495061) (xy 16.151501 -220.477054)
			(xy 16.206344 -220.466924) (xy 16.262078 -220.464887) (xy 16.317515 -220.470987) (xy 16.371472 -220.485093)
			(xy 16.422801 -220.506905) (xy 16.451343 -220.524324) (xy 25.975562 -220.524324) (xy 25.979633 -220.468702)
			(xy 25.991759 -220.414265) (xy 26.011682 -220.362174) (xy 26.038978 -220.313539) (xy 26.073064 -220.269396)
			(xy 26.113213 -220.230687) (xy 26.158571 -220.198236) (xy 26.208171 -220.172735) (xy 26.260955 -220.154728)
			(xy 26.315798 -220.144598) (xy 26.371532 -220.142561) (xy 26.426969 -220.148661) (xy 26.480926 -220.162767)
			(xy 26.532255 -220.184579) (xy 26.579861 -220.213633) (xy 26.622729 -220.249308) (xy 26.659946 -220.290845)
			(xy 26.690719 -220.337358) (xy 26.714391 -220.387855) (xy 26.730459 -220.441262) (xy 26.738579 -220.496438)
			(xy 26.739088 -220.524324) (xy 26.738579 -220.55221) (xy 26.730459 -220.607386) (xy 26.714391 -220.660793)
			(xy 26.690719 -220.71129) (xy 26.659946 -220.757803) (xy 26.622729 -220.79934) (xy 26.579861 -220.835015)
			(xy 26.532255 -220.864069) (xy 26.480926 -220.885881) (xy 26.426969 -220.899987) (xy 26.371532 -220.906087)
			(xy 26.315798 -220.90405) (xy 26.260955 -220.89392) (xy 26.208171 -220.875913) (xy 26.158571 -220.850412)
			(xy 26.113213 -220.817961) (xy 26.073064 -220.779252) (xy 26.038978 -220.735109) (xy 26.011682 -220.686474)
			(xy 25.991759 -220.634383) (xy 25.979633 -220.579946) (xy 25.975562 -220.524324) (xy 16.451343 -220.524324)
			(xy 16.470407 -220.535959) (xy 16.513275 -220.571634) (xy 16.550492 -220.613171) (xy 16.581265 -220.659684)
			(xy 16.604937 -220.710181) (xy 16.621005 -220.763588) (xy 16.629125 -220.818764) (xy 16.629634 -220.84665)
			(xy 16.629125 -220.874536) (xy 16.621005 -220.929712) (xy 16.604937 -220.983119) (xy 16.581265 -221.033616)
			(xy 16.550492 -221.080129) (xy 16.513275 -221.121666) (xy 16.470407 -221.157341) (xy 16.422801 -221.186395)
			(xy 16.371472 -221.208207) (xy 16.317515 -221.222313) (xy 16.262078 -221.228413) (xy 16.206344 -221.226376)
			(xy 16.151501 -221.216246) (xy 16.098717 -221.198239) (xy 16.049117 -221.172738) (xy 16.003759 -221.140287)
			(xy 15.96361 -221.101578) (xy 15.929524 -221.057435) (xy 15.902228 -221.0088) (xy 15.882305 -220.956709)
			(xy 15.870179 -220.902272) (xy 15.866108 -220.84665) (xy 4.421886 -220.84665) (xy 4.421886 -221.332806)
			(xy 22.477982 -221.332806) (xy 22.482053 -221.277184) (xy 22.494179 -221.222747) (xy 22.514102 -221.170656)
			(xy 22.541398 -221.122021) (xy 22.575484 -221.077878) (xy 22.615633 -221.039169) (xy 22.660991 -221.006718)
			(xy 22.710591 -220.981217) (xy 22.763375 -220.96321) (xy 22.818218 -220.95308) (xy 22.873952 -220.951043)
			(xy 22.929389 -220.957143) (xy 22.983346 -220.971249) (xy 23.034675 -220.993061) (xy 23.082281 -221.022115)
			(xy 23.125149 -221.05779) (xy 23.162366 -221.099327) (xy 23.193139 -221.14584) (xy 23.216811 -221.196337)
			(xy 23.232879 -221.249744) (xy 23.240999 -221.30492) (xy 23.241508 -221.332806) (xy 23.240999 -221.360692)
			(xy 23.232879 -221.415868) (xy 23.216811 -221.469275) (xy 23.193139 -221.519772) (xy 23.162366 -221.566285)
			(xy 23.125149 -221.607822) (xy 23.082281 -221.643497) (xy 23.034675 -221.672551) (xy 22.983346 -221.694363)
			(xy 22.929389 -221.708469) (xy 22.873952 -221.714569) (xy 22.818218 -221.712532) (xy 22.763375 -221.702402)
			(xy 22.710591 -221.684395) (xy 22.660991 -221.658894) (xy 22.615633 -221.626443) (xy 22.575484 -221.587734)
			(xy 22.541398 -221.543591) (xy 22.514102 -221.494956) (xy 22.494179 -221.442865) (xy 22.482053 -221.388428)
			(xy 22.477982 -221.332806) (xy 4.421886 -221.332806) (xy 4.421886 -222.172276) (xy 15.856202 -222.172276)
			(xy 15.860273 -222.116654) (xy 15.872399 -222.062217) (xy 15.892322 -222.010126) (xy 15.919618 -221.961491)
			(xy 15.953704 -221.917348) (xy 15.993853 -221.878639) (xy 16.039211 -221.846188) (xy 16.088811 -221.820687)
			(xy 16.141595 -221.80268) (xy 16.196438 -221.79255) (xy 16.252172 -221.790513) (xy 16.307609 -221.796613)
			(xy 16.361566 -221.810719) (xy 16.412895 -221.832531) (xy 16.460501 -221.861585) (xy 16.503369 -221.89726)
			(xy 16.540586 -221.938797) (xy 16.548351 -221.950534) (xy 17.087594 -221.950534) (xy 17.091665 -221.894912)
			(xy 17.103791 -221.840475) (xy 17.123714 -221.788384) (xy 17.15101 -221.739749) (xy 17.185096 -221.695606)
			(xy 17.225245 -221.656897) (xy 17.270603 -221.624446) (xy 17.320203 -221.598945) (xy 17.372987 -221.580938)
			(xy 17.42783 -221.570808) (xy 17.483564 -221.568771) (xy 17.539001 -221.574871) (xy 17.592958 -221.588977)
			(xy 17.644287 -221.610789) (xy 17.691893 -221.639843) (xy 17.734761 -221.675518) (xy 17.771978 -221.717055)
			(xy 17.802751 -221.763568) (xy 17.826423 -221.814065) (xy 17.842491 -221.867472) (xy 17.850611 -221.922648)
			(xy 17.85112 -221.950534) (xy 17.850611 -221.97842) (xy 17.842491 -222.033596) (xy 17.833398 -222.063818)
			(xy 25.616662 -222.063818) (xy 25.617148 -222.036567) (xy 25.624904 -221.982619) (xy 25.640259 -221.930324)
			(xy 25.662901 -221.880747) (xy 25.692367 -221.834897) (xy 25.728058 -221.793706) (xy 25.769249 -221.758015)
			(xy 25.815099 -221.728549) (xy 25.864676 -221.705907) (xy 25.916971 -221.690552) (xy 25.970919 -221.682796)
			(xy 26.025421 -221.682796) (xy 26.079369 -221.690552) (xy 26.131664 -221.705907) (xy 26.181241 -221.728549)
			(xy 26.227091 -221.758015) (xy 26.268282 -221.793706) (xy 26.303973 -221.834897) (xy 26.333439 -221.880747)
			(xy 26.356081 -221.930324) (xy 26.371436 -221.982619) (xy 26.379192 -222.036567) (xy 26.379678 -222.063818)
			(xy 26.379197 -222.090681) (xy 26.371658 -222.143877) (xy 26.356731 -222.195488) (xy 26.334711 -222.244495)
			(xy 26.306034 -222.289929) (xy 26.289 -222.310706) (xy 26.28138 -222.319596) (xy 26.275538 -222.342202)
			(xy 26.296112 -222.443548) (xy 26.310336 -222.46209) (xy 26.320496 -222.46717) (xy 26.343793 -222.479423)
			(xy 26.387068 -222.509392) (xy 26.425814 -222.545024) (xy 26.459295 -222.585642) (xy 26.486876 -222.630476)
			(xy 26.508034 -222.678676) (xy 26.522367 -222.729326) (xy 26.529603 -222.781465) (xy 26.530046 -222.807784)
			(xy 26.52956 -222.835035) (xy 26.521804 -222.888983) (xy 26.506449 -222.941278) (xy 26.483807 -222.990855)
			(xy 26.454341 -223.036705) (xy 26.41865 -223.077896) (xy 26.377459 -223.113587) (xy 26.331609 -223.143053)
			(xy 26.282032 -223.165695) (xy 26.229737 -223.18105) (xy 26.175789 -223.188806) (xy 26.121287 -223.188806)
			(xy 26.067339 -223.18105) (xy 26.015044 -223.165695) (xy 25.965467 -223.143053) (xy 25.919617 -223.113587)
			(xy 25.878426 -223.077896) (xy 25.842735 -223.036705) (xy 25.813269 -222.990855) (xy 25.790627 -222.941278)
			(xy 25.775272 -222.888983) (xy 25.767516 -222.835035) (xy 25.76703 -222.807784) (xy 25.767476 -222.78092)
			(xy 25.775027 -222.727724) (xy 25.789964 -222.676113) (xy 25.81199 -222.627106) (xy 25.840672 -222.581673)
			(xy 25.857708 -222.560896) (xy 25.865328 -222.552006) (xy 25.87117 -222.5294) (xy 25.850596 -222.428054)
			(xy 25.836372 -222.409512) (xy 25.826212 -222.404432) (xy 25.802918 -222.392174) (xy 25.759643 -222.362206)
			(xy 25.720897 -222.326575) (xy 25.687415 -222.285958) (xy 25.659833 -222.241124) (xy 25.638675 -222.192925)
			(xy 25.624341 -222.142276) (xy 25.617105 -222.090137) (xy 25.616662 -222.063818) (xy 17.833398 -222.063818)
			(xy 17.826423 -222.087003) (xy 17.802751 -222.1375) (xy 17.771978 -222.184013) (xy 17.734761 -222.22555)
			(xy 17.691893 -222.261225) (xy 17.644287 -222.290279) (xy 17.592958 -222.312091) (xy 17.539001 -222.326197)
			(xy 17.483564 -222.332297) (xy 17.42783 -222.33026) (xy 17.372987 -222.32013) (xy 17.320203 -222.302123)
			(xy 17.270603 -222.276622) (xy 17.225245 -222.244171) (xy 17.185096 -222.205462) (xy 17.15101 -222.161319)
			(xy 17.123714 -222.112684) (xy 17.103791 -222.060593) (xy 17.091665 -222.006156) (xy 17.087594 -221.950534)
			(xy 16.548351 -221.950534) (xy 16.571359 -221.98531) (xy 16.595031 -222.035807) (xy 16.611099 -222.089214)
			(xy 16.619219 -222.14439) (xy 16.619728 -222.172276) (xy 16.619219 -222.200162) (xy 16.611099 -222.255338)
			(xy 16.595031 -222.308745) (xy 16.571359 -222.359242) (xy 16.540586 -222.405755) (xy 16.503369 -222.447292)
			(xy 16.460501 -222.482967) (xy 16.412895 -222.512021) (xy 16.361566 -222.533833) (xy 16.307609 -222.547939)
			(xy 16.252172 -222.554039) (xy 16.196438 -222.552002) (xy 16.141595 -222.541872) (xy 16.088811 -222.523865)
			(xy 16.039211 -222.498364) (xy 15.993853 -222.465913) (xy 15.953704 -222.427204) (xy 15.919618 -222.383061)
			(xy 15.892322 -222.334426) (xy 15.872399 -222.282335) (xy 15.860273 -222.227898) (xy 15.856202 -222.172276)
			(xy 4.421886 -222.172276) (xy 4.421886 -223.147382) (xy 19.056094 -223.147382) (xy 19.060165 -223.09176)
			(xy 19.072291 -223.037323) (xy 19.092214 -222.985232) (xy 19.11951 -222.936597) (xy 19.153596 -222.892454)
			(xy 19.193745 -222.853745) (xy 19.239103 -222.821294) (xy 19.288703 -222.795793) (xy 19.341487 -222.777786)
			(xy 19.39633 -222.767656) (xy 19.452064 -222.765619) (xy 19.507501 -222.771719) (xy 19.561458 -222.785825)
			(xy 19.612787 -222.807637) (xy 19.660393 -222.836691) (xy 19.703261 -222.872366) (xy 19.740478 -222.913903)
			(xy 19.771251 -222.960416) (xy 19.794923 -223.010913) (xy 19.810991 -223.06432) (xy 19.813982 -223.084644)
			(xy 21.0472 -223.084644) (xy 21.051271 -223.029022) (xy 21.063397 -222.974585) (xy 21.08332 -222.922494)
			(xy 21.110616 -222.873859) (xy 21.144702 -222.829716) (xy 21.184851 -222.791007) (xy 21.230209 -222.758556)
			(xy 21.279809 -222.733055) (xy 21.332593 -222.715048) (xy 21.387436 -222.704918) (xy 21.44317 -222.702881)
			(xy 21.498607 -222.708981) (xy 21.552564 -222.723087) (xy 21.603893 -222.744899) (xy 21.651499 -222.773953)
			(xy 21.694367 -222.809628) (xy 21.731584 -222.851165) (xy 21.762357 -222.897678) (xy 21.786029 -222.948175)
			(xy 21.802097 -223.001582) (xy 21.810217 -223.056758) (xy 21.810726 -223.084644) (xy 21.810217 -223.11253)
			(xy 21.802097 -223.167706) (xy 21.786029 -223.221113) (xy 21.762357 -223.27161) (xy 21.731584 -223.318123)
			(xy 21.694367 -223.35966) (xy 21.651499 -223.395335) (xy 21.603893 -223.424389) (xy 21.552564 -223.446201)
			(xy 21.498607 -223.460307) (xy 21.44317 -223.466407) (xy 21.387436 -223.46437) (xy 21.332593 -223.45424)
			(xy 21.279809 -223.436233) (xy 21.230209 -223.410732) (xy 21.184851 -223.378281) (xy 21.144702 -223.339572)
			(xy 21.110616 -223.295429) (xy 21.08332 -223.246794) (xy 21.063397 -223.194703) (xy 21.051271 -223.140266)
			(xy 21.0472 -223.084644) (xy 19.813982 -223.084644) (xy 19.819111 -223.119496) (xy 19.81962 -223.147382)
			(xy 19.819111 -223.175268) (xy 19.810991 -223.230444) (xy 19.794923 -223.283851) (xy 19.771251 -223.334348)
			(xy 19.740478 -223.380861) (xy 19.703261 -223.422398) (xy 19.660393 -223.458073) (xy 19.612787 -223.487127)
			(xy 19.561458 -223.508939) (xy 19.507501 -223.523045) (xy 19.452064 -223.529145) (xy 19.39633 -223.527108)
			(xy 19.341487 -223.516978) (xy 19.288703 -223.498971) (xy 19.239103 -223.47347) (xy 19.193745 -223.441019)
			(xy 19.153596 -223.40231) (xy 19.11951 -223.358167) (xy 19.092214 -223.309532) (xy 19.072291 -223.257441)
			(xy 19.060165 -223.203004) (xy 19.056094 -223.147382) (xy 4.421886 -223.147382) (xy 4.421886 -224.536)
			(xy 27.78328 -224.536) (xy 27.787351 -224.480378) (xy 27.799477 -224.425941) (xy 27.8194 -224.37385)
			(xy 27.846696 -224.325215) (xy 27.880782 -224.281072) (xy 27.920931 -224.242363) (xy 27.966289 -224.209912)
			(xy 28.015889 -224.184411) (xy 28.068673 -224.166404) (xy 28.123516 -224.156274) (xy 28.17925 -224.154237)
			(xy 28.234687 -224.160337) (xy 28.288644 -224.174443) (xy 28.339973 -224.196255) (xy 28.387579 -224.225309)
			(xy 28.430447 -224.260984) (xy 28.467664 -224.302521) (xy 28.498437 -224.349034) (xy 28.522109 -224.399531)
			(xy 28.538177 -224.452938) (xy 28.546297 -224.508114) (xy 28.546806 -224.536) (xy 28.546297 -224.563886)
			(xy 28.538177 -224.619062) (xy 28.522109 -224.672469) (xy 28.498437 -224.722966) (xy 28.467664 -224.769479)
			(xy 28.430447 -224.811016) (xy 28.387579 -224.846691) (xy 28.339973 -224.875745) (xy 28.288644 -224.897557)
			(xy 28.234687 -224.911663) (xy 28.17925 -224.917763) (xy 28.123516 -224.915726) (xy 28.068673 -224.905596)
			(xy 28.015889 -224.887589) (xy 27.966289 -224.862088) (xy 27.920931 -224.829637) (xy 27.880782 -224.790928)
			(xy 27.846696 -224.746785) (xy 27.8194 -224.69815) (xy 27.799477 -224.646059) (xy 27.787351 -224.591622)
			(xy 27.78328 -224.536) (xy 4.421886 -224.536) (xy 4.421886 -225.82251) (xy 18.421094 -225.82251)
			(xy 18.425165 -225.766888) (xy 18.437291 -225.712451) (xy 18.457214 -225.66036) (xy 18.48451 -225.611725)
			(xy 18.518596 -225.567582) (xy 18.558745 -225.528873) (xy 18.604103 -225.496422) (xy 18.653703 -225.470921)
			(xy 18.706487 -225.452914) (xy 18.76133 -225.442784) (xy 18.817064 -225.440747) (xy 18.872501 -225.446847)
			(xy 18.926458 -225.460953) (xy 18.977787 -225.482765) (xy 19.025393 -225.511819) (xy 19.068261 -225.547494)
			(xy 19.105478 -225.589031) (xy 19.136251 -225.635544) (xy 19.158408 -225.68281) (xy 20.720048 -225.68281)
			(xy 20.724119 -225.627188) (xy 20.736245 -225.572751) (xy 20.756168 -225.52066) (xy 20.783464 -225.472025)
			(xy 20.81755 -225.427882) (xy 20.857699 -225.389173) (xy 20.903057 -225.356722) (xy 20.952657 -225.331221)
			(xy 21.005441 -225.313214) (xy 21.060284 -225.303084) (xy 21.116018 -225.301047) (xy 21.171455 -225.307147)
			(xy 21.225412 -225.321253) (xy 21.276741 -225.343065) (xy 21.324347 -225.372119) (xy 21.367215 -225.407794)
			(xy 21.404432 -225.449331) (xy 21.435205 -225.495844) (xy 21.458877 -225.546341) (xy 21.46058 -225.552)
			(xy 30.83128 -225.552) (xy 30.835351 -225.496378) (xy 30.847477 -225.441941) (xy 30.8674 -225.38985)
			(xy 30.894696 -225.341215) (xy 30.928782 -225.297072) (xy 30.968931 -225.258363) (xy 31.014289 -225.225912)
			(xy 31.063889 -225.200411) (xy 31.116673 -225.182404) (xy 31.171516 -225.172274) (xy 31.22725 -225.170237)
			(xy 31.282687 -225.176337) (xy 31.336644 -225.190443) (xy 31.387973 -225.212255) (xy 31.435579 -225.241309)
			(xy 31.478447 -225.276984) (xy 31.515664 -225.318521) (xy 31.546437 -225.365034) (xy 31.570109 -225.415531)
			(xy 31.586177 -225.468938) (xy 31.594297 -225.524114) (xy 31.594806 -225.552) (xy 31.594297 -225.579886)
			(xy 31.586177 -225.635062) (xy 31.570109 -225.688469) (xy 31.546437 -225.738966) (xy 31.515664 -225.785479)
			(xy 31.478447 -225.827016) (xy 31.435579 -225.862691) (xy 31.387973 -225.891745) (xy 31.336644 -225.913557)
			(xy 31.282687 -225.927663) (xy 31.22725 -225.933763) (xy 31.171516 -225.931726) (xy 31.116673 -225.921596)
			(xy 31.063889 -225.903589) (xy 31.014289 -225.878088) (xy 30.968931 -225.845637) (xy 30.928782 -225.806928)
			(xy 30.894696 -225.762785) (xy 30.8674 -225.71415) (xy 30.847477 -225.662059) (xy 30.835351 -225.607622)
			(xy 30.83128 -225.552) (xy 21.46058 -225.552) (xy 21.474945 -225.599748) (xy 21.483065 -225.654924)
			(xy 21.483574 -225.68281) (xy 21.483065 -225.710696) (xy 21.474945 -225.765872) (xy 21.458877 -225.819279)
			(xy 21.435205 -225.869776) (xy 21.404432 -225.916289) (xy 21.367215 -225.957826) (xy 21.324347 -225.993501)
			(xy 21.276741 -226.022555) (xy 21.225412 -226.044367) (xy 21.171455 -226.058473) (xy 21.116018 -226.064573)
			(xy 21.060284 -226.062536) (xy 21.005441 -226.052406) (xy 20.952657 -226.034399) (xy 20.903057 -226.008898)
			(xy 20.857699 -225.976447) (xy 20.81755 -225.937738) (xy 20.783464 -225.893595) (xy 20.756168 -225.84496)
			(xy 20.736245 -225.792869) (xy 20.724119 -225.738432) (xy 20.720048 -225.68281) (xy 19.158408 -225.68281)
			(xy 19.159923 -225.686041) (xy 19.175991 -225.739448) (xy 19.184111 -225.794624) (xy 19.18462 -225.82251)
			(xy 19.184111 -225.850396) (xy 19.175991 -225.905572) (xy 19.159923 -225.958979) (xy 19.136251 -226.009476)
			(xy 19.105478 -226.055989) (xy 19.068261 -226.097526) (xy 19.025393 -226.133201) (xy 18.977787 -226.162255)
			(xy 18.926458 -226.184067) (xy 18.872501 -226.198173) (xy 18.817064 -226.204273) (xy 18.76133 -226.202236)
			(xy 18.706487 -226.192106) (xy 18.653703 -226.174099) (xy 18.604103 -226.148598) (xy 18.558745 -226.116147)
			(xy 18.518596 -226.077438) (xy 18.48451 -226.033295) (xy 18.457214 -225.98466) (xy 18.437291 -225.932569)
			(xy 18.425165 -225.878132) (xy 18.421094 -225.82251) (xy 4.421886 -225.82251) (xy 4.421886 -226.324922)
			(xy 25.607262 -226.324922) (xy 25.611333 -226.2693) (xy 25.623459 -226.214863) (xy 25.643382 -226.162772)
			(xy 25.670678 -226.114137) (xy 25.704764 -226.069994) (xy 25.744913 -226.031285) (xy 25.790271 -225.998834)
			(xy 25.839871 -225.973333) (xy 25.892655 -225.955326) (xy 25.947498 -225.945196) (xy 26.003232 -225.943159)
			(xy 26.058669 -225.949259) (xy 26.112626 -225.963365) (xy 26.163955 -225.985177) (xy 26.211561 -226.014231)
			(xy 26.254429 -226.049906) (xy 26.291646 -226.091443) (xy 26.322419 -226.137956) (xy 26.346091 -226.188453)
			(xy 26.362159 -226.24186) (xy 26.370279 -226.297036) (xy 26.370788 -226.324922) (xy 26.370279 -226.352808)
			(xy 26.362159 -226.407984) (xy 26.346091 -226.461391) (xy 26.322419 -226.511888) (xy 26.291646 -226.558401)
			(xy 26.283045 -226.568) (xy 30.95828 -226.568) (xy 30.962351 -226.512378) (xy 30.974477 -226.457941)
			(xy 30.9944 -226.40585) (xy 31.021696 -226.357215) (xy 31.055782 -226.313072) (xy 31.095931 -226.274363)
			(xy 31.141289 -226.241912) (xy 31.190889 -226.216411) (xy 31.243673 -226.198404) (xy 31.298516 -226.188274)
			(xy 31.35425 -226.186237) (xy 31.409687 -226.192337) (xy 31.463644 -226.206443) (xy 31.514973 -226.228255)
			(xy 31.562579 -226.257309) (xy 31.605447 -226.292984) (xy 31.642664 -226.334521) (xy 31.673437 -226.381034)
			(xy 31.697109 -226.431531) (xy 31.713177 -226.484938) (xy 31.721297 -226.540114) (xy 31.721806 -226.568)
			(xy 31.721297 -226.595886) (xy 31.713177 -226.651062) (xy 31.697109 -226.704469) (xy 31.673437 -226.754966)
			(xy 31.642664 -226.801479) (xy 31.605447 -226.843016) (xy 31.562579 -226.878691) (xy 31.514973 -226.907745)
			(xy 31.463644 -226.929557) (xy 31.409687 -226.943663) (xy 31.35425 -226.949763) (xy 31.298516 -226.947726)
			(xy 31.243673 -226.937596) (xy 31.190889 -226.919589) (xy 31.141289 -226.894088) (xy 31.095931 -226.861637)
			(xy 31.055782 -226.822928) (xy 31.021696 -226.778785) (xy 30.9944 -226.73015) (xy 30.974477 -226.678059)
			(xy 30.962351 -226.623622) (xy 30.95828 -226.568) (xy 26.283045 -226.568) (xy 26.254429 -226.599938)
			(xy 26.211561 -226.635613) (xy 26.163955 -226.664667) (xy 26.112626 -226.686479) (xy 26.058669 -226.700585)
			(xy 26.003232 -226.706685) (xy 25.947498 -226.704648) (xy 25.892655 -226.694518) (xy 25.839871 -226.676511)
			(xy 25.790271 -226.65101) (xy 25.744913 -226.618559) (xy 25.704764 -226.57985) (xy 25.670678 -226.535707)
			(xy 25.643382 -226.487072) (xy 25.623459 -226.434981) (xy 25.611333 -226.380544) (xy 25.607262 -226.324922)
			(xy 4.421886 -226.324922) (xy 4.421886 -228.179884) (xy 17.914872 -228.179884) (xy 17.918943 -228.124262)
			(xy 17.931069 -228.069825) (xy 17.950992 -228.017734) (xy 17.978288 -227.969099) (xy 18.012374 -227.924956)
			(xy 18.052523 -227.886247) (xy 18.097881 -227.853796) (xy 18.147481 -227.828295) (xy 18.200265 -227.810288)
			(xy 18.255108 -227.800158) (xy 18.310842 -227.798121) (xy 18.366279 -227.804221) (xy 18.420236 -227.818327)
			(xy 18.471565 -227.840139) (xy 18.519171 -227.869193) (xy 18.562039 -227.904868) (xy 18.599256 -227.946405)
			(xy 18.630029 -227.992918) (xy 18.653701 -228.043415) (xy 18.661441 -228.06914) (xy 18.973544 -228.06914)
			(xy 18.977615 -228.013518) (xy 18.989741 -227.959081) (xy 19.009664 -227.90699) (xy 19.03696 -227.858355)
			(xy 19.071046 -227.814212) (xy 19.111195 -227.775503) (xy 19.156553 -227.743052) (xy 19.206153 -227.717551)
			(xy 19.258937 -227.699544) (xy 19.31378 -227.689414) (xy 19.369514 -227.687377) (xy 19.424951 -227.693477)
			(xy 19.478908 -227.707583) (xy 19.530237 -227.729395) (xy 19.577843 -227.758449) (xy 19.620711 -227.794124)
			(xy 19.657928 -227.835661) (xy 19.688701 -227.882174) (xy 19.712373 -227.932671) (xy 19.728441 -227.986078)
			(xy 19.736561 -228.041254) (xy 19.73707 -228.06914) (xy 19.736917 -228.077522) (xy 20.024088 -228.077522)
			(xy 20.028159 -228.0219) (xy 20.040285 -227.967463) (xy 20.060208 -227.915372) (xy 20.087504 -227.866737)
			(xy 20.12159 -227.822594) (xy 20.161739 -227.783885) (xy 20.207097 -227.751434) (xy 20.256697 -227.725933)
			(xy 20.309481 -227.707926) (xy 20.364324 -227.697796) (xy 20.420058 -227.695759) (xy 20.475495 -227.701859)
			(xy 20.529452 -227.715965) (xy 20.580781 -227.737777) (xy 20.628387 -227.766831) (xy 20.671255 -227.802506)
			(xy 20.708472 -227.844043) (xy 20.739245 -227.890556) (xy 20.762917 -227.941053) (xy 20.778985 -227.99446)
			(xy 20.787105 -228.049636) (xy 20.787614 -228.077522) (xy 20.787105 -228.105408) (xy 20.778985 -228.160584)
			(xy 20.762917 -228.213991) (xy 20.739245 -228.264488) (xy 20.708472 -228.311001) (xy 20.671255 -228.352538)
			(xy 20.628387 -228.388213) (xy 20.580781 -228.417267) (xy 20.529452 -228.439079) (xy 20.475495 -228.453185)
			(xy 20.420058 -228.459285) (xy 20.364324 -228.457248) (xy 20.309481 -228.447118) (xy 20.256697 -228.429111)
			(xy 20.207097 -228.40361) (xy 20.161739 -228.371159) (xy 20.12159 -228.33245) (xy 20.087504 -228.288307)
			(xy 20.060208 -228.239672) (xy 20.040285 -228.187581) (xy 20.028159 -228.133144) (xy 20.024088 -228.077522)
			(xy 19.736917 -228.077522) (xy 19.736561 -228.097026) (xy 19.728441 -228.152202) (xy 19.712373 -228.205609)
			(xy 19.688701 -228.256106) (xy 19.657928 -228.302619) (xy 19.620711 -228.344156) (xy 19.577843 -228.379831)
			(xy 19.530237 -228.408885) (xy 19.478908 -228.430697) (xy 19.424951 -228.444803) (xy 19.369514 -228.450903)
			(xy 19.31378 -228.448866) (xy 19.258937 -228.438736) (xy 19.206153 -228.420729) (xy 19.156553 -228.395228)
			(xy 19.111195 -228.362777) (xy 19.071046 -228.324068) (xy 19.03696 -228.279925) (xy 19.009664 -228.23129)
			(xy 18.989741 -228.179199) (xy 18.977615 -228.124762) (xy 18.973544 -228.06914) (xy 18.661441 -228.06914)
			(xy 18.669769 -228.096822) (xy 18.677889 -228.151998) (xy 18.678398 -228.179884) (xy 18.677889 -228.20777)
			(xy 18.669769 -228.262946) (xy 18.653701 -228.316353) (xy 18.630029 -228.36685) (xy 18.599256 -228.413363)
			(xy 18.562039 -228.4549) (xy 18.519171 -228.490575) (xy 18.471565 -228.519629) (xy 18.420236 -228.541441)
			(xy 18.366279 -228.555547) (xy 18.310842 -228.561647) (xy 18.255108 -228.55961) (xy 18.200265 -228.54948)
			(xy 18.147481 -228.531473) (xy 18.097881 -228.505972) (xy 18.052523 -228.473521) (xy 18.012374 -228.434812)
			(xy 17.978288 -228.390669) (xy 17.950992 -228.342034) (xy 17.931069 -228.289943) (xy 17.918943 -228.235506)
			(xy 17.914872 -228.179884) (xy 4.421886 -228.179884) (xy 4.421886 -228.981) (xy 16.03451 -228.981)
			(xy 16.038581 -228.925378) (xy 16.050707 -228.870941) (xy 16.07063 -228.81885) (xy 16.097926 -228.770215)
			(xy 16.132012 -228.726072) (xy 16.172161 -228.687363) (xy 16.217519 -228.654912) (xy 16.267119 -228.629411)
			(xy 16.319903 -228.611404) (xy 16.374746 -228.601274) (xy 16.43048 -228.599237) (xy 16.485917 -228.605337)
			(xy 16.539874 -228.619443) (xy 16.591203 -228.641255) (xy 16.638809 -228.670309) (xy 16.644362 -228.67493)
			(xy 25.95575 -228.67493) (xy 25.959821 -228.619308) (xy 25.971947 -228.564871) (xy 25.99187 -228.51278)
			(xy 26.019166 -228.464145) (xy 26.053252 -228.420002) (xy 26.093401 -228.381293) (xy 26.138759 -228.348842)
			(xy 26.188359 -228.323341) (xy 26.241143 -228.305334) (xy 26.295986 -228.295204) (xy 26.35172 -228.293167)
			(xy 26.407157 -228.299267) (xy 26.461114 -228.313373) (xy 26.512443 -228.335185) (xy 26.560049 -228.364239)
			(xy 26.602917 -228.399914) (xy 26.640134 -228.441451) (xy 26.670907 -228.487964) (xy 26.694579 -228.538461)
			(xy 26.710647 -228.591868) (xy 26.718767 -228.647044) (xy 26.719276 -228.67493) (xy 26.718767 -228.702816)
			(xy 26.710647 -228.757992) (xy 26.694579 -228.811399) (xy 26.670907 -228.861896) (xy 26.640134 -228.908409)
			(xy 26.602917 -228.949946) (xy 26.560049 -228.985621) (xy 26.512443 -229.014675) (xy 26.461114 -229.036487)
			(xy 26.407157 -229.050593) (xy 26.35172 -229.056693) (xy 26.295986 -229.054656) (xy 26.241143 -229.044526)
			(xy 26.188359 -229.026519) (xy 26.138759 -229.001018) (xy 26.093401 -228.968567) (xy 26.053252 -228.929858)
			(xy 26.019166 -228.885715) (xy 25.99187 -228.83708) (xy 25.971947 -228.784989) (xy 25.959821 -228.730552)
			(xy 25.95575 -228.67493) (xy 16.644362 -228.67493) (xy 16.681677 -228.705984) (xy 16.718894 -228.747521)
			(xy 16.749667 -228.794034) (xy 16.773339 -228.844531) (xy 16.789407 -228.897938) (xy 16.797527 -228.953114)
			(xy 16.798036 -228.981) (xy 16.797527 -229.008886) (xy 16.789407 -229.064062) (xy 16.773339 -229.117469)
			(xy 16.749667 -229.167966) (xy 16.718894 -229.214479) (xy 16.681677 -229.256016) (xy 16.638809 -229.291691)
			(xy 16.591203 -229.320745) (xy 16.539874 -229.342557) (xy 16.485917 -229.356663) (xy 16.43048 -229.362763)
			(xy 16.374746 -229.360726) (xy 16.319903 -229.350596) (xy 16.267119 -229.332589) (xy 16.217519 -229.307088)
			(xy 16.172161 -229.274637) (xy 16.132012 -229.235928) (xy 16.097926 -229.191785) (xy 16.07063 -229.14315)
			(xy 16.050707 -229.091059) (xy 16.038581 -229.036622) (xy 16.03451 -228.981) (xy 4.421886 -228.981)
			(xy 4.421886 -229.94493) (xy 12.84554 -229.94493) (xy 12.849611 -229.889308) (xy 12.861737 -229.834871)
			(xy 12.88166 -229.78278) (xy 12.908956 -229.734145) (xy 12.943042 -229.690002) (xy 12.983191 -229.651293)
			(xy 13.028549 -229.618842) (xy 13.078149 -229.593341) (xy 13.130933 -229.575334) (xy 13.185776 -229.565204)
			(xy 13.24151 -229.563167) (xy 13.296947 -229.569267) (xy 13.350904 -229.583373) (xy 13.402233 -229.605185)
			(xy 13.449839 -229.634239) (xy 13.492707 -229.669914) (xy 13.529924 -229.711451) (xy 13.560697 -229.757964)
			(xy 13.584369 -229.808461) (xy 13.600437 -229.861868) (xy 13.608557 -229.917044) (xy 13.609066 -229.94493)
			(xy 22.83028 -229.94493) (xy 22.834351 -229.889308) (xy 22.846477 -229.834871) (xy 22.8664 -229.78278)
			(xy 22.893696 -229.734145) (xy 22.927782 -229.690002) (xy 22.967931 -229.651293) (xy 23.013289 -229.618842)
			(xy 23.062889 -229.593341) (xy 23.115673 -229.575334) (xy 23.170516 -229.565204) (xy 23.22625 -229.563167)
			(xy 23.281687 -229.569267) (xy 23.335644 -229.583373) (xy 23.386973 -229.605185) (xy 23.434579 -229.634239)
			(xy 23.477447 -229.669914) (xy 23.514664 -229.711451) (xy 23.545437 -229.757964) (xy 23.569109 -229.808461)
			(xy 23.585177 -229.861868) (xy 23.593297 -229.917044) (xy 23.593806 -229.94493) (xy 23.593297 -229.972816)
			(xy 23.585177 -230.027992) (xy 23.569109 -230.081399) (xy 23.545437 -230.131896) (xy 23.514664 -230.178409)
			(xy 23.477447 -230.219946) (xy 23.434579 -230.255621) (xy 23.386973 -230.284675) (xy 23.335644 -230.306487)
			(xy 23.281687 -230.320593) (xy 23.22625 -230.326693) (xy 23.170516 -230.324656) (xy 23.115673 -230.314526)
			(xy 23.062889 -230.296519) (xy 23.013289 -230.271018) (xy 22.967931 -230.238567) (xy 22.927782 -230.199858)
			(xy 22.893696 -230.155715) (xy 22.8664 -230.10708) (xy 22.846477 -230.054989) (xy 22.834351 -230.000552)
			(xy 22.83028 -229.94493) (xy 13.609066 -229.94493) (xy 13.608557 -229.972816) (xy 13.600437 -230.027992)
			(xy 13.584369 -230.081399) (xy 13.560697 -230.131896) (xy 13.529924 -230.178409) (xy 13.492707 -230.219946)
			(xy 13.449839 -230.255621) (xy 13.402233 -230.284675) (xy 13.350904 -230.306487) (xy 13.296947 -230.320593)
			(xy 13.24151 -230.326693) (xy 13.185776 -230.324656) (xy 13.130933 -230.314526) (xy 13.078149 -230.296519)
			(xy 13.028549 -230.271018) (xy 12.983191 -230.238567) (xy 12.943042 -230.199858) (xy 12.908956 -230.155715)
			(xy 12.88166 -230.10708) (xy 12.861737 -230.054989) (xy 12.849611 -230.000552) (xy 12.84554 -229.94493)
			(xy 4.421886 -229.94493) (xy 4.421886 -231.203754) (xy 14.84833 -231.203754) (xy 14.852401 -231.148132)
			(xy 14.864527 -231.093695) (xy 14.88445 -231.041604) (xy 14.911746 -230.992969) (xy 14.945832 -230.948826)
			(xy 14.985981 -230.910117) (xy 15.031339 -230.877666) (xy 15.080939 -230.852165) (xy 15.133723 -230.834158)
			(xy 15.188566 -230.824028) (xy 15.2443 -230.821991) (xy 15.299737 -230.828091) (xy 15.353694 -230.842197)
			(xy 15.405023 -230.864009) (xy 15.452629 -230.893063) (xy 15.495497 -230.928738) (xy 15.532714 -230.970275)
			(xy 15.563487 -231.016788) (xy 15.587159 -231.067285) (xy 15.603227 -231.120692) (xy 15.610629 -231.170988)
			(xy 16.915382 -231.170988) (xy 16.919453 -231.115366) (xy 16.931579 -231.060929) (xy 16.951502 -231.008838)
			(xy 16.978798 -230.960203) (xy 17.012884 -230.91606) (xy 17.053033 -230.877351) (xy 17.098391 -230.8449)
			(xy 17.147991 -230.819399) (xy 17.200775 -230.801392) (xy 17.255618 -230.791262) (xy 17.311352 -230.789225)
			(xy 17.366789 -230.795325) (xy 17.420746 -230.809431) (xy 17.472075 -230.831243) (xy 17.519681 -230.860297)
			(xy 17.562549 -230.895972) (xy 17.599766 -230.937509) (xy 17.630539 -230.984022) (xy 17.654211 -231.034519)
			(xy 17.670279 -231.087926) (xy 17.678399 -231.143102) (xy 17.678908 -231.170988) (xy 17.678399 -231.198874)
			(xy 17.670279 -231.25405) (xy 17.654211 -231.307457) (xy 17.630539 -231.357954) (xy 17.599766 -231.404467)
			(xy 17.562549 -231.446004) (xy 17.519681 -231.481679) (xy 17.472075 -231.510733) (xy 17.420746 -231.532545)
			(xy 17.366789 -231.546651) (xy 17.311352 -231.552751) (xy 17.255618 -231.550714) (xy 17.200775 -231.540584)
			(xy 17.147991 -231.522577) (xy 17.098391 -231.497076) (xy 17.053033 -231.464625) (xy 17.012884 -231.425916)
			(xy 16.978798 -231.381773) (xy 16.951502 -231.333138) (xy 16.931579 -231.281047) (xy 16.919453 -231.22661)
			(xy 16.915382 -231.170988) (xy 15.610629 -231.170988) (xy 15.611347 -231.175868) (xy 15.611856 -231.203754)
			(xy 15.611347 -231.23164) (xy 15.603227 -231.286816) (xy 15.587159 -231.340223) (xy 15.563487 -231.39072)
			(xy 15.532714 -231.437233) (xy 15.495497 -231.47877) (xy 15.452629 -231.514445) (xy 15.405023 -231.543499)
			(xy 15.353694 -231.565311) (xy 15.299737 -231.579417) (xy 15.2443 -231.585517) (xy 15.188566 -231.58348)
			(xy 15.133723 -231.57335) (xy 15.080939 -231.555343) (xy 15.031339 -231.529842) (xy 14.985981 -231.497391)
			(xy 14.945832 -231.458682) (xy 14.911746 -231.414539) (xy 14.88445 -231.365904) (xy 14.864527 -231.313813)
			(xy 14.852401 -231.259376) (xy 14.84833 -231.203754) (xy 4.421886 -231.203754) (xy 4.421886 -231.95026)
			(xy 17.786094 -231.95026) (xy 17.790165 -231.894638) (xy 17.802291 -231.840201) (xy 17.822214 -231.78811)
			(xy 17.84951 -231.739475) (xy 17.883596 -231.695332) (xy 17.923745 -231.656623) (xy 17.969103 -231.624172)
			(xy 18.018703 -231.598671) (xy 18.071487 -231.580664) (xy 18.12633 -231.570534) (xy 18.182064 -231.568497)
			(xy 18.237501 -231.574597) (xy 18.291458 -231.588703) (xy 18.342787 -231.610515) (xy 18.390393 -231.639569)
			(xy 18.433261 -231.675244) (xy 18.470478 -231.716781) (xy 18.501251 -231.763294) (xy 18.524923 -231.813791)
			(xy 18.540991 -231.867198) (xy 18.549111 -231.922374) (xy 18.54962 -231.95026) (xy 18.549111 -231.978146)
			(xy 18.540991 -232.033322) (xy 18.524923 -232.086729) (xy 18.501251 -232.137226) (xy 18.470478 -232.183739)
			(xy 18.433261 -232.225276) (xy 18.390393 -232.260951) (xy 18.342787 -232.290005) (xy 18.291458 -232.311817)
			(xy 18.237501 -232.325923) (xy 18.182064 -232.332023) (xy 18.12633 -232.329986) (xy 18.071487 -232.319856)
			(xy 18.018703 -232.301849) (xy 17.969103 -232.276348) (xy 17.923745 -232.243897) (xy 17.883596 -232.205188)
			(xy 17.84951 -232.161045) (xy 17.822214 -232.11241) (xy 17.802291 -232.060319) (xy 17.790165 -232.005882)
			(xy 17.786094 -231.95026) (xy 4.421886 -231.95026) (xy 4.421886 -232.77322) (xy 11.918948 -232.77322)
			(xy 11.923019 -232.717598) (xy 11.935145 -232.663161) (xy 11.955068 -232.61107) (xy 11.982364 -232.562435)
			(xy 12.01645 -232.518292) (xy 12.056599 -232.479583) (xy 12.101957 -232.447132) (xy 12.151557 -232.421631)
			(xy 12.204341 -232.403624) (xy 12.259184 -232.393494) (xy 12.314918 -232.391457) (xy 12.370355 -232.397557)
			(xy 12.424312 -232.411663) (xy 12.475641 -232.433475) (xy 12.523247 -232.462529) (xy 12.566115 -232.498204)
			(xy 12.603332 -232.539741) (xy 12.634105 -232.586254) (xy 12.657777 -232.636751) (xy 12.673845 -232.690158)
			(xy 12.681965 -232.745334) (xy 12.682474 -232.77322) (xy 12.681965 -232.801106) (xy 12.673845 -232.856282)
			(xy 12.657777 -232.909689) (xy 12.634105 -232.960186) (xy 12.603332 -233.006699) (xy 12.566115 -233.048236)
			(xy 12.523247 -233.083911) (xy 12.475641 -233.112965) (xy 12.424312 -233.134777) (xy 12.370355 -233.148883)
			(xy 12.314918 -233.154983) (xy 12.259184 -233.152946) (xy 12.204341 -233.142816) (xy 12.151557 -233.124809)
			(xy 12.101957 -233.099308) (xy 12.056599 -233.066857) (xy 12.01645 -233.028148) (xy 11.982364 -232.984005)
			(xy 11.955068 -232.93537) (xy 11.935145 -232.883279) (xy 11.923019 -232.828842) (xy 11.918948 -232.77322)
			(xy 4.421886 -232.77322) (xy 4.421886 -233.590846) (xy 11.623038 -233.590846) (xy 11.627109 -233.535224)
			(xy 11.639235 -233.480787) (xy 11.659158 -233.428696) (xy 11.686454 -233.380061) (xy 11.72054 -233.335918)
			(xy 11.760689 -233.297209) (xy 11.806047 -233.264758) (xy 11.855647 -233.239257) (xy 11.908431 -233.22125)
			(xy 11.963274 -233.21112) (xy 12.019008 -233.209083) (xy 12.074445 -233.215183) (xy 12.128402 -233.229289)
			(xy 12.179731 -233.251101) (xy 12.227337 -233.280155) (xy 12.270205 -233.31583) (xy 12.307422 -233.357367)
			(xy 12.338195 -233.40388) (xy 12.361867 -233.454377) (xy 12.377935 -233.507784) (xy 12.386055 -233.56296)
			(xy 12.386564 -233.590846) (xy 12.386055 -233.618732) (xy 12.377935 -233.673908) (xy 12.361867 -233.727315)
			(xy 12.338195 -233.777812) (xy 12.307422 -233.824325) (xy 12.270205 -233.865862) (xy 12.227337 -233.901537)
			(xy 12.179731 -233.930591) (xy 12.128402 -233.952403) (xy 12.074445 -233.966509) (xy 12.019008 -233.972609)
			(xy 11.963274 -233.970572) (xy 11.908431 -233.960442) (xy 11.855647 -233.942435) (xy 11.806047 -233.916934)
			(xy 11.760689 -233.884483) (xy 11.72054 -233.845774) (xy 11.686454 -233.801631) (xy 11.659158 -233.752996)
			(xy 11.639235 -233.700905) (xy 11.627109 -233.646468) (xy 11.623038 -233.590846) (xy 4.421886 -233.590846)
			(xy 4.421886 -240.304828) (xy 20.088604 -240.304828) (xy 20.092675 -240.249206) (xy 20.104801 -240.194769)
			(xy 20.124724 -240.142678) (xy 20.15202 -240.094043) (xy 20.186106 -240.0499) (xy 20.226255 -240.011191)
			(xy 20.271613 -239.97874) (xy 20.321213 -239.953239) (xy 20.373997 -239.935232) (xy 20.42884 -239.925102)
			(xy 20.484574 -239.923065) (xy 20.540011 -239.929165) (xy 20.593968 -239.943271) (xy 20.645297 -239.965083)
			(xy 20.692903 -239.994137) (xy 20.735771 -240.029812) (xy 20.772988 -240.071349) (xy 20.803761 -240.117862)
			(xy 20.827433 -240.168359) (xy 20.843501 -240.221766) (xy 20.851621 -240.276942) (xy 20.85213 -240.304828)
			(xy 20.851621 -240.332714) (xy 20.843501 -240.38789) (xy 20.827433 -240.441297) (xy 20.803761 -240.491794)
			(xy 20.772988 -240.538307) (xy 20.735771 -240.579844) (xy 20.692903 -240.615519) (xy 20.645297 -240.644573)
			(xy 20.593968 -240.666385) (xy 20.540011 -240.680491) (xy 20.484574 -240.686591) (xy 20.42884 -240.684554)
			(xy 20.373997 -240.674424) (xy 20.321213 -240.656417) (xy 20.271613 -240.630916) (xy 20.226255 -240.598465)
			(xy 20.186106 -240.559756) (xy 20.15202 -240.515613) (xy 20.124724 -240.466978) (xy 20.104801 -240.414887)
			(xy 20.092675 -240.36045) (xy 20.088604 -240.304828) (xy 4.421886 -240.304828) (xy 4.421886 -241.112294)
			(xy 19.4724 -241.112294) (xy 19.476471 -241.056672) (xy 19.488597 -241.002235) (xy 19.50852 -240.950144)
			(xy 19.535816 -240.901509) (xy 19.569902 -240.857366) (xy 19.610051 -240.818657) (xy 19.655409 -240.786206)
			(xy 19.705009 -240.760705) (xy 19.757793 -240.742698) (xy 19.812636 -240.732568) (xy 19.86837 -240.730531)
			(xy 19.923807 -240.736631) (xy 19.977764 -240.750737) (xy 20.029093 -240.772549) (xy 20.076699 -240.801603)
			(xy 20.119567 -240.837278) (xy 20.156784 -240.878815) (xy 20.187557 -240.925328) (xy 20.211229 -240.975825)
			(xy 20.227297 -241.029232) (xy 20.235417 -241.084408) (xy 20.235926 -241.112294) (xy 20.235417 -241.14018)
			(xy 20.227297 -241.195356) (xy 20.211229 -241.248763) (xy 20.187557 -241.29926) (xy 20.156784 -241.345773)
			(xy 20.119567 -241.38731) (xy 20.076699 -241.422985) (xy 20.029093 -241.452039) (xy 19.977764 -241.473851)
			(xy 19.923807 -241.487957) (xy 19.86837 -241.494057) (xy 19.812636 -241.49202) (xy 19.757793 -241.48189)
			(xy 19.705009 -241.463883) (xy 19.655409 -241.438382) (xy 19.610051 -241.405931) (xy 19.569902 -241.367222)
			(xy 19.535816 -241.323079) (xy 19.50852 -241.274444) (xy 19.488597 -241.222353) (xy 19.476471 -241.167916)
			(xy 19.4724 -241.112294) (xy 4.421886 -241.112294) (xy 4.421886 -242.099592) (xy 4.421464 -242.109663)
			(xy 4.41375 -242.128268) (xy 4.4069 -242.13566) (xy 4.373626 -242.168934) (xy 19.00631 -242.168934)
			(xy 19.010381 -242.113312) (xy 19.022507 -242.058875) (xy 19.04243 -242.006784) (xy 19.069726 -241.958149)
			(xy 19.103812 -241.914006) (xy 19.143961 -241.875297) (xy 19.189319 -241.842846) (xy 19.238919 -241.817345)
			(xy 19.291703 -241.799338) (xy 19.346546 -241.789208) (xy 19.40228 -241.787171) (xy 19.457717 -241.793271)
			(xy 19.511674 -241.807377) (xy 19.563003 -241.829189) (xy 19.610609 -241.858243) (xy 19.653477 -241.893918)
			(xy 19.690694 -241.935455) (xy 19.721467 -241.981968) (xy 19.745139 -242.032465) (xy 19.761207 -242.085872)
			(xy 19.769327 -242.141048) (xy 19.769836 -242.168934) (xy 19.769327 -242.19682) (xy 19.761207 -242.251996)
			(xy 19.745139 -242.305403) (xy 19.721467 -242.3559) (xy 19.690694 -242.402413) (xy 19.653477 -242.44395)
			(xy 19.610609 -242.479625) (xy 19.563003 -242.508679) (xy 19.511674 -242.530491) (xy 19.457717 -242.544597)
			(xy 19.40228 -242.550697) (xy 19.346546 -242.54866) (xy 19.291703 -242.53853) (xy 19.238919 -242.520523)
			(xy 19.189319 -242.495022) (xy 19.143961 -242.462571) (xy 19.103812 -242.423862) (xy 19.069726 -242.379719)
			(xy 19.04243 -242.331084) (xy 19.022507 -242.278993) (xy 19.010381 -242.224556) (xy 19.00631 -242.168934)
			(xy 4.373626 -242.168934) (xy 1.029716 -245.512844) (xy 1.026195 -245.516574) (xy 1.020567 -245.525149)
			(xy 1.01854 -245.529862) (xy 1.014984 -245.538498) (xy 1.014984 -246.036846) (xy 1.014552 -246.046912)
			(xy 1.006824 -246.065503) (xy 0.999998 -246.072914) (xy 0.631952 -246.44096) (xy 0.628435 -246.444693)
			(xy 0.622816 -246.453272) (xy 0.620776 -246.457978) (xy 0.61722 -246.466614) (xy 0.61722 -249.00382)
			(xy 24.976836 -249.00382) (xy 24.97731 -248.976214) (xy 24.985267 -248.921579) (xy 25.001016 -248.868662)
			(xy 25.02423 -248.818567) (xy 25.054422 -248.772343) (xy 25.090963 -248.730954) (xy 25.11171 -248.712736)
			(xy 25.11933 -248.706386) (xy 25.128728 -248.688352) (xy 25.136094 -248.596658) (xy 25.129998 -248.577354)
			(xy 25.123394 -248.569734) (xy 25.10644 -248.54898) (xy 25.07791 -248.503616) (xy 25.056009 -248.454706)
			(xy 25.041166 -248.403212) (xy 25.033674 -248.350149) (xy 25.033224 -248.323354) (xy 25.03371 -248.296103)
			(xy 25.041466 -248.242155) (xy 25.056821 -248.18986) (xy 25.079463 -248.140283) (xy 25.108929 -248.094433)
			(xy 25.14462 -248.053242) (xy 25.185811 -248.017551) (xy 25.231661 -247.988085) (xy 25.281238 -247.965443)
			(xy 25.333533 -247.950088) (xy 25.387481 -247.942332) (xy 25.441983 -247.942332) (xy 25.495931 -247.950088)
			(xy 25.548226 -247.965443) (xy 25.597803 -247.988085) (xy 25.643653 -248.017551) (xy 25.684844 -248.053242)
			(xy 25.720535 -248.094433) (xy 25.750001 -248.140283) (xy 25.772643 -248.18986) (xy 25.787998 -248.242155)
			(xy 25.795754 -248.296103) (xy 25.79624 -248.323354) (xy 25.795756 -248.35096) (xy 25.787803 -248.405595)
			(xy 25.772056 -248.458512) (xy 25.748844 -248.508607) (xy 25.718653 -248.554832) (xy 25.682113 -248.596221)
			(xy 25.661366 -248.614438) (xy 25.653746 -248.620788) (xy 25.644348 -248.638822) (xy 25.636982 -248.730516)
			(xy 25.643078 -248.74982) (xy 25.649682 -248.75744) (xy 25.666636 -248.778194) (xy 25.695163 -248.82356)
			(xy 25.717063 -248.87247) (xy 25.731907 -248.923962) (xy 25.7394 -248.977025) (xy 25.739852 -249.00382)
			(xy 25.992836 -249.00382) (xy 25.993288 -248.97683) (xy 26.000894 -248.92339) (xy 26.015958 -248.871555)
			(xy 26.038178 -248.822361) (xy 26.067112 -248.776791) (xy 26.10218 -248.735755) (xy 26.122122 -248.717562)
			(xy 26.129418 -248.710472) (xy 26.138188 -248.692132) (xy 26.13914 -248.682002) (xy 26.14295 -248.609612)
			(xy 26.14299 -248.59934) (xy 26.135915 -248.580076) (xy 26.129234 -248.572274) (xy 26.110197 -248.550977)
			(xy 26.078029 -248.503778) (xy 26.053252 -248.452311) (xy 26.036422 -248.397728) (xy 26.027912 -248.341246)
			(xy 26.02738 -248.312686) (xy 26.027866 -248.285435) (xy 26.035622 -248.231487) (xy 26.050977 -248.179192)
			(xy 26.073619 -248.129615) (xy 26.103085 -248.083765) (xy 26.138776 -248.042574) (xy 26.179967 -248.006883)
			(xy 26.225817 -247.977417) (xy 26.275394 -247.954775) (xy 26.327689 -247.93942) (xy 26.381637 -247.931664)
			(xy 26.436139 -247.931664) (xy 26.490087 -247.93942) (xy 26.542382 -247.954775) (xy 26.591959 -247.977417)
			(xy 26.637809 -248.006883) (xy 26.679 -248.042574) (xy 26.714691 -248.083765) (xy 26.744157 -248.129615)
			(xy 26.766799 -248.179192) (xy 26.782154 -248.231487) (xy 26.78991 -248.285435) (xy 26.790396 -248.312686)
			(xy 26.789971 -248.339677) (xy 26.782362 -248.39312) (xy 26.767295 -248.444956) (xy 26.745069 -248.49415)
			(xy 26.71613 -248.539719) (xy 26.681056 -248.580753) (xy 26.66111 -248.598944) (xy 26.653801 -248.606022)
			(xy 26.64504 -248.624372) (xy 26.644092 -248.634504) (xy 26.640282 -248.706894) (xy 26.640231 -248.717167)
			(xy 26.647313 -248.736431) (xy 26.653998 -248.744232) (xy 26.673026 -248.765536) (xy 26.705199 -248.812732)
			(xy 26.729978 -248.864197) (xy 26.74681 -248.918779) (xy 26.75532 -248.975261) (xy 26.755852 -249.00382)
			(xy 26.755366 -249.031071) (xy 26.74761 -249.085019) (xy 26.732255 -249.137314) (xy 26.709613 -249.186891)
			(xy 26.680147 -249.232741) (xy 26.644456 -249.273932) (xy 26.603265 -249.309623) (xy 26.557415 -249.339089)
			(xy 26.507838 -249.361731) (xy 26.455543 -249.377086) (xy 26.401595 -249.384842) (xy 26.347093 -249.384842)
			(xy 26.293145 -249.377086) (xy 26.24085 -249.361731) (xy 26.191273 -249.339089) (xy 26.145423 -249.309623)
			(xy 26.104232 -249.273932) (xy 26.068541 -249.232741) (xy 26.039075 -249.186891) (xy 26.016433 -249.137314)
			(xy 26.001078 -249.085019) (xy 25.993322 -249.031071) (xy 25.992836 -249.00382) (xy 25.739852 -249.00382)
			(xy 25.739366 -249.031071) (xy 25.73161 -249.085019) (xy 25.716255 -249.137314) (xy 25.693613 -249.186891)
			(xy 25.664147 -249.232741) (xy 25.628456 -249.273932) (xy 25.587265 -249.309623) (xy 25.541415 -249.339089)
			(xy 25.491838 -249.361731) (xy 25.439543 -249.377086) (xy 25.385595 -249.384842) (xy 25.331093 -249.384842)
			(xy 25.277145 -249.377086) (xy 25.22485 -249.361731) (xy 25.175273 -249.339089) (xy 25.129423 -249.309623)
			(xy 25.088232 -249.273932) (xy 25.052541 -249.232741) (xy 25.023075 -249.186891) (xy 25.000433 -249.137314)
			(xy 24.985078 -249.085019) (xy 24.977322 -249.031071) (xy 24.976836 -249.00382) (xy 0.61722 -249.00382)
			(xy 0.61722 -251.158502) (xy 23.960326 -251.158502) (xy 23.964397 -251.10288) (xy 23.976523 -251.048443)
			(xy 23.996446 -250.996352) (xy 24.023742 -250.947717) (xy 24.057828 -250.903574) (xy 24.097977 -250.864865)
			(xy 24.143335 -250.832414) (xy 24.192935 -250.806913) (xy 24.245719 -250.788906) (xy 24.300562 -250.778776)
			(xy 24.356296 -250.776739) (xy 24.411733 -250.782839) (xy 24.46569 -250.796945) (xy 24.517019 -250.818757)
			(xy 24.564625 -250.847811) (xy 24.607493 -250.883486) (xy 24.64471 -250.925023) (xy 24.675483 -250.971536)
			(xy 24.699155 -251.022033) (xy 24.715223 -251.07544) (xy 24.723343 -251.130616) (xy 24.723792 -251.1552)
			(xy 25.068782 -251.1552) (xy 25.072853 -251.099578) (xy 25.084979 -251.045141) (xy 25.104902 -250.99305)
			(xy 25.132198 -250.944415) (xy 25.166284 -250.900272) (xy 25.206433 -250.861563) (xy 25.251791 -250.829112)
			(xy 25.301391 -250.803611) (xy 25.354175 -250.785604) (xy 25.409018 -250.775474) (xy 25.464752 -250.773437)
			(xy 25.520189 -250.779537) (xy 25.574146 -250.793643) (xy 25.625475 -250.815455) (xy 25.673081 -250.844509)
			(xy 25.715949 -250.880184) (xy 25.753166 -250.921721) (xy 25.783939 -250.968234) (xy 25.807611 -251.018731)
			(xy 25.823679 -251.072138) (xy 25.831799 -251.127314) (xy 25.832308 -251.1552) (xy 25.832248 -251.158502)
			(xy 25.992326 -251.158502) (xy 25.996397 -251.10288) (xy 26.008523 -251.048443) (xy 26.028446 -250.996352)
			(xy 26.055742 -250.947717) (xy 26.089828 -250.903574) (xy 26.129977 -250.864865) (xy 26.175335 -250.832414)
			(xy 26.224935 -250.806913) (xy 26.277719 -250.788906) (xy 26.332562 -250.778776) (xy 26.388296 -250.776739)
			(xy 26.443733 -250.782839) (xy 26.49769 -250.796945) (xy 26.549019 -250.818757) (xy 26.596625 -250.847811)
			(xy 26.639493 -250.883486) (xy 26.67671 -250.925023) (xy 26.707483 -250.971536) (xy 26.731155 -251.022033)
			(xy 26.747223 -251.07544) (xy 26.755343 -251.130616) (xy 26.755852 -251.158502) (xy 27.008326 -251.158502)
			(xy 27.012397 -251.10288) (xy 27.024523 -251.048443) (xy 27.044446 -250.996352) (xy 27.071742 -250.947717)
			(xy 27.105828 -250.903574) (xy 27.145977 -250.864865) (xy 27.191335 -250.832414) (xy 27.240935 -250.806913)
			(xy 27.293719 -250.788906) (xy 27.348562 -250.778776) (xy 27.404296 -250.776739) (xy 27.459733 -250.782839)
			(xy 27.51369 -250.796945) (xy 27.565019 -250.818757) (xy 27.612625 -250.847811) (xy 27.655493 -250.883486)
			(xy 27.69271 -250.925023) (xy 27.723483 -250.971536) (xy 27.747155 -251.022033) (xy 27.763223 -251.07544)
			(xy 27.771343 -251.130616) (xy 27.771852 -251.158502) (xy 28.024326 -251.158502) (xy 28.028397 -251.10288)
			(xy 28.040523 -251.048443) (xy 28.060446 -250.996352) (xy 28.087742 -250.947717) (xy 28.121828 -250.903574)
			(xy 28.161977 -250.864865) (xy 28.207335 -250.832414) (xy 28.256935 -250.806913) (xy 28.309719 -250.788906)
			(xy 28.364562 -250.778776) (xy 28.420296 -250.776739) (xy 28.475733 -250.782839) (xy 28.52969 -250.796945)
			(xy 28.581019 -250.818757) (xy 28.628625 -250.847811) (xy 28.671493 -250.883486) (xy 28.70871 -250.925023)
			(xy 28.739483 -250.971536) (xy 28.763155 -251.022033) (xy 28.779223 -251.07544) (xy 28.787343 -251.130616)
			(xy 28.787852 -251.158502) (xy 29.040326 -251.158502) (xy 29.044397 -251.10288) (xy 29.056523 -251.048443)
			(xy 29.076446 -250.996352) (xy 29.103742 -250.947717) (xy 29.137828 -250.903574) (xy 29.177977 -250.864865)
			(xy 29.223335 -250.832414) (xy 29.272935 -250.806913) (xy 29.325719 -250.788906) (xy 29.380562 -250.778776)
			(xy 29.436296 -250.776739) (xy 29.491733 -250.782839) (xy 29.54569 -250.796945) (xy 29.597019 -250.818757)
			(xy 29.644625 -250.847811) (xy 29.687493 -250.883486) (xy 29.72471 -250.925023) (xy 29.755483 -250.971536)
			(xy 29.779155 -251.022033) (xy 29.795223 -251.07544) (xy 29.803343 -251.130616) (xy 29.803852 -251.158502)
			(xy 30.056326 -251.158502) (xy 30.060397 -251.10288) (xy 30.072523 -251.048443) (xy 30.092446 -250.996352)
			(xy 30.119742 -250.947717) (xy 30.153828 -250.903574) (xy 30.193977 -250.864865) (xy 30.239335 -250.832414)
			(xy 30.288935 -250.806913) (xy 30.341719 -250.788906) (xy 30.396562 -250.778776) (xy 30.452296 -250.776739)
			(xy 30.507733 -250.782839) (xy 30.56169 -250.796945) (xy 30.613019 -250.818757) (xy 30.660625 -250.847811)
			(xy 30.703493 -250.883486) (xy 30.74071 -250.925023) (xy 30.771483 -250.971536) (xy 30.795155 -251.022033)
			(xy 30.811223 -251.07544) (xy 30.819343 -251.130616) (xy 30.819852 -251.158502) (xy 31.072326 -251.158502)
			(xy 31.076397 -251.10288) (xy 31.088523 -251.048443) (xy 31.108446 -250.996352) (xy 31.135742 -250.947717)
			(xy 31.169828 -250.903574) (xy 31.209977 -250.864865) (xy 31.255335 -250.832414) (xy 31.304935 -250.806913)
			(xy 31.357719 -250.788906) (xy 31.412562 -250.778776) (xy 31.468296 -250.776739) (xy 31.523733 -250.782839)
			(xy 31.57769 -250.796945) (xy 31.629019 -250.818757) (xy 31.676625 -250.847811) (xy 31.719493 -250.883486)
			(xy 31.75671 -250.925023) (xy 31.787483 -250.971536) (xy 31.811155 -251.022033) (xy 31.827223 -251.07544)
			(xy 31.835343 -251.130616) (xy 31.835852 -251.158502) (xy 32.088326 -251.158502) (xy 32.092397 -251.10288)
			(xy 32.104523 -251.048443) (xy 32.124446 -250.996352) (xy 32.151742 -250.947717) (xy 32.185828 -250.903574)
			(xy 32.225977 -250.864865) (xy 32.271335 -250.832414) (xy 32.320935 -250.806913) (xy 32.373719 -250.788906)
			(xy 32.428562 -250.778776) (xy 32.484296 -250.776739) (xy 32.539733 -250.782839) (xy 32.59369 -250.796945)
			(xy 32.645019 -250.818757) (xy 32.692625 -250.847811) (xy 32.735493 -250.883486) (xy 32.77271 -250.925023)
			(xy 32.803483 -250.971536) (xy 32.827155 -251.022033) (xy 32.843223 -251.07544) (xy 32.851343 -251.130616)
			(xy 32.851852 -251.158502) (xy 33.104326 -251.158502) (xy 33.108397 -251.10288) (xy 33.120523 -251.048443)
			(xy 33.140446 -250.996352) (xy 33.167742 -250.947717) (xy 33.201828 -250.903574) (xy 33.241977 -250.864865)
			(xy 33.287335 -250.832414) (xy 33.336935 -250.806913) (xy 33.389719 -250.788906) (xy 33.444562 -250.778776)
			(xy 33.500296 -250.776739) (xy 33.555733 -250.782839) (xy 33.60969 -250.796945) (xy 33.661019 -250.818757)
			(xy 33.708625 -250.847811) (xy 33.751493 -250.883486) (xy 33.78871 -250.925023) (xy 33.819483 -250.971536)
			(xy 33.843155 -251.022033) (xy 33.859223 -251.07544) (xy 33.867343 -251.130616) (xy 33.867852 -251.158502)
			(xy 34.120326 -251.158502) (xy 34.124397 -251.10288) (xy 34.136523 -251.048443) (xy 34.156446 -250.996352)
			(xy 34.183742 -250.947717) (xy 34.217828 -250.903574) (xy 34.257977 -250.864865) (xy 34.303335 -250.832414)
			(xy 34.352935 -250.806913) (xy 34.405719 -250.788906) (xy 34.460562 -250.778776) (xy 34.516296 -250.776739)
			(xy 34.571733 -250.782839) (xy 34.62569 -250.796945) (xy 34.677019 -250.818757) (xy 34.724625 -250.847811)
			(xy 34.767493 -250.883486) (xy 34.80471 -250.925023) (xy 34.835483 -250.971536) (xy 34.859155 -251.022033)
			(xy 34.875223 -251.07544) (xy 34.883343 -251.130616) (xy 34.883852 -251.158502) (xy 35.136326 -251.158502)
			(xy 35.140397 -251.10288) (xy 35.152523 -251.048443) (xy 35.172446 -250.996352) (xy 35.199742 -250.947717)
			(xy 35.233828 -250.903574) (xy 35.273977 -250.864865) (xy 35.319335 -250.832414) (xy 35.368935 -250.806913)
			(xy 35.421719 -250.788906) (xy 35.476562 -250.778776) (xy 35.532296 -250.776739) (xy 35.587733 -250.782839)
			(xy 35.64169 -250.796945) (xy 35.693019 -250.818757) (xy 35.740625 -250.847811) (xy 35.783493 -250.883486)
			(xy 35.82071 -250.925023) (xy 35.851483 -250.971536) (xy 35.875155 -251.022033) (xy 35.891223 -251.07544)
			(xy 35.899343 -251.130616) (xy 35.899852 -251.158502) (xy 36.152326 -251.158502) (xy 36.156397 -251.10288)
			(xy 36.168523 -251.048443) (xy 36.188446 -250.996352) (xy 36.215742 -250.947717) (xy 36.249828 -250.903574)
			(xy 36.289977 -250.864865) (xy 36.335335 -250.832414) (xy 36.384935 -250.806913) (xy 36.437719 -250.788906)
			(xy 36.492562 -250.778776) (xy 36.548296 -250.776739) (xy 36.603733 -250.782839) (xy 36.65769 -250.796945)
			(xy 36.709019 -250.818757) (xy 36.756625 -250.847811) (xy 36.799493 -250.883486) (xy 36.83671 -250.925023)
			(xy 36.867483 -250.971536) (xy 36.891155 -251.022033) (xy 36.907223 -251.07544) (xy 36.915343 -251.130616)
			(xy 36.915852 -251.158502) (xy 37.168326 -251.158502) (xy 37.172397 -251.10288) (xy 37.184523 -251.048443)
			(xy 37.204446 -250.996352) (xy 37.231742 -250.947717) (xy 37.265828 -250.903574) (xy 37.305977 -250.864865)
			(xy 37.351335 -250.832414) (xy 37.400935 -250.806913) (xy 37.453719 -250.788906) (xy 37.508562 -250.778776)
			(xy 37.564296 -250.776739) (xy 37.619733 -250.782839) (xy 37.67369 -250.796945) (xy 37.725019 -250.818757)
			(xy 37.772625 -250.847811) (xy 37.815493 -250.883486) (xy 37.85271 -250.925023) (xy 37.883483 -250.971536)
			(xy 37.907155 -251.022033) (xy 37.923223 -251.07544) (xy 37.931343 -251.130616) (xy 37.931852 -251.158502)
			(xy 38.184326 -251.158502) (xy 38.188397 -251.10288) (xy 38.200523 -251.048443) (xy 38.220446 -250.996352)
			(xy 38.247742 -250.947717) (xy 38.281828 -250.903574) (xy 38.321977 -250.864865) (xy 38.367335 -250.832414)
			(xy 38.416935 -250.806913) (xy 38.469719 -250.788906) (xy 38.524562 -250.778776) (xy 38.580296 -250.776739)
			(xy 38.635733 -250.782839) (xy 38.68969 -250.796945) (xy 38.741019 -250.818757) (xy 38.788625 -250.847811)
			(xy 38.831493 -250.883486) (xy 38.86871 -250.925023) (xy 38.899483 -250.971536) (xy 38.923155 -251.022033)
			(xy 38.939223 -251.07544) (xy 38.947343 -251.130616) (xy 38.947852 -251.158502) (xy 40.216326 -251.158502)
			(xy 40.220397 -251.10288) (xy 40.232523 -251.048443) (xy 40.252446 -250.996352) (xy 40.279742 -250.947717)
			(xy 40.313828 -250.903574) (xy 40.353977 -250.864865) (xy 40.399335 -250.832414) (xy 40.448935 -250.806913)
			(xy 40.501719 -250.788906) (xy 40.556562 -250.778776) (xy 40.612296 -250.776739) (xy 40.667733 -250.782839)
			(xy 40.72169 -250.796945) (xy 40.773019 -250.818757) (xy 40.820625 -250.847811) (xy 40.863493 -250.883486)
			(xy 40.90071 -250.925023) (xy 40.931483 -250.971536) (xy 40.955155 -251.022033) (xy 40.971223 -251.07544)
			(xy 40.979343 -251.130616) (xy 40.979852 -251.158502) (xy 40.979343 -251.186388) (xy 40.971223 -251.241564)
			(xy 40.955155 -251.294971) (xy 40.931483 -251.345468) (xy 40.90071 -251.391981) (xy 40.863493 -251.433518)
			(xy 40.820625 -251.469193) (xy 40.773019 -251.498247) (xy 40.72169 -251.520059) (xy 40.667733 -251.534165)
			(xy 40.612296 -251.540265) (xy 40.556562 -251.538228) (xy 40.501719 -251.528098) (xy 40.448935 -251.510091)
			(xy 40.399335 -251.48459) (xy 40.353977 -251.452139) (xy 40.313828 -251.41343) (xy 40.279742 -251.369287)
			(xy 40.252446 -251.320652) (xy 40.232523 -251.268561) (xy 40.220397 -251.214124) (xy 40.216326 -251.158502)
			(xy 38.947852 -251.158502) (xy 38.947343 -251.186388) (xy 38.939223 -251.241564) (xy 38.923155 -251.294971)
			(xy 38.899483 -251.345468) (xy 38.86871 -251.391981) (xy 38.831493 -251.433518) (xy 38.788625 -251.469193)
			(xy 38.741019 -251.498247) (xy 38.68969 -251.520059) (xy 38.635733 -251.534165) (xy 38.580296 -251.540265)
			(xy 38.524562 -251.538228) (xy 38.469719 -251.528098) (xy 38.416935 -251.510091) (xy 38.367335 -251.48459)
			(xy 38.321977 -251.452139) (xy 38.281828 -251.41343) (xy 38.247742 -251.369287) (xy 38.220446 -251.320652)
			(xy 38.200523 -251.268561) (xy 38.188397 -251.214124) (xy 38.184326 -251.158502) (xy 37.931852 -251.158502)
			(xy 37.931343 -251.186388) (xy 37.923223 -251.241564) (xy 37.907155 -251.294971) (xy 37.883483 -251.345468)
			(xy 37.85271 -251.391981) (xy 37.815493 -251.433518) (xy 37.772625 -251.469193) (xy 37.725019 -251.498247)
			(xy 37.67369 -251.520059) (xy 37.619733 -251.534165) (xy 37.564296 -251.540265) (xy 37.508562 -251.538228)
			(xy 37.453719 -251.528098) (xy 37.400935 -251.510091) (xy 37.351335 -251.48459) (xy 37.305977 -251.452139)
			(xy 37.265828 -251.41343) (xy 37.231742 -251.369287) (xy 37.204446 -251.320652) (xy 37.184523 -251.268561)
			(xy 37.172397 -251.214124) (xy 37.168326 -251.158502) (xy 36.915852 -251.158502) (xy 36.915343 -251.186388)
			(xy 36.907223 -251.241564) (xy 36.891155 -251.294971) (xy 36.867483 -251.345468) (xy 36.83671 -251.391981)
			(xy 36.799493 -251.433518) (xy 36.756625 -251.469193) (xy 36.709019 -251.498247) (xy 36.65769 -251.520059)
			(xy 36.603733 -251.534165) (xy 36.548296 -251.540265) (xy 36.492562 -251.538228) (xy 36.437719 -251.528098)
			(xy 36.384935 -251.510091) (xy 36.335335 -251.48459) (xy 36.289977 -251.452139) (xy 36.249828 -251.41343)
			(xy 36.215742 -251.369287) (xy 36.188446 -251.320652) (xy 36.168523 -251.268561) (xy 36.156397 -251.214124)
			(xy 36.152326 -251.158502) (xy 35.899852 -251.158502) (xy 35.899343 -251.186388) (xy 35.891223 -251.241564)
			(xy 35.875155 -251.294971) (xy 35.851483 -251.345468) (xy 35.82071 -251.391981) (xy 35.783493 -251.433518)
			(xy 35.740625 -251.469193) (xy 35.693019 -251.498247) (xy 35.64169 -251.520059) (xy 35.587733 -251.534165)
			(xy 35.532296 -251.540265) (xy 35.476562 -251.538228) (xy 35.421719 -251.528098) (xy 35.368935 -251.510091)
			(xy 35.319335 -251.48459) (xy 35.273977 -251.452139) (xy 35.233828 -251.41343) (xy 35.199742 -251.369287)
			(xy 35.172446 -251.320652) (xy 35.152523 -251.268561) (xy 35.140397 -251.214124) (xy 35.136326 -251.158502)
			(xy 34.883852 -251.158502) (xy 34.883343 -251.186388) (xy 34.875223 -251.241564) (xy 34.859155 -251.294971)
			(xy 34.835483 -251.345468) (xy 34.80471 -251.391981) (xy 34.767493 -251.433518) (xy 34.724625 -251.469193)
			(xy 34.677019 -251.498247) (xy 34.62569 -251.520059) (xy 34.571733 -251.534165) (xy 34.516296 -251.540265)
			(xy 34.460562 -251.538228) (xy 34.405719 -251.528098) (xy 34.352935 -251.510091) (xy 34.303335 -251.48459)
			(xy 34.257977 -251.452139) (xy 34.217828 -251.41343) (xy 34.183742 -251.369287) (xy 34.156446 -251.320652)
			(xy 34.136523 -251.268561) (xy 34.124397 -251.214124) (xy 34.120326 -251.158502) (xy 33.867852 -251.158502)
			(xy 33.867343 -251.186388) (xy 33.859223 -251.241564) (xy 33.843155 -251.294971) (xy 33.819483 -251.345468)
			(xy 33.78871 -251.391981) (xy 33.751493 -251.433518) (xy 33.708625 -251.469193) (xy 33.661019 -251.498247)
			(xy 33.60969 -251.520059) (xy 33.555733 -251.534165) (xy 33.500296 -251.540265) (xy 33.444562 -251.538228)
			(xy 33.389719 -251.528098) (xy 33.336935 -251.510091) (xy 33.287335 -251.48459) (xy 33.241977 -251.452139)
			(xy 33.201828 -251.41343) (xy 33.167742 -251.369287) (xy 33.140446 -251.320652) (xy 33.120523 -251.268561)
			(xy 33.108397 -251.214124) (xy 33.104326 -251.158502) (xy 32.851852 -251.158502) (xy 32.851343 -251.186388)
			(xy 32.843223 -251.241564) (xy 32.827155 -251.294971) (xy 32.803483 -251.345468) (xy 32.77271 -251.391981)
			(xy 32.735493 -251.433518) (xy 32.692625 -251.469193) (xy 32.645019 -251.498247) (xy 32.59369 -251.520059)
			(xy 32.539733 -251.534165) (xy 32.484296 -251.540265) (xy 32.428562 -251.538228) (xy 32.373719 -251.528098)
			(xy 32.320935 -251.510091) (xy 32.271335 -251.48459) (xy 32.225977 -251.452139) (xy 32.185828 -251.41343)
			(xy 32.151742 -251.369287) (xy 32.124446 -251.320652) (xy 32.104523 -251.268561) (xy 32.092397 -251.214124)
			(xy 32.088326 -251.158502) (xy 31.835852 -251.158502) (xy 31.835343 -251.186388) (xy 31.827223 -251.241564)
			(xy 31.811155 -251.294971) (xy 31.787483 -251.345468) (xy 31.75671 -251.391981) (xy 31.719493 -251.433518)
			(xy 31.676625 -251.469193) (xy 31.629019 -251.498247) (xy 31.57769 -251.520059) (xy 31.523733 -251.534165)
			(xy 31.468296 -251.540265) (xy 31.412562 -251.538228) (xy 31.357719 -251.528098) (xy 31.304935 -251.510091)
			(xy 31.255335 -251.48459) (xy 31.209977 -251.452139) (xy 31.169828 -251.41343) (xy 31.135742 -251.369287)
			(xy 31.108446 -251.320652) (xy 31.088523 -251.268561) (xy 31.076397 -251.214124) (xy 31.072326 -251.158502)
			(xy 30.819852 -251.158502) (xy 30.819343 -251.186388) (xy 30.811223 -251.241564) (xy 30.795155 -251.294971)
			(xy 30.771483 -251.345468) (xy 30.74071 -251.391981) (xy 30.703493 -251.433518) (xy 30.660625 -251.469193)
			(xy 30.613019 -251.498247) (xy 30.56169 -251.520059) (xy 30.507733 -251.534165) (xy 30.452296 -251.540265)
			(xy 30.396562 -251.538228) (xy 30.341719 -251.528098) (xy 30.288935 -251.510091) (xy 30.239335 -251.48459)
			(xy 30.193977 -251.452139) (xy 30.153828 -251.41343) (xy 30.119742 -251.369287) (xy 30.092446 -251.320652)
			(xy 30.072523 -251.268561) (xy 30.060397 -251.214124) (xy 30.056326 -251.158502) (xy 29.803852 -251.158502)
			(xy 29.803343 -251.186388) (xy 29.795223 -251.241564) (xy 29.779155 -251.294971) (xy 29.755483 -251.345468)
			(xy 29.72471 -251.391981) (xy 29.687493 -251.433518) (xy 29.644625 -251.469193) (xy 29.597019 -251.498247)
			(xy 29.54569 -251.520059) (xy 29.491733 -251.534165) (xy 29.436296 -251.540265) (xy 29.380562 -251.538228)
			(xy 29.325719 -251.528098) (xy 29.272935 -251.510091) (xy 29.223335 -251.48459) (xy 29.177977 -251.452139)
			(xy 29.137828 -251.41343) (xy 29.103742 -251.369287) (xy 29.076446 -251.320652) (xy 29.056523 -251.268561)
			(xy 29.044397 -251.214124) (xy 29.040326 -251.158502) (xy 28.787852 -251.158502) (xy 28.787343 -251.186388)
			(xy 28.779223 -251.241564) (xy 28.763155 -251.294971) (xy 28.739483 -251.345468) (xy 28.70871 -251.391981)
			(xy 28.671493 -251.433518) (xy 28.628625 -251.469193) (xy 28.581019 -251.498247) (xy 28.52969 -251.520059)
			(xy 28.475733 -251.534165) (xy 28.420296 -251.540265) (xy 28.364562 -251.538228) (xy 28.309719 -251.528098)
			(xy 28.256935 -251.510091) (xy 28.207335 -251.48459) (xy 28.161977 -251.452139) (xy 28.121828 -251.41343)
			(xy 28.087742 -251.369287) (xy 28.060446 -251.320652) (xy 28.040523 -251.268561) (xy 28.028397 -251.214124)
			(xy 28.024326 -251.158502) (xy 27.771852 -251.158502) (xy 27.771343 -251.186388) (xy 27.763223 -251.241564)
			(xy 27.747155 -251.294971) (xy 27.723483 -251.345468) (xy 27.69271 -251.391981) (xy 27.655493 -251.433518)
			(xy 27.612625 -251.469193) (xy 27.565019 -251.498247) (xy 27.51369 -251.520059) (xy 27.459733 -251.534165)
			(xy 27.404296 -251.540265) (xy 27.348562 -251.538228) (xy 27.293719 -251.528098) (xy 27.240935 -251.510091)
			(xy 27.191335 -251.48459) (xy 27.145977 -251.452139) (xy 27.105828 -251.41343) (xy 27.071742 -251.369287)
			(xy 27.044446 -251.320652) (xy 27.024523 -251.268561) (xy 27.012397 -251.214124) (xy 27.008326 -251.158502)
			(xy 26.755852 -251.158502) (xy 26.755343 -251.186388) (xy 26.747223 -251.241564) (xy 26.731155 -251.294971)
			(xy 26.707483 -251.345468) (xy 26.67671 -251.391981) (xy 26.639493 -251.433518) (xy 26.596625 -251.469193)
			(xy 26.549019 -251.498247) (xy 26.49769 -251.520059) (xy 26.443733 -251.534165) (xy 26.388296 -251.540265)
			(xy 26.332562 -251.538228) (xy 26.277719 -251.528098) (xy 26.224935 -251.510091) (xy 26.175335 -251.48459)
			(xy 26.129977 -251.452139) (xy 26.089828 -251.41343) (xy 26.055742 -251.369287) (xy 26.028446 -251.320652)
			(xy 26.008523 -251.268561) (xy 25.996397 -251.214124) (xy 25.992326 -251.158502) (xy 25.832248 -251.158502)
			(xy 25.831799 -251.183086) (xy 25.823679 -251.238262) (xy 25.807611 -251.291669) (xy 25.783939 -251.342166)
			(xy 25.753166 -251.388679) (xy 25.715949 -251.430216) (xy 25.673081 -251.465891) (xy 25.625475 -251.494945)
			(xy 25.574146 -251.516757) (xy 25.520189 -251.530863) (xy 25.464752 -251.536963) (xy 25.409018 -251.534926)
			(xy 25.354175 -251.524796) (xy 25.301391 -251.506789) (xy 25.251791 -251.481288) (xy 25.206433 -251.448837)
			(xy 25.166284 -251.410128) (xy 25.132198 -251.365985) (xy 25.104902 -251.31735) (xy 25.084979 -251.265259)
			(xy 25.072853 -251.210822) (xy 25.068782 -251.1552) (xy 24.723792 -251.1552) (xy 24.723852 -251.158502)
			(xy 24.723343 -251.186388) (xy 24.715223 -251.241564) (xy 24.699155 -251.294971) (xy 24.675483 -251.345468)
			(xy 24.64471 -251.391981) (xy 24.607493 -251.433518) (xy 24.564625 -251.469193) (xy 24.517019 -251.498247)
			(xy 24.46569 -251.520059) (xy 24.411733 -251.534165) (xy 24.356296 -251.540265) (xy 24.300562 -251.538228)
			(xy 24.245719 -251.528098) (xy 24.192935 -251.510091) (xy 24.143335 -251.48459) (xy 24.097977 -251.452139)
			(xy 24.057828 -251.41343) (xy 24.023742 -251.369287) (xy 23.996446 -251.320652) (xy 23.976523 -251.268561)
			(xy 23.964397 -251.214124) (xy 23.960326 -251.158502) (xy 0.61722 -251.158502) (xy 0.61722 -251.518928)
			(xy 0.617982 -251.52731) (xy 0.619497 -251.534915) (xy 0.626484 -251.548748) (xy 0.631698 -251.554488)
			(xy 1.415542 -252.338332) (xy 1.421289 -252.343535) (xy 1.43512 -252.350521) (xy 1.44272 -252.352048)
			(xy 1.451102 -252.35281) (xy 8.942578 -252.35281) (xy 8.947676 -252.35292) (xy 8.957663 -252.354963)
			(xy 8.96239 -252.356874) (xy 8.962644 -252.356874) (xy 8.9789 -252.363732) (xy 8.988298 -252.367796)
			(xy 53.23967 -252.367796) (xy 53.252973 -252.367366) (xy 53.278676 -252.360488) (xy 53.301723 -252.347193)
			(xy 53.320544 -252.328387) (xy 53.333857 -252.305351) (xy 53.337714 -252.292612) (xy 53.339363 -252.285301)
			(xy 53.33884 -252.27033) (xy 53.336698 -252.263148) (xy 24.677878 -167.59174) (xy 24.674878 -167.589558)
			(xy 24.668374 -167.585991) (xy 24.664924 -167.584628) (xy 24.62911 -167.570912) (xy 24.62784 -167.570404)
			(xy 24.618188 -167.566848) (xy 24.61401 -167.565436) (xy 24.605325 -167.563898) (xy 24.600916 -167.5638)
			(xy 24.570182 -167.5638) (xy 24.563578 -167.564562) (xy 24.559211 -167.56526) (xy 24.550786 -167.567949)
			(xy 24.546814 -167.569896) (xy 24.54402 -167.57142) (xy 24.533606 -167.5765) (xy 24.525986 -167.580056)
			(xy 24.500314 -167.591408) (xy 24.446521 -167.607445) (xy 24.390983 -167.615592) (xy 24.362918 -167.616124)
			(xy 24.332869 -167.615571) (xy 24.273486 -167.606333) (xy 24.216234 -167.588059) (xy 24.16248 -167.561185)
			(xy 24.113507 -167.526352) (xy 24.070483 -167.484392) (xy 24.052022 -167.460676) (xy 24.04999 -167.457882)
			(xy 24.044148 -167.45204) (xy 24.037287 -167.445794) (xy 24.020359 -167.438232) (xy 24.011128 -167.437308)
			(xy 23.978108 -167.437054) (xy 23.9776 -167.437054) (xy 23.93823 -167.4368) (xy 23.926536 -167.437318)
			(xy 23.905484 -167.447493) (xy 23.897844 -167.456358) (xy 23.89759 -167.456612) (xy 23.895812 -167.458898)
			(xy 23.877619 -167.481207) (xy 23.835662 -167.520615) (xy 23.78826 -167.553273) (xy 23.736491 -167.57844)
			(xy 23.681528 -167.595544) (xy 23.624619 -167.604197) (xy 23.595838 -167.604694) (xy 23.568584 -167.604233)
			(xy 23.514631 -167.596481) (xy 23.462331 -167.581129) (xy 23.412748 -167.558489) (xy 23.366892 -167.529023)
			(xy 23.325696 -167.493331) (xy 23.289999 -167.452139) (xy 23.260529 -167.406286) (xy 23.237884 -167.356705)
			(xy 23.222527 -167.304406) (xy 23.214769 -167.250454) (xy 23.214769 -167.195946) (xy 23.222527 -167.141994)
			(xy 23.237884 -167.089695) (xy 23.260529 -167.040114) (xy 23.289999 -166.994261) (xy 23.325696 -166.953069)
			(xy 23.366892 -166.917377) (xy 23.412748 -166.887911) (xy 23.462331 -166.865271) (xy 23.514631 -166.849919)
			(xy 23.568584 -166.842167) (xy 23.595838 -166.841678) (xy 23.596092 -166.841678) (xy 23.624464 -166.842198)
			(xy 23.680581 -166.850603) (xy 23.734835 -166.867229) (xy 23.786026 -166.89171) (xy 23.833025 -166.923504)
			(xy 23.874796 -166.961911) (xy 23.893018 -166.983664) (xy 23.893018 -166.983918) (xy 23.899876 -166.992046)
			(xy 23.929594 -167.007286) (xy 23.934906 -167.009813) (xy 23.946322 -167.01264) (xy 23.9522 -167.012874)
			(xy 23.980648 -167.013128) (xy 23.981156 -167.013128) (xy 24.010874 -167.013382) (xy 24.022304 -167.012112)
			(xy 24.030967 -167.009841) (xy 24.046053 -167.000211) (xy 24.051768 -166.993316) (xy 24.052276 -166.992808)
			(xy 24.054308 -166.990014) (xy 24.064221 -166.977366) (xy 24.085839 -166.953585) (xy 24.097488 -166.942516)
			(xy 24.09825 -166.942008) (xy 24.103838 -166.93642) (xy 24.109443 -166.92992) (xy 24.116335 -166.914213)
			(xy 24.1173 -166.905686) (xy 24.11857 -166.85006) (xy 24.11857 -166.849552) (xy 24.118824 -166.841678)
			(xy 24.119078 -166.831264) (xy 24.115268 -166.821358) (xy 24.113435 -166.816892) (xy 24.108318 -166.808708)
			(xy 24.105108 -166.805102) (xy 24.104346 -166.80434) (xy 24.103838 -166.803832) (xy 24.096726 -166.796466)
			(xy 24.096218 -166.795958) (xy 24.077416 -166.774722) (xy 24.045652 -166.727735) (xy 24.021189 -166.676566)
			(xy 24.004565 -166.62234) (xy 23.996146 -166.566252) (xy 23.995634 -166.537894) (xy 23.995634 -166.53764)
			(xy 23.996061 -166.511881) (xy 24.002997 -166.460833) (xy 24.016735 -166.411181) (xy 24.037026 -166.363828)
			(xy 24.0635 -166.319634) (xy 24.095677 -166.279401) (xy 24.113998 -166.261288) (xy 24.127376 -166.2488)
			(xy 24.156127 -166.226155) (xy 24.171402 -166.216076) (xy 24.178514 -166.211504) (xy 24.186642 -166.203376)
			(xy 24.191232 -166.198432) (xy 24.197932 -166.186729) (xy 24.19985 -166.180262) (xy 23.135082 -163.034218)
			(xy 23.124921 -163.003416) (xy 23.108144 -162.940755) (xy 23.101554 -162.908996) (xy 22.536912 -160.070292)
			(xy 22.530061 -160.034234) (xy 22.521032 -159.961389) (xy 22.518878 -159.92475) (xy 22.353778 -156.558742)
			(xy 22.353016 -156.552646) (xy 22.095206 -155.07589) (xy 22.089043 -155.038458) (xy 22.081794 -154.962935)
			(xy 22.080728 -154.925014) (xy 22.068536 -154.28976) (xy 22.067012 -154.213814) (xy 22.067012 -154.213306)
			(xy 22.066504 -154.18054) (xy 22.066172 -154.174426) (xy 22.062967 -154.162611) (xy 22.060154 -154.157172)
			(xy 22.05736 -154.152092) (xy 22.048724 -154.142694) (xy 22.043136 -154.139138) (xy 22.017898 -154.122365)
			(xy 21.972042 -154.082747) (xy 21.932305 -154.036997) (xy 21.899496 -153.986047) (xy 21.874287 -153.930941)
			(xy 21.857194 -153.872803) (xy 21.848564 -153.812822) (xy 21.848064 -153.782522) (xy 21.848064 -153.782268)
			(xy 21.84855 -153.75396) (xy 21.856117 -153.697852) (xy 21.871084 -153.64325) (xy 21.893185 -153.591127)
			(xy 21.922028 -153.542408) (xy 21.957099 -153.497963) (xy 21.997773 -153.45858) (xy 22.020276 -153.4414)
			(xy 22.02053 -153.441146) (xy 22.029928 -153.434034) (xy 22.03323 -153.427938) (xy 22.039326 -153.420826)
			(xy 22.051772 -153.396442) (xy 22.05101 -153.38298) (xy 22.05101 -153.379932) (xy 22.017482 -151.630126)
			(xy 21.956268 -148.464524) (xy 21.956268 -148.463) (xy 21.940774 -148.148802) (xy 21.940121 -148.141414)
			(xy 21.935091 -148.127467) (xy 21.930868 -148.12137) (xy 21.92528 -148.113496) (xy 21.925026 -148.113242)
			(xy 21.920746 -148.107732) (xy 21.909792 -148.099101) (xy 21.903436 -148.096224) (xy 21.902928 -148.09597)
			(xy 21.894546 -148.092668) (xy 21.868377 -148.080957) (xy 21.819593 -148.050844) (xy 21.775863 -148.013771)
			(xy 21.738173 -147.970571) (xy 21.707371 -147.922219) (xy 21.68415 -147.869801) (xy 21.669035 -147.8145)
			(xy 21.665184 -147.78609) (xy 21.66366 -147.771866) (xy 21.66239 -147.741386) (xy 21.66239 -147.721066)
			(xy 21.66366 -147.709128) (xy 21.666572 -147.680913) (xy 21.679681 -147.625728) (xy 21.700822 -147.573094)
			(xy 21.729529 -147.524175) (xy 21.765168 -147.480049) (xy 21.806951 -147.44169) (xy 21.853957 -147.409947)
			(xy 21.879306 -147.397216) (xy 21.880322 -147.396708) (xy 21.886926 -147.393406) (xy 21.90242 -147.367244)
			(xy 21.818346 -145.65249) (xy 21.818027 -145.648118) (xy 21.816109 -145.639564) (xy 21.814536 -145.635472)
			(xy 20.343622 -142.084298) (xy 20.339702 -142.07598) (xy 20.327077 -142.062631) (xy 20.310567 -142.054568)
			(xy 20.301458 -142.05331) (xy 20.19808 -142.043404) (xy 20.172426 -142.055596) (xy 20.164806 -142.067534)
			(xy 20.155627 -142.081168) (xy 20.135275 -142.106982) (xy 20.124166 -142.119096) (xy 20.119086 -142.12443)
			(xy 20.112736 -142.13713) (xy 20.11045 -142.149322) (xy 20.11045 -142.222728) (xy 20.110507 -142.227002)
			(xy 20.111907 -142.235433) (xy 20.113244 -142.239492) (xy 20.11807 -142.251176) (xy 20.12442 -142.258034)
			(xy 20.143658 -142.279365) (xy 20.176159 -142.326726) (xy 20.201192 -142.378424) (xy 20.218191 -142.433291)
			(xy 20.226772 -142.490087) (xy 20.226741 -142.547527) (xy 20.218098 -142.604313) (xy 20.201039 -142.659162)
			(xy 20.17595 -142.710833) (xy 20.143398 -142.758158) (xy 20.124166 -142.779496) (xy 20.119086 -142.78483)
			(xy 20.112736 -142.79753) (xy 20.11045 -142.809722) (xy 20.11045 -142.883128) (xy 20.11057 -142.887676)
			(xy 20.112225 -142.896622) (xy 20.113752 -142.900908) (xy 20.11807 -142.91183) (xy 20.125182 -142.919196)
			(xy 20.144272 -142.940493) (xy 20.176512 -142.98773) (xy 20.201348 -143.039247) (xy 20.218223 -143.093892)
			(xy 20.226761 -143.150442) (xy 20.22729 -143.179038) (xy 20.22729 -143.18107) (xy 20.22729 -143.188436)
			(xy 20.226362 -143.212707) (xy 20.219101 -143.260733) (xy 20.212812 -143.284194) (xy 20.209256 -143.295624)
			(xy 20.199792 -143.323302) (xy 20.173639 -143.375623) (xy 20.139808 -143.423338) (xy 20.119848 -143.444722)
			(xy 20.096988 -143.46809) (xy 20.091654 -143.473678) (xy 20.088098 -143.480536) (xy 20.07997 -143.496538)
			(xy 20.078954 -143.500094) (xy 20.074636 -143.510762) (xy 20.074636 -143.57477) (xy 20.074806 -143.580287)
			(xy 20.077251 -143.591048) (xy 20.079462 -143.596106) (xy 20.092416 -143.6243) (xy 20.10029 -143.631412)
			(xy 20.119906 -143.649582) (xy 20.154367 -143.690463) (xy 20.182781 -143.735757) (xy 20.204592 -143.784574)
			(xy 20.219373 -143.835959) (xy 20.226834 -143.888904) (xy 20.22729 -143.915638) (xy 20.226801 -143.942887)
			(xy 20.21904 -143.99683) (xy 20.203682 -144.049119) (xy 20.181038 -144.09869) (xy 20.15157 -144.144534)
			(xy 20.115879 -144.185718) (xy 20.074689 -144.221404) (xy 20.028841 -144.250865) (xy 19.979266 -144.273501)
			(xy 19.926975 -144.288852) (xy 19.873031 -144.296605) (xy 19.845782 -144.297146) (xy 19.818957 -144.296683)
			(xy 19.765837 -144.289154) (xy 19.714294 -144.274263) (xy 19.665345 -144.252301) (xy 19.619952 -144.223702)
			(xy 19.579011 -144.189029) (xy 19.543328 -144.148965) (xy 19.513606 -144.104299) (xy 19.49043 -144.055912)
			(xy 19.474258 -144.004757) (xy 19.465408 -143.951841) (xy 19.464274 -143.925036) (xy 19.464274 -143.91513)
			(xy 19.464752 -143.888328) (xy 19.472299 -143.835257) (xy 19.487193 -143.783763) (xy 19.509141 -143.734857)
			(xy 19.537712 -143.689501) (xy 19.572344 -143.648585) (xy 19.592036 -143.630396) (xy 19.5961 -143.626586)
			(xy 19.602196 -143.618204) (xy 19.612356 -143.595598) (xy 19.616928 -143.585438) (xy 19.616928 -143.519906)
			(xy 19.616766 -143.514387) (xy 19.614339 -143.503617) (xy 19.612102 -143.49857) (xy 19.599148 -143.470376)
			(xy 19.591274 -143.463264) (xy 19.571656 -143.445096) (xy 19.537193 -143.404215) (xy 19.508776 -143.358922)
			(xy 19.486964 -143.310105) (xy 19.472184 -143.258719) (xy 19.464725 -143.205773) (xy 19.464274 -143.179038)
			(xy 19.464793 -143.150298) (xy 19.473412 -143.093469) (xy 19.49046 -143.038576) (xy 19.515552 -142.986863)
			(xy 19.54812 -142.939501) (xy 19.567398 -142.91818) (xy 19.572478 -142.912846) (xy 19.578828 -142.900146)
			(xy 19.581114 -142.887954) (xy 19.581114 -142.814548) (xy 19.581055 -142.810275) (xy 19.57965 -142.801845)
			(xy 19.57832 -142.797784) (xy 19.573494 -142.7861) (xy 19.567144 -142.779242) (xy 19.547904 -142.757911)
			(xy 19.515399 -142.710549) (xy 19.490362 -142.65885) (xy 19.473359 -142.603981) (xy 19.464775 -142.547183)
			(xy 19.464803 -142.489741) (xy 19.473444 -142.432951) (xy 19.490501 -142.378099) (xy 19.515589 -142.326425)
			(xy 19.548141 -142.279095) (xy 19.567398 -142.25778) (xy 19.572478 -142.252446) (xy 19.578828 -142.239746)
			(xy 19.581114 -142.227554) (xy 19.581114 -142.154148) (xy 19.581055 -142.149875) (xy 19.57965 -142.141445)
			(xy 19.57832 -142.137384) (xy 19.573494 -142.1257) (xy 19.567144 -142.118842) (xy 19.547904 -142.097511)
			(xy 19.515399 -142.050149) (xy 19.490362 -141.99845) (xy 19.473359 -141.943581) (xy 19.464775 -141.886783)
			(xy 19.464803 -141.829341) (xy 19.473444 -141.772551) (xy 19.490501 -141.717699) (xy 19.515589 -141.666025)
			(xy 19.548141 -141.618695) (xy 19.567398 -141.59738) (xy 19.572478 -141.592046) (xy 19.578828 -141.579346)
			(xy 19.581114 -141.567154) (xy 19.581114 -141.493748) (xy 19.581055 -141.489475) (xy 19.57965 -141.481045)
			(xy 19.57832 -141.476984) (xy 19.573494 -141.4653) (xy 19.567144 -141.458442) (xy 19.547904 -141.437111)
			(xy 19.515399 -141.389749) (xy 19.490362 -141.33805) (xy 19.473359 -141.283181) (xy 19.464775 -141.226383)
			(xy 19.464803 -141.168941) (xy 19.473444 -141.112151) (xy 19.490501 -141.057299) (xy 19.515589 -141.005625)
			(xy 19.548141 -140.958295) (xy 19.567398 -140.93698) (xy 19.572478 -140.931646) (xy 19.578828 -140.918946)
			(xy 19.581114 -140.906754) (xy 19.581114 -140.833348) (xy 19.580992 -140.8288) (xy 19.579335 -140.819855)
			(xy 19.577812 -140.815568) (xy 19.573494 -140.804646) (xy 19.566382 -140.79728) (xy 19.54729 -140.775984)
			(xy 19.515043 -140.728747) (xy 19.490199 -140.677231) (xy 19.473315 -140.622586) (xy 19.464766 -140.566035)
			(xy 19.464274 -140.537438) (xy 19.464351 -140.5247) (xy 19.466002 -140.499278) (xy 19.467576 -140.486638)
			(xy 19.471979 -140.457945) (xy 19.488323 -140.402247) (xy 19.512899 -140.34966) (xy 19.545142 -140.301392)
			(xy 19.56435 -140.279628) (xy 19.570548 -140.272215) (xy 19.577381 -140.254156) (xy 19.577077 -140.234851)
			(xy 19.573748 -140.22578) (xy 19.351244 -139.688316) (xy 19.346287 -139.677828) (xy 19.32893 -139.662472)
			(xy 19.306603 -139.656264) (xy 19.29511 -139.657836) (xy 19.294856 -139.657836) (xy 19.277491 -139.660901)
			(xy 19.242383 -139.664213) (xy 19.224752 -139.66444) (xy 19.197384 -139.663965) (xy 19.14321 -139.656134)
			(xy 19.090711 -139.640639) (xy 19.040967 -139.6178) (xy 18.994998 -139.588085) (xy 18.974054 -139.57046)
			(xy 18.9738 -139.57046) (xy 18.9738 -139.570206) (xy 18.966714 -139.56462) (xy 18.949796 -139.558377)
			(xy 18.94078 -139.558014) (xy 18.873724 -139.558014) (xy 18.864706 -139.55837) (xy 18.847786 -139.564612)
			(xy 18.840704 -139.570206) (xy 18.84045 -139.57046) (xy 18.819517 -139.588101) (xy 18.773549 -139.617825)
			(xy 18.723803 -139.640671) (xy 18.671301 -139.656167) (xy 18.617123 -139.663996) (xy 18.562381 -139.663996)
			(xy 18.508203 -139.656167) (xy 18.455701 -139.640671) (xy 18.405955 -139.617825) (xy 18.359987 -139.588101)
			(xy 18.339054 -139.57046) (xy 18.3388 -139.57046) (xy 18.3388 -139.570206) (xy 18.331714 -139.56462)
			(xy 18.314796 -139.558377) (xy 18.30578 -139.558014) (xy 18.238724 -139.558014) (xy 18.229706 -139.55837)
			(xy 18.212786 -139.564612) (xy 18.205704 -139.570206) (xy 18.20545 -139.57046) (xy 18.184517 -139.588101)
			(xy 18.138549 -139.617825) (xy 18.088803 -139.640671) (xy 18.036301 -139.656167) (xy 17.982123 -139.663996)
			(xy 17.927381 -139.663996) (xy 17.873203 -139.656167) (xy 17.820701 -139.640671) (xy 17.770955 -139.617825)
			(xy 17.724987 -139.588101) (xy 17.704054 -139.57046) (xy 17.7038 -139.57046) (xy 17.7038 -139.570206)
			(xy 17.696714 -139.56462) (xy 17.679796 -139.558377) (xy 17.67078 -139.558014) (xy 17.603724 -139.558014)
			(xy 17.594706 -139.55837) (xy 17.577786 -139.564612) (xy 17.570704 -139.570206) (xy 17.57045 -139.57046)
			(xy 17.549519 -139.588101) (xy 17.503552 -139.617824) (xy 17.453805 -139.640663) (xy 17.401301 -139.656148)
			(xy 17.347122 -139.66396) (xy 17.319752 -139.66444) (xy 17.292502 -139.663951) (xy 17.238558 -139.656189)
			(xy 17.186267 -139.64083) (xy 17.136694 -139.618187) (xy 17.090847 -139.58872) (xy 17.04966 -139.553029)
			(xy 17.013971 -139.51184) (xy 16.984506 -139.465992) (xy 16.961864 -139.416418) (xy 16.946508 -139.364126)
			(xy 16.938748 -139.310182) (xy 16.938244 -139.282932) (xy 16.938789 -139.254142) (xy 16.947478 -139.197222)
			(xy 16.96462 -139.142253) (xy 16.989824 -139.090482) (xy 17.02252 -139.043085) (xy 17.061964 -139.001138)
			(xy 17.084294 -138.982958) (xy 17.092978 -138.975435) (xy 17.103047 -138.954808) (xy 17.103598 -138.943334)
			(xy 17.104106 -138.851894) (xy 17.093946 -138.830812) (xy 17.084802 -138.8237) (xy 17.062914 -138.80548)
			(xy 17.024263 -138.763657) (xy 16.992254 -138.716556) (xy 16.967595 -138.665223) (xy 16.950835 -138.610797)
			(xy 16.942345 -138.554486) (xy 16.9418 -138.526012) (xy 16.9418 -138.525758) (xy 16.942275 -138.498389)
			(xy 16.950104 -138.444214) (xy 16.965596 -138.391714) (xy 16.988432 -138.341966) (xy 17.018143 -138.295994)
			(xy 17.03578 -138.27506) (xy 17.03578 -138.274806) (xy 17.036034 -138.274806) (xy 17.041617 -138.267718)
			(xy 17.047857 -138.250801) (xy 17.048226 -138.241786) (xy 17.048226 -138.17473) (xy 17.047872 -138.165711)
			(xy 17.041635 -138.148787) (xy 17.036034 -138.14171) (xy 17.03578 -138.141456) (xy 17.018139 -138.120523)
			(xy 16.988415 -138.074556) (xy 16.965569 -138.024809) (xy 16.950073 -137.972307) (xy 16.942245 -137.918129)
			(xy 16.942245 -137.863388) (xy 16.950074 -137.80921) (xy 16.96557 -137.756708) (xy 16.988416 -137.706962)
			(xy 17.018141 -137.660994) (xy 17.03578 -137.64006) (xy 17.03578 -137.639806) (xy 17.036034 -137.639806)
			(xy 17.041617 -137.632718) (xy 17.047857 -137.615801) (xy 17.048226 -137.606786) (xy 17.048226 -137.53973)
			(xy 17.047872 -137.530711) (xy 17.041635 -137.513787) (xy 17.036034 -137.50671) (xy 17.03578 -137.506456)
			(xy 17.018139 -137.485523) (xy 16.988415 -137.439556) (xy 16.965569 -137.389809) (xy 16.950073 -137.337307)
			(xy 16.942245 -137.283129) (xy 16.942245 -137.228388) (xy 16.950074 -137.17421) (xy 16.96557 -137.121708)
			(xy 16.988416 -137.071962) (xy 17.018141 -137.025994) (xy 17.03578 -137.00506) (xy 17.03578 -137.004806)
			(xy 17.036034 -137.004806) (xy 17.041617 -136.997718) (xy 17.047857 -136.980801) (xy 17.048226 -136.971786)
			(xy 17.048226 -136.90473) (xy 17.047872 -136.895711) (xy 17.041635 -136.878787) (xy 17.036034 -136.87171)
			(xy 17.03578 -136.871456) (xy 17.018141 -136.850523) (xy 16.988422 -136.804555) (xy 16.965586 -136.754808)
			(xy 16.950103 -136.702305) (xy 16.942291 -136.648127) (xy 16.9418 -136.620758) (xy 16.942286 -136.593507)
			(xy 16.950042 -136.539559) (xy 16.965397 -136.487264) (xy 16.988039 -136.437687) (xy 17.017505 -136.391837)
			(xy 17.053196 -136.350646) (xy 17.094387 -136.314955) (xy 17.140237 -136.285489) (xy 17.189814 -136.262847)
			(xy 17.242109 -136.247492) (xy 17.296057 -136.239736) (xy 17.350559 -136.239736) (xy 17.404507 -136.247492)
			(xy 17.456802 -136.262847) (xy 17.506379 -136.285489) (xy 17.552229 -136.314955) (xy 17.59342 -136.350646)
			(xy 17.629111 -136.391837) (xy 17.658577 -136.437687) (xy 17.681219 -136.487264) (xy 17.696574 -136.539559)
			(xy 17.70433 -136.593507) (xy 17.704816 -136.620758) (xy 17.70434 -136.648127) (xy 17.696509 -136.702301)
			(xy 17.681016 -136.7548) (xy 17.65818 -136.804546) (xy 17.628468 -136.850518) (xy 17.610836 -136.871456)
			(xy 17.610836 -136.87171) (xy 17.610582 -136.87171) (xy 17.605 -136.878798) (xy 17.598763 -136.895715)
			(xy 17.59839 -136.90473) (xy 17.59839 -136.971786) (xy 17.598747 -136.980803) (xy 17.60499 -136.997723)
			(xy 17.610582 -137.004806) (xy 17.610836 -137.00506) (xy 17.628477 -137.025993) (xy 17.658202 -137.071961)
			(xy 17.681047 -137.121707) (xy 17.696543 -137.174209) (xy 17.704372 -137.228388) (xy 17.704372 -137.283129)
			(xy 17.696544 -137.337308) (xy 17.681048 -137.38981) (xy 17.658203 -137.439557) (xy 17.628479 -137.485525)
			(xy 17.610836 -137.506456) (xy 17.610836 -137.50671) (xy 17.610582 -137.50671) (xy 17.605 -137.513798)
			(xy 17.598763 -137.530715) (xy 17.59839 -137.53973) (xy 17.59839 -137.606786) (xy 17.598747 -137.615803)
			(xy 17.60499 -137.632723) (xy 17.610582 -137.639806) (xy 17.610836 -137.64006) (xy 17.628477 -137.660993)
			(xy 17.658202 -137.706961) (xy 17.681047 -137.756707) (xy 17.696543 -137.809209) (xy 17.704372 -137.863388)
			(xy 17.704372 -137.918129) (xy 17.696544 -137.972308) (xy 17.681048 -138.02481) (xy 17.658203 -138.074557)
			(xy 17.628479 -138.120525) (xy 17.610836 -138.141456) (xy 17.610836 -138.14171) (xy 17.610582 -138.14171)
			(xy 17.605 -138.148798) (xy 17.598763 -138.165715) (xy 17.59839 -138.17473) (xy 17.59839 -138.241786)
			(xy 17.598747 -138.250803) (xy 17.60499 -138.267723) (xy 17.610582 -138.274806) (xy 17.610836 -138.27506)
			(xy 17.628477 -138.295991) (xy 17.658201 -138.341958) (xy 17.68104 -138.391705) (xy 17.696525 -138.444209)
			(xy 17.704336 -138.498388) (xy 17.704816 -138.525758) (xy 17.704272 -138.554549) (xy 17.695585 -138.611471)
			(xy 17.678446 -138.666443) (xy 17.653246 -138.718218) (xy 17.620554 -138.765619) (xy 17.581113 -138.807573)
			(xy 17.558766 -138.825732) (xy 17.550086 -138.833257) (xy 17.540021 -138.853883) (xy 17.539462 -138.865356)
			(xy 17.538954 -138.956796) (xy 17.549114 -138.977878) (xy 17.558258 -138.98499) (xy 17.570196 -138.99515)
			(xy 17.570704 -138.995658) (xy 17.577562 -139.0015) (xy 17.59458 -139.00785) (xy 17.67078 -139.00785)
			(xy 17.679799 -139.007495) (xy 17.696723 -139.001258) (xy 17.7038 -138.995658) (xy 17.704054 -138.995404)
			(xy 17.724987 -138.977763) (xy 17.770955 -138.948039) (xy 17.820701 -138.925193) (xy 17.873203 -138.909697)
			(xy 17.927381 -138.901868) (xy 17.982123 -138.901868) (xy 18.036301 -138.909697) (xy 18.088803 -138.925193)
			(xy 18.138549 -138.948039) (xy 18.184517 -138.977763) (xy 18.20545 -138.995404) (xy 18.205704 -138.995404)
			(xy 18.205704 -138.995658) (xy 18.212789 -139.001246) (xy 18.229707 -139.007492) (xy 18.238724 -139.00785)
			(xy 18.30578 -139.00785) (xy 18.314799 -139.007495) (xy 18.331723 -139.001258) (xy 18.3388 -138.995658)
			(xy 18.339054 -138.995404) (xy 18.359987 -138.977763) (xy 18.405955 -138.948039) (xy 18.455701 -138.925193)
			(xy 18.508203 -138.909697) (xy 18.562381 -138.901868) (xy 18.617123 -138.901868) (xy 18.671301 -138.909697)
			(xy 18.723803 -138.925193) (xy 18.773549 -138.948039) (xy 18.819517 -138.977763) (xy 18.84045 -138.995404)
			(xy 18.840704 -138.995404) (xy 18.840704 -138.995658) (xy 18.847789 -139.001246) (xy 18.864707 -139.007492)
			(xy 18.873724 -139.00785) (xy 18.94078 -139.00785) (xy 18.949799 -139.007495) (xy 18.966723 -139.001258)
			(xy 18.9738 -138.995658) (xy 18.974054 -138.995404) (xy 18.994488 -138.978199) (xy 19.039267 -138.949073)
			(xy 19.087668 -138.926474) (xy 19.138748 -138.910842) (xy 19.165062 -138.90625) (xy 19.165316 -138.90625)
			(xy 19.174143 -138.904448) (xy 19.189817 -138.895589) (xy 19.20147 -138.881864) (xy 19.207671 -138.864961)
			(xy 19.207988 -138.855958) (xy 19.207988 -132.367274) (xy 19.207389 -132.355495) (xy 19.196882 -132.334413)
			(xy 19.178053 -132.320259) (xy 19.166586 -132.31749) (xy 19.139311 -132.311861) (xy 19.086648 -132.293752)
			(xy 19.037176 -132.268181) (xy 18.991945 -132.235693) (xy 18.951915 -132.196977) (xy 18.917936 -132.152855)
			(xy 18.890729 -132.104264) (xy 18.870872 -132.052235) (xy 18.858787 -131.997872) (xy 18.85473 -131.94233)
			(xy 18.858787 -131.886789) (xy 18.870872 -131.832426) (xy 18.890729 -131.780397) (xy 18.917935 -131.731805)
			(xy 18.951914 -131.687683) (xy 18.991944 -131.648967) (xy 19.037176 -131.616479) (xy 19.086648 -131.590909)
			(xy 19.139311 -131.572799) (xy 19.166586 -131.567174) (xy 19.178028 -131.564381) (xy 19.196788 -131.550185)
			(xy 19.207324 -131.529149) (xy 19.207988 -131.51739) (xy 19.207988 -130.714496) (xy 19.208566 -130.665563)
			(xy 19.21816 -130.568168) (xy 19.237265 -130.472185) (xy 19.250914 -130.42519) (xy 25.168098 -110.920022)
			(xy 25.175297 -110.89663) (xy 25.191686 -110.850508) (xy 25.200864 -110.82782) (xy 27.267662 -105.838244)
			(xy 27.286966 -105.793246) (xy 27.333186 -105.706921) (xy 27.387648 -105.625544) (xy 27.449827 -105.5499)
			(xy 27.48407 -105.514902) (xy 27.970734 -105.027984) (xy 27.973782 -105.022904) (xy 27.994651 -104.98921)
			(xy 28.041011 -104.924917) (xy 28.092364 -104.864539) (xy 28.120086 -104.836214) (xy 33.052512 -99.903788)
			(xy 33.091722 -99.865755) (xy 33.17714 -99.797658) (xy 33.222946 -99.767898) (xy 33.223454 -99.76739)
			(xy 33.22828 -99.764596) (xy 33.228788 -99.764088) (xy 33.230312 -99.763326) (xy 33.266888 -99.741482)
			(xy 33.267142 -99.741482) (xy 33.278318 -99.735386) (xy 33.281366 -99.733862) (xy 33.282128 -99.733608)
			(xy 33.304183 -99.721881) (xy 33.349289 -99.700405) (xy 33.372298 -99.690682) (xy 35.774884 -98.695764)
			(xy 35.811433 -98.681061) (xy 35.886405 -98.656836) (xy 35.963066 -98.638655) (xy 36.040931 -98.626634)
			(xy 36.080192 -98.623374) (xy 36.085272 -98.622612) (xy 36.127545 -98.615734) (xy 36.21288 -98.60836)
			(xy 36.255706 -98.60788) (xy 37.04336 -98.60788) (xy 37.053086 -98.607405) (xy 37.07112 -98.600107)
			(xy 37.078412 -98.593656) (xy 37.109281 -98.564739) (xy 37.175132 -98.511645) (xy 37.245242 -98.464317)
			(xy 37.319108 -98.423094) (xy 37.396198 -98.388274) (xy 37.47596 -98.360105) (xy 37.55782 -98.33879)
			(xy 37.641191 -98.324482) (xy 37.725473 -98.317283) (xy 37.767768 -98.316796) (xy 37.814432 -98.317347)
			(xy 37.907352 -98.326082) (xy 37.999049 -98.34346) (xy 38.088721 -98.36933) (xy 38.175584 -98.403464)
			(xy 38.258878 -98.445564) (xy 38.337874 -98.495261) (xy 38.411882 -98.552122) (xy 38.480254 -98.615649)
			(xy 38.542391 -98.685285) (xy 38.597751 -98.760423) (xy 38.622224 -98.800158) (xy 38.624822 -98.804134)
			(xy 38.631218 -98.811156) (xy 38.634924 -98.814128) (xy 38.657589 -98.832313) (xy 38.697666 -98.874386)
			(xy 38.730897 -98.922051) (xy 38.756512 -98.974207) (xy 38.773918 -99.029644) (xy 38.782713 -99.087081)
			(xy 38.78326 -99.116134) (xy 38.78326 -99.116896) (xy 38.782756 -99.146261) (xy 38.773818 -99.204305)
			(xy 38.76548 -99.232466) (xy 38.764127 -99.236972) (xy 38.762969 -99.246309) (xy 38.763194 -99.251008)
			(xy 38.764079 -99.266804) (xy 38.764968 -99.298433) (xy 38.764972 -99.314254) (xy 38.764539 -99.356622)
			(xy 38.757356 -99.441052) (xy 38.743029 -99.524568) (xy 38.721661 -99.606565) (xy 38.693407 -99.686452)
			(xy 38.676326 -99.725226) (xy 38.672348 -99.735268) (xy 38.67233 -99.756849) (xy 38.676326 -99.766882)
			(xy 38.693371 -99.805671) (xy 38.72161 -99.885559) (xy 38.742976 -99.967553) (xy 38.757316 -100.051063)
			(xy 38.764527 -100.135488) (xy 38.764972 -100.177854) (xy 38.764966 -100.193675) (xy 38.764078 -100.225304)
			(xy 38.763194 -100.2411) (xy 38.762432 -100.251006) (xy 38.762686 -100.252022) (xy 38.764972 -100.258626)
			(xy 38.772846 -100.282756) (xy 38.773862 -100.288598) (xy 38.774116 -100.289868) (xy 38.777418 -100.30841)
			(xy 38.78072 -100.330508) (xy 38.78199 -100.342954) (xy 38.783514 -100.375466) (xy 38.782966 -100.404535)
			(xy 38.774151 -100.462001) (xy 38.756735 -100.517469) (xy 38.731119 -100.56966) (xy 38.697895 -100.61737)
			(xy 38.657828 -100.659497) (xy 38.635178 -100.677726) (xy 38.631434 -100.680656) (xy 38.625041 -100.687691)
			(xy 38.622478 -100.691696) (xy 38.597965 -100.731426) (xy 38.542604 -100.806602) (xy 38.48046 -100.876276)
			(xy 38.412076 -100.939837) (xy 38.338052 -100.996729) (xy 38.259036 -101.046455) (xy 38.175718 -101.088579)
			(xy 38.088828 -101.122733) (xy 37.999127 -101.148617) (xy 37.9074 -101.166006) (xy 37.814448 -101.174746)
			(xy 37.767768 -101.175312) (xy 37.725458 -101.174863) (xy 37.641142 -101.16769) (xy 37.557737 -101.153398)
			(xy 37.475844 -101.132091) (xy 37.39605 -101.103921) (xy 37.31893 -101.069091) (xy 37.245039 -101.027852)
			(xy 37.174908 -100.9805) (xy 37.109041 -100.927376) (xy 37.078158 -100.898452) (xy 37.070792 -100.89134)
			(xy 37.053012 -100.884228) (xy 36.781486 -100.884228) (xy 36.774882 -100.89134) (xy 36.77285 -100.89388)
			(xy 36.767008 -100.900738) (xy 36.760912 -100.909374) (xy 36.752022 -100.927154) (xy 36.750498 -100.9396)
			(xy 36.750244 -100.941632) (xy 36.747704 -100.970588) (xy 36.747704 -100.97135) (xy 36.74745 -100.974398)
			(xy 36.746942 -100.978462) (xy 36.745418 -100.988876) (xy 36.74491 -100.99167) (xy 36.744656 -100.992686)
			(xy 36.74364 -100.997766) (xy 36.742878 -101.00056) (xy 36.737544 -101.022658) (xy 36.736782 -101.026214)
			(xy 36.735766 -101.029262) (xy 36.732718 -101.038914) (xy 36.731449 -101.043435) (xy 36.730422 -101.052768)
			(xy 36.730686 -101.057456) (xy 36.731572 -101.073252) (xy 36.732462 -101.104881) (xy 36.732464 -101.120702)
			(xy 36.732029 -101.163069) (xy 36.724842 -101.247499) (xy 36.710511 -101.331013) (xy 36.689139 -101.413008)
			(xy 36.660882 -101.492893) (xy 36.643818 -101.531674) (xy 36.639851 -101.541716) (xy 36.639851 -101.563288)
			(xy 36.643818 -101.57333) (xy 36.660861 -101.612119) (xy 36.689096 -101.692008) (xy 36.710459 -101.774002)
			(xy 36.724795 -101.857512) (xy 36.732002 -101.941936) (xy 36.732464 -101.984302) (xy 36.730686 -102.046786)
			(xy 36.730489 -102.051548) (xy 36.731632 -102.061009) (xy 36.732972 -102.065582) (xy 36.736274 -102.076504)
			(xy 36.740987 -102.093606) (xy 36.747603 -102.12846) (xy 36.749482 -102.1461) (xy 36.749482 -102.146354)
			(xy 36.750244 -102.153466) (xy 36.763198 -102.186486) (xy 36.766355 -102.192778) (xy 36.77551 -102.203466)
			(xy 36.781232 -102.207568) (xy 37.043106 -102.207568) (xy 37.0528 -102.207128) (xy 37.070803 -102.199931)
			(xy 37.078158 -102.193598) (xy 37.109015 -102.164694) (xy 37.174842 -102.111625) (xy 37.244927 -102.064323)
			(xy 37.318766 -102.023125) (xy 37.39583 -101.98833) (xy 37.475563 -101.960186) (xy 37.557393 -101.938896)
			(xy 37.640733 -101.924614) (xy 37.724983 -101.91744) (xy 37.76726 -101.916992) (xy 37.767768 -101.916992)
			(xy 37.814466 -101.91754) (xy 37.907454 -101.926278) (xy 37.999216 -101.943672) (xy 38.088951 -101.96957)
			(xy 38.175871 -102.003743) (xy 38.259216 -102.045894) (xy 38.338255 -102.095652) (xy 38.412295 -102.152582)
			(xy 38.480688 -102.216184) (xy 38.542835 -102.285903) (xy 38.598192 -102.361127) (xy 38.622732 -102.400862)
			(xy 38.625253 -102.404839) (xy 38.631521 -102.411865) (xy 38.635178 -102.414832) (xy 38.657615 -102.432847)
			(xy 38.697328 -102.474483) (xy 38.730341 -102.521609) (xy 38.755904 -102.573157) (xy 38.773439 -102.627959)
			(xy 38.782549 -102.684772) (xy 38.78326 -102.713536) (xy 38.78326 -102.717092) (xy 38.782631 -102.748137)
			(xy 38.772552 -102.809404) (xy 38.763194 -102.839012) (xy 38.762432 -102.841298) (xy 38.763651 -102.859498)
			(xy 38.764922 -102.895956) (xy 38.764972 -102.914196) (xy 38.764537 -102.956563) (xy 38.75735 -103.040993)
			(xy 38.74302 -103.124507) (xy 38.721649 -103.206503) (xy 38.693393 -103.286388) (xy 38.676326 -103.325168)
			(xy 38.672357 -103.33521) (xy 38.672355 -103.356783) (xy 38.676326 -103.366824) (xy 38.693369 -103.405613)
			(xy 38.721605 -103.485502) (xy 38.742968 -103.567496) (xy 38.757304 -103.651006) (xy 38.764512 -103.73543)
			(xy 38.764972 -103.777796) (xy 38.764927 -103.7961) (xy 38.763658 -103.832685) (xy 38.762432 -103.850948)
			(xy 38.76294 -103.852218) (xy 38.763194 -103.852726) (xy 38.765226 -103.859076) (xy 38.765226 -103.85933)
			(xy 38.766242 -103.862886) (xy 38.76802 -103.86822) (xy 38.76802 -103.868728) (xy 38.770052 -103.875586)
			(xy 38.77183 -103.882444) (xy 38.774878 -103.894382) (xy 38.78072 -103.930704) (xy 38.78199 -103.942896)
			(xy 38.783514 -103.975408) (xy 38.78297 -104.004479) (xy 38.774163 -104.06195) (xy 38.756753 -104.117424)
			(xy 38.731142 -104.169622) (xy 38.697921 -104.217338) (xy 38.657856 -104.259472) (xy 38.635178 -104.277668)
			(xy 38.631436 -104.2806) (xy 38.625048 -104.287639) (xy 38.622478 -104.291638) (xy 38.597954 -104.331354)
			(xy 38.542575 -104.4065) (xy 38.480418 -104.476145) (xy 38.412026 -104.539678) (xy 38.337999 -104.596545)
			(xy 38.258983 -104.646247) (xy 38.17567 -104.688351) (xy 38.088787 -104.722488) (xy 37.999096 -104.748359)
			(xy 37.90738 -104.765739) (xy 37.814442 -104.774475) (xy 37.767768 -104.775) (xy 37.767514 -104.775)
			(xy 37.723568 -104.774525) (xy 37.636018 -104.766797) (xy 37.549487 -104.75139) (xy 37.46465 -104.728424)
			(xy 37.382163 -104.698079) (xy 37.302669 -104.660589) (xy 37.226784 -104.616245) (xy 37.155099 -104.565392)
			(xy 37.121338 -104.537256) (xy 37.114107 -104.53158) (xy 37.096831 -104.525338) (xy 37.078464 -104.525613)
			(xy 37.069776 -104.52862) (xy 37.025945 -104.545402) (xy 36.935817 -104.571616) (xy 36.843625 -104.589246)
			(xy 36.750185 -104.598136) (xy 36.703254 -104.598724) (xy 36.220654 -104.598724) (xy 36.21532 -104.59847)
			(xy 36.209732 -104.59847) (xy 36.206136 -104.598991) (xy 36.199127 -104.600909) (xy 36.195762 -104.60228)
			(xy 36.191255 -104.604288) (xy 36.183062 -104.609782) (xy 36.179506 -104.613202) (xy 36.137088 -104.656382)
			(xy 36.130267 -104.663993) (xy 36.122789 -104.682994) (xy 36.12261 -104.693212) (xy 36.122864 -104.720898)
			(xy 36.122429 -104.763265) (xy 36.115242 -104.847695) (xy 36.100911 -104.931209) (xy 36.079541 -105.013205)
			(xy 36.051284 -105.093089) (xy 36.034218 -105.13187) (xy 36.03025 -105.141912) (xy 36.030249 -105.163485)
			(xy 36.034218 -105.173526) (xy 36.051261 -105.212315) (xy 36.079497 -105.292204) (xy 36.10086 -105.374198)
			(xy 36.115196 -105.457708) (xy 36.122403 -105.542132) (xy 36.122864 -105.584498) (xy 36.122857 -105.600319)
			(xy 36.121968 -105.631948) (xy 36.121086 -105.647744) (xy 36.120324 -105.657142) (xy 36.122102 -105.662476)
			(xy 36.122356 -105.663492) (xy 36.126928 -105.678224) (xy 36.127436 -105.680002) (xy 36.127436 -105.68051)
			(xy 36.12896 -105.68686) (xy 36.131974 -105.698722) (xy 36.136677 -105.722743) (xy 36.138358 -105.734866)
			(xy 36.138358 -105.735374) (xy 36.139628 -105.747058) (xy 36.14039 -105.75544) (xy 36.151058 -105.779062)
			(xy 36.151058 -105.779316) (xy 36.154614 -105.786936) (xy 36.163504 -105.796842) (xy 36.164774 -105.798112)
			(xy 36.167568 -105.801668) (xy 36.17341 -105.807764) (xy 37.04336 -105.807764) (xy 37.053085 -105.807289)
			(xy 37.071118 -105.799988) (xy 37.078412 -105.79354) (xy 37.109279 -105.764621) (xy 37.175129 -105.711523)
			(xy 37.245238 -105.664191) (xy 37.319103 -105.622965) (xy 37.396194 -105.588141) (xy 37.475956 -105.559969)
			(xy 37.557817 -105.538652) (xy 37.641189 -105.524343) (xy 37.725473 -105.517144) (xy 37.767768 -105.51668)
			(xy 37.814432 -105.517231) (xy 37.90735 -105.525967) (xy 37.999045 -105.543346) (xy 38.088716 -105.569217)
			(xy 38.175576 -105.603352) (xy 38.258868 -105.645454) (xy 38.337861 -105.695155) (xy 38.411865 -105.752018)
			(xy 38.480233 -105.815547) (xy 38.542365 -105.885187) (xy 38.597719 -105.960326) (xy 38.622224 -106.000042)
			(xy 38.624821 -106.004019) (xy 38.631215 -106.011043) (xy 38.634924 -106.014012) (xy 38.657589 -106.032197)
			(xy 38.697669 -106.074269) (xy 38.730902 -106.121934) (xy 38.756519 -106.174089) (xy 38.773928 -106.229527)
			(xy 38.782725 -106.286964) (xy 38.78326 -106.316018) (xy 38.78326 -106.31678) (xy 38.782757 -106.346145)
			(xy 38.773821 -106.40419) (xy 38.76548 -106.43235) (xy 38.764135 -106.436857) (xy 38.762993 -106.446192)
			(xy 38.763194 -106.450892) (xy 38.764079 -106.466688) (xy 38.764969 -106.498317) (xy 38.764972 -106.514138)
			(xy 38.764535 -106.556505) (xy 38.757345 -106.640934) (xy 38.743012 -106.724447) (xy 38.721638 -106.806441)
			(xy 38.693379 -106.886324) (xy 38.676326 -106.92511) (xy 38.672366 -106.935151) (xy 38.672381 -106.956717)
			(xy 38.676326 -106.966766) (xy 38.693368 -107.005555) (xy 38.7216 -107.085444) (xy 38.742959 -107.167439)
			(xy 38.757292 -107.250949) (xy 38.764496 -107.335373) (xy 38.764972 -107.377738) (xy 38.764966 -107.393559)
			(xy 38.764079 -107.425188) (xy 38.763194 -107.440984) (xy 38.762432 -107.45089) (xy 38.762686 -107.451906)
			(xy 38.764972 -107.45851) (xy 38.772846 -107.48264) (xy 38.773862 -107.488482) (xy 38.774116 -107.489752)
			(xy 38.777418 -107.508294) (xy 38.78072 -107.530392) (xy 38.78199 -107.542838) (xy 38.783514 -107.57535)
			(xy 38.782967 -107.60442) (xy 38.774155 -107.661887) (xy 38.75674 -107.717357) (xy 38.731126 -107.76955)
			(xy 38.697902 -107.817261) (xy 38.657836 -107.85939) (xy 38.635178 -107.87761) (xy 38.631433 -107.88054)
			(xy 38.625038 -107.887574) (xy 38.622478 -107.89158) (xy 38.597965 -107.931311) (xy 38.542605 -108.006488)
			(xy 38.480461 -108.076162) (xy 38.412078 -108.139724) (xy 38.338054 -108.196618) (xy 38.259038 -108.246345)
			(xy 38.17572 -108.28847) (xy 38.08883 -108.322624) (xy 37.999128 -108.348509) (xy 37.9074 -108.365897)
			(xy 37.814449 -108.374638) (xy 37.767768 -108.375196) (xy 37.723944 -108.374695) (xy 37.636638 -108.366951)
			(xy 37.550347 -108.35158) (xy 37.465738 -108.328699) (xy 37.383462 -108.298484) (xy 37.304153 -108.261169)
			(xy 37.228423 -108.217041) (xy 37.156855 -108.166441) (xy 37.123116 -108.138468) (xy 37.119052 -108.137198)
			(xy 37.110924 -108.137198) (xy 37.106577 -108.137306) (xy 37.098019 -108.138837) (xy 37.093906 -108.140246)
			(xy 37.053632 -108.154223) (xy 36.971206 -108.176008) (xy 36.887211 -108.19062) (xy 36.80227 -108.19795)
			(xy 36.759642 -108.198412) (xy 36.199572 -108.198412) (xy 36.195689 -108.200226) (xy 36.188537 -108.204947)
			(xy 36.185348 -108.20781) (xy 36.15055 -108.240322) (xy 36.127182 -108.262166) (xy 36.121848 -108.269024)
			(xy 36.12261 -108.290106) (xy 36.122864 -108.320586) (xy 36.122864 -108.321094) (xy 36.122468 -108.363856)
			(xy 36.115252 -108.449075) (xy 36.100753 -108.53336) (xy 36.090352 -108.57484) (xy 36.089082 -108.580682)
			(xy 36.088504 -108.584288) (xy 36.086465 -108.591299) (xy 36.085018 -108.594652) (xy 36.084002 -108.596938)
			(xy 36.073694 -108.631408) (xy 36.048778 -108.698911) (xy 36.034218 -108.731812) (xy 36.030259 -108.741853)
			(xy 36.030274 -108.763419) (xy 36.034218 -108.773468) (xy 36.05126 -108.812257) (xy 36.079492 -108.892146)
			(xy 36.100851 -108.974141) (xy 36.115184 -109.057651) (xy 36.122388 -109.142075) (xy 36.122864 -109.18444)
			(xy 36.121086 -109.247178) (xy 36.120914 -109.251876) (xy 36.12206 -109.261206) (xy 36.123372 -109.26572)
			(xy 36.129468 -109.287056) (xy 36.133104 -109.30178) (xy 36.138315 -109.331661) (xy 36.139882 -109.346746)
			(xy 36.139882 -109.347) (xy 36.140644 -109.353858) (xy 36.147248 -109.371384) (xy 36.147756 -109.372654)
			(xy 36.15309 -109.385354) (xy 36.159694 -109.39272) (xy 36.169092 -109.403388) (xy 36.169854 -109.40415)
			(xy 36.17087 -109.405166) (xy 36.173664 -109.40796) (xy 37.04336 -109.40796) (xy 37.053085 -109.407485)
			(xy 37.071118 -109.400184) (xy 37.078412 -109.393736) (xy 37.10928 -109.364817) (xy 37.175129 -109.311719)
			(xy 37.245239 -109.264387) (xy 37.319104 -109.223161) (xy 37.396194 -109.188338) (xy 37.475956 -109.160166)
			(xy 37.557817 -109.138849) (xy 37.641189 -109.12454) (xy 37.725473 -109.117341) (xy 37.767768 -109.116876)
			(xy 37.814432 -109.117427) (xy 37.90735 -109.126163) (xy 37.999045 -109.143542) (xy 38.088716 -109.169412)
			(xy 38.175577 -109.203548) (xy 38.258868 -109.24565) (xy 38.337862 -109.29535) (xy 38.411866 -109.352214)
			(xy 38.480234 -109.415743) (xy 38.542367 -109.485382) (xy 38.597721 -109.560521) (xy 38.622224 -109.600238)
			(xy 38.624821 -109.604215) (xy 38.631215 -109.61124) (xy 38.634924 -109.614208) (xy 38.65759 -109.632392)
			(xy 38.697669 -109.674465) (xy 38.730903 -109.72213) (xy 38.756521 -109.774285) (xy 38.77393 -109.829723)
			(xy 38.782728 -109.88716) (xy 38.78326 -109.916214) (xy 38.78326 -109.916976) (xy 38.782757 -109.946341)
			(xy 38.773822 -110.004386) (xy 38.76548 -110.032546) (xy 38.764134 -110.037053) (xy 38.762991 -110.046388)
			(xy 38.763194 -110.051088) (xy 38.764079 -110.066884) (xy 38.764969 -110.098513) (xy 38.764972 -110.114334)
			(xy 38.764536 -110.156701) (xy 38.757346 -110.24113) (xy 38.743012 -110.324643) (xy 38.721639 -110.406637)
			(xy 38.69338 -110.48652) (xy 38.676326 -110.525306) (xy 38.672365 -110.535347) (xy 38.672378 -110.556914)
			(xy 38.676326 -110.566962) (xy 38.693368 -110.605751) (xy 38.7216 -110.68564) (xy 38.74296 -110.767635)
			(xy 38.757294 -110.851145) (xy 38.764497 -110.935569) (xy 38.764972 -110.977934) (xy 38.764966 -110.993755)
			(xy 38.764079 -111.025384) (xy 38.763194 -111.04118) (xy 38.762432 -111.051086) (xy 38.762686 -111.052102)
			(xy 38.764972 -111.058706) (xy 38.772846 -111.082836) (xy 38.773862 -111.088678) (xy 38.774116 -111.089948)
			(xy 38.777418 -111.10849) (xy 38.78072 -111.130588) (xy 38.78199 -111.143034) (xy 38.783514 -111.175546)
			(xy 38.782968 -111.204616) (xy 38.774155 -111.262084) (xy 38.756741 -111.317554) (xy 38.731127 -111.369747)
			(xy 38.697904 -111.417459) (xy 38.657838 -111.459588) (xy 38.635178 -111.477806) (xy 38.631433 -111.480735)
			(xy 38.625037 -111.487769) (xy 38.622478 -111.491776) (xy 38.597965 -111.531507) (xy 38.542605 -111.606684)
			(xy 38.480461 -111.676359) (xy 38.412078 -111.739921) (xy 38.338055 -111.796815) (xy 38.259038 -111.846542)
			(xy 38.17572 -111.888667) (xy 38.08883 -111.922822) (xy 37.999128 -111.948707) (xy 37.9074 -111.966095)
			(xy 37.814449 -111.974836) (xy 37.767768 -111.975392) (xy 37.725553 -111.974938) (xy 37.641427 -111.967779)
			(xy 37.558208 -111.953532) (xy 37.476492 -111.932298) (xy 37.396864 -111.90423) (xy 37.319895 -111.86953)
			(xy 37.246135 -111.828445) (xy 37.176114 -111.78127) (xy 37.142928 -111.755174) (xy 37.136097 -111.750099)
			(xy 37.12007 -111.744406) (xy 37.103063 -111.744316) (xy 37.094922 -111.746792) (xy 37.056558 -111.759238)
			(xy 36.978262 -111.778633) (xy 36.898657 -111.791644) (xy 36.818261 -111.798189) (xy 36.77793 -111.798608)
			(xy 36.29279 -111.798608) (xy 36.264788 -111.798401) (xy 36.208875 -111.795223) (xy 36.18103 -111.792258)
			(xy 36.13658 -111.787178) (xy 36.134548 -111.79556) (xy 36.13404 -111.797846) (xy 36.13404 -111.798354)
			(xy 36.13277 -111.802926) (xy 36.128198 -111.821976) (xy 36.127182 -111.826294) (xy 36.126166 -111.829342)
			(xy 36.123118 -111.838994) (xy 36.121847 -111.843515) (xy 36.120816 -111.852848) (xy 36.121086 -111.857536)
			(xy 36.121971 -111.873332) (xy 36.122858 -111.904961) (xy 36.122864 -111.920782) (xy 36.12243 -111.96315)
			(xy 36.115244 -112.047579) (xy 36.100915 -112.131094) (xy 36.079545 -112.21309) (xy 36.051289 -112.292976)
			(xy 36.034218 -112.331754) (xy 36.030246 -112.341796) (xy 36.030239 -112.363372) (xy 36.034218 -112.37341)
			(xy 36.051262 -112.412199) (xy 36.079499 -112.492087) (xy 36.100863 -112.574082) (xy 36.115201 -112.657592)
			(xy 36.122409 -112.742016) (xy 36.122864 -112.784382) (xy 36.122858 -112.800203) (xy 36.121968 -112.831832)
			(xy 36.121086 -112.847628) (xy 36.120324 -112.857534) (xy 36.120578 -112.85855) (xy 36.122864 -112.865154)
			(xy 36.130738 -112.889284) (xy 36.131754 -112.895126) (xy 36.132008 -112.896396) (xy 36.13531 -112.914938)
			(xy 36.138612 -112.937036) (xy 36.139882 -112.949482) (xy 36.141406 -112.981994) (xy 36.140856 -113.011062)
			(xy 36.132037 -113.068526) (xy 36.114618 -113.123991) (xy 36.089 -113.176178) (xy 36.055773 -113.223884)
			(xy 36.015705 -113.266007) (xy 35.99307 -113.284254) (xy 35.989328 -113.287186) (xy 35.982939 -113.294224)
			(xy 35.98037 -113.298224) (xy 35.955859 -113.337956) (xy 35.9005 -113.413137) (xy 35.838358 -113.482814)
			(xy 35.769976 -113.546379) (xy 35.695952 -113.603276) (xy 35.616936 -113.653005) (xy 35.533617 -113.695132)
			(xy 35.446726 -113.729287) (xy 35.357024 -113.755173) (xy 35.265294 -113.772562) (xy 35.172341 -113.781303)
			(xy 35.12566 -113.78184) (xy 35.087296 -113.781438) (xy 35.010801 -113.775461) (xy 34.934991 -113.763625)
			(xy 34.897568 -113.75517) (xy 34.888741 -113.753452) (xy 34.870899 -113.755615) (xy 34.854897 -113.763795)
			(xy 34.842696 -113.776991) (xy 34.838894 -113.785142) (xy 34.657538 -114.223546) (xy 34.640262 -114.264044)
			(xy 34.599557 -114.342125) (xy 34.552123 -114.416309) (xy 34.498329 -114.48602) (xy 34.468816 -114.518694)
			(xy 34.463014 -114.525572) (xy 34.45624 -114.54223) (xy 34.455608 -114.551206) (xy 34.453319 -114.595014)
			(xy 34.442012 -114.682013) (xy 34.423114 -114.767684) (xy 34.396772 -114.851366) (xy 34.380424 -114.892074)
			(xy 34.19094 -115.350036) (xy 34.173664 -115.390535) (xy 34.13296 -115.468615) (xy 34.085526 -115.542801)
			(xy 34.031733 -115.612512) (xy 34.002218 -115.645184) (xy 33.996415 -115.652062) (xy 33.989637 -115.66872)
			(xy 33.98901 -115.677696) (xy 33.986721 -115.721504) (xy 33.975415 -115.808503) (xy 33.956518 -115.894175)
			(xy 33.930177 -115.977857) (xy 33.913826 -116.018564) (xy 33.724342 -116.476526) (xy 33.708953 -116.512594)
			(xy 36.543996 -116.512594) (xy 36.544506 -116.485345) (xy 36.552275 -116.431403) (xy 36.567639 -116.379116)
			(xy 36.590286 -116.329546) (xy 36.619756 -116.283703) (xy 36.655447 -116.242518) (xy 36.696635 -116.206831)
			(xy 36.742482 -116.177367) (xy 36.792054 -116.154725) (xy 36.818062 -116.14658) (xy 36.825761 -116.143936)
			(xy 36.839099 -116.134617) (xy 36.844224 -116.128292) (xy 36.872418 -116.091208) (xy 36.872164 -116.080032)
			(xy 36.872164 -114.098578) (xy 36.872604 -114.072489) (xy 36.880777 -114.020954) (xy 36.896919 -113.971334)
			(xy 36.920631 -113.924854) (xy 36.951327 -113.88266) (xy 36.969446 -113.863882) (xy 38.936422 -111.896906)
			(xy 38.943255 -111.889501) (xy 38.950978 -111.870905) (xy 38.951408 -111.860838) (xy 38.951408 -97.998788)
			(xy 38.951013 -97.988715) (xy 38.943274 -97.970116) (xy 38.936422 -97.96272) (xy 38.156642 -97.18294)
			(xy 38.14973 -97.176593) (xy 38.132598 -97.16897) (xy 38.113872 -97.167993) (xy 38.104826 -97.170494)
			(xy 38.005258 -97.203006) (xy 37.986716 -97.22485) (xy 37.98443 -97.239074) (xy 37.979769 -97.265702)
			(xy 37.96401 -97.31741) (xy 37.941108 -97.366374) (xy 37.911522 -97.411615) (xy 37.875845 -97.452225)
			(xy 37.834792 -97.487391) (xy 37.789185 -97.516408) (xy 37.739937 -97.538696) (xy 37.688036 -97.553806)
			(xy 37.634522 -97.561438) (xy 37.607494 -97.561908) (xy 37.580243 -97.561428) (xy 37.526295 -97.55367)
			(xy 37.474 -97.538315) (xy 37.424423 -97.515673) (xy 37.378572 -97.486206) (xy 37.337382 -97.450514)
			(xy 37.301691 -97.409323) (xy 37.272224 -97.363472) (xy 37.249583 -97.313895) (xy 37.234228 -97.261599)
			(xy 37.226472 -97.207651) (xy 37.225986 -97.1804) (xy 37.226402 -97.15337) (xy 37.234046 -97.099853)
			(xy 37.249167 -97.047951) (xy 37.271462 -96.998702) (xy 37.300485 -96.953093) (xy 37.335655 -96.912038)
			(xy 37.376267 -96.876357) (xy 37.421509 -96.846765) (xy 37.470475 -96.823855) (xy 37.522184 -96.808085)
			(xy 37.54882 -96.803464) (xy 37.563044 -96.801178) (xy 37.584888 -96.782636) (xy 37.6174 -96.683068)
			(xy 37.619912 -96.674021) (xy 37.61896 -96.655288) (xy 37.61131 -96.638162) (xy 37.604954 -96.631252)
			(xy 37.514784 -96.541082) (xy 37.510389 -96.536968) (xy 37.500126 -96.530682) (xy 37.494464 -96.528636)
			(xy 37.493956 -96.528636) (xy 37.468414 -96.520181) (xy 37.41981 -96.497112) (xy 37.374928 -96.467444)
			(xy 37.33466 -96.431764) (xy 37.299804 -96.390781) (xy 37.271051 -96.345308) (xy 37.248973 -96.296245)
			(xy 37.234005 -96.244568) (xy 37.226447 -96.191301) (xy 37.225986 -96.1644) (xy 37.226478 -96.137149)
			(xy 37.234234 -96.083202) (xy 37.249589 -96.030908) (xy 37.27223 -95.981331) (xy 37.301695 -95.935481)
			(xy 37.337386 -95.894291) (xy 37.378576 -95.858599) (xy 37.424425 -95.829133) (xy 37.474002 -95.806491)
			(xy 37.526296 -95.791135) (xy 37.580243 -95.783378) (xy 37.607494 -95.782892) (xy 37.634403 -95.783402)
			(xy 37.687685 -95.790978) (xy 37.739374 -95.805965) (xy 37.788445 -95.828067) (xy 37.833922 -95.856844)
			(xy 37.874905 -95.891726) (xy 37.91058 -95.932021) (xy 37.940239 -95.97693) (xy 37.963293 -96.02556)
			(xy 37.97173 -96.051116) (xy 37.97173 -96.05137) (xy 37.973706 -96.057065) (xy 37.980005 -96.067338)
			(xy 37.984176 -96.07169) (xy 38.287452 -96.374966) (xy 94.427038 -96.374966) (xy 94.431109 -96.319344)
			(xy 94.443235 -96.264907) (xy 94.463158 -96.212816) (xy 94.490454 -96.164181) (xy 94.52454 -96.120038)
			(xy 94.564689 -96.081329) (xy 94.610047 -96.048878) (xy 94.659647 -96.023377) (xy 94.712431 -96.00537)
			(xy 94.767274 -95.99524) (xy 94.823008 -95.993203) (xy 94.878445 -95.999303) (xy 94.932402 -96.013409)
			(xy 94.983731 -96.035221) (xy 95.031337 -96.064275) (xy 95.074205 -96.09995) (xy 95.111422 -96.141487)
			(xy 95.142195 -96.188) (xy 95.165867 -96.238497) (xy 95.180866 -96.288352) (xy 95.852232 -96.288352)
			(xy 95.856303 -96.23273) (xy 95.868429 -96.178293) (xy 95.888352 -96.126202) (xy 95.915648 -96.077567)
			(xy 95.949734 -96.033424) (xy 95.989883 -95.994715) (xy 96.035241 -95.962264) (xy 96.084841 -95.936763)
			(xy 96.137625 -95.918756) (xy 96.192468 -95.908626) (xy 96.248202 -95.906589) (xy 96.303639 -95.912689)
			(xy 96.357596 -95.926795) (xy 96.408925 -95.948607) (xy 96.456531 -95.977661) (xy 96.499399 -96.013336)
			(xy 96.536616 -96.054873) (xy 96.567389 -96.101386) (xy 96.591061 -96.151883) (xy 96.607129 -96.20529)
			(xy 96.615249 -96.260466) (xy 96.61548 -96.273112) (xy 97.197924 -96.273112) (xy 97.201995 -96.21749)
			(xy 97.214121 -96.163053) (xy 97.234044 -96.110962) (xy 97.26134 -96.062327) (xy 97.295426 -96.018184)
			(xy 97.335575 -95.979475) (xy 97.380933 -95.947024) (xy 97.430533 -95.921523) (xy 97.483317 -95.903516)
			(xy 97.53816 -95.893386) (xy 97.593894 -95.891349) (xy 97.649331 -95.897449) (xy 97.703288 -95.911555)
			(xy 97.754617 -95.933367) (xy 97.802223 -95.962421) (xy 97.845091 -95.998096) (xy 97.882308 -96.039633)
			(xy 97.913081 -96.086146) (xy 97.936753 -96.136643) (xy 97.952821 -96.19005) (xy 97.960941 -96.245226)
			(xy 97.96145 -96.273112) (xy 97.960941 -96.300998) (xy 97.952821 -96.356174) (xy 97.936753 -96.409581)
			(xy 97.913081 -96.460078) (xy 97.882308 -96.506591) (xy 97.845091 -96.548128) (xy 97.802223 -96.583803)
			(xy 97.754617 -96.612857) (xy 97.703288 -96.634669) (xy 97.649331 -96.648775) (xy 97.593894 -96.654875)
			(xy 97.53816 -96.652838) (xy 97.483317 -96.642708) (xy 97.430533 -96.624701) (xy 97.380933 -96.5992)
			(xy 97.335575 -96.566749) (xy 97.295426 -96.52804) (xy 97.26134 -96.483897) (xy 97.234044 -96.435262)
			(xy 97.214121 -96.383171) (xy 97.201995 -96.328734) (xy 97.197924 -96.273112) (xy 96.61548 -96.273112)
			(xy 96.615758 -96.288352) (xy 96.615249 -96.316238) (xy 96.607129 -96.371414) (xy 96.591061 -96.424821)
			(xy 96.567389 -96.475318) (xy 96.536616 -96.521831) (xy 96.499399 -96.563368) (xy 96.456531 -96.599043)
			(xy 96.408925 -96.628097) (xy 96.357596 -96.649909) (xy 96.303639 -96.664015) (xy 96.248202 -96.670115)
			(xy 96.192468 -96.668078) (xy 96.137625 -96.657948) (xy 96.084841 -96.639941) (xy 96.035241 -96.61444)
			(xy 95.989883 -96.581989) (xy 95.949734 -96.54328) (xy 95.915648 -96.499137) (xy 95.888352 -96.450502)
			(xy 95.868429 -96.398411) (xy 95.856303 -96.343974) (xy 95.852232 -96.288352) (xy 95.180866 -96.288352)
			(xy 95.181935 -96.291904) (xy 95.190055 -96.34708) (xy 95.190564 -96.374966) (xy 95.190055 -96.402852)
			(xy 95.181935 -96.458028) (xy 95.165867 -96.511435) (xy 95.142195 -96.561932) (xy 95.111422 -96.608445)
			(xy 95.074205 -96.649982) (xy 95.031337 -96.685657) (xy 94.983731 -96.714711) (xy 94.932402 -96.736523)
			(xy 94.878445 -96.750629) (xy 94.823008 -96.756729) (xy 94.767274 -96.754692) (xy 94.712431 -96.744562)
			(xy 94.659647 -96.726555) (xy 94.610047 -96.701054) (xy 94.564689 -96.668603) (xy 94.52454 -96.629894)
			(xy 94.490454 -96.585751) (xy 94.463158 -96.537116) (xy 94.443235 -96.485025) (xy 94.431109 -96.430588)
			(xy 94.427038 -96.374966) (xy 38.287452 -96.374966) (xy 39.518082 -97.605596) (xy 39.536193 -97.624378)
			(xy 39.566877 -97.666576) (xy 39.590577 -97.713057) (xy 39.60671 -97.762674) (xy 39.614877 -97.814205)
			(xy 39.615364 -97.840292) (xy 39.615364 -112.019334) (xy 39.61486 -112.045421) (xy 39.606701 -112.096952)
			(xy 39.590574 -112.146571) (xy 39.566877 -112.193052) (xy 39.536194 -112.23525) (xy 39.518082 -112.25403)
			(xy 38.261798 -113.510314) (xy 50.770536 -113.510314) (xy 50.770536 -98.50247) (xy 50.771055 -98.476446)
			(xy 50.779221 -98.425041) (xy 50.795316 -98.375543) (xy 50.818946 -98.329167) (xy 50.84953 -98.287052)
			(xy 50.867564 -98.268282) (xy 51.640486 -97.49536) (xy 51.647334 -97.487966) (xy 51.65505 -97.469362)
			(xy 51.655472 -97.459292) (xy 51.655472 -97.25025) (xy 51.652932 -97.239074) (xy 51.650138 -97.23374)
			(xy 51.64963 -97.232724) (xy 51.635913 -97.205246) (xy 51.616458 -97.147) (xy 51.606579 -97.08639)
			(xy 51.605942 -97.055686) (xy 51.606428 -97.028435) (xy 51.614184 -96.974487) (xy 51.629539 -96.922192)
			(xy 51.652181 -96.872615) (xy 51.681647 -96.826765) (xy 51.717338 -96.785574) (xy 51.758529 -96.749883)
			(xy 51.804379 -96.720417) (xy 51.853956 -96.697775) (xy 51.906251 -96.68242) (xy 51.960199 -96.674664)
			(xy 52.014701 -96.674664) (xy 52.068649 -96.68242) (xy 52.120944 -96.697775) (xy 52.170521 -96.720417)
			(xy 52.216371 -96.749883) (xy 52.257562 -96.785574) (xy 52.293253 -96.826765) (xy 52.322719 -96.872615)
			(xy 52.335683 -96.901) (xy 69.321932 -96.901) (xy 69.326003 -96.845378) (xy 69.338129 -96.790941)
			(xy 69.358052 -96.73885) (xy 69.385348 -96.690215) (xy 69.419434 -96.646072) (xy 69.459583 -96.607363)
			(xy 69.504941 -96.574912) (xy 69.554541 -96.549411) (xy 69.607325 -96.531404) (xy 69.662168 -96.521274)
			(xy 69.717902 -96.519237) (xy 69.773339 -96.525337) (xy 69.827296 -96.539443) (xy 69.878625 -96.561255)
			(xy 69.926231 -96.590309) (xy 69.969099 -96.625984) (xy 70.006316 -96.667521) (xy 70.037089 -96.714034)
			(xy 70.060761 -96.764531) (xy 70.076829 -96.817938) (xy 70.084949 -96.873114) (xy 70.085458 -96.901)
			(xy 70.084949 -96.928886) (xy 70.076829 -96.984062) (xy 70.060761 -97.037469) (xy 70.059604 -97.039938)
			(xy 74.725528 -97.039938) (xy 74.729599 -96.984316) (xy 74.741725 -96.929879) (xy 74.761648 -96.877788)
			(xy 74.788944 -96.829153) (xy 74.82303 -96.78501) (xy 74.863179 -96.746301) (xy 74.908537 -96.71385)
			(xy 74.958137 -96.688349) (xy 75.010921 -96.670342) (xy 75.065764 -96.660212) (xy 75.121498 -96.658175)
			(xy 75.176935 -96.664275) (xy 75.230892 -96.678381) (xy 75.282221 -96.700193) (xy 75.329827 -96.729247)
			(xy 75.372695 -96.764922) (xy 75.409912 -96.806459) (xy 75.440685 -96.852972) (xy 75.464357 -96.903469)
			(xy 75.480425 -96.956876) (xy 75.488545 -97.012052) (xy 75.489054 -97.039938) (xy 75.488545 -97.067824)
			(xy 75.480425 -97.123) (xy 75.464357 -97.176407) (xy 75.440685 -97.226904) (xy 75.409912 -97.273417)
			(xy 75.372695 -97.314954) (xy 75.329827 -97.350629) (xy 75.282221 -97.379683) (xy 75.230892 -97.401495)
			(xy 75.176935 -97.415601) (xy 75.121498 -97.421701) (xy 75.065764 -97.419664) (xy 75.010921 -97.409534)
			(xy 74.958137 -97.391527) (xy 74.908537 -97.366026) (xy 74.863179 -97.333575) (xy 74.82303 -97.294866)
			(xy 74.788944 -97.250723) (xy 74.761648 -97.202088) (xy 74.741725 -97.149997) (xy 74.729599 -97.09556)
			(xy 74.725528 -97.039938) (xy 70.059604 -97.039938) (xy 70.037089 -97.087966) (xy 70.006316 -97.134479)
			(xy 69.969099 -97.176016) (xy 69.926231 -97.211691) (xy 69.878625 -97.240745) (xy 69.827296 -97.262557)
			(xy 69.773339 -97.276663) (xy 69.717902 -97.282763) (xy 69.662168 -97.280726) (xy 69.607325 -97.270596)
			(xy 69.554541 -97.252589) (xy 69.504941 -97.227088) (xy 69.459583 -97.194637) (xy 69.419434 -97.155928)
			(xy 69.385348 -97.111785) (xy 69.358052 -97.06315) (xy 69.338129 -97.011059) (xy 69.326003 -96.956622)
			(xy 69.321932 -96.901) (xy 52.335683 -96.901) (xy 52.345361 -96.922192) (xy 52.360716 -96.974487)
			(xy 52.368472 -97.028435) (xy 52.368958 -97.055686) (xy 52.368342 -97.086489) (xy 52.35842 -97.14729)
			(xy 52.338848 -97.205703) (xy 52.325016 -97.233232) (xy 52.324762 -97.23374) (xy 52.322287 -97.239061)
			(xy 52.319593 -97.25048) (xy 52.319428 -97.256346) (xy 52.319428 -97.617788) (xy 52.31901 -97.64014)
			(xy 73.918062 -97.64014) (xy 73.922133 -97.584518) (xy 73.934259 -97.530081) (xy 73.954182 -97.47799)
			(xy 73.981478 -97.429355) (xy 74.015564 -97.385212) (xy 74.055713 -97.346503) (xy 74.101071 -97.314052)
			(xy 74.150671 -97.288551) (xy 74.203455 -97.270544) (xy 74.258298 -97.260414) (xy 74.314032 -97.258377)
			(xy 74.369469 -97.264477) (xy 74.423426 -97.278583) (xy 74.474755 -97.300395) (xy 74.522361 -97.329449)
			(xy 74.565229 -97.365124) (xy 74.602446 -97.406661) (xy 74.633219 -97.453174) (xy 74.656891 -97.503671)
			(xy 74.672959 -97.557078) (xy 74.681079 -97.612254) (xy 74.681588 -97.64014) (xy 74.681079 -97.668026)
			(xy 74.672959 -97.723202) (xy 74.656891 -97.776609) (xy 74.633219 -97.827106) (xy 74.602446 -97.873619)
			(xy 74.565229 -97.915156) (xy 74.522361 -97.950831) (xy 74.474755 -97.979885) (xy 74.423426 -98.001697)
			(xy 74.369469 -98.015803) (xy 74.314032 -98.021903) (xy 74.258298 -98.019866) (xy 74.203455 -98.009736)
			(xy 74.150671 -97.991729) (xy 74.101071 -97.966228) (xy 74.055713 -97.933777) (xy 74.015564 -97.895068)
			(xy 73.981478 -97.850925) (xy 73.954182 -97.80229) (xy 73.934259 -97.750199) (xy 73.922133 -97.695762)
			(xy 73.918062 -97.64014) (xy 52.31901 -97.64014) (xy 52.31894 -97.643875) (xy 52.310774 -97.695407)
			(xy 52.294642 -97.745024) (xy 52.270942 -97.791505) (xy 52.240258 -97.833703) (xy 52.222146 -97.852484)
			(xy 51.903525 -98.171) (xy 75.563982 -98.171) (xy 75.568053 -98.115378) (xy 75.580179 -98.060941)
			(xy 75.600102 -98.00885) (xy 75.627398 -97.960215) (xy 75.661484 -97.916072) (xy 75.701633 -97.877363)
			(xy 75.746991 -97.844912) (xy 75.796591 -97.819411) (xy 75.849375 -97.801404) (xy 75.904218 -97.791274)
			(xy 75.959952 -97.789237) (xy 76.015389 -97.795337) (xy 76.069346 -97.809443) (xy 76.120675 -97.831255)
			(xy 76.168281 -97.860309) (xy 76.211149 -97.895984) (xy 76.248366 -97.937521) (xy 76.258988 -97.953576)
			(xy 88.342976 -97.953576) (xy 88.347047 -97.897954) (xy 88.359173 -97.843517) (xy 88.379096 -97.791426)
			(xy 88.406392 -97.742791) (xy 88.440478 -97.698648) (xy 88.480627 -97.659939) (xy 88.525985 -97.627488)
			(xy 88.575585 -97.601987) (xy 88.628369 -97.58398) (xy 88.683212 -97.57385) (xy 88.738946 -97.571813)
			(xy 88.794383 -97.577913) (xy 88.84834 -97.592019) (xy 88.899669 -97.613831) (xy 88.947275 -97.642885)
			(xy 88.990143 -97.67856) (xy 89.02736 -97.720097) (xy 89.058133 -97.76661) (xy 89.081805 -97.817107)
			(xy 89.083049 -97.821242) (xy 89.657426 -97.821242) (xy 89.661497 -97.76562) (xy 89.673623 -97.711183)
			(xy 89.693546 -97.659092) (xy 89.720842 -97.610457) (xy 89.754928 -97.566314) (xy 89.795077 -97.527605)
			(xy 89.840435 -97.495154) (xy 89.890035 -97.469653) (xy 89.942819 -97.451646) (xy 89.997662 -97.441516)
			(xy 90.053396 -97.439479) (xy 90.108833 -97.445579) (xy 90.16279 -97.459685) (xy 90.214119 -97.481497)
			(xy 90.261725 -97.510551) (xy 90.304593 -97.546226) (xy 90.34181 -97.587763) (xy 90.372583 -97.634276)
			(xy 90.396255 -97.684773) (xy 90.412323 -97.73818) (xy 90.420443 -97.793356) (xy 90.420952 -97.821242)
			(xy 90.420455 -97.848452) (xy 90.928397 -97.848452) (xy 90.928397 -97.793948) (xy 90.936155 -97.739999)
			(xy 90.951511 -97.687704) (xy 90.974154 -97.638126) (xy 91.003623 -97.592276) (xy 91.039318 -97.551087)
			(xy 91.080511 -97.515397) (xy 91.126365 -97.485933) (xy 91.175945 -97.463296) (xy 91.228242 -97.447945)
			(xy 91.282192 -97.440194) (xy 91.309444 -97.439734) (xy 91.33836 -97.44028) (xy 91.395531 -97.449001)
			(xy 91.450729 -97.466253) (xy 91.502692 -97.491639) (xy 91.550226 -97.524579) (xy 91.592244 -97.564316)
			(xy 91.610434 -97.5868) (xy 91.618036 -97.595613) (xy 91.638941 -97.605793) (xy 91.650566 -97.606358)
			(xy 91.730322 -97.606358) (xy 91.741956 -97.605832) (xy 91.762866 -97.595635) (xy 91.770454 -97.5868)
			(xy 91.788671 -97.564339) (xy 91.830685 -97.524602) (xy 91.878215 -97.49166) (xy 91.930171 -97.466268)
			(xy 91.985364 -97.449007) (xy 92.04253 -97.440272) (xy 92.071444 -97.439734) (xy 92.098696 -97.440139)
			(xy 92.152645 -97.447901) (xy 92.20494 -97.463262) (xy 92.254517 -97.485908) (xy 92.300367 -97.515379)
			(xy 92.341557 -97.551074) (xy 92.377248 -97.592268) (xy 92.406713 -97.638121) (xy 92.429353 -97.687701)
			(xy 92.444708 -97.739998) (xy 92.452464 -97.793948) (xy 92.452464 -97.821242) (xy 92.705426 -97.821242)
			(xy 92.709497 -97.76562) (xy 92.721623 -97.711183) (xy 92.741546 -97.659092) (xy 92.768842 -97.610457)
			(xy 92.802928 -97.566314) (xy 92.843077 -97.527605) (xy 92.888435 -97.495154) (xy 92.938035 -97.469653)
			(xy 92.990819 -97.451646) (xy 93.045662 -97.441516) (xy 93.101396 -97.439479) (xy 93.156833 -97.445579)
			(xy 93.21079 -97.459685) (xy 93.262119 -97.481497) (xy 93.309725 -97.510551) (xy 93.352593 -97.546226)
			(xy 93.38981 -97.587763) (xy 93.420583 -97.634276) (xy 93.444255 -97.684773) (xy 93.460323 -97.73818)
			(xy 93.468443 -97.793356) (xy 93.468952 -97.821242) (xy 93.468443 -97.849128) (xy 93.460323 -97.904304)
			(xy 93.444255 -97.957711) (xy 93.420583 -98.008208) (xy 93.38981 -98.054721) (xy 93.352593 -98.096258)
			(xy 93.309725 -98.131933) (xy 93.262119 -98.160987) (xy 93.21079 -98.182799) (xy 93.156833 -98.196905)
			(xy 93.101396 -98.203005) (xy 93.045662 -98.200968) (xy 92.990819 -98.190838) (xy 92.938035 -98.172831)
			(xy 92.888435 -98.14733) (xy 92.843077 -98.114879) (xy 92.802928 -98.07617) (xy 92.768842 -98.032027)
			(xy 92.741546 -97.983392) (xy 92.721623 -97.931301) (xy 92.709497 -97.876864) (xy 92.705426 -97.821242)
			(xy 92.452464 -97.821242) (xy 92.452464 -97.848452) (xy 92.444708 -97.902402) (xy 92.429353 -97.954699)
			(xy 92.406713 -98.004279) (xy 92.377248 -98.050132) (xy 92.341557 -98.091326) (xy 92.300367 -98.127021)
			(xy 92.254517 -98.156492) (xy 92.20494 -98.179138) (xy 92.152645 -98.194499) (xy 92.098696 -98.202261)
			(xy 92.071444 -98.20275) (xy 92.042527 -98.202219) (xy 91.985356 -98.193495) (xy 91.930156 -98.176241)
			(xy 91.878194 -98.150852) (xy 91.83066 -98.11791) (xy 91.788644 -98.078169) (xy 91.770454 -98.055684)
			(xy 91.76286 -98.046863) (xy 91.741949 -98.036687) (xy 91.730322 -98.036126) (xy 91.650566 -98.036126)
			(xy 91.638932 -98.036651) (xy 91.618022 -98.046849) (xy 91.610434 -98.055684) (xy 91.59222 -98.078148)
			(xy 91.550205 -98.117885) (xy 91.502675 -98.150827) (xy 91.450719 -98.176219) (xy 91.395525 -98.193479)
			(xy 91.338359 -98.202213) (xy 91.309444 -98.20275) (xy 91.282192 -98.202206) (xy 91.228242 -98.194455)
			(xy 91.175945 -98.179104) (xy 91.126365 -98.156467) (xy 91.080511 -98.127003) (xy 91.039318 -98.091313)
			(xy 91.003623 -98.050124) (xy 90.974154 -98.004274) (xy 90.951511 -97.954696) (xy 90.936155 -97.902401)
			(xy 90.928397 -97.848452) (xy 90.420455 -97.848452) (xy 90.420443 -97.849128) (xy 90.412323 -97.904304)
			(xy 90.396255 -97.957711) (xy 90.372583 -98.008208) (xy 90.34181 -98.054721) (xy 90.304593 -98.096258)
			(xy 90.261725 -98.131933) (xy 90.214119 -98.160987) (xy 90.16279 -98.182799) (xy 90.108833 -98.196905)
			(xy 90.053396 -98.203005) (xy 89.997662 -98.200968) (xy 89.942819 -98.190838) (xy 89.890035 -98.172831)
			(xy 89.840435 -98.14733) (xy 89.795077 -98.114879) (xy 89.754928 -98.07617) (xy 89.720842 -98.032027)
			(xy 89.693546 -97.983392) (xy 89.673623 -97.931301) (xy 89.661497 -97.876864) (xy 89.657426 -97.821242)
			(xy 89.083049 -97.821242) (xy 89.097873 -97.870514) (xy 89.105993 -97.92569) (xy 89.106502 -97.953576)
			(xy 89.105993 -97.981462) (xy 89.097873 -98.036638) (xy 89.081805 -98.090045) (xy 89.058133 -98.140542)
			(xy 89.02736 -98.187055) (xy 88.990143 -98.228592) (xy 88.947275 -98.264267) (xy 88.899669 -98.293321)
			(xy 88.84834 -98.315133) (xy 88.794383 -98.329239) (xy 88.738946 -98.335339) (xy 88.683212 -98.333302)
			(xy 88.628369 -98.323172) (xy 88.575585 -98.305165) (xy 88.525985 -98.279664) (xy 88.480627 -98.247213)
			(xy 88.440478 -98.208504) (xy 88.406392 -98.164361) (xy 88.379096 -98.115726) (xy 88.359173 -98.063635)
			(xy 88.347047 -98.009198) (xy 88.342976 -97.953576) (xy 76.258988 -97.953576) (xy 76.279139 -97.984034)
			(xy 76.302811 -98.034531) (xy 76.318879 -98.087938) (xy 76.326999 -98.143114) (xy 76.327508 -98.171)
			(xy 76.326999 -98.198886) (xy 76.318879 -98.254062) (xy 76.302811 -98.307469) (xy 76.279139 -98.357966)
			(xy 76.248366 -98.404479) (xy 76.211149 -98.446016) (xy 76.168281 -98.481691) (xy 76.120675 -98.510745)
			(xy 76.069346 -98.532557) (xy 76.015389 -98.546663) (xy 75.959952 -98.552763) (xy 75.904218 -98.550726)
			(xy 75.849375 -98.540596) (xy 75.796591 -98.522589) (xy 75.746991 -98.497088) (xy 75.701633 -98.464637)
			(xy 75.661484 -98.425928) (xy 75.627398 -98.381785) (xy 75.600102 -98.33315) (xy 75.580179 -98.281059)
			(xy 75.568053 -98.226622) (xy 75.563982 -98.171) (xy 51.903525 -98.171) (xy 51.44897 -98.625406)
			(xy 51.442131 -98.632806) (xy 51.434411 -98.651406) (xy 51.433984 -98.661474) (xy 51.433984 -98.759518)
			(xy 99.171252 -98.759518) (xy 99.171716 -98.732148) (xy 99.179532 -98.677968) (xy 99.195021 -98.625464)
			(xy 99.217864 -98.575717) (xy 99.24759 -98.529751) (xy 99.265232 -98.50882) (xy 99.265486 -98.508566)
			(xy 99.27105 -98.501464) (xy 99.277311 -98.484559) (xy 99.277678 -98.475546) (xy 99.277678 -98.40849)
			(xy 99.277331 -98.399472) (xy 99.271077 -98.382555) (xy 99.265486 -98.37547) (xy 99.265232 -98.37547)
			(xy 99.265232 -98.375216) (xy 99.247609 -98.354269) (xy 99.217883 -98.308304) (xy 99.195036 -98.25856)
			(xy 99.179538 -98.20606) (xy 99.171708 -98.151883) (xy 99.171706 -98.097144) (xy 99.179532 -98.042966)
			(xy 99.195027 -97.990465) (xy 99.21787 -97.94072) (xy 99.247592 -97.894753) (xy 99.265232 -97.87382)
			(xy 99.265486 -97.873566) (xy 99.27105 -97.866464) (xy 99.277311 -97.849559) (xy 99.277678 -97.840546)
			(xy 99.277678 -97.77349) (xy 99.277331 -97.764472) (xy 99.271077 -97.747555) (xy 99.265486 -97.74047)
			(xy 99.265232 -97.74047) (xy 99.265232 -97.740216) (xy 99.247592 -97.719285) (xy 99.217879 -97.673312)
			(xy 99.195043 -97.623565) (xy 99.179552 -97.571063) (xy 99.171725 -97.516887) (xy 99.171252 -97.489518)
			(xy 99.171738 -97.462267) (xy 99.179494 -97.408319) (xy 99.194849 -97.356024) (xy 99.217491 -97.306447)
			(xy 99.246957 -97.260597) (xy 99.282648 -97.219406) (xy 99.323839 -97.183715) (xy 99.369689 -97.154249)
			(xy 99.419266 -97.131607) (xy 99.471561 -97.116252) (xy 99.525509 -97.108496) (xy 99.580011 -97.108496)
			(xy 99.633959 -97.116252) (xy 99.686254 -97.131607) (xy 99.735831 -97.154249) (xy 99.781681 -97.183715)
			(xy 99.822872 -97.219406) (xy 99.858563 -97.260597) (xy 99.888029 -97.306447) (xy 99.910671 -97.356024)
			(xy 99.926026 -97.408319) (xy 99.933782 -97.462267) (xy 99.934268 -97.489518) (xy 99.93382 -97.516889)
			(xy 99.925999 -97.571069) (xy 99.910506 -97.623573) (xy 99.88766 -97.673319) (xy 99.857931 -97.719285)
			(xy 99.840288 -97.740216) (xy 99.840034 -97.74047) (xy 99.834446 -97.747555) (xy 99.828202 -97.764473)
			(xy 99.827842 -97.77349) (xy 99.827842 -97.840546) (xy 99.828216 -97.849561) (xy 99.834451 -97.866479)
			(xy 99.840034 -97.873566) (xy 99.840288 -97.873566) (xy 99.840288 -97.87382) (xy 99.857946 -97.894739)
			(xy 99.887669 -97.940709) (xy 99.910512 -97.990458) (xy 99.926006 -98.042962) (xy 99.933833 -98.097142)
			(xy 99.933831 -98.151885) (xy 99.926 -98.206064) (xy 99.910502 -98.258567) (xy 99.887656 -98.308314)
			(xy 99.857929 -98.354283) (xy 99.840288 -98.375216) (xy 99.840034 -98.37547) (xy 99.834446 -98.382555)
			(xy 99.828202 -98.399473) (xy 99.827842 -98.40849) (xy 99.827842 -98.475546) (xy 99.828216 -98.484561)
			(xy 99.834451 -98.501479) (xy 99.836082 -98.503549) (xy 100.826086 -98.503549) (xy 100.826086 -98.449051)
			(xy 100.833841 -98.395108) (xy 100.849194 -98.342817) (xy 100.871832 -98.293244) (xy 100.901294 -98.247396)
			(xy 100.936981 -98.206207) (xy 100.978165 -98.170517) (xy 101.02401 -98.14105) (xy 101.073582 -98.118407)
			(xy 101.125871 -98.103049) (xy 101.179813 -98.095288) (xy 101.207062 -98.0948) (xy 101.233377 -98.095226)
			(xy 101.285508 -98.102469) (xy 101.336151 -98.116797) (xy 101.38435 -98.137937) (xy 101.429192 -98.16549)
			(xy 101.46983 -98.198935) (xy 101.487986 -98.21799) (xy 101.495512 -98.225386) (xy 101.514789 -98.233914)
			(xy 101.525324 -98.2345) (xy 101.6 -98.2345) (xy 101.610551 -98.233985) (xy 101.629847 -98.22544)
			(xy 101.637338 -98.21799) (xy 101.65548 -98.198921) (xy 101.696113 -98.165466) (xy 101.740956 -98.137909)
			(xy 101.789159 -98.116772) (xy 101.839809 -98.102458) (xy 101.891945 -98.095237) (xy 101.918262 -98.0948)
			(xy 101.945517 -98.095245) (xy 101.999473 -98.102998) (xy 102.051777 -98.118351) (xy 102.101363 -98.140991)
			(xy 102.147222 -98.170459) (xy 102.18842 -98.206153) (xy 102.224118 -98.247348) (xy 102.25359 -98.293204)
			(xy 102.273298 -98.336354) (xy 102.849426 -98.336354) (xy 102.849917 -98.308985) (xy 102.857728 -98.254806)
			(xy 102.873211 -98.202303) (xy 102.896047 -98.152556) (xy 102.925767 -98.106588) (xy 102.943406 -98.085656)
			(xy 102.94366 -98.085402) (xy 102.949259 -98.078324) (xy 102.955497 -98.0614) (xy 102.955852 -98.052382)
			(xy 102.955852 -97.985326) (xy 102.955493 -97.976309) (xy 102.949248 -97.959392) (xy 102.94366 -97.952306)
			(xy 102.943406 -97.952306) (xy 102.943406 -97.952052) (xy 102.925721 -97.931155) (xy 102.896 -97.885181)
			(xy 102.873158 -97.835428) (xy 102.857667 -97.782921) (xy 102.849843 -97.728738) (xy 102.849848 -97.673993)
			(xy 102.857681 -97.619811) (xy 102.873183 -97.567307) (xy 102.896033 -97.517558) (xy 102.925763 -97.471589)
			(xy 102.943406 -97.450656) (xy 102.94366 -97.450402) (xy 102.949259 -97.443324) (xy 102.955497 -97.4264)
			(xy 102.955852 -97.417382) (xy 102.955852 -97.350326) (xy 102.955493 -97.341309) (xy 102.949248 -97.324392)
			(xy 102.94366 -97.317306) (xy 102.943406 -97.317306) (xy 102.943406 -97.317052) (xy 102.925779 -97.29611)
			(xy 102.896065 -97.25014) (xy 102.873227 -97.200395) (xy 102.857733 -97.147897) (xy 102.849902 -97.093723)
			(xy 102.849426 -97.066354) (xy 102.849912 -97.039103) (xy 102.857668 -96.985155) (xy 102.873023 -96.93286)
			(xy 102.895665 -96.883283) (xy 102.925131 -96.837433) (xy 102.960822 -96.796242) (xy 103.002013 -96.760551)
			(xy 103.047863 -96.731085) (xy 103.09744 -96.708443) (xy 103.149735 -96.693088) (xy 103.203683 -96.685332)
			(xy 103.258185 -96.685332) (xy 103.312133 -96.693088) (xy 103.364428 -96.708443) (xy 103.414005 -96.731085)
			(xy 103.459855 -96.760551) (xy 103.501046 -96.796242) (xy 103.536737 -96.837433) (xy 103.566203 -96.883283)
			(xy 103.588845 -96.93286) (xy 103.6042 -96.985155) (xy 103.611956 -97.039103) (xy 103.612442 -97.066354)
			(xy 103.611963 -97.093724) (xy 103.604151 -97.147903) (xy 103.588665 -97.200407) (xy 103.565826 -97.250154)
			(xy 103.536103 -97.296121) (xy 103.518462 -97.317052) (xy 103.518208 -97.317306) (xy 103.512614 -97.324387)
			(xy 103.506371 -97.341308) (xy 103.506016 -97.350326) (xy 103.506016 -97.417382) (xy 103.506378 -97.426398)
			(xy 103.512622 -97.443316) (xy 103.518208 -97.450402) (xy 103.518462 -97.450402) (xy 103.518462 -97.450656)
			(xy 103.536058 -97.471625) (xy 103.565786 -97.517586) (xy 103.588634 -97.567326) (xy 103.604135 -97.619823)
			(xy 103.611968 -97.673997) (xy 103.611973 -97.728734) (xy 103.604149 -97.782909) (xy 103.588659 -97.835409)
			(xy 103.565819 -97.885153) (xy 103.5361 -97.93112) (xy 103.518462 -97.952052) (xy 103.518208 -97.952306)
			(xy 103.512614 -97.959387) (xy 103.506371 -97.976308) (xy 103.506016 -97.985326) (xy 103.506016 -98.052382)
			(xy 103.506378 -98.061398) (xy 103.512622 -98.078316) (xy 103.518208 -98.085402) (xy 103.518462 -98.085402)
			(xy 103.518462 -98.085656) (xy 103.536088 -98.106599) (xy 103.565803 -98.152568) (xy 103.588642 -98.202313)
			(xy 103.604136 -98.254811) (xy 103.611967 -98.308985) (xy 103.612442 -98.336354) (xy 103.612175 -98.35134)
			(xy 106.04373 -98.35134) (xy 106.044212 -98.32397) (xy 106.052025 -98.269792) (xy 106.06751 -98.217288)
			(xy 106.090348 -98.167541) (xy 106.12007 -98.121574) (xy 106.13771 -98.100642) (xy 106.137964 -98.100388)
			(xy 106.143569 -98.093315) (xy 106.149803 -98.076387) (xy 106.150156 -98.067368) (xy 106.150156 -98.000312)
			(xy 106.149803 -97.991295) (xy 106.143553 -97.974377) (xy 106.137964 -97.967292) (xy 106.13771 -97.967292)
			(xy 106.13771 -97.967038) (xy 106.120109 -97.946073) (xy 106.090384 -97.900111) (xy 106.067537 -97.850369)
			(xy 106.052039 -97.797872) (xy 106.044207 -97.743699) (xy 106.044202 -97.688962) (xy 106.052026 -97.634786)
			(xy 106.067516 -97.582287) (xy 106.090355 -97.532542) (xy 106.120073 -97.486575) (xy 106.13771 -97.465642)
			(xy 106.137964 -97.465388) (xy 106.143569 -97.458315) (xy 106.149803 -97.441387) (xy 106.150156 -97.432368)
			(xy 106.150156 -97.365312) (xy 106.149803 -97.356295) (xy 106.143553 -97.339377) (xy 106.137964 -97.332292)
			(xy 106.13771 -97.332292) (xy 106.13771 -97.332038) (xy 106.120077 -97.311101) (xy 106.090364 -97.26513)
			(xy 106.067527 -97.215384) (xy 106.052034 -97.162884) (xy 106.044205 -97.108709) (xy 106.04373 -97.08134)
			(xy 106.044216 -97.054089) (xy 106.051972 -97.000141) (xy 106.067327 -96.947846) (xy 106.089969 -96.898269)
			(xy 106.119435 -96.852419) (xy 106.155126 -96.811228) (xy 106.196317 -96.775537) (xy 106.242167 -96.746071)
			(xy 106.291744 -96.723429) (xy 106.344039 -96.708074) (xy 106.397987 -96.700318) (xy 106.452489 -96.700318)
			(xy 106.506437 -96.708074) (xy 106.558732 -96.723429) (xy 106.608309 -96.746071) (xy 106.654159 -96.775537)
			(xy 106.69535 -96.811228) (xy 106.731041 -96.852419) (xy 106.760507 -96.898269) (xy 106.783149 -96.947846)
			(xy 106.798504 -97.000141) (xy 106.80626 -97.054089) (xy 106.806746 -97.08134) (xy 106.806258 -97.10871)
			(xy 106.798447 -97.162888) (xy 106.782964 -97.215392) (xy 106.760127 -97.265139) (xy 106.730406 -97.311106)
			(xy 106.712766 -97.332038) (xy 106.712512 -97.332292) (xy 106.706924 -97.339378) (xy 106.700678 -97.356295)
			(xy 106.70032 -97.365312) (xy 106.70032 -97.432368) (xy 106.700688 -97.441384) (xy 106.706928 -97.458301)
			(xy 106.712512 -97.465388) (xy 106.712766 -97.465388) (xy 106.712766 -97.465642) (xy 106.730446 -97.486543)
			(xy 106.76017 -97.532516) (xy 106.783013 -97.582268) (xy 106.798507 -97.634774) (xy 106.806332 -97.688958)
			(xy 106.806327 -97.743703) (xy 106.798494 -97.797884) (xy 106.782992 -97.850389) (xy 106.760141 -97.900137)
			(xy 106.73041 -97.946105) (xy 106.712766 -97.967038) (xy 106.712512 -97.967292) (xy 106.706924 -97.974378)
			(xy 106.700678 -97.991295) (xy 106.70032 -98.000312) (xy 106.70032 -98.067368) (xy 106.700688 -98.076384)
			(xy 106.706928 -98.093301) (xy 106.712512 -98.100388) (xy 106.712766 -98.100388) (xy 106.712766 -98.100642)
			(xy 106.730386 -98.121589) (xy 106.760102 -98.167558) (xy 106.782942 -98.217301) (xy 106.798437 -98.269799)
			(xy 106.805783 -98.320606) (xy 119.737884 -98.320606) (xy 119.741955 -98.264984) (xy 119.754081 -98.210547)
			(xy 119.774004 -98.158456) (xy 119.8013 -98.109821) (xy 119.835386 -98.065678) (xy 119.875535 -98.026969)
			(xy 119.920893 -97.994518) (xy 119.970493 -97.969017) (xy 120.023277 -97.95101) (xy 120.07812 -97.94088)
			(xy 120.133854 -97.938843) (xy 120.189291 -97.944943) (xy 120.243248 -97.959049) (xy 120.294577 -97.980861)
			(xy 120.342183 -98.009915) (xy 120.385051 -98.04559) (xy 120.422268 -98.087127) (xy 120.453041 -98.13364)
			(xy 120.476713 -98.184137) (xy 120.492781 -98.237544) (xy 120.497566 -98.27006) (xy 125.399544 -98.27006)
			(xy 125.403615 -98.214438) (xy 125.415741 -98.160001) (xy 125.435664 -98.10791) (xy 125.46296 -98.059275)
			(xy 125.497046 -98.015132) (xy 125.537195 -97.976423) (xy 125.582553 -97.943972) (xy 125.632153 -97.918471)
			(xy 125.684937 -97.900464) (xy 125.73978 -97.890334) (xy 125.795514 -97.888297) (xy 125.850951 -97.894397)
			(xy 125.904908 -97.908503) (xy 125.956237 -97.930315) (xy 126.003843 -97.959369) (xy 126.046711 -97.995044)
			(xy 126.083928 -98.036581) (xy 126.114701 -98.083094) (xy 126.138373 -98.133591) (xy 126.154441 -98.186998)
			(xy 126.162561 -98.242174) (xy 126.16307 -98.27006) (xy 126.162561 -98.297946) (xy 126.154441 -98.353122)
			(xy 126.138373 -98.406529) (xy 126.114701 -98.457026) (xy 126.083928 -98.503539) (xy 126.046711 -98.545076)
			(xy 126.003843 -98.580751) (xy 125.956237 -98.609805) (xy 125.904908 -98.631617) (xy 125.850951 -98.645723)
			(xy 125.795514 -98.651823) (xy 125.73978 -98.649786) (xy 125.684937 -98.639656) (xy 125.632153 -98.621649)
			(xy 125.582553 -98.596148) (xy 125.537195 -98.563697) (xy 125.497046 -98.524988) (xy 125.46296 -98.480845)
			(xy 125.435664 -98.43221) (xy 125.415741 -98.380119) (xy 125.403615 -98.325682) (xy 125.399544 -98.27006)
			(xy 120.497566 -98.27006) (xy 120.500901 -98.29272) (xy 120.50141 -98.320606) (xy 120.500901 -98.348492)
			(xy 120.492781 -98.403668) (xy 120.476713 -98.457075) (xy 120.453041 -98.507572) (xy 120.422268 -98.554085)
			(xy 120.385051 -98.595622) (xy 120.342183 -98.631297) (xy 120.294577 -98.660351) (xy 120.243248 -98.682163)
			(xy 120.189291 -98.696269) (xy 120.133854 -98.702369) (xy 120.07812 -98.700332) (xy 120.023277 -98.690202)
			(xy 119.970493 -98.672195) (xy 119.920893 -98.646694) (xy 119.875535 -98.614243) (xy 119.835386 -98.575534)
			(xy 119.8013 -98.531391) (xy 119.774004 -98.482756) (xy 119.754081 -98.430665) (xy 119.741955 -98.376228)
			(xy 119.737884 -98.320606) (xy 106.805783 -98.320606) (xy 106.80627 -98.323972) (xy 106.806746 -98.35134)
			(xy 106.80626 -98.378591) (xy 106.798504 -98.432539) (xy 106.783149 -98.484834) (xy 106.760507 -98.534411)
			(xy 106.731041 -98.580261) (xy 106.69535 -98.621452) (xy 106.654159 -98.657143) (xy 106.608309 -98.686609)
			(xy 106.558732 -98.709251) (xy 106.506437 -98.724606) (xy 106.452489 -98.732362) (xy 106.397987 -98.732362)
			(xy 106.344039 -98.724606) (xy 106.291744 -98.709251) (xy 106.242167 -98.686609) (xy 106.196317 -98.657143)
			(xy 106.155126 -98.621452) (xy 106.119435 -98.580261) (xy 106.089969 -98.534411) (xy 106.067327 -98.484834)
			(xy 106.051972 -98.432539) (xy 106.044216 -98.378591) (xy 106.04373 -98.35134) (xy 103.612175 -98.35134)
			(xy 103.611956 -98.363605) (xy 103.6042 -98.417553) (xy 103.588845 -98.469848) (xy 103.566203 -98.519425)
			(xy 103.536737 -98.565275) (xy 103.501046 -98.606466) (xy 103.459855 -98.642157) (xy 103.414005 -98.671623)
			(xy 103.364428 -98.694265) (xy 103.312133 -98.70962) (xy 103.258185 -98.717376) (xy 103.203683 -98.717376)
			(xy 103.149735 -98.70962) (xy 103.09744 -98.694265) (xy 103.047863 -98.671623) (xy 103.002013 -98.642157)
			(xy 102.960822 -98.606466) (xy 102.925131 -98.565275) (xy 102.895665 -98.519425) (xy 102.873023 -98.469848)
			(xy 102.857668 -98.417553) (xy 102.849912 -98.363605) (xy 102.849426 -98.336354) (xy 102.273298 -98.336354)
			(xy 102.276236 -98.342787) (xy 102.291594 -98.395089) (xy 102.299353 -98.449045) (xy 102.299353 -98.503555)
			(xy 102.291594 -98.557511) (xy 102.276236 -98.609813) (xy 102.25359 -98.659396) (xy 102.224118 -98.705252)
			(xy 102.18842 -98.746447) (xy 102.147222 -98.782141) (xy 102.101363 -98.811609) (xy 102.051777 -98.834249)
			(xy 101.999473 -98.849602) (xy 101.945517 -98.857355) (xy 101.918262 -98.857816) (xy 101.891947 -98.857369)
			(xy 101.839818 -98.850129) (xy 101.789175 -98.835806) (xy 101.740977 -98.814669) (xy 101.696134 -98.78712)
			(xy 101.655494 -98.753679) (xy 101.637338 -98.734626) (xy 101.629801 -98.727243) (xy 101.610533 -98.718707)
			(xy 101.6 -98.718116) (xy 101.525324 -98.718116) (xy 101.514774 -98.71864) (xy 101.495478 -98.727178)
			(xy 101.487986 -98.734626) (xy 101.469835 -98.753686) (xy 101.429204 -98.787142) (xy 101.384363 -98.8147)
			(xy 101.336161 -98.835837) (xy 101.285513 -98.850154) (xy 101.233378 -98.857378) (xy 101.207062 -98.857816)
			(xy 101.179813 -98.857312) (xy 101.125871 -98.849551) (xy 101.073582 -98.834193) (xy 101.02401 -98.81155)
			(xy 100.978165 -98.782083) (xy 100.936981 -98.746393) (xy 100.901294 -98.705204) (xy 100.871832 -98.659356)
			(xy 100.849194 -98.609783) (xy 100.833841 -98.557492) (xy 100.826086 -98.503549) (xy 99.836082 -98.503549)
			(xy 99.840034 -98.508566) (xy 99.840288 -98.509074) (xy 99.851231 -98.521809) (xy 99.871073 -98.5489)
			(xy 99.879912 -98.563176) (xy 99.885246 -98.572066) (xy 99.902264 -98.584258) (xy 99.995482 -98.604578)
			(xy 100.016056 -98.60026) (xy 100.024692 -98.594418) (xy 100.048758 -98.578421) (xy 100.100688 -98.553077)
			(xy 100.155846 -98.535851) (xy 100.21297 -98.527135) (xy 100.241862 -98.5266) (xy 100.269117 -98.527045)
			(xy 100.323073 -98.534798) (xy 100.375377 -98.550151) (xy 100.424963 -98.572791) (xy 100.470822 -98.602259)
			(xy 100.51202 -98.637953) (xy 100.547718 -98.679148) (xy 100.57719 -98.725004) (xy 100.599836 -98.774587)
			(xy 100.615194 -98.826889) (xy 100.622953 -98.880845) (xy 100.622953 -98.935355) (xy 100.615194 -98.989311)
			(xy 100.599836 -99.041613) (xy 100.57719 -99.091196) (xy 100.547718 -99.137052) (xy 100.51202 -99.178247)
			(xy 100.470822 -99.213941) (xy 100.424963 -99.243409) (xy 100.375377 -99.266049) (xy 100.323073 -99.281402)
			(xy 100.269117 -99.289155) (xy 100.241862 -99.289616) (xy 100.213769 -99.289152) (xy 100.158191 -99.28092)
			(xy 100.104421 -99.264623) (xy 100.053623 -99.240615) (xy 100.006897 -99.209416) (xy 99.965253 -99.171699)
			(xy 99.929592 -99.128282) (xy 99.91471 -99.10445) (xy 99.909376 -99.09556) (xy 99.892358 -99.083368)
			(xy 99.79914 -99.063048) (xy 99.778566 -99.067366) (xy 99.76993 -99.073208) (xy 99.74586 -99.089198)
			(xy 99.693931 -99.114543) (xy 99.638775 -99.131771) (xy 99.581652 -99.14049) (xy 99.55276 -99.141026)
			(xy 99.525509 -99.140559) (xy 99.471561 -99.132798) (xy 99.419267 -99.117439) (xy 99.369691 -99.094794)
			(xy 99.323842 -99.065325) (xy 99.282652 -99.029632) (xy 99.246961 -98.988441) (xy 99.217495 -98.94259)
			(xy 99.194854 -98.893012) (xy 99.179497 -98.840717) (xy 99.171739 -98.786769) (xy 99.171252 -98.759518)
			(xy 51.433984 -98.759518) (xy 51.433984 -100.17633) (xy 53.639212 -100.17633) (xy 53.639212 -99.31273)
			(xy 53.639702 -99.282762) (xy 53.647525 -99.22334) (xy 53.663038 -99.165447) (xy 53.685974 -99.110074)
			(xy 53.715941 -99.058168) (xy 53.752428 -99.010618) (xy 53.794808 -98.968238) (xy 53.842358 -98.931751)
			(xy 53.894264 -98.901784) (xy 53.949637 -98.878848) (xy 54.00753 -98.863335) (xy 54.066952 -98.855512)
			(xy 54.126888 -98.855512) (xy 54.18631 -98.863335) (xy 54.244203 -98.878848) (xy 54.299576 -98.901784)
			(xy 54.351482 -98.931751) (xy 54.399032 -98.968238) (xy 54.441412 -99.010618) (xy 54.477899 -99.058168)
			(xy 54.507866 -99.110074) (xy 54.530802 -99.165447) (xy 54.546315 -99.22334) (xy 54.554138 -99.282762)
			(xy 54.554628 -99.31273) (xy 54.554628 -99.439984) (xy 75.309982 -99.439984) (xy 75.314053 -99.384362)
			(xy 75.326179 -99.329925) (xy 75.346102 -99.277834) (xy 75.373398 -99.229199) (xy 75.407484 -99.185056)
			(xy 75.447633 -99.146347) (xy 75.492991 -99.113896) (xy 75.542591 -99.088395) (xy 75.595375 -99.070388)
			(xy 75.650218 -99.060258) (xy 75.705952 -99.058221) (xy 75.761389 -99.064321) (xy 75.815346 -99.078427)
			(xy 75.866675 -99.100239) (xy 75.914281 -99.129293) (xy 75.957149 -99.164968) (xy 75.994366 -99.206505)
			(xy 76.025139 -99.253018) (xy 76.048811 -99.303515) (xy 76.064879 -99.356922) (xy 76.072999 -99.412098)
			(xy 76.073508 -99.439984) (xy 76.073336 -99.449382) (xy 87.906096 -99.449382) (xy 87.910167 -99.39376)
			(xy 87.922293 -99.339323) (xy 87.942216 -99.287232) (xy 87.969512 -99.238597) (xy 88.003598 -99.194454)
			(xy 88.043747 -99.155745) (xy 88.089105 -99.123294) (xy 88.138705 -99.097793) (xy 88.191489 -99.079786)
			(xy 88.246332 -99.069656) (xy 88.302066 -99.067619) (xy 88.357503 -99.073719) (xy 88.41146 -99.087825)
			(xy 88.462789 -99.109637) (xy 88.510395 -99.138691) (xy 88.553263 -99.174366) (xy 88.59048 -99.215903)
			(xy 88.621253 -99.262416) (xy 88.644925 -99.312913) (xy 88.660993 -99.36632) (xy 88.669113 -99.421496)
			(xy 88.669622 -99.449382) (xy 88.669455 -99.458526) (xy 93.638622 -99.458526) (xy 93.642693 -99.402904)
			(xy 93.654819 -99.348467) (xy 93.674742 -99.296376) (xy 93.702038 -99.247741) (xy 93.736124 -99.203598)
			(xy 93.776273 -99.164889) (xy 93.821631 -99.132438) (xy 93.871231 -99.106937) (xy 93.924015 -99.08893)
			(xy 93.978858 -99.0788) (xy 94.034592 -99.076763) (xy 94.090029 -99.082863) (xy 94.143986 -99.096969)
			(xy 94.195315 -99.118781) (xy 94.242921 -99.147835) (xy 94.285789 -99.18351) (xy 94.323006 -99.225047)
			(xy 94.353779 -99.27156) (xy 94.377451 -99.322057) (xy 94.393519 -99.375464) (xy 94.401639 -99.43064)
			(xy 94.402148 -99.458526) (xy 94.402055 -99.463606) (xy 119.737884 -99.463606) (xy 119.741955 -99.407984)
			(xy 119.754081 -99.353547) (xy 119.774004 -99.301456) (xy 119.8013 -99.252821) (xy 119.835386 -99.208678)
			(xy 119.875535 -99.169969) (xy 119.920893 -99.137518) (xy 119.970493 -99.112017) (xy 120.023277 -99.09401)
			(xy 120.07812 -99.08388) (xy 120.133854 -99.081843) (xy 120.189291 -99.087943) (xy 120.243248 -99.102049)
			(xy 120.294577 -99.123861) (xy 120.342183 -99.152915) (xy 120.385051 -99.18859) (xy 120.422268 -99.230127)
			(xy 120.453041 -99.27664) (xy 120.476713 -99.327137) (xy 120.492781 -99.380544) (xy 120.500901 -99.43572)
			(xy 120.50141 -99.463606) (xy 124.405388 -99.463606) (xy 124.409459 -99.407984) (xy 124.421585 -99.353547)
			(xy 124.441508 -99.301456) (xy 124.468804 -99.252821) (xy 124.50289 -99.208678) (xy 124.543039 -99.169969)
			(xy 124.588397 -99.137518) (xy 124.637997 -99.112017) (xy 124.690781 -99.09401) (xy 124.745624 -99.08388)
			(xy 124.801358 -99.081843) (xy 124.856795 -99.087943) (xy 124.910752 -99.102049) (xy 124.962081 -99.123861)
			(xy 125.009687 -99.152915) (xy 125.052555 -99.18859) (xy 125.089772 -99.230127) (xy 125.120545 -99.27664)
			(xy 125.144217 -99.327137) (xy 125.160285 -99.380544) (xy 125.168405 -99.43572) (xy 125.168914 -99.463606)
			(xy 125.168405 -99.491492) (xy 125.160285 -99.546668) (xy 125.144217 -99.600075) (xy 125.120545 -99.650572)
			(xy 125.089772 -99.697085) (xy 125.052555 -99.738622) (xy 125.009687 -99.774297) (xy 124.962081 -99.803351)
			(xy 124.910752 -99.825163) (xy 124.856795 -99.839269) (xy 124.801358 -99.845369) (xy 124.745624 -99.843332)
			(xy 124.690781 -99.833202) (xy 124.637997 -99.815195) (xy 124.588397 -99.789694) (xy 124.543039 -99.757243)
			(xy 124.50289 -99.718534) (xy 124.468804 -99.674391) (xy 124.441508 -99.625756) (xy 124.421585 -99.573665)
			(xy 124.409459 -99.519228) (xy 124.405388 -99.463606) (xy 120.50141 -99.463606) (xy 120.500901 -99.491492)
			(xy 120.492781 -99.546668) (xy 120.476713 -99.600075) (xy 120.453041 -99.650572) (xy 120.422268 -99.697085)
			(xy 120.385051 -99.738622) (xy 120.342183 -99.774297) (xy 120.294577 -99.803351) (xy 120.243248 -99.825163)
			(xy 120.189291 -99.839269) (xy 120.133854 -99.845369) (xy 120.07812 -99.843332) (xy 120.023277 -99.833202)
			(xy 119.970493 -99.815195) (xy 119.920893 -99.789694) (xy 119.875535 -99.757243) (xy 119.835386 -99.718534)
			(xy 119.8013 -99.674391) (xy 119.774004 -99.625756) (xy 119.754081 -99.573665) (xy 119.741955 -99.519228)
			(xy 119.737884 -99.463606) (xy 94.402055 -99.463606) (xy 94.401639 -99.486412) (xy 94.393519 -99.541588)
			(xy 94.377451 -99.594995) (xy 94.353779 -99.645492) (xy 94.323006 -99.692005) (xy 94.285789 -99.733542)
			(xy 94.242921 -99.769217) (xy 94.195315 -99.798271) (xy 94.143986 -99.820083) (xy 94.090029 -99.834189)
			(xy 94.034592 -99.840289) (xy 93.978858 -99.838252) (xy 93.924015 -99.828122) (xy 93.871231 -99.810115)
			(xy 93.821631 -99.784614) (xy 93.776273 -99.752163) (xy 93.736124 -99.713454) (xy 93.702038 -99.669311)
			(xy 93.674742 -99.620676) (xy 93.654819 -99.568585) (xy 93.642693 -99.514148) (xy 93.638622 -99.458526)
			(xy 88.669455 -99.458526) (xy 88.669113 -99.477268) (xy 88.660993 -99.532444) (xy 88.644925 -99.585851)
			(xy 88.621253 -99.636348) (xy 88.59048 -99.682861) (xy 88.553263 -99.724398) (xy 88.510395 -99.760073)
			(xy 88.462789 -99.789127) (xy 88.41146 -99.810939) (xy 88.357503 -99.825045) (xy 88.302066 -99.831145)
			(xy 88.246332 -99.829108) (xy 88.191489 -99.818978) (xy 88.138705 -99.800971) (xy 88.089105 -99.77547)
			(xy 88.043747 -99.743019) (xy 88.003598 -99.70431) (xy 87.969512 -99.660167) (xy 87.942216 -99.611532)
			(xy 87.922293 -99.559441) (xy 87.910167 -99.505004) (xy 87.906096 -99.449382) (xy 76.073336 -99.449382)
			(xy 76.072999 -99.46787) (xy 76.064879 -99.523046) (xy 76.048811 -99.576453) (xy 76.025139 -99.62695)
			(xy 75.994366 -99.673463) (xy 75.957149 -99.715) (xy 75.914281 -99.750675) (xy 75.866675 -99.779729)
			(xy 75.815346 -99.801541) (xy 75.761389 -99.815647) (xy 75.705952 -99.821747) (xy 75.650218 -99.81971)
			(xy 75.595375 -99.80958) (xy 75.542591 -99.791573) (xy 75.492991 -99.766072) (xy 75.447633 -99.733621)
			(xy 75.407484 -99.694912) (xy 75.373398 -99.650769) (xy 75.346102 -99.602134) (xy 75.326179 -99.550043)
			(xy 75.314053 -99.495606) (xy 75.309982 -99.439984) (xy 54.554628 -99.439984) (xy 54.554628 -100.17633)
			(xy 54.554138 -100.206298) (xy 54.546315 -100.26572) (xy 54.530802 -100.323613) (xy 54.519319 -100.351336)
			(xy 70.122032 -100.351336) (xy 70.126103 -100.295714) (xy 70.138229 -100.241277) (xy 70.158152 -100.189186)
			(xy 70.185448 -100.140551) (xy 70.219534 -100.096408) (xy 70.259683 -100.057699) (xy 70.305041 -100.025248)
			(xy 70.354641 -99.999747) (xy 70.407425 -99.98174) (xy 70.462268 -99.97161) (xy 70.518002 -99.969573)
			(xy 70.573439 -99.975673) (xy 70.627396 -99.989779) (xy 70.678725 -100.011591) (xy 70.725163 -100.039932)
			(xy 73.876914 -100.039932) (xy 73.880985 -99.98431) (xy 73.893111 -99.929873) (xy 73.913034 -99.877782)
			(xy 73.94033 -99.829147) (xy 73.974416 -99.785004) (xy 74.014565 -99.746295) (xy 74.059923 -99.713844)
			(xy 74.109523 -99.688343) (xy 74.162307 -99.670336) (xy 74.21715 -99.660206) (xy 74.272884 -99.658169)
			(xy 74.328321 -99.664269) (xy 74.382278 -99.678375) (xy 74.433607 -99.700187) (xy 74.481213 -99.729241)
			(xy 74.524081 -99.764916) (xy 74.561298 -99.806453) (xy 74.592071 -99.852966) (xy 74.615743 -99.903463)
			(xy 74.631811 -99.95687) (xy 74.639931 -100.012046) (xy 74.64044 -100.039932) (xy 74.639931 -100.067818)
			(xy 74.631811 -100.122994) (xy 74.615743 -100.176401) (xy 74.592319 -100.226368) (xy 119.200166 -100.226368)
			(xy 119.204237 -100.170746) (xy 119.216363 -100.116309) (xy 119.236286 -100.064218) (xy 119.263582 -100.015583)
			(xy 119.297668 -99.97144) (xy 119.337817 -99.932731) (xy 119.383175 -99.90028) (xy 119.432775 -99.874779)
			(xy 119.485559 -99.856772) (xy 119.540402 -99.846642) (xy 119.596136 -99.844605) (xy 119.651573 -99.850705)
			(xy 119.70553 -99.864811) (xy 119.756859 -99.886623) (xy 119.804465 -99.915677) (xy 119.847333 -99.951352)
			(xy 119.88455 -99.992889) (xy 119.915323 -100.039402) (xy 119.938995 -100.089899) (xy 119.955063 -100.143306)
			(xy 119.963183 -100.198482) (xy 119.963692 -100.226368) (xy 119.963183 -100.254254) (xy 119.955063 -100.30943)
			(xy 119.938995 -100.362837) (xy 119.915323 -100.413334) (xy 119.88455 -100.459847) (xy 119.847333 -100.501384)
			(xy 119.804465 -100.537059) (xy 119.756859 -100.566113) (xy 119.70553 -100.587925) (xy 119.651573 -100.602031)
			(xy 119.596136 -100.608131) (xy 119.540402 -100.606094) (xy 119.485559 -100.595964) (xy 119.432775 -100.577957)
			(xy 119.383175 -100.552456) (xy 119.337817 -100.520005) (xy 119.297668 -100.481296) (xy 119.263582 -100.437153)
			(xy 119.236286 -100.388518) (xy 119.216363 -100.336427) (xy 119.204237 -100.28199) (xy 119.200166 -100.226368)
			(xy 74.592319 -100.226368) (xy 74.592071 -100.226898) (xy 74.561298 -100.273411) (xy 74.524081 -100.314948)
			(xy 74.481213 -100.350623) (xy 74.433607 -100.379677) (xy 74.382278 -100.401489) (xy 74.328321 -100.415595)
			(xy 74.272884 -100.421695) (xy 74.21715 -100.419658) (xy 74.162307 -100.409528) (xy 74.109523 -100.391521)
			(xy 74.059923 -100.36602) (xy 74.014565 -100.333569) (xy 73.974416 -100.29486) (xy 73.94033 -100.250717)
			(xy 73.913034 -100.202082) (xy 73.893111 -100.149991) (xy 73.880985 -100.095554) (xy 73.876914 -100.039932)
			(xy 70.725163 -100.039932) (xy 70.726331 -100.040645) (xy 70.769199 -100.07632) (xy 70.806416 -100.117857)
			(xy 70.837189 -100.16437) (xy 70.860861 -100.214867) (xy 70.876929 -100.268274) (xy 70.885049 -100.32345)
			(xy 70.885558 -100.351336) (xy 70.885049 -100.379222) (xy 70.876929 -100.434398) (xy 70.860861 -100.487805)
			(xy 70.837189 -100.538302) (xy 70.806416 -100.584815) (xy 70.769199 -100.626352) (xy 70.726331 -100.662027)
			(xy 70.678725 -100.691081) (xy 70.627396 -100.712893) (xy 70.573439 -100.726999) (xy 70.518002 -100.733099)
			(xy 70.462268 -100.731062) (xy 70.407425 -100.720932) (xy 70.354641 -100.702925) (xy 70.305041 -100.677424)
			(xy 70.259683 -100.644973) (xy 70.219534 -100.606264) (xy 70.185448 -100.562121) (xy 70.158152 -100.513486)
			(xy 70.138229 -100.461395) (xy 70.126103 -100.406958) (xy 70.122032 -100.351336) (xy 54.519319 -100.351336)
			(xy 54.507866 -100.378986) (xy 54.477899 -100.430892) (xy 54.441412 -100.478442) (xy 54.399032 -100.520822)
			(xy 54.351482 -100.557309) (xy 54.299576 -100.587276) (xy 54.244203 -100.610212) (xy 54.18631 -100.625725)
			(xy 54.126888 -100.633548) (xy 54.066952 -100.633548) (xy 54.00753 -100.625725) (xy 53.949637 -100.610212)
			(xy 53.894264 -100.587276) (xy 53.842358 -100.557309) (xy 53.794808 -100.520822) (xy 53.752428 -100.478442)
			(xy 53.715941 -100.430892) (xy 53.685974 -100.378986) (xy 53.663038 -100.323613) (xy 53.647525 -100.26572)
			(xy 53.639702 -100.206298) (xy 53.639212 -100.17633) (xy 51.433984 -100.17633) (xy 51.433984 -101.976428)
			(xy 51.785012 -101.976428) (xy 51.785012 -101.112828) (xy 51.785502 -101.08286) (xy 51.793325 -101.023438)
			(xy 51.808838 -100.965545) (xy 51.831774 -100.910172) (xy 51.861741 -100.858266) (xy 51.898228 -100.810716)
			(xy 51.940608 -100.768336) (xy 51.988158 -100.731849) (xy 52.040064 -100.701882) (xy 52.095437 -100.678946)
			(xy 52.15333 -100.663433) (xy 52.212752 -100.65561) (xy 52.272688 -100.65561) (xy 52.33211 -100.663433)
			(xy 52.390003 -100.678946) (xy 52.445376 -100.701882) (xy 52.497282 -100.731849) (xy 52.542273 -100.766372)
			(xy 57.5978 -100.766372) (xy 57.601871 -100.71075) (xy 57.613997 -100.656313) (xy 57.63392 -100.604222)
			(xy 57.661216 -100.555587) (xy 57.695302 -100.511444) (xy 57.735451 -100.472735) (xy 57.780809 -100.440284)
			(xy 57.830409 -100.414783) (xy 57.883193 -100.396776) (xy 57.938036 -100.386646) (xy 57.99377 -100.384609)
			(xy 58.049207 -100.390709) (xy 58.103164 -100.404815) (xy 58.154493 -100.426627) (xy 58.202099 -100.455681)
			(xy 58.244967 -100.491356) (xy 58.282184 -100.532893) (xy 58.312957 -100.579406) (xy 58.336629 -100.629903)
			(xy 58.352697 -100.68331) (xy 58.360817 -100.738486) (xy 58.361326 -100.766372) (xy 58.360817 -100.794258)
			(xy 58.352697 -100.849434) (xy 58.336629 -100.902841) (xy 58.312957 -100.953338) (xy 58.282184 -100.999851)
			(xy 58.244967 -101.041388) (xy 58.202099 -101.077063) (xy 58.154493 -101.106117) (xy 58.103164 -101.127929)
			(xy 58.049207 -101.142035) (xy 57.99377 -101.148135) (xy 57.938036 -101.146098) (xy 57.883193 -101.135968)
			(xy 57.830409 -101.117961) (xy 57.780809 -101.09246) (xy 57.735451 -101.060009) (xy 57.695302 -101.0213)
			(xy 57.661216 -100.977157) (xy 57.63392 -100.928522) (xy 57.613997 -100.876431) (xy 57.601871 -100.821994)
			(xy 57.5978 -100.766372) (xy 52.542273 -100.766372) (xy 52.544832 -100.768336) (xy 52.587212 -100.810716)
			(xy 52.623699 -100.858266) (xy 52.653666 -100.910172) (xy 52.676602 -100.965545) (xy 52.692115 -101.023438)
			(xy 52.699938 -101.08286) (xy 52.700428 -101.112828) (xy 52.700428 -101.240082) (xy 74.293982 -101.240082)
			(xy 74.298053 -101.18446) (xy 74.310179 -101.130023) (xy 74.330102 -101.077932) (xy 74.357398 -101.029297)
			(xy 74.391484 -100.985154) (xy 74.431633 -100.946445) (xy 74.476991 -100.913994) (xy 74.526591 -100.888493)
			(xy 74.579375 -100.870486) (xy 74.634218 -100.860356) (xy 74.689952 -100.858319) (xy 74.745389 -100.864419)
			(xy 74.799346 -100.878525) (xy 74.850675 -100.900337) (xy 74.898281 -100.929391) (xy 74.941149 -100.965066)
			(xy 74.978366 -101.006603) (xy 75.009139 -101.053116) (xy 75.016889 -101.069648) (xy 75.586334 -101.069648)
			(xy 75.590405 -101.014026) (xy 75.602531 -100.959589) (xy 75.622454 -100.907498) (xy 75.64975 -100.858863)
			(xy 75.683836 -100.81472) (xy 75.723985 -100.776011) (xy 75.769343 -100.74356) (xy 75.818943 -100.718059)
			(xy 75.871727 -100.700052) (xy 75.92657 -100.689922) (xy 75.982304 -100.687885) (xy 76.037741 -100.693985)
			(xy 76.091698 -100.708091) (xy 76.143027 -100.729903) (xy 76.190633 -100.758957) (xy 76.233501 -100.794632)
			(xy 76.270718 -100.836169) (xy 76.301491 -100.882682) (xy 76.325163 -100.933179) (xy 76.341231 -100.986586)
			(xy 76.349351 -101.041762) (xy 76.34986 -101.069648) (xy 76.349351 -101.097534) (xy 76.341231 -101.15271)
			(xy 76.330058 -101.189848) (xy 96.99349 -101.189848) (xy 96.99349 -101.135352) (xy 97.001245 -101.08141)
			(xy 97.016598 -101.02912) (xy 97.039235 -100.979547) (xy 97.068696 -100.933701) (xy 97.104382 -100.892513)
			(xy 97.145565 -100.856822) (xy 97.191409 -100.827356) (xy 97.240979 -100.804713) (xy 97.293266 -100.789355)
			(xy 97.347208 -100.781593) (xy 97.374456 -100.781104) (xy 97.401825 -100.781595) (xy 97.456003 -100.789407)
			(xy 97.508506 -100.80489) (xy 97.558254 -100.827726) (xy 97.604221 -100.857445) (xy 97.625154 -100.875084)
			(xy 97.625408 -100.875338) (xy 97.632485 -100.880938) (xy 97.649409 -100.887176) (xy 97.658428 -100.88753)
			(xy 97.725484 -100.88753) (xy 97.734499 -100.887159) (xy 97.751416 -100.88092) (xy 97.758504 -100.875338)
			(xy 97.758504 -100.875084) (xy 97.758758 -100.875084) (xy 97.779693 -100.857449) (xy 97.825665 -100.827737)
			(xy 97.875412 -100.8049) (xy 97.927912 -100.789408) (xy 97.982087 -100.781579) (xy 98.009456 -100.781104)
			(xy 98.036712 -100.78154) (xy 98.090669 -100.789292) (xy 98.142974 -100.804645) (xy 98.192561 -100.827285)
			(xy 98.238422 -100.856753) (xy 98.279621 -100.892448) (xy 98.31532 -100.933643) (xy 98.344793 -100.9795)
			(xy 98.36744 -101.029085) (xy 98.382799 -101.081388) (xy 98.390557 -101.135344) (xy 98.390557 -101.189856)
			(xy 98.382799 -101.243812) (xy 98.36744 -101.296115) (xy 98.344793 -101.3457) (xy 98.31532 -101.391557)
			(xy 98.279621 -101.432752) (xy 98.238422 -101.468447) (xy 98.192561 -101.497915) (xy 98.142974 -101.520555)
			(xy 98.090669 -101.535908) (xy 98.036712 -101.54366) (xy 98.009456 -101.54412) (xy 97.982086 -101.543641)
			(xy 97.927907 -101.535829) (xy 97.875403 -101.520344) (xy 97.825656 -101.497505) (xy 97.779689 -101.467781)
			(xy 97.758758 -101.45014) (xy 97.758504 -101.449886) (xy 97.751422 -101.444293) (xy 97.734502 -101.438051)
			(xy 97.725484 -101.437694) (xy 97.658428 -101.437694) (xy 97.649413 -101.438066) (xy 97.632496 -101.444303)
			(xy 97.625408 -101.449886) (xy 97.625408 -101.45014) (xy 97.625154 -101.45014) (xy 97.604218 -101.467774)
			(xy 97.558246 -101.497485) (xy 97.508499 -101.520322) (xy 97.455999 -101.535814) (xy 97.401825 -101.543645)
			(xy 97.374456 -101.54412) (xy 97.347208 -101.543607) (xy 97.293266 -101.535845) (xy 97.240979 -101.520487)
			(xy 97.191409 -101.497844) (xy 97.145565 -101.468378) (xy 97.104382 -101.432687) (xy 97.068696 -101.391499)
			(xy 97.039235 -101.345653) (xy 97.016598 -101.29608) (xy 97.001245 -101.24379) (xy 96.99349 -101.189848)
			(xy 76.330058 -101.189848) (xy 76.325163 -101.206117) (xy 76.301491 -101.256614) (xy 76.270718 -101.303127)
			(xy 76.233501 -101.344664) (xy 76.190633 -101.380339) (xy 76.143027 -101.409393) (xy 76.091698 -101.431205)
			(xy 76.037741 -101.445311) (xy 75.982304 -101.451411) (xy 75.92657 -101.449374) (xy 75.871727 -101.439244)
			(xy 75.818943 -101.421237) (xy 75.769343 -101.395736) (xy 75.723985 -101.363285) (xy 75.683836 -101.324576)
			(xy 75.64975 -101.280433) (xy 75.622454 -101.231798) (xy 75.602531 -101.179707) (xy 75.590405 -101.12527)
			(xy 75.586334 -101.069648) (xy 75.016889 -101.069648) (xy 75.032811 -101.103613) (xy 75.048879 -101.15702)
			(xy 75.056999 -101.212196) (xy 75.057508 -101.240082) (xy 75.056999 -101.267968) (xy 75.048879 -101.323144)
			(xy 75.032811 -101.376551) (xy 75.009139 -101.427048) (xy 74.978366 -101.473561) (xy 74.941149 -101.515098)
			(xy 74.898281 -101.550773) (xy 74.851748 -101.579172) (xy 87.770714 -101.579172) (xy 87.774785 -101.52355)
			(xy 87.786911 -101.469113) (xy 87.806834 -101.417022) (xy 87.83413 -101.368387) (xy 87.868216 -101.324244)
			(xy 87.908365 -101.285535) (xy 87.953723 -101.253084) (xy 88.003323 -101.227583) (xy 88.056107 -101.209576)
			(xy 88.11095 -101.199446) (xy 88.166684 -101.197409) (xy 88.222121 -101.203509) (xy 88.276078 -101.217615)
			(xy 88.327407 -101.239427) (xy 88.375013 -101.268481) (xy 88.417881 -101.304156) (xy 88.455098 -101.345693)
			(xy 88.485871 -101.392206) (xy 88.509543 -101.442703) (xy 88.525611 -101.49611) (xy 88.533731 -101.551286)
			(xy 88.53424 -101.579172) (xy 88.533731 -101.607058) (xy 88.525611 -101.662234) (xy 88.509543 -101.715641)
			(xy 88.485871 -101.766138) (xy 88.455098 -101.812651) (xy 88.417881 -101.854188) (xy 88.397963 -101.870764)
			(xy 93.23908 -101.870764) (xy 93.243151 -101.815142) (xy 93.255277 -101.760705) (xy 93.2752 -101.708614)
			(xy 93.302496 -101.659979) (xy 93.336582 -101.615836) (xy 93.376731 -101.577127) (xy 93.422089 -101.544676)
			(xy 93.471689 -101.519175) (xy 93.524473 -101.501168) (xy 93.579316 -101.491038) (xy 93.63505 -101.489001)
			(xy 93.690487 -101.495101) (xy 93.744444 -101.509207) (xy 93.795773 -101.531019) (xy 93.843379 -101.560073)
			(xy 93.886247 -101.595748) (xy 93.923464 -101.637285) (xy 93.954237 -101.683798) (xy 93.977909 -101.734295)
			(xy 93.993977 -101.787702) (xy 94.002097 -101.842878) (xy 94.002606 -101.870764) (xy 94.002097 -101.89865)
			(xy 93.993977 -101.953826) (xy 93.977909 -102.007233) (xy 93.954237 -102.05773) (xy 93.923464 -102.104243)
			(xy 93.899978 -102.130455) (xy 96.543029 -102.130455) (xy 96.543029 -102.075945) (xy 96.550787 -102.021989)
			(xy 96.566145 -101.969686) (xy 96.58879 -101.920102) (xy 96.618261 -101.874245) (xy 96.653959 -101.833049)
			(xy 96.695156 -101.797353) (xy 96.741014 -101.767883) (xy 96.790599 -101.74524) (xy 96.842902 -101.729884)
			(xy 96.896859 -101.722128) (xy 96.924114 -101.721666) (xy 96.951485 -101.722108) (xy 97.005666 -101.729929)
			(xy 97.05817 -101.745423) (xy 97.107917 -101.76827) (xy 97.153882 -101.798001) (xy 97.174812 -101.815646)
			(xy 97.175066 -101.8159) (xy 97.182158 -101.821478) (xy 97.199071 -101.82773) (xy 97.208086 -101.828092)
			(xy 97.275142 -101.828092) (xy 97.284156 -101.827709) (xy 97.301073 -101.82148) (xy 97.308162 -101.8159)
			(xy 97.308162 -101.815646) (xy 97.308416 -101.815646) (xy 97.329375 -101.79804) (xy 97.37534 -101.768322)
			(xy 97.42508 -101.745479) (xy 97.477575 -101.72998) (xy 97.531747 -101.722144) (xy 97.559114 -101.721666)
			(xy 97.586363 -101.722205) (xy 97.640305 -101.729963) (xy 97.692595 -101.745318) (xy 97.742167 -101.767958)
			(xy 97.788012 -101.797423) (xy 97.829198 -101.833112) (xy 97.864885 -101.874299) (xy 97.894348 -101.920146)
			(xy 97.916987 -101.969719) (xy 97.93234 -102.022009) (xy 97.940096 -102.075951) (xy 97.940096 -102.130449)
			(xy 97.93234 -102.184391) (xy 97.916987 -102.236681) (xy 97.894348 -102.286254) (xy 97.864885 -102.332101)
			(xy 97.829198 -102.373288) (xy 97.788012 -102.408977) (xy 97.742167 -102.438442) (xy 97.692595 -102.461082)
			(xy 97.640305 -102.476437) (xy 97.586363 -102.484195) (xy 97.559114 -102.484682) (xy 97.531744 -102.484212)
			(xy 97.477565 -102.476396) (xy 97.425062 -102.460908) (xy 97.375315 -102.438067) (xy 97.329348 -102.408343)
			(xy 97.308416 -102.390702) (xy 97.308162 -102.390448) (xy 97.301066 -102.384875) (xy 97.284156 -102.378621)
			(xy 97.275142 -102.378256) (xy 97.208086 -102.378256) (xy 97.199067 -102.378594) (xy 97.18215 -102.384854)
			(xy 97.175066 -102.390448) (xy 97.175066 -102.390702) (xy 97.174812 -102.390702) (xy 97.153886 -102.408349)
			(xy 97.107912 -102.43806) (xy 97.058163 -102.460894) (xy 97.005661 -102.476383) (xy 96.951484 -102.484209)
			(xy 96.924114 -102.484682) (xy 96.896859 -102.484272) (xy 96.842902 -102.476516) (xy 96.790599 -102.46116)
			(xy 96.741014 -102.438517) (xy 96.695156 -102.409047) (xy 96.653959 -102.373351) (xy 96.618261 -102.332155)
			(xy 96.58879 -102.286298) (xy 96.566145 -102.236714) (xy 96.550787 -102.184411) (xy 96.543029 -102.130455)
			(xy 93.899978 -102.130455) (xy 93.886247 -102.14578) (xy 93.843379 -102.181455) (xy 93.795773 -102.210509)
			(xy 93.744444 -102.232321) (xy 93.690487 -102.246427) (xy 93.63505 -102.252527) (xy 93.579316 -102.25049)
			(xy 93.524473 -102.24036) (xy 93.471689 -102.222353) (xy 93.422089 -102.196852) (xy 93.376731 -102.164401)
			(xy 93.336582 -102.125692) (xy 93.302496 -102.081549) (xy 93.2752 -102.032914) (xy 93.255277 -101.980823)
			(xy 93.243151 -101.926386) (xy 93.23908 -101.870764) (xy 88.397963 -101.870764) (xy 88.375013 -101.889863)
			(xy 88.327407 -101.918917) (xy 88.276078 -101.940729) (xy 88.222121 -101.954835) (xy 88.166684 -101.960935)
			(xy 88.11095 -101.958898) (xy 88.056107 -101.948768) (xy 88.003323 -101.930761) (xy 87.953723 -101.90526)
			(xy 87.908365 -101.872809) (xy 87.868216 -101.8341) (xy 87.83413 -101.789957) (xy 87.806834 -101.741322)
			(xy 87.786911 -101.689231) (xy 87.774785 -101.634794) (xy 87.770714 -101.579172) (xy 74.851748 -101.579172)
			(xy 74.850675 -101.579827) (xy 74.799346 -101.601639) (xy 74.745389 -101.615745) (xy 74.689952 -101.621845)
			(xy 74.634218 -101.619808) (xy 74.579375 -101.609678) (xy 74.526591 -101.591671) (xy 74.476991 -101.56617)
			(xy 74.431633 -101.533719) (xy 74.391484 -101.49501) (xy 74.357398 -101.450867) (xy 74.330102 -101.402232)
			(xy 74.310179 -101.350141) (xy 74.298053 -101.295704) (xy 74.293982 -101.240082) (xy 52.700428 -101.240082)
			(xy 52.700428 -101.976428) (xy 52.699938 -102.006396) (xy 52.692115 -102.065818) (xy 52.676602 -102.123711)
			(xy 52.653666 -102.179084) (xy 52.623699 -102.23099) (xy 52.587212 -102.27854) (xy 52.544832 -102.32092)
			(xy 52.497282 -102.357407) (xy 52.445376 -102.387374) (xy 52.390003 -102.41031) (xy 52.33211 -102.425823)
			(xy 52.272688 -102.433646) (xy 52.212752 -102.433646) (xy 52.15333 -102.425823) (xy 52.095437 -102.41031)
			(xy 52.040064 -102.387374) (xy 51.988158 -102.357407) (xy 51.940608 -102.32092) (xy 51.898228 -102.27854)
			(xy 51.861741 -102.23099) (xy 51.831774 -102.179084) (xy 51.808838 -102.123711) (xy 51.793325 -102.065818)
			(xy 51.785502 -102.006396) (xy 51.785012 -101.976428) (xy 51.433984 -101.976428) (xy 51.433984 -103.776272)
			(xy 53.639212 -103.776272) (xy 53.639212 -102.912672) (xy 53.639702 -102.882704) (xy 53.647525 -102.823282)
			(xy 53.663038 -102.765389) (xy 53.685974 -102.710016) (xy 53.715941 -102.65811) (xy 53.752428 -102.61056)
			(xy 53.794808 -102.56818) (xy 53.842358 -102.531693) (xy 53.894264 -102.501726) (xy 53.949637 -102.47879)
			(xy 54.00753 -102.463277) (xy 54.066952 -102.455454) (xy 54.126888 -102.455454) (xy 54.18631 -102.463277)
			(xy 54.244203 -102.47879) (xy 54.268852 -102.489) (xy 74.801982 -102.489) (xy 74.806053 -102.433378)
			(xy 74.818179 -102.378941) (xy 74.838102 -102.32685) (xy 74.865398 -102.278215) (xy 74.899484 -102.234072)
			(xy 74.939633 -102.195363) (xy 74.984991 -102.162912) (xy 75.034591 -102.137411) (xy 75.087375 -102.119404)
			(xy 75.142218 -102.109274) (xy 75.197952 -102.107237) (xy 75.253389 -102.113337) (xy 75.307346 -102.127443)
			(xy 75.358675 -102.149255) (xy 75.406281 -102.178309) (xy 75.449149 -102.213984) (xy 75.486366 -102.255521)
			(xy 75.517139 -102.302034) (xy 75.540811 -102.352531) (xy 75.556879 -102.405938) (xy 75.564999 -102.461114)
			(xy 75.565508 -102.489) (xy 75.564999 -102.516886) (xy 75.556879 -102.572062) (xy 75.540811 -102.625469)
			(xy 75.517139 -102.675966) (xy 75.486366 -102.722479) (xy 75.449149 -102.764016) (xy 75.406281 -102.799691)
			(xy 75.358675 -102.828745) (xy 75.307346 -102.850557) (xy 75.253389 -102.864663) (xy 75.197952 -102.870763)
			(xy 75.142218 -102.868726) (xy 75.087375 -102.858596) (xy 75.034591 -102.840589) (xy 74.984991 -102.815088)
			(xy 74.939633 -102.782637) (xy 74.899484 -102.743928) (xy 74.865398 -102.699785) (xy 74.838102 -102.65115)
			(xy 74.818179 -102.599059) (xy 74.806053 -102.544622) (xy 74.801982 -102.489) (xy 54.268852 -102.489)
			(xy 54.299576 -102.501726) (xy 54.351482 -102.531693) (xy 54.399032 -102.56818) (xy 54.441412 -102.61056)
			(xy 54.477899 -102.65811) (xy 54.507866 -102.710016) (xy 54.530802 -102.765389) (xy 54.546315 -102.823282)
			(xy 54.554138 -102.882704) (xy 54.554628 -102.912672) (xy 54.554628 -103.13924) (xy 89.507058 -103.13924)
			(xy 89.511129 -103.083618) (xy 89.523255 -103.029181) (xy 89.543178 -102.97709) (xy 89.570474 -102.928455)
			(xy 89.60456 -102.884312) (xy 89.644709 -102.845603) (xy 89.690067 -102.813152) (xy 89.739667 -102.787651)
			(xy 89.792451 -102.769644) (xy 89.847294 -102.759514) (xy 89.903028 -102.757477) (xy 89.958465 -102.763577)
			(xy 90.012422 -102.777683) (xy 90.063751 -102.799495) (xy 90.111357 -102.828549) (xy 90.154225 -102.864224)
			(xy 90.191442 -102.905761) (xy 90.222215 -102.952274) (xy 90.245887 -103.002771) (xy 90.261955 -103.056178)
			(xy 90.270075 -103.111354) (xy 90.270584 -103.13924) (xy 90.270075 -103.167126) (xy 90.261955 -103.222302)
			(xy 90.245887 -103.275709) (xy 90.222215 -103.326206) (xy 90.191442 -103.372719) (xy 90.154225 -103.414256)
			(xy 90.111357 -103.449931) (xy 90.063751 -103.478985) (xy 90.012422 -103.500797) (xy 89.958465 -103.514903)
			(xy 89.903028 -103.521003) (xy 89.847294 -103.518966) (xy 89.792451 -103.508836) (xy 89.739667 -103.490829)
			(xy 89.690067 -103.465328) (xy 89.644709 -103.432877) (xy 89.60456 -103.394168) (xy 89.570474 -103.350025)
			(xy 89.543178 -103.30139) (xy 89.523255 -103.249299) (xy 89.511129 -103.194862) (xy 89.507058 -103.13924)
			(xy 54.554628 -103.13924) (xy 54.554628 -103.776272) (xy 54.554138 -103.80624) (xy 54.546315 -103.865662)
			(xy 54.540865 -103.886) (xy 75.309982 -103.886) (xy 75.314053 -103.830378) (xy 75.326179 -103.775941)
			(xy 75.346102 -103.72385) (xy 75.373398 -103.675215) (xy 75.407484 -103.631072) (xy 75.447633 -103.592363)
			(xy 75.492991 -103.559912) (xy 75.542591 -103.534411) (xy 75.595375 -103.516404) (xy 75.650218 -103.506274)
			(xy 75.705952 -103.504237) (xy 75.761389 -103.510337) (xy 75.815346 -103.524443) (xy 75.866675 -103.546255)
			(xy 75.914281 -103.575309) (xy 75.957149 -103.610984) (xy 75.994366 -103.652521) (xy 76.025139 -103.699034)
			(xy 76.048811 -103.749531) (xy 76.064879 -103.802938) (xy 76.072999 -103.858114) (xy 76.073508 -103.886)
			(xy 76.072999 -103.913886) (xy 76.064879 -103.969062) (xy 76.048811 -104.022469) (xy 76.025139 -104.072966)
			(xy 75.994366 -104.119479) (xy 75.957149 -104.161016) (xy 75.914281 -104.196691) (xy 75.866675 -104.225745)
			(xy 75.815346 -104.247557) (xy 75.761389 -104.261663) (xy 75.705952 -104.267763) (xy 75.650218 -104.265726)
			(xy 75.595375 -104.255596) (xy 75.542591 -104.237589) (xy 75.492991 -104.212088) (xy 75.447633 -104.179637)
			(xy 75.407484 -104.140928) (xy 75.373398 -104.096785) (xy 75.346102 -104.04815) (xy 75.326179 -103.996059)
			(xy 75.314053 -103.941622) (xy 75.309982 -103.886) (xy 54.540865 -103.886) (xy 54.530802 -103.923555)
			(xy 54.507866 -103.978928) (xy 54.477899 -104.030834) (xy 54.441412 -104.078384) (xy 54.399032 -104.120764)
			(xy 54.351482 -104.157251) (xy 54.299576 -104.187218) (xy 54.244203 -104.210154) (xy 54.18631 -104.225667)
			(xy 54.126888 -104.23349) (xy 54.066952 -104.23349) (xy 54.00753 -104.225667) (xy 53.949637 -104.210154)
			(xy 53.894264 -104.187218) (xy 53.842358 -104.157251) (xy 53.794808 -104.120764) (xy 53.752428 -104.078384)
			(xy 53.715941 -104.030834) (xy 53.685974 -103.978928) (xy 53.663038 -103.923555) (xy 53.647525 -103.865662)
			(xy 53.639702 -103.80624) (xy 53.639212 -103.776272) (xy 51.433984 -103.776272) (xy 51.433984 -105.57637)
			(xy 51.785012 -105.57637) (xy 51.785012 -104.71277) (xy 51.785502 -104.682802) (xy 51.793325 -104.62338)
			(xy 51.808838 -104.565487) (xy 51.831774 -104.510114) (xy 51.861741 -104.458208) (xy 51.898228 -104.410658)
			(xy 51.940608 -104.368278) (xy 51.988158 -104.331791) (xy 52.040064 -104.301824) (xy 52.095437 -104.278888)
			(xy 52.15333 -104.263375) (xy 52.212752 -104.255552) (xy 52.272688 -104.255552) (xy 52.33211 -104.263375)
			(xy 52.390003 -104.278888) (xy 52.445376 -104.301824) (xy 52.497282 -104.331791) (xy 52.544832 -104.368278)
			(xy 52.587212 -104.410658) (xy 52.623699 -104.458208) (xy 52.653666 -104.510114) (xy 52.676602 -104.565487)
			(xy 52.692115 -104.62338) (xy 52.698901 -104.674924) (xy 88.559384 -104.674924) (xy 88.563455 -104.619302)
			(xy 88.575581 -104.564865) (xy 88.595504 -104.512774) (xy 88.6228 -104.464139) (xy 88.656886 -104.419996)
			(xy 88.697035 -104.381287) (xy 88.742393 -104.348836) (xy 88.791993 -104.323335) (xy 88.844777 -104.305328)
			(xy 88.89962 -104.295198) (xy 88.955354 -104.293161) (xy 89.010791 -104.299261) (xy 89.064748 -104.313367)
			(xy 89.116077 -104.335179) (xy 89.163683 -104.364233) (xy 89.206551 -104.399908) (xy 89.243768 -104.441445)
			(xy 89.274541 -104.487958) (xy 89.298213 -104.538455) (xy 89.314281 -104.591862) (xy 89.322401 -104.647038)
			(xy 89.32291 -104.674924) (xy 89.322401 -104.70281) (xy 89.314281 -104.757986) (xy 89.298213 -104.811393)
			(xy 89.274541 -104.86189) (xy 89.243768 -104.908403) (xy 89.206551 -104.94994) (xy 89.163683 -104.985615)
			(xy 89.116077 -105.014669) (xy 89.064748 -105.036481) (xy 89.010791 -105.050587) (xy 88.955354 -105.056687)
			(xy 88.89962 -105.05465) (xy 88.844777 -105.04452) (xy 88.791993 -105.026513) (xy 88.742393 -105.001012)
			(xy 88.697035 -104.968561) (xy 88.656886 -104.929852) (xy 88.6228 -104.885709) (xy 88.595504 -104.837074)
			(xy 88.575581 -104.784983) (xy 88.563455 -104.730546) (xy 88.559384 -104.674924) (xy 52.698901 -104.674924)
			(xy 52.699938 -104.682802) (xy 52.700428 -104.71277) (xy 52.700428 -105.57637) (xy 52.699938 -105.606338)
			(xy 52.692115 -105.66576) (xy 52.676602 -105.723653) (xy 52.653666 -105.779026) (xy 52.623699 -105.830932)
			(xy 52.587212 -105.878482) (xy 52.544832 -105.920862) (xy 52.497282 -105.957349) (xy 52.445376 -105.987316)
			(xy 52.390003 -106.010252) (xy 52.33211 -106.025765) (xy 52.272688 -106.033588) (xy 52.212752 -106.033588)
			(xy 52.15333 -106.025765) (xy 52.095437 -106.010252) (xy 52.040064 -105.987316) (xy 51.988158 -105.957349)
			(xy 51.940608 -105.920862) (xy 51.898228 -105.878482) (xy 51.861741 -105.830932) (xy 51.831774 -105.779026)
			(xy 51.808838 -105.723653) (xy 51.793325 -105.66576) (xy 51.785502 -105.606338) (xy 51.785012 -105.57637)
			(xy 51.433984 -105.57637) (xy 51.433984 -107.376214) (xy 53.639212 -107.376214) (xy 53.639212 -106.512614)
			(xy 53.639702 -106.482646) (xy 53.647525 -106.423224) (xy 53.663038 -106.365331) (xy 53.685974 -106.309958)
			(xy 53.715941 -106.258052) (xy 53.752428 -106.210502) (xy 53.794808 -106.168122) (xy 53.842358 -106.131635)
			(xy 53.894264 -106.101668) (xy 53.949637 -106.078732) (xy 54.00753 -106.063219) (xy 54.066952 -106.055396)
			(xy 54.126888 -106.055396) (xy 54.18631 -106.063219) (xy 54.244203 -106.078732) (xy 54.299576 -106.101668)
			(xy 54.351482 -106.131635) (xy 54.399032 -106.168122) (xy 54.441412 -106.210502) (xy 54.477899 -106.258052)
			(xy 54.507866 -106.309958) (xy 54.530802 -106.365331) (xy 54.546315 -106.423224) (xy 54.554138 -106.482646)
			(xy 54.554628 -106.512614) (xy 54.554628 -107.210352) (xy 64.762632 -107.210352) (xy 64.766703 -107.15473)
			(xy 64.778829 -107.100293) (xy 64.798752 -107.048202) (xy 64.826048 -106.999567) (xy 64.860134 -106.955424)
			(xy 64.900283 -106.916715) (xy 64.945641 -106.884264) (xy 64.995241 -106.858763) (xy 65.048025 -106.840756)
			(xy 65.102868 -106.830626) (xy 65.158602 -106.828589) (xy 65.214039 -106.834689) (xy 65.267996 -106.848795)
			(xy 65.319325 -106.870607) (xy 65.366931 -106.899661) (xy 65.409799 -106.935336) (xy 65.447016 -106.976873)
			(xy 65.477789 -107.023386) (xy 65.501461 -107.073883) (xy 65.517529 -107.12729) (xy 65.525649 -107.182466)
			(xy 65.526158 -107.210352) (xy 85.74278 -107.210352) (xy 85.74328 -107.181612) (xy 85.751909 -107.124784)
			(xy 85.768965 -107.069893) (xy 85.794062 -107.018182) (xy 85.826631 -106.97082) (xy 85.845904 -106.949494)
			(xy 85.852508 -106.942636) (xy 85.85962 -106.924602) (xy 85.85962 -106.835702) (xy 85.852508 -106.817668)
			(xy 85.845904 -106.81081) (xy 85.826587 -106.789524) (xy 85.794025 -106.742154) (xy 85.768937 -106.690435)
			(xy 85.751891 -106.635539) (xy 85.743274 -106.578706) (xy 85.743279 -106.521224) (xy 85.751907 -106.464393)
			(xy 85.768963 -106.409499) (xy 85.79406 -106.357785) (xy 85.826631 -106.310421) (xy 85.845904 -106.289094)
			(xy 85.852508 -106.282236) (xy 85.85962 -106.264202) (xy 85.85962 -106.175302) (xy 85.852508 -106.157268)
			(xy 85.845904 -106.15041) (xy 85.826622 -106.129093) (xy 85.794055 -106.081729) (xy 85.768963 -106.030015)
			(xy 85.751916 -105.975122) (xy 85.743298 -105.918292) (xy 85.74278 -105.889552) (xy 85.743266 -105.862301)
			(xy 85.751022 -105.808353) (xy 85.766377 -105.756058) (xy 85.789019 -105.706481) (xy 85.818485 -105.660631)
			(xy 85.854176 -105.61944) (xy 85.895367 -105.583749) (xy 85.941217 -105.554283) (xy 85.990794 -105.531641)
			(xy 86.043089 -105.516286) (xy 86.097037 -105.50853) (xy 86.151539 -105.50853) (xy 86.205487 -105.516286)
			(xy 86.257782 -105.531641) (xy 86.307359 -105.554283) (xy 86.353209 -105.583749) (xy 86.3944 -105.61944)
			(xy 86.430091 -105.660631) (xy 86.459557 -105.706481) (xy 86.482199 -105.756058) (xy 86.497554 -105.808353)
			(xy 86.50531 -105.862301) (xy 86.505796 -105.889552) (xy 86.505305 -105.918292) (xy 86.496675 -105.975121)
			(xy 86.479617 -106.030012) (xy 86.454518 -106.081723) (xy 86.421946 -106.129084) (xy 86.402672 -106.15041)
			(xy 86.396068 -106.157268) (xy 86.388956 -106.175302) (xy 86.388956 -106.264202) (xy 86.396068 -106.282236)
			(xy 86.402672 -106.289094) (xy 86.421895 -106.310462) (xy 86.454463 -106.357817) (xy 86.479557 -106.409522)
			(xy 86.496611 -106.464407) (xy 86.505238 -106.521229) (xy 86.505243 -106.578702) (xy 86.496626 -106.635525)
			(xy 86.479583 -106.690412) (xy 86.454498 -106.742122) (xy 86.421939 -106.789483) (xy 86.402672 -106.81081)
			(xy 86.396068 -106.817668) (xy 86.388956 -106.835702) (xy 86.388956 -106.924602) (xy 86.396068 -106.942636)
			(xy 86.402672 -106.949494) (xy 86.421969 -106.970798) (xy 86.454531 -107.018167) (xy 86.473954 -107.058206)
			(xy 89.573862 -107.058206) (xy 89.5744 -107.029468) (xy 89.58302 -106.972641) (xy 89.600068 -106.917751)
			(xy 89.625156 -106.866039) (xy 89.657717 -106.818676) (xy 89.676986 -106.797348) (xy 89.68359 -106.79049)
			(xy 89.690702 -106.772456) (xy 89.690702 -106.683556) (xy 89.68359 -106.665522) (xy 89.676986 -106.658664)
			(xy 89.657723 -106.637331) (xy 89.625161 -106.589969) (xy 89.600071 -106.538258) (xy 89.583023 -106.483368)
			(xy 89.5744 -106.426542) (xy 89.5744 -106.369066) (xy 89.583021 -106.31224) (xy 89.600068 -106.257351)
			(xy 89.625156 -106.205639) (xy 89.657717 -106.158276) (xy 89.676986 -106.136948) (xy 89.68359 -106.13009)
			(xy 89.690702 -106.112056) (xy 89.690702 -106.023156) (xy 89.68359 -106.005122) (xy 89.676986 -105.998264)
			(xy 89.657726 -105.976927) (xy 89.625156 -105.929569) (xy 89.600061 -105.87786) (xy 89.583008 -105.822971)
			(xy 89.574384 -105.766145) (xy 89.573862 -105.737406) (xy 89.574348 -105.710155) (xy 89.582104 -105.656207)
			(xy 89.597459 -105.603912) (xy 89.620101 -105.554335) (xy 89.649567 -105.508485) (xy 89.685258 -105.467294)
			(xy 89.726449 -105.431603) (xy 89.772299 -105.402137) (xy 89.821876 -105.379495) (xy 89.874171 -105.36414)
			(xy 89.928119 -105.356384) (xy 89.982621 -105.356384) (xy 90.036569 -105.36414) (xy 90.088864 -105.379495)
			(xy 90.138441 -105.402137) (xy 90.184291 -105.431603) (xy 90.225482 -105.467294) (xy 90.261173 -105.508485)
			(xy 90.290639 -105.554335) (xy 90.313281 -105.603912) (xy 90.328636 -105.656207) (xy 90.336392 -105.710155)
			(xy 90.336878 -105.737406) (xy 90.336337 -105.766144) (xy 90.327715 -105.82297) (xy 90.310668 -105.877859)
			(xy 90.285581 -105.929571) (xy 90.253022 -105.976936) (xy 90.233754 -105.998264) (xy 90.22715 -106.005122)
			(xy 90.220038 -106.023156) (xy 90.220038 -106.112056) (xy 90.22715 -106.13009) (xy 90.233754 -106.136948)
			(xy 90.253032 -106.158269) (xy 90.285599 -106.205632) (xy 90.310691 -106.257344) (xy 90.327742 -106.312236)
			(xy 90.336365 -106.369065) (xy 90.336364 -106.426544) (xy 90.32774 -106.483372) (xy 90.310688 -106.538264)
			(xy 90.285594 -106.589976) (xy 90.253026 -106.637338) (xy 90.233754 -106.658664) (xy 90.22715 -106.665522)
			(xy 90.220038 -106.683556) (xy 90.220038 -106.772456) (xy 90.22715 -106.79049) (xy 90.233754 -106.797348)
			(xy 90.253026 -106.818674) (xy 90.285593 -106.866036) (xy 90.310685 -106.917748) (xy 90.327735 -106.972639)
			(xy 90.336357 -107.029467) (xy 90.336878 -107.058206) (xy 90.336392 -107.085457) (xy 90.328636 -107.139405)
			(xy 90.313281 -107.1917) (xy 90.290639 -107.241277) (xy 90.261173 -107.287127) (xy 90.225482 -107.328318)
			(xy 90.184291 -107.364009) (xy 90.138441 -107.393475) (xy 90.088864 -107.416117) (xy 90.036569 -107.431472)
			(xy 89.982621 -107.439228) (xy 89.928119 -107.439228) (xy 89.874171 -107.431472) (xy 89.821876 -107.416117)
			(xy 89.772299 -107.393475) (xy 89.726449 -107.364009) (xy 89.685258 -107.328318) (xy 89.649567 -107.287127)
			(xy 89.620101 -107.241277) (xy 89.597459 -107.1917) (xy 89.582104 -107.139405) (xy 89.574348 -107.085457)
			(xy 89.573862 -107.058206) (xy 86.473954 -107.058206) (xy 86.479619 -107.069884) (xy 86.496663 -107.12478)
			(xy 86.505279 -107.181611) (xy 86.505796 -107.210352) (xy 86.50531 -107.237603) (xy 86.497554 -107.291551)
			(xy 86.482199 -107.343846) (xy 86.459557 -107.393423) (xy 86.430091 -107.439273) (xy 86.3944 -107.480464)
			(xy 86.353209 -107.516155) (xy 86.307359 -107.545621) (xy 86.257782 -107.568263) (xy 86.205487 -107.583618)
			(xy 86.151539 -107.591374) (xy 86.097037 -107.591374) (xy 86.043089 -107.583618) (xy 85.990794 -107.568263)
			(xy 85.941217 -107.545621) (xy 85.895367 -107.516155) (xy 85.854176 -107.480464) (xy 85.818485 -107.439273)
			(xy 85.789019 -107.393423) (xy 85.766377 -107.343846) (xy 85.751022 -107.291551) (xy 85.743266 -107.237603)
			(xy 85.74278 -107.210352) (xy 65.526158 -107.210352) (xy 65.525649 -107.238238) (xy 65.517529 -107.293414)
			(xy 65.501461 -107.346821) (xy 65.477789 -107.397318) (xy 65.447016 -107.443831) (xy 65.409799 -107.485368)
			(xy 65.366931 -107.521043) (xy 65.319325 -107.550097) (xy 65.267996 -107.571909) (xy 65.214039 -107.586015)
			(xy 65.158602 -107.592115) (xy 65.102868 -107.590078) (xy 65.048025 -107.579948) (xy 64.995241 -107.561941)
			(xy 64.945641 -107.53644) (xy 64.900283 -107.503989) (xy 64.860134 -107.46528) (xy 64.826048 -107.421137)
			(xy 64.798752 -107.372502) (xy 64.778829 -107.320411) (xy 64.766703 -107.265974) (xy 64.762632 -107.210352)
			(xy 54.554628 -107.210352) (xy 54.554628 -107.376214) (xy 54.554138 -107.406182) (xy 54.546315 -107.465604)
			(xy 54.530802 -107.523497) (xy 54.507866 -107.57887) (xy 54.477899 -107.630776) (xy 54.441412 -107.678326)
			(xy 54.399032 -107.720706) (xy 54.351482 -107.757193) (xy 54.299576 -107.78716) (xy 54.244203 -107.810096)
			(xy 54.18631 -107.825609) (xy 54.126888 -107.833432) (xy 54.066952 -107.833432) (xy 54.00753 -107.825609)
			(xy 53.949637 -107.810096) (xy 53.894264 -107.78716) (xy 53.842358 -107.757193) (xy 53.794808 -107.720706)
			(xy 53.752428 -107.678326) (xy 53.715941 -107.630776) (xy 53.685974 -107.57887) (xy 53.663038 -107.523497)
			(xy 53.647525 -107.465604) (xy 53.639702 -107.406182) (xy 53.639212 -107.376214) (xy 51.433984 -107.376214)
			(xy 51.433984 -109.176312) (xy 51.785012 -109.176312) (xy 51.785012 -108.312712) (xy 51.785502 -108.282744)
			(xy 51.793325 -108.223322) (xy 51.808838 -108.165429) (xy 51.831774 -108.110056) (xy 51.861741 -108.05815)
			(xy 51.898228 -108.0106) (xy 51.940608 -107.96822) (xy 51.988158 -107.931733) (xy 52.040064 -107.901766)
			(xy 52.095437 -107.87883) (xy 52.15333 -107.863317) (xy 52.212752 -107.855494) (xy 52.272688 -107.855494)
			(xy 52.33211 -107.863317) (xy 52.390003 -107.87883) (xy 52.445376 -107.901766) (xy 52.497282 -107.931733)
			(xy 52.544832 -107.96822) (xy 52.587212 -108.0106) (xy 52.623699 -108.05815) (xy 52.653666 -108.110056)
			(xy 52.676602 -108.165429) (xy 52.692115 -108.223322) (xy 52.699938 -108.282744) (xy 52.700428 -108.312712)
			(xy 52.700428 -108.379006) (xy 90.462862 -108.379006) (xy 90.4634 -108.350268) (xy 90.47202 -108.293441)
			(xy 90.489068 -108.238551) (xy 90.514156 -108.186839) (xy 90.546717 -108.139476) (xy 90.565986 -108.118148)
			(xy 90.57259 -108.11129) (xy 90.579702 -108.093256) (xy 90.579702 -108.004356) (xy 90.57259 -107.986322)
			(xy 90.565986 -107.979464) (xy 90.546723 -107.958131) (xy 90.514161 -107.910769) (xy 90.489071 -107.859058)
			(xy 90.472023 -107.804168) (xy 90.4634 -107.747342) (xy 90.4634 -107.689866) (xy 90.472021 -107.63304)
			(xy 90.489068 -107.578151) (xy 90.514156 -107.526439) (xy 90.546717 -107.479076) (xy 90.565986 -107.457748)
			(xy 90.57259 -107.45089) (xy 90.579702 -107.432856) (xy 90.579702 -107.343956) (xy 90.57259 -107.325922)
			(xy 90.565986 -107.319064) (xy 90.546723 -107.297731) (xy 90.514161 -107.250369) (xy 90.489071 -107.198658)
			(xy 90.472023 -107.143768) (xy 90.4634 -107.086942) (xy 90.4634 -107.029466) (xy 90.472021 -106.97264)
			(xy 90.489068 -106.917751) (xy 90.514156 -106.866039) (xy 90.546717 -106.818676) (xy 90.565986 -106.797348)
			(xy 90.57259 -106.79049) (xy 90.579702 -106.772456) (xy 90.579702 -106.683556) (xy 90.57259 -106.665522)
			(xy 90.565986 -106.658664) (xy 90.546723 -106.637331) (xy 90.514161 -106.589969) (xy 90.489071 -106.538258)
			(xy 90.472023 -106.483368) (xy 90.4634 -106.426542) (xy 90.4634 -106.369066) (xy 90.472021 -106.31224)
			(xy 90.489068 -106.257351) (xy 90.514156 -106.205639) (xy 90.546717 -106.158276) (xy 90.565986 -106.136948)
			(xy 90.57259 -106.13009) (xy 90.579702 -106.112056) (xy 90.579702 -106.023156) (xy 90.57259 -106.005122)
			(xy 90.565986 -105.998264) (xy 90.546723 -105.976931) (xy 90.514161 -105.929569) (xy 90.489071 -105.877858)
			(xy 90.472023 -105.822968) (xy 90.4634 -105.766142) (xy 90.4634 -105.708666) (xy 90.472021 -105.65184)
			(xy 90.489068 -105.596951) (xy 90.514156 -105.545239) (xy 90.546717 -105.497876) (xy 90.565986 -105.476548)
			(xy 90.57259 -105.46969) (xy 90.579702 -105.451656) (xy 90.579702 -105.362756) (xy 90.57259 -105.344722)
			(xy 90.565986 -105.337864) (xy 90.546723 -105.316531) (xy 90.514161 -105.269169) (xy 90.489071 -105.217458)
			(xy 90.472023 -105.162568) (xy 90.4634 -105.105742) (xy 90.4634 -105.048266) (xy 90.472021 -104.99144)
			(xy 90.489068 -104.936551) (xy 90.514156 -104.884839) (xy 90.546717 -104.837476) (xy 90.565986 -104.816148)
			(xy 90.57259 -104.80929) (xy 90.579702 -104.791256) (xy 90.579702 -104.702356) (xy 90.57259 -104.684322)
			(xy 90.565986 -104.677464) (xy 90.546723 -104.656131) (xy 90.514161 -104.608769) (xy 90.489071 -104.557058)
			(xy 90.472023 -104.502168) (xy 90.4634 -104.445342) (xy 90.4634 -104.387866) (xy 90.472021 -104.33104)
			(xy 90.489068 -104.276151) (xy 90.514156 -104.224439) (xy 90.546717 -104.177076) (xy 90.565986 -104.155748)
			(xy 90.57259 -104.14889) (xy 90.579702 -104.130856) (xy 90.579702 -104.041956) (xy 90.57259 -104.023922)
			(xy 90.565986 -104.017064) (xy 90.546723 -103.995731) (xy 90.514161 -103.948369) (xy 90.489071 -103.896658)
			(xy 90.472023 -103.841768) (xy 90.4634 -103.784942) (xy 90.4634 -103.727466) (xy 90.472021 -103.67064)
			(xy 90.489068 -103.615751) (xy 90.514156 -103.564039) (xy 90.546717 -103.516676) (xy 90.565986 -103.495348)
			(xy 90.57259 -103.48849) (xy 90.579702 -103.470456) (xy 90.579702 -103.381556) (xy 90.57259 -103.363522)
			(xy 90.565986 -103.356664) (xy 90.546726 -103.335327) (xy 90.514156 -103.287969) (xy 90.489061 -103.23626)
			(xy 90.472008 -103.181371) (xy 90.463384 -103.124545) (xy 90.462862 -103.095806) (xy 90.463323 -103.068599)
			(xy 90.471046 -103.014737) (xy 90.486351 -102.962521) (xy 90.508926 -102.913012) (xy 90.538312 -102.867217)
			(xy 90.573912 -102.826066) (xy 90.615003 -102.790397) (xy 90.637614 -102.775258) (xy 90.645996 -102.769924)
			(xy 90.657172 -102.753668) (xy 90.67546 -102.674674) (xy 90.67726 -102.665044) (xy 90.674266 -102.645705)
			(xy 90.669618 -102.637082) (xy 90.669364 -102.637082) (xy 90.669364 -102.636574) (xy 90.656155 -102.614065)
			(xy 90.635301 -102.566222) (xy 90.621152 -102.515987) (xy 90.613969 -102.464294) (xy 90.613484 -102.4382)
			(xy 90.61397 -102.410949) (xy 90.621726 -102.357001) (xy 90.637081 -102.304706) (xy 90.659723 -102.255129)
			(xy 90.689189 -102.209279) (xy 90.72488 -102.168088) (xy 90.766071 -102.132397) (xy 90.811921 -102.102931)
			(xy 90.861498 -102.080289) (xy 90.913793 -102.064934) (xy 90.967741 -102.057178) (xy 91.022243 -102.057178)
			(xy 91.076191 -102.064934) (xy 91.128486 -102.080289) (xy 91.178063 -102.102931) (xy 91.223913 -102.132397)
			(xy 91.265104 -102.168088) (xy 91.300795 -102.209279) (xy 91.330261 -102.255129) (xy 91.352903 -102.304706)
			(xy 91.368258 -102.357001) (xy 91.376014 -102.410949) (xy 91.3765 -102.4382) (xy 91.376061 -102.465408)
			(xy 91.368336 -102.519271) (xy 91.353029 -102.571489) (xy 91.330451 -102.620999) (xy 91.301061 -102.666794)
			(xy 91.265456 -102.707943) (xy 91.224361 -102.743611) (xy 91.201748 -102.758748) (xy 91.193366 -102.764082)
			(xy 91.18219 -102.780338) (xy 91.163902 -102.859332) (xy 91.16209 -102.868961) (xy 91.16509 -102.888303)
			(xy 91.169744 -102.896924) (xy 91.169998 -102.896924) (xy 91.169998 -102.897432) (xy 91.183206 -102.919942)
			(xy 91.204061 -102.967784) (xy 91.218211 -103.018019) (xy 91.225393 -103.069712) (xy 91.225878 -103.095806)
			(xy 91.225337 -103.124544) (xy 91.216715 -103.18137) (xy 91.199668 -103.236259) (xy 91.174581 -103.287971)
			(xy 91.142022 -103.335336) (xy 91.122754 -103.356664) (xy 91.11615 -103.363522) (xy 91.109038 -103.381556)
			(xy 91.109038 -103.470456) (xy 91.11615 -103.48849) (xy 91.122754 -103.495348) (xy 91.142032 -103.516669)
			(xy 91.174599 -103.564032) (xy 91.199691 -103.615744) (xy 91.216742 -103.670636) (xy 91.225365 -103.727465)
			(xy 91.225364 -103.784944) (xy 91.21674 -103.841772) (xy 91.199688 -103.896664) (xy 91.174594 -103.948376)
			(xy 91.142026 -103.995738) (xy 91.122754 -104.017064) (xy 91.117128 -104.022906) (xy 95.86595 -104.022906)
			(xy 95.866405 -103.996591) (xy 95.873641 -103.944462) (xy 95.887961 -103.893818) (xy 95.909095 -103.845619)
			(xy 95.936644 -103.800776) (xy 95.970087 -103.760138) (xy 95.98914 -103.741982) (xy 95.996543 -103.734461)
			(xy 96.005069 -103.715181) (xy 96.00565 -103.704644) (xy 96.00565 -103.629968) (xy 96.005083 -103.619423)
			(xy 95.996573 -103.600128) (xy 95.98914 -103.59263) (xy 95.970095 -103.574465) (xy 95.936639 -103.533836)
			(xy 95.90908 -103.488997) (xy 95.88794 -103.440798) (xy 95.87362 -103.390153) (xy 95.866391 -103.338021)
			(xy 95.86595 -103.311706) (xy 95.866483 -103.284457) (xy 95.874238 -103.230513) (xy 95.88959 -103.178222)
			(xy 95.912227 -103.128647) (xy 95.941689 -103.082799) (xy 95.977376 -103.04161) (xy 96.01856 -103.005918)
			(xy 96.064405 -102.97645) (xy 96.113977 -102.953807) (xy 96.166266 -102.938448) (xy 96.220209 -102.930687)
			(xy 96.247458 -102.930198) (xy 96.275122 -102.930744) (xy 96.329869 -102.938737) (xy 96.38289 -102.954548)
			(xy 96.433074 -102.977846) (xy 96.47937 -103.008142) (xy 96.520809 -103.044802) (xy 96.556524 -103.087059)
			(xy 96.571562 -103.110284) (xy 96.578207 -103.119953) (xy 96.598063 -103.1324) (xy 96.609662 -103.13416)
			(xy 96.689672 -103.142034) (xy 96.70131 -103.142646) (xy 96.723146 -103.13458) (xy 96.731582 -103.12654)
			(xy 96.731836 -103.126286) (xy 96.749915 -103.107703) (xy 96.790247 -103.075125) (xy 96.834622 -103.048312)
			(xy 96.882221 -103.02776) (xy 96.932166 -103.013847) (xy 96.983535 -103.00683) (xy 97.009458 -103.006398)
			(xy 97.03671 -103.006894) (xy 97.09066 -103.014646) (xy 97.142958 -103.029997) (xy 97.192538 -103.052635)
			(xy 97.238392 -103.082099) (xy 97.279585 -103.117789) (xy 97.315279 -103.158979) (xy 97.344748 -103.20483)
			(xy 97.367391 -103.254408) (xy 97.382747 -103.306705) (xy 97.390503 -103.360654) (xy 97.390966 -103.387906)
			(xy 97.390512 -103.415277) (xy 97.382692 -103.469457) (xy 97.367201 -103.52196) (xy 97.344356 -103.571707)
			(xy 97.314629 -103.617673) (xy 97.296986 -103.638604) (xy 97.296732 -103.638858) (xy 97.291149 -103.645947)
			(xy 97.284902 -103.662862) (xy 97.28454 -103.671878) (xy 97.28454 -103.68565) (xy 108.492794 -103.68565)
			(xy 108.492794 -103.63115) (xy 108.50055 -103.577205) (xy 108.515905 -103.524912) (xy 108.538545 -103.475338)
			(xy 108.56801 -103.429489) (xy 108.603699 -103.388301) (xy 108.644888 -103.352611) (xy 108.690736 -103.323146)
			(xy 108.740311 -103.300505) (xy 108.792603 -103.285151) (xy 108.846548 -103.277394) (xy 108.873798 -103.276908)
			(xy 108.900112 -103.277374) (xy 108.952241 -103.284609) (xy 109.002884 -103.298928) (xy 109.051083 -103.320061)
			(xy 109.095926 -103.347607) (xy 109.136566 -103.381046) (xy 109.154722 -103.400098) (xy 109.162234 -103.407511)
			(xy 109.181521 -103.416029) (xy 109.19206 -103.416608) (xy 109.266736 -103.416608) (xy 109.277283 -103.416056)
			(xy 109.296579 -103.407537) (xy 109.304074 -103.400098) (xy 109.323894 -103.37931) (xy 109.368666 -103.343335)
			(xy 109.418324 -103.314475) (xy 109.471746 -103.293382) (xy 109.527725 -103.280533) (xy 109.584998 -103.276218)
			(xy 109.642271 -103.280533) (xy 109.69825 -103.293382) (xy 109.751672 -103.314475) (xy 109.80133 -103.343335)
			(xy 109.846102 -103.37931) (xy 109.865922 -103.400098) (xy 109.873434 -103.407511) (xy 109.892721 -103.416029)
			(xy 109.90326 -103.416608) (xy 109.977936 -103.416608) (xy 109.988483 -103.416056) (xy 110.007779 -103.407537)
			(xy 110.015274 -103.400098) (xy 110.033449 -103.381062) (xy 110.074074 -103.347603) (xy 110.118911 -103.320041)
			(xy 110.167108 -103.2989) (xy 110.217752 -103.284578) (xy 110.269883 -103.277349) (xy 110.296198 -103.276908)
			(xy 110.323452 -103.277339) (xy 110.377406 -103.285096) (xy 110.429706 -103.300452) (xy 110.479288 -103.323096)
			(xy 110.525144 -103.352565) (xy 110.566338 -103.38826) (xy 110.602034 -103.429455) (xy 110.631503 -103.47531)
			(xy 110.654147 -103.524892) (xy 110.669504 -103.577192) (xy 110.677261 -103.631146) (xy 110.677261 -103.685654)
			(xy 110.669504 -103.739608) (xy 110.654147 -103.791908) (xy 110.631503 -103.84149) (xy 110.602034 -103.887345)
			(xy 110.566338 -103.92854) (xy 110.525144 -103.964235) (xy 110.479288 -103.993704) (xy 110.429706 -104.016348)
			(xy 110.377406 -104.031704) (xy 110.323452 -104.039461) (xy 110.296198 -104.039924) (xy 110.269884 -104.03945)
			(xy 110.217756 -104.032216) (xy 110.167114 -104.017897) (xy 110.118915 -103.996766) (xy 110.074072 -103.969221)
			(xy 110.033431 -103.935785) (xy 110.015274 -103.916734) (xy 110.00776 -103.909324) (xy 109.988474 -103.900803)
			(xy 109.977936 -103.900224) (xy 109.90326 -103.900224) (xy 109.892712 -103.900765) (xy 109.873416 -103.909291)
			(xy 109.865922 -103.916734) (xy 109.846102 -103.937522) (xy 109.80133 -103.973497) (xy 109.751672 -104.002357)
			(xy 109.69825 -104.02345) (xy 109.642271 -104.036299) (xy 109.584998 -104.040614) (xy 109.527725 -104.036299)
			(xy 109.471746 -104.02345) (xy 109.418324 -104.002357) (xy 109.368666 -103.973497) (xy 109.323894 -103.937522)
			(xy 109.304074 -103.916734) (xy 109.29656 -103.909324) (xy 109.277274 -103.900803) (xy 109.266736 -103.900224)
			(xy 109.19206 -103.900224) (xy 109.181512 -103.900765) (xy 109.162216 -103.909291) (xy 109.154722 -103.916734)
			(xy 109.136555 -103.935778) (xy 109.095927 -103.969235) (xy 109.051089 -103.996795) (xy 109.002891 -104.017935)
			(xy 108.952245 -104.032255) (xy 108.900113 -104.039483) (xy 108.873798 -104.039924) (xy 108.846548 -104.039406)
			(xy 108.792603 -104.031649) (xy 108.740311 -104.016295) (xy 108.690736 -103.993654) (xy 108.644888 -103.964189)
			(xy 108.603699 -103.928499) (xy 108.56801 -103.887311) (xy 108.538545 -103.841462) (xy 108.515905 -103.791888)
			(xy 108.50055 -103.739595) (xy 108.492794 -103.68565) (xy 97.28454 -103.68565) (xy 97.28454 -103.738934)
			(xy 97.284872 -103.747954) (xy 97.291136 -103.764871) (xy 97.296732 -103.771954) (xy 97.296986 -103.771954)
			(xy 97.296986 -103.772208) (xy 97.31464 -103.793128) (xy 97.34435 -103.839104) (xy 97.367183 -103.888854)
			(xy 97.382671 -103.941358) (xy 97.390495 -103.995536) (xy 97.390966 -104.022906) (xy 97.39055 -104.050161)
			(xy 97.382791 -104.104116) (xy 97.367432 -104.156417) (xy 97.344786 -104.206) (xy 97.315314 -104.251855)
			(xy 97.279615 -104.293049) (xy 97.238417 -104.328742) (xy 97.192558 -104.358209) (xy 97.142972 -104.380849)
			(xy 97.090669 -104.396201) (xy 97.036713 -104.403954) (xy 97.009458 -104.404414) (xy 96.980541 -104.403886)
			(xy 96.923369 -104.395164) (xy 96.868169 -104.37791) (xy 96.816206 -104.35252) (xy 96.768673 -104.319576)
			(xy 96.726657 -104.279834) (xy 96.708468 -104.257348) (xy 96.700874 -104.248527) (xy 96.679963 -104.238353)
			(xy 96.668336 -104.23779) (xy 96.58858 -104.23779) (xy 96.576949 -104.238336) (xy 96.55604 -104.24852)
			(xy 96.548448 -104.257348) (xy 96.530242 -104.279818) (xy 96.488224 -104.319552) (xy 96.440692 -104.352491)
			(xy 96.388734 -104.377882) (xy 96.333539 -104.395141) (xy 96.276373 -104.403876) (xy 96.247458 -104.404414)
			(xy 96.220206 -104.403961) (xy 96.166257 -104.396199) (xy 96.113962 -104.380839) (xy 96.064385 -104.358193)
			(xy 96.018536 -104.328723) (xy 95.977346 -104.293029) (xy 95.941655 -104.251836) (xy 95.912189 -104.205983)
			(xy 95.889548 -104.156404) (xy 95.874193 -104.104107) (xy 95.866436 -104.050158) (xy 95.86595 -104.022906)
			(xy 91.117128 -104.022906) (xy 91.11615 -104.023922) (xy 91.109038 -104.041956) (xy 91.109038 -104.130856)
			(xy 91.11615 -104.14889) (xy 91.122754 -104.155748) (xy 91.142032 -104.177069) (xy 91.174599 -104.224432)
			(xy 91.199691 -104.276144) (xy 91.216742 -104.331036) (xy 91.225365 -104.387865) (xy 91.225364 -104.445344)
			(xy 91.21674 -104.502172) (xy 91.199688 -104.557064) (xy 91.174594 -104.608776) (xy 91.142026 -104.656138)
			(xy 91.122754 -104.677464) (xy 91.11615 -104.684322) (xy 91.109038 -104.702356) (xy 91.109038 -104.791256)
			(xy 91.11615 -104.80929) (xy 91.122754 -104.816148) (xy 91.142032 -104.837469) (xy 91.174599 -104.884832)
			(xy 91.199691 -104.936544) (xy 91.216742 -104.991436) (xy 91.225365 -105.048265) (xy 91.225364 -105.084455)
			(xy 95.743949 -105.084455) (xy 95.743949 -105.029945) (xy 95.751707 -104.975991) (xy 95.767065 -104.92369)
			(xy 95.78971 -104.874107) (xy 95.819181 -104.828252) (xy 95.854879 -104.787058) (xy 95.896076 -104.751363)
			(xy 95.941933 -104.721896) (xy 95.991518 -104.699255) (xy 96.04382 -104.683901) (xy 96.097775 -104.676147)
			(xy 96.12503 -104.675686) (xy 96.152401 -104.676138) (xy 96.20658 -104.68396) (xy 96.259083 -104.699452)
			(xy 96.30883 -104.722297) (xy 96.354796 -104.752024) (xy 96.375728 -104.769666) (xy 96.375982 -104.76992)
			(xy 96.383068 -104.775507) (xy 96.399985 -104.781753) (xy 96.409002 -104.782112) (xy 96.476058 -104.782112)
			(xy 96.485073 -104.781732) (xy 96.50199 -104.7755) (xy 96.509078 -104.76992) (xy 96.509078 -104.769666)
			(xy 96.509332 -104.769666) (xy 96.530265 -104.752025) (xy 96.576233 -104.722301) (xy 96.625979 -104.699455)
			(xy 96.678481 -104.683959) (xy 96.732659 -104.67613) (xy 96.787401 -104.67613) (xy 96.841579 -104.683959)
			(xy 96.894081 -104.699455) (xy 96.943827 -104.722301) (xy 96.989795 -104.752025) (xy 97.010728 -104.769666)
			(xy 97.010982 -104.76992) (xy 97.018068 -104.775507) (xy 97.034985 -104.781753) (xy 97.044002 -104.782112)
			(xy 97.111058 -104.782112) (xy 97.120073 -104.781732) (xy 97.13699 -104.7755) (xy 97.144078 -104.76992)
			(xy 97.144078 -104.769666) (xy 97.144332 -104.769666) (xy 97.165265 -104.752025) (xy 97.211233 -104.722301)
			(xy 97.260979 -104.699455) (xy 97.313481 -104.683959) (xy 97.367659 -104.67613) (xy 97.422401 -104.67613)
			(xy 97.476579 -104.683959) (xy 97.529081 -104.699455) (xy 97.578827 -104.722301) (xy 97.624795 -104.752025)
			(xy 97.645728 -104.769666) (xy 97.645982 -104.76992) (xy 97.653068 -104.775507) (xy 97.669985 -104.781753)
			(xy 97.679002 -104.782112) (xy 97.746058 -104.782112) (xy 97.755073 -104.781732) (xy 97.77199 -104.7755)
			(xy 97.779078 -104.76992) (xy 97.779078 -104.769666) (xy 97.779332 -104.769666) (xy 97.800275 -104.75204)
			(xy 97.846245 -104.722327) (xy 97.89599 -104.699489) (xy 97.948488 -104.683995) (xy 98.002662 -104.676163)
			(xy 98.03003 -104.675686) (xy 98.057279 -104.676186) (xy 98.111223 -104.683946) (xy 98.163513 -104.699303)
			(xy 98.213086 -104.721946) (xy 98.258932 -104.751412) (xy 98.300118 -104.787103) (xy 98.335806 -104.828292)
			(xy 98.365269 -104.87414) (xy 98.387907 -104.923715) (xy 98.403261 -104.976006) (xy 98.411016 -105.029951)
			(xy 98.411016 -105.084449) (xy 98.403261 -105.138394) (xy 98.387907 -105.190685) (xy 98.365269 -105.24026)
			(xy 98.335806 -105.286108) (xy 98.300118 -105.327297) (xy 98.258932 -105.362988) (xy 98.213086 -105.392454)
			(xy 98.163513 -105.415097) (xy 98.111223 -105.430454) (xy 98.057279 -105.438214) (xy 98.03003 -105.438702)
			(xy 98.00266 -105.438218) (xy 97.948482 -105.430404) (xy 97.895979 -105.414919) (xy 97.846232 -105.392082)
			(xy 97.800264 -105.362361) (xy 97.779332 -105.344722) (xy 97.779078 -105.344468) (xy 97.772005 -105.338863)
			(xy 97.755078 -105.332628) (xy 97.746058 -105.332276) (xy 97.679002 -105.332276) (xy 97.669986 -105.332639)
			(xy 97.653069 -105.338883) (xy 97.645982 -105.344468) (xy 97.645982 -105.344722) (xy 97.645728 -105.344722)
			(xy 97.624795 -105.362363) (xy 97.578827 -105.392087) (xy 97.529081 -105.414933) (xy 97.476579 -105.430429)
			(xy 97.422401 -105.438258) (xy 97.367659 -105.438258) (xy 97.313481 -105.430429) (xy 97.260979 -105.414933)
			(xy 97.211233 -105.392087) (xy 97.165265 -105.362363) (xy 97.144332 -105.344722) (xy 97.144078 -105.344468)
			(xy 97.137005 -105.338863) (xy 97.120078 -105.332628) (xy 97.111058 -105.332276) (xy 97.044002 -105.332276)
			(xy 97.034986 -105.332639) (xy 97.018069 -105.338883) (xy 97.010982 -105.344468) (xy 97.010982 -105.344722)
			(xy 97.010728 -105.344722) (xy 96.989795 -105.362363) (xy 96.943827 -105.392087) (xy 96.894081 -105.414933)
			(xy 96.841579 -105.430429) (xy 96.787401 -105.438258) (xy 96.732659 -105.438258) (xy 96.678481 -105.430429)
			(xy 96.625979 -105.414933) (xy 96.576233 -105.392087) (xy 96.530265 -105.362363) (xy 96.509332 -105.344722)
			(xy 96.509078 -105.344468) (xy 96.502005 -105.338863) (xy 96.485078 -105.332628) (xy 96.476058 -105.332276)
			(xy 96.409002 -105.332276) (xy 96.399986 -105.332639) (xy 96.383069 -105.338883) (xy 96.375982 -105.344468)
			(xy 96.375982 -105.344722) (xy 96.375728 -105.344722) (xy 96.354799 -105.362365) (xy 96.308825 -105.392075)
			(xy 96.259077 -105.41491) (xy 96.206575 -105.4304) (xy 96.152399 -105.438228) (xy 96.12503 -105.438702)
			(xy 96.097775 -105.438253) (xy 96.04382 -105.430499) (xy 95.991518 -105.415145) (xy 95.941933 -105.392504)
			(xy 95.896076 -105.363037) (xy 95.854879 -105.327342) (xy 95.819181 -105.286148) (xy 95.78971 -105.240293)
			(xy 95.767065 -105.19071) (xy 95.751707 -105.138409) (xy 95.743949 -105.084455) (xy 91.225364 -105.084455)
			(xy 91.225364 -105.105744) (xy 91.21674 -105.162572) (xy 91.199688 -105.217464) (xy 91.174594 -105.269176)
			(xy 91.142026 -105.316538) (xy 91.122754 -105.337864) (xy 91.11615 -105.344722) (xy 91.109038 -105.362756)
			(xy 91.109038 -105.451656) (xy 91.11615 -105.46969) (xy 91.122754 -105.476548) (xy 91.142032 -105.497869)
			(xy 91.174599 -105.545232) (xy 91.199691 -105.596944) (xy 91.216742 -105.651836) (xy 91.225365 -105.708665)
			(xy 91.225364 -105.766144) (xy 91.21674 -105.822972) (xy 91.199688 -105.877864) (xy 91.174594 -105.929576)
			(xy 91.142026 -105.976938) (xy 91.122754 -105.998264) (xy 91.11615 -106.005122) (xy 91.109038 -106.023156)
			(xy 91.109038 -106.112056) (xy 91.11615 -106.13009) (xy 91.122754 -106.136948) (xy 91.142032 -106.158269)
			(xy 91.174599 -106.205632) (xy 91.199691 -106.257344) (xy 91.216742 -106.312236) (xy 91.225365 -106.369065)
			(xy 91.225364 -106.426544) (xy 91.21674 -106.483372) (xy 91.199688 -106.538264) (xy 91.174594 -106.589976)
			(xy 91.142026 -106.637338) (xy 91.122754 -106.658664) (xy 91.11615 -106.665522) (xy 91.109038 -106.683556)
			(xy 91.109038 -106.772456) (xy 91.11615 -106.79049) (xy 91.122754 -106.797348) (xy 91.127367 -106.80245)
			(xy 108.420905 -106.80245) (xy 108.420905 -106.74795) (xy 108.428662 -106.694005) (xy 108.444016 -106.641712)
			(xy 108.466657 -106.592138) (xy 108.496123 -106.54629) (xy 108.531814 -106.505102) (xy 108.573003 -106.469413)
			(xy 108.618852 -106.439949) (xy 108.668427 -106.417311) (xy 108.72072 -106.401958) (xy 108.774666 -106.394204)
			(xy 108.801916 -106.393742) (xy 108.828231 -106.394185) (xy 108.880361 -106.401423) (xy 108.931005 -106.415746)
			(xy 108.979204 -106.436883) (xy 109.024047 -106.464434) (xy 109.064685 -106.497878) (xy 109.08284 -106.516932)
			(xy 109.090354 -106.524343) (xy 109.109639 -106.532865) (xy 109.120178 -106.533442) (xy 109.194854 -106.533442)
			(xy 109.205401 -106.532889) (xy 109.224695 -106.524369) (xy 109.232192 -106.516932) (xy 109.252012 -106.496144)
			(xy 109.296784 -106.460169) (xy 109.346442 -106.431309) (xy 109.399864 -106.410216) (xy 109.455843 -106.397367)
			(xy 109.513116 -106.393052) (xy 109.570389 -106.397367) (xy 109.626368 -106.410216) (xy 109.67979 -106.431309)
			(xy 109.729448 -106.460169) (xy 109.77422 -106.496144) (xy 109.79404 -106.516932) (xy 109.801554 -106.524343)
			(xy 109.820839 -106.532865) (xy 109.831378 -106.533442) (xy 109.906054 -106.533442) (xy 109.916601 -106.532889)
			(xy 109.935895 -106.524369) (xy 109.943392 -106.516932) (xy 109.961565 -106.497893) (xy 110.00219 -106.464434)
			(xy 110.047026 -106.436871) (xy 110.095224 -106.41573) (xy 110.145869 -106.401409) (xy 110.198001 -106.394182)
			(xy 110.224316 -106.393742) (xy 110.25157 -106.394129) (xy 110.305523 -106.401888) (xy 110.357823 -106.417247)
			(xy 110.407405 -106.439892) (xy 110.453259 -106.469362) (xy 110.494453 -106.505059) (xy 110.530147 -106.546254)
			(xy 110.559616 -106.59211) (xy 110.582259 -106.641692) (xy 110.597615 -106.693993) (xy 110.605372 -106.747946)
			(xy 110.605372 -106.802454) (xy 110.597615 -106.856407) (xy 110.582259 -106.908708) (xy 110.559616 -106.95829)
			(xy 110.530147 -107.004146) (xy 110.494453 -107.045341) (xy 110.453259 -107.081038) (xy 110.407405 -107.110508)
			(xy 110.357823 -107.133153) (xy 110.305523 -107.148512) (xy 110.25157 -107.156271) (xy 110.224316 -107.156758)
			(xy 110.198002 -107.156293) (xy 110.145873 -107.14906) (xy 110.095229 -107.134741) (xy 110.04703 -107.113608)
			(xy 110.002187 -107.086061) (xy 109.961548 -107.052621) (xy 109.943392 -107.033568) (xy 109.935866 -107.026171)
			(xy 109.91659 -107.017642) (xy 109.906054 -107.017058) (xy 109.831378 -107.017058) (xy 109.820833 -107.017628)
			(xy 109.801538 -107.026136) (xy 109.79404 -107.033568) (xy 109.77422 -107.054356) (xy 109.729448 -107.090331)
			(xy 109.67979 -107.119191) (xy 109.626368 -107.140284) (xy 109.570389 -107.153133) (xy 109.513116 -107.157448)
			(xy 109.455843 -107.153133) (xy 109.399864 -107.140284) (xy 109.346442 -107.119191) (xy 109.296784 -107.090331)
			(xy 109.252012 -107.054356) (xy 109.232192 -107.033568) (xy 109.224666 -107.026171) (xy 109.20539 -107.017642)
			(xy 109.194854 -107.017058) (xy 109.120178 -107.017058) (xy 109.109633 -107.017628) (xy 109.090338 -107.026136)
			(xy 109.08284 -107.033568) (xy 109.0647 -107.05264) (xy 109.024068 -107.086096) (xy 108.979225 -107.113654)
			(xy 108.931021 -107.13479) (xy 108.88037 -107.149103) (xy 108.828233 -107.156323) (xy 108.801916 -107.156758)
			(xy 108.774666 -107.156196) (xy 108.72072 -107.148442) (xy 108.668427 -107.133089) (xy 108.618852 -107.110451)
			(xy 108.573003 -107.080987) (xy 108.531813 -107.045298) (xy 108.496123 -107.00411) (xy 108.466657 -106.958262)
			(xy 108.444016 -106.908688) (xy 108.428662 -106.856395) (xy 108.420905 -106.80245) (xy 91.127367 -106.80245)
			(xy 91.142032 -106.818669) (xy 91.174599 -106.866032) (xy 91.199691 -106.917744) (xy 91.216742 -106.972636)
			(xy 91.225365 -107.029465) (xy 91.225364 -107.086944) (xy 91.21674 -107.143772) (xy 91.199688 -107.198664)
			(xy 91.174594 -107.250376) (xy 91.142026 -107.297738) (xy 91.122754 -107.319064) (xy 91.11615 -107.325922)
			(xy 91.109038 -107.343956) (xy 91.109038 -107.432856) (xy 91.11615 -107.45089) (xy 91.122754 -107.457748)
			(xy 91.142032 -107.479069) (xy 91.174599 -107.526432) (xy 91.199691 -107.578144) (xy 91.216742 -107.633036)
			(xy 91.225365 -107.689865) (xy 91.225364 -107.740253) (xy 95.684273 -107.740253) (xy 95.684273 -107.685747)
			(xy 95.692031 -107.631795) (xy 95.707388 -107.579496) (xy 95.730033 -107.529916) (xy 95.759503 -107.484063)
			(xy 95.795199 -107.442871) (xy 95.836395 -107.407179) (xy 95.882251 -107.377714) (xy 95.931834 -107.355074)
			(xy 95.984134 -107.339723) (xy 96.038087 -107.331971) (xy 96.06534 -107.33151) (xy 96.092709 -107.332009)
			(xy 96.146887 -107.339818) (xy 96.19939 -107.3553) (xy 96.249137 -107.378134) (xy 96.295105 -107.407852)
			(xy 96.316038 -107.42549) (xy 96.316292 -107.425744) (xy 96.323373 -107.431339) (xy 96.340294 -107.437579)
			(xy 96.349312 -107.437936) (xy 96.416368 -107.437936) (xy 96.425382 -107.437556) (xy 96.442299 -107.431323)
			(xy 96.449388 -107.425744) (xy 96.449388 -107.42549) (xy 96.449642 -107.42549) (xy 96.470575 -107.407849)
			(xy 96.516543 -107.378125) (xy 96.566289 -107.355279) (xy 96.618791 -107.339783) (xy 96.672969 -107.331954)
			(xy 96.727711 -107.331954) (xy 96.781889 -107.339783) (xy 96.834391 -107.355279) (xy 96.884137 -107.378125)
			(xy 96.930105 -107.407849) (xy 96.951038 -107.42549) (xy 96.951292 -107.425744) (xy 96.958373 -107.431339)
			(xy 96.975294 -107.437579) (xy 96.984312 -107.437936) (xy 97.051368 -107.437936) (xy 97.060382 -107.437556)
			(xy 97.077299 -107.431323) (xy 97.084388 -107.425744) (xy 97.084388 -107.42549) (xy 97.084642 -107.42549)
			(xy 97.105575 -107.407849) (xy 97.151543 -107.378125) (xy 97.201289 -107.355279) (xy 97.253791 -107.339783)
			(xy 97.307969 -107.331954) (xy 97.362711 -107.331954) (xy 97.416889 -107.339783) (xy 97.469391 -107.355279)
			(xy 97.519137 -107.378125) (xy 97.565105 -107.407849) (xy 97.586038 -107.42549) (xy 97.586292 -107.425744)
			(xy 97.593373 -107.431339) (xy 97.610294 -107.437579) (xy 97.619312 -107.437936) (xy 97.686368 -107.437936)
			(xy 97.695382 -107.437556) (xy 97.712299 -107.431323) (xy 97.719388 -107.425744) (xy 97.719388 -107.42549)
			(xy 97.719642 -107.42549) (xy 97.740584 -107.407863) (xy 97.786554 -107.37815) (xy 97.836299 -107.355312)
			(xy 97.888798 -107.339818) (xy 97.942972 -107.331986) (xy 97.97034 -107.33151) (xy 97.997591 -107.331963)
			(xy 98.051537 -107.339724) (xy 98.103829 -107.355083) (xy 98.153404 -107.377728) (xy 98.199251 -107.407197)
			(xy 98.240438 -107.44289) (xy 98.276127 -107.484081) (xy 98.305591 -107.529932) (xy 98.328231 -107.579508)
			(xy 98.343584 -107.631803) (xy 98.35134 -107.685749) (xy 98.35134 -107.740251) (xy 98.343584 -107.794197)
			(xy 98.328231 -107.846492) (xy 98.305591 -107.896068) (xy 98.276127 -107.941919) (xy 98.240438 -107.98311)
			(xy 98.199251 -108.018803) (xy 98.153404 -108.048272) (xy 98.103829 -108.070917) (xy 98.051537 -108.086276)
			(xy 97.997591 -108.094037) (xy 97.97034 -108.094526) (xy 97.94297 -108.094055) (xy 97.88879 -108.086241)
			(xy 97.836286 -108.070754) (xy 97.786539 -108.047913) (xy 97.740573 -108.018188) (xy 97.719642 -108.000546)
			(xy 97.719388 -108.000292) (xy 97.71231 -107.994693) (xy 97.695387 -107.988454) (xy 97.686368 -107.9881)
			(xy 97.619312 -107.9881) (xy 97.610296 -107.988463) (xy 97.593379 -107.994706) (xy 97.586292 -108.000292)
			(xy 97.586292 -108.000546) (xy 97.586038 -108.000546) (xy 97.565105 -108.018187) (xy 97.519137 -108.047911)
			(xy 97.469391 -108.070757) (xy 97.416889 -108.086253) (xy 97.362711 -108.094082) (xy 97.307969 -108.094082)
			(xy 97.253791 -108.086253) (xy 97.201289 -108.070757) (xy 97.151543 -108.047911) (xy 97.105575 -108.018187)
			(xy 97.084642 -108.000546) (xy 97.084388 -108.000292) (xy 97.07731 -107.994693) (xy 97.060387 -107.988454)
			(xy 97.051368 -107.9881) (xy 96.984312 -107.9881) (xy 96.975296 -107.988463) (xy 96.958379 -107.994706)
			(xy 96.951292 -108.000292) (xy 96.951292 -108.000546) (xy 96.951038 -108.000546) (xy 96.930105 -108.018187)
			(xy 96.884137 -108.047911) (xy 96.834391 -108.070757) (xy 96.781889 -108.086253) (xy 96.727711 -108.094082)
			(xy 96.672969 -108.094082) (xy 96.618791 -108.086253) (xy 96.566289 -108.070757) (xy 96.516543 -108.047911)
			(xy 96.470575 -108.018187) (xy 96.449642 -108.000546) (xy 96.449388 -108.000292) (xy 96.44231 -107.994693)
			(xy 96.425387 -107.988454) (xy 96.416368 -107.9881) (xy 96.349312 -107.9881) (xy 96.340296 -107.988463)
			(xy 96.323379 -107.994706) (xy 96.316292 -108.000292) (xy 96.316292 -108.000546) (xy 96.316038 -108.000546)
			(xy 96.295095 -108.018172) (xy 96.249126 -108.047888) (xy 96.199382 -108.070727) (xy 96.146883 -108.086221)
			(xy 96.092709 -108.094051) (xy 96.06534 -108.094526) (xy 96.038087 -108.094029) (xy 95.984134 -108.086277)
			(xy 95.931834 -108.070926) (xy 95.882251 -108.048286) (xy 95.836395 -108.018821) (xy 95.795199 -107.983129)
			(xy 95.759503 -107.941937) (xy 95.730033 -107.896084) (xy 95.707388 -107.846504) (xy 95.692031 -107.794205)
			(xy 95.684273 -107.740253) (xy 91.225364 -107.740253) (xy 91.225364 -107.747344) (xy 91.21674 -107.804172)
			(xy 91.199688 -107.859064) (xy 91.174594 -107.910776) (xy 91.142026 -107.958138) (xy 91.122754 -107.979464)
			(xy 91.11615 -107.986322) (xy 91.109038 -108.004356) (xy 91.109038 -108.093256) (xy 91.11615 -108.11129)
			(xy 91.122754 -108.118148) (xy 91.142026 -108.139474) (xy 91.174593 -108.186836) (xy 91.199685 -108.238548)
			(xy 91.216735 -108.293439) (xy 91.225357 -108.350267) (xy 91.225878 -108.379006) (xy 91.225392 -108.406257)
			(xy 91.217636 -108.460205) (xy 91.202281 -108.5125) (xy 91.179639 -108.562077) (xy 91.174865 -108.569506)
			(xy 106.861102 -108.569506) (xy 106.861571 -108.542136) (xy 106.869388 -108.487957) (xy 106.884876 -108.435454)
			(xy 106.907718 -108.385707) (xy 106.937441 -108.33974) (xy 106.955082 -108.318808) (xy 106.955336 -108.318554)
			(xy 106.96091 -108.311459) (xy 106.967163 -108.294549) (xy 106.967528 -108.285534) (xy 106.967528 -108.218478)
			(xy 106.967176 -108.209461) (xy 106.960924 -108.192544) (xy 106.955336 -108.185458) (xy 106.955082 -108.185458)
			(xy 106.955082 -108.185204) (xy 106.937429 -108.164284) (xy 106.907719 -108.118307) (xy 106.884887 -108.068557)
			(xy 106.869399 -108.016054) (xy 106.861574 -107.961876) (xy 106.861102 -107.934506) (xy 106.861588 -107.907255)
			(xy 106.869344 -107.853307) (xy 106.884699 -107.801012) (xy 106.907341 -107.751435) (xy 106.936807 -107.705585)
			(xy 106.972498 -107.664394) (xy 107.013689 -107.628703) (xy 107.059539 -107.599237) (xy 107.109116 -107.576595)
			(xy 107.161411 -107.56124) (xy 107.215359 -107.553484) (xy 107.269861 -107.553484) (xy 107.323809 -107.56124)
			(xy 107.376104 -107.576595) (xy 107.425681 -107.599237) (xy 107.471531 -107.628703) (xy 107.512722 -107.664394)
			(xy 107.548413 -107.705585) (xy 107.577879 -107.751435) (xy 107.600521 -107.801012) (xy 107.615876 -107.853307)
			(xy 107.623632 -107.907255) (xy 107.624118 -107.934506) (xy 107.623675 -107.961877) (xy 107.615855 -108.016058)
			(xy 107.600362 -108.068562) (xy 107.577514 -108.118309) (xy 107.547783 -108.164274) (xy 107.530138 -108.185204)
			(xy 107.529884 -108.185458) (xy 107.524307 -108.192551) (xy 107.518055 -108.209463) (xy 107.517692 -108.218478)
			(xy 107.517692 -108.285534) (xy 107.518035 -108.294552) (xy 107.524293 -108.311469) (xy 107.529884 -108.318554)
			(xy 107.530138 -108.318554) (xy 107.530138 -108.318808) (xy 107.547801 -108.339721) (xy 107.577508 -108.3857)
			(xy 107.600339 -108.435452) (xy 107.615824 -108.487957) (xy 107.623647 -108.542136) (xy 107.624118 -108.569506)
			(xy 107.623632 -108.596757) (xy 107.615876 -108.650705) (xy 107.600521 -108.703) (xy 107.577879 -108.752577)
			(xy 107.548413 -108.798427) (xy 107.512722 -108.839618) (xy 107.471531 -108.875309) (xy 107.425681 -108.904775)
			(xy 107.376104 -108.927417) (xy 107.323809 -108.942772) (xy 107.269861 -108.950528) (xy 107.215359 -108.950528)
			(xy 107.161411 -108.942772) (xy 107.109116 -108.927417) (xy 107.059539 -108.904775) (xy 107.013689 -108.875309)
			(xy 106.972498 -108.839618) (xy 106.936807 -108.798427) (xy 106.907341 -108.752577) (xy 106.884699 -108.703)
			(xy 106.869344 -108.650705) (xy 106.861588 -108.596757) (xy 106.861102 -108.569506) (xy 91.174865 -108.569506)
			(xy 91.150173 -108.607927) (xy 91.114482 -108.649118) (xy 91.073291 -108.684809) (xy 91.027441 -108.714275)
			(xy 90.977864 -108.736917) (xy 90.925569 -108.752272) (xy 90.871621 -108.760028) (xy 90.817119 -108.760028)
			(xy 90.763171 -108.752272) (xy 90.710876 -108.736917) (xy 90.661299 -108.714275) (xy 90.615449 -108.684809)
			(xy 90.574258 -108.649118) (xy 90.538567 -108.607927) (xy 90.509101 -108.562077) (xy 90.486459 -108.5125)
			(xy 90.471104 -108.460205) (xy 90.463348 -108.406257) (xy 90.462862 -108.379006) (xy 52.700428 -108.379006)
			(xy 52.700428 -109.176312) (xy 52.699938 -109.20628) (xy 52.692115 -109.265702) (xy 52.676602 -109.323595)
			(xy 52.653666 -109.378968) (xy 52.623699 -109.430874) (xy 52.587212 -109.478424) (xy 52.544832 -109.520804)
			(xy 52.497282 -109.557291) (xy 52.445376 -109.587258) (xy 52.390003 -109.610194) (xy 52.33211 -109.625707)
			(xy 52.272688 -109.63353) (xy 52.212752 -109.63353) (xy 52.15333 -109.625707) (xy 52.095437 -109.610194)
			(xy 52.040064 -109.587258) (xy 51.988158 -109.557291) (xy 51.940608 -109.520804) (xy 51.898228 -109.478424)
			(xy 51.861741 -109.430874) (xy 51.831774 -109.378968) (xy 51.808838 -109.323595) (xy 51.793325 -109.265702)
			(xy 51.785502 -109.20628) (xy 51.785012 -109.176312) (xy 51.433984 -109.176312) (xy 51.433984 -110.97641)
			(xy 53.639212 -110.97641) (xy 53.639212 -110.11281) (xy 53.639702 -110.082842) (xy 53.647525 -110.02342)
			(xy 53.663038 -109.965527) (xy 53.685974 -109.910154) (xy 53.715941 -109.858248) (xy 53.752428 -109.810698)
			(xy 53.794808 -109.768318) (xy 53.842358 -109.731831) (xy 53.894264 -109.701864) (xy 53.949637 -109.678928)
			(xy 54.00753 -109.663415) (xy 54.066952 -109.655592) (xy 54.126888 -109.655592) (xy 54.18631 -109.663415)
			(xy 54.244203 -109.678928) (xy 54.299576 -109.701864) (xy 54.351482 -109.731831) (xy 54.399032 -109.768318)
			(xy 54.441412 -109.810698) (xy 54.477899 -109.858248) (xy 54.507866 -109.910154) (xy 54.530802 -109.965527)
			(xy 54.546315 -110.02342) (xy 54.554138 -110.082842) (xy 54.554628 -110.11281) (xy 54.554628 -110.530132)
			(xy 70.429118 -110.530132) (xy 70.433189 -110.47451) (xy 70.445315 -110.420073) (xy 70.465238 -110.367982)
			(xy 70.492534 -110.319347) (xy 70.52662 -110.275204) (xy 70.566769 -110.236495) (xy 70.612127 -110.204044)
			(xy 70.661727 -110.178543) (xy 70.714511 -110.160536) (xy 70.769354 -110.150406) (xy 70.825088 -110.148369)
			(xy 70.880525 -110.154469) (xy 70.934482 -110.168575) (xy 70.985811 -110.190387) (xy 71.033417 -110.219441)
			(xy 71.076285 -110.255116) (xy 71.113502 -110.296653) (xy 71.144275 -110.343166) (xy 71.167947 -110.393663)
			(xy 71.184015 -110.44707) (xy 71.192135 -110.502246) (xy 71.192644 -110.530132) (xy 71.192135 -110.558018)
			(xy 71.184015 -110.613194) (xy 71.167947 -110.666601) (xy 71.144275 -110.717098) (xy 71.113502 -110.763611)
			(xy 71.076285 -110.805148) (xy 71.033417 -110.840823) (xy 70.985811 -110.869877) (xy 70.934482 -110.891689)
			(xy 70.880525 -110.905795) (xy 70.825088 -110.911895) (xy 70.769354 -110.909858) (xy 70.714511 -110.899728)
			(xy 70.661727 -110.881721) (xy 70.612127 -110.85622) (xy 70.566769 -110.823769) (xy 70.52662 -110.78506)
			(xy 70.492534 -110.740917) (xy 70.465238 -110.692282) (xy 70.445315 -110.640191) (xy 70.433189 -110.585754)
			(xy 70.429118 -110.530132) (xy 54.554628 -110.530132) (xy 54.554628 -110.97641) (xy 54.554138 -111.006378)
			(xy 54.546315 -111.0658) (xy 54.530802 -111.123693) (xy 54.507866 -111.179066) (xy 54.477899 -111.230972)
			(xy 54.441412 -111.278522) (xy 54.399032 -111.320902) (xy 54.351482 -111.357389) (xy 54.299576 -111.387356)
			(xy 54.244203 -111.410292) (xy 54.18631 -111.425805) (xy 54.126888 -111.433628) (xy 54.066952 -111.433628)
			(xy 54.00753 -111.425805) (xy 53.949637 -111.410292) (xy 53.894264 -111.387356) (xy 53.842358 -111.357389)
			(xy 53.794808 -111.320902) (xy 53.752428 -111.278522) (xy 53.715941 -111.230972) (xy 53.685974 -111.179066)
			(xy 53.663038 -111.123693) (xy 53.647525 -111.0658) (xy 53.639702 -111.006378) (xy 53.639212 -110.97641)
			(xy 51.433984 -110.97641) (xy 51.433984 -112.776508) (xy 51.785012 -112.776508) (xy 51.785012 -111.912908)
			(xy 51.785502 -111.88294) (xy 51.793325 -111.823518) (xy 51.808838 -111.765625) (xy 51.831774 -111.710252)
			(xy 51.861741 -111.658346) (xy 51.898228 -111.610796) (xy 51.940608 -111.568416) (xy 51.988158 -111.531929)
			(xy 52.040064 -111.501962) (xy 52.095437 -111.479026) (xy 52.15333 -111.463513) (xy 52.212752 -111.45569)
			(xy 52.272688 -111.45569) (xy 52.33211 -111.463513) (xy 52.390003 -111.479026) (xy 52.445376 -111.501962)
			(xy 52.497282 -111.531929) (xy 52.544832 -111.568416) (xy 52.587212 -111.610796) (xy 52.623699 -111.658346)
			(xy 52.653666 -111.710252) (xy 52.676602 -111.765625) (xy 52.692115 -111.823518) (xy 52.699938 -111.88294)
			(xy 52.700428 -111.912908) (xy 52.700428 -112.776508) (xy 52.699938 -112.806476) (xy 52.692115 -112.865898)
			(xy 52.676602 -112.923791) (xy 52.653666 -112.979164) (xy 52.623699 -113.03107) (xy 52.587212 -113.07862)
			(xy 52.544832 -113.121) (xy 52.497282 -113.157487) (xy 52.445376 -113.187454) (xy 52.390003 -113.21039)
			(xy 52.33211 -113.225903) (xy 52.272688 -113.233726) (xy 52.212752 -113.233726) (xy 52.15333 -113.225903)
			(xy 52.095437 -113.21039) (xy 52.040064 -113.187454) (xy 51.988158 -113.157487) (xy 51.940608 -113.121)
			(xy 51.898228 -113.07862) (xy 51.861741 -113.03107) (xy 51.831774 -112.979164) (xy 51.808838 -112.923791)
			(xy 51.793325 -112.865898) (xy 51.785502 -112.806476) (xy 51.785012 -112.776508) (xy 51.433984 -112.776508)
			(xy 51.433984 -113.35131) (xy 51.434382 -113.361383) (xy 51.44212 -113.379982) (xy 51.44897 -113.387378)
			(xy 51.760882 -113.69929) (xy 51.768295 -113.706113) (xy 51.786884 -113.713843) (xy 51.79695 -113.714276)
			(xy 53.958236 -113.714276) (xy 53.984259 -113.714808) (xy 54.035662 -113.722974) (xy 54.085159 -113.739067)
			(xy 54.131536 -113.762693) (xy 54.173653 -113.793272) (xy 54.192424 -113.811304) (xy 55.757572 -115.376452)
			(xy 55.765976 -115.383994) (xy 55.787186 -115.391651) (xy 55.798466 -115.391184) (xy 55.887874 -115.382802)
			(xy 55.906924 -115.371372) (xy 55.913528 -115.362228) (xy 55.913528 -115.36172) (xy 55.928862 -115.340025)
			(xy 55.964533 -115.300656) (xy 56.005318 -115.266612) (xy 56.050428 -115.238552) (xy 56.098994 -115.217016)
			(xy 56.150075 -115.202421) (xy 56.202687 -115.195049) (xy 56.22925 -115.194588) (xy 56.256206 -115.195038)
			(xy 56.309579 -115.202646) (xy 56.36135 -115.21769) (xy 56.410488 -115.23987) (xy 56.456016 -115.268745)
			(xy 56.497027 -115.30374) (xy 56.532705 -115.344159) (xy 56.56234 -115.389196) (xy 56.585341 -115.437955)
			(xy 56.59374 -115.463574) (xy 56.59374 -115.463828) (xy 56.595725 -115.469519) (xy 56.602017 -115.479795)
			(xy 56.606186 -115.484148) (xy 57.858406 -116.736368) (xy 57.865818 -116.743052) (xy 57.884251 -116.750649)
			(xy 57.904189 -116.750649) (xy 57.922622 -116.743052) (xy 57.930034 -116.736368) (xy 63.746634 -110.919768)
			(xy 63.770234 -110.896874) (xy 63.82164 -110.855876) (xy 63.87731 -110.820886) (xy 63.936544 -110.792343)
			(xy 63.998599 -110.770605) (xy 64.062697 -110.755944) (xy 64.128032 -110.748546) (xy 64.160908 -110.748064)
			(xy 64.646048 -110.748064) (xy 64.680149 -110.748478) (xy 64.74789 -110.756401) (xy 64.814252 -110.772135)
			(xy 64.87834 -110.795465) (xy 64.939286 -110.826078) (xy 64.996266 -110.863559) (xy 65.04851 -110.9074)
			(xy 65.095311 -110.957011) (xy 65.136037 -111.011719) (xy 65.170137 -111.070785) (xy 65.197149 -111.13341)
			(xy 65.216709 -111.198747) (xy 65.228551 -111.265913) (xy 65.232517 -111.334) (xy 65.228551 -111.402087)
			(xy 65.216709 -111.469253) (xy 65.197149 -111.53459) (xy 65.170137 -111.597215) (xy 65.136037 -111.656281)
			(xy 65.095311 -111.710989) (xy 65.04851 -111.7606) (xy 64.996266 -111.804441) (xy 64.939286 -111.841922)
			(xy 64.87834 -111.872535) (xy 64.84628 -111.884206) (xy 70.364348 -111.884206) (xy 70.368419 -111.828584)
			(xy 70.380545 -111.774147) (xy 70.400468 -111.722056) (xy 70.427764 -111.673421) (xy 70.46185 -111.629278)
			(xy 70.501999 -111.590569) (xy 70.547357 -111.558118) (xy 70.596957 -111.532617) (xy 70.649741 -111.51461)
			(xy 70.704584 -111.50448) (xy 70.760318 -111.502443) (xy 70.815755 -111.508543) (xy 70.869712 -111.522649)
			(xy 70.921041 -111.544461) (xy 70.968647 -111.573515) (xy 71.011515 -111.60919) (xy 71.048732 -111.650727)
			(xy 71.079505 -111.69724) (xy 71.103177 -111.747737) (xy 71.119245 -111.801144) (xy 71.127365 -111.85632)
			(xy 71.127874 -111.884206) (xy 71.127365 -111.912092) (xy 71.119245 -111.967268) (xy 71.115196 -111.980726)
			(xy 73.901554 -111.980726) (xy 73.902106 -111.951988) (xy 73.910723 -111.895163) (xy 73.927768 -111.840273)
			(xy 73.952853 -111.788561) (xy 73.985411 -111.741196) (xy 74.004678 -111.719868) (xy 74.011282 -111.71301)
			(xy 74.018394 -111.694976) (xy 74.018394 -111.606076) (xy 74.011282 -111.588042) (xy 74.004678 -111.581184)
			(xy 73.985435 -111.559834) (xy 73.952873 -111.512474) (xy 73.927783 -111.460766) (xy 73.910733 -111.405879)
			(xy 73.902109 -111.349056) (xy 73.902106 -111.291582) (xy 73.910725 -111.234758) (xy 73.927769 -111.17987)
			(xy 73.952854 -111.128159) (xy 73.985411 -111.080796) (xy 74.004678 -111.059468) (xy 74.011282 -111.05261)
			(xy 74.018394 -111.034576) (xy 74.018394 -110.945676) (xy 74.011282 -110.927642) (xy 74.004678 -110.920784)
			(xy 73.985435 -110.899434) (xy 73.952873 -110.852074) (xy 73.927783 -110.800366) (xy 73.910733 -110.745479)
			(xy 73.902109 -110.688656) (xy 73.902106 -110.631182) (xy 73.910725 -110.574358) (xy 73.927769 -110.51947)
			(xy 73.952854 -110.467759) (xy 73.985411 -110.420396) (xy 74.004678 -110.399068) (xy 74.011282 -110.39221)
			(xy 74.018394 -110.374176) (xy 74.018394 -110.285276) (xy 74.011282 -110.267242) (xy 74.004678 -110.260384)
			(xy 73.985435 -110.239034) (xy 73.952873 -110.191674) (xy 73.927783 -110.139966) (xy 73.910733 -110.085079)
			(xy 73.902109 -110.028256) (xy 73.902106 -109.970782) (xy 73.910725 -109.913958) (xy 73.927769 -109.85907)
			(xy 73.952854 -109.807359) (xy 73.985411 -109.759996) (xy 74.004678 -109.738668) (xy 74.011282 -109.73181)
			(xy 74.018394 -109.713776) (xy 74.018394 -109.624876) (xy 74.011282 -109.606842) (xy 74.004678 -109.599984)
			(xy 73.985426 -109.57864) (xy 73.952856 -109.531284) (xy 73.927759 -109.479576) (xy 73.910704 -109.424689)
			(xy 73.902077 -109.367864) (xy 73.901554 -109.339126) (xy 73.902102 -109.311877) (xy 73.909854 -109.257934)
			(xy 73.925204 -109.205642) (xy 73.94784 -109.156068) (xy 73.9773 -109.110219) (xy 74.012984 -109.06903)
			(xy 74.054168 -109.033338) (xy 74.100012 -109.00387) (xy 74.149582 -108.981227) (xy 74.201871 -108.965868)
			(xy 74.255813 -108.958107) (xy 74.283062 -108.957618) (xy 74.309378 -108.958038) (xy 74.361508 -108.965282)
			(xy 74.412152 -108.97961) (xy 74.460351 -109.000751) (xy 74.505193 -109.028306) (xy 74.545831 -109.061753)
			(xy 74.563986 -109.080808) (xy 74.57151 -109.088206) (xy 74.590788 -109.096732) (xy 74.601324 -109.097318)
			(xy 74.676 -109.097318) (xy 74.686551 -109.096797) (xy 74.705845 -109.088256) (xy 74.713338 -109.080808)
			(xy 74.731484 -109.061743) (xy 74.772115 -109.028286) (xy 74.816958 -109.000728) (xy 74.86516 -108.979591)
			(xy 74.91581 -108.965276) (xy 74.967945 -108.958055) (xy 74.994262 -108.957618) (xy 75.021515 -108.958091)
			(xy 75.075467 -108.965843) (xy 75.127766 -108.981196) (xy 75.177348 -109.003836) (xy 75.223203 -109.033302)
			(xy 75.264396 -109.068995) (xy 75.300091 -109.110188) (xy 75.329559 -109.156041) (xy 75.3522 -109.205622)
			(xy 75.367554 -109.257921) (xy 75.375308 -109.311873) (xy 75.37577 -109.339126) (xy 75.375243 -109.367865)
			(xy 75.366619 -109.424691) (xy 75.349568 -109.479581) (xy 75.338473 -109.502448) (xy 109.414562 -109.502448)
			(xy 109.418633 -109.446826) (xy 109.430759 -109.392389) (xy 109.450682 -109.340298) (xy 109.477978 -109.291663)
			(xy 109.512064 -109.24752) (xy 109.552213 -109.208811) (xy 109.597571 -109.17636) (xy 109.647171 -109.150859)
			(xy 109.699955 -109.132852) (xy 109.754798 -109.122722) (xy 109.810532 -109.120685) (xy 109.865969 -109.126785)
			(xy 109.919926 -109.140891) (xy 109.971255 -109.162703) (xy 110.018861 -109.191757) (xy 110.061729 -109.227432)
			(xy 110.098946 -109.268969) (xy 110.129719 -109.315482) (xy 110.153391 -109.365979) (xy 110.169459 -109.419386)
			(xy 110.177579 -109.474562) (xy 110.178088 -109.502448) (xy 110.177579 -109.530334) (xy 110.169459 -109.58551)
			(xy 110.153391 -109.638917) (xy 110.129719 -109.689414) (xy 110.098946 -109.735927) (xy 110.061729 -109.777464)
			(xy 110.018861 -109.813139) (xy 109.971255 -109.842193) (xy 109.919926 -109.864005) (xy 109.865969 -109.878111)
			(xy 109.810532 -109.884211) (xy 109.754798 -109.882174) (xy 109.699955 -109.872044) (xy 109.647171 -109.854037)
			(xy 109.597571 -109.828536) (xy 109.552213 -109.796085) (xy 109.512064 -109.757376) (xy 109.477978 -109.713233)
			(xy 109.450682 -109.664598) (xy 109.430759 -109.612507) (xy 109.418633 -109.55807) (xy 109.414562 -109.502448)
			(xy 75.338473 -109.502448) (xy 75.324478 -109.531293) (xy 75.291915 -109.578656) (xy 75.272646 -109.599984)
			(xy 75.266042 -109.606842) (xy 75.25893 -109.624876) (xy 75.25893 -109.713776) (xy 75.266042 -109.73181)
			(xy 75.272646 -109.738668) (xy 75.291944 -109.759972) (xy 75.324511 -109.807337) (xy 75.349603 -109.859053)
			(xy 75.366653 -109.913947) (xy 75.375273 -109.970778) (xy 75.375271 -110.02826) (xy 75.366644 -110.08509)
			(xy 75.349589 -110.139983) (xy 75.324492 -110.191696) (xy 75.29192 -110.239058) (xy 75.272646 -110.260384)
			(xy 75.266042 -110.267242) (xy 75.25893 -110.285276) (xy 75.25893 -110.374176) (xy 75.266042 -110.39221)
			(xy 75.272646 -110.399068) (xy 75.291944 -110.420372) (xy 75.324511 -110.467737) (xy 75.349603 -110.519453)
			(xy 75.366653 -110.574347) (xy 75.373816 -110.621572) (xy 90.56116 -110.621572) (xy 90.56159 -110.595257)
			(xy 90.568829 -110.543126) (xy 90.583155 -110.492481) (xy 90.604294 -110.444282) (xy 90.631848 -110.39944)
			(xy 90.665294 -110.358803) (xy 90.68435 -110.340648) (xy 90.691769 -110.333141) (xy 90.700285 -110.31385)
			(xy 90.70086 -110.30331) (xy 90.70086 -110.228634) (xy 90.700338 -110.218083) (xy 90.691799 -110.198787)
			(xy 90.68435 -110.191296) (xy 90.66529 -110.173145) (xy 90.631835 -110.132513) (xy 90.604278 -110.087672)
			(xy 90.583141 -110.03947) (xy 90.568824 -109.988822) (xy 90.561599 -109.936688) (xy 90.56116 -109.910372)
			(xy 90.561646 -109.883121) (xy 90.569402 -109.829173) (xy 90.584757 -109.776878) (xy 90.607399 -109.727301)
			(xy 90.636865 -109.681451) (xy 90.672556 -109.64026) (xy 90.713747 -109.604569) (xy 90.759597 -109.575103)
			(xy 90.809174 -109.552461) (xy 90.861469 -109.537106) (xy 90.915417 -109.52935) (xy 90.969919 -109.52935)
			(xy 91.023867 -109.537106) (xy 91.076162 -109.552461) (xy 91.125739 -109.575103) (xy 91.171589 -109.604569)
			(xy 91.21278 -109.64026) (xy 91.248471 -109.681451) (xy 91.277937 -109.727301) (xy 91.300579 -109.776878)
			(xy 91.315934 -109.829173) (xy 91.32369 -109.883121) (xy 91.324176 -109.910372) (xy 91.323764 -109.936688)
			(xy 91.316519 -109.988819) (xy 91.30219 -110.039463) (xy 91.281047 -110.087662) (xy 91.253491 -110.132504)
			(xy 91.220042 -110.173141) (xy 91.200986 -110.191296) (xy 91.193582 -110.198815) (xy 91.185059 -110.218097)
			(xy 91.184476 -110.228634) (xy 91.184476 -110.30331) (xy 91.184993 -110.313861) (xy 91.193538 -110.333156)
			(xy 91.200986 -110.340648) (xy 91.220055 -110.35879) (xy 91.253512 -110.399422) (xy 91.281069 -110.444265)
			(xy 91.302205 -110.492469) (xy 91.316519 -110.543119) (xy 91.32374 -110.595255) (xy 91.324176 -110.621572)
			(xy 91.32369 -110.648823) (xy 91.315934 -110.702771) (xy 91.300579 -110.755066) (xy 91.277937 -110.804643)
			(xy 91.248471 -110.850493) (xy 91.21278 -110.891684) (xy 91.171589 -110.927375) (xy 91.125739 -110.956841)
			(xy 91.076162 -110.979483) (xy 91.023867 -110.994838) (xy 90.969919 -111.002594) (xy 90.915417 -111.002594)
			(xy 90.861469 -110.994838) (xy 90.809174 -110.979483) (xy 90.759597 -110.956841) (xy 90.713747 -110.927375)
			(xy 90.672556 -110.891684) (xy 90.636865 -110.850493) (xy 90.607399 -110.804643) (xy 90.584757 -110.755066)
			(xy 90.569402 -110.702771) (xy 90.561646 -110.648823) (xy 90.56116 -110.621572) (xy 75.373816 -110.621572)
			(xy 75.375273 -110.631178) (xy 75.375271 -110.68866) (xy 75.366644 -110.74549) (xy 75.349589 -110.800383)
			(xy 75.324492 -110.852096) (xy 75.29192 -110.899458) (xy 75.272646 -110.920784) (xy 75.266042 -110.927642)
			(xy 75.25893 -110.945676) (xy 75.25893 -111.034576) (xy 75.266042 -111.05261) (xy 75.272646 -111.059468)
			(xy 75.291944 -111.080772) (xy 75.324511 -111.128137) (xy 75.349603 -111.179853) (xy 75.366653 -111.234747)
			(xy 75.375273 -111.291578) (xy 75.375271 -111.34906) (xy 75.366644 -111.40589) (xy 75.349589 -111.460783)
			(xy 75.324492 -111.512496) (xy 75.29192 -111.559858) (xy 75.272646 -111.581184) (xy 75.266042 -111.588042)
			(xy 75.25893 -111.606076) (xy 75.25893 -111.694976) (xy 75.266042 -111.71301) (xy 75.272646 -111.719868)
			(xy 75.291926 -111.741187) (xy 75.324492 -111.788551) (xy 75.349583 -111.840264) (xy 75.366631 -111.895157)
			(xy 75.375251 -111.951986) (xy 75.37577 -111.980726) (xy 75.375369 -112.007981) (xy 75.367608 -112.061936)
			(xy 75.352246 -112.114238) (xy 75.329598 -112.163821) (xy 75.300124 -112.209676) (xy 75.264424 -112.250869)
			(xy 75.223224 -112.286562) (xy 75.205466 -112.297972) (xy 93.069918 -112.297972) (xy 93.070361 -112.271657)
			(xy 93.0776 -112.219527) (xy 93.091924 -112.168884) (xy 93.113061 -112.120685) (xy 93.140611 -112.075842)
			(xy 93.174054 -112.035204) (xy 93.193108 -112.017048) (xy 93.200536 -112.009549) (xy 93.209045 -111.990252)
			(xy 93.209618 -111.97971) (xy 93.209618 -111.905034) (xy 93.209079 -111.894486) (xy 93.20055 -111.875191)
			(xy 93.193108 -111.867696) (xy 93.174059 -111.849534) (xy 93.140601 -111.808906) (xy 93.113041 -111.764067)
			(xy 93.091901 -111.715867) (xy 93.077583 -111.665221) (xy 93.070357 -111.613088) (xy 93.069918 -111.586772)
			(xy 93.070404 -111.559521) (xy 93.07816 -111.505573) (xy 93.093515 -111.453278) (xy 93.116157 -111.403701)
			(xy 93.145623 -111.357851) (xy 93.181314 -111.31666) (xy 93.222505 -111.280969) (xy 93.268355 -111.251503)
			(xy 93.317932 -111.228861) (xy 93.370227 -111.213506) (xy 93.424175 -111.20575) (xy 93.478677 -111.20575)
			(xy 93.532625 -111.213506) (xy 93.58492 -111.228861) (xy 93.634497 -111.251503) (xy 93.680347 -111.280969)
			(xy 93.721538 -111.31666) (xy 93.757229 -111.357851) (xy 93.786695 -111.403701) (xy 93.809337 -111.453278)
			(xy 93.824692 -111.505573) (xy 93.832448 -111.559521) (xy 93.832934 -111.586772) (xy 93.832504 -111.613087)
			(xy 93.82526 -111.665217) (xy 93.810933 -111.71586) (xy 93.789793 -111.764058) (xy 93.762241 -111.808901)
			(xy 93.728798 -111.84954) (xy 93.709744 -111.867696) (xy 93.702349 -111.875223) (xy 93.693819 -111.894499)
			(xy 93.693234 -111.905034) (xy 93.693234 -111.97971) (xy 93.693734 -111.990263) (xy 93.702289 -112.009559)
			(xy 93.709744 -112.017048) (xy 93.728824 -112.035179) (xy 93.762277 -112.075815) (xy 93.789832 -112.12066)
			(xy 93.810966 -112.168866) (xy 93.825278 -112.219517) (xy 93.832498 -112.271655) (xy 93.832934 -112.297972)
			(xy 95.101918 -112.297972) (xy 95.102361 -112.271657) (xy 95.1096 -112.219527) (xy 95.123924 -112.168884)
			(xy 95.145061 -112.120685) (xy 95.172611 -112.075842) (xy 95.206054 -112.035204) (xy 95.225108 -112.017048)
			(xy 95.232536 -112.009549) (xy 95.241045 -111.990252) (xy 95.241618 -111.97971) (xy 95.241618 -111.905034)
			(xy 95.241079 -111.894486) (xy 95.23255 -111.875191) (xy 95.225108 -111.867696) (xy 95.206059 -111.849534)
			(xy 95.172601 -111.808906) (xy 95.145041 -111.764067) (xy 95.123901 -111.715867) (xy 95.109583 -111.665221)
			(xy 95.102357 -111.613088) (xy 95.101918 -111.586772) (xy 95.102404 -111.559521) (xy 95.11016 -111.505573)
			(xy 95.125515 -111.453278) (xy 95.148157 -111.403701) (xy 95.177623 -111.357851) (xy 95.213314 -111.31666)
			(xy 95.254505 -111.280969) (xy 95.300355 -111.251503) (xy 95.349932 -111.228861) (xy 95.402227 -111.213506)
			(xy 95.456175 -111.20575) (xy 95.510677 -111.20575) (xy 95.564625 -111.213506) (xy 95.61692 -111.228861)
			(xy 95.666497 -111.251503) (xy 95.712347 -111.280969) (xy 95.753538 -111.31666) (xy 95.789229 -111.357851)
			(xy 95.818695 -111.403701) (xy 95.841337 -111.453278) (xy 95.856692 -111.505573) (xy 95.864448 -111.559521)
			(xy 95.864934 -111.586772) (xy 95.864504 -111.613087) (xy 95.85726 -111.665217) (xy 95.842933 -111.71586)
			(xy 95.821793 -111.764058) (xy 95.794241 -111.808901) (xy 95.760798 -111.84954) (xy 95.741744 -111.867696)
			(xy 95.734349 -111.875223) (xy 95.725819 -111.894499) (xy 95.725234 -111.905034) (xy 95.725234 -111.97971)
			(xy 95.725734 -111.990263) (xy 95.734289 -112.009559) (xy 95.741744 -112.017048) (xy 95.760824 -112.035179)
			(xy 95.762829 -112.037615) (xy 97.556142 -112.037615) (xy 97.560456 -111.980343) (xy 97.573304 -111.924365)
			(xy 97.594396 -111.870944) (xy 97.623255 -111.821288) (xy 97.65923 -111.776517) (xy 97.680018 -111.756698)
			(xy 97.687425 -111.749182) (xy 97.695946 -111.729897) (xy 97.696528 -111.71936) (xy 97.696528 -111.644684)
			(xy 97.696013 -111.634133) (xy 97.687467 -111.614838) (xy 97.680018 -111.607346) (xy 97.660947 -111.589206)
			(xy 97.62749 -111.548573) (xy 97.599933 -111.50373) (xy 97.578797 -111.455526) (xy 97.564484 -111.404876)
			(xy 97.557264 -111.352739) (xy 97.556828 -111.326422) (xy 97.557314 -111.299171) (xy 97.56507 -111.245223)
			(xy 97.580425 -111.192928) (xy 97.603067 -111.143351) (xy 97.632533 -111.097501) (xy 97.668224 -111.05631)
			(xy 97.709415 -111.020619) (xy 97.755265 -110.991153) (xy 97.804842 -110.968511) (xy 97.857137 -110.953156)
			(xy 97.911085 -110.9454) (xy 97.965587 -110.9454) (xy 98.019535 -110.953156) (xy 98.07183 -110.968511)
			(xy 98.121407 -110.991153) (xy 98.167257 -111.020619) (xy 98.208448 -111.05631) (xy 98.244139 -111.097501)
			(xy 98.273605 -111.143351) (xy 98.296247 -111.192928) (xy 98.311602 -111.245223) (xy 98.319358 -111.299171)
			(xy 98.319844 -111.326422) (xy 98.319409 -111.352737) (xy 98.31217 -111.404868) (xy 98.297846 -111.455512)
			(xy 98.276707 -111.503711) (xy 98.249155 -111.548554) (xy 98.215709 -111.589191) (xy 98.196654 -111.607346)
			(xy 98.189238 -111.614856) (xy 98.18072 -111.634144) (xy 98.180144 -111.644684) (xy 98.180144 -111.71936)
			(xy 98.180668 -111.729911) (xy 98.189206 -111.749207) (xy 98.196654 -111.756698) (xy 98.217462 -111.776497)
			(xy 98.253434 -111.821274) (xy 98.28229 -111.870935) (xy 98.303379 -111.924359) (xy 98.316226 -111.980341)
			(xy 98.320539 -112.037615) (xy 100.09439 -112.037615) (xy 100.098702 -111.980346) (xy 100.111547 -111.924369)
			(xy 100.132634 -111.87095) (xy 100.161488 -111.821292) (xy 100.197456 -111.776519) (xy 100.21824 -111.756698)
			(xy 100.225636 -111.749171) (xy 100.234165 -111.729895) (xy 100.23475 -111.71936) (xy 100.23475 -111.644684)
			(xy 100.234228 -111.634134) (xy 100.225686 -111.614839) (xy 100.21824 -111.607346) (xy 100.199154 -111.589222)
			(xy 100.165702 -111.548584) (xy 100.138148 -111.503737) (xy 100.117016 -111.45553) (xy 100.102704 -111.404878)
			(xy 100.095486 -111.35274) (xy 100.09505 -111.326422) (xy 100.095536 -111.299171) (xy 100.103292 -111.245223)
			(xy 100.118647 -111.192928) (xy 100.141289 -111.143351) (xy 100.170755 -111.097501) (xy 100.206446 -111.05631)
			(xy 100.247637 -111.020619) (xy 100.293487 -110.991153) (xy 100.343064 -110.968511) (xy 100.395359 -110.953156)
			(xy 100.449307 -110.9454) (xy 100.503809 -110.9454) (xy 100.557757 -110.953156) (xy 100.610052 -110.968511)
			(xy 100.659629 -110.991153) (xy 100.705479 -111.020619) (xy 100.74667 -111.05631) (xy 100.782361 -111.097501)
			(xy 100.811827 -111.143351) (xy 100.834469 -111.192928) (xy 100.849824 -111.245223) (xy 100.85758 -111.299171)
			(xy 100.858066 -111.326422) (xy 100.857624 -111.352737) (xy 100.850386 -111.404867) (xy 100.836062 -111.455511)
			(xy 100.814925 -111.50371) (xy 100.787374 -111.548553) (xy 100.75393 -111.589191) (xy 100.734876 -111.607346)
			(xy 100.727463 -111.614859) (xy 100.718942 -111.634145) (xy 100.718366 -111.644684) (xy 100.718366 -111.71936)
			(xy 100.718913 -111.729907) (xy 100.727437 -111.749202) (xy 100.734876 -111.756698) (xy 100.755688 -111.776495)
			(xy 100.791667 -111.821269) (xy 100.820529 -111.87093) (xy 100.841623 -111.924355) (xy 100.854472 -111.980338)
			(xy 100.855495 -111.993923) (xy 104.297324 -111.993923) (xy 104.301636 -111.936654) (xy 104.314481 -111.880678)
			(xy 104.335569 -111.827258) (xy 104.364423 -111.777602) (xy 104.400393 -111.73283) (xy 104.421178 -111.71301)
			(xy 104.428574 -111.705484) (xy 104.437102 -111.686207) (xy 104.437688 -111.675672) (xy 104.437688 -111.600996)
			(xy 104.437178 -111.590444) (xy 104.42863 -111.571149) (xy 104.421178 -111.563658) (xy 104.400424 -111.543804)
			(xy 104.364449 -111.499036) (xy 104.335589 -111.449383) (xy 104.314494 -111.395966) (xy 104.301643 -111.339992)
			(xy 104.297324 -111.282723) (xy 104.301636 -111.225454) (xy 104.314481 -111.169478) (xy 104.335569 -111.116058)
			(xy 104.364423 -111.066402) (xy 104.400393 -111.02163) (xy 104.421178 -111.00181) (xy 104.428574 -110.994284)
			(xy 104.437102 -110.975007) (xy 104.437688 -110.964472) (xy 104.437688 -110.889796) (xy 104.437178 -110.879244)
			(xy 104.42863 -110.859949) (xy 104.421178 -110.852458) (xy 104.402105 -110.83432) (xy 104.36865 -110.793686)
			(xy 104.341094 -110.748842) (xy 104.319959 -110.700638) (xy 104.305645 -110.649987) (xy 104.298424 -110.597851)
			(xy 104.297988 -110.571534) (xy 104.298487 -110.544282) (xy 104.306239 -110.490333) (xy 104.321591 -110.438036)
			(xy 104.344229 -110.388456) (xy 104.373693 -110.342603) (xy 104.409383 -110.30141) (xy 104.450572 -110.265716)
			(xy 104.496423 -110.236247) (xy 104.546 -110.213604) (xy 104.598296 -110.198247) (xy 104.652244 -110.19049)
			(xy 104.679496 -110.190026) (xy 104.70581 -110.190488) (xy 104.757939 -110.197723) (xy 104.808583 -110.212042)
			(xy 104.856782 -110.233176) (xy 104.901625 -110.260723) (xy 104.942264 -110.294164) (xy 104.96042 -110.313216)
			(xy 104.96793 -110.320631) (xy 104.987219 -110.329147) (xy 104.997758 -110.329726) (xy 105.072434 -110.329726)
			(xy 105.08298 -110.329167) (xy 105.102275 -110.320652) (xy 105.109772 -110.313216) (xy 105.127951 -110.294184)
			(xy 105.168576 -110.260724) (xy 105.213411 -110.233162) (xy 105.261607 -110.212019) (xy 105.31225 -110.197697)
			(xy 105.364381 -110.190467) (xy 105.390696 -110.190026) (xy 105.41795 -110.190459) (xy 105.471904 -110.198216)
			(xy 105.524205 -110.213574) (xy 105.573787 -110.236218) (xy 105.613417 -110.261688) (xy 106.914421 -110.261688)
			(xy 106.914421 -110.209712) (xy 106.922553 -110.158377) (xy 106.938615 -110.108946) (xy 106.962213 -110.062636)
			(xy 106.992766 -110.020588) (xy 107.02952 -109.983839) (xy 107.071572 -109.953291) (xy 107.117884 -109.929699)
			(xy 107.167318 -109.913643) (xy 107.218654 -109.905518) (xy 107.244642 -109.905038) (xy 107.271287 -109.905526)
			(xy 107.323889 -109.914057) (xy 107.374439 -109.930922) (xy 107.421625 -109.955684) (xy 107.464224 -109.987701)
			(xy 107.50113 -110.026141) (xy 107.516676 -110.047786) (xy 107.52504 -110.059072) (xy 107.546713 -110.076927)
			(xy 107.572427 -110.08821) (xy 107.600242 -110.092068) (xy 107.628057 -110.08821) (xy 107.653771 -110.076927)
			(xy 107.675444 -110.059072) (xy 107.683808 -110.047786) (xy 107.699397 -110.026178) (xy 107.73631 -109.987761)
			(xy 107.778906 -109.95576) (xy 107.826082 -109.931002) (xy 107.876617 -109.914129) (xy 107.929203 -109.905578)
			(xy 107.955842 -109.905038) (xy 107.981831 -109.905459) (xy 108.033167 -109.913596) (xy 108.082599 -109.929663)
			(xy 108.128909 -109.953264) (xy 108.170957 -109.983819) (xy 108.207709 -110.020575) (xy 108.238258 -110.062627)
			(xy 108.261853 -110.10894) (xy 108.277914 -110.158374) (xy 108.286044 -110.209711) (xy 108.286044 -110.261689)
			(xy 108.277914 -110.313026) (xy 108.261853 -110.36246) (xy 108.238258 -110.408773) (xy 108.207709 -110.450825)
			(xy 108.170957 -110.487581) (xy 108.132325 -110.515654) (xy 110.828072 -110.515654) (xy 110.832143 -110.460032)
			(xy 110.844269 -110.405595) (xy 110.864192 -110.353504) (xy 110.891488 -110.304869) (xy 110.925574 -110.260726)
			(xy 110.965723 -110.222017) (xy 111.011081 -110.189566) (xy 111.060681 -110.164065) (xy 111.113465 -110.146058)
			(xy 111.168308 -110.135928) (xy 111.224042 -110.133891) (xy 111.279479 -110.139991) (xy 111.333436 -110.154097)
			(xy 111.384765 -110.175909) (xy 111.432371 -110.204963) (xy 111.475239 -110.240638) (xy 111.512456 -110.282175)
			(xy 111.543229 -110.328688) (xy 111.566901 -110.379185) (xy 111.582969 -110.432592) (xy 111.591089 -110.487768)
			(xy 111.591598 -110.515654) (xy 111.591089 -110.54354) (xy 111.582969 -110.598716) (xy 111.566901 -110.652123)
			(xy 111.543229 -110.70262) (xy 111.512456 -110.749133) (xy 111.475239 -110.79067) (xy 111.432371 -110.826345)
			(xy 111.384765 -110.855399) (xy 111.333436 -110.877211) (xy 111.279479 -110.891317) (xy 111.224042 -110.897417)
			(xy 111.168308 -110.89538) (xy 111.113465 -110.88525) (xy 111.060681 -110.867243) (xy 111.011081 -110.841742)
			(xy 110.965723 -110.809291) (xy 110.925574 -110.770582) (xy 110.891488 -110.726439) (xy 110.864192 -110.677804)
			(xy 110.844269 -110.625713) (xy 110.832143 -110.571276) (xy 110.828072 -110.515654) (xy 108.132325 -110.515654)
			(xy 108.128909 -110.518136) (xy 108.082599 -110.541737) (xy 108.033167 -110.557804) (xy 107.981831 -110.565941)
			(xy 107.955842 -110.566454) (xy 107.929197 -110.565981) (xy 107.876594 -110.557448) (xy 107.826043 -110.54058)
			(xy 107.778857 -110.515815) (xy 107.736259 -110.483795) (xy 107.699354 -110.445352) (xy 107.683808 -110.423706)
			(xy 107.675444 -110.41242) (xy 107.653771 -110.394565) (xy 107.628057 -110.383282) (xy 107.600242 -110.379424)
			(xy 107.572427 -110.383282) (xy 107.546713 -110.394565) (xy 107.52504 -110.41242) (xy 107.516676 -110.423706)
			(xy 107.501095 -110.44532) (xy 107.46418 -110.483737) (xy 107.421583 -110.515738) (xy 107.374405 -110.540494)
			(xy 107.323869 -110.557366) (xy 107.271281 -110.565916) (xy 107.244642 -110.566454) (xy 107.218654 -110.565882)
			(xy 107.167318 -110.557757) (xy 107.117884 -110.541701) (xy 107.071572 -110.518109) (xy 107.02952 -110.487561)
			(xy 106.992766 -110.450812) (xy 106.962213 -110.408764) (xy 106.938615 -110.362454) (xy 106.922553 -110.313023)
			(xy 106.914421 -110.261688) (xy 105.613417 -110.261688) (xy 105.619642 -110.265689) (xy 105.660835 -110.301386)
			(xy 105.696529 -110.342582) (xy 105.725996 -110.388439) (xy 105.748637 -110.438024) (xy 105.76399 -110.490325)
			(xy 105.771743 -110.54428) (xy 105.772204 -110.571534) (xy 105.771758 -110.597849) (xy 105.764519 -110.649978)
			(xy 105.750195 -110.700621) (xy 105.729059 -110.74882) (xy 105.701509 -110.793663) (xy 105.668067 -110.834302)
			(xy 105.649014 -110.852458) (xy 105.641631 -110.859995) (xy 105.633095 -110.879263) (xy 105.632504 -110.889796)
			(xy 105.632504 -110.964472) (xy 105.633034 -110.975022) (xy 105.641568 -110.994317) (xy 105.649014 -111.00181)
			(xy 105.669836 -111.021596) (xy 105.705811 -111.066373) (xy 105.73467 -111.116036) (xy 105.752772 -111.16189)
			(xy 106.914397 -111.16189) (xy 106.914397 -111.10991) (xy 106.922529 -111.058571) (xy 106.938593 -111.009136)
			(xy 106.962193 -110.962823) (xy 106.992748 -110.920773) (xy 107.029505 -110.88402) (xy 107.071559 -110.853471)
			(xy 107.117875 -110.829877) (xy 107.167312 -110.813819) (xy 107.218652 -110.805694) (xy 107.244642 -110.805214)
			(xy 107.271286 -110.805713) (xy 107.323887 -110.814242) (xy 107.374436 -110.831106) (xy 107.421622 -110.855866)
			(xy 107.464222 -110.887881) (xy 107.501129 -110.926319) (xy 107.516676 -110.947962) (xy 107.52504 -110.959248)
			(xy 107.546713 -110.977103) (xy 107.572427 -110.988386) (xy 107.600242 -110.992244) (xy 107.628057 -110.988386)
			(xy 107.653771 -110.977103) (xy 107.675444 -110.959248) (xy 107.683808 -110.947962) (xy 107.69939 -110.926349)
			(xy 107.736306 -110.887933) (xy 107.778903 -110.855933) (xy 107.82608 -110.831177) (xy 107.876616 -110.814305)
			(xy 107.929203 -110.805754) (xy 107.955842 -110.805214) (xy 107.981829 -110.805683) (xy 108.033162 -110.813819)
			(xy 108.08259 -110.829885) (xy 108.128897 -110.853484) (xy 108.170942 -110.884037) (xy 108.20769 -110.92079)
			(xy 108.238238 -110.962839) (xy 108.261831 -111.009149) (xy 108.277891 -111.058579) (xy 108.286021 -111.109913)
			(xy 108.286021 -111.161887) (xy 108.277891 -111.213221) (xy 108.261831 -111.262651) (xy 108.238238 -111.308961)
			(xy 108.20769 -111.35101) (xy 108.170942 -111.387763) (xy 108.128897 -111.418316) (xy 108.08259 -111.441915)
			(xy 108.033162 -111.457981) (xy 107.981829 -111.466117) (xy 107.955842 -111.46663) (xy 107.929196 -111.466167)
			(xy 107.876592 -111.457633) (xy 107.826041 -111.440764) (xy 107.778855 -111.415997) (xy 107.736257 -111.383975)
			(xy 107.699353 -111.345529) (xy 107.683808 -111.323882) (xy 107.675444 -111.312596) (xy 107.653771 -111.294741)
			(xy 107.628057 -111.283458) (xy 107.600242 -111.2796) (xy 107.572427 -111.283458) (xy 107.546713 -111.294741)
			(xy 107.52504 -111.312596) (xy 107.516676 -111.323882) (xy 107.501117 -111.345512) (xy 107.464195 -111.383925)
			(xy 107.421592 -111.415922) (xy 107.374411 -111.440675) (xy 107.323872 -111.457543) (xy 107.271282 -111.466092)
			(xy 107.244642 -111.46663) (xy 107.218652 -111.466106) (xy 107.167312 -111.457981) (xy 107.117875 -111.441923)
			(xy 107.071559 -111.418329) (xy 107.029505 -111.38778) (xy 106.992748 -111.351027) (xy 106.962193 -111.308977)
			(xy 106.938593 -111.262664) (xy 106.922529 -111.213229) (xy 106.914397 -111.16189) (xy 105.752772 -111.16189)
			(xy 105.755761 -111.169462) (xy 105.768608 -111.225446) (xy 105.77292 -111.282723) (xy 105.768601 -111.339999)
			(xy 105.755748 -111.395982) (xy 105.73465 -111.449406) (xy 105.705785 -111.499065) (xy 105.669805 -111.543838)
			(xy 105.649014 -111.563658) (xy 105.641631 -111.571195) (xy 105.633095 -111.590463) (xy 105.632504 -111.600996)
			(xy 105.632504 -111.675672) (xy 105.633034 -111.686222) (xy 105.641568 -111.705517) (xy 105.649014 -111.71301)
			(xy 105.669836 -111.732796) (xy 105.705811 -111.777573) (xy 105.73467 -111.827236) (xy 105.755761 -111.880662)
			(xy 105.768608 -111.936646) (xy 105.77292 -111.993923) (xy 105.768601 -112.051199) (xy 105.76617 -112.061788)
			(xy 106.914419 -112.061788) (xy 106.914419 -112.009812) (xy 106.922551 -111.958476) (xy 106.938613 -111.909045)
			(xy 106.962212 -111.862735) (xy 106.992764 -111.820687) (xy 107.029519 -111.783937) (xy 107.071571 -111.75339)
			(xy 107.117884 -111.729797) (xy 107.167317 -111.713741) (xy 107.218654 -111.705616) (xy 107.244642 -111.705136)
			(xy 107.271287 -111.705625) (xy 107.323888 -111.714156) (xy 107.374438 -111.73102) (xy 107.421625 -111.755782)
			(xy 107.464224 -111.787799) (xy 107.501129 -111.826239) (xy 107.516676 -111.847884) (xy 107.52504 -111.85917)
			(xy 107.546713 -111.877025) (xy 107.572427 -111.888308) (xy 107.600242 -111.892166) (xy 107.628057 -111.888308)
			(xy 107.653771 -111.877025) (xy 107.675444 -111.85917) (xy 107.683808 -111.847884) (xy 107.699396 -111.826275)
			(xy 107.73631 -111.787859) (xy 107.778906 -111.755857) (xy 107.826082 -111.7311) (xy 107.876617 -111.714227)
			(xy 107.929203 -111.705676) (xy 107.955842 -111.705136) (xy 107.98183 -111.705561) (xy 108.033167 -111.713698)
			(xy 108.082598 -111.729765) (xy 108.128908 -111.753366) (xy 108.170956 -111.78392) (xy 108.17269 -111.785654)
			(xy 109.457742 -111.785654) (xy 109.461813 -111.730032) (xy 109.473939 -111.675595) (xy 109.493862 -111.623504)
			(xy 109.521158 -111.574869) (xy 109.555244 -111.530726) (xy 109.595393 -111.492017) (xy 109.640751 -111.459566)
			(xy 109.690351 -111.434065) (xy 109.743135 -111.416058) (xy 109.797978 -111.405928) (xy 109.853712 -111.403891)
			(xy 109.909149 -111.409991) (xy 109.963106 -111.424097) (xy 110.014435 -111.445909) (xy 110.062041 -111.474963)
			(xy 110.104909 -111.510638) (xy 110.142126 -111.552175) (xy 110.172899 -111.598688) (xy 110.196571 -111.649185)
			(xy 110.212639 -111.702592) (xy 110.220759 -111.757768) (xy 110.221268 -111.785654) (xy 110.220759 -111.81354)
			(xy 110.212639 -111.868716) (xy 110.196571 -111.922123) (xy 110.172899 -111.97262) (xy 110.142126 -112.019133)
			(xy 110.104909 -112.06067) (xy 110.062041 -112.096345) (xy 110.014435 -112.125399) (xy 109.963106 -112.147211)
			(xy 109.909149 -112.161317) (xy 109.853712 -112.167417) (xy 109.797978 -112.16538) (xy 109.743135 -112.15525)
			(xy 109.690351 -112.137243) (xy 109.640751 -112.111742) (xy 109.595393 -112.079291) (xy 109.555244 -112.040582)
			(xy 109.521158 -111.996439) (xy 109.493862 -111.947804) (xy 109.473939 -111.895713) (xy 109.461813 -111.841276)
			(xy 109.457742 -111.785654) (xy 108.17269 -111.785654) (xy 108.207707 -111.820676) (xy 108.238256 -111.862728)
			(xy 108.261852 -111.909041) (xy 108.277912 -111.958474) (xy 108.286042 -112.009811) (xy 108.286042 -112.061789)
			(xy 108.277912 -112.113126) (xy 108.261852 -112.162559) (xy 108.238256 -112.208872) (xy 108.207707 -112.250924)
			(xy 108.170956 -112.28768) (xy 108.15819 -112.296956) (xy 110.894874 -112.296956) (xy 110.898945 -112.241334)
			(xy 110.911071 -112.186897) (xy 110.930994 -112.134806) (xy 110.95829 -112.086171) (xy 110.992376 -112.042028)
			(xy 111.032525 -112.003319) (xy 111.077883 -111.970868) (xy 111.127483 -111.945367) (xy 111.180267 -111.92736)
			(xy 111.23511 -111.91723) (xy 111.290844 -111.915193) (xy 111.346281 -111.921293) (xy 111.400238 -111.935399)
			(xy 111.451567 -111.957211) (xy 111.499173 -111.986265) (xy 111.542041 -112.02194) (xy 111.579258 -112.063477)
			(xy 111.610031 -112.10999) (xy 111.633703 -112.160487) (xy 111.649771 -112.213894) (xy 111.657891 -112.26907)
			(xy 111.6584 -112.296956) (xy 111.657891 -112.324842) (xy 111.649771 -112.380018) (xy 111.633703 -112.433425)
			(xy 111.610031 -112.483922) (xy 111.579258 -112.530435) (xy 111.542041 -112.571972) (xy 111.499173 -112.607647)
			(xy 111.451567 -112.636701) (xy 111.400238 -112.658513) (xy 111.346281 -112.672619) (xy 111.290844 -112.678719)
			(xy 111.23511 -112.676682) (xy 111.180267 -112.666552) (xy 111.127483 -112.648545) (xy 111.077883 -112.623044)
			(xy 111.032525 -112.590593) (xy 110.992376 -112.551884) (xy 110.95829 -112.507741) (xy 110.930994 -112.459106)
			(xy 110.911071 -112.407015) (xy 110.898945 -112.352578) (xy 110.894874 -112.296956) (xy 108.15819 -112.296956)
			(xy 108.128908 -112.318234) (xy 108.082598 -112.341835) (xy 108.033167 -112.357902) (xy 107.98183 -112.366039)
			(xy 107.955842 -112.366552) (xy 107.929197 -112.36608) (xy 107.876594 -112.357547) (xy 107.826043 -112.340679)
			(xy 107.778857 -112.315913) (xy 107.736259 -112.283894) (xy 107.699354 -112.24545) (xy 107.683808 -112.223804)
			(xy 107.675444 -112.212518) (xy 107.653771 -112.194663) (xy 107.628057 -112.18338) (xy 107.600242 -112.179522)
			(xy 107.572427 -112.18338) (xy 107.546713 -112.194663) (xy 107.52504 -112.212518) (xy 107.516676 -112.223804)
			(xy 107.501094 -112.245417) (xy 107.46418 -112.283835) (xy 107.421582 -112.315836) (xy 107.374405 -112.340592)
			(xy 107.323869 -112.357464) (xy 107.271281 -112.366014) (xy 107.244642 -112.366552) (xy 107.218654 -112.365984)
			(xy 107.167317 -112.357859) (xy 107.117884 -112.341803) (xy 107.071571 -112.31821) (xy 107.029519 -112.287663)
			(xy 106.992764 -112.250913) (xy 106.962212 -112.208865) (xy 106.938613 -112.162555) (xy 106.922551 -112.113124)
			(xy 106.914419 -112.061788) (xy 105.76617 -112.061788) (xy 105.755748 -112.107182) (xy 105.73465 -112.160606)
			(xy 105.705785 -112.210265) (xy 105.669805 -112.255038) (xy 105.649014 -112.274858) (xy 105.641631 -112.282395)
			(xy 105.633095 -112.301663) (xy 105.632504 -112.312196) (xy 105.632504 -112.386872) (xy 105.633034 -112.397422)
			(xy 105.641568 -112.416717) (xy 105.649014 -112.42421) (xy 105.66807 -112.442365) (xy 105.701527 -112.482995)
			(xy 105.729085 -112.527836) (xy 105.750224 -112.576036) (xy 105.764541 -112.626684) (xy 105.771765 -112.678818)
			(xy 105.772204 -112.705134) (xy 105.771754 -112.732386) (xy 105.763993 -112.786335) (xy 105.748633 -112.838631)
			(xy 105.725988 -112.888209) (xy 105.696517 -112.934059) (xy 105.672482 -112.961794) (xy 106.914341 -112.961794)
			(xy 106.914341 -112.909806) (xy 106.922475 -112.858458) (xy 106.938541 -112.809015) (xy 106.962145 -112.762694)
			(xy 106.992705 -112.720636) (xy 107.029468 -112.683878) (xy 107.07153 -112.653323) (xy 107.117854 -112.629725)
			(xy 107.167299 -112.613665) (xy 107.218648 -112.605538) (xy 107.244642 -112.605058) (xy 107.271287 -112.605538)
			(xy 107.32389 -112.614069) (xy 107.37444 -112.630935) (xy 107.421627 -112.655699) (xy 107.464225 -112.687717)
			(xy 107.50113 -112.72616) (xy 107.516676 -112.747806) (xy 107.52504 -112.759092) (xy 107.546713 -112.776947)
			(xy 107.572427 -112.78823) (xy 107.600242 -112.792088) (xy 107.628057 -112.78823) (xy 107.653771 -112.776947)
			(xy 107.675444 -112.759092) (xy 107.683808 -112.747806) (xy 107.699373 -112.72618) (xy 107.736294 -112.687768)
			(xy 107.778896 -112.655771) (xy 107.826076 -112.631018) (xy 107.876614 -112.614148) (xy 107.929202 -112.605598)
			(xy 107.955842 -112.605058) (xy 107.981824 -112.605639) (xy 108.033148 -112.613774) (xy 108.082568 -112.629837)
			(xy 108.128867 -112.653432) (xy 108.170905 -112.68398) (xy 108.207648 -112.720727) (xy 108.23819 -112.762769)
			(xy 108.26178 -112.809071) (xy 108.277836 -112.858492) (xy 108.285965 -112.909818) (xy 108.285965 -112.961782)
			(xy 108.277836 -113.013108) (xy 108.26178 -113.062529) (xy 108.23819 -113.108831) (xy 108.207648 -113.150873)
			(xy 108.170905 -113.18762) (xy 108.128867 -113.218168) (xy 108.082568 -113.241763) (xy 108.033148 -113.257826)
			(xy 107.981824 -113.265961) (xy 107.955842 -113.266474) (xy 107.929197 -113.265992) (xy 107.876595 -113.25746)
			(xy 107.826045 -113.240593) (xy 107.778859 -113.21583) (xy 107.73626 -113.183812) (xy 107.699355 -113.145371)
			(xy 107.683808 -113.123726) (xy 107.675444 -113.11244) (xy 107.653771 -113.094585) (xy 107.628057 -113.083302)
			(xy 107.600242 -113.079444) (xy 107.572427 -113.083302) (xy 107.546713 -113.094585) (xy 107.52504 -113.11244)
			(xy 107.516676 -113.123726) (xy 107.501101 -113.145344) (xy 107.464184 -113.18376) (xy 107.421585 -113.21576)
			(xy 107.374407 -113.240516) (xy 107.32387 -113.257386) (xy 107.271281 -113.265936) (xy 107.244642 -113.266474)
			(xy 107.218648 -113.266062) (xy 107.167299 -113.257935) (xy 107.117854 -113.241875) (xy 107.07153 -113.218277)
			(xy 107.029468 -113.187722) (xy 106.992705 -113.150964) (xy 106.962145 -113.108906) (xy 106.938541 -113.062585)
			(xy 106.922475 -113.013142) (xy 106.914341 -112.961794) (xy 105.672482 -112.961794) (xy 105.660822 -112.975249)
			(xy 105.619629 -113.01094) (xy 105.573775 -113.040406) (xy 105.524195 -113.063046) (xy 105.471898 -113.078401)
			(xy 105.417948 -113.086157) (xy 105.390696 -113.086642) (xy 105.364381 -113.086196) (xy 105.312251 -113.078959)
			(xy 105.261607 -113.064637) (xy 105.213408 -113.043501) (xy 105.168565 -113.01595) (xy 105.127927 -112.982506)
			(xy 105.109772 -112.963452) (xy 105.102256 -112.956044) (xy 105.082972 -112.947521) (xy 105.072434 -112.946942)
			(xy 104.997758 -112.946942) (xy 104.987209 -112.947477) (xy 104.967912 -112.956007) (xy 104.96042 -112.963452)
			(xy 104.942258 -112.982501) (xy 104.901628 -113.015957) (xy 104.856789 -113.043515) (xy 104.80859 -113.064654)
			(xy 104.757944 -113.078974) (xy 104.705812 -113.086202) (xy 104.679496 -113.086642) (xy 104.652246 -113.086126)
			(xy 104.598301 -113.07837) (xy 104.546009 -113.063016) (xy 104.496434 -113.040377) (xy 104.450585 -113.010913)
			(xy 104.409396 -112.975225) (xy 104.373705 -112.934039) (xy 104.344238 -112.888192) (xy 104.321595 -112.838619)
			(xy 104.306237 -112.786328) (xy 104.298476 -112.732384) (xy 104.297988 -112.705134) (xy 104.298415 -112.678819)
			(xy 104.305659 -112.626689) (xy 104.319986 -112.576045) (xy 104.341126 -112.527847) (xy 104.368679 -112.483004)
			(xy 104.402124 -112.442366) (xy 104.421178 -112.42421) (xy 104.428574 -112.416684) (xy 104.437102 -112.397407)
			(xy 104.437688 -112.386872) (xy 104.437688 -112.312196) (xy 104.437178 -112.301644) (xy 104.42863 -112.282349)
			(xy 104.421178 -112.274858) (xy 104.400424 -112.255004) (xy 104.364449 -112.210236) (xy 104.335589 -112.160583)
			(xy 104.314494 -112.107166) (xy 104.301643 -112.051192) (xy 104.297324 -111.993923) (xy 100.855495 -111.993923)
			(xy 100.858786 -112.037615) (xy 100.854467 -112.094891) (xy 100.841614 -112.150873) (xy 100.820516 -112.204297)
			(xy 100.79165 -112.253956) (xy 100.755667 -112.298727) (xy 100.734876 -112.318546) (xy 100.727463 -112.326059)
			(xy 100.718942 -112.345345) (xy 100.718366 -112.355884) (xy 100.718366 -112.43056) (xy 100.718913 -112.441107)
			(xy 100.727437 -112.460402) (xy 100.734876 -112.467898) (xy 100.753919 -112.486066) (xy 100.787378 -112.526693)
			(xy 100.814939 -112.57153) (xy 100.83608 -112.619729) (xy 100.8504 -112.670374) (xy 100.857627 -112.722506)
			(xy 100.858066 -112.748822) (xy 100.85758 -112.776073) (xy 100.849824 -112.830021) (xy 100.834469 -112.882316)
			(xy 100.811827 -112.931893) (xy 100.782361 -112.977743) (xy 100.74667 -113.018934) (xy 100.705479 -113.054625)
			(xy 100.659629 -113.084091) (xy 100.610052 -113.106733) (xy 100.557757 -113.122088) (xy 100.503809 -113.129844)
			(xy 100.449307 -113.129844) (xy 100.395359 -113.122088) (xy 100.343064 -113.106733) (xy 100.293487 -113.084091)
			(xy 100.247637 -113.054625) (xy 100.206446 -113.018934) (xy 100.170755 -112.977743) (xy 100.141289 -112.931893)
			(xy 100.118647 -112.882316) (xy 100.103292 -112.830021) (xy 100.095536 -112.776073) (xy 100.09505 -112.748822)
			(xy 100.095516 -112.722508) (xy 100.102749 -112.670379) (xy 100.117067 -112.619735) (xy 100.1382 -112.571536)
			(xy 100.165747 -112.526693) (xy 100.199187 -112.486054) (xy 100.21824 -112.467898) (xy 100.225636 -112.460371)
			(xy 100.234165 -112.441095) (xy 100.23475 -112.43056) (xy 100.23475 -112.355884) (xy 100.234228 -112.345334)
			(xy 100.225686 -112.326039) (xy 100.21824 -112.318546) (xy 100.197476 -112.298703) (xy 100.161505 -112.253932)
			(xy 100.132647 -112.204277) (xy 100.111556 -112.150859) (xy 100.098707 -112.094884) (xy 100.09439 -112.037615)
			(xy 98.320539 -112.037615) (xy 98.316221 -112.094889) (xy 98.303371 -112.150869) (xy 98.282277 -112.204292)
			(xy 98.253417 -112.253951) (xy 98.217442 -112.298725) (xy 98.196654 -112.318546) (xy 98.189238 -112.326056)
			(xy 98.18072 -112.345344) (xy 98.180144 -112.355884) (xy 98.180144 -112.43056) (xy 98.180668 -112.441111)
			(xy 98.189206 -112.460407) (xy 98.196654 -112.467898) (xy 98.215712 -112.486051) (xy 98.249167 -112.526682)
			(xy 98.276724 -112.571524) (xy 98.297862 -112.619725) (xy 98.312179 -112.670372) (xy 98.319405 -112.722506)
			(xy 98.319844 -112.748822) (xy 98.319358 -112.776073) (xy 98.311602 -112.830021) (xy 98.296247 -112.882316)
			(xy 98.273605 -112.931893) (xy 98.244139 -112.977743) (xy 98.208448 -113.018934) (xy 98.167257 -113.054625)
			(xy 98.121407 -113.084091) (xy 98.07183 -113.106733) (xy 98.019535 -113.122088) (xy 97.965587 -113.129844)
			(xy 97.911085 -113.129844) (xy 97.857137 -113.122088) (xy 97.804842 -113.106733) (xy 97.755265 -113.084091)
			(xy 97.709415 -113.054625) (xy 97.668224 -113.018934) (xy 97.632533 -112.977743) (xy 97.603067 -112.931893)
			(xy 97.580425 -112.882316) (xy 97.56507 -112.830021) (xy 97.557314 -112.776073) (xy 97.556828 -112.748822)
			(xy 97.557301 -112.722508) (xy 97.564534 -112.67038) (xy 97.578851 -112.619737) (xy 97.599982 -112.571537)
			(xy 97.627528 -112.526694) (xy 97.660966 -112.486054) (xy 97.680018 -112.467898) (xy 97.687425 -112.460382)
			(xy 97.695946 -112.441097) (xy 97.696528 -112.43056) (xy 97.696528 -112.355884) (xy 97.696013 -112.345333)
			(xy 97.687467 -112.326038) (xy 97.680018 -112.318546) (xy 97.65925 -112.298705) (xy 97.623272 -112.253937)
			(xy 97.594409 -112.204283) (xy 97.573313 -112.150863) (xy 97.560461 -112.094886) (xy 97.556142 -112.037615)
			(xy 95.762829 -112.037615) (xy 95.794277 -112.075815) (xy 95.821832 -112.12066) (xy 95.842966 -112.168866)
			(xy 95.857278 -112.219517) (xy 95.864498 -112.271655) (xy 95.864934 -112.297972) (xy 95.864448 -112.325223)
			(xy 95.856692 -112.379171) (xy 95.841337 -112.431466) (xy 95.818695 -112.481043) (xy 95.789229 -112.526893)
			(xy 95.753538 -112.568084) (xy 95.712347 -112.603775) (xy 95.666497 -112.633241) (xy 95.61692 -112.655883)
			(xy 95.564625 -112.671238) (xy 95.510677 -112.678994) (xy 95.456175 -112.678994) (xy 95.402227 -112.671238)
			(xy 95.349932 -112.655883) (xy 95.300355 -112.633241) (xy 95.254505 -112.603775) (xy 95.213314 -112.568084)
			(xy 95.177623 -112.526893) (xy 95.148157 -112.481043) (xy 95.125515 -112.431466) (xy 95.11016 -112.379171)
			(xy 95.102404 -112.325223) (xy 95.101918 -112.297972) (xy 93.832934 -112.297972) (xy 93.832448 -112.325223)
			(xy 93.824692 -112.379171) (xy 93.809337 -112.431466) (xy 93.786695 -112.481043) (xy 93.757229 -112.526893)
			(xy 93.721538 -112.568084) (xy 93.680347 -112.603775) (xy 93.634497 -112.633241) (xy 93.58492 -112.655883)
			(xy 93.532625 -112.671238) (xy 93.478677 -112.678994) (xy 93.424175 -112.678994) (xy 93.370227 -112.671238)
			(xy 93.317932 -112.655883) (xy 93.268355 -112.633241) (xy 93.222505 -112.603775) (xy 93.181314 -112.568084)
			(xy 93.145623 -112.526893) (xy 93.116157 -112.481043) (xy 93.093515 -112.431466) (xy 93.07816 -112.379171)
			(xy 93.070404 -112.325223) (xy 93.069918 -112.297972) (xy 75.205466 -112.297972) (xy 75.177364 -112.316029)
			(xy 75.127778 -112.338669) (xy 75.075474 -112.354021) (xy 75.021517 -112.361774) (xy 74.994262 -112.362234)
			(xy 74.967948 -112.361781) (xy 74.915819 -112.354542) (xy 74.865176 -112.340219) (xy 74.816978 -112.319084)
			(xy 74.772135 -112.291536) (xy 74.731495 -112.258096) (xy 74.713338 -112.239044) (xy 74.705798 -112.231664)
			(xy 74.686532 -112.223126) (xy 74.676 -112.222534) (xy 74.601324 -112.222534) (xy 74.590773 -112.223052)
			(xy 74.571477 -112.231594) (xy 74.563986 -112.239044) (xy 74.545839 -112.258108) (xy 74.505206 -112.291562)
			(xy 74.460364 -112.319119) (xy 74.412162 -112.340256) (xy 74.361513 -112.354572) (xy 74.309378 -112.361796)
			(xy 74.283062 -112.362234) (xy 74.255811 -112.361758) (xy 74.201864 -112.353997) (xy 74.149571 -112.338638)
			(xy 74.099995 -112.315994) (xy 74.054146 -112.286526) (xy 74.012957 -112.250834) (xy 73.977266 -112.209644)
			(xy 73.9478 -112.163794) (xy 73.925158 -112.114218) (xy 73.909801 -112.061924) (xy 73.902042 -112.007977)
			(xy 73.901554 -111.980726) (xy 71.115196 -111.980726) (xy 71.103177 -112.020675) (xy 71.079505 -112.071172)
			(xy 71.048732 -112.117685) (xy 71.011515 -112.159222) (xy 70.968647 -112.194897) (xy 70.921041 -112.223951)
			(xy 70.869712 -112.245763) (xy 70.815755 -112.259869) (xy 70.760318 -112.265969) (xy 70.704584 -112.263932)
			(xy 70.649741 -112.253802) (xy 70.596957 -112.235795) (xy 70.547357 -112.210294) (xy 70.501999 -112.177843)
			(xy 70.46185 -112.139134) (xy 70.427764 -112.094991) (xy 70.400468 -112.046356) (xy 70.380545 -111.994265)
			(xy 70.368419 -111.939828) (xy 70.364348 -111.884206) (xy 64.84628 -111.884206) (xy 64.814252 -111.895865)
			(xy 64.74789 -111.911599) (xy 64.680149 -111.919522) (xy 64.646048 -111.92002) (xy 64.42456 -111.92002)
			(xy 64.414488 -111.920419) (xy 64.39589 -111.928158) (xy 64.388492 -111.935006) (xy 64.32042 -112.003078)
			(xy 64.312362 -112.012216) (xy 64.305069 -112.035424) (xy 64.30645 -112.047528) (xy 64.322706 -112.141762)
			(xy 64.337438 -112.161066) (xy 64.348614 -112.1664) (xy 64.372686 -112.17834) (xy 64.417471 -112.208032)
			(xy 64.457646 -112.243715) (xy 64.492418 -112.284681) (xy 64.521098 -112.330121) (xy 64.543119 -112.379135)
			(xy 64.555492 -112.421924) (xy 69.455028 -112.421924) (xy 69.459099 -112.366302) (xy 69.471225 -112.311865)
			(xy 69.491148 -112.259774) (xy 69.518444 -112.211139) (xy 69.55253 -112.166996) (xy 69.592679 -112.128287)
			(xy 69.638037 -112.095836) (xy 69.687637 -112.070335) (xy 69.740421 -112.052328) (xy 69.795264 -112.042198)
			(xy 69.850998 -112.040161) (xy 69.906435 -112.046261) (xy 69.960392 -112.060367) (xy 70.011721 -112.082179)
			(xy 70.059327 -112.111233) (xy 70.102195 -112.146908) (xy 70.139412 -112.188445) (xy 70.170185 -112.234958)
			(xy 70.193857 -112.285455) (xy 70.209925 -112.338862) (xy 70.218045 -112.394038) (xy 70.218554 -112.421924)
			(xy 70.218045 -112.44981) (xy 70.209925 -112.504986) (xy 70.193857 -112.558393) (xy 70.170185 -112.60889)
			(xy 70.139412 -112.655403) (xy 70.102195 -112.69694) (xy 70.059327 -112.732615) (xy 70.011721 -112.761669)
			(xy 69.960392 -112.783481) (xy 69.906435 -112.797587) (xy 69.850998 -112.803687) (xy 69.795264 -112.80165)
			(xy 69.740421 -112.79152) (xy 69.687637 -112.773513) (xy 69.638037 -112.748012) (xy 69.592679 -112.715561)
			(xy 69.55253 -112.676852) (xy 69.518444 -112.632709) (xy 69.491148 -112.584074) (xy 69.471225 -112.531983)
			(xy 69.459099 -112.477546) (xy 69.455028 -112.421924) (xy 64.555492 -112.421924) (xy 64.558045 -112.430754)
			(xy 64.565581 -112.483957) (xy 64.566038 -112.510824) (xy 64.565545 -112.538074) (xy 64.557786 -112.59202)
			(xy 64.542429 -112.644313) (xy 64.519787 -112.693888) (xy 64.490321 -112.739737) (xy 64.454631 -112.780926)
			(xy 64.413442 -112.816618) (xy 64.384952 -112.834928) (xy 66.496946 -112.834928) (xy 66.497432 -112.807677)
			(xy 66.505188 -112.753729) (xy 66.520543 -112.701434) (xy 66.543185 -112.651857) (xy 66.572651 -112.606007)
			(xy 66.608342 -112.564816) (xy 66.649533 -112.529125) (xy 66.695383 -112.499659) (xy 66.74496 -112.477017)
			(xy 66.797255 -112.461662) (xy 66.851203 -112.453906) (xy 66.905705 -112.453906) (xy 66.959653 -112.461662)
			(xy 67.011948 -112.477017) (xy 67.061525 -112.499659) (xy 67.107375 -112.529125) (xy 67.148566 -112.564816)
			(xy 67.184257 -112.606007) (xy 67.213723 -112.651857) (xy 67.236365 -112.701434) (xy 67.25172 -112.753729)
			(xy 67.259476 -112.807677) (xy 67.259962 -112.834928) (xy 67.259592 -112.858546) (xy 67.253736 -112.905418)
			(xy 67.248278 -112.9284) (xy 67.245153 -112.942907) (xy 67.246479 -112.97254) (xy 67.252438 -112.989614)
			(xy 70.44004 -112.989614) (xy 70.444111 -112.933992) (xy 70.456237 -112.879555) (xy 70.47616 -112.827464)
			(xy 70.503456 -112.778829) (xy 70.537542 -112.734686) (xy 70.577691 -112.695977) (xy 70.623049 -112.663526)
			(xy 70.672649 -112.638025) (xy 70.725433 -112.620018) (xy 70.780276 -112.609888) (xy 70.83601 -112.607851)
			(xy 70.891447 -112.613951) (xy 70.945404 -112.628057) (xy 70.996733 -112.649869) (xy 71.044339 -112.678923)
			(xy 71.087207 -112.714598) (xy 71.124424 -112.756135) (xy 71.155197 -112.802648) (xy 71.178869 -112.853145)
			(xy 71.194937 -112.906552) (xy 71.203057 -112.961728) (xy 71.203566 -112.989614) (xy 71.203057 -113.0175)
			(xy 71.194937 -113.072676) (xy 71.178869 -113.126083) (xy 71.155197 -113.17658) (xy 71.124424 -113.223093)
			(xy 71.087207 -113.26463) (xy 71.044339 -113.300305) (xy 70.996733 -113.329359) (xy 70.945404 -113.351171)
			(xy 70.891447 -113.365277) (xy 70.83601 -113.371377) (xy 70.780276 -113.36934) (xy 70.725433 -113.35921)
			(xy 70.672649 -113.341203) (xy 70.623049 -113.315702) (xy 70.577691 -113.283251) (xy 70.537542 -113.244542)
			(xy 70.503456 -113.200399) (xy 70.47616 -113.151764) (xy 70.456237 -113.099673) (xy 70.444111 -113.045236)
			(xy 70.44004 -112.989614) (xy 67.252438 -112.989614) (xy 67.256253 -113.000546) (xy 67.273654 -113.024568)
			(xy 67.297217 -113.042587) (xy 67.32496 -113.053085) (xy 67.339718 -113.054638) (xy 67.368241 -113.057167)
			(xy 67.424115 -113.069687) (xy 67.47749 -113.090418) (xy 67.527167 -113.118895) (xy 67.572028 -113.154479)
			(xy 67.611066 -113.196368) (xy 67.643403 -113.243623) (xy 67.668313 -113.295181) (xy 67.685236 -113.349883)
			(xy 67.693791 -113.4065) (xy 67.694302 -113.43513) (xy 67.694252 -113.437924) (xy 69.433946 -113.437924)
			(xy 69.438017 -113.382302) (xy 69.450143 -113.327865) (xy 69.470066 -113.275774) (xy 69.497362 -113.227139)
			(xy 69.531448 -113.182996) (xy 69.571597 -113.144287) (xy 69.616955 -113.111836) (xy 69.666555 -113.086335)
			(xy 69.719339 -113.068328) (xy 69.774182 -113.058198) (xy 69.829916 -113.056161) (xy 69.885353 -113.062261)
			(xy 69.93931 -113.076367) (xy 69.990639 -113.098179) (xy 70.038245 -113.127233) (xy 70.081113 -113.162908)
			(xy 70.11833 -113.204445) (xy 70.149103 -113.250958) (xy 70.172775 -113.301455) (xy 70.188843 -113.354862)
			(xy 70.196963 -113.410038) (xy 70.197472 -113.437924) (xy 70.196963 -113.46581) (xy 70.188843 -113.520986)
			(xy 70.172775 -113.574393) (xy 70.149103 -113.62489) (xy 70.11833 -113.671403) (xy 70.081113 -113.71294)
			(xy 70.038245 -113.748615) (xy 69.990639 -113.777669) (xy 69.93931 -113.799481) (xy 69.885353 -113.813587)
			(xy 69.829916 -113.819687) (xy 69.774182 -113.81765) (xy 69.719339 -113.80752) (xy 69.666555 -113.789513)
			(xy 69.616955 -113.764012) (xy 69.571597 -113.731561) (xy 69.531448 -113.692852) (xy 69.497362 -113.648709)
			(xy 69.470066 -113.600074) (xy 69.450143 -113.547983) (xy 69.438017 -113.493546) (xy 69.433946 -113.437924)
			(xy 67.694252 -113.437924) (xy 67.693816 -113.462381) (xy 67.68606 -113.516329) (xy 67.670705 -113.568624)
			(xy 67.648063 -113.618201) (xy 67.618597 -113.664051) (xy 67.582906 -113.705242) (xy 67.541715 -113.740933)
			(xy 67.495865 -113.770399) (xy 67.446288 -113.793041) (xy 67.393993 -113.808396) (xy 67.340045 -113.816152)
			(xy 67.285543 -113.816152) (xy 67.231595 -113.808396) (xy 67.1793 -113.793041) (xy 67.129723 -113.770399)
			(xy 67.083873 -113.740933) (xy 67.042682 -113.705242) (xy 67.006991 -113.664051) (xy 66.977525 -113.618201)
			(xy 66.954883 -113.568624) (xy 66.939528 -113.516329) (xy 66.931772 -113.462381) (xy 66.931286 -113.43513)
			(xy 66.93165 -113.411512) (xy 66.93751 -113.364639) (xy 66.94297 -113.341658) (xy 66.946079 -113.327146)
			(xy 66.944768 -113.297511) (xy 66.935001 -113.269501) (xy 66.917602 -113.245475) (xy 66.894037 -113.227458)
			(xy 66.86629 -113.216967) (xy 66.85153 -113.21542) (xy 66.823006 -113.212891) (xy 66.767129 -113.200377)
			(xy 66.713751 -113.179649) (xy 66.664072 -113.151173) (xy 66.619209 -113.11559) (xy 66.58017 -113.073699)
			(xy 66.547833 -113.026443) (xy 66.522924 -112.974883) (xy 66.506005 -112.920178) (xy 66.497454 -112.863559)
			(xy 66.496946 -112.834928) (xy 64.384952 -112.834928) (xy 64.367594 -112.846084) (xy 64.318019 -112.868727)
			(xy 64.265726 -112.884084) (xy 64.21178 -112.891844) (xy 64.18453 -112.892332) (xy 64.157666 -112.891839)
			(xy 64.104468 -112.884304) (xy 64.052853 -112.86938) (xy 64.003843 -112.847361) (xy 63.958407 -112.818684)
			(xy 63.917445 -112.783915) (xy 63.881766 -112.743743) (xy 63.852077 -112.698962) (xy 63.840106 -112.674908)
			(xy 63.834772 -112.663732) (xy 63.815468 -112.649) (xy 63.721234 -112.632744) (xy 63.709127 -112.631323)
			(xy 63.685907 -112.638628) (xy 63.676784 -112.646714) (xy 63.071756 -113.251742) (xy 64.306194 -113.251742)
			(xy 64.310265 -113.19612) (xy 64.322391 -113.141683) (xy 64.342314 -113.089592) (xy 64.36961 -113.040957)
			(xy 64.403696 -112.996814) (xy 64.443845 -112.958105) (xy 64.489203 -112.925654) (xy 64.538803 -112.900153)
			(xy 64.591587 -112.882146) (xy 64.64643 -112.872016) (xy 64.702164 -112.869979) (xy 64.757601 -112.876079)
			(xy 64.811558 -112.890185) (xy 64.862887 -112.911997) (xy 64.910493 -112.941051) (xy 64.953361 -112.976726)
			(xy 64.990578 -113.018263) (xy 65.021351 -113.064776) (xy 65.045023 -113.115273) (xy 65.061091 -113.16868)
			(xy 65.069211 -113.223856) (xy 65.06972 -113.251742) (xy 65.069211 -113.279628) (xy 65.061091 -113.334804)
			(xy 65.045023 -113.388211) (xy 65.021351 -113.438708) (xy 64.990578 -113.485221) (xy 64.953361 -113.526758)
			(xy 64.910493 -113.562433) (xy 64.862887 -113.591487) (xy 64.811558 -113.613299) (xy 64.757601 -113.627405)
			(xy 64.702164 -113.633505) (xy 64.64643 -113.631468) (xy 64.591587 -113.621338) (xy 64.538803 -113.603331)
			(xy 64.489203 -113.57783) (xy 64.443845 -113.545379) (xy 64.403696 -113.50667) (xy 64.36961 -113.462527)
			(xy 64.342314 -113.413892) (xy 64.322391 -113.361801) (xy 64.310265 -113.307364) (xy 64.306194 -113.251742)
			(xy 63.071756 -113.251742) (xy 62.406276 -113.917222) (xy 70.793862 -113.917222) (xy 70.797933 -113.8616)
			(xy 70.810059 -113.807163) (xy 70.829982 -113.755072) (xy 70.857278 -113.706437) (xy 70.891364 -113.662294)
			(xy 70.931513 -113.623585) (xy 70.976871 -113.591134) (xy 71.026471 -113.565633) (xy 71.079255 -113.547626)
			(xy 71.134098 -113.537496) (xy 71.189832 -113.535459) (xy 71.245269 -113.541559) (xy 71.299226 -113.555665)
			(xy 71.350555 -113.577477) (xy 71.398161 -113.606531) (xy 71.441029 -113.642206) (xy 71.478246 -113.683743)
			(xy 71.509019 -113.730256) (xy 71.532691 -113.780753) (xy 71.548759 -113.83416) (xy 71.556879 -113.889336)
			(xy 71.557388 -113.917222) (xy 71.556879 -113.945108) (xy 71.548759 -114.000284) (xy 71.532691 -114.053691)
			(xy 71.518184 -114.084637) (xy 89.449407 -114.084637) (xy 89.449409 -114.03014) (xy 89.457166 -113.976198)
			(xy 89.472521 -113.923908) (xy 89.495161 -113.874336) (xy 89.524626 -113.828491) (xy 89.560315 -113.787305)
			(xy 89.601502 -113.751618) (xy 89.647348 -113.722155) (xy 89.696921 -113.699517) (xy 89.749211 -113.684163)
			(xy 89.803153 -113.676408) (xy 89.830402 -113.675922) (xy 89.83091 -113.675922) (xy 89.854668 -113.676301)
			(xy 89.901812 -113.682246) (xy 89.947855 -113.693991) (xy 89.970102 -113.702338) (xy 89.982802 -113.707418)
			(xy 90.009472 -113.703354) (xy 90.088974 -113.640108) (xy 90.095629 -113.634331) (xy 90.10491 -113.619367)
			(xy 90.108586 -113.602146) (xy 90.10777 -113.593372) (xy 90.10777 -113.592864) (xy 90.105906 -113.579288)
			(xy 90.103869 -113.551957) (xy 90.103706 -113.538254) (xy 90.104135 -113.511001) (xy 90.111898 -113.45705)
			(xy 90.12726 -113.404754) (xy 90.149907 -113.355176) (xy 90.17938 -113.309325) (xy 90.215077 -113.268135)
			(xy 90.256273 -113.232444) (xy 90.302128 -113.202979) (xy 90.35171 -113.180339) (xy 90.404009 -113.164985)
			(xy 90.457961 -113.157231) (xy 90.485214 -113.156746) (xy 90.514129 -113.157309) (xy 90.571299 -113.166026)
			(xy 90.626498 -113.183274) (xy 90.67846 -113.208657) (xy 90.725995 -113.241594) (xy 90.768013 -113.281329)
			(xy 90.786204 -113.303812) (xy 90.793817 -113.312613) (xy 90.814713 -113.322799) (xy 90.826336 -113.32337)
			(xy 90.906092 -113.32337) (xy 90.917723 -113.322822) (xy 90.938633 -113.312641) (xy 90.946224 -113.303812)
			(xy 90.964405 -113.28132) (xy 91.006426 -113.241584) (xy 91.053963 -113.208646) (xy 91.105926 -113.183259)
			(xy 91.161126 -113.166005) (xy 91.218297 -113.157279) (xy 91.247214 -113.156746) (xy 91.274464 -113.157265)
			(xy 91.328408 -113.165022) (xy 91.380699 -113.180376) (xy 91.430273 -113.203016) (xy 91.476121 -113.232479)
			(xy 91.51731 -113.268167) (xy 91.553001 -113.309353) (xy 91.582469 -113.355199) (xy 91.605112 -113.404771)
			(xy 91.620471 -113.457061) (xy 91.628233 -113.511005) (xy 91.628722 -113.538254) (xy 91.628284 -113.565013)
			(xy 91.627758 -113.568734) (xy 110.889794 -113.568734) (xy 110.893865 -113.513112) (xy 110.905991 -113.458675)
			(xy 110.925914 -113.406584) (xy 110.95321 -113.357949) (xy 110.987296 -113.313806) (xy 111.027445 -113.275097)
			(xy 111.072803 -113.242646) (xy 111.122403 -113.217145) (xy 111.175187 -113.199138) (xy 111.23003 -113.189008)
			(xy 111.285764 -113.186971) (xy 111.341201 -113.193071) (xy 111.395158 -113.207177) (xy 111.446487 -113.228989)
			(xy 111.494093 -113.258043) (xy 111.536961 -113.293718) (xy 111.574178 -113.335255) (xy 111.604951 -113.381768)
			(xy 111.628623 -113.432265) (xy 111.644691 -113.485672) (xy 111.652811 -113.540848) (xy 111.65332 -113.568734)
			(xy 111.652811 -113.59662) (xy 111.644691 -113.651796) (xy 111.628623 -113.705203) (xy 111.604951 -113.7557)
			(xy 111.574178 -113.802213) (xy 111.536961 -113.84375) (xy 111.494093 -113.879425) (xy 111.446487 -113.908479)
			(xy 111.395158 -113.930291) (xy 111.341201 -113.944397) (xy 111.285764 -113.950497) (xy 111.23003 -113.94846)
			(xy 111.175187 -113.93833) (xy 111.122403 -113.920323) (xy 111.072803 -113.894822) (xy 111.027445 -113.862371)
			(xy 110.987296 -113.823662) (xy 110.95321 -113.779519) (xy 110.925914 -113.730884) (xy 110.905991 -113.678793)
			(xy 110.893865 -113.624356) (xy 110.889794 -113.568734) (xy 91.627758 -113.568734) (xy 91.620797 -113.618004)
			(xy 91.605979 -113.669429) (xy 91.58412 -113.718279) (xy 91.555649 -113.763594) (xy 91.521125 -113.804487)
			(xy 91.481225 -113.840153) (xy 91.436732 -113.869894) (xy 91.412822 -113.881916) (xy 91.412568 -113.881916)
			(xy 91.40182 -113.888029) (xy 91.387212 -113.907926) (xy 91.384628 -113.920016) (xy 91.369642 -114.015012)
			(xy 91.37777 -114.03838) (xy 91.38666 -114.047016) (xy 91.396783 -114.05681) (xy 91.415729 -114.077656)
			(xy 91.424506 -114.088672) (xy 91.432057 -114.097444) (xy 91.452825 -114.107619) (xy 91.464384 -114.10823)
			(xy 91.544394 -114.10823) (xy 91.556027 -114.107697) (xy 91.576938 -114.097506) (xy 91.584526 -114.088672)
			(xy 91.602695 -114.06617) (xy 91.64472 -114.026437) (xy 91.69226 -113.993501) (xy 91.744225 -113.968116)
			(xy 91.799426 -113.950864) (xy 91.856599 -113.942139) (xy 91.885516 -113.941606) (xy 91.912768 -113.942065)
			(xy 91.966715 -113.949824) (xy 92.01901 -113.965181) (xy 92.068587 -113.987824) (xy 92.114437 -114.017291)
			(xy 92.127342 -114.028474) (xy 105.005122 -114.028474) (xy 105.009193 -113.972852) (xy 105.021319 -113.918415)
			(xy 105.041242 -113.866324) (xy 105.068538 -113.817689) (xy 105.102624 -113.773546) (xy 105.142773 -113.734837)
			(xy 105.188131 -113.702386) (xy 105.237731 -113.676885) (xy 105.290515 -113.658878) (xy 105.345358 -113.648748)
			(xy 105.401092 -113.646711) (xy 105.456529 -113.652811) (xy 105.510486 -113.666917) (xy 105.561815 -113.688729)
			(xy 105.609421 -113.717783) (xy 105.652289 -113.753458) (xy 105.689506 -113.794995) (xy 105.720279 -113.841508)
			(xy 105.743951 -113.892005) (xy 105.760019 -113.945412) (xy 105.768139 -114.000588) (xy 105.768648 -114.028474)
			(xy 105.768139 -114.05636) (xy 105.760019 -114.111536) (xy 105.743951 -114.164943) (xy 105.720279 -114.21544)
			(xy 105.689506 -114.261953) (xy 105.652289 -114.30349) (xy 105.609421 -114.339165) (xy 105.561815 -114.368219)
			(xy 105.510486 -114.390031) (xy 105.456529 -114.404137) (xy 105.401092 -114.410237) (xy 105.345358 -114.4082)
			(xy 105.290515 -114.39807) (xy 105.237731 -114.380063) (xy 105.188131 -114.354562) (xy 105.142773 -114.322111)
			(xy 105.102624 -114.283402) (xy 105.068538 -114.239259) (xy 105.041242 -114.190624) (xy 105.021319 -114.138533)
			(xy 105.009193 -114.084096) (xy 105.005122 -114.028474) (xy 92.127342 -114.028474) (xy 92.155627 -114.052984)
			(xy 92.191318 -114.094175) (xy 92.220784 -114.140027) (xy 92.243425 -114.189605) (xy 92.25878 -114.2419)
			(xy 92.266536 -114.295848) (xy 92.266536 -114.350352) (xy 92.25878 -114.4043) (xy 92.243425 -114.456595)
			(xy 92.220784 -114.506173) (xy 92.191318 -114.552025) (xy 92.155627 -114.593216) (xy 92.114437 -114.628909)
			(xy 92.068587 -114.658376) (xy 92.01901 -114.681019) (xy 91.966715 -114.696376) (xy 91.912767 -114.704135)
			(xy 91.885516 -114.704622) (xy 91.856598 -114.704122) (xy 91.799425 -114.695393) (xy 91.744224 -114.678134)
			(xy 91.692262 -114.652739) (xy 91.644729 -114.619791) (xy 91.602714 -114.580044) (xy 91.584526 -114.557556)
			(xy 91.576905 -114.548763) (xy 91.556015 -114.538574) (xy 91.544394 -114.537998) (xy 91.464638 -114.537998)
			(xy 91.453004 -114.538516) (xy 91.432094 -114.54872) (xy 91.424506 -114.557556) (xy 91.4063 -114.580027)
			(xy 91.364285 -114.619765) (xy 91.316754 -114.652707) (xy 91.264795 -114.678098) (xy 91.209599 -114.695356)
			(xy 91.152431 -114.704087) (xy 91.123516 -114.704622) (xy 91.096264 -114.70413) (xy 91.042315 -114.696375)
			(xy 90.990019 -114.681022) (xy 90.940439 -114.658383) (xy 90.894587 -114.628917) (xy 90.853394 -114.593227)
			(xy 90.817701 -114.552037) (xy 90.788232 -114.506187) (xy 90.765588 -114.45661) (xy 90.750231 -114.404314)
			(xy 90.742472 -114.350366) (xy 90.742008 -114.323114) (xy 90.742459 -114.296356) (xy 90.749948 -114.243367)
			(xy 90.764767 -114.191945) (xy 90.786626 -114.143097) (xy 90.815095 -114.097782) (xy 90.849616 -114.056889)
			(xy 90.889512 -114.021221) (xy 90.934 -113.991476) (xy 90.957908 -113.979452) (xy 90.958162 -113.979452)
			(xy 90.968927 -113.973364) (xy 90.983526 -113.953449) (xy 90.986102 -113.941352) (xy 91.001088 -113.846356)
			(xy 90.99296 -113.822988) (xy 90.98407 -113.814352) (xy 90.973942 -113.804563) (xy 90.954999 -113.783714)
			(xy 90.946224 -113.772696) (xy 90.938648 -113.763949) (xy 90.9179 -113.753757) (xy 90.906346 -113.753138)
			(xy 90.826336 -113.753138) (xy 90.814699 -113.753642) (xy 90.793789 -113.763854) (xy 90.786204 -113.772696)
			(xy 90.76801 -113.795177) (xy 90.725991 -113.834912) (xy 90.678457 -113.867852) (xy 90.626496 -113.893241)
			(xy 90.571299 -113.910497) (xy 90.51413 -113.919227) (xy 90.485214 -113.919762) (xy 90.484706 -113.919762)
			(xy 90.460948 -113.919379) (xy 90.413804 -113.913436) (xy 90.367761 -113.901692) (xy 90.345514 -113.893346)
			(xy 90.332814 -113.888266) (xy 90.306144 -113.89233) (xy 90.226642 -113.955576) (xy 90.219982 -113.961347)
			(xy 90.210709 -113.976316) (xy 90.207033 -113.993537) (xy 90.207846 -114.002312) (xy 90.207846 -114.00282)
			(xy 90.209719 -114.016395) (xy 90.21175 -114.043727) (xy 90.21191 -114.05743) (xy 90.21139 -114.084679)
			(xy 90.20363 -114.138621) (xy 90.188272 -114.190909) (xy 90.16563 -114.24048) (xy 90.136163 -114.286324)
			(xy 90.100472 -114.327508) (xy 90.059283 -114.363193) (xy 90.013436 -114.392654) (xy 89.963862 -114.41529)
			(xy 89.911571 -114.430641) (xy 89.857628 -114.438393) (xy 89.803131 -114.43839) (xy 89.749189 -114.430632)
			(xy 89.6969 -114.415276) (xy 89.647328 -114.392634) (xy 89.601483 -114.363169) (xy 89.560299 -114.327479)
			(xy 89.524612 -114.286291) (xy 89.49515 -114.240444) (xy 89.472513 -114.19087) (xy 89.457161 -114.13858)
			(xy 89.449407 -114.084637) (xy 71.518184 -114.084637) (xy 71.509019 -114.104188) (xy 71.478246 -114.150701)
			(xy 71.441029 -114.192238) (xy 71.398161 -114.227913) (xy 71.350555 -114.256967) (xy 71.299226 -114.278779)
			(xy 71.245269 -114.292885) (xy 71.189832 -114.298985) (xy 71.134098 -114.296948) (xy 71.079255 -114.286818)
			(xy 71.026471 -114.268811) (xy 70.976871 -114.24331) (xy 70.931513 -114.210859) (xy 70.891364 -114.17215)
			(xy 70.857278 -114.128007) (xy 70.829982 -114.079372) (xy 70.810059 -114.027281) (xy 70.797933 -113.972844)
			(xy 70.793862 -113.917222) (xy 62.406276 -113.917222) (xy 61.742066 -114.581432) (xy 66.299586 -114.581432)
			(xy 66.303657 -114.52581) (xy 66.315783 -114.471373) (xy 66.335706 -114.419282) (xy 66.363002 -114.370647)
			(xy 66.397088 -114.326504) (xy 66.437237 -114.287795) (xy 66.482595 -114.255344) (xy 66.532195 -114.229843)
			(xy 66.584979 -114.211836) (xy 66.639822 -114.201706) (xy 66.695556 -114.199669) (xy 66.750993 -114.205769)
			(xy 66.80495 -114.219875) (xy 66.856279 -114.241687) (xy 66.903885 -114.270741) (xy 66.946753 -114.306416)
			(xy 66.98397 -114.347953) (xy 67.014743 -114.394466) (xy 67.038415 -114.444963) (xy 67.054483 -114.49837)
			(xy 67.062603 -114.553546) (xy 67.063112 -114.581432) (xy 67.062603 -114.609318) (xy 67.054483 -114.664494)
			(xy 67.038415 -114.717901) (xy 67.014743 -114.768398) (xy 66.98397 -114.814911) (xy 66.946753 -114.856448)
			(xy 66.903885 -114.892123) (xy 66.856279 -114.921177) (xy 66.80495 -114.942989) (xy 66.750993 -114.957095)
			(xy 66.695556 -114.963195) (xy 66.639822 -114.961158) (xy 66.584979 -114.951028) (xy 66.532195 -114.933021)
			(xy 66.482595 -114.90752) (xy 66.437237 -114.875069) (xy 66.397088 -114.83636) (xy 66.363002 -114.792217)
			(xy 66.335706 -114.743582) (xy 66.315783 -114.691491) (xy 66.303657 -114.637054) (xy 66.299586 -114.581432)
			(xy 61.742066 -114.581432) (xy 61.037724 -115.285774) (xy 66.930776 -115.285774) (xy 66.934847 -115.230152)
			(xy 66.946973 -115.175715) (xy 66.966896 -115.123624) (xy 66.994192 -115.074989) (xy 67.028278 -115.030846)
			(xy 67.068427 -114.992137) (xy 67.113785 -114.959686) (xy 67.163385 -114.934185) (xy 67.216169 -114.916178)
			(xy 67.271012 -114.906048) (xy 67.326746 -114.904011) (xy 67.382183 -114.910111) (xy 67.43614 -114.924217)
			(xy 67.487469 -114.946029) (xy 67.535075 -114.975083) (xy 67.577943 -115.010758) (xy 67.61516 -115.052295)
			(xy 67.645933 -115.098808) (xy 67.669605 -115.149305) (xy 67.685673 -115.202712) (xy 67.693793 -115.257888)
			(xy 67.694302 -115.285774) (xy 67.693793 -115.31366) (xy 67.686832 -115.360958) (xy 74.11847 -115.360958)
			(xy 74.118953 -115.333588) (xy 74.126764 -115.279409) (xy 74.142248 -115.226906) (xy 74.165087 -115.177158)
			(xy 74.194809 -115.131191) (xy 74.21245 -115.11026) (xy 74.212704 -115.110006) (xy 74.218295 -115.102922)
			(xy 74.224539 -115.086003) (xy 74.224896 -115.076986) (xy 74.224896 -115.00993) (xy 74.224526 -115.000914)
			(xy 74.218288 -114.983997) (xy 74.212704 -114.97691) (xy 74.21245 -114.97691) (xy 74.21245 -114.976656)
			(xy 74.194831 -114.955707) (xy 74.165115 -114.90974) (xy 74.142274 -114.859997) (xy 74.126778 -114.807499)
			(xy 74.118946 -114.753326) (xy 74.11847 -114.725958) (xy 74.118939 -114.698707) (xy 74.1267 -114.64476)
			(xy 74.14206 -114.592466) (xy 74.164704 -114.54289) (xy 74.194173 -114.497041) (xy 74.229866 -114.455852)
			(xy 74.271057 -114.420161) (xy 74.316907 -114.390694) (xy 74.366485 -114.368053) (xy 74.418779 -114.352696)
			(xy 74.472727 -114.344937) (xy 74.499978 -114.34445) (xy 74.527348 -114.344917) (xy 74.581528 -114.352733)
			(xy 74.634031 -114.368221) (xy 74.683778 -114.391063) (xy 74.729745 -114.420788) (xy 74.750676 -114.43843)
			(xy 74.75093 -114.438684) (xy 74.758034 -114.444246) (xy 74.774937 -114.450508) (xy 74.78395 -114.450876)
			(xy 74.851006 -114.450876) (xy 74.860024 -114.450527) (xy 74.876941 -114.444275) (xy 74.884026 -114.438684)
			(xy 74.884026 -114.43843) (xy 74.88428 -114.43843) (xy 74.905213 -114.420791) (xy 74.951185 -114.391079)
			(xy 75.000932 -114.368242) (xy 75.053433 -114.352751) (xy 75.107609 -114.344923) (xy 75.134978 -114.34445)
			(xy 75.162227 -114.344999) (xy 75.21617 -114.352751) (xy 75.268461 -114.368101) (xy 75.318035 -114.390737)
			(xy 75.363884 -114.420197) (xy 75.405073 -114.455882) (xy 75.440765 -114.497065) (xy 75.470233 -114.542909)
			(xy 75.492876 -114.592479) (xy 75.508235 -114.644767) (xy 75.515997 -114.698709) (xy 75.516486 -114.725958)
			(xy 75.515999 -114.753328) (xy 75.508187 -114.807506) (xy 75.492703 -114.860009) (xy 75.469866 -114.909756)
			(xy 75.440145 -114.955724) (xy 75.422506 -114.976656) (xy 75.422252 -114.97691) (xy 75.416649 -114.983985)
			(xy 75.410413 -115.000911) (xy 75.41006 -115.00993) (xy 75.41006 -115.076986) (xy 75.410411 -115.086004)
			(xy 75.416661 -115.102921) (xy 75.422252 -115.110006) (xy 75.422506 -115.110006) (xy 75.422506 -115.11026)
			(xy 75.440141 -115.131196) (xy 75.469853 -115.177167) (xy 75.49269 -115.226914) (xy 75.508182 -115.279414)
			(xy 75.516011 -115.333589) (xy 75.516486 -115.360958) (xy 75.516006 -115.388211) (xy 75.514192 -115.400836)
			(xy 87.260682 -115.400836) (xy 87.264753 -115.345214) (xy 87.276879 -115.290777) (xy 87.296802 -115.238686)
			(xy 87.324098 -115.190051) (xy 87.358184 -115.145908) (xy 87.398333 -115.107199) (xy 87.443691 -115.074748)
			(xy 87.493291 -115.049247) (xy 87.546075 -115.03124) (xy 87.600918 -115.02111) (xy 87.656652 -115.019073)
			(xy 87.712089 -115.025173) (xy 87.766046 -115.039279) (xy 87.817375 -115.061091) (xy 87.864981 -115.090145)
			(xy 87.907849 -115.12582) (xy 87.945066 -115.167357) (xy 87.975839 -115.21387) (xy 87.999511 -115.264367)
			(xy 88.015579 -115.317774) (xy 88.023317 -115.370356) (xy 89.361262 -115.370356) (xy 89.365333 -115.314734)
			(xy 89.377459 -115.260297) (xy 89.397382 -115.208206) (xy 89.424678 -115.159571) (xy 89.458764 -115.115428)
			(xy 89.498913 -115.076719) (xy 89.544271 -115.044268) (xy 89.593871 -115.018767) (xy 89.646655 -115.00076)
			(xy 89.701498 -114.99063) (xy 89.757232 -114.988593) (xy 89.812669 -114.994693) (xy 89.866626 -115.008799)
			(xy 89.871678 -115.010946) (xy 106.6198 -115.010946) (xy 106.623871 -114.955324) (xy 106.635997 -114.900887)
			(xy 106.65592 -114.848796) (xy 106.683216 -114.800161) (xy 106.717302 -114.756018) (xy 106.757451 -114.717309)
			(xy 106.802809 -114.684858) (xy 106.852409 -114.659357) (xy 106.905193 -114.64135) (xy 106.960036 -114.63122)
			(xy 107.01577 -114.629183) (xy 107.071207 -114.635283) (xy 107.125164 -114.649389) (xy 107.176493 -114.671201)
			(xy 107.224099 -114.700255) (xy 107.266967 -114.73593) (xy 107.304184 -114.777467) (xy 107.334957 -114.82398)
			(xy 107.358629 -114.874477) (xy 107.374697 -114.927884) (xy 107.382817 -114.98306) (xy 107.383326 -115.010946)
			(xy 107.382817 -115.038832) (xy 107.379893 -115.058698) (xy 107.98632 -115.058698) (xy 107.990391 -115.003076)
			(xy 108.002517 -114.948639) (xy 108.02244 -114.896548) (xy 108.049736 -114.847913) (xy 108.083822 -114.80377)
			(xy 108.123971 -114.765061) (xy 108.169329 -114.73261) (xy 108.218929 -114.707109) (xy 108.271713 -114.689102)
			(xy 108.326556 -114.678972) (xy 108.38229 -114.676935) (xy 108.437727 -114.683035) (xy 108.491684 -114.697141)
			(xy 108.543013 -114.718953) (xy 108.590619 -114.748007) (xy 108.633487 -114.783682) (xy 108.670704 -114.825219)
			(xy 108.701477 -114.871732) (xy 108.725149 -114.922229) (xy 108.741217 -114.975636) (xy 108.743386 -114.990372)
			(xy 109.365032 -114.990372) (xy 109.369103 -114.93475) (xy 109.381229 -114.880313) (xy 109.401152 -114.828222)
			(xy 109.428448 -114.779587) (xy 109.462534 -114.735444) (xy 109.502683 -114.696735) (xy 109.548041 -114.664284)
			(xy 109.597641 -114.638783) (xy 109.650425 -114.620776) (xy 109.705268 -114.610646) (xy 109.761002 -114.608609)
			(xy 109.816439 -114.614709) (xy 109.870396 -114.628815) (xy 109.921725 -114.650627) (xy 109.969331 -114.679681)
			(xy 110.012199 -114.715356) (xy 110.049416 -114.756893) (xy 110.080189 -114.803406) (xy 110.103861 -114.853903)
			(xy 110.119929 -114.90731) (xy 110.127779 -114.960654) (xy 110.891826 -114.960654) (xy 110.895897 -114.905032)
			(xy 110.908023 -114.850595) (xy 110.927946 -114.798504) (xy 110.955242 -114.749869) (xy 110.989328 -114.705726)
			(xy 111.029477 -114.667017) (xy 111.074835 -114.634566) (xy 111.124435 -114.609065) (xy 111.177219 -114.591058)
			(xy 111.232062 -114.580928) (xy 111.287796 -114.578891) (xy 111.343233 -114.584991) (xy 111.39719 -114.599097)
			(xy 111.448519 -114.620909) (xy 111.496125 -114.649963) (xy 111.538993 -114.685638) (xy 111.57621 -114.727175)
			(xy 111.606983 -114.773688) (xy 111.630655 -114.824185) (xy 111.646723 -114.877592) (xy 111.654843 -114.932768)
			(xy 111.655352 -114.960654) (xy 111.654843 -114.98854) (xy 111.646723 -115.043716) (xy 111.630655 -115.097123)
			(xy 111.606983 -115.14762) (xy 111.57621 -115.194133) (xy 111.538993 -115.23567) (xy 111.496125 -115.271345)
			(xy 111.448519 -115.300399) (xy 111.39719 -115.322211) (xy 111.343233 -115.336317) (xy 111.287796 -115.342417)
			(xy 111.232062 -115.34038) (xy 111.177219 -115.33025) (xy 111.124435 -115.312243) (xy 111.074835 -115.286742)
			(xy 111.029477 -115.254291) (xy 110.989328 -115.215582) (xy 110.955242 -115.171439) (xy 110.927946 -115.122804)
			(xy 110.908023 -115.070713) (xy 110.895897 -115.016276) (xy 110.891826 -114.960654) (xy 110.127779 -114.960654)
			(xy 110.128049 -114.962486) (xy 110.128558 -114.990372) (xy 110.128049 -115.018258) (xy 110.119929 -115.073434)
			(xy 110.103861 -115.126841) (xy 110.080189 -115.177338) (xy 110.049416 -115.223851) (xy 110.012199 -115.265388)
			(xy 109.969331 -115.301063) (xy 109.921725 -115.330117) (xy 109.870396 -115.351929) (xy 109.816439 -115.366035)
			(xy 109.761002 -115.372135) (xy 109.705268 -115.370098) (xy 109.650425 -115.359968) (xy 109.597641 -115.341961)
			(xy 109.548041 -115.31646) (xy 109.502683 -115.284009) (xy 109.462534 -115.2453) (xy 109.428448 -115.201157)
			(xy 109.401152 -115.152522) (xy 109.381229 -115.100431) (xy 109.369103 -115.045994) (xy 109.365032 -114.990372)
			(xy 108.743386 -114.990372) (xy 108.749337 -115.030812) (xy 108.749846 -115.058698) (xy 108.749337 -115.086584)
			(xy 108.741217 -115.14176) (xy 108.725149 -115.195167) (xy 108.701477 -115.245664) (xy 108.670704 -115.292177)
			(xy 108.633487 -115.333714) (xy 108.590619 -115.369389) (xy 108.543013 -115.398443) (xy 108.491684 -115.420255)
			(xy 108.437727 -115.434361) (xy 108.38229 -115.440461) (xy 108.326556 -115.438424) (xy 108.271713 -115.428294)
			(xy 108.218929 -115.410287) (xy 108.169329 -115.384786) (xy 108.123971 -115.352335) (xy 108.083822 -115.313626)
			(xy 108.049736 -115.269483) (xy 108.02244 -115.220848) (xy 108.002517 -115.168757) (xy 107.990391 -115.11432)
			(xy 107.98632 -115.058698) (xy 107.379893 -115.058698) (xy 107.374697 -115.094008) (xy 107.358629 -115.147415)
			(xy 107.334957 -115.197912) (xy 107.304184 -115.244425) (xy 107.266967 -115.285962) (xy 107.224099 -115.321637)
			(xy 107.176493 -115.350691) (xy 107.125164 -115.372503) (xy 107.071207 -115.386609) (xy 107.01577 -115.392709)
			(xy 106.960036 -115.390672) (xy 106.905193 -115.380542) (xy 106.852409 -115.362535) (xy 106.802809 -115.337034)
			(xy 106.757451 -115.304583) (xy 106.717302 -115.265874) (xy 106.683216 -115.221731) (xy 106.65592 -115.173096)
			(xy 106.635997 -115.121005) (xy 106.623871 -115.066568) (xy 106.6198 -115.010946) (xy 89.871678 -115.010946)
			(xy 89.917955 -115.030611) (xy 89.965561 -115.059665) (xy 90.008429 -115.09534) (xy 90.045646 -115.136877)
			(xy 90.076419 -115.18339) (xy 90.100091 -115.233887) (xy 90.116159 -115.287294) (xy 90.124279 -115.34247)
			(xy 90.124788 -115.370356) (xy 90.124279 -115.398242) (xy 90.116159 -115.453418) (xy 90.100091 -115.506825)
			(xy 90.076419 -115.557322) (xy 90.045646 -115.603835) (xy 90.008429 -115.645372) (xy 89.965561 -115.681047)
			(xy 89.917955 -115.710101) (xy 89.866626 -115.731913) (xy 89.812669 -115.746019) (xy 89.757232 -115.752119)
			(xy 89.701498 -115.750082) (xy 89.646655 -115.739952) (xy 89.593871 -115.721945) (xy 89.544271 -115.696444)
			(xy 89.498913 -115.663993) (xy 89.458764 -115.625284) (xy 89.424678 -115.581141) (xy 89.397382 -115.532506)
			(xy 89.377459 -115.480415) (xy 89.365333 -115.425978) (xy 89.361262 -115.370356) (xy 88.023317 -115.370356)
			(xy 88.023699 -115.37295) (xy 88.024208 -115.400836) (xy 88.023699 -115.428722) (xy 88.015579 -115.483898)
			(xy 87.999511 -115.537305) (xy 87.975839 -115.587802) (xy 87.945066 -115.634315) (xy 87.907849 -115.675852)
			(xy 87.864981 -115.711527) (xy 87.817375 -115.740581) (xy 87.766046 -115.762393) (xy 87.712089 -115.776499)
			(xy 87.656652 -115.782599) (xy 87.600918 -115.780562) (xy 87.546075 -115.770432) (xy 87.493291 -115.752425)
			(xy 87.443691 -115.726924) (xy 87.398333 -115.694473) (xy 87.358184 -115.655764) (xy 87.324098 -115.611621)
			(xy 87.296802 -115.562986) (xy 87.276879 -115.510895) (xy 87.264753 -115.456458) (xy 87.260682 -115.400836)
			(xy 75.514192 -115.400836) (xy 75.508254 -115.442162) (xy 75.492902 -115.494461) (xy 75.470263 -115.544043)
			(xy 75.440797 -115.589897) (xy 75.405105 -115.631091) (xy 75.363913 -115.666785) (xy 75.31806 -115.696253)
			(xy 75.26848 -115.718895) (xy 75.216182 -115.734249) (xy 75.162231 -115.742004) (xy 75.134978 -115.742466)
			(xy 75.107607 -115.742021) (xy 75.053427 -115.734199) (xy 75.000923 -115.718706) (xy 74.951176 -115.695859)
			(xy 74.905211 -115.66613) (xy 74.88428 -115.648486) (xy 74.884026 -115.648232) (xy 74.876942 -115.642642)
			(xy 74.860023 -115.636399) (xy 74.851006 -115.63604) (xy 74.78395 -115.63604) (xy 74.774934 -115.636412)
			(xy 74.758017 -115.642648) (xy 74.75093 -115.648232) (xy 74.75093 -115.648486) (xy 74.750676 -115.648486)
			(xy 74.729724 -115.666101) (xy 74.683757 -115.695817) (xy 74.634015 -115.718658) (xy 74.581518 -115.734154)
			(xy 74.527346 -115.741989) (xy 74.499978 -115.742466) (xy 74.472723 -115.742065) (xy 74.418767 -115.734304)
			(xy 74.366466 -115.718943) (xy 74.316883 -115.696295) (xy 74.271027 -115.666821) (xy 74.229834 -115.631121)
			(xy 74.194141 -115.589921) (xy 74.164674 -115.544061) (xy 74.142034 -115.494474) (xy 74.126682 -115.44217)
			(xy 74.11893 -115.388213) (xy 74.11847 -115.360958) (xy 67.686832 -115.360958) (xy 67.685673 -115.368836)
			(xy 67.669605 -115.422243) (xy 67.645933 -115.47274) (xy 67.61516 -115.519253) (xy 67.577943 -115.56079)
			(xy 67.535075 -115.596465) (xy 67.487469 -115.625519) (xy 67.43614 -115.647331) (xy 67.382183 -115.661437)
			(xy 67.326746 -115.667537) (xy 67.271012 -115.6655) (xy 67.216169 -115.65537) (xy 67.163385 -115.637363)
			(xy 67.113785 -115.611862) (xy 67.068427 -115.579411) (xy 67.028278 -115.540702) (xy 66.994192 -115.496559)
			(xy 66.966896 -115.447924) (xy 66.946973 -115.395833) (xy 66.934847 -115.341396) (xy 66.930776 -115.285774)
			(xy 61.037724 -115.285774) (xy 60.401454 -115.922044) (xy 63.203326 -115.922044) (xy 63.207397 -115.866422)
			(xy 63.219523 -115.811985) (xy 63.239446 -115.759894) (xy 63.266742 -115.711259) (xy 63.300828 -115.667116)
			(xy 63.340977 -115.628407) (xy 63.386335 -115.595956) (xy 63.435935 -115.570455) (xy 63.488719 -115.552448)
			(xy 63.543562 -115.542318) (xy 63.599296 -115.540281) (xy 63.654733 -115.546381) (xy 63.70869 -115.560487)
			(xy 63.760019 -115.582299) (xy 63.807625 -115.611353) (xy 63.850493 -115.647028) (xy 63.88771 -115.688565)
			(xy 63.918483 -115.735078) (xy 63.942155 -115.785575) (xy 63.956314 -115.832636) (xy 92.979238 -115.832636)
			(xy 92.983309 -115.777014) (xy 92.995435 -115.722577) (xy 93.015358 -115.670486) (xy 93.042654 -115.621851)
			(xy 93.07674 -115.577708) (xy 93.116889 -115.538999) (xy 93.162247 -115.506548) (xy 93.211847 -115.481047)
			(xy 93.264631 -115.46304) (xy 93.319474 -115.45291) (xy 93.375208 -115.450873) (xy 93.430645 -115.456973)
			(xy 93.484602 -115.471079) (xy 93.535931 -115.492891) (xy 93.583537 -115.521945) (xy 93.626405 -115.55762)
			(xy 93.663622 -115.599157) (xy 93.694395 -115.64567) (xy 93.718067 -115.696167) (xy 93.734135 -115.749574)
			(xy 93.742255 -115.80475) (xy 93.742764 -115.832636) (xy 93.742255 -115.860522) (xy 93.734135 -115.915698)
			(xy 93.718067 -115.969105) (xy 93.694395 -116.019602) (xy 93.663622 -116.066115) (xy 93.626405 -116.107652)
			(xy 93.583537 -116.143327) (xy 93.535931 -116.172381) (xy 93.484602 -116.194193) (xy 93.430645 -116.208299)
			(xy 93.375208 -116.214399) (xy 93.319474 -116.212362) (xy 93.264631 -116.202232) (xy 93.211847 -116.184225)
			(xy 93.162247 -116.158724) (xy 93.116889 -116.126273) (xy 93.07674 -116.087564) (xy 93.042654 -116.043421)
			(xy 93.015358 -115.994786) (xy 92.995435 -115.942695) (xy 92.983309 -115.888258) (xy 92.979238 -115.832636)
			(xy 63.956314 -115.832636) (xy 63.958223 -115.838982) (xy 63.966343 -115.894158) (xy 63.966852 -115.922044)
			(xy 63.966343 -115.94993) (xy 63.958223 -116.005106) (xy 63.942155 -116.058513) (xy 63.918483 -116.10901)
			(xy 63.88771 -116.155523) (xy 63.850493 -116.19706) (xy 63.807625 -116.232735) (xy 63.760019 -116.261789)
			(xy 63.70869 -116.283601) (xy 63.654733 -116.297707) (xy 63.599296 -116.303807) (xy 63.543562 -116.30177)
			(xy 63.488719 -116.29164) (xy 63.435935 -116.273633) (xy 63.386335 -116.248132) (xy 63.340977 -116.215681)
			(xy 63.300828 -116.176972) (xy 63.266742 -116.132829) (xy 63.239446 -116.084194) (xy 63.219523 -116.032103)
			(xy 63.207397 -115.977666) (xy 63.203326 -115.922044) (xy 60.401454 -115.922044) (xy 59.875928 -116.44757)
			(xy 66.157092 -116.44757) (xy 66.161163 -116.391948) (xy 66.173289 -116.337511) (xy 66.193212 -116.28542)
			(xy 66.220508 -116.236785) (xy 66.254594 -116.192642) (xy 66.294743 -116.153933) (xy 66.340101 -116.121482)
			(xy 66.389701 -116.095981) (xy 66.442485 -116.077974) (xy 66.497328 -116.067844) (xy 66.553062 -116.065807)
			(xy 66.608499 -116.071907) (xy 66.662456 -116.086013) (xy 66.713785 -116.107825) (xy 66.761391 -116.136879)
			(xy 66.804259 -116.172554) (xy 66.841476 -116.214091) (xy 66.872249 -116.260604) (xy 66.895921 -116.311101)
			(xy 66.911989 -116.364508) (xy 66.920109 -116.419684) (xy 66.920618 -116.44757) (xy 66.920109 -116.475456)
			(xy 66.919839 -116.477288) (xy 71.304402 -116.477288) (xy 71.308473 -116.421666) (xy 71.320599 -116.367229)
			(xy 71.340522 -116.315138) (xy 71.367818 -116.266503) (xy 71.401904 -116.22236) (xy 71.442053 -116.183651)
			(xy 71.487411 -116.1512) (xy 71.537011 -116.125699) (xy 71.589795 -116.107692) (xy 71.644638 -116.097562)
			(xy 71.700372 -116.095525) (xy 71.755809 -116.101625) (xy 71.809766 -116.115731) (xy 71.861095 -116.137543)
			(xy 71.908701 -116.166597) (xy 71.951569 -116.202272) (xy 71.988786 -116.243809) (xy 72.019559 -116.290322)
			(xy 72.043231 -116.340819) (xy 72.059299 -116.394226) (xy 72.067419 -116.449402) (xy 72.067928 -116.477288)
			(xy 72.067419 -116.505174) (xy 72.059299 -116.56035) (xy 72.043231 -116.613757) (xy 72.019559 -116.664254)
			(xy 71.988786 -116.710767) (xy 71.951569 -116.752304) (xy 71.908701 -116.787979) (xy 71.861095 -116.817033)
			(xy 71.809766 -116.838845) (xy 71.755809 -116.852951) (xy 71.700372 -116.859051) (xy 71.644638 -116.857014)
			(xy 71.589795 -116.846884) (xy 71.537011 -116.828877) (xy 71.487411 -116.803376) (xy 71.442053 -116.770925)
			(xy 71.401904 -116.732216) (xy 71.367818 -116.688073) (xy 71.340522 -116.639438) (xy 71.320599 -116.587347)
			(xy 71.308473 -116.53291) (xy 71.304402 -116.477288) (xy 66.919839 -116.477288) (xy 66.911989 -116.530632)
			(xy 66.895921 -116.584039) (xy 66.872249 -116.634536) (xy 66.841476 -116.681049) (xy 66.804259 -116.722586)
			(xy 66.761391 -116.758261) (xy 66.713785 -116.787315) (xy 66.662456 -116.809127) (xy 66.608499 -116.823233)
			(xy 66.553062 -116.829333) (xy 66.497328 -116.827296) (xy 66.442485 -116.817166) (xy 66.389701 -116.799159)
			(xy 66.340101 -116.773658) (xy 66.294743 -116.741207) (xy 66.254594 -116.702498) (xy 66.220508 -116.658355)
			(xy 66.193212 -116.60972) (xy 66.173289 -116.557629) (xy 66.161163 -116.503192) (xy 66.157092 -116.44757)
			(xy 59.875928 -116.44757) (xy 58.817002 -117.506496) (xy 58.810171 -117.513904) (xy 58.802446 -117.532497)
			(xy 58.802016 -117.542564) (xy 58.802016 -117.723666) (xy 69.689724 -117.723666) (xy 69.693795 -117.668044)
			(xy 69.705921 -117.613607) (xy 69.725844 -117.561516) (xy 69.75314 -117.512881) (xy 69.787226 -117.468738)
			(xy 69.827375 -117.430029) (xy 69.872733 -117.397578) (xy 69.922333 -117.372077) (xy 69.975117 -117.35407)
			(xy 70.02996 -117.34394) (xy 70.085694 -117.341903) (xy 70.141131 -117.348003) (xy 70.195088 -117.362109)
			(xy 70.246417 -117.383921) (xy 70.294023 -117.412975) (xy 70.336891 -117.44865) (xy 70.374108 -117.490187)
			(xy 70.404881 -117.5367) (xy 70.428553 -117.587197) (xy 70.444621 -117.640604) (xy 70.452741 -117.69578)
			(xy 70.45325 -117.723666) (xy 70.452741 -117.751552) (xy 70.451686 -117.758718) (xy 74.474832 -117.758718)
			(xy 74.474832 -116.895118) (xy 74.475322 -116.865134) (xy 74.48315 -116.805678) (xy 74.498671 -116.747753)
			(xy 74.52162 -116.692349) (xy 74.551604 -116.640415) (xy 74.58811 -116.592839) (xy 74.630515 -116.550434)
			(xy 74.678091 -116.513928) (xy 74.730025 -116.483944) (xy 74.785429 -116.460995) (xy 74.843354 -116.445474)
			(xy 74.90281 -116.437646) (xy 74.962778 -116.437646) (xy 75.022234 -116.445474) (xy 75.080159 -116.460995)
			(xy 75.135563 -116.483944) (xy 75.187497 -116.513928) (xy 75.235073 -116.550434) (xy 75.277478 -116.592839)
			(xy 75.313984 -116.640415) (xy 75.330961 -116.66982) (xy 89.3732 -116.66982) (xy 89.377271 -116.614198)
			(xy 89.389397 -116.559761) (xy 89.40932 -116.50767) (xy 89.436616 -116.459035) (xy 89.470702 -116.414892)
			(xy 89.510851 -116.376183) (xy 89.556209 -116.343732) (xy 89.605809 -116.318231) (xy 89.658593 -116.300224)
			(xy 89.713436 -116.290094) (xy 89.76917 -116.288057) (xy 89.824607 -116.294157) (xy 89.878564 -116.308263)
			(xy 89.929893 -116.330075) (xy 89.977499 -116.359129) (xy 90.020367 -116.394804) (xy 90.057584 -116.436341)
			(xy 90.088357 -116.482854) (xy 90.112029 -116.533351) (xy 90.128097 -116.586758) (xy 90.13434 -116.62918)
			(xy 105.137964 -116.62918) (xy 105.142035 -116.573558) (xy 105.154161 -116.519121) (xy 105.174084 -116.46703)
			(xy 105.20138 -116.418395) (xy 105.235466 -116.374252) (xy 105.275615 -116.335543) (xy 105.320973 -116.303092)
			(xy 105.370573 -116.277591) (xy 105.423357 -116.259584) (xy 105.4782 -116.249454) (xy 105.533934 -116.247417)
			(xy 105.589371 -116.253517) (xy 105.643328 -116.267623) (xy 105.694657 -116.289435) (xy 105.742263 -116.318489)
			(xy 105.785131 -116.354164) (xy 105.822348 -116.395701) (xy 105.853121 -116.442214) (xy 105.876793 -116.492711)
			(xy 105.892861 -116.546118) (xy 105.900981 -116.601294) (xy 105.90149 -116.62918) (xy 105.900981 -116.657066)
			(xy 105.892861 -116.712242) (xy 105.876793 -116.765649) (xy 105.853121 -116.816146) (xy 105.822348 -116.862659)
			(xy 105.785131 -116.904196) (xy 105.742263 -116.939871) (xy 105.694657 -116.968925) (xy 105.643328 -116.990737)
			(xy 105.589371 -117.004843) (xy 105.533934 -117.010943) (xy 105.4782 -117.008906) (xy 105.423357 -116.998776)
			(xy 105.370573 -116.980769) (xy 105.320973 -116.955268) (xy 105.275615 -116.922817) (xy 105.235466 -116.884108)
			(xy 105.20138 -116.839965) (xy 105.174084 -116.79133) (xy 105.154161 -116.739239) (xy 105.142035 -116.684802)
			(xy 105.137964 -116.62918) (xy 90.13434 -116.62918) (xy 90.136217 -116.641934) (xy 90.136726 -116.66982)
			(xy 90.136217 -116.697706) (xy 90.128097 -116.752882) (xy 90.112029 -116.806289) (xy 90.088357 -116.856786)
			(xy 90.057584 -116.903299) (xy 90.020367 -116.944836) (xy 89.977499 -116.980511) (xy 89.929893 -117.009565)
			(xy 89.878564 -117.031377) (xy 89.824607 -117.045483) (xy 89.76917 -117.051583) (xy 89.713436 -117.049546)
			(xy 89.658593 -117.039416) (xy 89.605809 -117.021409) (xy 89.556209 -116.995908) (xy 89.510851 -116.963457)
			(xy 89.470702 -116.924748) (xy 89.436616 -116.880605) (xy 89.40932 -116.83197) (xy 89.389397 -116.779879)
			(xy 89.377271 -116.725442) (xy 89.3732 -116.66982) (xy 75.330961 -116.66982) (xy 75.343968 -116.692349)
			(xy 75.366917 -116.747753) (xy 75.382438 -116.805678) (xy 75.390266 -116.865134) (xy 75.390756 -116.895118)
			(xy 75.390756 -117.390451) (xy 90.742495 -117.390451) (xy 90.742495 -117.335949) (xy 90.750252 -117.282003)
			(xy 90.765607 -117.229709) (xy 90.788248 -117.180133) (xy 90.817715 -117.134284) (xy 90.853406 -117.093095)
			(xy 90.894597 -117.057405) (xy 90.940447 -117.027941) (xy 90.990024 -117.005301) (xy 91.042318 -116.989948)
			(xy 91.096265 -116.982194) (xy 91.123516 -116.981732) (xy 91.152431 -116.982299) (xy 91.209601 -116.991016)
			(xy 91.264799 -117.008264) (xy 91.316761 -117.033646) (xy 91.364296 -117.066582) (xy 91.406315 -117.106316)
			(xy 91.424506 -117.128798) (xy 91.432121 -117.137598) (xy 91.453016 -117.147786) (xy 91.464638 -117.148356)
			(xy 91.544394 -117.148356) (xy 91.556026 -117.147815) (xy 91.576937 -117.137629) (xy 91.584526 -117.128798)
			(xy 91.602702 -117.106302) (xy 91.644725 -117.066567) (xy 91.692263 -117.03363) (xy 91.744227 -117.008244)
			(xy 91.799427 -116.99099) (xy 91.856599 -116.982265) (xy 91.885516 -116.981732) (xy 91.912769 -116.982139)
			(xy 91.966721 -116.989898) (xy 92.019019 -117.005256) (xy 92.0686 -117.027901) (xy 92.114453 -117.057371)
			(xy 92.155646 -117.093066) (xy 92.163938 -117.102636) (xy 92.979238 -117.102636) (xy 92.983309 -117.047014)
			(xy 92.995435 -116.992577) (xy 93.015358 -116.940486) (xy 93.042654 -116.891851) (xy 93.07674 -116.847708)
			(xy 93.116889 -116.808999) (xy 93.162247 -116.776548) (xy 93.211847 -116.751047) (xy 93.264631 -116.73304)
			(xy 93.319474 -116.72291) (xy 93.375208 -116.720873) (xy 93.430645 -116.726973) (xy 93.484602 -116.741079)
			(xy 93.535931 -116.762891) (xy 93.583537 -116.791945) (xy 93.626405 -116.82762) (xy 93.663622 -116.869157)
			(xy 93.694395 -116.91567) (xy 93.718067 -116.966167) (xy 93.734135 -117.019574) (xy 93.742255 -117.07475)
			(xy 93.742764 -117.102636) (xy 93.742255 -117.130522) (xy 93.734135 -117.185698) (xy 93.718067 -117.239105)
			(xy 93.713814 -117.248178) (xy 107.738924 -117.248178) (xy 107.742995 -117.192556) (xy 107.755121 -117.138119)
			(xy 107.775044 -117.086028) (xy 107.80234 -117.037393) (xy 107.836426 -116.99325) (xy 107.876575 -116.954541)
			(xy 107.921933 -116.92209) (xy 107.971533 -116.896589) (xy 108.024317 -116.878582) (xy 108.07916 -116.868452)
			(xy 108.134894 -116.866415) (xy 108.190331 -116.872515) (xy 108.244288 -116.886621) (xy 108.295617 -116.908433)
			(xy 108.343223 -116.937487) (xy 108.386091 -116.973162) (xy 108.423308 -117.014699) (xy 108.454081 -117.061212)
			(xy 108.477753 -117.111709) (xy 108.493821 -117.165116) (xy 108.501941 -117.220292) (xy 108.50245 -117.248178)
			(xy 108.754924 -117.248178) (xy 108.758995 -117.192556) (xy 108.771121 -117.138119) (xy 108.791044 -117.086028)
			(xy 108.81834 -117.037393) (xy 108.852426 -116.99325) (xy 108.892575 -116.954541) (xy 108.937933 -116.92209)
			(xy 108.987533 -116.896589) (xy 109.040317 -116.878582) (xy 109.09516 -116.868452) (xy 109.150894 -116.866415)
			(xy 109.206331 -116.872515) (xy 109.260288 -116.886621) (xy 109.311617 -116.908433) (xy 109.359223 -116.937487)
			(xy 109.402091 -116.973162) (xy 109.439308 -117.014699) (xy 109.470081 -117.061212) (xy 109.493753 -117.111709)
			(xy 109.509821 -117.165116) (xy 109.517941 -117.220292) (xy 109.51845 -117.248178) (xy 109.770924 -117.248178)
			(xy 109.774995 -117.192556) (xy 109.787121 -117.138119) (xy 109.807044 -117.086028) (xy 109.83434 -117.037393)
			(xy 109.868426 -116.99325) (xy 109.908575 -116.954541) (xy 109.953933 -116.92209) (xy 110.003533 -116.896589)
			(xy 110.056317 -116.878582) (xy 110.11116 -116.868452) (xy 110.166894 -116.866415) (xy 110.222331 -116.872515)
			(xy 110.276288 -116.886621) (xy 110.327617 -116.908433) (xy 110.375223 -116.937487) (xy 110.418091 -116.973162)
			(xy 110.455308 -117.014699) (xy 110.486081 -117.061212) (xy 110.509753 -117.111709) (xy 110.525821 -117.165116)
			(xy 110.533941 -117.220292) (xy 110.53445 -117.248178) (xy 110.533941 -117.276064) (xy 110.525821 -117.33124)
			(xy 110.509753 -117.384647) (xy 110.486081 -117.435144) (xy 110.455308 -117.481657) (xy 110.418091 -117.523194)
			(xy 110.375223 -117.558869) (xy 110.327617 -117.587923) (xy 110.276288 -117.609735) (xy 110.222331 -117.623841)
			(xy 110.166894 -117.629941) (xy 110.11116 -117.627904) (xy 110.056317 -117.617774) (xy 110.003533 -117.599767)
			(xy 109.953933 -117.574266) (xy 109.908575 -117.541815) (xy 109.868426 -117.503106) (xy 109.83434 -117.458963)
			(xy 109.807044 -117.410328) (xy 109.787121 -117.358237) (xy 109.774995 -117.3038) (xy 109.770924 -117.248178)
			(xy 109.51845 -117.248178) (xy 109.517941 -117.276064) (xy 109.509821 -117.33124) (xy 109.493753 -117.384647)
			(xy 109.470081 -117.435144) (xy 109.439308 -117.481657) (xy 109.402091 -117.523194) (xy 109.359223 -117.558869)
			(xy 109.311617 -117.587923) (xy 109.260288 -117.609735) (xy 109.206331 -117.623841) (xy 109.150894 -117.629941)
			(xy 109.09516 -117.627904) (xy 109.040317 -117.617774) (xy 108.987533 -117.599767) (xy 108.937933 -117.574266)
			(xy 108.892575 -117.541815) (xy 108.852426 -117.503106) (xy 108.81834 -117.458963) (xy 108.791044 -117.410328)
			(xy 108.771121 -117.358237) (xy 108.758995 -117.3038) (xy 108.754924 -117.248178) (xy 108.50245 -117.248178)
			(xy 108.501941 -117.276064) (xy 108.493821 -117.33124) (xy 108.477753 -117.384647) (xy 108.454081 -117.435144)
			(xy 108.423308 -117.481657) (xy 108.386091 -117.523194) (xy 108.343223 -117.558869) (xy 108.295617 -117.587923)
			(xy 108.244288 -117.609735) (xy 108.190331 -117.623841) (xy 108.134894 -117.629941) (xy 108.07916 -117.627904)
			(xy 108.024317 -117.617774) (xy 107.971533 -117.599767) (xy 107.921933 -117.574266) (xy 107.876575 -117.541815)
			(xy 107.836426 -117.503106) (xy 107.80234 -117.458963) (xy 107.775044 -117.410328) (xy 107.755121 -117.358237)
			(xy 107.742995 -117.3038) (xy 107.738924 -117.248178) (xy 93.713814 -117.248178) (xy 93.694395 -117.289602)
			(xy 93.663622 -117.336115) (xy 93.626405 -117.377652) (xy 93.583537 -117.413327) (xy 93.535931 -117.442381)
			(xy 93.484602 -117.464193) (xy 93.430645 -117.478299) (xy 93.375208 -117.484399) (xy 93.319474 -117.482362)
			(xy 93.264631 -117.472232) (xy 93.211847 -117.454225) (xy 93.162247 -117.428724) (xy 93.116889 -117.396273)
			(xy 93.07674 -117.357564) (xy 93.042654 -117.313421) (xy 93.015358 -117.264786) (xy 92.995435 -117.212695)
			(xy 92.983309 -117.158258) (xy 92.979238 -117.102636) (xy 92.163938 -117.102636) (xy 92.191339 -117.13426)
			(xy 92.220807 -117.180114) (xy 92.243449 -117.229696) (xy 92.258805 -117.281995) (xy 92.266562 -117.335947)
			(xy 92.266562 -117.390453) (xy 92.258805 -117.444405) (xy 92.243449 -117.496704) (xy 92.220807 -117.546286)
			(xy 92.191339 -117.59214) (xy 92.155646 -117.633334) (xy 92.114453 -117.66903) (xy 92.0686 -117.698499)
			(xy 92.019019 -117.721144) (xy 91.966721 -117.736502) (xy 91.912769 -117.744261) (xy 91.885516 -117.744748)
			(xy 91.856599 -117.744238) (xy 91.799426 -117.73551) (xy 91.744226 -117.718252) (xy 91.692264 -117.692859)
			(xy 91.644731 -117.659913) (xy 91.602715 -117.620169) (xy 91.584526 -117.597682) (xy 91.576901 -117.588893)
			(xy 91.556014 -117.5787) (xy 91.544394 -117.578124) (xy 91.464638 -117.578124) (xy 91.453002 -117.578633)
			(xy 91.432092 -117.588842) (xy 91.424506 -117.597682) (xy 91.406307 -117.620159) (xy 91.364289 -117.659895)
			(xy 91.316756 -117.692836) (xy 91.264797 -117.718225) (xy 91.2096 -117.735483) (xy 91.152432 -117.744213)
			(xy 91.123516 -117.744748) (xy 91.096265 -117.744206) (xy 91.042318 -117.736452) (xy 90.990024 -117.721099)
			(xy 90.940447 -117.698459) (xy 90.894597 -117.668995) (xy 90.853406 -117.633305) (xy 90.817715 -117.592116)
			(xy 90.788248 -117.546267) (xy 90.765607 -117.496691) (xy 90.750252 -117.444397) (xy 90.742495 -117.390451)
			(xy 75.390756 -117.390451) (xy 75.390756 -117.758718) (xy 75.390266 -117.788702) (xy 75.382438 -117.848158)
			(xy 75.366917 -117.906083) (xy 75.343968 -117.961487) (xy 75.313984 -118.013421) (xy 75.277478 -118.060997)
			(xy 75.235073 -118.103402) (xy 75.187497 -118.139908) (xy 75.135563 -118.169892) (xy 75.080159 -118.192841)
			(xy 75.022234 -118.208362) (xy 74.962778 -118.21619) (xy 74.90281 -118.21619) (xy 74.843354 -118.208362)
			(xy 74.785429 -118.192841) (xy 74.730025 -118.169892) (xy 74.678091 -118.139908) (xy 74.630515 -118.103402)
			(xy 74.58811 -118.060997) (xy 74.551604 -118.013421) (xy 74.52162 -117.961487) (xy 74.498671 -117.906083)
			(xy 74.48315 -117.848158) (xy 74.475322 -117.788702) (xy 74.474832 -117.758718) (xy 70.451686 -117.758718)
			(xy 70.444621 -117.806728) (xy 70.428553 -117.860135) (xy 70.404881 -117.910632) (xy 70.374108 -117.957145)
			(xy 70.336891 -117.998682) (xy 70.294023 -118.034357) (xy 70.246417 -118.063411) (xy 70.195088 -118.085223)
			(xy 70.141131 -118.099329) (xy 70.085694 -118.105429) (xy 70.02996 -118.103392) (xy 69.975117 -118.093262)
			(xy 69.922333 -118.075255) (xy 69.872733 -118.049754) (xy 69.827375 -118.017303) (xy 69.787226 -117.978594)
			(xy 69.75314 -117.934451) (xy 69.725844 -117.885816) (xy 69.705921 -117.833725) (xy 69.693795 -117.779288)
			(xy 69.689724 -117.723666) (xy 58.802016 -117.723666) (xy 58.802016 -132.695442) (xy 58.801534 -132.728322)
			(xy 58.794173 -132.793668) (xy 58.779538 -132.857778) (xy 58.757813 -132.919846) (xy 58.729271 -132.979088)
			(xy 58.694272 -133.03476) (xy 58.653256 -133.086161) (xy 58.630312 -133.109716) (xy 57.87771 -133.862064)
			(xy 57.870895 -133.869484) (xy 57.86316 -133.888068) (xy 57.862724 -133.898132) (xy 57.862724 -134.62)
			(xy 57.86219 -134.655397) (xy 57.853657 -134.725676) (xy 57.836714 -134.794414) (xy 57.81161 -134.860608)
			(xy 57.77871 -134.923294) (xy 57.738494 -134.981557) (xy 57.691548 -135.034548) (xy 57.638557 -135.081494)
			(xy 57.580294 -135.12171) (xy 57.517608 -135.15461) (xy 57.451414 -135.179714) (xy 57.382676 -135.196657)
			(xy 57.312397 -135.20519) (xy 57.277 -135.205724) (xy 57.275984 -135.205724) (xy 57.245642 -135.205326)
			(xy 57.185288 -135.199004) (xy 57.125912 -135.186469) (xy 57.096914 -135.17753) (xy 57.08523 -135.17372)
			(xy 57.0611 -135.17753) (xy 56.9849 -135.232902) (xy 56.975613 -135.24057) (xy 56.964746 -135.262026)
			(xy 56.964072 -135.27405) (xy 56.964072 -136.610598) (xy 56.964479 -136.62067) (xy 56.972211 -136.639268)
			(xy 56.979058 -136.646666) (xy 57.24271 -136.910318) (xy 57.247106 -136.914431) (xy 57.257369 -136.920718)
			(xy 57.26303 -136.922764) (xy 57.263538 -136.922764) (xy 57.289078 -136.931222) (xy 57.337683 -136.95429)
			(xy 57.382565 -136.983958) (xy 57.422833 -137.019637) (xy 57.457689 -137.06062) (xy 57.486442 -137.106093)
			(xy 57.508521 -137.155155) (xy 57.523489 -137.206832) (xy 57.531047 -137.2601) (xy 57.531508 -137.287)
			(xy 57.531022 -137.314251) (xy 57.523266 -137.368199) (xy 57.507911 -137.420494) (xy 57.485269 -137.470071)
			(xy 57.455803 -137.515921) (xy 57.420112 -137.557112) (xy 57.378921 -137.592803) (xy 57.333071 -137.622269)
			(xy 57.283494 -137.644911) (xy 57.231199 -137.660266) (xy 57.177251 -137.668022) (xy 57.15 -137.668508)
			(xy 57.123091 -137.668003) (xy 57.069809 -137.660427) (xy 57.018119 -137.645439) (xy 56.969049 -137.623336)
			(xy 56.923571 -137.594558) (xy 56.882588 -137.559675) (xy 56.846913 -137.51938) (xy 56.817255 -137.474471)
			(xy 56.794201 -137.425841) (xy 56.785764 -137.400284) (xy 56.785764 -137.40003) (xy 56.78379 -137.394335)
			(xy 56.77749 -137.384061) (xy 56.773318 -137.37971) (xy 56.516016 -137.122408) (xy 56.486044 -137.116312)
			(xy 56.47182 -137.122408) (xy 56.462695 -137.12663) (xy 56.448458 -137.140803) (xy 56.440749 -137.159354)
			(xy 56.440324 -137.169398) (xy 56.440324 -138.628374) (xy 56.440813 -138.638542) (xy 56.448726 -138.657277)
			(xy 56.463283 -138.671478) (xy 56.472582 -138.675618) (xy 56.56072 -138.710162) (xy 56.570359 -138.713533)
			(xy 56.590757 -138.713062) (xy 56.609348 -138.704653) (xy 56.6166 -138.697462) (xy 56.634697 -138.678589)
			(xy 56.675185 -138.645503) (xy 56.719809 -138.61825) (xy 56.767734 -138.597341) (xy 56.818063 -138.583166)
			(xy 56.869857 -138.575991) (xy 56.896 -138.575542) (xy 56.923255 -138.575955) (xy 56.97721 -138.583714)
			(xy 57.029512 -138.599072) (xy 57.079096 -138.621718) (xy 57.124951 -138.651191) (xy 57.166145 -138.68689)
			(xy 57.201839 -138.728089) (xy 57.231306 -138.773948) (xy 57.253945 -138.823535) (xy 57.266071 -138.864848)
			(xy 61.94044 -138.864848) (xy 61.940866 -138.837936) (xy 61.94845 -138.784649) (xy 61.963447 -138.732956)
			(xy 61.985559 -138.683883) (xy 62.014347 -138.638404) (xy 62.04924 -138.597422) (xy 62.089545 -138.56175)
			(xy 62.134464 -138.532094) (xy 62.183103 -138.509045) (xy 62.208664 -138.500612) (xy 62.208918 -138.500612)
			(xy 62.214611 -138.498633) (xy 62.224887 -138.492337) (xy 62.229238 -138.488166) (xy 62.319408 -138.397996)
			(xy 62.325713 -138.391049) (xy 62.333352 -138.373936) (xy 62.334345 -138.355223) (xy 62.331854 -138.34618)
			(xy 62.299342 -138.246612) (xy 62.277498 -138.22807) (xy 62.263274 -138.225784) (xy 62.23663 -138.221207)
			(xy 62.184919 -138.205438) (xy 62.135952 -138.182527) (xy 62.09071 -138.152931) (xy 62.050101 -138.117244)
			(xy 62.014936 -138.076181) (xy 61.985922 -138.030565) (xy 61.963638 -137.981309) (xy 61.948533 -137.9294)
			(xy 61.940907 -137.875879) (xy 61.94044 -137.848848) (xy 61.9409 -137.821594) (xy 61.948652 -137.767641)
			(xy 61.964004 -137.71534) (xy 61.986645 -137.665757) (xy 62.016112 -137.619901) (xy 62.051806 -137.578706)
			(xy 62.093001 -137.543012) (xy 62.138857 -137.513545) (xy 62.18844 -137.490904) (xy 62.240741 -137.475552)
			(xy 62.294694 -137.4678) (xy 62.321948 -137.46734) (xy 62.345629 -137.467706) (xy 62.392629 -137.473559)
			(xy 62.415674 -137.479024) (xy 62.427082 -137.481336) (xy 62.449841 -137.476576) (xy 62.459362 -137.46988)
			(xy 62.522862 -137.420604) (xy 62.531668 -137.412996) (xy 62.54185 -137.392096) (xy 62.54242 -137.380472)
			(xy 62.54242 -119.47906) (xy 62.542937 -119.453036) (xy 62.551104 -119.401631) (xy 62.5672 -119.352134)
			(xy 62.59083 -119.305758) (xy 62.621414 -119.263642) (xy 62.639448 -119.244872) (xy 62.930786 -118.953534)
			(xy 62.937602 -118.946115) (xy 62.945336 -118.92753) (xy 62.945772 -118.917466) (xy 62.945772 -118.52656)
			(xy 62.943232 -118.515384) (xy 62.940438 -118.51005) (xy 62.93993 -118.509034) (xy 62.926217 -118.481555)
			(xy 62.90676 -118.423309) (xy 62.89688 -118.3627) (xy 62.896242 -118.331996) (xy 62.896728 -118.304745)
			(xy 62.904484 -118.250797) (xy 62.919839 -118.198502) (xy 62.942481 -118.148925) (xy 62.971947 -118.103075)
			(xy 63.007638 -118.061884) (xy 63.048829 -118.026193) (xy 63.094679 -117.996727) (xy 63.144256 -117.974085)
			(xy 63.196551 -117.95873) (xy 63.250499 -117.950974) (xy 63.305001 -117.950974) (xy 63.358949 -117.95873)
			(xy 63.411244 -117.974085) (xy 63.460821 -117.996727) (xy 63.506671 -118.026193) (xy 63.547862 -118.061884)
			(xy 63.583553 -118.103075) (xy 63.613019 -118.148925) (xy 63.635661 -118.198502) (xy 63.651016 -118.250797)
			(xy 63.658772 -118.304745) (xy 63.659258 -118.331996) (xy 63.658645 -118.362799) (xy 63.648722 -118.4236)
			(xy 63.629149 -118.482014) (xy 63.615316 -118.509542) (xy 63.615062 -118.51005) (xy 63.612584 -118.51537)
			(xy 63.609892 -118.526789) (xy 63.609728 -118.532656) (xy 63.609728 -119.075962) (xy 63.609223 -119.102049)
			(xy 63.601062 -119.153579) (xy 63.584934 -119.203197) (xy 63.561237 -119.249678) (xy 63.530557 -119.291876)
			(xy 63.512446 -119.310658) (xy 63.255682 -119.567198) (xy 66.599308 -119.567198) (xy 66.599308 -118.703598)
			(xy 66.599798 -118.673614) (xy 66.607626 -118.614158) (xy 66.623147 -118.556233) (xy 66.646096 -118.500829)
			(xy 66.67608 -118.448895) (xy 66.712586 -118.401319) (xy 66.754991 -118.358914) (xy 66.802567 -118.322408)
			(xy 66.854501 -118.292424) (xy 66.909905 -118.269475) (xy 66.96783 -118.253954) (xy 67.027286 -118.246126)
			(xy 67.087254 -118.246126) (xy 67.14671 -118.253954) (xy 67.204635 -118.269475) (xy 67.260039 -118.292424)
			(xy 67.311973 -118.322408) (xy 67.359549 -118.358914) (xy 67.401954 -118.401319) (xy 67.43846 -118.448895)
			(xy 67.468444 -118.500829) (xy 67.491393 -118.556233) (xy 67.506914 -118.614158) (xy 67.514742 -118.673614)
			(xy 67.515232 -118.703598) (xy 67.515232 -118.711218) (xy 69.809358 -118.711218) (xy 69.813429 -118.655596)
			(xy 69.825555 -118.601159) (xy 69.845478 -118.549068) (xy 69.872774 -118.500433) (xy 69.90686 -118.45629)
			(xy 69.947009 -118.417581) (xy 69.992367 -118.38513) (xy 70.041967 -118.359629) (xy 70.094751 -118.341622)
			(xy 70.149594 -118.331492) (xy 70.205328 -118.329455) (xy 70.260765 -118.335555) (xy 70.314722 -118.349661)
			(xy 70.366051 -118.371473) (xy 70.413657 -118.400527) (xy 70.456525 -118.436202) (xy 70.493742 -118.477739)
			(xy 70.524515 -118.524252) (xy 70.548187 -118.574749) (xy 70.564255 -118.628156) (xy 70.572375 -118.683332)
			(xy 70.572884 -118.711218) (xy 70.572375 -118.739104) (xy 70.564255 -118.79428) (xy 70.548187 -118.847687)
			(xy 70.524515 -118.898184) (xy 70.493742 -118.944697) (xy 70.456525 -118.986234) (xy 70.413657 -119.021909)
			(xy 70.366051 -119.050963) (xy 70.314722 -119.072775) (xy 70.260765 -119.086881) (xy 70.205328 -119.092981)
			(xy 70.149594 -119.090944) (xy 70.094751 -119.080814) (xy 70.041967 -119.062807) (xy 69.992367 -119.037306)
			(xy 69.947009 -119.004855) (xy 69.90686 -118.966146) (xy 69.872774 -118.922003) (xy 69.845478 -118.873368)
			(xy 69.825555 -118.821277) (xy 69.813429 -118.76684) (xy 69.809358 -118.711218) (xy 67.515232 -118.711218)
			(xy 67.515232 -119.567198) (xy 67.514742 -119.597182) (xy 67.506914 -119.656638) (xy 67.491393 -119.714563)
			(xy 67.468444 -119.769967) (xy 67.43846 -119.821901) (xy 67.401954 -119.869477) (xy 67.359549 -119.911882)
			(xy 67.311973 -119.948388) (xy 67.260039 -119.978372) (xy 67.204635 -120.001321) (xy 67.14671 -120.016842)
			(xy 67.087254 -120.02467) (xy 67.027286 -120.02467) (xy 66.96783 -120.016842) (xy 66.909905 -120.001321)
			(xy 66.854501 -119.978372) (xy 66.802567 -119.948388) (xy 66.754991 -119.911882) (xy 66.712586 -119.869477)
			(xy 66.67608 -119.821901) (xy 66.646096 -119.769967) (xy 66.623147 -119.714563) (xy 66.607626 -119.656638)
			(xy 66.599798 -119.597182) (xy 66.599308 -119.567198) (xy 63.255682 -119.567198) (xy 63.220854 -119.601996)
			(xy 63.214017 -119.609398) (xy 63.206297 -119.627996) (xy 63.205868 -119.638064) (xy 63.205868 -121.367296)
			(xy 64.745108 -121.367296) (xy 64.745108 -120.503696) (xy 64.745598 -120.473712) (xy 64.753426 -120.414256)
			(xy 64.768947 -120.356331) (xy 64.791896 -120.300927) (xy 64.82188 -120.248993) (xy 64.858386 -120.201417)
			(xy 64.900791 -120.159012) (xy 64.948367 -120.122506) (xy 65.000301 -120.092522) (xy 65.055705 -120.069573)
			(xy 65.11363 -120.054052) (xy 65.173086 -120.046224) (xy 65.233054 -120.046224) (xy 65.29251 -120.054052)
			(xy 65.350435 -120.069573) (xy 65.405839 -120.092522) (xy 65.457773 -120.122506) (xy 65.505349 -120.159012)
			(xy 65.547754 -120.201417) (xy 65.58426 -120.248993) (xy 65.614244 -120.300927) (xy 65.637193 -120.356331)
			(xy 65.652714 -120.414256) (xy 65.660542 -120.473712) (xy 65.661032 -120.503696) (xy 65.661032 -121.367296)
			(xy 65.660542 -121.39728) (xy 65.652714 -121.456736) (xy 65.637193 -121.514661) (xy 65.614244 -121.570065)
			(xy 65.58426 -121.621999) (xy 65.547754 -121.669575) (xy 65.505349 -121.71198) (xy 65.457773 -121.748486)
			(xy 65.405839 -121.77847) (xy 65.350435 -121.801419) (xy 65.29251 -121.81694) (xy 65.233054 -121.824768)
			(xy 65.173086 -121.824768) (xy 65.11363 -121.81694) (xy 65.055705 -121.801419) (xy 65.000301 -121.77847)
			(xy 64.948367 -121.748486) (xy 64.900791 -121.71198) (xy 64.858386 -121.669575) (xy 64.82188 -121.621999)
			(xy 64.791896 -121.570065) (xy 64.768947 -121.514661) (xy 64.753426 -121.456736) (xy 64.745598 -121.39728)
			(xy 64.745108 -121.367296) (xy 63.205868 -121.367296) (xy 63.205868 -123.16714) (xy 66.599308 -123.16714)
			(xy 66.599308 -122.30354) (xy 66.599798 -122.273556) (xy 66.607626 -122.2141) (xy 66.623147 -122.156175)
			(xy 66.646096 -122.100771) (xy 66.67608 -122.048837) (xy 66.712586 -122.001261) (xy 66.754991 -121.958856)
			(xy 66.802567 -121.92235) (xy 66.854501 -121.892366) (xy 66.909905 -121.869417) (xy 66.96783 -121.853896)
			(xy 67.027286 -121.846068) (xy 67.087254 -121.846068) (xy 67.14671 -121.853896) (xy 67.204635 -121.869417)
			(xy 67.260039 -121.892366) (xy 67.311973 -121.92235) (xy 67.359549 -121.958856) (xy 67.401954 -122.001261)
			(xy 67.43846 -122.048837) (xy 67.468444 -122.100771) (xy 67.491393 -122.156175) (xy 67.506914 -122.2141)
			(xy 67.514742 -122.273556) (xy 67.515232 -122.30354) (xy 67.515232 -123.16714) (xy 67.514742 -123.197124)
			(xy 67.506914 -123.25658) (xy 67.491393 -123.314505) (xy 67.468444 -123.369909) (xy 67.43846 -123.421843)
			(xy 67.401954 -123.469419) (xy 67.359549 -123.511824) (xy 67.311973 -123.54833) (xy 67.260039 -123.578314)
			(xy 67.204635 -123.601263) (xy 67.14671 -123.616784) (xy 67.087254 -123.624612) (xy 67.027286 -123.624612)
			(xy 66.96783 -123.616784) (xy 66.909905 -123.601263) (xy 66.854501 -123.578314) (xy 66.802567 -123.54833)
			(xy 66.754991 -123.511824) (xy 66.712586 -123.469419) (xy 66.67608 -123.421843) (xy 66.646096 -123.369909)
			(xy 66.623147 -123.314505) (xy 66.607626 -123.25658) (xy 66.599798 -123.197124) (xy 66.599308 -123.16714)
			(xy 63.205868 -123.16714) (xy 63.205868 -124.967238) (xy 64.745108 -124.967238) (xy 64.745108 -124.103638)
			(xy 64.745598 -124.073654) (xy 64.753426 -124.014198) (xy 64.768947 -123.956273) (xy 64.791896 -123.900869)
			(xy 64.82188 -123.848935) (xy 64.858386 -123.801359) (xy 64.900791 -123.758954) (xy 64.948367 -123.722448)
			(xy 65.000301 -123.692464) (xy 65.055705 -123.669515) (xy 65.11363 -123.653994) (xy 65.173086 -123.646166)
			(xy 65.233054 -123.646166) (xy 65.29251 -123.653994) (xy 65.350435 -123.669515) (xy 65.405839 -123.692464)
			(xy 65.457773 -123.722448) (xy 65.505349 -123.758954) (xy 65.547754 -123.801359) (xy 65.58426 -123.848935)
			(xy 65.614244 -123.900869) (xy 65.637193 -123.956273) (xy 65.652714 -124.014198) (xy 65.660542 -124.073654)
			(xy 65.661032 -124.103638) (xy 65.661032 -124.967238) (xy 65.660542 -124.997222) (xy 65.652714 -125.056678)
			(xy 65.637193 -125.114603) (xy 65.614244 -125.170007) (xy 65.58426 -125.221941) (xy 65.547754 -125.269517)
			(xy 65.505349 -125.311922) (xy 65.457773 -125.348428) (xy 65.405839 -125.378412) (xy 65.350435 -125.401361)
			(xy 65.29251 -125.416882) (xy 65.233054 -125.42471) (xy 65.173086 -125.42471) (xy 65.11363 -125.416882)
			(xy 65.055705 -125.401361) (xy 65.000301 -125.378412) (xy 64.948367 -125.348428) (xy 64.900791 -125.311922)
			(xy 64.858386 -125.269517) (xy 64.82188 -125.221941) (xy 64.791896 -125.170007) (xy 64.768947 -125.114603)
			(xy 64.753426 -125.056678) (xy 64.745598 -124.997222) (xy 64.745108 -124.967238) (xy 63.205868 -124.967238)
			(xy 63.205868 -130.777234) (xy 66.599308 -130.777234) (xy 66.599308 -129.913634) (xy 66.599798 -129.88365)
			(xy 66.607626 -129.824194) (xy 66.623147 -129.766269) (xy 66.646096 -129.710865) (xy 66.67608 -129.658931)
			(xy 66.712586 -129.611355) (xy 66.754991 -129.56895) (xy 66.802567 -129.532444) (xy 66.854501 -129.50246)
			(xy 66.909905 -129.479511) (xy 66.96783 -129.46399) (xy 67.027286 -129.456162) (xy 67.087254 -129.456162)
			(xy 67.14671 -129.46399) (xy 67.204635 -129.479511) (xy 67.260039 -129.50246) (xy 67.311973 -129.532444)
			(xy 67.359549 -129.56895) (xy 67.401954 -129.611355) (xy 67.43846 -129.658931) (xy 67.468444 -129.710865)
			(xy 67.491393 -129.766269) (xy 67.506914 -129.824194) (xy 67.514742 -129.88365) (xy 67.515232 -129.913634)
			(xy 67.515232 -130.777234) (xy 67.514742 -130.807218) (xy 67.506914 -130.866674) (xy 67.491393 -130.924599)
			(xy 67.468444 -130.980003) (xy 67.43846 -131.031937) (xy 67.401954 -131.079513) (xy 67.359549 -131.121918)
			(xy 67.311973 -131.158424) (xy 67.260039 -131.188408) (xy 67.204635 -131.211357) (xy 67.14671 -131.226878)
			(xy 67.087254 -131.234706) (xy 67.027286 -131.234706) (xy 66.96783 -131.226878) (xy 66.909905 -131.211357)
			(xy 66.854501 -131.188408) (xy 66.802567 -131.158424) (xy 66.754991 -131.121918) (xy 66.712586 -131.079513)
			(xy 66.67608 -131.031937) (xy 66.646096 -130.980003) (xy 66.623147 -130.924599) (xy 66.607626 -130.866674)
			(xy 66.599798 -130.807218) (xy 66.599308 -130.777234) (xy 63.205868 -130.777234) (xy 63.205868 -132.577332)
			(xy 64.745108 -132.577332) (xy 64.745108 -131.713732) (xy 64.745598 -131.683748) (xy 64.753426 -131.624292)
			(xy 64.768947 -131.566367) (xy 64.791896 -131.510963) (xy 64.82188 -131.459029) (xy 64.858386 -131.411453)
			(xy 64.900791 -131.369048) (xy 64.948367 -131.332542) (xy 65.000301 -131.302558) (xy 65.055705 -131.279609)
			(xy 65.11363 -131.264088) (xy 65.173086 -131.25626) (xy 65.233054 -131.25626) (xy 65.29251 -131.264088)
			(xy 65.350435 -131.279609) (xy 65.405839 -131.302558) (xy 65.457773 -131.332542) (xy 65.505349 -131.369048)
			(xy 65.547754 -131.411453) (xy 65.58426 -131.459029) (xy 65.614244 -131.510963) (xy 65.637193 -131.566367)
			(xy 65.652714 -131.624292) (xy 65.660542 -131.683748) (xy 65.661032 -131.713732) (xy 65.661032 -132.577332)
			(xy 65.660542 -132.607316) (xy 65.652714 -132.666772) (xy 65.637193 -132.724697) (xy 65.614244 -132.780101)
			(xy 65.58426 -132.832035) (xy 65.547754 -132.879611) (xy 65.505349 -132.922016) (xy 65.457773 -132.958522)
			(xy 65.405839 -132.988506) (xy 65.350435 -133.011455) (xy 65.29251 -133.026976) (xy 65.233054 -133.034804)
			(xy 65.173086 -133.034804) (xy 65.11363 -133.026976) (xy 65.055705 -133.011455) (xy 65.000301 -132.988506)
			(xy 64.948367 -132.958522) (xy 64.900791 -132.922016) (xy 64.858386 -132.879611) (xy 64.82188 -132.832035)
			(xy 64.791896 -132.780101) (xy 64.768947 -132.724697) (xy 64.753426 -132.666772) (xy 64.745598 -132.607316)
			(xy 64.745108 -132.577332) (xy 63.205868 -132.577332) (xy 63.205868 -134.377176) (xy 66.599308 -134.377176)
			(xy 66.599308 -133.513576) (xy 66.599798 -133.483592) (xy 66.607626 -133.424136) (xy 66.623147 -133.366211)
			(xy 66.646096 -133.310807) (xy 66.67608 -133.258873) (xy 66.712586 -133.211297) (xy 66.754991 -133.168892)
			(xy 66.802567 -133.132386) (xy 66.854501 -133.102402) (xy 66.909905 -133.079453) (xy 66.96783 -133.063932)
			(xy 67.027286 -133.056104) (xy 67.087254 -133.056104) (xy 67.14671 -133.063932) (xy 67.204635 -133.079453)
			(xy 67.260039 -133.102402) (xy 67.311973 -133.132386) (xy 67.359549 -133.168892) (xy 67.401954 -133.211297)
			(xy 67.43846 -133.258873) (xy 67.468444 -133.310807) (xy 67.491393 -133.366211) (xy 67.506914 -133.424136)
			(xy 67.514742 -133.483592) (xy 67.515232 -133.513576) (xy 67.515232 -134.377176) (xy 67.514742 -134.40716)
			(xy 67.506914 -134.466616) (xy 67.491393 -134.524541) (xy 67.468444 -134.579945) (xy 67.43846 -134.631879)
			(xy 67.401954 -134.679455) (xy 67.359549 -134.72186) (xy 67.311973 -134.758366) (xy 67.260039 -134.78835)
			(xy 67.204635 -134.811299) (xy 67.14671 -134.82682) (xy 67.087254 -134.834648) (xy 67.027286 -134.834648)
			(xy 66.96783 -134.82682) (xy 66.909905 -134.811299) (xy 66.854501 -134.78835) (xy 66.802567 -134.758366)
			(xy 66.754991 -134.72186) (xy 66.712586 -134.679455) (xy 66.67608 -134.631879) (xy 66.646096 -134.579945)
			(xy 66.623147 -134.524541) (xy 66.607626 -134.466616) (xy 66.599798 -134.40716) (xy 66.599308 -134.377176)
			(xy 63.205868 -134.377176) (xy 63.205868 -136.177274) (xy 64.745108 -136.177274) (xy 64.745108 -135.313674)
			(xy 64.745598 -135.28369) (xy 64.753426 -135.224234) (xy 64.768947 -135.166309) (xy 64.791896 -135.110905)
			(xy 64.82188 -135.058971) (xy 64.858386 -135.011395) (xy 64.900791 -134.96899) (xy 64.948367 -134.932484)
			(xy 65.000301 -134.9025) (xy 65.055705 -134.879551) (xy 65.11363 -134.86403) (xy 65.173086 -134.856202)
			(xy 65.233054 -134.856202) (xy 65.29251 -134.86403) (xy 65.350435 -134.879551) (xy 65.405839 -134.9025)
			(xy 65.457773 -134.932484) (xy 65.505349 -134.96899) (xy 65.547754 -135.011395) (xy 65.58426 -135.058971)
			(xy 65.614244 -135.110905) (xy 65.637193 -135.166309) (xy 65.652714 -135.224234) (xy 65.660542 -135.28369)
			(xy 65.661032 -135.313674) (xy 65.661032 -136.177274) (xy 65.660542 -136.207258) (xy 65.652714 -136.266714)
			(xy 65.637193 -136.324639) (xy 65.614244 -136.380043) (xy 65.58426 -136.431977) (xy 65.547754 -136.479553)
			(xy 65.505349 -136.521958) (xy 65.457773 -136.558464) (xy 65.405839 -136.588448) (xy 65.350435 -136.611397)
			(xy 65.29251 -136.626918) (xy 65.233054 -136.634746) (xy 65.173086 -136.634746) (xy 65.11363 -136.626918)
			(xy 65.055705 -136.611397) (xy 65.000301 -136.588448) (xy 64.948367 -136.558464) (xy 64.900791 -136.521958)
			(xy 64.858386 -136.479553) (xy 64.82188 -136.431977) (xy 64.791896 -136.380043) (xy 64.768947 -136.324639)
			(xy 64.753426 -136.266714) (xy 64.745598 -136.207258) (xy 64.745108 -136.177274) (xy 63.205868 -136.177274)
			(xy 63.205868 -136.98601) (xy 80.557622 -136.98601) (xy 80.561693 -136.930388) (xy 80.573819 -136.875951)
			(xy 80.593742 -136.82386) (xy 80.621038 -136.775225) (xy 80.655124 -136.731082) (xy 80.695273 -136.692373)
			(xy 80.740631 -136.659922) (xy 80.790231 -136.634421) (xy 80.843015 -136.616414) (xy 80.897858 -136.606284)
			(xy 80.953592 -136.604247) (xy 81.009029 -136.610347) (xy 81.062986 -136.624453) (xy 81.114315 -136.646265)
			(xy 81.161921 -136.675319) (xy 81.204789 -136.710994) (xy 81.242006 -136.752531) (xy 81.272779 -136.799044)
			(xy 81.296451 -136.849541) (xy 81.312519 -136.902948) (xy 81.320639 -136.958124) (xy 81.321148 -136.98601)
			(xy 81.320639 -137.013896) (xy 81.312519 -137.069072) (xy 81.296451 -137.122479) (xy 81.272779 -137.172976)
			(xy 81.242006 -137.219489) (xy 81.204789 -137.261026) (xy 81.161921 -137.296701) (xy 81.114315 -137.325755)
			(xy 81.062986 -137.347567) (xy 81.009029 -137.361673) (xy 80.953592 -137.367773) (xy 80.897858 -137.365736)
			(xy 80.843015 -137.355606) (xy 80.790231 -137.337599) (xy 80.740631 -137.312098) (xy 80.695273 -137.279647)
			(xy 80.655124 -137.240938) (xy 80.621038 -137.196795) (xy 80.593742 -137.14816) (xy 80.573819 -137.096069)
			(xy 80.561693 -137.041632) (xy 80.557622 -136.98601) (xy 63.205868 -136.98601) (xy 63.205868 -138.31316)
			(xy 63.205367 -138.339185) (xy 63.197196 -138.39059) (xy 63.181097 -138.440088) (xy 63.157463 -138.486464)
			(xy 63.126876 -138.528579) (xy 63.10884 -138.547348) (xy 62.69863 -138.957558) (xy 62.694513 -138.96195)
			(xy 62.688228 -138.972215) (xy 62.686184 -138.977878) (xy 62.686184 -138.978386) (xy 62.677712 -139.003921)
			(xy 62.654642 -139.052523) (xy 62.624974 -139.097401) (xy 62.589296 -139.137668) (xy 62.548315 -139.172523)
			(xy 62.502844 -139.201276) (xy 62.453786 -139.223357) (xy 62.402112 -139.238328) (xy 62.348847 -139.245892)
			(xy 62.321948 -139.246356) (xy 62.2947 -139.245777) (xy 62.240758 -139.238029) (xy 62.188468 -139.222682)
			(xy 62.138894 -139.20005) (xy 62.093046 -139.170593) (xy 62.051857 -139.134911) (xy 62.016164 -139.093731)
			(xy 61.986696 -139.04789) (xy 61.964052 -138.998322) (xy 61.948692 -138.946036) (xy 61.94093 -138.892096)
			(xy 61.94044 -138.864848) (xy 57.266071 -138.864848) (xy 57.269297 -138.875838) (xy 57.277048 -138.929795)
			(xy 57.277508 -138.95705) (xy 57.277021 -138.984831) (xy 57.268946 -139.039802) (xy 57.252975 -139.093019)
			(xy 57.229446 -139.143352) (xy 57.198858 -139.189736) (xy 57.180734 -139.210796) (xy 57.18048 -139.21105)
			(xy 57.174172 -139.218927) (xy 57.167759 -139.238046) (xy 57.168034 -139.248134) (xy 57.173368 -139.321286)
			(xy 57.17455 -139.33136) (xy 57.183715 -139.349437) (xy 57.191148 -139.356338) (xy 57.191402 -139.356592)
			(xy 57.212402 -139.374834) (xy 57.249478 -139.416297) (xy 57.280132 -139.46271) (xy 57.303711 -139.513087)
			(xy 57.319715 -139.566358) (xy 57.327802 -139.621389) (xy 57.328308 -139.6492) (xy 57.327822 -139.676451)
			(xy 57.322063 -139.71651) (xy 82.791806 -139.71651) (xy 82.795877 -139.660888) (xy 82.808003 -139.606451)
			(xy 82.827926 -139.55436) (xy 82.855222 -139.505725) (xy 82.889308 -139.461582) (xy 82.929457 -139.422873)
			(xy 82.974815 -139.390422) (xy 83.024415 -139.364921) (xy 83.077199 -139.346914) (xy 83.132042 -139.336784)
			(xy 83.187776 -139.334747) (xy 83.243213 -139.340847) (xy 83.29717 -139.354953) (xy 83.348499 -139.376765)
			(xy 83.396105 -139.405819) (xy 83.438973 -139.441494) (xy 83.47619 -139.483031) (xy 83.506963 -139.529544)
			(xy 83.530635 -139.580041) (xy 83.546703 -139.633448) (xy 83.554823 -139.688624) (xy 83.555332 -139.71651)
			(xy 83.554823 -139.744396) (xy 83.546703 -139.799572) (xy 83.530635 -139.852979) (xy 83.506963 -139.903476)
			(xy 83.47619 -139.949989) (xy 83.438973 -139.991526) (xy 83.396105 -140.027201) (xy 83.348499 -140.056255)
			(xy 83.29717 -140.078067) (xy 83.243213 -140.092173) (xy 83.187776 -140.098273) (xy 83.132042 -140.096236)
			(xy 83.077199 -140.086106) (xy 83.024415 -140.068099) (xy 82.974815 -140.042598) (xy 82.929457 -140.010147)
			(xy 82.889308 -139.971438) (xy 82.855222 -139.927295) (xy 82.827926 -139.87866) (xy 82.808003 -139.826569)
			(xy 82.795877 -139.772132) (xy 82.791806 -139.71651) (xy 57.322063 -139.71651) (xy 57.320066 -139.730399)
			(xy 57.304711 -139.782694) (xy 57.282069 -139.832271) (xy 57.252603 -139.878121) (xy 57.216912 -139.919312)
			(xy 57.175721 -139.955003) (xy 57.129871 -139.984469) (xy 57.080294 -140.007111) (xy 57.027999 -140.022466)
			(xy 56.974051 -140.030222) (xy 56.919549 -140.030222) (xy 56.865601 -140.022466) (xy 56.813306 -140.007111)
			(xy 56.763729 -139.984469) (xy 56.717879 -139.955003) (xy 56.676688 -139.919312) (xy 56.640997 -139.878121)
			(xy 56.611531 -139.832271) (xy 56.588889 -139.782694) (xy 56.573534 -139.730399) (xy 56.565778 -139.676451)
			(xy 56.565292 -139.6492) (xy 56.565809 -139.62142) (xy 56.573876 -139.56645) (xy 56.58984 -139.513234)
			(xy 56.613363 -139.4629) (xy 56.643945 -139.416515) (xy 56.662066 -139.395454) (xy 56.66232 -139.3952)
			(xy 56.668651 -139.387339) (xy 56.675051 -139.368207) (xy 56.674766 -139.358116) (xy 56.669432 -139.284964)
			(xy 56.668275 -139.274885) (xy 56.659093 -139.25681) (xy 56.651652 -139.249912) (xy 56.651398 -139.249658)
			(xy 56.642251 -139.241887) (xy 56.624838 -139.225367) (xy 56.6166 -139.216638) (xy 56.609325 -139.209494)
			(xy 56.590738 -139.20115) (xy 56.57037 -139.200645) (xy 56.56072 -139.203938) (xy 56.472582 -139.238482)
			(xy 56.46327 -139.242609) (xy 56.448685 -139.256801) (xy 56.440773 -139.275551) (xy 56.440324 -139.285726)
			(xy 56.440324 -140.534898) (xy 81.097372 -140.534898) (xy 81.101443 -140.479276) (xy 81.113569 -140.424839)
			(xy 81.133492 -140.372748) (xy 81.160788 -140.324113) (xy 81.194874 -140.27997) (xy 81.235023 -140.241261)
			(xy 81.280381 -140.20881) (xy 81.329981 -140.183309) (xy 81.382765 -140.165302) (xy 81.437608 -140.155172)
			(xy 81.493342 -140.153135) (xy 81.548779 -140.159235) (xy 81.602736 -140.173341) (xy 81.654065 -140.195153)
			(xy 81.701671 -140.224207) (xy 81.744539 -140.259882) (xy 81.781756 -140.301419) (xy 81.812529 -140.347932)
			(xy 81.836201 -140.398429) (xy 81.852269 -140.451836) (xy 81.860389 -140.507012) (xy 81.860898 -140.534898)
			(xy 81.860389 -140.562784) (xy 81.852269 -140.61796) (xy 81.836201 -140.671367) (xy 81.812529 -140.721864)
			(xy 81.781756 -140.768377) (xy 81.744539 -140.809914) (xy 81.701671 -140.845589) (xy 81.654065 -140.874643)
			(xy 81.602736 -140.896455) (xy 81.548779 -140.910561) (xy 81.493342 -140.916661) (xy 81.437608 -140.914624)
			(xy 81.382765 -140.904494) (xy 81.329981 -140.886487) (xy 81.280381 -140.860986) (xy 81.235023 -140.828535)
			(xy 81.194874 -140.789826) (xy 81.160788 -140.745683) (xy 81.133492 -140.697048) (xy 81.113569 -140.644957)
			(xy 81.101443 -140.59052) (xy 81.097372 -140.534898) (xy 56.440324 -140.534898) (xy 56.440324 -141.6177)
			(xy 56.440836 -141.628035) (xy 56.448926 -141.647054) (xy 56.463842 -141.66136) (xy 56.473344 -141.665452)
			(xy 56.577738 -141.704314) (xy 56.607964 -141.696694) (xy 56.618632 -141.684502) (xy 56.636824 -141.664338)
			(xy 56.67795 -141.628871) (xy 56.723692 -141.599598) (xy 56.773125 -141.57711) (xy 56.825248 -141.561864)
			(xy 56.879006 -141.554168) (xy 56.90616 -141.553692) (xy 56.933415 -141.554153) (xy 56.98737 -141.561905)
			(xy 57.039673 -141.577258) (xy 57.089258 -141.599898) (xy 57.135116 -141.629365) (xy 57.176313 -141.665058)
			(xy 57.212011 -141.706252) (xy 57.241483 -141.752107) (xy 57.264128 -141.80169) (xy 57.279487 -141.853991)
			(xy 57.287245 -141.907945) (xy 57.287245 -141.962455) (xy 57.279487 -142.016409) (xy 57.264128 -142.06871)
			(xy 57.241483 -142.118293) (xy 57.212011 -142.164148) (xy 57.176313 -142.205342) (xy 57.135116 -142.241035)
			(xy 57.089258 -142.270502) (xy 57.039673 -142.293142) (xy 56.98737 -142.308495) (xy 56.933415 -142.316247)
			(xy 56.90616 -142.316708) (xy 56.879009 -142.316222) (xy 56.825257 -142.308507) (xy 56.773141 -142.293251)
			(xy 56.723714 -142.270764) (xy 56.677972 -142.241498) (xy 56.636839 -142.206046) (xy 56.618632 -142.185898)
			(xy 56.611523 -142.17849) (xy 56.593036 -142.169591) (xy 56.572544 -142.168583) (xy 56.562752 -142.171674)
			(xy 56.473344 -142.204948) (xy 56.463817 -142.209018) (xy 56.448843 -142.223302) (xy 56.440755 -142.24235)
			(xy 56.440324 -142.2527) (xy 56.440324 -142.653258) (xy 56.440888 -142.663785) (xy 56.449351 -142.683066)
			(xy 56.464832 -142.697337) (xy 56.474614 -142.701264) (xy 56.565292 -142.73276) (xy 56.575421 -142.735785)
			(xy 56.596473 -142.734078) (xy 56.615045 -142.724019) (xy 56.621934 -142.715996) (xy 56.640131 -142.693613)
			(xy 56.682134 -142.654075) (xy 56.729608 -142.621307) (xy 56.781472 -142.596056) (xy 56.836546 -142.578896)
			(xy 56.893574 -142.570219) (xy 56.922416 -142.569692) (xy 56.949667 -142.570179) (xy 57.003613 -142.577937)
			(xy 57.055905 -142.593294) (xy 57.105481 -142.615936) (xy 57.151329 -142.645403) (xy 57.192517 -142.681094)
			(xy 57.228207 -142.722284) (xy 57.257672 -142.768134) (xy 57.280312 -142.81771) (xy 57.295666 -142.870003)
			(xy 57.303422 -142.923949) (xy 57.303422 -142.978451) (xy 57.295666 -143.032397) (xy 57.280312 -143.08469)
			(xy 57.257672 -143.134266) (xy 57.228207 -143.180116) (xy 57.192517 -143.221306) (xy 57.151329 -143.256997)
			(xy 57.105481 -143.286464) (xy 57.055905 -143.309106) (xy 57.003613 -143.324463) (xy 56.949667 -143.332221)
			(xy 56.922416 -143.332708) (xy 56.893574 -143.332207) (xy 56.836547 -143.323517) (xy 56.781476 -143.306349)
			(xy 56.729614 -143.281092) (xy 56.682141 -143.248321) (xy 56.640138 -143.208782) (xy 56.621934 -143.186404)
			(xy 56.615009 -143.178439) (xy 56.596445 -143.168448) (xy 56.575434 -143.16672) (xy 56.565292 -143.16964)
			(xy 56.474614 -143.201136) (xy 56.464819 -143.205051) (xy 56.449307 -143.219311) (xy 56.440844 -143.238607)
			(xy 56.440324 -143.249142) (xy 56.440324 -143.48714) (xy 66.599308 -143.48714) (xy 66.599308 -142.62354)
			(xy 66.599798 -142.593556) (xy 66.607626 -142.5341) (xy 66.623147 -142.476175) (xy 66.646096 -142.420771)
			(xy 66.67608 -142.368837) (xy 66.712586 -142.321261) (xy 66.754991 -142.278856) (xy 66.802567 -142.24235)
			(xy 66.854501 -142.212366) (xy 66.909905 -142.189417) (xy 66.96783 -142.173896) (xy 67.027286 -142.166068)
			(xy 67.087254 -142.166068) (xy 67.14671 -142.173896) (xy 67.204635 -142.189417) (xy 67.260039 -142.212366)
			(xy 67.311973 -142.24235) (xy 67.359549 -142.278856) (xy 67.401954 -142.321261) (xy 67.43846 -142.368837)
			(xy 67.468444 -142.420771) (xy 67.491393 -142.476175) (xy 67.506914 -142.5341) (xy 67.514742 -142.593556)
			(xy 67.515232 -142.62354) (xy 67.515232 -143.48714) (xy 67.514742 -143.517124) (xy 67.506914 -143.57658)
			(xy 67.491393 -143.634505) (xy 67.468444 -143.689909) (xy 67.43846 -143.741843) (xy 67.401954 -143.789419)
			(xy 67.359549 -143.831824) (xy 67.311973 -143.86833) (xy 67.260039 -143.898314) (xy 67.204635 -143.921263)
			(xy 67.14671 -143.936784) (xy 67.087254 -143.944612) (xy 67.027286 -143.944612) (xy 66.96783 -143.936784)
			(xy 66.909905 -143.921263) (xy 66.854501 -143.898314) (xy 66.802567 -143.86833) (xy 66.754991 -143.831824)
			(xy 66.712586 -143.789419) (xy 66.67608 -143.741843) (xy 66.646096 -143.689909) (xy 66.623147 -143.634505)
			(xy 66.607626 -143.57658) (xy 66.599798 -143.517124) (xy 66.599308 -143.48714) (xy 56.440324 -143.48714)
			(xy 56.440324 -143.845534) (xy 56.440743 -143.85425) (xy 56.446643 -143.870658) (xy 56.457686 -143.884153)
			(xy 56.464962 -143.888968) (xy 56.539638 -143.933926) (xy 56.547333 -143.938094) (xy 56.564483 -143.941514)
			(xy 56.581785 -143.938979) (xy 56.589676 -143.935196) (xy 56.617411 -143.921141) (xy 56.676314 -143.901241)
			(xy 56.73766 -143.891128) (xy 56.768746 -143.890492) (xy 56.769 -143.890492) (xy 56.796251 -143.890978)
			(xy 56.850199 -143.898734) (xy 56.902494 -143.914089) (xy 56.952071 -143.936731) (xy 56.997921 -143.966197)
			(xy 57.039112 -144.001888) (xy 57.074803 -144.043079) (xy 57.104269 -144.088929) (xy 57.126911 -144.138506)
			(xy 57.142266 -144.190801) (xy 57.150022 -144.244749) (xy 57.150508 -144.272) (xy 57.149979 -144.300841)
			(xy 57.141267 -144.357863) (xy 57.124074 -144.412924) (xy 57.098789 -144.46477) (xy 57.06599 -144.51222)
			(xy 57.026423 -144.554194) (xy 56.980989 -144.589735) (xy 56.930725 -144.618033) (xy 56.876773 -144.638444)
			(xy 56.820365 -144.650503) (xy 56.791606 -144.652746) (xy 56.78189 -144.653776) (xy 56.764268 -144.662186)
			(xy 56.751035 -144.676543) (xy 56.747156 -144.685512) (xy 56.71439 -144.772126) (xy 56.711331 -144.781376)
			(xy 56.711682 -144.800838) (xy 56.719267 -144.818765) (xy 56.72582 -144.825974) (xy 57.187084 -145.287238)
			(xy 64.745108 -145.287238) (xy 64.745108 -144.423638) (xy 64.745598 -144.393654) (xy 64.753426 -144.334198)
			(xy 64.768947 -144.276273) (xy 64.791896 -144.220869) (xy 64.82188 -144.168935) (xy 64.858386 -144.121359)
			(xy 64.900791 -144.078954) (xy 64.948367 -144.042448) (xy 65.000301 -144.012464) (xy 65.055705 -143.989515)
			(xy 65.11363 -143.973994) (xy 65.173086 -143.966166) (xy 65.233054 -143.966166) (xy 65.29251 -143.973994)
			(xy 65.350435 -143.989515) (xy 65.405839 -144.012464) (xy 65.457773 -144.042448) (xy 65.505349 -144.078954)
			(xy 65.547754 -144.121359) (xy 65.58426 -144.168935) (xy 65.614244 -144.220869) (xy 65.637193 -144.276273)
			(xy 65.652714 -144.334198) (xy 65.660542 -144.393654) (xy 65.661032 -144.423638) (xy 65.661032 -145.287238)
			(xy 65.660542 -145.317222) (xy 65.652714 -145.376678) (xy 65.637193 -145.434603) (xy 65.614244 -145.490007)
			(xy 65.58426 -145.541941) (xy 65.547754 -145.589517) (xy 65.505349 -145.631922) (xy 65.457773 -145.668428)
			(xy 65.405839 -145.698412) (xy 65.350435 -145.721361) (xy 65.29251 -145.736882) (xy 65.233054 -145.74471)
			(xy 65.173086 -145.74471) (xy 65.11363 -145.736882) (xy 65.055705 -145.721361) (xy 65.000301 -145.698412)
			(xy 64.948367 -145.668428) (xy 64.900791 -145.631922) (xy 64.858386 -145.589517) (xy 64.82188 -145.541941)
			(xy 64.791896 -145.490007) (xy 64.768947 -145.434603) (xy 64.753426 -145.376678) (xy 64.745598 -145.317222)
			(xy 64.745108 -145.287238) (xy 57.187084 -145.287238) (xy 57.547256 -145.64741) (xy 57.565271 -145.666196)
			(xy 57.595851 -145.70831) (xy 57.619481 -145.754683) (xy 57.635579 -145.804176) (xy 57.643753 -145.855576)
			(xy 57.644284 -145.881598) (xy 57.644284 -147.087336) (xy 66.599308 -147.087336) (xy 66.599308 -146.223736)
			(xy 66.599798 -146.193752) (xy 66.607626 -146.134296) (xy 66.623147 -146.076371) (xy 66.646096 -146.020967)
			(xy 66.67608 -145.969033) (xy 66.712586 -145.921457) (xy 66.754991 -145.879052) (xy 66.802567 -145.842546)
			(xy 66.854501 -145.812562) (xy 66.909905 -145.789613) (xy 66.96783 -145.774092) (xy 67.027286 -145.766264)
			(xy 67.087254 -145.766264) (xy 67.14671 -145.774092) (xy 67.204635 -145.789613) (xy 67.260039 -145.812562)
			(xy 67.311973 -145.842546) (xy 67.359549 -145.879052) (xy 67.401954 -145.921457) (xy 67.43846 -145.969033)
			(xy 67.468444 -146.020967) (xy 67.491393 -146.076371) (xy 67.506914 -146.134296) (xy 67.514742 -146.193752)
			(xy 67.515232 -146.223736) (xy 67.515232 -147.087336) (xy 67.514742 -147.11732) (xy 67.506914 -147.176776)
			(xy 67.491393 -147.234701) (xy 67.468444 -147.290105) (xy 67.43846 -147.342039) (xy 67.401954 -147.389615)
			(xy 67.359549 -147.43202) (xy 67.311973 -147.468526) (xy 67.260039 -147.49851) (xy 67.204635 -147.521459)
			(xy 67.14671 -147.53698) (xy 67.087254 -147.544808) (xy 67.027286 -147.544808) (xy 66.96783 -147.53698)
			(xy 66.909905 -147.521459) (xy 66.854501 -147.49851) (xy 66.802567 -147.468526) (xy 66.754991 -147.43202)
			(xy 66.712586 -147.389615) (xy 66.67608 -147.342039) (xy 66.646096 -147.290105) (xy 66.623147 -147.234701)
			(xy 66.607626 -147.176776) (xy 66.599798 -147.11732) (xy 66.599308 -147.087336) (xy 57.644284 -147.087336)
			(xy 57.644284 -148.887434) (xy 64.745108 -148.887434) (xy 64.745108 -148.023834) (xy 64.745598 -147.99385)
			(xy 64.753426 -147.934394) (xy 64.768947 -147.876469) (xy 64.791896 -147.821065) (xy 64.82188 -147.769131)
			(xy 64.858386 -147.721555) (xy 64.900791 -147.67915) (xy 64.948367 -147.642644) (xy 65.000301 -147.61266)
			(xy 65.055705 -147.589711) (xy 65.11363 -147.57419) (xy 65.173086 -147.566362) (xy 65.233054 -147.566362)
			(xy 65.29251 -147.57419) (xy 65.350435 -147.589711) (xy 65.405839 -147.61266) (xy 65.457773 -147.642644)
			(xy 65.505349 -147.67915) (xy 65.547754 -147.721555) (xy 65.58426 -147.769131) (xy 65.614244 -147.821065)
			(xy 65.637193 -147.876469) (xy 65.652714 -147.934394) (xy 65.660542 -147.99385) (xy 65.661032 -148.023834)
			(xy 65.661032 -148.887434) (xy 65.660542 -148.917418) (xy 65.652714 -148.976874) (xy 65.637193 -149.034799)
			(xy 65.614244 -149.090203) (xy 65.58426 -149.142137) (xy 65.547754 -149.189713) (xy 65.505349 -149.232118)
			(xy 65.457773 -149.268624) (xy 65.405839 -149.298608) (xy 65.350435 -149.321557) (xy 65.29251 -149.337078)
			(xy 65.233054 -149.344906) (xy 65.173086 -149.344906) (xy 65.11363 -149.337078) (xy 65.055705 -149.321557)
			(xy 65.000301 -149.298608) (xy 64.948367 -149.268624) (xy 64.900791 -149.232118) (xy 64.858386 -149.189713)
			(xy 64.82188 -149.142137) (xy 64.791896 -149.090203) (xy 64.768947 -149.034799) (xy 64.753426 -148.976874)
			(xy 64.745598 -148.917418) (xy 64.745108 -148.887434) (xy 57.644284 -148.887434) (xy 57.644284 -150.687278)
			(xy 66.599308 -150.687278) (xy 66.599308 -149.823678) (xy 66.599798 -149.793694) (xy 66.607626 -149.734238)
			(xy 66.623147 -149.676313) (xy 66.646096 -149.620909) (xy 66.67608 -149.568975) (xy 66.712586 -149.521399)
			(xy 66.754991 -149.478994) (xy 66.802567 -149.442488) (xy 66.854501 -149.412504) (xy 66.909905 -149.389555)
			(xy 66.96783 -149.374034) (xy 67.027286 -149.366206) (xy 67.087254 -149.366206) (xy 67.14671 -149.374034)
			(xy 67.204635 -149.389555) (xy 67.260039 -149.412504) (xy 67.311973 -149.442488) (xy 67.359549 -149.478994)
			(xy 67.401954 -149.521399) (xy 67.43846 -149.568975) (xy 67.468444 -149.620909) (xy 67.491393 -149.676313)
			(xy 67.506914 -149.734238) (xy 67.514742 -149.793694) (xy 67.515232 -149.823678) (xy 67.515232 -150.687278)
			(xy 67.514742 -150.717262) (xy 67.506914 -150.776718) (xy 67.491393 -150.834643) (xy 67.468444 -150.890047)
			(xy 67.43846 -150.941981) (xy 67.401954 -150.989557) (xy 67.359549 -151.031962) (xy 67.311973 -151.068468)
			(xy 67.260039 -151.098452) (xy 67.204635 -151.121401) (xy 67.14671 -151.136922) (xy 67.087254 -151.14475)
			(xy 67.027286 -151.14475) (xy 66.96783 -151.136922) (xy 66.909905 -151.121401) (xy 66.854501 -151.098452)
			(xy 66.802567 -151.068468) (xy 66.754991 -151.031962) (xy 66.712586 -150.989557) (xy 66.67608 -150.941981)
			(xy 66.646096 -150.890047) (xy 66.623147 -150.834643) (xy 66.607626 -150.776718) (xy 66.599798 -150.717262)
			(xy 66.599308 -150.687278) (xy 57.644284 -150.687278) (xy 57.644284 -152.487376) (xy 64.745108 -152.487376)
			(xy 64.745108 -151.623776) (xy 64.745598 -151.593792) (xy 64.753426 -151.534336) (xy 64.768947 -151.476411)
			(xy 64.791896 -151.421007) (xy 64.82188 -151.369073) (xy 64.858386 -151.321497) (xy 64.900791 -151.279092)
			(xy 64.948367 -151.242586) (xy 65.000301 -151.212602) (xy 65.055705 -151.189653) (xy 65.11363 -151.174132)
			(xy 65.173086 -151.166304) (xy 65.233054 -151.166304) (xy 65.29251 -151.174132) (xy 65.350435 -151.189653)
			(xy 65.405839 -151.212602) (xy 65.457773 -151.242586) (xy 65.505349 -151.279092) (xy 65.547754 -151.321497)
			(xy 65.58426 -151.369073) (xy 65.614244 -151.421007) (xy 65.637193 -151.476411) (xy 65.652714 -151.534336)
			(xy 65.660542 -151.593792) (xy 65.661032 -151.623776) (xy 65.661032 -152.487376) (xy 65.660542 -152.51736)
			(xy 65.652714 -152.576816) (xy 65.637193 -152.634741) (xy 65.614244 -152.690145) (xy 65.58426 -152.742079)
			(xy 65.547754 -152.789655) (xy 65.505349 -152.83206) (xy 65.457773 -152.868566) (xy 65.405839 -152.89855)
			(xy 65.350435 -152.921499) (xy 65.29251 -152.93702) (xy 65.233054 -152.944848) (xy 65.173086 -152.944848)
			(xy 65.11363 -152.93702) (xy 65.055705 -152.921499) (xy 65.000301 -152.89855) (xy 64.948367 -152.868566)
			(xy 64.900791 -152.83206) (xy 64.858386 -152.789655) (xy 64.82188 -152.742079) (xy 64.791896 -152.690145)
			(xy 64.768947 -152.634741) (xy 64.753426 -152.576816) (xy 64.745598 -152.51736) (xy 64.745108 -152.487376)
			(xy 57.644284 -152.487376) (xy 57.644284 -153.083006) (xy 62.492126 -153.083006) (xy 62.496197 -153.027384)
			(xy 62.508323 -152.972947) (xy 62.528246 -152.920856) (xy 62.555542 -152.872221) (xy 62.589628 -152.828078)
			(xy 62.629777 -152.789369) (xy 62.675135 -152.756918) (xy 62.724735 -152.731417) (xy 62.777519 -152.71341)
			(xy 62.832362 -152.70328) (xy 62.888096 -152.701243) (xy 62.943533 -152.707343) (xy 62.99749 -152.721449)
			(xy 63.048819 -152.743261) (xy 63.096425 -152.772315) (xy 63.139293 -152.80799) (xy 63.17651 -152.849527)
			(xy 63.207283 -152.89604) (xy 63.230955 -152.946537) (xy 63.247023 -152.999944) (xy 63.255143 -153.05512)
			(xy 63.255652 -153.083006) (xy 63.255143 -153.110892) (xy 63.247023 -153.166068) (xy 63.230955 -153.219475)
			(xy 63.207283 -153.269972) (xy 63.17651 -153.316485) (xy 63.139293 -153.358022) (xy 63.096425 -153.393697)
			(xy 63.048819 -153.422751) (xy 62.99749 -153.444563) (xy 62.943533 -153.458669) (xy 62.888096 -153.464769)
			(xy 62.832362 -153.462732) (xy 62.777519 -153.452602) (xy 62.724735 -153.434595) (xy 62.675135 -153.409094)
			(xy 62.629777 -153.376643) (xy 62.589628 -153.337934) (xy 62.555542 -153.293791) (xy 62.528246 -153.245156)
			(xy 62.508323 -153.193065) (xy 62.496197 -153.138628) (xy 62.492126 -153.083006) (xy 57.644284 -153.083006)
			(xy 57.644284 -154.28722) (xy 66.599308 -154.28722) (xy 66.599308 -153.42362) (xy 66.599798 -153.393636)
			(xy 66.607626 -153.33418) (xy 66.623147 -153.276255) (xy 66.646096 -153.220851) (xy 66.67608 -153.168917)
			(xy 66.712586 -153.121341) (xy 66.754991 -153.078936) (xy 66.802567 -153.04243) (xy 66.854501 -153.012446)
			(xy 66.909905 -152.989497) (xy 66.96783 -152.973976) (xy 67.027286 -152.966148) (xy 67.087254 -152.966148)
			(xy 67.14671 -152.973976) (xy 67.204635 -152.989497) (xy 67.260039 -153.012446) (xy 67.311973 -153.04243)
			(xy 67.359549 -153.078936) (xy 67.401954 -153.121341) (xy 67.43846 -153.168917) (xy 67.468444 -153.220851)
			(xy 67.491393 -153.276255) (xy 67.506914 -153.33418) (xy 67.514742 -153.393636) (xy 67.515232 -153.42362)
			(xy 67.515232 -154.28722) (xy 67.514742 -154.317204) (xy 67.506914 -154.37666) (xy 67.491393 -154.434585)
			(xy 67.468444 -154.489989) (xy 67.43846 -154.541923) (xy 67.401954 -154.589499) (xy 67.359549 -154.631904)
			(xy 67.311973 -154.66841) (xy 67.260039 -154.698394) (xy 67.204635 -154.721343) (xy 67.14671 -154.736864)
			(xy 67.087254 -154.744692) (xy 67.027286 -154.744692) (xy 66.96783 -154.736864) (xy 66.909905 -154.721343)
			(xy 66.854501 -154.698394) (xy 66.802567 -154.66841) (xy 66.754991 -154.631904) (xy 66.712586 -154.589499)
			(xy 66.67608 -154.541923) (xy 66.646096 -154.489989) (xy 66.623147 -154.434585) (xy 66.607626 -154.37666)
			(xy 66.599798 -154.317204) (xy 66.599308 -154.28722) (xy 57.644284 -154.28722) (xy 57.644284 -156.087318)
			(xy 64.745108 -156.087318) (xy 64.745108 -155.223718) (xy 64.745598 -155.193734) (xy 64.753426 -155.134278)
			(xy 64.768947 -155.076353) (xy 64.791896 -155.020949) (xy 64.82188 -154.969015) (xy 64.858386 -154.921439)
			(xy 64.900791 -154.879034) (xy 64.948367 -154.842528) (xy 65.000301 -154.812544) (xy 65.055705 -154.789595)
			(xy 65.11363 -154.774074) (xy 65.173086 -154.766246) (xy 65.233054 -154.766246) (xy 65.29251 -154.774074)
			(xy 65.350435 -154.789595) (xy 65.405839 -154.812544) (xy 65.457773 -154.842528) (xy 65.505349 -154.879034)
			(xy 65.547754 -154.921439) (xy 65.58426 -154.969015) (xy 65.614244 -155.020949) (xy 65.637193 -155.076353)
			(xy 65.652714 -155.134278) (xy 65.660542 -155.193734) (xy 65.661032 -155.223718) (xy 65.661032 -156.087318)
			(xy 65.660542 -156.117302) (xy 65.652714 -156.176758) (xy 65.637193 -156.234683) (xy 65.614244 -156.290087)
			(xy 65.58426 -156.342021) (xy 65.547754 -156.389597) (xy 65.505349 -156.432002) (xy 65.457773 -156.468508)
			(xy 65.405839 -156.498492) (xy 65.350435 -156.521441) (xy 65.29251 -156.536962) (xy 65.233054 -156.54479)
			(xy 65.173086 -156.54479) (xy 65.11363 -156.536962) (xy 65.055705 -156.521441) (xy 65.000301 -156.498492)
			(xy 64.948367 -156.468508) (xy 64.900791 -156.432002) (xy 64.858386 -156.389597) (xy 64.82188 -156.342021)
			(xy 64.791896 -156.290087) (xy 64.768947 -156.234683) (xy 64.753426 -156.176758) (xy 64.745598 -156.117302)
			(xy 64.745108 -156.087318) (xy 57.644284 -156.087318) (xy 57.644284 -157.045152) (xy 61.411104 -157.045152)
			(xy 61.41159 -157.017901) (xy 61.419346 -156.963953) (xy 61.434701 -156.911658) (xy 61.457343 -156.862081)
			(xy 61.486809 -156.816231) (xy 61.5225 -156.77504) (xy 61.563691 -156.739349) (xy 61.609541 -156.709883)
			(xy 61.659118 -156.687241) (xy 61.711413 -156.671886) (xy 61.765361 -156.66413) (xy 61.819863 -156.66413)
			(xy 61.873811 -156.671886) (xy 61.926106 -156.687241) (xy 61.975683 -156.709883) (xy 62.021533 -156.739349)
			(xy 62.062724 -156.77504) (xy 62.098415 -156.816231) (xy 62.127881 -156.862081) (xy 62.150523 -156.911658)
			(xy 62.165878 -156.963953) (xy 62.173634 -157.017901) (xy 62.17412 -157.045152) (xy 62.426594 -157.045152)
			(xy 62.430665 -156.98953) (xy 62.442791 -156.935093) (xy 62.462714 -156.883002) (xy 62.49001 -156.834367)
			(xy 62.524096 -156.790224) (xy 62.564245 -156.751515) (xy 62.609603 -156.719064) (xy 62.659203 -156.693563)
			(xy 62.711987 -156.675556) (xy 62.76683 -156.665426) (xy 62.822564 -156.663389) (xy 62.878001 -156.669489)
			(xy 62.931958 -156.683595) (xy 62.983287 -156.705407) (xy 63.030893 -156.734461) (xy 63.073761 -156.770136)
			(xy 63.110978 -156.811673) (xy 63.141751 -156.858186) (xy 63.165423 -156.908683) (xy 63.181491 -156.96209)
			(xy 63.189611 -157.017266) (xy 63.19012 -157.045152) (xy 63.189611 -157.073038) (xy 63.181491 -157.128214)
			(xy 63.165423 -157.181621) (xy 63.141751 -157.232118) (xy 63.110978 -157.278631) (xy 63.073761 -157.320168)
			(xy 63.030893 -157.355843) (xy 62.983287 -157.384897) (xy 62.931958 -157.406709) (xy 62.878001 -157.420815)
			(xy 62.822564 -157.426915) (xy 62.76683 -157.424878) (xy 62.711987 -157.414748) (xy 62.659203 -157.396741)
			(xy 62.609603 -157.37124) (xy 62.564245 -157.338789) (xy 62.524096 -157.30008) (xy 62.49001 -157.255937)
			(xy 62.462714 -157.207302) (xy 62.442791 -157.155211) (xy 62.430665 -157.100774) (xy 62.426594 -157.045152)
			(xy 62.17412 -157.045152) (xy 62.173522 -157.075955) (xy 62.163592 -157.136757) (xy 62.144013 -157.19517)
			(xy 62.130178 -157.222698) (xy 62.127463 -157.228222) (xy 62.124507 -157.240167) (xy 62.124336 -157.24632)
			(xy 62.124336 -158.219648) (xy 81.182208 -158.219648) (xy 81.186279 -158.164026) (xy 81.198405 -158.109589)
			(xy 81.218328 -158.057498) (xy 81.245624 -158.008863) (xy 81.27971 -157.96472) (xy 81.319859 -157.926011)
			(xy 81.365217 -157.89356) (xy 81.414817 -157.868059) (xy 81.467601 -157.850052) (xy 81.522444 -157.839922)
			(xy 81.578178 -157.837885) (xy 81.633615 -157.843985) (xy 81.687572 -157.858091) (xy 81.738901 -157.879903)
			(xy 81.786507 -157.908957) (xy 81.829375 -157.944632) (xy 81.866592 -157.986169) (xy 81.897365 -158.032682)
			(xy 81.921037 -158.083179) (xy 81.937105 -158.136586) (xy 81.945225 -158.191762) (xy 81.945734 -158.219648)
			(xy 81.945225 -158.247534) (xy 81.937105 -158.30271) (xy 81.921037 -158.356117) (xy 81.897365 -158.406614)
			(xy 81.866592 -158.453127) (xy 81.829375 -158.494664) (xy 81.786507 -158.530339) (xy 81.738901 -158.559393)
			(xy 81.687572 -158.581205) (xy 81.633615 -158.595311) (xy 81.578178 -158.601411) (xy 81.522444 -158.599374)
			(xy 81.467601 -158.589244) (xy 81.414817 -158.571237) (xy 81.365217 -158.545736) (xy 81.319859 -158.513285)
			(xy 81.27971 -158.474576) (xy 81.245624 -158.430433) (xy 81.218328 -158.381798) (xy 81.198405 -158.329707)
			(xy 81.186279 -158.27527) (xy 81.182208 -158.219648) (xy 62.124336 -158.219648) (xy 62.124336 -160.1851)
			(xy 69.888621 -160.1851) (xy 69.892578 -160.093219) (xy 69.904418 -160.002019) (xy 69.924055 -159.912174)
			(xy 69.951342 -159.824349) (xy 69.986078 -159.739196) (xy 70.028006 -159.657343) (xy 70.076815 -159.579398)
			(xy 70.132144 -159.505938) (xy 70.193584 -159.437506) (xy 70.260678 -159.374608) (xy 70.332931 -159.317712)
			(xy 70.409808 -159.267237) (xy 70.490739 -159.223557) (xy 70.575125 -159.186997) (xy 70.662342 -159.157826)
			(xy 70.751744 -159.136261) (xy 70.842669 -159.122461) (xy 70.934443 -159.116528) (xy 71.026388 -159.118507)
			(xy 71.117822 -159.128383) (xy 71.208069 -159.146082) (xy 71.29646 -159.171473) (xy 71.382341 -159.204369)
			(xy 71.465077 -159.244526) (xy 71.544054 -159.291647) (xy 71.618688 -159.345383) (xy 71.688426 -159.405335)
			(xy 71.752752 -159.471061) (xy 71.811191 -159.542073) (xy 71.863308 -159.617846) (xy 71.908718 -159.697818)
			(xy 71.947086 -159.781399) (xy 71.978127 -159.867968) (xy 72.00161 -159.956885) (xy 72.017364 -160.047492)
			(xy 72.025269 -160.139117) (xy 72.025764 -160.1851) (xy 72.025269 -160.231083) (xy 72.017364 -160.322708)
			(xy 72.00161 -160.413315) (xy 71.978127 -160.502232) (xy 71.947086 -160.588801) (xy 71.908718 -160.672382)
			(xy 71.863308 -160.752354) (xy 71.811191 -160.828127) (xy 71.752752 -160.899139) (xy 71.688426 -160.964865)
			(xy 71.618688 -161.024817) (xy 71.544054 -161.078553) (xy 71.465077 -161.125674) (xy 71.382341 -161.165831)
			(xy 71.29646 -161.198727) (xy 71.208069 -161.224118) (xy 71.117822 -161.241817) (xy 71.026388 -161.251693)
			(xy 70.934443 -161.253672) (xy 70.842669 -161.247739) (xy 70.751744 -161.233939) (xy 70.662342 -161.212374)
			(xy 70.575125 -161.183203) (xy 70.490739 -161.146643) (xy 70.409808 -161.102963) (xy 70.332931 -161.052488)
			(xy 70.260678 -160.995592) (xy 70.193584 -160.932694) (xy 70.132144 -160.864262) (xy 70.076815 -160.790802)
			(xy 70.028006 -160.712857) (xy 69.986078 -160.631004) (xy 69.951342 -160.545851) (xy 69.924055 -160.458026)
			(xy 69.904418 -160.368181) (xy 69.892578 -160.276981) (xy 69.888621 -160.1851) (xy 62.124336 -160.1851)
			(xy 62.124336 -160.33877) (xy 62.124768 -160.348839) (xy 62.132483 -160.367437) (xy 62.139322 -160.374838)
			(xy 62.500764 -160.736026) (xy 62.518788 -160.754804) (xy 62.549367 -160.79692) (xy 62.572994 -160.843295)
			(xy 62.589091 -160.89279) (xy 62.597262 -160.944191) (xy 62.597792 -160.970214) (xy 62.597792 -161.636456)
			(xy 63.800734 -161.636456) (xy 63.804805 -161.580834) (xy 63.816931 -161.526397) (xy 63.836854 -161.474306)
			(xy 63.86415 -161.425671) (xy 63.898236 -161.381528) (xy 63.938385 -161.342819) (xy 63.983743 -161.310368)
			(xy 64.033343 -161.284867) (xy 64.086127 -161.26686) (xy 64.14097 -161.25673) (xy 64.196704 -161.254693)
			(xy 64.252141 -161.260793) (xy 64.306098 -161.274899) (xy 64.357427 -161.296711) (xy 64.405033 -161.325765)
			(xy 64.447901 -161.36144) (xy 64.485118 -161.402977) (xy 64.515891 -161.44949) (xy 64.539563 -161.499987)
			(xy 64.555631 -161.553394) (xy 64.563751 -161.60857) (xy 64.56426 -161.636456) (xy 64.563751 -161.664342)
			(xy 64.555631 -161.719518) (xy 64.539563 -161.772925) (xy 64.515891 -161.823422) (xy 64.485118 -161.869935)
			(xy 64.447901 -161.911472) (xy 64.405033 -161.947147) (xy 64.357427 -161.976201) (xy 64.306098 -161.998013)
			(xy 64.252141 -162.012119) (xy 64.196704 -162.018219) (xy 64.14097 -162.016182) (xy 64.086127 -162.006052)
			(xy 64.033343 -161.988045) (xy 63.983743 -161.962544) (xy 63.938385 -161.930093) (xy 63.898236 -161.891384)
			(xy 63.86415 -161.847241) (xy 63.836854 -161.798606) (xy 63.816931 -161.746515) (xy 63.804805 -161.692078)
			(xy 63.800734 -161.636456) (xy 62.597792 -161.636456) (xy 62.597792 -163.111688) (xy 62.598199 -163.12176)
			(xy 62.60593 -163.140359) (xy 62.612778 -163.147756) (xy 63.760604 -164.295328) (xy 63.778619 -164.314115)
			(xy 63.809201 -164.356228) (xy 63.832831 -164.4026) (xy 63.84893 -164.452093) (xy 63.857102 -164.503494)
			(xy 63.857632 -164.529516) (xy 63.857632 -166.504366) (xy 63.857837 -166.510515) (xy 63.860783 -166.522456)
			(xy 63.863474 -166.527988) (xy 63.877308 -166.555516) (xy 63.896873 -166.613932) (xy 63.906807 -166.674732)
			(xy 63.907416 -166.705534) (xy 63.90693 -166.732785) (xy 63.899174 -166.786733) (xy 63.883819 -166.839028)
			(xy 63.861177 -166.888605) (xy 63.831711 -166.934455) (xy 63.79602 -166.975646) (xy 63.754829 -167.011337)
			(xy 63.708979 -167.040803) (xy 63.659402 -167.063445) (xy 63.607107 -167.0788) (xy 63.553159 -167.086556)
			(xy 63.498657 -167.086556) (xy 63.444709 -167.0788) (xy 63.392414 -167.063445) (xy 63.342837 -167.040803)
			(xy 63.296987 -167.011337) (xy 63.255796 -166.975646) (xy 63.220105 -166.934455) (xy 63.190639 -166.888605)
			(xy 63.167997 -166.839028) (xy 63.152642 -166.786733) (xy 63.144886 -166.732785) (xy 63.1444 -166.705534)
			(xy 63.14499 -166.67473) (xy 63.154923 -166.613929) (xy 63.174505 -166.555516) (xy 63.188342 -166.527988)
			(xy 63.191063 -166.522466) (xy 63.194015 -166.510519) (xy 63.194184 -166.504366) (xy 63.194184 -164.68852)
			(xy 63.193752 -164.678451) (xy 63.186037 -164.659853) (xy 63.179198 -164.652452) (xy 62.031372 -163.50488)
			(xy 62.013357 -163.486094) (xy 61.982776 -163.44398) (xy 61.959146 -163.397608) (xy 61.943047 -163.348115)
			(xy 61.934875 -163.296714) (xy 61.934344 -163.270692) (xy 61.934344 -161.129218) (xy 61.933924 -161.119148)
			(xy 61.926201 -161.100549) (xy 61.919358 -161.09315) (xy 61.557916 -160.731962) (xy 61.539883 -160.713193)
			(xy 61.509306 -160.671073) (xy 61.485681 -160.624697) (xy 61.469586 -160.5752) (xy 61.461417 -160.523797)
			(xy 61.460888 -160.497774) (xy 61.460888 -157.24632) (xy 61.460686 -157.240171) (xy 61.457738 -157.22823)
			(xy 61.455046 -157.222698) (xy 61.441209 -157.195172) (xy 61.421644 -157.136755) (xy 61.411713 -157.075955)
			(xy 61.411104 -157.045152) (xy 57.644284 -157.045152) (xy 57.644284 -161.34969) (xy 57.644692 -161.359762)
			(xy 57.652423 -161.378361) (xy 57.65927 -161.385758) (xy 59.624315 -163.350702) (xy 60.627258 -163.350702)
			(xy 60.631329 -163.29508) (xy 60.643455 -163.240643) (xy 60.663378 -163.188552) (xy 60.690674 -163.139917)
			(xy 60.72476 -163.095774) (xy 60.764909 -163.057065) (xy 60.810267 -163.024614) (xy 60.859867 -162.999113)
			(xy 60.912651 -162.981106) (xy 60.967494 -162.970976) (xy 61.023228 -162.968939) (xy 61.078665 -162.975039)
			(xy 61.132622 -162.989145) (xy 61.183951 -163.010957) (xy 61.231557 -163.040011) (xy 61.274425 -163.075686)
			(xy 61.311642 -163.117223) (xy 61.342415 -163.163736) (xy 61.366087 -163.214233) (xy 61.382155 -163.26764)
			(xy 61.390275 -163.322816) (xy 61.390784 -163.350702) (xy 61.390275 -163.378588) (xy 61.382155 -163.433764)
			(xy 61.366087 -163.487171) (xy 61.342415 -163.537668) (xy 61.311642 -163.584181) (xy 61.274425 -163.625718)
			(xy 61.231557 -163.661393) (xy 61.183951 -163.690447) (xy 61.132622 -163.712259) (xy 61.078665 -163.726365)
			(xy 61.023228 -163.732465) (xy 60.967494 -163.730428) (xy 60.912651 -163.720298) (xy 60.859867 -163.702291)
			(xy 60.810267 -163.67679) (xy 60.764909 -163.644339) (xy 60.72476 -163.60563) (xy 60.690674 -163.561487)
			(xy 60.663378 -163.512852) (xy 60.643455 -163.460761) (xy 60.631329 -163.406324) (xy 60.627258 -163.350702)
			(xy 59.624315 -163.350702) (xy 62.602618 -166.328852) (xy 62.60702 -166.332958) (xy 62.617278 -166.33925)
			(xy 62.622938 -166.341298) (xy 62.623446 -166.341298) (xy 62.648999 -166.349722) (xy 62.697605 -166.372794)
			(xy 62.742487 -166.402466) (xy 62.782756 -166.438149) (xy 62.817611 -166.479136) (xy 62.846362 -166.524614)
			(xy 62.868439 -166.57368) (xy 62.883403 -166.625361) (xy 62.890957 -166.678632) (xy 62.891416 -166.705534)
			(xy 62.890954 -166.732786) (xy 62.883193 -166.786734) (xy 62.867834 -166.839029) (xy 62.845189 -166.888605)
			(xy 62.81572 -166.934455) (xy 62.780026 -166.975645) (xy 62.738834 -167.011336) (xy 62.692983 -167.040802)
			(xy 62.643404 -167.063443) (xy 62.591108 -167.078798) (xy 62.53716 -167.086556) (xy 62.509908 -167.087042)
			(xy 62.483 -167.086506) (xy 62.42972 -167.078932) (xy 62.378033 -167.063946) (xy 62.328964 -167.041847)
			(xy 62.283487 -167.013073) (xy 62.242504 -166.978194) (xy 62.206828 -166.937903) (xy 62.177167 -166.892999)
			(xy 62.15411 -166.844373) (xy 62.145672 -166.818818) (xy 62.145672 -166.818564) (xy 62.143687 -166.812873)
			(xy 62.137394 -166.802597) (xy 62.133226 -166.798244) (xy 62.043056 -166.708074) (xy 62.036133 -166.70174)
			(xy 62.019007 -166.694111) (xy 62.000285 -166.693129) (xy 61.99124 -166.695628) (xy 61.891672 -166.72814)
			(xy 61.87313 -166.749984) (xy 61.870844 -166.764208) (xy 61.866196 -166.790838) (xy 61.850433 -166.842545)
			(xy 61.827528 -166.891508) (xy 61.79794 -166.936748) (xy 61.762261 -166.977357) (xy 61.721207 -167.012522)
			(xy 61.675599 -167.041539) (xy 61.626351 -167.063827) (xy 61.574451 -167.078938) (xy 61.520936 -167.086571)
			(xy 61.493908 -167.087042) (xy 61.466658 -167.086515) (xy 61.412714 -167.07876) (xy 61.360422 -167.063408)
			(xy 61.310847 -167.04077) (xy 61.264998 -167.011308) (xy 61.223809 -166.975621) (xy 61.188117 -166.934435)
			(xy 61.15865 -166.88859) (xy 61.136007 -166.839017) (xy 61.120649 -166.786727) (xy 61.112888 -166.732783)
			(xy 61.1124 -166.705534) (xy 61.112835 -166.678504) (xy 61.120475 -166.624988) (xy 61.135593 -166.573085)
			(xy 61.157885 -166.523836) (xy 61.186905 -166.478227) (xy 61.222073 -166.43717) (xy 61.262684 -166.401489)
			(xy 61.307925 -166.371897) (xy 61.35689 -166.348987) (xy 61.408598 -166.333218) (xy 61.435234 -166.328598)
			(xy 61.449458 -166.326312) (xy 61.471302 -166.30777) (xy 61.503814 -166.208202) (xy 61.506378 -166.19916)
			(xy 61.505436 -166.180405) (xy 61.497775 -166.16326) (xy 61.491368 -166.156386) (xy 57.077864 -161.742882)
			(xy 57.059848 -161.724096) (xy 57.029268 -161.681982) (xy 57.005638 -161.63561) (xy 56.989539 -161.586117)
			(xy 56.981367 -161.534716) (xy 56.980836 -161.508694) (xy 56.980836 -146.040602) (xy 56.980426 -146.030531)
			(xy 56.972696 -146.011932) (xy 56.96585 -146.004534) (xy 55.873904 -144.912842) (xy 55.855876 -144.894067)
			(xy 55.825295 -144.851951) (xy 55.801667 -144.805576) (xy 55.785572 -144.75608) (xy 55.777404 -144.704677)
			(xy 55.776876 -144.678654) (xy 55.776876 -133.451092) (xy 55.777426 -133.425069) (xy 55.785587 -133.373667)
			(xy 55.801676 -133.32417) (xy 55.825298 -133.277794) (xy 55.855874 -133.235676) (xy 55.873904 -133.216904)
			(xy 56.95569 -132.135372) (xy 56.962533 -132.127975) (xy 56.970252 -132.109373) (xy 56.970676 -132.099304)
			(xy 56.970676 -117.549168) (xy 56.970273 -117.539096) (xy 56.962537 -117.520498) (xy 56.95569 -117.5131)
			(xy 53.8353 -114.39271) (xy 53.827893 -114.385879) (xy 53.809299 -114.378154) (xy 53.799232 -114.377724)
			(xy 51.637946 -114.377724) (xy 51.611922 -114.377203) (xy 51.560519 -114.369035) (xy 51.511021 -114.352939)
			(xy 51.464645 -114.32931) (xy 51.422529 -114.298729) (xy 51.403758 -114.280696) (xy 50.867564 -113.744502)
			(xy 50.84951 -113.725751) (xy 50.818934 -113.683628) (xy 50.795312 -113.637247) (xy 50.779222 -113.587745)
			(xy 50.771061 -113.536339) (xy 50.770536 -113.510314) (xy 38.261798 -113.510314) (xy 37.551106 -114.221006)
			(xy 37.544272 -114.228411) (xy 37.536548 -114.247006) (xy 37.53612 -114.257074) (xy 37.53612 -115.361212)
			(xy 37.536785 -115.373856) (xy 37.548788 -115.396116) (xy 37.55898 -115.40363) (xy 37.640768 -115.457224)
			(xy 37.666422 -115.459256) (xy 37.678106 -115.454176) (xy 37.709391 -115.4413) (xy 37.775189 -115.425593)
			(xy 37.808916 -115.422934) (xy 37.819838 -115.422426) (xy 37.839142 -115.412266) (xy 37.899848 -115.335304)
			(xy 37.905182 -115.314222) (xy 37.90315 -115.303554) (xy 37.900308 -115.286807) (xy 37.897252 -115.252975)
			(xy 37.897054 -115.23599) (xy 37.897054 -115.235228) (xy 37.89754 -115.207977) (xy 37.905296 -115.154029)
			(xy 37.920651 -115.101734) (xy 37.943293 -115.052157) (xy 37.972759 -115.006307) (xy 38.00845 -114.965116)
			(xy 38.049641 -114.929425) (xy 38.095491 -114.899959) (xy 38.145068 -114.877317) (xy 38.197363 -114.861962)
			(xy 38.251311 -114.854206) (xy 38.305813 -114.854206) (xy 38.359761 -114.861962) (xy 38.412056 -114.877317)
			(xy 38.461633 -114.899959) (xy 38.507483 -114.929425) (xy 38.548674 -114.965116) (xy 38.584365 -115.006307)
			(xy 38.613831 -115.052157) (xy 38.636473 -115.101734) (xy 38.651828 -115.154029) (xy 38.659584 -115.207977)
			(xy 38.66007 -115.235228) (xy 38.659626 -115.264125) (xy 38.650934 -115.32126) (xy 38.633722 -115.37643)
			(xy 38.608384 -115.428372) (xy 38.575501 -115.475897) (xy 38.535825 -115.517919) (xy 38.490263 -115.553474)
			(xy 38.43986 -115.581749) (xy 38.385768 -115.602096) (xy 38.329225 -115.614052) (xy 38.300406 -115.616228)
			(xy 38.289484 -115.616736) (xy 38.27018 -115.626896) (xy 38.209474 -115.703858) (xy 38.20414 -115.72494)
			(xy 38.206172 -115.735608) (xy 38.209022 -115.752353) (xy 38.212073 -115.786187) (xy 38.212268 -115.803172)
			(xy 38.212268 -115.803934) (xy 38.211754 -115.830915) (xy 38.204134 -115.884336) (xy 38.189064 -115.936152)
			(xy 38.166846 -115.985327) (xy 38.137922 -116.030883) (xy 38.102869 -116.07191) (xy 38.062387 -116.10759)
			(xy 38.017282 -116.137212) (xy 37.993066 -116.14912) (xy 37.982906 -116.153946) (xy 37.968682 -116.17071)
			(xy 37.942266 -116.267484) (xy 37.945822 -116.28882) (xy 37.952172 -116.297964) (xy 37.952172 -116.298218)
			(xy 37.967757 -116.322053) (xy 37.992408 -116.373387) (xy 38.009167 -116.427812) (xy 38.017664 -116.484121)
			(xy 38.018212 -116.512594) (xy 38.017651 -116.542175) (xy 38.008518 -116.600629) (xy 37.990472 -116.656973)
			(xy 37.963944 -116.709855) (xy 37.92957 -116.758008) (xy 37.888175 -116.800277) (xy 37.864796 -116.81841)
			(xy 37.85616 -116.82476) (xy 37.845492 -116.844318) (xy 37.839142 -116.931948) (xy 37.838856 -116.942913)
			(xy 37.846502 -116.963449) (xy 37.853874 -116.971572) (xy 39.15029 -118.267988) (xy 55.586628 -118.267988)
			(xy 55.590699 -118.212366) (xy 55.602825 -118.157929) (xy 55.622748 -118.105838) (xy 55.650044 -118.057203)
			(xy 55.68413 -118.01306) (xy 55.724279 -117.974351) (xy 55.769637 -117.9419) (xy 55.819237 -117.916399)
			(xy 55.872021 -117.898392) (xy 55.926864 -117.888262) (xy 55.982598 -117.886225) (xy 56.038035 -117.892325)
			(xy 56.091992 -117.906431) (xy 56.143321 -117.928243) (xy 56.190927 -117.957297) (xy 56.233795 -117.992972)
			(xy 56.271012 -118.034509) (xy 56.301785 -118.081022) (xy 56.325457 -118.131519) (xy 56.341525 -118.184926)
			(xy 56.349645 -118.240102) (xy 56.350154 -118.267988) (xy 56.349645 -118.295874) (xy 56.341525 -118.35105)
			(xy 56.325457 -118.404457) (xy 56.301785 -118.454954) (xy 56.271012 -118.501467) (xy 56.233795 -118.543004)
			(xy 56.190927 -118.578679) (xy 56.143321 -118.607733) (xy 56.091992 -118.629545) (xy 56.038035 -118.643651)
			(xy 55.982598 -118.649751) (xy 55.926864 -118.647714) (xy 55.872021 -118.637584) (xy 55.819237 -118.619577)
			(xy 55.769637 -118.594076) (xy 55.724279 -118.561625) (xy 55.68413 -118.522916) (xy 55.650044 -118.478773)
			(xy 55.622748 -118.430138) (xy 55.602825 -118.378047) (xy 55.590699 -118.32361) (xy 55.586628 -118.267988)
			(xy 39.15029 -118.267988) (xy 40.968676 -120.086374) (xy 53.639212 -120.086374) (xy 53.639212 -119.222774)
			(xy 53.639702 -119.192806) (xy 53.647525 -119.133384) (xy 53.663038 -119.075491) (xy 53.685974 -119.020118)
			(xy 53.715941 -118.968212) (xy 53.752428 -118.920662) (xy 53.794808 -118.878282) (xy 53.842358 -118.841795)
			(xy 53.894264 -118.811828) (xy 53.949637 -118.788892) (xy 54.00753 -118.773379) (xy 54.066952 -118.765556)
			(xy 54.126888 -118.765556) (xy 54.18631 -118.773379) (xy 54.244203 -118.788892) (xy 54.299576 -118.811828)
			(xy 54.351482 -118.841795) (xy 54.399032 -118.878282) (xy 54.441412 -118.920662) (xy 54.477899 -118.968212)
			(xy 54.507866 -119.020118) (xy 54.530802 -119.075491) (xy 54.546315 -119.133384) (xy 54.554138 -119.192806)
			(xy 54.554628 -119.222774) (xy 54.554628 -120.086374) (xy 54.554138 -120.116342) (xy 54.546315 -120.175764)
			(xy 54.530802 -120.233657) (xy 54.507866 -120.28903) (xy 54.477899 -120.340936) (xy 54.441412 -120.388486)
			(xy 54.399032 -120.430866) (xy 54.351482 -120.467353) (xy 54.299576 -120.49732) (xy 54.244203 -120.520256)
			(xy 54.18631 -120.535769) (xy 54.126888 -120.543592) (xy 54.066952 -120.543592) (xy 54.00753 -120.535769)
			(xy 53.949637 -120.520256) (xy 53.894264 -120.49732) (xy 53.842358 -120.467353) (xy 53.794808 -120.430866)
			(xy 53.752428 -120.388486) (xy 53.715941 -120.340936) (xy 53.685974 -120.28903) (xy 53.663038 -120.233657)
			(xy 53.647525 -120.175764) (xy 53.639702 -120.116342) (xy 53.639212 -120.086374) (xy 40.968676 -120.086374)
			(xy 42.452036 -121.569734) (xy 42.470059 -121.588513) (xy 42.500639 -121.630629) (xy 42.524267 -121.677003)
			(xy 42.540364 -121.726498) (xy 42.548535 -121.777899) (xy 42.549064 -121.803922) (xy 42.549064 -121.886472)
			(xy 51.785012 -121.886472) (xy 51.785012 -121.022872) (xy 51.785502 -120.992904) (xy 51.793325 -120.933482)
			(xy 51.808838 -120.875589) (xy 51.831774 -120.820216) (xy 51.861741 -120.76831) (xy 51.898228 -120.72076)
			(xy 51.940608 -120.67838) (xy 51.988158 -120.641893) (xy 52.040064 -120.611926) (xy 52.095437 -120.58899)
			(xy 52.15333 -120.573477) (xy 52.212752 -120.565654) (xy 52.272688 -120.565654) (xy 52.33211 -120.573477)
			(xy 52.390003 -120.58899) (xy 52.445376 -120.611926) (xy 52.497282 -120.641893) (xy 52.544832 -120.67838)
			(xy 52.587212 -120.72076) (xy 52.623699 -120.76831) (xy 52.653666 -120.820216) (xy 52.676602 -120.875589)
			(xy 52.692115 -120.933482) (xy 52.699938 -120.992904) (xy 52.700428 -121.022872) (xy 52.700428 -121.886472)
			(xy 52.699938 -121.91644) (xy 52.692115 -121.975862) (xy 52.676602 -122.033755) (xy 52.653666 -122.089128)
			(xy 52.623699 -122.141034) (xy 52.587212 -122.188584) (xy 52.544832 -122.230964) (xy 52.497282 -122.267451)
			(xy 52.445376 -122.297418) (xy 52.390003 -122.320354) (xy 52.33211 -122.335867) (xy 52.272688 -122.34369)
			(xy 52.212752 -122.34369) (xy 52.15333 -122.335867) (xy 52.095437 -122.320354) (xy 52.040064 -122.297418)
			(xy 51.988158 -122.267451) (xy 51.940608 -122.230964) (xy 51.898228 -122.188584) (xy 51.861741 -122.141034)
			(xy 51.831774 -122.089128) (xy 51.808838 -122.033755) (xy 51.793325 -121.975862) (xy 51.785502 -121.91644)
			(xy 51.785012 -121.886472) (xy 42.549064 -121.886472) (xy 42.549064 -123.686316) (xy 53.639212 -123.686316)
			(xy 53.639212 -122.822716) (xy 53.639702 -122.792748) (xy 53.647525 -122.733326) (xy 53.663038 -122.675433)
			(xy 53.685974 -122.62006) (xy 53.715941 -122.568154) (xy 53.752428 -122.520604) (xy 53.794808 -122.478224)
			(xy 53.842358 -122.441737) (xy 53.894264 -122.41177) (xy 53.949637 -122.388834) (xy 54.00753 -122.373321)
			(xy 54.066952 -122.365498) (xy 54.126888 -122.365498) (xy 54.18631 -122.373321) (xy 54.244203 -122.388834)
			(xy 54.299576 -122.41177) (xy 54.351482 -122.441737) (xy 54.399032 -122.478224) (xy 54.441412 -122.520604)
			(xy 54.477899 -122.568154) (xy 54.507866 -122.62006) (xy 54.530802 -122.675433) (xy 54.546315 -122.733326)
			(xy 54.554138 -122.792748) (xy 54.554628 -122.822716) (xy 54.554628 -123.686316) (xy 54.554138 -123.716284)
			(xy 54.546315 -123.775706) (xy 54.530802 -123.833599) (xy 54.507866 -123.888972) (xy 54.477899 -123.940878)
			(xy 54.441412 -123.988428) (xy 54.399032 -124.030808) (xy 54.351482 -124.067295) (xy 54.299576 -124.097262)
			(xy 54.244203 -124.120198) (xy 54.18631 -124.135711) (xy 54.126888 -124.143534) (xy 54.066952 -124.143534)
			(xy 54.00753 -124.135711) (xy 53.949637 -124.120198) (xy 53.894264 -124.097262) (xy 53.842358 -124.067295)
			(xy 53.794808 -124.030808) (xy 53.752428 -123.988428) (xy 53.715941 -123.940878) (xy 53.685974 -123.888972)
			(xy 53.663038 -123.833599) (xy 53.647525 -123.775706) (xy 53.639702 -123.716284) (xy 53.639212 -123.686316)
			(xy 42.549064 -123.686316) (xy 42.549064 -125.486414) (xy 51.785012 -125.486414) (xy 51.785012 -124.622814)
			(xy 51.785502 -124.592846) (xy 51.793325 -124.533424) (xy 51.808838 -124.475531) (xy 51.831774 -124.420158)
			(xy 51.861741 -124.368252) (xy 51.898228 -124.320702) (xy 51.940608 -124.278322) (xy 51.988158 -124.241835)
			(xy 52.040064 -124.211868) (xy 52.095437 -124.188932) (xy 52.15333 -124.173419) (xy 52.212752 -124.165596)
			(xy 52.272688 -124.165596) (xy 52.33211 -124.173419) (xy 52.390003 -124.188932) (xy 52.445376 -124.211868)
			(xy 52.497282 -124.241835) (xy 52.544832 -124.278322) (xy 52.587212 -124.320702) (xy 52.623699 -124.368252)
			(xy 52.653666 -124.420158) (xy 52.676602 -124.475531) (xy 52.692115 -124.533424) (xy 52.699938 -124.592846)
			(xy 52.700428 -124.622814) (xy 52.700428 -125.486414) (xy 52.699938 -125.516382) (xy 52.692115 -125.575804)
			(xy 52.676602 -125.633697) (xy 52.653666 -125.68907) (xy 52.623699 -125.740976) (xy 52.587212 -125.788526)
			(xy 52.544832 -125.830906) (xy 52.497282 -125.867393) (xy 52.445376 -125.89736) (xy 52.390003 -125.920296)
			(xy 52.33211 -125.935809) (xy 52.272688 -125.943632) (xy 52.212752 -125.943632) (xy 52.15333 -125.935809)
			(xy 52.095437 -125.920296) (xy 52.040064 -125.89736) (xy 51.988158 -125.867393) (xy 51.940608 -125.830906)
			(xy 51.898228 -125.788526) (xy 51.861741 -125.740976) (xy 51.831774 -125.68907) (xy 51.808838 -125.633697)
			(xy 51.793325 -125.575804) (xy 51.785502 -125.516382) (xy 51.785012 -125.486414) (xy 42.549064 -125.486414)
			(xy 42.549064 -131.29641) (xy 53.639212 -131.29641) (xy 53.639212 -130.43281) (xy 53.639702 -130.402842)
			(xy 53.647525 -130.34342) (xy 53.663038 -130.285527) (xy 53.685974 -130.230154) (xy 53.715941 -130.178248)
			(xy 53.752428 -130.130698) (xy 53.794808 -130.088318) (xy 53.842358 -130.051831) (xy 53.894264 -130.021864)
			(xy 53.949637 -129.998928) (xy 54.00753 -129.983415) (xy 54.066952 -129.975592) (xy 54.126888 -129.975592)
			(xy 54.18631 -129.983415) (xy 54.244203 -129.998928) (xy 54.299576 -130.021864) (xy 54.351482 -130.051831)
			(xy 54.399032 -130.088318) (xy 54.441412 -130.130698) (xy 54.477899 -130.178248) (xy 54.507866 -130.230154)
			(xy 54.530802 -130.285527) (xy 54.546315 -130.34342) (xy 54.554138 -130.402842) (xy 54.554628 -130.43281)
			(xy 54.554628 -131.29641) (xy 54.554138 -131.326378) (xy 54.546315 -131.3858) (xy 54.530802 -131.443693)
			(xy 54.507866 -131.499066) (xy 54.477899 -131.550972) (xy 54.441412 -131.598522) (xy 54.399032 -131.640902)
			(xy 54.351482 -131.677389) (xy 54.299576 -131.707356) (xy 54.244203 -131.730292) (xy 54.18631 -131.745805)
			(xy 54.126888 -131.753628) (xy 54.066952 -131.753628) (xy 54.00753 -131.745805) (xy 53.949637 -131.730292)
			(xy 53.894264 -131.707356) (xy 53.842358 -131.677389) (xy 53.794808 -131.640902) (xy 53.752428 -131.598522)
			(xy 53.715941 -131.550972) (xy 53.685974 -131.499066) (xy 53.663038 -131.443693) (xy 53.647525 -131.3858)
			(xy 53.639702 -131.326378) (xy 53.639212 -131.29641) (xy 42.549064 -131.29641) (xy 42.549064 -133.096508)
			(xy 51.785012 -133.096508) (xy 51.785012 -132.232908) (xy 51.785502 -132.20294) (xy 51.793325 -132.143518)
			(xy 51.808838 -132.085625) (xy 51.831774 -132.030252) (xy 51.861741 -131.978346) (xy 51.898228 -131.930796)
			(xy 51.940608 -131.888416) (xy 51.988158 -131.851929) (xy 52.040064 -131.821962) (xy 52.095437 -131.799026)
			(xy 52.15333 -131.783513) (xy 52.212752 -131.77569) (xy 52.272688 -131.77569) (xy 52.33211 -131.783513)
			(xy 52.390003 -131.799026) (xy 52.445376 -131.821962) (xy 52.497282 -131.851929) (xy 52.544832 -131.888416)
			(xy 52.587212 -131.930796) (xy 52.623699 -131.978346) (xy 52.653666 -132.030252) (xy 52.676602 -132.085625)
			(xy 52.692115 -132.143518) (xy 52.699938 -132.20294) (xy 52.700428 -132.232908) (xy 52.700428 -133.096508)
			(xy 52.699938 -133.126476) (xy 52.692115 -133.185898) (xy 52.676602 -133.243791) (xy 52.653666 -133.299164)
			(xy 52.623699 -133.35107) (xy 52.587212 -133.39862) (xy 52.544832 -133.441) (xy 52.497282 -133.477487)
			(xy 52.445376 -133.507454) (xy 52.390003 -133.53039) (xy 52.33211 -133.545903) (xy 52.272688 -133.553726)
			(xy 52.212752 -133.553726) (xy 52.15333 -133.545903) (xy 52.095437 -133.53039) (xy 52.040064 -133.507454)
			(xy 51.988158 -133.477487) (xy 51.940608 -133.441) (xy 51.898228 -133.39862) (xy 51.861741 -133.35107)
			(xy 51.831774 -133.299164) (xy 51.808838 -133.243791) (xy 51.793325 -133.185898) (xy 51.785502 -133.126476)
			(xy 51.785012 -133.096508) (xy 42.549064 -133.096508) (xy 42.549064 -134.896352) (xy 53.639212 -134.896352)
			(xy 53.639212 -134.032752) (xy 53.639702 -134.002784) (xy 53.647525 -133.943362) (xy 53.663038 -133.885469)
			(xy 53.685974 -133.830096) (xy 53.715941 -133.77819) (xy 53.752428 -133.73064) (xy 53.794808 -133.68826)
			(xy 53.842358 -133.651773) (xy 53.894264 -133.621806) (xy 53.949637 -133.59887) (xy 54.00753 -133.583357)
			(xy 54.066952 -133.575534) (xy 54.126888 -133.575534) (xy 54.18631 -133.583357) (xy 54.244203 -133.59887)
			(xy 54.299576 -133.621806) (xy 54.351482 -133.651773) (xy 54.399032 -133.68826) (xy 54.441412 -133.73064)
			(xy 54.477899 -133.77819) (xy 54.507866 -133.830096) (xy 54.530802 -133.885469) (xy 54.546315 -133.943362)
			(xy 54.554138 -134.002784) (xy 54.554628 -134.032752) (xy 54.554628 -134.896352) (xy 54.554138 -134.92632)
			(xy 54.546315 -134.985742) (xy 54.530802 -135.043635) (xy 54.507866 -135.099008) (xy 54.477899 -135.150914)
			(xy 54.441412 -135.198464) (xy 54.399032 -135.240844) (xy 54.351482 -135.277331) (xy 54.299576 -135.307298)
			(xy 54.244203 -135.330234) (xy 54.18631 -135.345747) (xy 54.126888 -135.35357) (xy 54.066952 -135.35357)
			(xy 54.00753 -135.345747) (xy 53.949637 -135.330234) (xy 53.894264 -135.307298) (xy 53.842358 -135.277331)
			(xy 53.794808 -135.240844) (xy 53.752428 -135.198464) (xy 53.715941 -135.150914) (xy 53.685974 -135.099008)
			(xy 53.663038 -135.043635) (xy 53.647525 -134.985742) (xy 53.639702 -134.92632) (xy 53.639212 -134.896352)
			(xy 42.549064 -134.896352) (xy 42.549064 -136.69645) (xy 51.785012 -136.69645) (xy 51.785012 -135.83285)
			(xy 51.785502 -135.802882) (xy 51.793325 -135.74346) (xy 51.808838 -135.685567) (xy 51.831774 -135.630194)
			(xy 51.861741 -135.578288) (xy 51.898228 -135.530738) (xy 51.940608 -135.488358) (xy 51.988158 -135.451871)
			(xy 52.040064 -135.421904) (xy 52.095437 -135.398968) (xy 52.15333 -135.383455) (xy 52.212752 -135.375632)
			(xy 52.272688 -135.375632) (xy 52.33211 -135.383455) (xy 52.390003 -135.398968) (xy 52.445376 -135.421904)
			(xy 52.497282 -135.451871) (xy 52.544832 -135.488358) (xy 52.587212 -135.530738) (xy 52.623699 -135.578288)
			(xy 52.653666 -135.630194) (xy 52.676602 -135.685567) (xy 52.692115 -135.74346) (xy 52.699938 -135.802882)
			(xy 52.700428 -135.83285) (xy 52.700428 -136.69645) (xy 52.699938 -136.726418) (xy 52.692115 -136.78584)
			(xy 52.676602 -136.843733) (xy 52.653666 -136.899106) (xy 52.623699 -136.951012) (xy 52.587212 -136.998562)
			(xy 52.544832 -137.040942) (xy 52.497282 -137.077429) (xy 52.445376 -137.107396) (xy 52.390003 -137.130332)
			(xy 52.33211 -137.145845) (xy 52.272688 -137.153668) (xy 52.212752 -137.153668) (xy 52.15333 -137.145845)
			(xy 52.095437 -137.130332) (xy 52.040064 -137.107396) (xy 51.988158 -137.077429) (xy 51.940608 -137.040942)
			(xy 51.898228 -136.998562) (xy 51.861741 -136.951012) (xy 51.831774 -136.899106) (xy 51.808838 -136.843733)
			(xy 51.793325 -136.78584) (xy 51.785502 -136.726418) (xy 51.785012 -136.69645) (xy 42.549064 -136.69645)
			(xy 42.549064 -138.496548) (xy 43.97248 -138.496548) (xy 43.97248 -137.632948) (xy 43.97297 -137.602964)
			(xy 43.980798 -137.543508) (xy 43.996319 -137.485583) (xy 44.019268 -137.430179) (xy 44.049252 -137.378245)
			(xy 44.085758 -137.330669) (xy 44.128163 -137.288264) (xy 44.175739 -137.251758) (xy 44.227673 -137.221774)
			(xy 44.283077 -137.198825) (xy 44.341002 -137.183304) (xy 44.400458 -137.175476) (xy 44.460426 -137.175476)
			(xy 44.519882 -137.183304) (xy 44.577807 -137.198825) (xy 44.633211 -137.221774) (xy 44.685145 -137.251758)
			(xy 44.732721 -137.288264) (xy 44.775126 -137.330669) (xy 44.811632 -137.378245) (xy 44.841616 -137.430179)
			(xy 44.864565 -137.485583) (xy 44.880086 -137.543508) (xy 44.887914 -137.602964) (xy 44.888404 -137.632948)
			(xy 44.888404 -138.496548) (xy 44.887914 -138.526532) (xy 44.882966 -138.564112) (xy 46.691294 -138.564112)
			(xy 46.695365 -138.50849) (xy 46.707491 -138.454053) (xy 46.727414 -138.401962) (xy 46.75471 -138.353327)
			(xy 46.788796 -138.309184) (xy 46.828945 -138.270475) (xy 46.874303 -138.238024) (xy 46.923903 -138.212523)
			(xy 46.976687 -138.194516) (xy 47.03153 -138.184386) (xy 47.087264 -138.182349) (xy 47.142701 -138.188449)
			(xy 47.196658 -138.202555) (xy 47.247987 -138.224367) (xy 47.295593 -138.253421) (xy 47.338461 -138.289096)
			(xy 47.375678 -138.330633) (xy 47.406451 -138.377146) (xy 47.430123 -138.427643) (xy 47.446191 -138.48105)
			(xy 47.454311 -138.536226) (xy 47.45482 -138.564112) (xy 47.454311 -138.591998) (xy 47.446191 -138.647174)
			(xy 47.430123 -138.700581) (xy 47.406451 -138.751078) (xy 47.375678 -138.797591) (xy 47.338461 -138.839128)
			(xy 47.295593 -138.874803) (xy 47.247987 -138.903857) (xy 47.196658 -138.925669) (xy 47.142701 -138.939775)
			(xy 47.087264 -138.945875) (xy 47.03153 -138.943838) (xy 46.976687 -138.933708) (xy 46.923903 -138.915701)
			(xy 46.874303 -138.8902) (xy 46.828945 -138.857749) (xy 46.788796 -138.81904) (xy 46.75471 -138.774897)
			(xy 46.727414 -138.726262) (xy 46.707491 -138.674171) (xy 46.695365 -138.619734) (xy 46.691294 -138.564112)
			(xy 44.882966 -138.564112) (xy 44.880086 -138.585988) (xy 44.864565 -138.643913) (xy 44.841616 -138.699317)
			(xy 44.811632 -138.751251) (xy 44.775126 -138.798827) (xy 44.732721 -138.841232) (xy 44.685145 -138.877738)
			(xy 44.633211 -138.907722) (xy 44.577807 -138.930671) (xy 44.519882 -138.946192) (xy 44.460426 -138.95402)
			(xy 44.400458 -138.95402) (xy 44.341002 -138.946192) (xy 44.283077 -138.930671) (xy 44.227673 -138.907722)
			(xy 44.175739 -138.877738) (xy 44.128163 -138.841232) (xy 44.085758 -138.798827) (xy 44.049252 -138.751251)
			(xy 44.019268 -138.699317) (xy 43.996319 -138.643913) (xy 43.980798 -138.585988) (xy 43.97297 -138.526532)
			(xy 43.97248 -138.496548) (xy 42.549064 -138.496548) (xy 42.549064 -139.366244) (xy 42.54945 -139.376318)
			(xy 42.557196 -139.394917) (xy 42.56405 -139.402312) (xy 43.511216 -140.349478) (xy 43.519329 -140.356866)
			(xy 43.539872 -140.364506) (xy 43.55084 -140.36421) (xy 43.627802 -140.358622) (xy 43.6387 -140.357331)
			(xy 43.657924 -140.346787) (xy 43.664886 -140.338302) (xy 43.664886 -140.338048) (xy 43.683682 -140.31468)
			(xy 43.683936 -140.314426) (xy 43.689522 -140.307339) (xy 43.695768 -140.290422) (xy 43.696128 -140.281406)
			(xy 43.696128 -140.21435) (xy 43.695741 -140.205336) (xy 43.689514 -140.188419) (xy 43.683936 -140.18133)
			(xy 43.683682 -140.18133) (xy 43.683682 -140.181076) (xy 43.666062 -140.160128) (xy 43.636348 -140.11416)
			(xy 43.613509 -140.064416) (xy 43.598013 -140.011919) (xy 43.590179 -139.957746) (xy 43.589702 -139.930378)
			(xy 43.590157 -139.903126) (xy 43.597917 -139.849176) (xy 43.613276 -139.79688) (xy 43.63592 -139.747303)
			(xy 43.665389 -139.701452) (xy 43.701084 -139.660262) (xy 43.742277 -139.62457) (xy 43.788131 -139.595105)
			(xy 43.837711 -139.572464) (xy 43.890008 -139.55711) (xy 43.943958 -139.549355) (xy 43.97121 -139.54887)
			(xy 43.998581 -139.549313) (xy 44.052762 -139.557134) (xy 44.105266 -139.572627) (xy 44.155013 -139.595475)
			(xy 44.200978 -139.625205) (xy 44.221908 -139.64285) (xy 44.222162 -139.643104) (xy 44.229255 -139.648681)
			(xy 44.246167 -139.654933) (xy 44.255182 -139.655296) (xy 44.322238 -139.655296) (xy 44.331257 -139.654958)
			(xy 44.348174 -139.648697) (xy 44.355258 -139.643104) (xy 44.355258 -139.64285) (xy 44.355512 -139.64285)
			(xy 44.376473 -139.625246) (xy 44.422437 -139.595528) (xy 44.472177 -139.572684) (xy 44.524672 -139.557185)
			(xy 44.578843 -139.549348) (xy 44.60621 -139.54887) (xy 44.63346 -139.549368) (xy 44.687407 -139.557126)
			(xy 44.7397 -139.572481) (xy 44.789276 -139.595122) (xy 44.835125 -139.624587) (xy 44.876314 -139.660277)
			(xy 44.912006 -139.701465) (xy 44.941473 -139.747314) (xy 44.964115 -139.796889) (xy 44.979472 -139.849182)
			(xy 44.987231 -139.903128) (xy 44.987718 -139.930378) (xy 44.987259 -139.957749) (xy 44.979443 -140.011929)
			(xy 44.963953 -140.064433) (xy 44.941109 -140.11418) (xy 44.932506 -140.127482) (xy 51.605178 -140.127482)
			(xy 51.609249 -140.07186) (xy 51.621375 -140.017423) (xy 51.641298 -139.965332) (xy 51.668594 -139.916697)
			(xy 51.70268 -139.872554) (xy 51.742829 -139.833845) (xy 51.788187 -139.801394) (xy 51.837787 -139.775893)
			(xy 51.890571 -139.757886) (xy 51.945414 -139.747756) (xy 52.001148 -139.745719) (xy 52.056585 -139.751819)
			(xy 52.110542 -139.765925) (xy 52.161871 -139.787737) (xy 52.209477 -139.816791) (xy 52.252345 -139.852466)
			(xy 52.289562 -139.894003) (xy 52.320335 -139.940516) (xy 52.344007 -139.991013) (xy 52.360075 -140.04442)
			(xy 52.368195 -140.099596) (xy 52.368704 -140.127482) (xy 52.368195 -140.155368) (xy 52.360075 -140.210544)
			(xy 52.344007 -140.263951) (xy 52.320335 -140.314448) (xy 52.289562 -140.360961) (xy 52.252345 -140.402498)
			(xy 52.209477 -140.438173) (xy 52.161871 -140.467227) (xy 52.110542 -140.489039) (xy 52.056585 -140.503145)
			(xy 52.001148 -140.509245) (xy 51.945414 -140.507208) (xy 51.890571 -140.497078) (xy 51.837787 -140.479071)
			(xy 51.788187 -140.45357) (xy 51.742829 -140.421119) (xy 51.70268 -140.38241) (xy 51.668594 -140.338267)
			(xy 51.641298 -140.289632) (xy 51.621375 -140.237541) (xy 51.609249 -140.183104) (xy 51.605178 -140.127482)
			(xy 44.932506 -140.127482) (xy 44.911381 -140.160145) (xy 44.893738 -140.181076) (xy 44.893484 -140.18133)
			(xy 44.887919 -140.188431) (xy 44.88166 -140.205337) (xy 44.881292 -140.21435) (xy 44.881292 -140.281406)
			(xy 44.881648 -140.290423) (xy 44.887896 -140.30734) (xy 44.893484 -140.314426) (xy 44.893738 -140.314426)
			(xy 44.893738 -140.31468) (xy 44.911387 -140.335604) (xy 44.941097 -140.381579) (xy 44.96393 -140.431329)
			(xy 44.979419 -140.483831) (xy 44.987245 -140.538008) (xy 44.987718 -140.565378) (xy 44.987224 -140.59263)
			(xy 44.979471 -140.646579) (xy 44.964118 -140.698876) (xy 44.941479 -140.748455) (xy 44.912014 -140.794308)
			(xy 44.876323 -140.835501) (xy 44.835134 -140.871195) (xy 44.789283 -140.900663) (xy 44.739706 -140.923307)
			(xy 44.68741 -140.938664) (xy 44.633462 -140.946422) (xy 44.60621 -140.946886) (xy 44.57884 -140.946417)
			(xy 44.524661 -140.938601) (xy 44.472157 -140.923112) (xy 44.422411 -140.900271) (xy 44.376444 -140.870547)
			(xy 44.355512 -140.852906) (xy 44.355258 -140.852652) (xy 44.348163 -140.847078) (xy 44.331253 -140.840825)
			(xy 44.322238 -140.84046) (xy 44.255182 -140.84046) (xy 44.246163 -140.840796) (xy 44.229245 -140.847057)
			(xy 44.222162 -140.852652) (xy 44.221908 -140.852906) (xy 44.19854 -140.871702) (xy 44.198286 -140.871702)
			(xy 44.189837 -140.878692) (xy 44.179309 -140.897903) (xy 44.177966 -140.908786) (xy 44.172378 -140.985748)
			(xy 44.172082 -140.996713) (xy 44.179734 -141.017251) (xy 44.18711 -141.025372) (xy 47.253398 -144.091406)
			(xy 47.260804 -144.098238) (xy 47.279399 -144.105962) (xy 47.289466 -144.106392) (xy 49.117758 -144.106392)
			(xy 49.127825 -144.105947) (xy 49.146423 -144.09824) (xy 49.153826 -144.091406) (xy 50.350928 -142.894304)
			(xy 50.369716 -142.876291) (xy 50.411828 -142.845708) (xy 50.4582 -142.822077) (xy 50.507693 -142.805978)
			(xy 50.559094 -142.797806) (xy 50.585116 -142.797276) (xy 51.306222 -142.797276) (xy 51.317151 -142.796774)
			(xy 51.337026 -142.787671) (xy 51.344576 -142.77975) (xy 51.395122 -142.721838) (xy 51.401768 -142.713343)
			(xy 51.407965 -142.692706) (xy 51.40706 -142.68196) (xy 51.40706 -142.681198) (xy 51.404449 -142.661171)
			(xy 51.401654 -142.620876) (xy 51.401472 -142.60068) (xy 51.402085 -142.562371) (xy 51.412068 -142.486406)
			(xy 51.43186 -142.412389) (xy 51.461124 -142.34158) (xy 51.479704 -142.308072) (xy 51.483887 -142.300209)
			(xy 51.486976 -142.282676) (xy 51.483871 -142.265146) (xy 51.479704 -142.257272) (xy 51.461139 -142.223792)
			(xy 51.431873 -142.153051) (xy 51.41208 -142.079098) (xy 51.402097 -142.003196) (xy 51.401472 -141.964918)
			(xy 51.402073 -141.929517) (xy 51.410602 -141.859231) (xy 51.427539 -141.790486) (xy 51.452636 -141.724281)
			(xy 51.485527 -141.661584) (xy 51.525735 -141.603307) (xy 51.572671 -141.550299) (xy 51.625653 -141.503333)
			(xy 51.683908 -141.463094) (xy 51.746588 -141.430168) (xy 51.812778 -141.405035) (xy 51.881514 -141.38806)
			(xy 51.951796 -141.379492) (xy 51.987196 -141.37894) (xy 52.429918 -141.37894) (xy 52.4628 -141.379357)
			(xy 52.528149 -141.386726) (xy 52.592261 -141.401371) (xy 52.654329 -141.423107) (xy 52.713571 -141.451659)
			(xy 52.769241 -141.486669) (xy 52.820639 -141.527695) (xy 52.844192 -141.550644) (xy 54.232302 -142.938754)
			(xy 54.255228 -142.962292) (xy 54.296189 -143.013674) (xy 54.33114 -143.069319) (xy 54.359641 -143.128528)
			(xy 54.381335 -143.190554) (xy 54.395947 -143.25462) (xy 54.403296 -143.319918) (xy 54.403752 -143.352774)
			(xy 54.403752 -145.781776) (xy 54.404176 -145.791846) (xy 54.411896 -145.810444) (xy 54.418738 -145.817844)
			(xy 55.583074 -146.981926) (xy 55.605981 -147.005482) (xy 55.646945 -147.05686) (xy 55.681898 -147.112502)
			(xy 55.710402 -147.171707) (xy 55.732099 -147.233731) (xy 55.746715 -147.297794) (xy 55.754066 -147.363091)
			(xy 55.754524 -147.395946) (xy 55.754524 -150.08733) (xy 56.079388 -150.08733) (xy 56.083459 -150.031708)
			(xy 56.095585 -149.977271) (xy 56.115508 -149.92518) (xy 56.142804 -149.876545) (xy 56.17689 -149.832402)
			(xy 56.217039 -149.793693) (xy 56.262397 -149.761242) (xy 56.311997 -149.735741) (xy 56.364781 -149.717734)
			(xy 56.419624 -149.707604) (xy 56.475358 -149.705567) (xy 56.530795 -149.711667) (xy 56.584752 -149.725773)
			(xy 56.636081 -149.747585) (xy 56.683687 -149.776639) (xy 56.726555 -149.812314) (xy 56.763772 -149.853851)
			(xy 56.794545 -149.900364) (xy 56.818217 -149.950861) (xy 56.834285 -150.004268) (xy 56.842405 -150.059444)
			(xy 56.842914 -150.08733) (xy 56.842405 -150.115216) (xy 56.834285 -150.170392) (xy 56.818217 -150.223799)
			(xy 56.794545 -150.274296) (xy 56.763772 -150.320809) (xy 56.726555 -150.362346) (xy 56.683687 -150.398021)
			(xy 56.636081 -150.427075) (xy 56.584752 -150.448887) (xy 56.530795 -150.462993) (xy 56.475358 -150.469093)
			(xy 56.419624 -150.467056) (xy 56.364781 -150.456926) (xy 56.311997 -150.438919) (xy 56.262397 -150.413418)
			(xy 56.217039 -150.380967) (xy 56.17689 -150.342258) (xy 56.142804 -150.298115) (xy 56.115508 -150.24948)
			(xy 56.095585 -150.197389) (xy 56.083459 -150.142952) (xy 56.079388 -150.08733) (xy 55.754524 -150.08733)
			(xy 55.754524 -151.125428) (xy 55.928004 -151.125428) (xy 55.932075 -151.069806) (xy 55.944201 -151.015369)
			(xy 55.964124 -150.963278) (xy 55.99142 -150.914643) (xy 56.025506 -150.8705) (xy 56.065655 -150.831791)
			(xy 56.111013 -150.79934) (xy 56.160613 -150.773839) (xy 56.213397 -150.755832) (xy 56.26824 -150.745702)
			(xy 56.323974 -150.743665) (xy 56.379411 -150.749765) (xy 56.433368 -150.763871) (xy 56.484697 -150.785683)
			(xy 56.532303 -150.814737) (xy 56.575171 -150.850412) (xy 56.612388 -150.891949) (xy 56.643161 -150.938462)
			(xy 56.666833 -150.988959) (xy 56.682901 -151.042366) (xy 56.691021 -151.097542) (xy 56.69153 -151.125428)
			(xy 56.691021 -151.153314) (xy 56.682901 -151.20849) (xy 56.666833 -151.261897) (xy 56.643161 -151.312394)
			(xy 56.612388 -151.358907) (xy 56.575171 -151.400444) (xy 56.532303 -151.436119) (xy 56.484697 -151.465173)
			(xy 56.433368 -151.486985) (xy 56.379411 -151.501091) (xy 56.323974 -151.507191) (xy 56.26824 -151.505154)
			(xy 56.213397 -151.495024) (xy 56.160613 -151.477017) (xy 56.111013 -151.451516) (xy 56.065655 -151.419065)
			(xy 56.025506 -151.380356) (xy 55.99142 -151.336213) (xy 55.964124 -151.287578) (xy 55.944201 -151.235487)
			(xy 55.932075 -151.18105) (xy 55.928004 -151.125428) (xy 55.754524 -151.125428) (xy 55.754524 -156.483558)
			(xy 55.755172 -156.494973) (xy 55.765061 -156.515551) (xy 55.773574 -156.523182) (xy 55.845202 -156.580078)
			(xy 55.867554 -156.585158) (xy 55.878984 -156.582364) (xy 55.899907 -156.577878) (xy 55.942424 -156.573041)
			(xy 55.96382 -156.572712) (xy 55.964582 -156.572712) (xy 55.991837 -156.573134) (xy 56.045793 -156.580889)
			(xy 56.098096 -156.596244) (xy 56.147681 -156.618887) (xy 56.193539 -156.648356) (xy 56.234736 -156.684052)
			(xy 56.270433 -156.725247) (xy 56.299904 -156.771103) (xy 56.322549 -156.820687) (xy 56.337907 -156.872989)
			(xy 56.345665 -156.926945) (xy 56.345665 -156.981455) (xy 56.337907 -157.035411) (xy 56.322549 -157.087713)
			(xy 56.299904 -157.137297) (xy 56.270433 -157.183153) (xy 56.234736 -157.224348) (xy 56.193539 -157.260044)
			(xy 56.147681 -157.289513) (xy 56.098096 -157.312156) (xy 56.045793 -157.327511) (xy 55.991837 -157.335266)
			(xy 55.964582 -157.335728) (xy 55.96382 -157.335728) (xy 55.942423 -157.335418) (xy 55.899903 -157.330582)
			(xy 55.878984 -157.326076) (xy 55.867554 -157.323282) (xy 55.845202 -157.328362) (xy 55.773574 -157.385258)
			(xy 55.765069 -157.3929) (xy 55.755162 -157.413468) (xy 55.754524 -157.424882) (xy 55.754524 -159.481266)
			(xy 55.755099 -159.49247) (xy 55.764572 -159.512772) (xy 55.772812 -159.520382) (xy 55.8419 -159.577786)
			(xy 55.863744 -159.583374) (xy 55.87492 -159.581088) (xy 55.892227 -159.578096) (xy 55.927207 -159.574916)
			(xy 55.94477 -159.574738) (xy 55.972028 -159.575107) (xy 56.025988 -159.582861) (xy 56.078296 -159.598217)
			(xy 56.127886 -159.62086) (xy 56.173749 -159.650331) (xy 56.21495 -159.686029) (xy 56.250651 -159.727227)
			(xy 56.280125 -159.773088) (xy 56.302773 -159.822676) (xy 56.318132 -159.874982) (xy 56.325891 -159.928942)
			(xy 56.325891 -159.983458) (xy 56.318132 -160.037418) (xy 56.302773 -160.089724) (xy 56.280125 -160.139312)
			(xy 56.250651 -160.185173) (xy 56.21495 -160.226371) (xy 56.173749 -160.262069) (xy 56.127886 -160.29154)
			(xy 56.078296 -160.314183) (xy 56.025988 -160.329539) (xy 55.972028 -160.337293) (xy 55.94477 -160.337754)
			(xy 55.927207 -160.337581) (xy 55.892226 -160.3344) (xy 55.87492 -160.331404) (xy 55.863744 -160.329118)
			(xy 55.8419 -160.334706) (xy 55.772812 -160.39211) (xy 55.764587 -160.399732) (xy 55.755107 -160.420027)
			(xy 55.754524 -160.431226) (xy 55.754524 -172.329348) (xy 61.847982 -172.329348) (xy 61.852053 -172.273726)
			(xy 61.864179 -172.219289) (xy 61.884102 -172.167198) (xy 61.911398 -172.118563) (xy 61.945484 -172.07442)
			(xy 61.985633 -172.035711) (xy 62.030991 -172.00326) (xy 62.080591 -171.977759) (xy 62.133375 -171.959752)
			(xy 62.188218 -171.949622) (xy 62.243952 -171.947585) (xy 62.299389 -171.953685) (xy 62.353346 -171.967791)
			(xy 62.404675 -171.989603) (xy 62.452281 -172.018657) (xy 62.495149 -172.054332) (xy 62.532366 -172.095869)
			(xy 62.563139 -172.142382) (xy 62.586811 -172.192879) (xy 62.602879 -172.246286) (xy 62.610999 -172.301462)
			(xy 62.611508 -172.329348) (xy 62.611244 -172.343826) (xy 62.785242 -172.343826) (xy 62.789313 -172.288204)
			(xy 62.801439 -172.233767) (xy 62.821362 -172.181676) (xy 62.848658 -172.133041) (xy 62.882744 -172.088898)
			(xy 62.922893 -172.050189) (xy 62.968251 -172.017738) (xy 63.017851 -171.992237) (xy 63.070635 -171.97423)
			(xy 63.125478 -171.9641) (xy 63.181212 -171.962063) (xy 63.236649 -171.968163) (xy 63.290606 -171.982269)
			(xy 63.341935 -172.004081) (xy 63.389541 -172.033135) (xy 63.432409 -172.06881) (xy 63.469626 -172.110347)
			(xy 63.500399 -172.15686) (xy 63.524071 -172.207357) (xy 63.540139 -172.260764) (xy 63.548259 -172.31594)
			(xy 63.548768 -172.343826) (xy 63.548259 -172.371712) (xy 63.540139 -172.426888) (xy 63.524071 -172.480295)
			(xy 63.500399 -172.530792) (xy 63.469626 -172.577305) (xy 63.432409 -172.618842) (xy 63.389541 -172.654517)
			(xy 63.341935 -172.683571) (xy 63.290606 -172.705383) (xy 63.236649 -172.719489) (xy 63.181212 -172.725589)
			(xy 63.125478 -172.723552) (xy 63.070635 -172.713422) (xy 63.017851 -172.695415) (xy 62.968251 -172.669914)
			(xy 62.922893 -172.637463) (xy 62.882744 -172.598754) (xy 62.848658 -172.554611) (xy 62.821362 -172.505976)
			(xy 62.801439 -172.453885) (xy 62.789313 -172.399448) (xy 62.785242 -172.343826) (xy 62.611244 -172.343826)
			(xy 62.610999 -172.357234) (xy 62.602879 -172.41241) (xy 62.586811 -172.465817) (xy 62.563139 -172.516314)
			(xy 62.532366 -172.562827) (xy 62.495149 -172.604364) (xy 62.452281 -172.640039) (xy 62.404675 -172.669093)
			(xy 62.353346 -172.690905) (xy 62.299389 -172.705011) (xy 62.243952 -172.711111) (xy 62.188218 -172.709074)
			(xy 62.133375 -172.698944) (xy 62.080591 -172.680937) (xy 62.030991 -172.655436) (xy 61.985633 -172.622985)
			(xy 61.945484 -172.584276) (xy 61.911398 -172.540133) (xy 61.884102 -172.491498) (xy 61.864179 -172.439407)
			(xy 61.852053 -172.38497) (xy 61.847982 -172.329348) (xy 55.754524 -172.329348) (xy 55.754524 -175.542956)
			(xy 62.632842 -175.542956) (xy 62.636913 -175.487334) (xy 62.649039 -175.432897) (xy 62.668962 -175.380806)
			(xy 62.696258 -175.332171) (xy 62.730344 -175.288028) (xy 62.770493 -175.249319) (xy 62.815851 -175.216868)
			(xy 62.865451 -175.191367) (xy 62.918235 -175.17336) (xy 62.973078 -175.16323) (xy 63.028812 -175.161193)
			(xy 63.084249 -175.167293) (xy 63.138206 -175.181399) (xy 63.189535 -175.203211) (xy 63.237141 -175.232265)
			(xy 63.280009 -175.26794) (xy 63.317226 -175.309477) (xy 63.347999 -175.35599) (xy 63.371671 -175.406487)
			(xy 63.387739 -175.459894) (xy 63.395859 -175.51507) (xy 63.396368 -175.542956) (xy 63.395859 -175.570842)
			(xy 63.387739 -175.626018) (xy 63.371671 -175.679425) (xy 63.347999 -175.729922) (xy 63.317226 -175.776435)
			(xy 63.280009 -175.817972) (xy 63.237141 -175.853647) (xy 63.189535 -175.882701) (xy 63.138206 -175.904513)
			(xy 63.084249 -175.918619) (xy 63.028812 -175.924719) (xy 62.973078 -175.922682) (xy 62.918235 -175.912552)
			(xy 62.865451 -175.894545) (xy 62.815851 -175.869044) (xy 62.770493 -175.836593) (xy 62.730344 -175.797884)
			(xy 62.696258 -175.753741) (xy 62.668962 -175.705106) (xy 62.649039 -175.653015) (xy 62.636913 -175.598578)
			(xy 62.632842 -175.542956) (xy 55.754524 -175.542956) (xy 55.754524 -177.015394) (xy 61.6618 -177.015394)
			(xy 61.665871 -176.959772) (xy 61.677997 -176.905335) (xy 61.69792 -176.853244) (xy 61.725216 -176.804609)
			(xy 61.759302 -176.760466) (xy 61.799451 -176.721757) (xy 61.844809 -176.689306) (xy 61.894409 -176.663805)
			(xy 61.947193 -176.645798) (xy 62.002036 -176.635668) (xy 62.05777 -176.633631) (xy 62.113207 -176.639731)
			(xy 62.167164 -176.653837) (xy 62.218493 -176.675649) (xy 62.266099 -176.704703) (xy 62.308967 -176.740378)
			(xy 62.346184 -176.781915) (xy 62.376957 -176.828428) (xy 62.400629 -176.878925) (xy 62.416697 -176.932332)
			(xy 62.424817 -176.987508) (xy 62.425326 -177.015394) (xy 62.424817 -177.04328) (xy 62.416697 -177.098456)
			(xy 62.400629 -177.151863) (xy 62.376957 -177.20236) (xy 62.346184 -177.248873) (xy 62.308967 -177.29041)
			(xy 62.266099 -177.326085) (xy 62.221647 -177.353214) (xy 64.295018 -177.353214) (xy 64.299089 -177.297592)
			(xy 64.311215 -177.243155) (xy 64.331138 -177.191064) (xy 64.358434 -177.142429) (xy 64.39252 -177.098286)
			(xy 64.432669 -177.059577) (xy 64.478027 -177.027126) (xy 64.527627 -177.001625) (xy 64.580411 -176.983618)
			(xy 64.635254 -176.973488) (xy 64.690988 -176.971451) (xy 64.746425 -176.977551) (xy 64.800382 -176.991657)
			(xy 64.851711 -177.013469) (xy 64.899317 -177.042523) (xy 64.942185 -177.078198) (xy 64.979402 -177.119735)
			(xy 65.010175 -177.166248) (xy 65.033847 -177.216745) (xy 65.049915 -177.270152) (xy 65.058035 -177.325328)
			(xy 65.058544 -177.353214) (xy 65.058035 -177.3811) (xy 65.049915 -177.436276) (xy 65.033847 -177.489683)
			(xy 65.010175 -177.54018) (xy 64.979402 -177.586693) (xy 64.942185 -177.62823) (xy 64.899317 -177.663905)
			(xy 64.851711 -177.692959) (xy 64.800382 -177.714771) (xy 64.746425 -177.728877) (xy 64.690988 -177.734977)
			(xy 64.635254 -177.73294) (xy 64.580411 -177.72281) (xy 64.527627 -177.704803) (xy 64.478027 -177.679302)
			(xy 64.432669 -177.646851) (xy 64.39252 -177.608142) (xy 64.358434 -177.563999) (xy 64.331138 -177.515364)
			(xy 64.311215 -177.463273) (xy 64.299089 -177.408836) (xy 64.295018 -177.353214) (xy 62.221647 -177.353214)
			(xy 62.218493 -177.355139) (xy 62.167164 -177.376951) (xy 62.113207 -177.391057) (xy 62.05777 -177.397157)
			(xy 62.002036 -177.39512) (xy 61.947193 -177.38499) (xy 61.894409 -177.366983) (xy 61.844809 -177.341482)
			(xy 61.799451 -177.309031) (xy 61.759302 -177.270322) (xy 61.725216 -177.226179) (xy 61.69792 -177.177544)
			(xy 61.677997 -177.125453) (xy 61.665871 -177.071016) (xy 61.6618 -177.015394) (xy 55.754524 -177.015394)
			(xy 55.754524 -178.247548) (xy 55.75497 -178.257615) (xy 55.762676 -178.276213) (xy 55.76951 -178.283616)
			(xy 62.695074 -185.208926) (xy 62.717981 -185.232482) (xy 62.758945 -185.28386) (xy 62.793898 -185.339502)
			(xy 62.822402 -185.398707) (xy 62.844099 -185.460731) (xy 62.858715 -185.524794) (xy 62.866066 -185.590091)
			(xy 62.866524 -185.622946) (xy 62.866524 -205.800198) (xy 62.867247 -205.812257) (xy 62.87823 -205.833731)
			(xy 62.887606 -205.841346) (xy 62.954662 -205.889606) (xy 62.964787 -205.896094) (xy 62.988509 -205.899813)
			(xy 63.000128 -205.896718) (xy 63.000636 -205.896718) (xy 63.02978 -205.887658) (xy 63.090011 -205.877826)
			(xy 63.120524 -205.87716) (xy 63.147774 -205.877655) (xy 63.20172 -205.885414) (xy 63.254013 -205.900771)
			(xy 63.303588 -205.923412) (xy 63.349437 -205.952878) (xy 63.390626 -205.988569) (xy 63.426317 -206.029757)
			(xy 63.455784 -206.075605) (xy 63.478426 -206.12518) (xy 63.493784 -206.177472) (xy 63.501544 -206.231418)
			(xy 63.502032 -206.258668) (xy 63.501444 -206.288538) (xy 63.497659 -206.312516) (xy 64.718944 -206.312516)
			(xy 64.723015 -206.256894) (xy 64.735141 -206.202457) (xy 64.755064 -206.150366) (xy 64.78236 -206.101731)
			(xy 64.816446 -206.057588) (xy 64.856595 -206.018879) (xy 64.901953 -205.986428) (xy 64.951553 -205.960927)
			(xy 65.004337 -205.94292) (xy 65.05918 -205.93279) (xy 65.114914 -205.930753) (xy 65.170351 -205.936853)
			(xy 65.224308 -205.950959) (xy 65.275637 -205.972771) (xy 65.323243 -206.001825) (xy 65.366111 -206.0375)
			(xy 65.403328 -206.079037) (xy 65.434101 -206.12555) (xy 65.457773 -206.176047) (xy 65.473841 -206.229454)
			(xy 65.481961 -206.28463) (xy 65.48247 -206.312516) (xy 65.481961 -206.340402) (xy 65.473841 -206.395578)
			(xy 65.457773 -206.448985) (xy 65.434101 -206.499482) (xy 65.403328 -206.545995) (xy 65.366111 -206.587532)
			(xy 65.323243 -206.623207) (xy 65.275637 -206.652261) (xy 65.224308 -206.674073) (xy 65.170351 -206.688179)
			(xy 65.114914 -206.694279) (xy 65.05918 -206.692242) (xy 65.004337 -206.682112) (xy 64.951553 -206.664105)
			(xy 64.901953 -206.638604) (xy 64.856595 -206.606153) (xy 64.816446 -206.567444) (xy 64.78236 -206.523301)
			(xy 64.755064 -206.474666) (xy 64.735141 -206.422575) (xy 64.723015 -206.368138) (xy 64.718944 -206.312516)
			(xy 63.497659 -206.312516) (xy 63.49213 -206.347547) (xy 63.473726 -206.404381) (xy 63.446682 -206.457649)
			(xy 63.429642 -206.482188) (xy 63.418466 -206.497428) (xy 63.421514 -206.534512) (xy 63.547498 -206.660496)
			(xy 63.570395 -206.684061) (xy 63.611359 -206.735439) (xy 63.646313 -206.791079) (xy 63.674818 -206.850282)
			(xy 63.696516 -206.912304) (xy 63.711134 -206.976366) (xy 63.718489 -207.041662) (xy 63.718948 -207.074516)
			(xy 63.718948 -207.831944) (xy 63.719479 -207.843551) (xy 63.729583 -207.864443) (xy 63.747848 -207.87876)
			(xy 63.75908 -207.881728) (xy 63.785485 -207.887967) (xy 63.836324 -207.906913) (xy 63.883968 -207.932869)
			(xy 63.927456 -207.965311) (xy 63.96591 -208.003585) (xy 63.998557 -208.046919) (xy 64.012064 -208.07045)
			(xy 64.0168 -208.078404) (xy 64.03085 -208.090441) (xy 64.048273 -208.096663) (xy 64.05753 -208.096866)
			(xy 64.146938 -208.095596) (xy 64.156126 -208.095041) (xy 64.173228 -208.088275) (xy 64.186847 -208.075916)
			(xy 64.191388 -208.06791) (xy 64.203721 -208.044842) (xy 64.233736 -208.002003) (xy 64.269325 -207.963667)
			(xy 64.309819 -207.930556) (xy 64.354458 -207.903289) (xy 64.402405 -207.88238) (xy 64.45276 -207.86822)
			(xy 64.504578 -207.861075) (xy 64.530732 -207.860646) (xy 64.557978 -207.861226) (xy 64.611916 -207.868986)
			(xy 64.664201 -207.884342) (xy 64.713768 -207.906982) (xy 64.759609 -207.936445) (xy 64.80079 -207.972133)
			(xy 64.836474 -208.013317) (xy 64.865933 -208.05916) (xy 64.88857 -208.108729) (xy 64.903921 -208.161015)
			(xy 64.911676 -208.214954) (xy 64.911676 -208.269446) (xy 64.903921 -208.323385) (xy 64.88857 -208.375671)
			(xy 64.865934 -208.42524) (xy 64.840929 -208.46415) (xy 69.238366 -208.46415) (xy 69.242437 -208.408528)
			(xy 69.254563 -208.354091) (xy 69.274486 -208.302) (xy 69.301782 -208.253365) (xy 69.335868 -208.209222)
			(xy 69.376017 -208.170513) (xy 69.421375 -208.138062) (xy 69.470975 -208.112561) (xy 69.523759 -208.094554)
			(xy 69.578602 -208.084424) (xy 69.634336 -208.082387) (xy 69.689773 -208.088487) (xy 69.74373 -208.102593)
			(xy 69.795059 -208.124405) (xy 69.842665 -208.153459) (xy 69.885533 -208.189134) (xy 69.92275 -208.230671)
			(xy 69.953523 -208.277184) (xy 69.977195 -208.327681) (xy 69.993263 -208.381088) (xy 70.001383 -208.436264)
			(xy 70.001892 -208.46415) (xy 70.001383 -208.492036) (xy 69.993263 -208.547212) (xy 69.977195 -208.600619)
			(xy 69.953523 -208.651116) (xy 69.92275 -208.697629) (xy 69.885533 -208.739166) (xy 69.842665 -208.774841)
			(xy 69.795059 -208.803895) (xy 69.74373 -208.825707) (xy 69.689773 -208.839813) (xy 69.634336 -208.845913)
			(xy 69.578602 -208.843876) (xy 69.523759 -208.833746) (xy 69.470975 -208.815739) (xy 69.421375 -208.790238)
			(xy 69.376017 -208.757787) (xy 69.335868 -208.719078) (xy 69.301782 -208.674935) (xy 69.274486 -208.6263)
			(xy 69.254563 -208.574209) (xy 69.242437 -208.519772) (xy 69.238366 -208.46415) (xy 64.840929 -208.46415)
			(xy 64.836474 -208.471083) (xy 64.80079 -208.512267) (xy 64.759609 -208.547955) (xy 64.713768 -208.577418)
			(xy 64.664201 -208.600058) (xy 64.611916 -208.615414) (xy 64.557978 -208.623174) (xy 64.530732 -208.623662)
			(xy 64.501632 -208.623082) (xy 64.444106 -208.614252) (xy 64.388587 -208.596793) (xy 64.336362 -208.571107)
			(xy 64.288641 -208.537792) (xy 64.24653 -208.497619) (xy 64.211005 -208.451519) (xy 64.196468 -208.426304)
			(xy 64.191693 -208.418375) (xy 64.177663 -208.406331) (xy 64.160254 -208.400097) (xy 64.151002 -208.399888)
			(xy 64.061594 -208.401158) (xy 64.052405 -208.401707) (xy 64.035299 -208.40847) (xy 64.021681 -208.420835)
			(xy 64.017144 -208.428844) (xy 64.003858 -208.45355) (xy 63.971207 -208.499162) (xy 63.932238 -208.53951)
			(xy 63.887789 -208.573729) (xy 63.838816 -208.601081) (xy 63.78637 -208.620981) (xy 63.75908 -208.627472)
			(xy 63.747862 -208.630451) (xy 63.729643 -208.644801) (xy 63.719508 -208.665661) (xy 63.718948 -208.677256)
			(xy 63.718948 -209.296762) (xy 63.718841 -209.31529) (xy 63.716551 -209.352275) (xy 63.714376 -209.370676)
			(xy 63.714376 -209.37093) (xy 63.713521 -209.381647) (xy 63.719833 -209.402175) (xy 63.726568 -209.410554)
			(xy 63.77686 -209.467704) (xy 63.784371 -209.475535) (xy 63.80412 -209.484479) (xy 63.81496 -209.484976)
			(xy 63.89116 -209.484976) (xy 63.901228 -209.484536) (xy 63.919826 -209.476826) (xy 63.927228 -209.46999)
			(xy 64.429132 -208.968086) (xy 64.452685 -208.945174) (xy 64.504062 -208.904207) (xy 64.559703 -208.869251)
			(xy 64.618909 -208.840744) (xy 64.680934 -208.819046) (xy 64.744998 -208.804429) (xy 64.810297 -208.797077)
			(xy 64.843152 -208.796636) (xy 64.843406 -208.796636) (xy 64.87881 -208.79715) (xy 64.949101 -208.805684)
			(xy 65.017852 -208.822625) (xy 65.08406 -208.847728) (xy 65.146761 -208.880627) (xy 65.20504 -208.920841)
			(xy 65.258049 -208.967785) (xy 65.305015 -209.020775) (xy 65.345252 -209.079039) (xy 65.378176 -209.141726)
			(xy 65.403305 -209.207925) (xy 65.420274 -209.276669) (xy 65.428835 -209.346957) (xy 65.429384 -209.38236)
			(xy 65.428923 -209.41524) (xy 65.42156 -209.480588) (xy 65.406922 -209.544699) (xy 65.385193 -209.606766)
			(xy 65.356648 -209.666009) (xy 65.321645 -209.72168) (xy 65.280626 -209.773079) (xy 65.25768 -209.796634)
			(xy 64.569086 -210.485228) (xy 64.547103 -210.506652) (xy 64.499369 -210.545252) (xy 64.44786 -210.578649)
			(xy 64.393141 -210.606477) (xy 64.364616 -210.617816) (xy 64.364362 -210.617816) (xy 64.35638 -210.621311)
			(xy 64.343235 -210.632731) (xy 64.334691 -210.647904) (xy 64.332866 -210.656424) (xy 64.31534 -210.755992)
			(xy 64.32423 -210.780884) (xy 64.334644 -210.789774) (xy 64.355012 -210.807984) (xy 64.390882 -210.849196)
			(xy 64.420501 -210.895105) (xy 64.443264 -210.944772) (xy 64.458705 -210.99718) (xy 64.466507 -211.051255)
			(xy 64.466685 -211.061554) (xy 69.39102 -211.061554) (xy 69.395091 -211.005932) (xy 69.407217 -210.951495)
			(xy 69.42714 -210.899404) (xy 69.454436 -210.850769) (xy 69.488522 -210.806626) (xy 69.528671 -210.767917)
			(xy 69.574029 -210.735466) (xy 69.623629 -210.709965) (xy 69.676413 -210.691958) (xy 69.731256 -210.681828)
			(xy 69.78699 -210.679791) (xy 69.842427 -210.685891) (xy 69.896384 -210.699997) (xy 69.947713 -210.721809)
			(xy 69.995319 -210.750863) (xy 70.038187 -210.786538) (xy 70.075404 -210.828075) (xy 70.106177 -210.874588)
			(xy 70.129849 -210.925085) (xy 70.145917 -210.978492) (xy 70.154037 -211.033668) (xy 70.154546 -211.061554)
			(xy 70.154037 -211.08944) (xy 70.145917 -211.144616) (xy 70.129849 -211.198023) (xy 70.106177 -211.24852)
			(xy 70.075404 -211.295033) (xy 70.038187 -211.33657) (xy 69.995319 -211.372245) (xy 69.947713 -211.401299)
			(xy 69.896384 -211.423111) (xy 69.842427 -211.437217) (xy 69.78699 -211.443317) (xy 69.731256 -211.44128)
			(xy 69.676413 -211.43115) (xy 69.623629 -211.413143) (xy 69.574029 -211.387642) (xy 69.528671 -211.355191)
			(xy 69.488522 -211.316482) (xy 69.454436 -211.272339) (xy 69.42714 -211.223704) (xy 69.407217 -211.171613)
			(xy 69.395091 -211.117176) (xy 69.39102 -211.061554) (xy 64.466685 -211.061554) (xy 64.466978 -211.078572)
			(xy 64.466492 -211.105823) (xy 64.458736 -211.159771) (xy 64.443381 -211.212066) (xy 64.420739 -211.261643)
			(xy 64.391273 -211.307493) (xy 64.355582 -211.348684) (xy 64.314391 -211.384375) (xy 64.268541 -211.413841)
			(xy 64.218964 -211.436483) (xy 64.166669 -211.451838) (xy 64.112721 -211.459594) (xy 64.058219 -211.459594)
			(xy 64.004271 -211.451838) (xy 63.951976 -211.436483) (xy 63.902399 -211.413841) (xy 63.856549 -211.384375)
			(xy 63.815358 -211.348684) (xy 63.779667 -211.307493) (xy 63.750201 -211.261643) (xy 63.727559 -211.212066)
			(xy 63.712204 -211.159771) (xy 63.704448 -211.105823) (xy 63.703962 -211.078572) (xy 63.704464 -211.050934)
			(xy 63.712455 -210.996239) (xy 63.728251 -210.943268) (xy 63.751521 -210.89313) (xy 63.78178 -210.846872)
			(xy 63.79972 -210.825842) (xy 63.805908 -210.818265) (xy 63.812495 -210.799859) (xy 63.811715 -210.780325)
			(xy 63.808102 -210.771232) (xy 63.770002 -210.686904) (xy 63.765647 -210.678171) (xy 63.751614 -210.664632)
			(xy 63.733525 -210.657354) (xy 63.723774 -210.656932) (xy 62.989968 -210.656932) (xy 62.957087 -210.656467)
			(xy 62.89174 -210.649106) (xy 62.827628 -210.63447) (xy 62.765561 -210.612743) (xy 62.706318 -210.584198)
			(xy 62.650647 -210.549194) (xy 62.599248 -210.508174) (xy 62.575694 -210.485228) (xy 61.383672 -209.293206)
			(xy 61.360749 -209.269633) (xy 61.319754 -209.218222) (xy 61.284767 -209.162547) (xy 61.256228 -209.103308)
			(xy 61.234494 -209.041249) (xy 61.219839 -208.977148) (xy 61.212446 -208.911809) (xy 61.211968 -208.878932)
			(xy 61.211968 -207.371442) (xy 61.190632 -207.34401) (xy 61.173614 -207.339692) (xy 61.146443 -207.332392)
			(xy 61.094431 -207.310947) (xy 61.046134 -207.282093) (xy 61.002602 -207.246455) (xy 60.964778 -207.204808)
			(xy 60.933484 -207.158055) (xy 60.909398 -207.107212) (xy 60.893045 -207.053382) (xy 60.884778 -206.997733)
			(xy 60.884778 -206.941474) (xy 60.893043 -206.885825) (xy 60.909396 -206.831994) (xy 60.93348 -206.781151)
			(xy 60.964774 -206.734397) (xy 61.002597 -206.69275) (xy 61.046129 -206.657111) (xy 61.094425 -206.628256)
			(xy 61.146436 -206.60681) (xy 61.173614 -206.599536) (xy 61.190632 -206.595218) (xy 61.211968 -206.567786)
			(xy 61.211968 -190.855092) (xy 61.19495 -190.829692) (xy 61.180726 -190.82385) (xy 61.171294 -190.82041)
			(xy 61.151231 -190.820465) (xy 61.13272 -190.828203) (xy 61.125354 -190.835026) (xy 60.267342 -191.693038)
			(xy 60.263231 -191.697435) (xy 60.256942 -191.707697) (xy 60.254896 -191.713358) (xy 60.254896 -191.713866)
			(xy 60.246402 -191.739393) (xy 60.223335 -191.787995) (xy 60.19367 -191.832874) (xy 60.157995 -191.87314)
			(xy 60.117017 -191.907997) (xy 60.071549 -191.936751) (xy 60.022493 -191.958833) (xy 59.970821 -191.973806)
			(xy 59.917559 -191.981371) (xy 59.89066 -191.981836) (xy 59.863409 -191.981359) (xy 59.809462 -191.973598)
			(xy 59.757169 -191.958239) (xy 59.707594 -191.935596) (xy 59.661745 -191.906128) (xy 59.620556 -191.870436)
			(xy 59.584865 -191.829245) (xy 59.555399 -191.783396) (xy 59.532756 -191.733819) (xy 59.517399 -191.681526)
			(xy 59.50964 -191.627579) (xy 59.509152 -191.600328) (xy 59.509621 -191.573418) (xy 59.517207 -191.520136)
			(xy 59.532202 -191.468447) (xy 59.55431 -191.419378) (xy 59.583093 -191.373901) (xy 59.61798 -191.332919)
			(xy 59.658277 -191.297245) (xy 59.703188 -191.267585) (xy 59.751819 -191.24453) (xy 59.777376 -191.236092)
			(xy 59.77763 -191.236092) (xy 59.783319 -191.234101) (xy 59.793596 -191.227812) (xy 59.79795 -191.223646)
			(xy 60.971938 -190.049912) (xy 60.978771 -190.042506) (xy 60.986494 -190.023911) (xy 60.986924 -190.013844)
			(xy 60.986924 -186.214512) (xy 60.986512 -186.204441) (xy 60.978784 -186.185842) (xy 60.971938 -186.178444)
			(xy 53.918104 -179.124864) (xy 53.900087 -179.106079) (xy 53.869505 -179.063966) (xy 53.845874 -179.017593)
			(xy 53.829776 -178.968099) (xy 53.821605 -178.916699) (xy 53.821076 -178.890676) (xy 53.821076 -168.973754)
			(xy 53.804058 -168.9481) (xy 53.78958 -168.942258) (xy 53.78018 -168.938943) (xy 53.760273 -168.938933)
			(xy 53.741865 -168.94651) (xy 53.734462 -168.95318) (xy 52.685696 -170.001946) (xy 52.681577 -170.006337)
			(xy 52.675294 -170.016603) (xy 52.67325 -170.022266) (xy 52.67325 -170.022774) (xy 52.664801 -170.048317)
			(xy 52.64173 -170.096921) (xy 52.612059 -170.141801) (xy 52.576378 -170.182068) (xy 52.535395 -170.216923)
			(xy 52.489921 -170.245675) (xy 52.440859 -170.267754) (xy 52.389182 -170.282722) (xy 52.335915 -170.290282)
			(xy 52.309014 -170.290744) (xy 52.281765 -170.290209) (xy 52.227821 -170.282455) (xy 52.175529 -170.267104)
			(xy 52.125954 -170.244467) (xy 52.080106 -170.215005) (xy 52.038916 -170.179319) (xy 52.003225 -170.138134)
			(xy 51.973757 -170.092289) (xy 51.951114 -170.042718) (xy 51.935755 -169.990428) (xy 51.927995 -169.936485)
			(xy 51.927506 -169.909236) (xy 51.927945 -169.882325) (xy 51.93553 -169.829039) (xy 51.950527 -169.777348)
			(xy 51.972638 -169.728276) (xy 52.001425 -169.682798) (xy 52.036315 -169.641816) (xy 52.076618 -169.606143)
			(xy 52.121534 -169.576487) (xy 52.17017 -169.553435) (xy 52.19573 -169.545) (xy 52.195984 -169.545)
			(xy 52.201678 -169.543022) (xy 52.211952 -169.536724) (xy 52.216304 -169.532554) (xy 53.39715 -168.351708)
			(xy 53.403972 -168.344293) (xy 53.411704 -168.325706) (xy 53.412136 -168.31564) (xy 53.412136 -158.225998)
			(xy 53.411766 -158.215973) (xy 53.404145 -158.197433) (xy 53.389991 -158.183238) (xy 53.380894 -158.179008)
			(xy 53.279802 -158.137098) (xy 53.249576 -158.143194) (xy 53.238908 -158.153862) (xy 53.21732 -158.174674)
			(xy 53.168816 -158.209928) (xy 53.115392 -158.237157) (xy 53.058366 -158.255689) (xy 52.999141 -158.265067)
			(xy 52.96916 -158.265622) (xy 52.941912 -158.265105) (xy 52.88797 -158.257344) (xy 52.835682 -158.241986)
			(xy 52.786112 -158.219344) (xy 52.740268 -158.189877) (xy 52.699084 -158.154187) (xy 52.663399 -158.113)
			(xy 52.633937 -158.067153) (xy 52.6113 -158.01758) (xy 52.595947 -157.965291) (xy 52.588192 -157.911348)
			(xy 52.588192 -157.856852) (xy 52.595947 -157.802909) (xy 52.6113 -157.75062) (xy 52.633937 -157.701047)
			(xy 52.663399 -157.6552) (xy 52.699084 -157.614013) (xy 52.740268 -157.578323) (xy 52.786112 -157.548856)
			(xy 52.835682 -157.526214) (xy 52.88797 -157.510856) (xy 52.941912 -157.503095) (xy 52.96916 -157.502606)
			(xy 52.999136 -157.503237) (xy 53.058348 -157.51262) (xy 53.115365 -157.531146) (xy 53.168785 -157.558359)
			(xy 53.217292 -157.59359) (xy 53.238908 -157.614366) (xy 53.249576 -157.625034) (xy 53.279802 -157.63113)
			(xy 53.380894 -157.58922) (xy 53.389913 -157.584884) (xy 53.403996 -157.570697) (xy 53.411635 -157.552224)
			(xy 53.412136 -157.54223) (xy 53.412136 -156.983938) (xy 53.411755 -156.975464) (xy 53.40619 -156.959454)
			(xy 53.395719 -156.946125) (xy 53.388768 -156.941266) (xy 53.316886 -156.895038) (xy 53.30583 -156.888746)
			(xy 53.280491 -156.886891) (xy 53.268626 -156.891482) (xy 53.268372 -156.891482) (xy 53.243376 -156.902356)
			(xy 53.191079 -156.917726) (xy 53.13713 -156.925517) (xy 53.109876 -156.926026) (xy 53.082627 -156.925502)
			(xy 53.028685 -156.917743) (xy 52.976395 -156.902387) (xy 52.926824 -156.879745) (xy 52.880978 -156.85028)
			(xy 52.839793 -156.81459) (xy 52.804106 -156.773402) (xy 52.774643 -156.727555) (xy 52.752005 -156.677982)
			(xy 52.736652 -156.625692) (xy 52.728896 -156.571749) (xy 52.728896 -156.517251) (xy 52.736652 -156.463308)
			(xy 52.752005 -156.411018) (xy 52.774643 -156.361445) (xy 52.804106 -156.315598) (xy 52.839793 -156.27441)
			(xy 52.880978 -156.23872) (xy 52.926824 -156.209255) (xy 52.976395 -156.186613) (xy 53.028685 -156.171257)
			(xy 53.082627 -156.163498) (xy 53.109876 -156.16301) (xy 53.137134 -156.163485) (xy 53.191094 -156.171248)
			(xy 53.243393 -156.186633) (xy 53.268372 -156.197554) (xy 53.268626 -156.197554) (xy 53.276444 -156.200734)
			(xy 53.293238 -156.202295) (xy 53.309624 -156.198297) (xy 53.316886 -156.193998) (xy 53.388768 -156.14777)
			(xy 53.395769 -156.142962) (xy 53.406283 -156.129632) (xy 53.411831 -156.113587) (xy 53.412136 -156.105098)
			(xy 53.412136 -155.40482) (xy 53.41148 -155.392275) (xy 53.399602 -155.370168) (xy 53.38953 -155.362656)
			(xy 53.308758 -155.308554) (xy 53.283358 -155.306014) (xy 53.271928 -155.31084) (xy 53.248719 -155.319985)
			(xy 53.200532 -155.332882) (xy 53.151074 -155.339388) (xy 53.126132 -155.339796) (xy 53.098877 -155.339359)
			(xy 53.044921 -155.331606) (xy 52.992617 -155.316252) (xy 52.943031 -155.293611) (xy 52.897173 -155.264143)
			(xy 52.855975 -155.228448) (xy 52.820277 -155.187253) (xy 52.790805 -155.141397) (xy 52.768159 -155.091813)
			(xy 52.752801 -155.039511) (xy 52.745043 -154.985555) (xy 52.745043 -154.931045) (xy 52.752801 -154.877089)
			(xy 52.768159 -154.824787) (xy 52.790805 -154.775203) (xy 52.820277 -154.729347) (xy 52.855975 -154.688152)
			(xy 52.897173 -154.652457) (xy 52.943031 -154.622989) (xy 52.992617 -154.600348) (xy 53.044921 -154.584994)
			(xy 53.098877 -154.577241) (xy 53.126132 -154.57678) (xy 53.151075 -154.577175) (xy 53.200534 -154.583681)
			(xy 53.248724 -154.596577) (xy 53.271928 -154.605736) (xy 53.283358 -154.610562) (xy 53.308758 -154.608022)
			(xy 53.38953 -154.55392) (xy 53.399603 -154.546407) (xy 53.411479 -154.524303) (xy 53.412136 -154.511756)
			(xy 53.412136 -151.588216) (xy 53.411691 -151.578071) (xy 53.403865 -151.559353) (xy 53.389394 -151.545134)
			(xy 53.380132 -151.540972) (xy 53.27777 -151.500332) (xy 53.24729 -151.50719) (xy 53.236622 -151.51862)
			(xy 53.218517 -151.537176) (xy 53.17819 -151.569757) (xy 53.13382 -151.596572) (xy 53.086227 -151.617129)
			(xy 53.036287 -151.631048) (xy 52.984922 -151.638072) (xy 52.959 -151.638508) (xy 52.931749 -151.638022)
			(xy 52.877801 -151.630266) (xy 52.825506 -151.614911) (xy 52.775929 -151.592269) (xy 52.730079 -151.562803)
			(xy 52.688888 -151.527112) (xy 52.653197 -151.485921) (xy 52.623731 -151.440071) (xy 52.601089 -151.390494)
			(xy 52.585734 -151.338199) (xy 52.577978 -151.284251) (xy 52.577978 -151.229749) (xy 52.585734 -151.175801)
			(xy 52.601089 -151.123506) (xy 52.623731 -151.073929) (xy 52.653197 -151.028079) (xy 52.688888 -150.986888)
			(xy 52.730079 -150.951197) (xy 52.775929 -150.921731) (xy 52.825506 -150.899089) (xy 52.877801 -150.883734)
			(xy 52.931749 -150.875978) (xy 52.959 -150.875492) (xy 52.98492 -150.875961) (xy 53.036281 -150.882991)
			(xy 53.086218 -150.896909) (xy 53.133812 -150.917457) (xy 53.178187 -150.944257) (xy 53.218526 -150.976818)
			(xy 53.236622 -150.99538) (xy 53.24729 -151.00681) (xy 53.27777 -151.013668) (xy 53.380132 -150.973028)
			(xy 53.389367 -150.968821) (xy 53.403826 -150.95461) (xy 53.411681 -150.93592) (xy 53.412136 -150.925784)
			(xy 53.412136 -148.454618) (xy 53.411718 -148.444548) (xy 53.403994 -148.425949) (xy 53.39715 -148.41855)
			(xy 52.121562 -147.142962) (xy 52.114174 -147.136107) (xy 52.095565 -147.128397) (xy 52.085494 -147.127976)
			(xy 51.120294 -147.127976) (xy 51.109118 -147.130516) (xy 51.103784 -147.13331) (xy 51.102768 -147.133818)
			(xy 51.075298 -147.14755) (xy 51.017048 -147.167001) (xy 50.956435 -147.176873) (xy 50.92573 -147.177506)
			(xy 50.898476 -147.177049) (xy 50.844521 -147.169295) (xy 50.792219 -147.153942) (xy 50.742635 -147.131301)
			(xy 50.696778 -147.101833) (xy 50.655582 -147.06614) (xy 50.619885 -147.024946) (xy 50.590414 -146.979091)
			(xy 50.567769 -146.929509) (xy 50.552411 -146.877208) (xy 50.544653 -146.823254) (xy 50.544653 -146.768746)
			(xy 50.552411 -146.714792) (xy 50.567769 -146.662491) (xy 50.590414 -146.612909) (xy 50.619885 -146.567054)
			(xy 50.655582 -146.52586) (xy 50.696778 -146.490167) (xy 50.742635 -146.460699) (xy 50.792219 -146.438058)
			(xy 50.844521 -146.422705) (xy 50.898476 -146.414951) (xy 50.92573 -146.41449) (xy 50.956533 -146.415095)
			(xy 51.017334 -146.425023) (xy 51.075748 -146.444598) (xy 51.103276 -146.458432) (xy 51.103784 -146.458686)
			(xy 51.109096 -146.461185) (xy 51.120521 -146.463873) (xy 51.12639 -146.46402) (xy 52.24399 -146.46402)
			(xy 52.274724 -146.465544) (xy 52.285307 -146.465963) (xy 52.305381 -146.459285) (xy 52.313586 -146.45259)
			(xy 52.369212 -146.402044) (xy 52.376891 -146.394543) (xy 52.385566 -146.374926) (xy 52.385976 -146.364198)
			(xy 52.385976 -143.985996) (xy 52.385559 -143.975926) (xy 52.377833 -143.957328) (xy 52.37099 -143.949928)
			(xy 51.896772 -143.47571) (xy 51.889375 -143.468867) (xy 51.870773 -143.461148) (xy 51.860704 -143.460724)
			(xy 50.74412 -143.460724) (xy 50.734051 -143.461153) (xy 50.715453 -143.468871) (xy 50.708052 -143.47571)
			(xy 49.51095 -144.673066) (xy 49.492145 -144.691152) (xy 49.449954 -144.72184) (xy 49.403479 -144.745545)
			(xy 49.353866 -144.761683) (xy 49.30234 -144.769858) (xy 49.276254 -144.770348) (xy 47.13097 -144.770348)
			(xy 47.104883 -144.769847) (xy 47.053351 -144.761688) (xy 47.003733 -144.74556) (xy 46.957251 -144.721863)
			(xy 46.915054 -144.691179) (xy 46.896274 -144.673066) (xy 41.982644 -139.759436) (xy 41.964603 -139.740673)
			(xy 41.934026 -139.698553) (xy 41.910402 -139.652175) (xy 41.894309 -139.602676) (xy 41.886143 -139.551272)
			(xy 41.885616 -139.525248) (xy 41.885616 -121.962926) (xy 41.885199 -121.952855) (xy 41.877475 -121.934256)
			(xy 41.87063 -121.926858) (xy 37.923216 -117.979444) (xy 37.915199 -117.972149) (xy 37.894937 -117.964511)
			(xy 37.8841 -117.964712) (xy 37.796978 -117.970046) (xy 37.777674 -117.980206) (xy 37.77107 -117.988842)
			(xy 37.752907 -118.011349) (xy 37.71088 -118.05108) (xy 37.663339 -118.084015) (xy 37.611372 -118.1094)
			(xy 37.55617 -118.126651) (xy 37.498997 -118.135375) (xy 37.47008 -118.135908) (xy 37.442828 -118.135441)
			(xy 37.38888 -118.127682) (xy 37.336585 -118.112324) (xy 37.287007 -118.08968) (xy 37.241157 -118.060212)
			(xy 37.199967 -118.024519) (xy 37.164276 -117.983327) (xy 37.13481 -117.937475) (xy 37.112169 -117.887896)
			(xy 37.096814 -117.835601) (xy 37.089058 -117.781652) (xy 37.088572 -117.7544) (xy 37.089063 -117.725482)
			(xy 37.097794 -117.668308) (xy 37.115055 -117.613107) (xy 37.140452 -117.561145) (xy 37.173402 -117.513612)
			(xy 37.213149 -117.471598) (xy 37.235638 -117.45341) (xy 37.244274 -117.446806) (xy 37.254434 -117.427502)
			(xy 37.259768 -117.34038) (xy 37.259972 -117.329542) (xy 37.252337 -117.309277) (xy 37.245036 -117.301264)
			(xy 36.832794 -116.889276) (xy 36.828398 -116.885164) (xy 36.818135 -116.878877) (xy 36.812474 -116.87683)
			(xy 36.811966 -116.87683) (xy 36.786424 -116.868375) (xy 36.73782 -116.845306) (xy 36.692938 -116.815638)
			(xy 36.652669 -116.779959) (xy 36.617813 -116.738976) (xy 36.58906 -116.693502) (xy 36.566981 -116.64444)
			(xy 36.552014 -116.592762) (xy 36.544456 -116.539495) (xy 36.543996 -116.512594) (xy 33.708953 -116.512594)
			(xy 33.707063 -116.517023) (xy 33.666353 -116.595099) (xy 33.618915 -116.66928) (xy 33.565117 -116.738986)
			(xy 33.53562 -116.771674) (xy 33.529829 -116.778556) (xy 33.523081 -116.795215) (xy 33.522412 -116.804186)
			(xy 33.520124 -116.847994) (xy 33.508818 -116.934994) (xy 33.489922 -117.020665) (xy 33.463582 -117.104349)
			(xy 33.447228 -117.145054) (xy 33.275524 -117.56009) (xy 33.273724 -117.564776) (xy 33.271803 -117.574629)
			(xy 33.271714 -117.579648) (xy 33.271714 -118.281196) (xy 33.272137 -118.291266) (xy 33.279852 -118.30987)
			(xy 33.2867 -118.317264) (xy 33.549082 -118.579646) (xy 33.556482 -118.586486) (xy 33.575081 -118.594199)
			(xy 33.58515 -118.594632) (xy 33.653476 -118.594632) (xy 33.672018 -118.602252) (xy 33.67405 -118.604284)
			(xy 33.705292 -118.591584) (xy 33.750137 -118.573924) (xy 33.842494 -118.546344) (xy 33.937083 -118.527807)
			(xy 34.033018 -118.518485) (xy 34.081212 -118.517924) (xy 34.401252 -118.517924) (xy 34.410969 -118.517432)
			(xy 34.428976 -118.510104) (xy 34.436304 -118.5037) (xy 34.467172 -118.474782) (xy 34.533022 -118.421685)
			(xy 34.603132 -118.374354) (xy 34.676997 -118.333129) (xy 34.754087 -118.298306) (xy 34.833849 -118.270135)
			(xy 34.91571 -118.248819) (xy 34.999081 -118.234509) (xy 35.083365 -118.22731) (xy 35.12566 -118.22684)
			(xy 35.172324 -118.227391) (xy 35.265243 -118.236125) (xy 35.35694 -118.253504) (xy 35.446612 -118.279373)
			(xy 35.533474 -118.313507) (xy 35.616767 -118.355608) (xy 35.695763 -118.405307) (xy 35.769769 -118.462169)
			(xy 35.838139 -118.525697) (xy 35.900275 -118.595335) (xy 35.955632 -118.670473) (xy 35.980116 -118.710202)
			(xy 35.982711 -118.714182) (xy 35.989101 -118.72121) (xy 35.992816 -118.724172) (xy 36.015484 -118.742356)
			(xy 36.055568 -118.784426) (xy 36.088807 -118.832091) (xy 36.11443 -118.884246) (xy 36.131845 -118.939684)
			(xy 36.140648 -118.997123) (xy 36.141152 -119.026178) (xy 36.141152 -119.02694) (xy 36.140652 -119.056306)
			(xy 36.131724 -119.114353) (xy 36.123372 -119.14251) (xy 36.122023 -119.147017) (xy 36.120874 -119.156352)
			(xy 36.121086 -119.161052) (xy 36.121972 -119.176848) (xy 36.122862 -119.208477) (xy 36.122864 -119.224298)
			(xy 36.122429 -119.266665) (xy 36.115242 -119.351095) (xy 36.100911 -119.434609) (xy 36.079541 -119.516605)
			(xy 36.051284 -119.596489) (xy 36.034218 -119.63527) (xy 36.03025 -119.645312) (xy 36.030249 -119.666885)
			(xy 36.034218 -119.676926) (xy 36.051261 -119.715715) (xy 36.079497 -119.795604) (xy 36.10086 -119.877598)
			(xy 36.115196 -119.961108) (xy 36.122403 -120.045532) (xy 36.122864 -120.087898) (xy 36.122857 -120.103719)
			(xy 36.121968 -120.135348) (xy 36.121086 -120.151144) (xy 36.12092 -120.155841) (xy 36.122077 -120.165167)
			(xy 36.123372 -120.169686) (xy 36.12958 -120.190373) (xy 36.137852 -120.232765) (xy 36.139882 -120.254268)
			(xy 36.140136 -120.257316) (xy 36.140898 -120.27154) (xy 36.141406 -120.280684) (xy 36.147756 -120.296686)
			(xy 36.15055 -120.299734) (xy 36.166552 -120.317768) (xy 36.16833 -120.319546) (xy 36.17087 -120.322086)
			(xy 36.17341 -120.324372) (xy 37.04336 -120.324372) (xy 37.053085 -120.323897) (xy 37.07112 -120.316598)
			(xy 37.078412 -120.310148) (xy 37.109279 -120.281229) (xy 37.175129 -120.22813) (xy 37.245238 -120.180798)
			(xy 37.319103 -120.139571) (xy 37.396193 -120.104747) (xy 37.475956 -120.076575) (xy 37.557817 -120.055258)
			(xy 37.641188 -120.040949) (xy 37.725473 -120.03375) (xy 37.767768 -120.033288) (xy 37.814432 -120.033839)
			(xy 37.907352 -120.042574) (xy 37.999049 -120.059952) (xy 38.088721 -120.085821) (xy 38.175585 -120.119955)
			(xy 38.258879 -120.162055) (xy 38.337876 -120.211752) (xy 38.411884 -120.268613) (xy 38.480256 -120.332139)
			(xy 38.542394 -120.401776) (xy 38.597754 -120.476913) (xy 38.622224 -120.51665) (xy 38.624822 -120.520627)
			(xy 38.631217 -120.52765) (xy 38.634924 -120.53062) (xy 38.657589 -120.548805) (xy 38.697667 -120.590877)
			(xy 38.730899 -120.638543) (xy 38.756515 -120.690698) (xy 38.773923 -120.746136) (xy 38.782719 -120.803573)
			(xy 38.78326 -120.832626) (xy 38.78326 -120.833388) (xy 38.782757 -120.862753) (xy 38.77382 -120.920797)
			(xy 38.76548 -120.948958) (xy 38.764126 -120.953464) (xy 38.762967 -120.962801) (xy 38.763194 -120.9675)
			(xy 38.764079 -120.983296) (xy 38.764968 -121.014925) (xy 38.764972 -121.030746) (xy 38.764535 -121.073113)
			(xy 38.757344 -121.157541) (xy 38.74301 -121.241054) (xy 38.721636 -121.323048) (xy 38.693376 -121.40293)
			(xy 38.676326 -121.441718) (xy 38.672368 -121.451759) (xy 38.672385 -121.473324) (xy 38.676326 -121.483374)
			(xy 38.693367 -121.522163) (xy 38.721599 -121.602053) (xy 38.742958 -121.684047) (xy 38.75729 -121.767557)
			(xy 38.764493 -121.851981) (xy 38.764972 -121.894346) (xy 38.764966 -121.910167) (xy 38.764078 -121.941796)
			(xy 38.763194 -121.957592) (xy 38.762432 -121.967498) (xy 38.762686 -121.968514) (xy 38.764972 -121.975118)
			(xy 38.772846 -121.999248) (xy 38.773862 -122.00509) (xy 38.774116 -122.00636) (xy 38.777418 -122.024902)
			(xy 38.78072 -122.047) (xy 38.78199 -122.059446) (xy 38.783514 -122.091958) (xy 38.782967 -122.121027)
			(xy 38.774153 -122.178494) (xy 38.756738 -122.233963) (xy 38.731122 -122.286155) (xy 38.697898 -122.333865)
			(xy 38.657832 -122.375994) (xy 38.635178 -122.394218) (xy 38.631434 -122.397148) (xy 38.62504 -122.404183)
			(xy 38.622478 -122.408188) (xy 38.597965 -122.447918) (xy 38.542604 -122.523095) (xy 38.48046 -122.592769)
			(xy 38.412077 -122.656331) (xy 38.338053 -122.713224) (xy 38.259037 -122.76295) (xy 38.175719 -122.805074)
			(xy 38.088829 -122.839229) (xy 37.999128 -122.865113) (xy 37.9074 -122.882502) (xy 37.814449 -122.891242)
			(xy 37.767768 -122.891804) (xy 37.725458 -122.891355) (xy 37.641142 -122.884182) (xy 37.557738 -122.86989)
			(xy 37.475844 -122.848583) (xy 37.39605 -122.820413) (xy 37.318931 -122.785583) (xy 37.24504 -122.744343)
			(xy 37.174909 -122.696991) (xy 37.109042 -122.643867) (xy 37.078158 -122.614944) (xy 37.070792 -122.607832)
			(xy 37.053012 -122.60072) (xy 37.023294 -122.60072) (xy 37.013642 -122.605038) (xy 36.978712 -122.620056)
			(xy 36.907006 -122.645357) (xy 36.870386 -122.655584) (xy 36.868354 -122.656092) (xy 36.820063 -122.670739)
			(xy 36.721256 -122.691276) (xy 36.620871 -122.70164) (xy 36.570412 -122.70232) (xy 36.21278 -122.70232)
			(xy 36.203353 -122.703218) (xy 36.186127 -122.711049) (xy 36.179252 -122.71756) (xy 36.137088 -122.760486)
			(xy 36.130268 -122.768097) (xy 36.122792 -122.787098) (xy 36.12261 -122.797316) (xy 36.122864 -122.82424)
			(xy 36.122427 -122.866607) (xy 36.115237 -122.951035) (xy 36.100903 -123.034548) (xy 36.079529 -123.116542)
			(xy 36.051269 -123.196425) (xy 36.034218 -123.235212) (xy 36.030259 -123.245253) (xy 36.030274 -123.266819)
			(xy 36.034218 -123.276868) (xy 36.05126 -123.315657) (xy 36.079492 -123.395546) (xy 36.100851 -123.477541)
			(xy 36.115184 -123.561051) (xy 36.122388 -123.645475) (xy 36.122864 -123.68784) (xy 36.122858 -123.703661)
			(xy 36.12197 -123.73529) (xy 36.121086 -123.751086) (xy 36.120914 -123.755784) (xy 36.122062 -123.765113)
			(xy 36.123372 -123.769628) (xy 36.131711 -123.797788) (xy 36.140638 -123.855834) (xy 36.141152 -123.885198)
			(xy 36.141152 -123.88977) (xy 36.140676 -123.910075) (xy 36.135962 -123.950418) (xy 36.131754 -123.970288)
			(xy 36.13023 -123.9774) (xy 36.130992 -123.99137) (xy 36.133532 -123.998482) (xy 36.136105 -124.005125)
			(xy 36.144365 -124.016722) (xy 36.149788 -124.021342) (xy 36.171632 -124.038614) (xy 36.17214 -124.038614)
			(xy 36.176204 -124.041916) (xy 36.186618 -124.047504) (xy 36.19246 -124.048774) (xy 36.198243 -124.049964)
			(xy 36.210045 -124.049964) (xy 36.215828 -124.048774) (xy 36.228782 -124.045726) (xy 36.234116 -124.042932)
			(xy 36.270328 -124.02515) (xy 36.345108 -123.994866) (xy 36.42211 -123.970781) (xy 36.500818 -123.953055)
			(xy 36.58071 -123.941805) (xy 36.620958 -123.939046) (xy 36.626546 -123.938284) (xy 36.667706 -123.931825)
			(xy 36.750746 -123.924961) (xy 36.792408 -123.924568) (xy 37.053012 -123.924568) (xy 37.070792 -123.917456)
			(xy 37.078158 -123.910344) (xy 37.109031 -123.881408) (xy 37.174896 -123.82828) (xy 37.245027 -123.780926)
			(xy 37.318919 -123.739685) (xy 37.396041 -123.704856) (xy 37.475836 -123.676687) (xy 37.557733 -123.655384)
			(xy 37.641139 -123.641097) (xy 37.725457 -123.633931) (xy 37.767768 -123.633484) (xy 37.814432 -123.634035)
			(xy 37.90735 -123.642771) (xy 37.999045 -123.66015) (xy 38.088715 -123.686021) (xy 38.175576 -123.720156)
			(xy 38.258867 -123.762259) (xy 38.337861 -123.811959) (xy 38.411865 -123.868823) (xy 38.480232 -123.932352)
			(xy 38.542364 -124.001991) (xy 38.597718 -124.077131) (xy 38.622224 -124.116846) (xy 38.624822 -124.120823)
			(xy 38.631216 -124.127846) (xy 38.634924 -124.130816) (xy 38.657589 -124.149001) (xy 38.697668 -124.191073)
			(xy 38.7309 -124.238738) (xy 38.756517 -124.290894) (xy 38.773925 -124.346331) (xy 38.782722 -124.403768)
			(xy 38.78326 -124.432822) (xy 38.78326 -124.433584) (xy 38.782757 -124.462949) (xy 38.77382 -124.520994)
			(xy 38.76548 -124.549154) (xy 38.764126 -124.55366) (xy 38.762966 -124.562997) (xy 38.763194 -124.567696)
			(xy 38.764079 -124.583492) (xy 38.764968 -124.615121) (xy 38.764972 -124.630942) (xy 38.764535 -124.673309)
			(xy 38.757345 -124.757737) (xy 38.743011 -124.84125) (xy 38.721637 -124.923244) (xy 38.693377 -125.003127)
			(xy 38.676326 -125.041914) (xy 38.672367 -125.051955) (xy 38.672383 -125.073521) (xy 38.676326 -125.08357)
			(xy 38.693368 -125.122359) (xy 38.721599 -125.202248) (xy 38.742959 -125.284243) (xy 38.757291 -125.367753)
			(xy 38.764495 -125.452177) (xy 38.764972 -125.494542) (xy 38.764966 -125.510363) (xy 38.764078 -125.541992)
			(xy 38.763194 -125.557788) (xy 38.762432 -125.567694) (xy 38.762686 -125.56871) (xy 38.764972 -125.575314)
			(xy 38.772846 -125.599444) (xy 38.773862 -125.605286) (xy 38.774116 -125.606556) (xy 38.777418 -125.625098)
			(xy 38.78072 -125.647196) (xy 38.78199 -125.659642) (xy 38.783514 -125.692154) (xy 38.782967 -125.721223)
			(xy 38.774154 -125.778691) (xy 38.756739 -125.83416) (xy 38.731124 -125.886352) (xy 38.6979 -125.934063)
			(xy 38.657834 -125.976192) (xy 38.635178 -125.994414) (xy 38.631434 -125.997344) (xy 38.625039 -126.004378)
			(xy 38.622478 -126.008384) (xy 38.597965 -126.048115) (xy 38.542605 -126.123291) (xy 38.480461 -126.192966)
			(xy 38.412078 -126.256527) (xy 38.338054 -126.313421) (xy 38.259037 -126.363147) (xy 38.175719 -126.405272)
			(xy 38.088829 -126.439426) (xy 37.999128 -126.465311) (xy 37.9074 -126.4827) (xy 37.814449 -126.49144)
			(xy 37.767768 -126.492) (xy 37.723538 -126.491524) (xy 37.635425 -126.48369) (xy 37.548353 -126.468077)
			(xy 37.463008 -126.444808) (xy 37.38006 -126.414067) (xy 37.300164 -126.376095) (xy 37.2618 -126.354078)
			(xy 37.2618 -126.353824) (xy 37.253926 -126.349252) (xy 37.245109 -126.344551) (xy 37.225335 -126.341793)
			(xy 37.215572 -126.343918) (xy 37.207444 -126.34595) (xy 37.183314 -126.387098) (xy 37.179758 -126.390654)
			(xy 36.867084 -126.703328) (xy 36.85159 -126.718568) (xy 36.851082 -126.719076) (xy 36.757864 -126.812294)
			(xy 36.741366 -126.828611) (xy 36.707062 -126.859866) (xy 36.689284 -126.874778) (xy 36.683696 -126.87935)
			(xy 36.288472 -127.470662) (xy 36.286694 -127.48133) (xy 36.27911 -127.522011) (xy 36.258069 -127.60205)
			(xy 36.230472 -127.680071) (xy 36.196508 -127.755539) (xy 36.15641 -127.827935) (xy 36.133786 -127.862584)
			(xy 35.893756 -128.22174) (xy 35.871264 -128.254692) (xy 35.82177 -128.317275) (xy 35.767428 -128.375698)
			(xy 35.708585 -128.429585) (xy 35.677348 -128.454404) (xy 35.671103 -128.459603) (xy 35.662041 -128.473079)
			(xy 35.659568 -128.48082) (xy 35.648552 -128.51926) (xy 35.621183 -128.594401) (xy 35.587889 -128.667112)
			(xy 35.548885 -128.736926) (xy 35.52698 -128.77038) (xy 35.286696 -129.12979) (xy 35.260992 -129.167327)
			(xy 35.203749 -129.238048) (xy 35.172396 -129.271014) (xy 35.166012 -129.278062) (xy 35.158566 -129.295546)
			(xy 35.15805 -129.314542) (xy 35.160966 -129.323592) (xy 35.191954 -129.409698) (xy 35.195538 -129.418468)
			(xy 35.207991 -129.432729) (xy 35.224755 -129.441527) (xy 35.234118 -129.442972) (xy 35.279681 -129.448479)
			(xy 35.369616 -129.466798) (xy 35.457488 -129.493306) (xy 35.54255 -129.52778) (xy 35.624083 -129.569928)
			(xy 35.701396 -129.619392) (xy 35.773834 -129.675755) (xy 35.840785 -129.738537) (xy 35.901681 -129.807208)
			(xy 35.956006 -129.881187) (xy 35.980116 -129.920238) (xy 35.982713 -129.924216) (xy 35.989106 -129.931241)
			(xy 35.992816 -129.934208) (xy 36.015482 -129.952392) (xy 36.055563 -129.994464) (xy 36.088797 -130.042129)
			(xy 36.114415 -130.094284) (xy 36.131825 -130.149723) (xy 36.140623 -130.20716) (xy 36.141152 -130.236214)
			(xy 36.141152 -130.236976) (xy 36.14065 -130.266341) (xy 36.131716 -130.324387) (xy 36.123372 -130.352546)
			(xy 36.122027 -130.357053) (xy 36.120884 -130.366388) (xy 36.121086 -130.371088) (xy 36.121971 -130.386884)
			(xy 36.122861 -130.418513) (xy 36.122864 -130.434334) (xy 36.122428 -130.476701) (xy 36.115238 -130.56113)
			(xy 36.100904 -130.644643) (xy 36.079531 -130.726637) (xy 36.051271 -130.80652) (xy 36.034218 -130.845306)
			(xy 36.030257 -130.855347) (xy 36.03027 -130.876914) (xy 36.034218 -130.886962) (xy 36.05126 -130.925751)
			(xy 36.079493 -131.00564) (xy 36.100853 -131.087635) (xy 36.115186 -131.171144) (xy 36.12239 -131.255569)
			(xy 36.122864 -131.297934) (xy 36.122858 -131.313755) (xy 36.121971 -131.345384) (xy 36.121086 -131.36118)
			(xy 36.120873 -131.365804) (xy 36.121898 -131.375003) (xy 36.123118 -131.379468) (xy 36.129214 -131.400804)
			(xy 36.129214 -131.401312) (xy 36.134233 -131.421863) (xy 36.140212 -131.463744) (xy 36.141152 -131.484878)
			(xy 36.141857 -131.494712) (xy 36.149742 -131.512763) (xy 36.163852 -131.526507) (xy 36.182103 -131.533917)
			(xy 36.191952 -131.534408) (xy 37.04336 -131.534408) (xy 37.053084 -131.533931) (xy 37.071112 -131.526625)
			(xy 37.078412 -131.520184) (xy 37.10928 -131.491267) (xy 37.175131 -131.438171) (xy 37.245241 -131.390842)
			(xy 37.319106 -131.349618) (xy 37.396197 -131.314796) (xy 37.475958 -131.286626) (xy 37.557819 -131.26531)
			(xy 37.64119 -131.251002) (xy 37.725473 -131.243804) (xy 37.767768 -131.243324) (xy 37.814432 -131.243875)
			(xy 37.907351 -131.25261) (xy 37.999047 -131.269989) (xy 38.088719 -131.295859) (xy 38.175581 -131.329993)
			(xy 38.258875 -131.372094) (xy 38.33787 -131.421792) (xy 38.411877 -131.478654) (xy 38.480247 -131.542182)
			(xy 38.542383 -131.611819) (xy 38.597741 -131.686957) (xy 38.622224 -131.726686) (xy 38.624818 -131.730666)
			(xy 38.631208 -131.737696) (xy 38.634924 -131.740656) (xy 38.657587 -131.758841) (xy 38.697661 -131.800915)
			(xy 38.730889 -131.848581) (xy 38.7565 -131.900737) (xy 38.773903 -131.956174) (xy 38.782693 -132.01361)
			(xy 38.78326 -132.042662) (xy 38.78326 -132.043424) (xy 38.782761 -132.07279) (xy 38.773834 -132.130837)
			(xy 38.76548 -132.158994) (xy 38.76413 -132.163501) (xy 38.762977 -132.172837) (xy 38.763194 -132.177536)
			(xy 38.764079 -132.193332) (xy 38.764966 -132.224961) (xy 38.764972 -132.240782) (xy 38.764538 -132.28315)
			(xy 38.757352 -132.367579) (xy 38.743023 -132.451094) (xy 38.721653 -132.53309) (xy 38.693398 -132.612976)
			(xy 38.676326 -132.651754) (xy 38.672354 -132.661796) (xy 38.672347 -132.683372) (xy 38.676326 -132.69341)
			(xy 38.69337 -132.732199) (xy 38.721607 -132.812087) (xy 38.742971 -132.894082) (xy 38.757308 -132.977592)
			(xy 38.764517 -133.062016) (xy 38.764972 -133.104382) (xy 38.764968 -133.120266) (xy 38.764078 -133.152022)
			(xy 38.763194 -133.167882) (xy 38.762432 -133.17728) (xy 38.772846 -133.209538) (xy 38.774116 -133.216396)
			(xy 38.774116 -133.216904) (xy 38.77564 -133.224524) (xy 38.77564 -133.224778) (xy 38.776656 -133.230366)
			(xy 38.78072 -133.257544) (xy 38.78072 -133.258052) (xy 38.780974 -133.260592) (xy 38.782498 -133.27888)
			(xy 38.782498 -133.279896) (xy 38.783514 -133.301994) (xy 38.783514 -133.302248) (xy 38.782973 -133.3313)
			(xy 38.774168 -133.388732) (xy 38.756754 -133.444165) (xy 38.731134 -133.496315) (xy 38.6979 -133.543976)
			(xy 38.657822 -133.586045) (xy 38.635178 -133.604254) (xy 38.631436 -133.607186) (xy 38.625046 -133.614223)
			(xy 38.622478 -133.618224) (xy 38.597967 -133.657957) (xy 38.542609 -133.733137) (xy 38.480466 -133.802816)
			(xy 38.412084 -133.866381) (xy 38.338061 -133.923278) (xy 38.259044 -133.973008) (xy 38.175726 -134.015135)
			(xy 38.088835 -134.049292) (xy 37.999132 -134.075178) (xy 37.907403 -134.092568) (xy 37.81445 -134.101309)
			(xy 37.767768 -134.10184) (xy 37.725458 -134.101391) (xy 37.641142 -134.094218) (xy 37.557737 -134.079927)
			(xy 37.475843 -134.05862) (xy 37.396048 -134.030451) (xy 37.318928 -133.995622) (xy 37.245036 -133.954383)
			(xy 37.174904 -133.907032) (xy 37.109036 -133.853909) (xy 37.078158 -133.82498) (xy 37.070792 -133.817868)
			(xy 37.053012 -133.810756) (xy 36.922456 -133.810756) (xy 36.916446 -133.810922) (xy 36.904762 -133.813743)
			(xy 36.899342 -133.816344) (xy 36.859424 -133.836137) (xy 36.776741 -133.869357) (xy 36.691424 -133.895068)
			(xy 36.604154 -133.913063) (xy 36.515625 -133.9232) (xy 36.471098 -133.924802) (xy 36.461954 -133.925056)
			(xy 36.30168 -133.99135) (xy 36.268825 -134.004631) (xy 36.201577 -134.027004) (xy 36.167314 -134.036054)
			(xy 36.16706 -134.036054) (xy 36.159586 -134.038262) (xy 36.146391 -134.04654) (xy 36.141152 -134.05231)
			(xy 36.13277 -134.06247) (xy 36.127947 -134.068846) (xy 36.122125 -134.083724) (xy 36.12134 -134.09168)
			(xy 36.118161 -134.137355) (xy 36.104485 -134.227893) (xy 36.082577 -134.316798) (xy 36.052619 -134.403323)
			(xy 36.034218 -134.445248) (xy 36.030245 -134.45529) (xy 36.030236 -134.476867) (xy 36.034218 -134.486904)
			(xy 36.051262 -134.525693) (xy 36.0795 -134.605581) (xy 36.100864 -134.687575) (xy 36.115203 -134.771085)
			(xy 36.122412 -134.85551) (xy 36.122864 -134.897876) (xy 36.122861 -134.91376) (xy 36.12197 -134.945516)
			(xy 36.121086 -134.961376) (xy 36.120324 -134.970774) (xy 36.130738 -135.003032) (xy 36.132008 -135.00989)
			(xy 36.132008 -135.010398) (xy 36.133532 -135.018018) (xy 36.133532 -135.018272) (xy 36.134548 -135.02386)
			(xy 36.138612 -135.051038) (xy 36.138612 -135.051546) (xy 36.138866 -135.054086) (xy 36.138866 -135.054848)
			(xy 36.139374 -135.058658) (xy 36.139628 -135.059674) (xy 36.141152 -135.095488) (xy 36.141152 -135.096504)
			(xy 36.140941 -135.113362) (xy 36.137893 -135.146941) (xy 36.135056 -135.16356) (xy 36.135056 -135.163814)
			(xy 36.134548 -135.166862) (xy 36.134294 -135.168894) (xy 36.133278 -135.172196) (xy 36.130992 -135.184388)
			(xy 36.13531 -135.197342) (xy 36.138162 -135.204717) (xy 36.147598 -135.217395) (xy 36.153852 -135.222234)
			(xy 36.231322 -135.278114) (xy 36.233354 -135.27913) (xy 36.272372 -135.256016) (xy 36.353831 -135.216143)
			(xy 36.438574 -135.183832) (xy 36.525901 -135.159349) (xy 36.61509 -135.142897) (xy 36.705405 -135.134612)
			(xy 36.750752 -135.134096) (xy 37.04336 -135.134096) (xy 37.053058 -135.133665) (xy 37.071075 -135.126483)
			(xy 37.078412 -135.120126) (xy 37.109269 -135.091223) (xy 37.175097 -135.038154) (xy 37.245182 -134.990852)
			(xy 37.319022 -134.949654) (xy 37.396085 -134.914857) (xy 37.475818 -134.886712) (xy 37.557648 -134.86542)
			(xy 37.640987 -134.851135) (xy 37.725237 -134.843959) (xy 37.767514 -134.84352) (xy 37.767768 -134.84352)
			(xy 37.814466 -134.844068) (xy 37.907453 -134.852807) (xy 37.999215 -134.870201) (xy 38.088949 -134.896099)
			(xy 38.175869 -134.930273) (xy 38.259213 -134.972424) (xy 38.33825 -135.022183) (xy 38.412289 -135.079114)
			(xy 38.480681 -135.142717) (xy 38.542827 -135.212437) (xy 38.598182 -135.287662) (xy 38.622732 -135.32739)
			(xy 38.625248 -135.331371) (xy 38.631511 -135.338404) (xy 38.635178 -135.34136) (xy 38.657797 -135.359548)
			(xy 38.69779 -135.401608) (xy 38.730951 -135.449241) (xy 38.756515 -135.501346) (xy 38.773892 -135.556723)
			(xy 38.782681 -135.614093) (xy 38.78326 -135.643112) (xy 38.78326 -135.64362) (xy 38.783006 -135.657336)
			(xy 38.783006 -135.659368) (xy 38.782114 -135.675568) (xy 38.777916 -135.707743) (xy 38.774624 -135.72363)
			(xy 38.765226 -135.758936) (xy 38.763959 -135.763457) (xy 38.762936 -135.77279) (xy 38.763194 -135.777478)
			(xy 38.76408 -135.793274) (xy 38.764969 -135.824903) (xy 38.764972 -135.840724) (xy 38.764536 -135.883091)
			(xy 38.757347 -135.96752) (xy 38.743014 -136.051033) (xy 38.721642 -136.133028) (xy 38.693383 -136.212912)
			(xy 38.676326 -136.251696) (xy 38.672363 -136.261737) (xy 38.672372 -136.283306) (xy 38.676326 -136.293352)
			(xy 38.693368 -136.332141) (xy 38.721602 -136.41203) (xy 38.742962 -136.494025) (xy 38.757296 -136.577534)
			(xy 38.764501 -136.661959) (xy 38.764972 -136.704324) (xy 38.764965 -136.720145) (xy 38.764074 -136.751774)
			(xy 38.763194 -136.76757) (xy 38.763021 -136.772268) (xy 38.764166 -136.781598) (xy 38.76548 -136.786112)
			(xy 38.773804 -136.81421) (xy 38.782731 -136.872127) (xy 38.78326 -136.901428) (xy 38.78326 -136.90219)
			(xy 38.78269 -136.931187) (xy 38.773857 -136.988505) (xy 38.756454 -137.043827) (xy 38.730882 -137.09588)
			(xy 38.697728 -137.143464) (xy 38.657757 -137.185485) (xy 38.635178 -137.203688) (xy 38.631512 -137.206646)
			(xy 38.625243 -137.213673) (xy 38.622732 -137.217658) (xy 38.602501 -137.250646) (xy 38.557643 -137.313711)
			(xy 38.508032 -137.37311) (xy 38.481254 -137.401046) (xy 38.47467 -137.408426) (xy 38.467216 -137.426726)
			(xy 38.466776 -137.436606) (xy 38.467284 -137.508488) (xy 38.467801 -137.518388) (xy 38.475377 -137.536687)
			(xy 38.482016 -137.544048) (xy 38.539928 -137.60196) (xy 38.574132 -137.63697) (xy 38.636244 -137.712622)
			(xy 38.690642 -137.793998) (xy 38.736801 -137.880315) (xy 38.756082 -137.925302) (xy 39.212012 -139.02563)
			(xy 39.230273 -139.071239) (xy 39.258771 -139.165265) (xy 39.268908 -139.213336) (xy 39.305738 -139.397486)
			(xy 39.310056 -139.407646) (xy 39.313612 -139.412218) (xy 39.339687 -139.448074) (xy 39.386094 -139.523624)
			(xy 39.425619 -139.602992) (xy 39.457951 -139.685551) (xy 39.482835 -139.770652) (xy 39.49192 -139.814046)
			(xy 39.5859 -140.287756) (xy 39.594883 -140.335768) (xy 39.604554 -140.432971) (xy 39.605204 -140.481812)
			(xy 39.604901 -140.517497) (xy 39.599818 -140.588686) (xy 39.595044 -140.624052) (xy 39.594133 -140.632683)
			(xy 39.597519 -140.649692) (xy 39.601648 -140.657326) (xy 39.622954 -140.694069) (xy 39.659963 -140.770527)
			(xy 39.690344 -140.849851) (xy 39.713877 -140.931469) (xy 39.722552 -140.973048) (xy 39.818818 -141.45895)
			(xy 39.827729 -141.506905) (xy 39.837273 -141.60398) (xy 39.837868 -141.652752) (xy 39.837563 -141.688437)
			(xy 39.832478 -141.759626) (xy 39.827708 -141.794992) (xy 39.826787 -141.803625) (xy 39.830153 -141.820646)
			(xy 39.834312 -141.828266) (xy 39.855616 -141.865011) (xy 39.89262 -141.941469) (xy 39.922995 -142.020795)
			(xy 39.946524 -142.102413) (xy 39.955216 -142.143988) (xy 39.99865 -142.364714) (xy 40.016176 -142.38478)
			(xy 40.023034 -142.38732) (xy 40.047898 -142.396196) (xy 40.095103 -142.419834) (xy 40.138597 -142.449756)
			(xy 40.17755 -142.48539) (xy 40.211217 -142.526055) (xy 40.238955 -142.570973) (xy 40.260233 -142.619288)
			(xy 40.274646 -142.670076) (xy 40.281917 -142.722365) (xy 40.282368 -142.748762) (xy 40.281857 -142.777426)
			(xy 40.273296 -142.834111) (xy 40.256359 -142.88888) (xy 40.231428 -142.940503) (xy 40.199062 -142.98782)
			(xy 40.159988 -143.029769) (xy 40.137842 -143.047974) (xy 40.129431 -143.055354) (xy 40.119448 -143.07535)
			(xy 40.118921 -143.097694) (xy 40.122856 -143.108172) (xy 40.14402 -143.15819) (xy 40.176607 -143.261799)
			(xy 40.18788 -143.314928) (xy 40.284146 -143.80083) (xy 40.293057 -143.848785) (xy 40.302604 -143.94586)
			(xy 40.303196 -143.994632) (xy 40.302892 -144.030317) (xy 40.297808 -144.101506) (xy 40.293036 -144.136872)
			(xy 40.292129 -144.145502) (xy 40.295519 -144.162508) (xy 40.29964 -144.170146) (xy 40.320944 -144.20689)
			(xy 40.357949 -144.283349) (xy 40.388325 -144.362674) (xy 40.411854 -144.444293) (xy 40.420544 -144.485868)
			(xy 40.51681 -144.97177) (xy 40.52572 -145.019725) (xy 40.535263 -145.1168) (xy 40.53586 -145.165572)
			(xy 40.535555 -145.201257) (xy 40.530468 -145.272446) (xy 40.525974 -145.30578) (xy 43.138598 -145.30578)
			(xy 43.139069 -145.278446) (xy 43.146849 -145.224334) (xy 43.162276 -145.171887) (xy 43.185033 -145.12218)
			(xy 43.214654 -145.076232) (xy 43.250532 -145.034984) (xy 43.291932 -144.999282) (xy 43.338006 -144.969856)
			(xy 43.387809 -144.947311) (xy 43.413934 -144.939258) (xy 43.422799 -144.936263) (xy 43.437779 -144.925079)
			(xy 43.443144 -144.917414) (xy 43.484038 -144.852136) (xy 43.487594 -144.834356) (xy 43.48607 -144.825212)
			(xy 43.48607 -144.824704) (xy 43.483585 -144.809074) (xy 43.480916 -144.777537) (xy 43.480736 -144.761712)
			(xy 43.481167 -144.734457) (xy 43.488923 -144.680503) (xy 43.50428 -144.628202) (xy 43.526924 -144.578619)
			(xy 43.556395 -144.532764) (xy 43.592092 -144.49157) (xy 43.633289 -144.455876) (xy 43.679147 -144.426409)
			(xy 43.728732 -144.403769) (xy 43.781034 -144.388416) (xy 43.834989 -144.380664) (xy 43.862244 -144.380204)
			(xy 43.874215 -144.380314) (xy 43.898108 -144.381841) (xy 43.909996 -144.383252) (xy 43.91025 -144.383252)
			(xy 43.919424 -144.383939) (xy 43.937265 -144.37952) (xy 43.945048 -144.374616) (xy 44.001182 -144.3355)
			(xy 44.008599 -144.32993) (xy 44.019139 -144.314682) (xy 44.021756 -144.305782) (xy 44.021756 -144.305528)
			(xy 44.028689 -144.277959) (xy 44.049728 -144.225149) (xy 44.078374 -144.176046) (xy 44.113991 -144.13174)
			(xy 44.15579 -144.093212) (xy 44.202845 -144.061316) (xy 44.254114 -144.036758) (xy 44.308461 -144.020082)
			(xy 44.36468 -144.011659) (xy 44.393104 -144.011142) (xy 44.417775 -144.011568) (xy 44.466701 -144.017963)
			(xy 44.514395 -144.030607) (xy 44.537376 -144.03959) (xy 44.548486 -144.043465) (xy 44.571921 -144.041763)
			(xy 44.582334 -144.036288) (xy 44.652184 -143.994632) (xy 44.661971 -143.988174) (xy 44.674817 -143.968592)
			(xy 44.676822 -143.95704) (xy 44.676822 -143.956532) (xy 44.680475 -143.928969) (xy 44.694738 -143.875231)
			(xy 44.716654 -143.824133) (xy 44.745758 -143.77676) (xy 44.781433 -143.734115) (xy 44.822922 -143.697103)
			(xy 44.869346 -143.666509) (xy 44.919721 -143.64298) (xy 44.972979 -143.627016) (xy 45.02799 -143.618955)
			(xy 45.05579 -143.618458) (xy 45.083039 -143.618987) (xy 45.136984 -143.626742) (xy 45.189276 -143.642094)
			(xy 45.23885 -143.664731) (xy 45.284699 -143.694193) (xy 45.325889 -143.72988) (xy 45.36158 -143.771066)
			(xy 45.391048 -143.816911) (xy 45.413691 -143.866483) (xy 45.429049 -143.918773) (xy 45.436809 -143.972717)
			(xy 45.437298 -143.999966) (xy 45.436835 -144.026547) (xy 45.429452 -144.079195) (xy 45.414826 -144.130306)
			(xy 45.393239 -144.178888) (xy 45.365111 -144.224) (xy 45.330987 -144.264765) (xy 45.311568 -144.282922)
			(xy 45.304979 -144.289398) (xy 45.296513 -144.305803) (xy 45.295058 -144.314926) (xy 45.287692 -144.381474)
			(xy 45.286951 -144.39065) (xy 45.291393 -144.4085) (xy 45.296328 -144.416272) (xy 45.312439 -144.4404)
			(xy 45.337976 -144.492493) (xy 45.355334 -144.54785) (xy 45.364113 -144.605197) (xy 45.364654 -144.634204)
			(xy 45.364126 -144.661453) (xy 45.35637 -144.715397) (xy 45.341017 -144.767688) (xy 45.318379 -144.817262)
			(xy 45.288916 -144.863111) (xy 45.253229 -144.9043) (xy 45.212044 -144.939991) (xy 45.166199 -144.969458)
			(xy 45.116628 -144.992102) (xy 45.064338 -145.007461) (xy 45.010395 -145.015223) (xy 44.983146 -145.015712)
			(xy 44.982638 -145.015712) (xy 44.972841 -145.015644) (xy 44.953273 -145.014629) (xy 44.943522 -145.01368)
			(xy 44.943268 -145.01368) (xy 44.933878 -145.013094) (xy 44.915742 -145.018044) (xy 44.907962 -145.023332)
			(xy 44.84497 -145.070068) (xy 44.835064 -145.08607) (xy 44.833286 -145.095722) (xy 44.827837 -145.121546)
			(xy 44.81091 -145.171534) (xy 44.787254 -145.218711) (xy 44.757323 -145.262178) (xy 44.721687 -145.301105)
			(xy 44.681025 -145.334749) (xy 44.636115 -145.362469) (xy 44.587814 -145.383734) (xy 44.537042 -145.39814)
			(xy 44.48477 -145.405411) (xy 44.458382 -145.405856) (xy 44.430833 -145.40536) (xy 44.376305 -145.397444)
			(xy 44.323485 -145.381765) (xy 44.273469 -145.35865) (xy 44.227301 -145.328578) (xy 44.185939 -145.292177)
			(xy 44.150245 -145.250203) (xy 44.120961 -145.20353) (xy 44.109386 -145.178526) (xy 44.105576 -145.16989)
			(xy 44.092114 -145.156428) (xy 44.01185 -145.121122) (xy 43.993308 -145.120106) (xy 43.984418 -145.1229)
			(xy 43.983402 -145.123408) (xy 43.968416 -145.128234) (xy 43.959545 -145.131213) (xy 43.944569 -145.142409)
			(xy 43.939206 -145.150078) (xy 43.898312 -145.215356) (xy 43.894756 -145.233136) (xy 43.89628 -145.24228)
			(xy 43.89628 -145.242788) (xy 43.898764 -145.258418) (xy 43.901433 -145.289955) (xy 43.901614 -145.30578)
			(xy 43.901128 -145.333031) (xy 43.893372 -145.386979) (xy 43.878017 -145.439274) (xy 43.855375 -145.488851)
			(xy 43.825909 -145.534701) (xy 43.790218 -145.575892) (xy 43.749027 -145.611583) (xy 43.703177 -145.641049)
			(xy 43.6536 -145.663691) (xy 43.601305 -145.679046) (xy 43.547357 -145.686802) (xy 43.492855 -145.686802)
			(xy 43.438907 -145.679046) (xy 43.386612 -145.663691) (xy 43.337035 -145.641049) (xy 43.291185 -145.611583)
			(xy 43.249994 -145.575892) (xy 43.214303 -145.534701) (xy 43.184837 -145.488851) (xy 43.162195 -145.439274)
			(xy 43.14684 -145.386979) (xy 43.139084 -145.333031) (xy 43.138598 -145.30578) (xy 40.525974 -145.30578)
			(xy 40.5257 -145.307812) (xy 40.524782 -145.316445) (xy 40.528154 -145.333462) (xy 40.532304 -145.341086)
			(xy 40.553607 -145.377831) (xy 40.59061 -145.45429) (xy 40.620984 -145.533615) (xy 40.644511 -145.615234)
			(xy 40.653208 -145.656808) (xy 40.749474 -146.14271) (xy 40.758381 -146.190665) (xy 40.76792 -146.287741)
			(xy 40.768524 -146.336512) (xy 40.768221 -146.372197) (xy 40.763138 -146.443386) (xy 40.758364 -146.478752)
			(xy 40.757453 -146.487383) (xy 40.76084 -146.504391) (xy 40.764968 -146.512026) (xy 40.786274 -146.54877)
			(xy 40.823282 -146.625227) (xy 40.853663 -146.704551) (xy 40.863844 -146.739864) (xy 48.909984 -146.739864)
			(xy 48.914055 -146.684242) (xy 48.926181 -146.629805) (xy 48.946104 -146.577714) (xy 48.9734 -146.529079)
			(xy 49.007486 -146.484936) (xy 49.047635 -146.446227) (xy 49.092993 -146.413776) (xy 49.142593 -146.388275)
			(xy 49.195377 -146.370268) (xy 49.25022 -146.360138) (xy 49.305954 -146.358101) (xy 49.361391 -146.364201)
			(xy 49.415348 -146.378307) (xy 49.466677 -146.400119) (xy 49.514283 -146.429173) (xy 49.557151 -146.464848)
			(xy 49.594368 -146.506385) (xy 49.625141 -146.552898) (xy 49.648813 -146.603395) (xy 49.664881 -146.656802)
			(xy 49.673001 -146.711978) (xy 49.67351 -146.739864) (xy 49.673001 -146.76775) (xy 49.664881 -146.822926)
			(xy 49.648813 -146.876333) (xy 49.625141 -146.92683) (xy 49.594368 -146.973343) (xy 49.557151 -147.01488)
			(xy 49.514283 -147.050555) (xy 49.466677 -147.079609) (xy 49.415348 -147.101421) (xy 49.361391 -147.115527)
			(xy 49.305954 -147.121627) (xy 49.25022 -147.11959) (xy 49.195377 -147.10946) (xy 49.142593 -147.091453)
			(xy 49.092993 -147.065952) (xy 49.047635 -147.033501) (xy 49.007486 -146.994792) (xy 48.9734 -146.950649)
			(xy 48.946104 -146.902014) (xy 48.926181 -146.849923) (xy 48.914055 -146.795486) (xy 48.909984 -146.739864)
			(xy 40.863844 -146.739864) (xy 40.877195 -146.78617) (xy 40.885872 -146.827748) (xy 40.982138 -147.31365)
			(xy 40.991049 -147.361605) (xy 41.000593 -147.45868) (xy 41.001188 -147.507452) (xy 41.00086 -147.54032)
			(xy 40.99641 -147.605905) (xy 40.992298 -147.638516) (xy 40.991526 -147.647331) (xy 40.99529 -147.664607)
			(xy 40.999664 -147.672298) (xy 41.023371 -147.711045) (xy 41.064437 -147.792075) (xy 41.097963 -147.876505)
			(xy 41.123673 -147.963633) (xy 41.133014 -148.008086) (xy 41.229534 -148.494242) (xy 41.238485 -148.542319)
			(xy 41.248029 -148.639652) (xy 41.248584 -148.688552) (xy 41.248064 -148.734349) (xy 41.239666 -148.825557)
			(xy 41.222946 -148.915612) (xy 41.210992 -148.959824) (xy 41.20769 -148.971508) (xy 42.118883 -153.560018)
			(xy 52.449982 -153.560018) (xy 52.454053 -153.504396) (xy 52.466179 -153.449959) (xy 52.486102 -153.397868)
			(xy 52.513398 -153.349233) (xy 52.547484 -153.30509) (xy 52.587633 -153.266381) (xy 52.632991 -153.23393)
			(xy 52.682591 -153.208429) (xy 52.735375 -153.190422) (xy 52.790218 -153.180292) (xy 52.845952 -153.178255)
			(xy 52.901389 -153.184355) (xy 52.955346 -153.198461) (xy 53.006675 -153.220273) (xy 53.054281 -153.249327)
			(xy 53.097149 -153.285002) (xy 53.134366 -153.326539) (xy 53.165139 -153.373052) (xy 53.188811 -153.423549)
			(xy 53.204879 -153.476956) (xy 53.212999 -153.532132) (xy 53.213508 -153.560018) (xy 53.212999 -153.587904)
			(xy 53.204879 -153.64308) (xy 53.188811 -153.696487) (xy 53.165139 -153.746984) (xy 53.134366 -153.793497)
			(xy 53.097149 -153.835034) (xy 53.054281 -153.870709) (xy 53.006675 -153.899763) (xy 52.955346 -153.921575)
			(xy 52.901389 -153.935681) (xy 52.845952 -153.941781) (xy 52.790218 -153.939744) (xy 52.735375 -153.929614)
			(xy 52.682591 -153.911607) (xy 52.632991 -153.886106) (xy 52.587633 -153.853655) (xy 52.547484 -153.814946)
			(xy 52.513398 -153.770803) (xy 52.486102 -153.722168) (xy 52.466179 -153.670077) (xy 52.454053 -153.61564)
			(xy 52.449982 -153.560018) (xy 42.118883 -153.560018) (xy 42.238022 -154.159966) (xy 51.306982 -154.159966)
			(xy 51.311053 -154.104344) (xy 51.323179 -154.049907) (xy 51.343102 -153.997816) (xy 51.370398 -153.949181)
			(xy 51.404484 -153.905038) (xy 51.444633 -153.866329) (xy 51.489991 -153.833878) (xy 51.539591 -153.808377)
			(xy 51.592375 -153.79037) (xy 51.647218 -153.78024) (xy 51.702952 -153.778203) (xy 51.758389 -153.784303)
			(xy 51.812346 -153.798409) (xy 51.863675 -153.820221) (xy 51.911281 -153.849275) (xy 51.954149 -153.88495)
			(xy 51.991366 -153.926487) (xy 52.022139 -153.973) (xy 52.045811 -154.023497) (xy 52.061879 -154.076904)
			(xy 52.069999 -154.13208) (xy 52.070508 -154.159966) (xy 52.069999 -154.187852) (xy 52.061879 -154.243028)
			(xy 52.045811 -154.296435) (xy 52.022139 -154.346932) (xy 51.991366 -154.393445) (xy 51.954149 -154.434982)
			(xy 51.911281 -154.470657) (xy 51.863675 -154.499711) (xy 51.812346 -154.521523) (xy 51.758389 -154.535629)
			(xy 51.702952 -154.541729) (xy 51.647218 -154.539692) (xy 51.592375 -154.529562) (xy 51.539591 -154.511555)
			(xy 51.489991 -154.486054) (xy 51.444633 -154.453603) (xy 51.404484 -154.414894) (xy 51.370398 -154.370751)
			(xy 51.343102 -154.322116) (xy 51.323179 -154.270025) (xy 51.311053 -154.215588) (xy 51.306982 -154.159966)
			(xy 42.238022 -154.159966) (xy 42.413098 -155.0416) (xy 48.163732 -155.0416) (xy 48.167803 -154.985978)
			(xy 48.179929 -154.931541) (xy 48.199852 -154.87945) (xy 48.227148 -154.830815) (xy 48.261234 -154.786672)
			(xy 48.301383 -154.747963) (xy 48.346741 -154.715512) (xy 48.396341 -154.690011) (xy 48.449125 -154.672004)
			(xy 48.503968 -154.661874) (xy 48.559702 -154.659837) (xy 48.615139 -154.665937) (xy 48.669096 -154.680043)
			(xy 48.720425 -154.701855) (xy 48.768031 -154.730909) (xy 48.810899 -154.766584) (xy 48.848116 -154.808121)
			(xy 48.878889 -154.854634) (xy 48.902561 -154.905131) (xy 48.918629 -154.958538) (xy 48.926749 -155.013714)
			(xy 48.927258 -155.0416) (xy 48.926749 -155.069486) (xy 48.918629 -155.124662) (xy 48.902561 -155.178069)
			(xy 48.878889 -155.228566) (xy 48.848116 -155.275079) (xy 48.810899 -155.316616) (xy 48.768031 -155.352291)
			(xy 48.720425 -155.381345) (xy 48.669096 -155.403157) (xy 48.615139 -155.417263) (xy 48.559702 -155.423363)
			(xy 48.503968 -155.421326) (xy 48.449125 -155.411196) (xy 48.396341 -155.393189) (xy 48.346741 -155.367688)
			(xy 48.301383 -155.335237) (xy 48.261234 -155.296528) (xy 48.227148 -155.252385) (xy 48.199852 -155.20375)
			(xy 48.179929 -155.151659) (xy 48.167803 -155.097222) (xy 48.163732 -155.0416) (xy 42.413098 -155.0416)
			(xy 42.523662 -155.598368) (xy 51.368196 -155.598368) (xy 51.372267 -155.542746) (xy 51.384393 -155.488309)
			(xy 51.404316 -155.436218) (xy 51.431612 -155.387583) (xy 51.465698 -155.34344) (xy 51.505847 -155.304731)
			(xy 51.551205 -155.27228) (xy 51.600805 -155.246779) (xy 51.653589 -155.228772) (xy 51.708432 -155.218642)
			(xy 51.764166 -155.216605) (xy 51.819603 -155.222705) (xy 51.87356 -155.236811) (xy 51.924889 -155.258623)
			(xy 51.972495 -155.287677) (xy 52.015363 -155.323352) (xy 52.05258 -155.364889) (xy 52.083353 -155.411402)
			(xy 52.107025 -155.461899) (xy 52.123093 -155.515306) (xy 52.131213 -155.570482) (xy 52.131722 -155.598368)
			(xy 52.131213 -155.626254) (xy 52.123093 -155.68143) (xy 52.107025 -155.734837) (xy 52.083353 -155.785334)
			(xy 52.05258 -155.831847) (xy 52.015363 -155.873384) (xy 51.972495 -155.909059) (xy 51.924889 -155.938113)
			(xy 51.87356 -155.959925) (xy 51.819603 -155.974031) (xy 51.764166 -155.980131) (xy 51.708432 -155.978094)
			(xy 51.653589 -155.967964) (xy 51.600805 -155.949957) (xy 51.551205 -155.924456) (xy 51.505847 -155.892005)
			(xy 51.465698 -155.853296) (xy 51.431612 -155.809153) (xy 51.404316 -155.760518) (xy 51.384393 -155.708427)
			(xy 51.372267 -155.65399) (xy 51.368196 -155.598368) (xy 42.523662 -155.598368) (xy 42.816616 -157.0736)
			(xy 51.296822 -157.0736) (xy 51.300893 -157.017978) (xy 51.313019 -156.963541) (xy 51.332942 -156.91145)
			(xy 51.360238 -156.862815) (xy 51.394324 -156.818672) (xy 51.434473 -156.779963) (xy 51.479831 -156.747512)
			(xy 51.529431 -156.722011) (xy 51.582215 -156.704004) (xy 51.637058 -156.693874) (xy 51.692792 -156.691837)
			(xy 51.748229 -156.697937) (xy 51.802186 -156.712043) (xy 51.853515 -156.733855) (xy 51.901121 -156.762909)
			(xy 51.943989 -156.798584) (xy 51.981206 -156.840121) (xy 52.011979 -156.886634) (xy 52.035651 -156.937131)
			(xy 52.051719 -156.990538) (xy 52.059839 -157.045714) (xy 52.060348 -157.0736) (xy 52.059839 -157.101486)
			(xy 52.051719 -157.156662) (xy 52.035651 -157.210069) (xy 52.011979 -157.260566) (xy 51.981206 -157.307079)
			(xy 51.943989 -157.348616) (xy 51.901121 -157.384291) (xy 51.853515 -157.413345) (xy 51.802186 -157.435157)
			(xy 51.748229 -157.449263) (xy 51.692792 -157.455363) (xy 51.637058 -157.453326) (xy 51.582215 -157.443196)
			(xy 51.529431 -157.425189) (xy 51.479831 -157.399688) (xy 51.434473 -157.367237) (xy 51.394324 -157.328528)
			(xy 51.360238 -157.284385) (xy 51.332942 -157.23575) (xy 51.313019 -157.183659) (xy 51.300893 -157.129222)
			(xy 51.296822 -157.0736) (xy 42.816616 -157.0736) (xy 43.434502 -160.1851) (xy 45.523925 -160.1851)
			(xy 45.527881 -160.093241) (xy 45.539718 -160.002062) (xy 45.55935 -159.912238) (xy 45.586631 -159.824435)
			(xy 45.621359 -159.739302) (xy 45.663277 -159.657469) (xy 45.712075 -159.579542) (xy 45.76739 -159.506099)
			(xy 45.828815 -159.437683) (xy 45.895894 -159.374801) (xy 45.968129 -159.317918) (xy 46.044988 -159.267455)
			(xy 46.1259 -159.223786) (xy 46.210266 -159.187234) (xy 46.297462 -159.15807) (xy 46.386843 -159.13651)
			(xy 46.477746 -159.122714) (xy 46.569499 -159.116782) (xy 46.661421 -159.118761) (xy 46.752834 -159.128634)
			(xy 46.843059 -159.146329) (xy 46.93143 -159.171714) (xy 47.01729 -159.204602) (xy 47.100006 -159.24475)
			(xy 47.178964 -159.291859) (xy 47.253581 -159.345582) (xy 47.323302 -159.40552) (xy 47.387613 -159.47123)
			(xy 47.446038 -159.542226) (xy 47.498143 -159.61798) (xy 47.543542 -159.697934) (xy 47.581901 -159.781494)
			(xy 47.612934 -159.868043) (xy 47.636412 -159.956939) (xy 47.652162 -160.047524) (xy 47.660066 -160.139128)
			(xy 47.66056 -160.1851) (xy 47.660066 -160.231072) (xy 47.652162 -160.322676) (xy 47.636412 -160.413261)
			(xy 47.612934 -160.502157) (xy 47.581901 -160.588706) (xy 47.543542 -160.672266) (xy 47.498143 -160.75222)
			(xy 47.446038 -160.827974) (xy 47.387613 -160.89897) (xy 47.323302 -160.96468) (xy 47.253581 -161.024618)
			(xy 47.178964 -161.078341) (xy 47.100006 -161.12545) (xy 47.01729 -161.165598) (xy 46.93143 -161.198486)
			(xy 46.843059 -161.223871) (xy 46.752834 -161.241566) (xy 46.661421 -161.251439) (xy 46.569499 -161.253418)
			(xy 46.477746 -161.247486) (xy 46.386843 -161.23369) (xy 46.297462 -161.21213) (xy 46.210266 -161.182966)
			(xy 46.1259 -161.146414) (xy 46.044988 -161.102745) (xy 45.968129 -161.052282) (xy 45.895894 -160.995399)
			(xy 45.828815 -160.932517) (xy 45.76739 -160.864101) (xy 45.712075 -160.790658) (xy 45.663277 -160.712731)
			(xy 45.621359 -160.630898) (xy 45.586631 -160.545765) (xy 45.55935 -160.457962) (xy 45.539718 -160.368138)
			(xy 45.527881 -160.276959) (xy 45.523925 -160.1851) (xy 43.434502 -160.1851) (xy 46.71502 -176.704855)
			(xy 50.702129 -176.704855) (xy 50.702129 -176.650345) (xy 50.709887 -176.596389) (xy 50.725244 -176.544087)
			(xy 50.747889 -176.494503) (xy 50.77736 -176.448646) (xy 50.813057 -176.40745) (xy 50.854254 -176.371754)
			(xy 50.900112 -176.342284) (xy 50.949696 -176.319641) (xy 51.001999 -176.304285) (xy 51.055955 -176.296528)
			(xy 51.08321 -176.296066) (xy 51.089052 -176.296066) (xy 51.102338 -176.295857) (xy 51.128101 -176.289393)
			(xy 51.151322 -176.276498) (xy 51.170429 -176.258047) (xy 51.184126 -176.23529) (xy 51.191485 -176.209768)
			(xy 51.192176 -176.196498) (xy 51.193121 -176.169592) (xy 51.201734 -176.116446) (xy 51.217731 -176.065038)
			(xy 51.240794 -176.016389) (xy 51.270465 -175.971464) (xy 51.306156 -175.931155) (xy 51.347157 -175.896262)
			(xy 51.392656 -175.867477) (xy 51.441748 -175.845373) (xy 51.49346 -175.830388) (xy 51.546764 -175.822819)
			(xy 51.573684 -175.822356) (xy 51.600935 -175.82289) (xy 51.654883 -175.830645) (xy 51.707177 -175.845998)
			(xy 51.756755 -175.868637) (xy 51.802606 -175.898102) (xy 51.843796 -175.933792) (xy 51.879488 -175.974981)
			(xy 51.908955 -176.020831) (xy 51.931597 -176.070408) (xy 51.946952 -176.122702) (xy 51.954709 -176.176649)
			(xy 51.954709 -176.231151) (xy 51.946952 -176.285098) (xy 51.931597 -176.337392) (xy 51.908955 -176.386969)
			(xy 51.879488 -176.432819) (xy 51.843796 -176.474008) (xy 51.802606 -176.509698) (xy 51.756755 -176.539163)
			(xy 51.707177 -176.561802) (xy 51.654883 -176.577155) (xy 51.600935 -176.58491) (xy 51.573684 -176.585372)
			(xy 51.567842 -176.585372) (xy 51.55456 -176.585636) (xy 51.528806 -176.592097) (xy 51.505591 -176.604983)
			(xy 51.486486 -176.623422) (xy 51.472785 -176.646166) (xy 51.465416 -176.671675) (xy 51.464718 -176.68494)
			(xy 51.463814 -176.711848) (xy 51.455195 -176.764996) (xy 51.439193 -176.816404) (xy 51.416126 -176.865054)
			(xy 51.38645 -176.909979) (xy 51.350755 -176.950288) (xy 51.30975 -176.98518) (xy 51.264248 -177.013964)
			(xy 51.215152 -177.036067) (xy 51.163438 -177.051051) (xy 51.110131 -177.058619) (xy 51.08321 -177.059082)
			(xy 51.055955 -177.058672) (xy 51.001999 -177.050915) (xy 50.949696 -177.035559) (xy 50.900112 -177.012916)
			(xy 50.854254 -176.983446) (xy 50.813057 -176.94775) (xy 50.77736 -176.906554) (xy 50.747889 -176.860697)
			(xy 50.725244 -176.811113) (xy 50.709887 -176.758811) (xy 50.702129 -176.704855) (xy 46.71502 -176.704855)
			(xy 48.362108 -184.999122) (xy 48.363886 -185.005472) (xy 55.835606 -207.077564) (xy 59.966096 -207.077564)
			(xy 59.970167 -207.021942) (xy 59.982293 -206.967505) (xy 60.002216 -206.915414) (xy 60.029512 -206.866779)
			(xy 60.063598 -206.822636) (xy 60.103747 -206.783927) (xy 60.149105 -206.751476) (xy 60.198705 -206.725975)
			(xy 60.251489 -206.707968) (xy 60.306332 -206.697838) (xy 60.362066 -206.695801) (xy 60.417503 -206.701901)
			(xy 60.47146 -206.716007) (xy 60.522789 -206.737819) (xy 60.570395 -206.766873) (xy 60.613263 -206.802548)
			(xy 60.65048 -206.844085) (xy 60.681253 -206.890598) (xy 60.704925 -206.941095) (xy 60.720993 -206.994502)
			(xy 60.729113 -207.049678) (xy 60.729622 -207.077564) (xy 60.729113 -207.10545) (xy 60.720993 -207.160626)
			(xy 60.704925 -207.214033) (xy 60.681253 -207.26453) (xy 60.65048 -207.311043) (xy 60.613263 -207.35258)
			(xy 60.570395 -207.388255) (xy 60.522789 -207.417309) (xy 60.47146 -207.439121) (xy 60.417503 -207.453227)
			(xy 60.362066 -207.459327) (xy 60.306332 -207.45729) (xy 60.251489 -207.44716) (xy 60.198705 -207.429153)
			(xy 60.149105 -207.403652) (xy 60.103747 -207.371201) (xy 60.063598 -207.332492) (xy 60.029512 -207.288349)
			(xy 60.002216 -207.239714) (xy 59.982293 -207.187623) (xy 59.970167 -207.133186) (xy 59.966096 -207.077564)
			(xy 55.835606 -207.077564) (xy 57.695755 -212.5726) (xy 60.171582 -212.5726) (xy 60.175653 -212.516978)
			(xy 60.187779 -212.462541) (xy 60.207702 -212.41045) (xy 60.234998 -212.361815) (xy 60.269084 -212.317672)
			(xy 60.309233 -212.278963) (xy 60.354591 -212.246512) (xy 60.404191 -212.221011) (xy 60.456975 -212.203004)
			(xy 60.511818 -212.192874) (xy 60.567552 -212.190837) (xy 60.622989 -212.196937) (xy 60.676946 -212.211043)
			(xy 60.728275 -212.232855) (xy 60.775881 -212.261909) (xy 60.818749 -212.297584) (xy 60.855966 -212.339121)
			(xy 60.886739 -212.385634) (xy 60.910411 -212.436131) (xy 60.926479 -212.489538) (xy 60.934599 -212.544714)
			(xy 60.934644 -212.5472) (xy 63.651382 -212.5472) (xy 63.655453 -212.491578) (xy 63.667579 -212.437141)
			(xy 63.687502 -212.38505) (xy 63.714798 -212.336415) (xy 63.748884 -212.292272) (xy 63.789033 -212.253563)
			(xy 63.834391 -212.221112) (xy 63.883991 -212.195611) (xy 63.936775 -212.177604) (xy 63.991618 -212.167474)
			(xy 64.047352 -212.165437) (xy 64.102789 -212.171537) (xy 64.156746 -212.185643) (xy 64.208075 -212.207455)
			(xy 64.255681 -212.236509) (xy 64.298549 -212.272184) (xy 64.335766 -212.313721) (xy 64.366539 -212.360234)
			(xy 64.390211 -212.410731) (xy 64.406279 -212.464138) (xy 64.414399 -212.519314) (xy 64.414908 -212.5472)
			(xy 64.414399 -212.575086) (xy 64.406279 -212.630262) (xy 64.390211 -212.683669) (xy 64.366539 -212.734166)
			(xy 64.335766 -212.780679) (xy 64.298549 -212.822216) (xy 64.255681 -212.857891) (xy 64.208075 -212.886945)
			(xy 64.156746 -212.908757) (xy 64.102789 -212.922863) (xy 64.047352 -212.928963) (xy 63.991618 -212.926926)
			(xy 63.936775 -212.916796) (xy 63.883991 -212.898789) (xy 63.834391 -212.873288) (xy 63.789033 -212.840837)
			(xy 63.748884 -212.802128) (xy 63.714798 -212.757985) (xy 63.687502 -212.70935) (xy 63.667579 -212.657259)
			(xy 63.655453 -212.602822) (xy 63.651382 -212.5472) (xy 60.934644 -212.5472) (xy 60.935108 -212.5726)
			(xy 60.934599 -212.600486) (xy 60.926479 -212.655662) (xy 60.910411 -212.709069) (xy 60.886739 -212.759566)
			(xy 60.855966 -212.806079) (xy 60.818749 -212.847616) (xy 60.775881 -212.883291) (xy 60.728275 -212.912345)
			(xy 60.676946 -212.934157) (xy 60.622989 -212.948263) (xy 60.567552 -212.954363) (xy 60.511818 -212.952326)
			(xy 60.456975 -212.942196) (xy 60.404191 -212.924189) (xy 60.354591 -212.898688) (xy 60.309233 -212.866237)
			(xy 60.269084 -212.827528) (xy 60.234998 -212.783385) (xy 60.207702 -212.73475) (xy 60.187779 -212.682659)
			(xy 60.175653 -212.628222) (xy 60.171582 -212.5726) (xy 57.695755 -212.5726) (xy 58.639329 -215.359996)
			(xy 69.499224 -215.359996) (xy 69.503295 -215.304374) (xy 69.515421 -215.249937) (xy 69.535344 -215.197846)
			(xy 69.56264 -215.149211) (xy 69.596726 -215.105068) (xy 69.636875 -215.066359) (xy 69.682233 -215.033908)
			(xy 69.731833 -215.008407) (xy 69.784617 -214.9904) (xy 69.83946 -214.98027) (xy 69.895194 -214.978233)
			(xy 69.950631 -214.984333) (xy 70.004588 -214.998439) (xy 70.055917 -215.020251) (xy 70.103523 -215.049305)
			(xy 70.146391 -215.08498) (xy 70.183608 -215.126517) (xy 70.214381 -215.17303) (xy 70.238053 -215.223527)
			(xy 70.254121 -215.276934) (xy 70.262241 -215.33211) (xy 70.26275 -215.359996) (xy 70.262241 -215.387882)
			(xy 70.254121 -215.443058) (xy 70.238053 -215.496465) (xy 70.214381 -215.546962) (xy 70.183608 -215.593475)
			(xy 70.146391 -215.635012) (xy 70.103523 -215.670687) (xy 70.055917 -215.699741) (xy 70.004588 -215.721553)
			(xy 69.950631 -215.735659) (xy 69.895194 -215.741759) (xy 69.83946 -215.739722) (xy 69.784617 -215.729592)
			(xy 69.731833 -215.711585) (xy 69.682233 -215.686084) (xy 69.636875 -215.653633) (xy 69.596726 -215.614924)
			(xy 69.56264 -215.570781) (xy 69.535344 -215.522146) (xy 69.515421 -215.470055) (xy 69.503295 -215.415618)
			(xy 69.499224 -215.359996) (xy 58.639329 -215.359996) (xy 59.088674 -216.6874) (xy 68.121782 -216.6874)
			(xy 68.125853 -216.631778) (xy 68.137979 -216.577341) (xy 68.157902 -216.52525) (xy 68.185198 -216.476615)
			(xy 68.219284 -216.432472) (xy 68.259433 -216.393763) (xy 68.304791 -216.361312) (xy 68.354391 -216.335811)
			(xy 68.407175 -216.317804) (xy 68.462018 -216.307674) (xy 68.517752 -216.305637) (xy 68.573189 -216.311737)
			(xy 68.627146 -216.325843) (xy 68.678475 -216.347655) (xy 68.726081 -216.376709) (xy 68.768949 -216.412384)
			(xy 68.806166 -216.453921) (xy 68.836939 -216.500434) (xy 68.860611 -216.550931) (xy 68.876679 -216.604338)
			(xy 68.884799 -216.659514) (xy 68.885308 -216.6874) (xy 68.884799 -216.715286) (xy 68.876679 -216.770462)
			(xy 68.860611 -216.823869) (xy 68.836939 -216.874366) (xy 68.806166 -216.920879) (xy 68.768949 -216.962416)
			(xy 68.726081 -216.998091) (xy 68.678475 -217.027145) (xy 68.627146 -217.048957) (xy 68.573189 -217.063063)
			(xy 68.517752 -217.069163) (xy 68.462018 -217.067126) (xy 68.407175 -217.056996) (xy 68.354391 -217.038989)
			(xy 68.304791 -217.013488) (xy 68.259433 -216.981037) (xy 68.219284 -216.942328) (xy 68.185198 -216.898185)
			(xy 68.157902 -216.84955) (xy 68.137979 -216.797459) (xy 68.125853 -216.743022) (xy 68.121782 -216.6874)
			(xy 59.088674 -216.6874) (xy 60.060278 -219.5576) (xy 69.569582 -219.5576) (xy 69.573653 -219.501978)
			(xy 69.585779 -219.447541) (xy 69.605702 -219.39545) (xy 69.632998 -219.346815) (xy 69.667084 -219.302672)
			(xy 69.707233 -219.263963) (xy 69.752591 -219.231512) (xy 69.802191 -219.206011) (xy 69.854975 -219.188004)
			(xy 69.909818 -219.177874) (xy 69.965552 -219.175837) (xy 70.020989 -219.181937) (xy 70.074946 -219.196043)
			(xy 70.126275 -219.217855) (xy 70.173881 -219.246909) (xy 70.216749 -219.282584) (xy 70.253966 -219.324121)
			(xy 70.284739 -219.370634) (xy 70.308411 -219.421131) (xy 70.324479 -219.474538) (xy 70.332599 -219.529714)
			(xy 70.333108 -219.5576) (xy 70.332599 -219.585486) (xy 70.324479 -219.640662) (xy 70.308411 -219.694069)
			(xy 70.284739 -219.744566) (xy 70.253966 -219.791079) (xy 70.216749 -219.832616) (xy 70.173881 -219.868291)
			(xy 70.126275 -219.897345) (xy 70.074946 -219.919157) (xy 70.020989 -219.933263) (xy 69.965552 -219.939363)
			(xy 69.909818 -219.937326) (xy 69.854975 -219.927196) (xy 69.802191 -219.909189) (xy 69.752591 -219.883688)
			(xy 69.707233 -219.851237) (xy 69.667084 -219.812528) (xy 69.632998 -219.768385) (xy 69.605702 -219.71975)
			(xy 69.585779 -219.667659) (xy 69.573653 -219.613222) (xy 69.569582 -219.5576) (xy 60.060278 -219.5576)
			(xy 63.06967 -228.4476) (xy 69.569582 -228.4476) (xy 69.573653 -228.391978) (xy 69.585779 -228.337541)
			(xy 69.605702 -228.28545) (xy 69.632998 -228.236815) (xy 69.667084 -228.192672) (xy 69.707233 -228.153963)
			(xy 69.752591 -228.121512) (xy 69.802191 -228.096011) (xy 69.854975 -228.078004) (xy 69.909818 -228.067874)
			(xy 69.965552 -228.065837) (xy 70.020989 -228.071937) (xy 70.074946 -228.086043) (xy 70.126275 -228.107855)
			(xy 70.173881 -228.136909) (xy 70.216749 -228.172584) (xy 70.253966 -228.214121) (xy 70.284739 -228.260634)
			(xy 70.308411 -228.311131) (xy 70.324479 -228.364538) (xy 70.332599 -228.419714) (xy 70.333108 -228.4476)
			(xy 70.332599 -228.475486) (xy 70.324479 -228.530662) (xy 70.308411 -228.584069) (xy 70.284739 -228.634566)
			(xy 70.253966 -228.681079) (xy 70.216749 -228.722616) (xy 70.173881 -228.758291) (xy 70.126275 -228.787345)
			(xy 70.074946 -228.809157) (xy 70.020989 -228.823263) (xy 69.965552 -228.829363) (xy 69.909818 -228.827326)
			(xy 69.854975 -228.817196) (xy 69.802191 -228.799189) (xy 69.752591 -228.773688) (xy 69.707233 -228.741237)
			(xy 69.667084 -228.702528) (xy 69.632998 -228.658385) (xy 69.605702 -228.60975) (xy 69.585779 -228.557659)
			(xy 69.573653 -228.503222) (xy 69.569582 -228.4476) (xy 63.06967 -228.4476) (xy 66.254381 -237.855506)
			(xy 70.417688 -237.855506) (xy 70.421759 -237.799884) (xy 70.433885 -237.745447) (xy 70.453808 -237.693356)
			(xy 70.481104 -237.644721) (xy 70.51519 -237.600578) (xy 70.555339 -237.561869) (xy 70.600697 -237.529418)
			(xy 70.650297 -237.503917) (xy 70.703081 -237.48591) (xy 70.757924 -237.47578) (xy 70.813658 -237.473743)
			(xy 70.869095 -237.479843) (xy 70.923052 -237.493949) (xy 70.974381 -237.515761) (xy 71.021987 -237.544815)
			(xy 71.064855 -237.58049) (xy 71.102072 -237.622027) (xy 71.132845 -237.66854) (xy 71.156517 -237.719037)
			(xy 71.172585 -237.772444) (xy 71.180705 -237.82762) (xy 71.181214 -237.855506) (xy 71.180705 -237.883392)
			(xy 71.172585 -237.938568) (xy 71.156517 -237.991975) (xy 71.132845 -238.042472) (xy 71.102072 -238.088985)
			(xy 71.064855 -238.130522) (xy 71.021987 -238.166197) (xy 70.974381 -238.195251) (xy 70.923052 -238.217063)
			(xy 70.869095 -238.231169) (xy 70.813658 -238.237269) (xy 70.757924 -238.235232) (xy 70.703081 -238.225102)
			(xy 70.650297 -238.207095) (xy 70.600697 -238.181594) (xy 70.555339 -238.149143) (xy 70.51519 -238.110434)
			(xy 70.481104 -238.066291) (xy 70.453808 -238.017656) (xy 70.433885 -237.965565) (xy 70.421759 -237.911128)
			(xy 70.417688 -237.855506) (xy 66.254381 -237.855506) (xy 67.75796 -242.297204) (xy 71.240902 -242.297204)
			(xy 71.244973 -242.241582) (xy 71.257099 -242.187145) (xy 71.277022 -242.135054) (xy 71.304318 -242.086419)
			(xy 71.338404 -242.042276) (xy 71.378553 -242.003567) (xy 71.423911 -241.971116) (xy 71.473511 -241.945615)
			(xy 71.526295 -241.927608) (xy 71.581138 -241.917478) (xy 71.636872 -241.915441) (xy 71.692309 -241.921541)
			(xy 71.746266 -241.935647) (xy 71.797595 -241.957459) (xy 71.845201 -241.986513) (xy 71.888069 -242.022188)
			(xy 71.925286 -242.063725) (xy 71.956059 -242.110238) (xy 71.979731 -242.160735) (xy 71.995799 -242.214142)
			(xy 72.003919 -242.269318) (xy 72.004428 -242.297204) (xy 72.003919 -242.32509) (xy 71.995799 -242.380266)
			(xy 71.979731 -242.433673) (xy 71.956059 -242.48417) (xy 71.925286 -242.530683) (xy 71.888069 -242.57222)
			(xy 71.845201 -242.607895) (xy 71.797595 -242.636949) (xy 71.746266 -242.658761) (xy 71.692309 -242.672867)
			(xy 71.636872 -242.678967) (xy 71.581138 -242.67693) (xy 71.526295 -242.6668) (xy 71.473511 -242.648793)
			(xy 71.423911 -242.623292) (xy 71.378553 -242.590841) (xy 71.338404 -242.552132) (xy 71.304318 -242.507989)
			(xy 71.277022 -242.459354) (xy 71.257099 -242.407263) (xy 71.244973 -242.352826) (xy 71.240902 -242.297204)
			(xy 67.75796 -242.297204) (xy 71.155306 -252.333252) (xy 71.159205 -252.343079) (xy 71.173455 -252.358666)
			(xy 71.192756 -252.367237) (xy 71.203312 -252.367796) (xy 73.318878 -252.367796) (xy 73.329599 -252.367371)
			(xy 73.349194 -252.358678) (xy 73.356724 -252.351032) (xy 73.363836 -252.343158) (xy 73.37044 -252.323346)
			(xy 72.86117 -246.497094) (xy 72.860662 -246.493538) (xy 72.597772 -244.843808) (xy 72.458072 -243.967)
			(xy 71.148448 -235.743242) (xy 71.146277 -235.732864) (xy 71.134857 -235.715027) (xy 71.12635 -235.708698)
			(xy 71.054976 -235.661454) (xy 71.034148 -235.657898) (xy 71.023734 -235.660438) (xy 71.001236 -235.665663)
			(xy 70.955388 -235.671268) (xy 70.932294 -235.671614) (xy 70.905043 -235.671128) (xy 70.851095 -235.663371)
			(xy 70.798801 -235.648015) (xy 70.749224 -235.625374) (xy 70.703374 -235.595907) (xy 70.662184 -235.560216)
			(xy 70.626493 -235.519026) (xy 70.597026 -235.473176) (xy 70.574385 -235.423599) (xy 70.559029 -235.371305)
			(xy 70.551272 -235.317357) (xy 70.550786 -235.290106) (xy 70.551294 -235.261538) (xy 70.559813 -235.205039)
			(xy 70.576663 -235.150443) (xy 70.601466 -235.098971) (xy 70.633667 -235.051772) (xy 70.672547 -235.009904)
			(xy 70.717236 -234.974301) (xy 70.766734 -234.945761) (xy 70.819935 -234.924921) (xy 70.875648 -234.912248)
			(xy 70.9041 -234.909614) (xy 70.914768 -234.908852) (xy 70.933564 -234.898946) (xy 70.98665 -234.83189)
			(xy 70.992752 -234.823245) (xy 70.998021 -234.802776) (xy 70.99681 -234.792266) (xy 70.3453 -230.700326)
			(xy 70.339598 -230.661909) (xy 70.333493 -230.584476) (xy 70.333108 -230.54564) (xy 70.333108 -230.54437)
			(xy 70.33317 -230.528547) (xy 70.334186 -230.496918) (xy 70.33514 -230.481124) (xy 70.58279 -226.652582)
			(xy 70.566788 -226.625658) (xy 70.552564 -226.619054) (xy 70.528222 -226.607181) (xy 70.482864 -226.577586)
			(xy 70.442142 -226.54188) (xy 70.406872 -226.50078) (xy 70.377761 -226.45511) (xy 70.355394 -226.405786)
			(xy 70.340218 -226.353797) (xy 70.332539 -226.300185) (xy 70.332092 -226.273106) (xy 70.332546 -226.246294)
			(xy 70.340054 -226.193199) (xy 70.354923 -226.141679) (xy 70.37686 -226.092748) (xy 70.405433 -226.047371)
			(xy 70.440078 -226.006443) (xy 70.480113 -225.970769) (xy 70.524749 -225.941052) (xy 70.573106 -225.917879)
			(xy 70.598538 -225.909378) (xy 70.61327 -225.904806) (xy 70.632828 -225.879914) (xy 70.812914 -223.09582)
			(xy 70.812914 -223.0882) (xy 70.586092 -220.497146) (xy 70.584384 -220.475534) (xy 70.582606 -220.432212)
			(xy 70.582536 -220.410532) (xy 70.582536 -220.410024) (xy 70.582595 -220.388344) (xy 70.584374 -220.345022)
			(xy 70.586092 -220.32341) (xy 72.146922 -202.484228) (xy 72.146922 -202.483212) (xy 72.150732 -202.425554)
			(xy 72.501252 -197.00875) (xy 72.539098 -196.423026) (xy 72.703182 -193.88836) (xy 72.84974 -191.622172)
			(xy 73.687686 -178.67757) (xy 73.690448 -178.639723) (xy 73.701062 -178.564578) (xy 73.717418 -178.490471)
			(xy 73.728072 -178.45405) (xy 75.389232 -172.983652) (xy 75.38974 -172.982128) (xy 75.948032 -170.898058)
			(xy 75.959726 -170.856136) (xy 75.989473 -170.774336) (xy 76.026246 -170.695445) (xy 76.0476 -170.65752)
			(xy 82.954114 -158.694374) (xy 82.955384 -158.68396) (xy 82.960276 -158.642795) (xy 82.976026 -158.561399)
			(xy 82.998475 -158.48159) (xy 83.027468 -158.403919) (xy 83.062806 -158.328922) (xy 83.083146 -158.2928)
			(xy 83.33105 -157.86354) (xy 83.351766 -157.828445) (xy 83.398121 -157.761411) (xy 83.449797 -157.698386)
			(xy 83.506447 -157.639792) (xy 83.53679 -157.612588) (xy 83.542872 -157.606877) (xy 83.551308 -157.592495)
			(xy 83.5533 -157.584394) (xy 83.561648 -157.544496) (xy 83.584024 -157.466108) (xy 83.612731 -157.389811)
			(xy 83.647575 -157.316114) (xy 83.6676 -157.28061) (xy 83.763104 -157.11551) (xy 83.767846 -157.106355)
			(xy 83.770344 -157.085909) (xy 83.76793 -157.075886) (xy 83.746848 -157.005274) (xy 83.743473 -156.995437)
			(xy 83.730232 -156.979428) (xy 83.721194 -156.974286) (xy 83.680115 -156.952725) (xy 83.601752 -156.903052)
			(xy 83.528343 -156.846312) (xy 83.460523 -156.782998) (xy 83.398879 -156.713656) (xy 83.343945 -156.638887)
			(xy 83.31962 -156.599382) (xy 83.317026 -156.595402) (xy 83.310637 -156.588371) (xy 83.30692 -156.585412)
			(xy 83.284439 -156.567354) (xy 83.244658 -156.525611) (xy 83.211612 -156.478357) (xy 83.186051 -156.42667)
			(xy 83.168558 -156.371725) (xy 83.159532 -156.314773) (xy 83.158838 -156.285946) (xy 83.158838 -156.28239)
			(xy 83.159421 -156.253281) (xy 83.168344 -156.19575) (xy 83.176618 -156.167836) (xy 83.177971 -156.16333)
			(xy 83.17913 -156.153993) (xy 83.178904 -156.149294) (xy 83.17795 -156.133436) (xy 83.176935 -156.10168)
			(xy 83.176872 -156.085794) (xy 83.177307 -156.043427) (xy 83.184494 -155.958997) (xy 83.198824 -155.875483)
			(xy 83.220195 -155.793487) (xy 83.24845 -155.713602) (xy 83.265518 -155.674822) (xy 83.269499 -155.664783)
			(xy 83.269496 -155.643206) (xy 83.265518 -155.633166) (xy 83.248484 -155.594401) (xy 83.220261 -155.514561)
			(xy 83.198902 -155.432618) (xy 83.184562 -155.349161) (xy 83.177342 -155.264788) (xy 83.176872 -155.222448)
			(xy 83.176872 -155.22194) (xy 83.17738 -155.195524) (xy 83.17738 -155.195016) (xy 83.177888 -155.175204)
			(xy 83.173316 -155.169362) (xy 83.138518 -155.133548) (xy 83.13801 -155.13304) (xy 83.119722 -155.114752)
			(xy 83.115992 -155.11123) (xy 83.107419 -155.105598) (xy 83.102704 -155.103576) (xy 83.094068 -155.10002)
			(xy 82.83575 -155.10002) (xy 82.795372 -155.099622) (xy 82.714886 -155.093037) (xy 82.635207 -155.079898)
			(xy 82.556868 -155.060294) (xy 82.518504 -155.047696) (xy 82.517488 -155.047442) (xy 82.51317 -155.046172)
			(xy 82.51063 -155.04541) (xy 82.50809 -155.044902) (xy 82.50174 -155.043632) (xy 82.49666 -155.042616)
			(xy 82.463774 -155.035662) (xy 82.398947 -155.017868) (xy 82.36712 -155.007056) (xy 82.354166 -155.002484)
			(xy 82.32013 -154.98953) (xy 82.317336 -154.988514) (xy 82.310986 -154.98572) (xy 82.246978 -154.98572)
			(xy 82.229198 -154.992832) (xy 82.221832 -154.999944) (xy 82.190959 -155.02888) (xy 82.125094 -155.082008)
			(xy 82.054963 -155.129362) (xy 81.981071 -155.170602) (xy 81.903949 -155.205432) (xy 81.824154 -155.233599)
			(xy 81.742257 -155.254903) (xy 81.65885 -155.269188) (xy 81.574533 -155.276354) (xy 81.532222 -155.276804)
			(xy 81.48554 -155.276261) (xy 81.392584 -155.267534) (xy 81.300851 -155.250155) (xy 81.211145 -155.224276)
			(xy 81.124252 -155.190124) (xy 81.040931 -155.147997) (xy 80.961915 -155.098265) (xy 80.887893 -155.041364)
			(xy 80.819516 -154.977792) (xy 80.757381 -154.908105) (xy 80.702034 -154.832915) (xy 80.677512 -154.793188)
			(xy 80.674918 -154.789208) (xy 80.668529 -154.782177) (xy 80.664812 -154.779218) (xy 80.642204 -154.761019)
			(xy 80.602229 -154.718945) (xy 80.569074 -154.67131) (xy 80.543503 -154.619211) (xy 80.526102 -154.563845)
			(xy 80.517273 -154.506484) (xy 80.51673 -154.477466) (xy 80.51673 -154.470354) (xy 80.517492 -154.451558)
			(xy 80.517746 -154.44978) (xy 80.517746 -154.447748) (xy 80.519016 -154.429714) (xy 80.51927 -154.42692)
			(xy 80.519778 -154.424126) (xy 80.522318 -154.411172) (xy 80.522572 -154.409648) (xy 80.524865 -154.397422)
			(xy 80.530838 -154.373273) (xy 80.53451 -154.361388) (xy 80.535871 -154.356818) (xy 80.537019 -154.347355)
			(xy 80.536796 -154.342592) (xy 80.535846 -154.326798) (xy 80.534831 -154.295169) (xy 80.534764 -154.279346)
			(xy 80.535196 -154.236978) (xy 80.542379 -154.152547) (xy 80.556706 -154.069031) (xy 80.578072 -153.987033)
			(xy 80.606324 -153.907146) (xy 80.62341 -153.868374) (xy 80.627402 -153.858334) (xy 80.62742 -153.836749)
			(xy 80.62341 -153.826718) (xy 80.606364 -153.78793) (xy 80.578125 -153.708041) (xy 80.556757 -153.626047)
			(xy 80.542417 -153.542537) (xy 80.535206 -153.458112) (xy 80.534764 -153.415746) (xy 80.534832 -153.39986)
			(xy 80.535848 -153.368104) (xy 80.536796 -153.352246) (xy 80.53697 -153.347548) (xy 80.535828 -153.338217)
			(xy 80.53451 -153.333704) (xy 80.52624 -153.305724) (xy 80.51731 -153.248067) (xy 80.51673 -153.218896)
			(xy 80.51673 -153.211784) (xy 80.51927 -153.17343) (xy 80.521556 -153.15438) (xy 80.52181 -153.152602)
			(xy 80.522318 -153.150316) (xy 80.527652 -153.126948) (xy 80.527652 -153.125678) (xy 80.528668 -153.122884)
			(xy 80.529684 -153.119074) (xy 80.529938 -153.117804) (xy 80.5307 -153.11501) (xy 80.534764 -153.101548)
			(xy 80.535018 -153.100786) (xy 80.535526 -153.09977) (xy 80.540098 -153.085292) (xy 80.543146 -153.078688)
			(xy 80.5434 -153.07818) (xy 80.54721 -153.068782) (xy 80.548226 -153.065734) (xy 80.550258 -153.06167)
			(xy 80.560729 -153.039257) (xy 80.586613 -152.997098) (xy 80.617717 -152.958628) (xy 80.635348 -152.941274)
			(xy 80.642423 -152.934594) (xy 80.657163 -152.921888) (xy 80.664812 -152.915874) (xy 80.668556 -152.912944)
			(xy 80.674951 -152.90591) (xy 80.677512 -152.901904) (xy 80.702025 -152.862174) (xy 80.757386 -152.786997)
			(xy 80.81953 -152.717323) (xy 80.887913 -152.653761) (xy 80.961937 -152.596868) (xy 81.040953 -152.547141)
			(xy 81.124271 -152.505016) (xy 81.211161 -152.470862) (xy 81.300862 -152.444976) (xy 81.39259 -152.427587)
			(xy 81.485541 -152.418846) (xy 81.532222 -152.418288) (xy 81.574518 -152.418745) (xy 81.658805 -152.425931)
			(xy 81.74218 -152.440232) (xy 81.824043 -152.461545) (xy 81.903806 -152.489717) (xy 81.980896 -152.524546)
			(xy 82.054758 -152.565781) (xy 82.124861 -152.613125) (xy 82.1907 -152.666239) (xy 82.221578 -152.695148)
			(xy 82.228878 -152.701589) (xy 82.246905 -152.708891) (xy 82.25663 -152.709372) (xy 83.126072 -152.709372)
			(xy 83.128612 -152.707086) (xy 83.131152 -152.704546) (xy 83.142836 -152.691338) (xy 83.1469 -152.686766)
			(xy 83.152488 -152.680416) (xy 83.159346 -152.66416) (xy 83.159854 -152.65527) (xy 83.161056 -152.640402)
			(xy 83.165505 -152.610903) (xy 83.168744 -152.596342) (xy 83.176872 -152.566624) (xy 83.178136 -152.562103)
			(xy 83.179151 -152.552771) (xy 83.178904 -152.548082) (xy 83.176872 -152.485852) (xy 83.177304 -152.443484)
			(xy 83.184487 -152.359053) (xy 83.198813 -152.275537) (xy 83.220179 -152.193539) (xy 83.24843 -152.113651)
			(xy 83.265518 -152.07488) (xy 83.26949 -152.064841) (xy 83.269471 -152.043272) (xy 83.265518 -152.033224)
			(xy 83.248476 -151.994435) (xy 83.220243 -151.914546) (xy 83.198884 -151.832551) (xy 83.184551 -151.749042)
			(xy 83.177348 -151.664617) (xy 83.176872 -151.622252) (xy 83.178904 -151.55926) (xy 83.179071 -151.554563)
			(xy 83.177914 -151.545236) (xy 83.176618 -151.540718) (xy 83.173423 -151.530318) (xy 83.168083 -151.509223)
			(xy 83.16595 -151.498554) (xy 83.163629 -151.489002) (xy 83.152913 -151.472545) (xy 83.145122 -151.46655)
			(xy 83.139534 -151.46274) (xy 83.124548 -151.454866) (xy 83.120484 -151.453342) (xy 83.081555 -151.440559)
			(xy 83.005766 -151.409401) (xy 82.9691 -151.391112) (xy 82.963674 -151.388524) (xy 82.951995 -151.38569)
			(xy 82.945986 -151.385524) (xy 82.25663 -151.385524) (xy 82.246905 -151.386) (xy 82.228873 -151.393302)
			(xy 82.221578 -151.399748) (xy 82.190711 -151.428667) (xy 82.124861 -151.481765) (xy 82.054752 -151.529097)
			(xy 81.980887 -151.570323) (xy 81.903796 -151.605146) (xy 81.824034 -151.633318) (xy 81.742173 -151.654634)
			(xy 81.658801 -151.668943) (xy 81.574517 -151.676141) (xy 81.532222 -151.676608) (xy 81.48554 -151.676065)
			(xy 81.392584 -151.667338) (xy 81.300851 -151.649959) (xy 81.211145 -151.62408) (xy 81.124251 -151.589928)
			(xy 81.040931 -151.547801) (xy 80.961914 -151.49807) (xy 80.887892 -151.441169) (xy 80.819515 -151.377596)
			(xy 80.75738 -151.30791) (xy 80.702033 -151.23272) (xy 80.677512 -151.192992) (xy 80.674918 -151.189012)
			(xy 80.668529 -151.181981) (xy 80.664812 -151.179022) (xy 80.642204 -151.160823) (xy 80.602228 -151.118749)
			(xy 80.569073 -151.071115) (xy 80.543501 -151.019015) (xy 80.5261 -150.963649) (xy 80.51727 -150.906288)
			(xy 80.51673 -150.87727) (xy 80.51673 -150.870158) (xy 80.517492 -150.851362) (xy 80.517746 -150.849584)
			(xy 80.517746 -150.847552) (xy 80.519016 -150.829518) (xy 80.51927 -150.826724) (xy 80.519778 -150.82393)
			(xy 80.522318 -150.810976) (xy 80.522572 -150.809452) (xy 80.524864 -150.797226) (xy 80.530837 -150.773076)
			(xy 80.53451 -150.761192) (xy 80.535871 -150.756622) (xy 80.53702 -150.747159) (xy 80.536796 -150.742396)
			(xy 80.535846 -150.726602) (xy 80.534831 -150.694973) (xy 80.534764 -150.67915) (xy 80.535196 -150.636782)
			(xy 80.542379 -150.552351) (xy 80.556705 -150.468835) (xy 80.578071 -150.386837) (xy 80.606322 -150.30695)
			(xy 80.62341 -150.268178) (xy 80.627403 -150.258138) (xy 80.627422 -150.236552) (xy 80.62341 -150.226522)
			(xy 80.606368 -150.187733) (xy 80.578136 -150.107844) (xy 80.556777 -150.025849) (xy 80.542444 -149.942339)
			(xy 80.535241 -149.857915) (xy 80.534764 -149.81555) (xy 80.534832 -149.799664) (xy 80.535848 -149.767908)
			(xy 80.536796 -149.75205) (xy 80.536962 -149.747353) (xy 80.535803 -149.738027) (xy 80.53451 -149.733508)
			(xy 80.52624 -149.705528) (xy 80.517309 -149.647871) (xy 80.51673 -149.6187) (xy 80.51673 -149.611588)
			(xy 80.51927 -149.573234) (xy 80.521556 -149.554184) (xy 80.52181 -149.552406) (xy 80.522318 -149.55012)
			(xy 80.527652 -149.526752) (xy 80.527652 -149.525482) (xy 80.528668 -149.522688) (xy 80.529684 -149.518878)
			(xy 80.529938 -149.517608) (xy 80.5307 -149.514814) (xy 80.534764 -149.501352) (xy 80.535018 -149.50059)
			(xy 80.535526 -149.499574) (xy 80.540098 -149.485096) (xy 80.543146 -149.478492) (xy 80.5434 -149.477984)
			(xy 80.54721 -149.468586) (xy 80.548226 -149.465538) (xy 80.550258 -149.461474) (xy 80.560729 -149.439061)
			(xy 80.586613 -149.396901) (xy 80.617716 -149.358431) (xy 80.635348 -149.341078) (xy 80.642423 -149.334398)
			(xy 80.657163 -149.321692) (xy 80.664812 -149.315678) (xy 80.668557 -149.312748) (xy 80.674951 -149.305714)
			(xy 80.677512 -149.301708) (xy 80.702025 -149.261977) (xy 80.757386 -149.186801) (xy 80.81953 -149.117126)
			(xy 80.887913 -149.053564) (xy 80.961936 -148.996671) (xy 81.040953 -148.946944) (xy 81.124271 -148.904819)
			(xy 81.211161 -148.870664) (xy 81.300862 -148.844778) (xy 81.39259 -148.827389) (xy 81.485541 -148.818648)
			(xy 81.532222 -148.818092) (xy 81.574518 -148.818549) (xy 81.658805 -148.825735) (xy 81.74218 -148.840036)
			(xy 81.824043 -148.861349) (xy 81.903806 -148.889521) (xy 81.980896 -148.92435) (xy 82.054758 -148.965585)
			(xy 82.12486 -149.01293) (xy 82.1907 -149.066043) (xy 82.221578 -149.094952) (xy 82.228878 -149.101393)
			(xy 82.246906 -149.108694) (xy 82.25663 -149.109176) (xy 83.126326 -149.109176) (xy 83.130898 -149.104604)
			(xy 83.14182 -149.092158) (xy 83.147408 -149.085808) (xy 83.1596 -149.056598) (xy 83.160362 -149.048724)
			(xy 83.160362 -149.04847) (xy 83.162472 -149.027807) (xy 83.170615 -148.987074) (xy 83.176618 -148.96719)
			(xy 83.177967 -148.962683) (xy 83.179117 -148.953348) (xy 83.178904 -148.948648) (xy 83.176872 -148.88591)
			(xy 83.177306 -148.843542) (xy 83.184492 -148.759112) (xy 83.198821 -148.675598) (xy 83.22019 -148.593601)
			(xy 83.248445 -148.513716) (xy 83.265518 -148.474938) (xy 83.269502 -148.464899) (xy 83.269506 -148.443319)
			(xy 83.265518 -148.433282) (xy 83.248474 -148.394493) (xy 83.220236 -148.314605) (xy 83.198872 -148.232611)
			(xy 83.184534 -148.149101) (xy 83.177326 -148.064676) (xy 83.176872 -148.02231) (xy 83.17738 -147.992846)
			(xy 83.177888 -147.978622) (xy 83.171284 -147.964398) (xy 83.16595 -147.95881) (xy 83.164934 -147.957794)
			(xy 83.141566 -147.933918) (xy 83.119468 -147.911312) (xy 83.113358 -147.906023) (xy 83.09874 -147.899158)
			(xy 83.090766 -147.89785) (xy 83.08467 -147.897596) (xy 82.73669 -147.897596) (xy 82.685381 -147.896914)
			(xy 82.58332 -147.88622) (xy 82.532982 -147.87626) (xy 82.520028 -147.873466) (xy 82.469444 -147.861406)
			(xy 82.37094 -147.828063) (xy 82.323432 -147.806918) (xy 82.323178 -147.806664) (xy 82.31886 -147.804632)
			(xy 82.316828 -147.80387) (xy 82.313272 -147.802346) (xy 82.312256 -147.801838) (xy 82.310986 -147.80133)
			(xy 82.291936 -147.791678) (xy 82.286405 -147.788981) (xy 82.274464 -147.786024) (xy 82.268314 -147.785836)
			(xy 82.256884 -147.785836) (xy 82.247184 -147.78626) (xy 82.229158 -147.793435) (xy 82.221832 -147.799806)
			(xy 82.190954 -147.828728) (xy 82.12508 -147.881828) (xy 82.054942 -147.929153) (xy 81.981046 -147.970365)
			(xy 81.903924 -148.005165) (xy 81.824129 -148.033304) (xy 81.742237 -148.054579) (xy 81.658836 -148.068837)
			(xy 81.574528 -148.075976) (xy 81.532222 -148.076412) (xy 81.485527 -148.075882) (xy 81.392544 -148.067179)
			(xy 81.300782 -148.049818) (xy 81.211046 -148.023953) (xy 81.124122 -147.989809) (xy 81.040771 -147.947685)
			(xy 80.961725 -147.897952) (xy 80.887677 -147.841045) (xy 80.819274 -147.777463) (xy 80.757118 -147.707762)
			(xy 80.701751 -147.632555) (xy 80.677258 -147.592796) (xy 80.67474 -147.588816) (xy 80.668476 -147.581785)
			(xy 80.664812 -147.578826) (xy 80.642425 -147.560853) (xy 80.602791 -147.51932) (xy 80.569826 -147.472319)
			(xy 80.544274 -147.42091) (xy 80.526711 -147.366253) (xy 80.517534 -147.309582) (xy 80.51673 -147.280884)
			(xy 80.51673 -147.27174) (xy 80.517544 -147.243465) (xy 80.526469 -147.187608) (xy 80.53451 -147.160488)
			(xy 80.535859 -147.155981) (xy 80.537009 -147.146646) (xy 80.536796 -147.141946) (xy 80.534764 -147.079208)
			(xy 80.535198 -147.03684) (xy 80.542384 -146.952411) (xy 80.556713 -146.868896) (xy 80.578082 -146.786899)
			(xy 80.606337 -146.707014) (xy 80.62341 -146.668236) (xy 80.627394 -146.658197) (xy 80.627397 -146.636618)
			(xy 80.62341 -146.62658) (xy 80.606366 -146.587791) (xy 80.578129 -146.507903) (xy 80.556765 -146.425908)
			(xy 80.542428 -146.342398) (xy 80.53522 -146.257974) (xy 80.534764 -146.215608) (xy 80.534833 -146.199722)
			(xy 80.53585 -146.167966) (xy 80.536796 -146.152108) (xy 80.53704 -146.14742) (xy 80.536018 -146.13809)
			(xy 80.534764 -146.133566) (xy 80.529176 -146.114516) (xy 80.524266 -146.094776) (xy 80.518152 -146.05456)
			(xy 80.516984 -146.034252) (xy 80.51673 -146.028156) (xy 80.51673 -146.01571) (xy 80.517432 -145.986833)
			(xy 80.526466 -145.929782) (xy 80.543983 -145.87474) (xy 80.569584 -145.822961) (xy 80.602685 -145.775624)
			(xy 80.642532 -145.733808) (xy 80.665066 -145.715736) (xy 80.668726 -145.712773) (xy 80.674981 -145.705737)
			(xy 80.677512 -145.701766) (xy 80.702036 -145.66205) (xy 80.757415 -145.586903) (xy 80.819572 -145.517257)
			(xy 80.887963 -145.453723) (xy 80.96199 -145.396855) (xy 81.041006 -145.347152) (xy 81.124319 -145.305047)
			(xy 81.211201 -145.270909) (xy 81.300893 -145.245036) (xy 81.392609 -145.227656) (xy 81.485548 -145.218919)
			(xy 81.532222 -145.218404) (xy 81.532476 -145.218404) (xy 81.574752 -145.218862) (xy 81.659 -145.226044)
			(xy 81.742337 -145.240332) (xy 81.824166 -145.261624) (xy 81.903898 -145.289767) (xy 81.980961 -145.32456)
			(xy 82.054802 -145.365751) (xy 82.12489 -145.413046) (xy 82.190723 -145.466105) (xy 82.221578 -145.49501)
			(xy 82.228899 -145.501393) (xy 82.246925 -145.508585) (xy 82.25663 -145.50898) (xy 83.12658 -145.50898)
			(xy 83.130644 -145.504916) (xy 83.148678 -145.485104) (xy 83.15198 -145.474944) (xy 83.159854 -145.45564)
			(xy 83.160362 -145.44802) (xy 83.161124 -145.440654) (xy 83.163397 -145.421938) (xy 83.171159 -145.38504)
			(xy 83.176618 -145.366994) (xy 83.177967 -145.362487) (xy 83.179118 -145.353152) (xy 83.178904 -145.348452)
			(xy 83.176872 -145.285714) (xy 83.177306 -145.243346) (xy 83.184491 -145.158916) (xy 83.19882 -145.075401)
			(xy 83.220189 -144.993405) (xy 83.248443 -144.913519) (xy 83.265518 -144.874742) (xy 83.269503 -144.864703)
			(xy 83.269508 -144.843123) (xy 83.265518 -144.833086) (xy 83.248474 -144.794297) (xy 83.220236 -144.714409)
			(xy 83.198871 -144.632415) (xy 83.184533 -144.548905) (xy 83.177325 -144.46448) (xy 83.176872 -144.422114)
			(xy 83.178904 -144.359376) (xy 83.179072 -144.354679) (xy 83.177918 -144.345351) (xy 83.176618 -144.340834)
			(xy 83.168282 -144.312673) (xy 83.159349 -144.254628) (xy 83.158838 -144.225264) (xy 83.158838 -144.222978)
			(xy 83.159362 -144.195399) (xy 83.1674 -144.140828) (xy 83.17484 -144.114266) (xy 83.175856 -144.110964)
			(xy 83.17865 -144.0942) (xy 83.177126 -144.085564) (xy 83.173062 -144.062196) (xy 83.171795 -144.055845)
			(xy 83.166518 -144.044021) (xy 83.162648 -144.038828) (xy 83.140296 -144.007332) (xy 83.12277 -143.98244)
			(xy 83.115912 -143.975836) (xy 83.115404 -143.975328) (xy 83.113372 -143.973804) (xy 83.018376 -143.973804)
			(xy 83.013356 -143.973894) (xy 83.003503 -143.975809) (xy 82.998818 -143.977614) (xy 82.679794 -144.109948)
			(xy 82.634426 -144.128061) (xy 82.54093 -144.156383) (xy 82.445113 -144.175435) (xy 82.347894 -144.185033)
			(xy 82.299048 -144.18564) (xy 82.246978 -144.18564) (xy 82.229198 -144.192752) (xy 82.221832 -144.199864)
			(xy 82.190959 -144.228799) (xy 82.125093 -144.281926) (xy 82.054962 -144.32928) (xy 81.98107 -144.370519)
			(xy 81.903948 -144.405348) (xy 81.824153 -144.433515) (xy 81.742257 -144.454818) (xy 81.65885 -144.469103)
			(xy 81.574533 -144.476268) (xy 81.532222 -144.476724) (xy 81.48554 -144.476181) (xy 81.392584 -144.467454)
			(xy 81.300851 -144.450075) (xy 81.211144 -144.424197) (xy 81.12425 -144.390045) (xy 81.040929 -144.347919)
			(xy 80.961911 -144.298188) (xy 80.887889 -144.241287) (xy 80.819511 -144.177715) (xy 80.757375 -144.108029)
			(xy 80.702027 -144.032839) (xy 80.677512 -143.993108) (xy 80.674919 -143.989127) (xy 80.668531 -143.982094)
			(xy 80.664812 -143.979138) (xy 80.642203 -143.960939) (xy 80.602225 -143.918866) (xy 80.569068 -143.871232)
			(xy 80.543494 -143.819133) (xy 80.526091 -143.763766) (xy 80.517258 -143.706404) (xy 80.51673 -143.677386)
			(xy 80.51673 -143.670274) (xy 80.517492 -143.651478) (xy 80.517746 -143.6497) (xy 80.517746 -143.647668)
			(xy 80.519016 -143.629634) (xy 80.51927 -143.62684) (xy 80.519778 -143.624046) (xy 80.522318 -143.611092)
			(xy 80.522572 -143.609568) (xy 80.524864 -143.597342) (xy 80.530836 -143.573192) (xy 80.53451 -143.561308)
			(xy 80.535872 -143.556739) (xy 80.537024 -143.547275) (xy 80.536796 -143.542512) (xy 80.535846 -143.526718)
			(xy 80.53483 -143.495089) (xy 80.534764 -143.479266) (xy 80.5352 -143.436899) (xy 80.542389 -143.35247)
			(xy 80.556722 -143.268957) (xy 80.578094 -143.186962) (xy 80.606351 -143.107078) (xy 80.62341 -143.068294)
			(xy 80.627385 -143.058255) (xy 80.627372 -143.036683) (xy 80.62341 -143.026638) (xy 80.606368 -142.987849)
			(xy 80.578134 -142.90796) (xy 80.556774 -142.825966) (xy 80.54244 -142.742456) (xy 80.535235 -142.658031)
			(xy 80.534764 -142.615666) (xy 80.534832 -142.59978) (xy 80.535847 -142.568024) (xy 80.536796 -142.552166)
			(xy 80.536963 -142.547469) (xy 80.535807 -142.538142) (xy 80.53451 -142.533624) (xy 80.526238 -142.505644)
			(xy 80.517305 -142.447987) (xy 80.51673 -142.418816) (xy 80.51673 -142.411704) (xy 80.51927 -142.37335)
			(xy 80.521556 -142.3543) (xy 80.52181 -142.352522) (xy 80.522318 -142.350236) (xy 80.527652 -142.326868)
			(xy 80.527652 -142.325598) (xy 80.528668 -142.322804) (xy 80.529684 -142.318994) (xy 80.529938 -142.317724)
			(xy 80.5307 -142.31493) (xy 80.534764 -142.301468) (xy 80.535018 -142.300706) (xy 80.535526 -142.29969)
			(xy 80.540098 -142.285212) (xy 80.54213 -142.280386) (xy 80.544162 -142.276068) (xy 80.547464 -142.26794)
			(xy 80.547718 -142.267686) (xy 80.548226 -142.265654) (xy 80.550258 -142.26159) (xy 80.563591 -142.233375)
			(xy 80.598048 -142.18135) (xy 80.640511 -142.135626) (xy 80.664812 -142.116048) (xy 80.668555 -142.113117)
			(xy 80.674946 -142.10608) (xy 80.677512 -142.102078) (xy 80.699921 -142.06561) (xy 80.750088 -141.99625)
			(xy 80.80602 -141.93145) (xy 80.867305 -141.871686) (xy 80.93349 -141.817399) (xy 81.004088 -141.76899)
			(xy 81.078578 -141.726814) (xy 81.156411 -141.691184) (xy 81.237014 -141.662362) (xy 81.319792 -141.64056)
			(xy 81.404135 -141.625939) (xy 81.489421 -141.618607) (xy 81.532222 -141.618208) (xy 81.574148 -141.618641)
			(xy 81.657704 -141.625683) (xy 81.740373 -141.639717) (xy 81.821572 -141.660643) (xy 81.900727 -141.688313)
			(xy 81.97728 -141.722532) (xy 82.050688 -141.763058) (xy 82.120435 -141.809604) (xy 82.153506 -141.835378)
			(xy 82.164428 -141.844268) (xy 82.191606 -141.848078) (xy 82.372454 -141.773148) (xy 82.417822 -141.755037)
			(xy 82.511319 -141.72672) (xy 82.607136 -141.707673) (xy 82.704355 -141.698079) (xy 82.7532 -141.697456)
			(xy 83.644232 -141.697456) (xy 83.693047 -141.698068) (xy 83.790207 -141.707653) (xy 83.885962 -141.726698)
			(xy 83.979395 -141.755021) (xy 84.024724 -141.773148) (xy 84.897976 -142.134844) (xy 84.901786 -142.136114)
			(xy 85.341206 -142.2781) (xy 85.38194 -142.291707) (xy 85.461096 -142.325041) (xy 85.537058 -142.365125)
			(xy 85.60925 -142.411656) (xy 85.643466 -142.437612) (xy 85.65515 -142.446502) (xy 85.666834 -142.45336)
			(xy 85.8012 -142.508986) (xy 85.846199 -142.528288) (xy 85.932526 -142.574505) (xy 86.013906 -142.628965)
			(xy 86.089552 -142.691143) (xy 86.124542 -142.725394) (xy 86.530434 -143.131286) (xy 86.53526 -143.135604)
			(xy 86.584028 -143.173704) (xy 87.177372 -143.638016) (xy 87.186576 -143.644454) (xy 87.20845 -143.649433)
			(xy 87.230372 -143.644665) (xy 87.239602 -143.63827) (xy 87.253318 -143.627856) (xy 87.262208 -143.594582)
			(xy 87.143082 -143.307054) (xy 87.136986 -143.298164) (xy 87.132668 -143.294354) (xy 87.116645 -143.279462)
			(xy 87.085774 -143.248461) (xy 87.070946 -143.232378) (xy 87.06993 -143.231362) (xy 87.038245 -143.197542)
			(xy 86.980599 -143.124967) (xy 86.929942 -143.047354) (xy 86.88671 -142.965372) (xy 86.868508 -142.922752)
			(xy 86.693502 -142.500096) (xy 86.678381 -142.462531) (xy 86.653554 -142.385447) (xy 86.635054 -142.306604)
			(xy 86.623004 -142.226522) (xy 86.619842 -142.186152) (xy 86.618974 -142.177851) (xy 86.612633 -142.162424)
			(xy 86.607396 -142.155926) (xy 86.580953 -142.125047) (xy 86.532604 -142.05968) (xy 86.489736 -141.990594)
			(xy 86.452633 -141.918249) (xy 86.436708 -141.880844) (xy 86.261702 -141.458188) (xy 86.246558 -141.420565)
			(xy 86.221703 -141.343357) (xy 86.203205 -141.264385) (xy 86.191185 -141.184171) (xy 86.188042 -141.143736)
			(xy 86.187172 -141.135436) (xy 86.180827 -141.120012) (xy 86.175596 -141.11351) (xy 86.149196 -141.082688)
			(xy 86.100924 -141.017441) (xy 86.058121 -140.948483) (xy 86.021072 -140.876271) (xy 86.005162 -140.838936)
			(xy 85.845142 -140.452348) (xy 85.841034 -140.443545) (xy 85.827458 -140.429675) (xy 85.818726 -140.425424)
			(xy 85.79231 -140.41374) (xy 85.782404 -140.409422) (xy 85.751162 -140.409422) (xy 85.743288 -140.412216)
			(xy 85.713619 -140.421592) (xy 85.652223 -140.431677) (xy 85.621114 -140.432282) (xy 85.620606 -140.432282)
			(xy 85.617812 -140.432282) (xy 85.590076 -140.431778) (xy 85.535189 -140.423735) (xy 85.482044 -140.407831)
			(xy 85.431762 -140.384402) (xy 85.385401 -140.35394) (xy 85.343938 -140.317088) (xy 85.308246 -140.274622)
			(xy 85.279078 -140.227436) (xy 85.257048 -140.176525) (xy 85.24262 -140.122961) (xy 85.238844 -140.095478)
			(xy 85.23732 -140.081762) (xy 85.23605 -140.050774) (xy 85.236555 -140.022961) (xy 85.244632 -139.967923)
			(xy 85.260611 -139.914641) (xy 85.284154 -139.864242) (xy 85.314763 -139.817794) (xy 85.351789 -139.77628)
			(xy 85.394448 -139.740579) (xy 85.441837 -139.711448) (xy 85.46719 -139.7) (xy 85.471 -139.69873)
			(xy 85.481733 -139.694036) (xy 85.497676 -139.676909) (xy 85.504366 -139.654487) (xy 85.503004 -139.64285)
			(xy 85.501988 -139.638278) (xy 85.500464 -139.633198) (xy 85.48116 -139.587224) (xy 85.445346 -139.501626)
			(xy 85.390482 -139.370562) (xy 85.390228 -139.370054) (xy 85.386926 -139.362434) (xy 85.386926 -139.36218)
			(xy 85.383116 -139.352782) (xy 85.381084 -139.347702) (xy 85.374734 -139.331192) (xy 85.374734 -139.330938)
			(xy 85.367876 -139.31265) (xy 85.367622 -139.311888) (xy 85.367368 -139.310364) (xy 85.359748 -139.287504)
			(xy 85.35268 -139.264657) (xy 85.340483 -139.218409) (xy 85.335364 -139.195048) (xy 85.329131 -139.164904)
			(xy 85.319978 -139.104027) (xy 85.317076 -139.073382) (xy 85.317076 -139.07135) (xy 85.316568 -139.067286)
			(xy 85.315552 -139.052554) (xy 85.315044 -139.043918) (xy 85.305646 -139.021566) (xy 85.30082 -139.015724)
			(xy 85.289674 -139.002402) (xy 85.268206 -138.975091) (xy 85.257894 -138.961114) (xy 85.256878 -138.95959)
			(xy 85.243931 -138.943036) (xy 85.219283 -138.908989) (xy 85.207602 -138.891518) (xy 85.20684 -138.889994)
			(xy 85.187736 -138.860425) (xy 85.15329 -138.799024) (xy 85.138006 -138.767312) (xy 85.135466 -138.761978)
			(xy 85.128862 -138.753342) (xy 85.12302 -138.748516) (xy 85.122766 -138.748262) (xy 85.099906 -138.729212)
			(xy 85.089238 -138.726164) (xy 85.062559 -138.71821) (xy 85.011669 -138.695645) (xy 84.964594 -138.665929)
			(xy 84.922333 -138.629693) (xy 84.885781 -138.587704) (xy 84.855714 -138.540854) (xy 84.832768 -138.490134)
			(xy 84.82457 -138.463528) (xy 84.817961 -138.438961) (xy 84.810566 -138.388628) (xy 84.809838 -138.363198)
			(xy 84.809838 -138.358118) (xy 84.810346 -138.329915) (xy 84.818658 -138.274125) (xy 84.835104 -138.22017)
			(xy 84.859323 -138.169228) (xy 84.874608 -138.14552) (xy 84.878672 -138.139424) (xy 84.888324 -138.109706)
			(xy 84.886292 -138.097514) (xy 84.882758 -138.074833) (xy 84.877548 -138.029222) (xy 84.875878 -138.006328)
			(xy 84.875624 -138.001502) (xy 84.87283 -137.991088) (xy 84.871814 -137.986262) (xy 84.862162 -137.963402)
			(xy 84.856066 -137.957052) (xy 84.838392 -137.937023) (xy 84.804972 -137.895345) (xy 84.789264 -137.87374)
			(xy 84.785708 -137.868406) (xy 84.7852 -137.867898) (xy 84.760816 -137.831576) (xy 84.738166 -137.79535)
			(xy 84.698484 -137.719679) (xy 84.681568 -137.680446) (xy 84.510626 -137.272776) (xy 84.502906 -137.254174)
			(xy 84.488806 -137.216443) (xy 84.482432 -137.197338) (xy 84.479384 -137.18794) (xy 84.46135 -137.16635)
			(xy 84.458253 -137.162782) (xy 84.450964 -137.156774) (xy 84.446872 -137.154412) (xy 84.439506 -137.150348)
			(xy 84.43214 -137.146284) (xy 84.41436 -137.143744) (xy 84.404454 -137.14603) (xy 84.366708 -137.154634)
			(xy 84.290227 -137.166683) (xy 84.213042 -137.172774) (xy 84.17433 -137.173208) (xy 84.127648 -137.172665)
			(xy 84.034691 -137.163939) (xy 83.942958 -137.146561) (xy 83.853252 -137.120682) (xy 83.766357 -137.08653)
			(xy 83.683036 -137.044404) (xy 83.604019 -136.994673) (xy 83.529997 -136.937772) (xy 83.461618 -136.8742)
			(xy 83.399483 -136.804513) (xy 83.344135 -136.729323) (xy 83.31962 -136.689592) (xy 83.317026 -136.685611)
			(xy 83.310638 -136.67858) (xy 83.30692 -136.675622) (xy 83.284311 -136.657423) (xy 83.244335 -136.615349)
			(xy 83.211179 -136.567715) (xy 83.185607 -136.515616) (xy 83.168205 -136.460249) (xy 83.159375 -136.402888)
			(xy 83.158838 -136.37387) (xy 83.158838 -136.366758) (xy 83.1596 -136.347962) (xy 83.159854 -136.346184)
			(xy 83.159854 -136.344152) (xy 83.161124 -136.326118) (xy 83.161378 -136.323324) (xy 83.161886 -136.32053)
			(xy 83.164426 -136.307576) (xy 83.16468 -136.306052) (xy 83.166972 -136.293826) (xy 83.172945 -136.269677)
			(xy 83.176618 -136.257792) (xy 83.177979 -136.253222) (xy 83.179127 -136.243759) (xy 83.178904 -136.238996)
			(xy 83.177954 -136.223202) (xy 83.176939 -136.191573) (xy 83.176872 -136.17575) (xy 83.177304 -136.133382)
			(xy 83.184487 -136.048951) (xy 83.198813 -135.965435) (xy 83.220179 -135.883437) (xy 83.248431 -135.80355)
			(xy 83.265518 -135.764778) (xy 83.26951 -135.754738) (xy 83.26953 -135.733152) (xy 83.265518 -135.723122)
			(xy 83.248482 -135.684357) (xy 83.220254 -135.604518) (xy 83.198891 -135.522576) (xy 83.184546 -135.439118)
			(xy 83.177321 -135.354745) (xy 83.176872 -135.312404) (xy 83.176872 -135.311896) (xy 83.17738 -135.28548)
			(xy 83.17738 -135.284972) (xy 83.177888 -135.26516) (xy 83.173316 -135.259318) (xy 83.138518 -135.223504)
			(xy 83.13801 -135.222996) (xy 83.119722 -135.204708) (xy 83.115994 -135.201183) (xy 83.107423 -135.195546)
			(xy 83.102704 -135.193532) (xy 83.094068 -135.189976) (xy 82.821526 -135.189976) (xy 82.790965 -135.189726)
			(xy 82.729961 -135.18591) (xy 82.699606 -135.182356) (xy 82.699098 -135.182356) (xy 82.652536 -135.181818)
			(xy 82.559817 -135.173138) (xy 82.46831 -135.155853) (xy 82.378813 -135.130114) (xy 82.292105 -135.096146)
			(xy 82.25028 -135.075676) (xy 82.236056 -135.075676) (xy 82.204975 -135.106004) (xy 82.138377 -135.161747)
			(xy 82.067185 -135.211489) (xy 81.991937 -135.254851) (xy 81.913204 -135.291507) (xy 81.831582 -135.321178)
			(xy 81.747689 -135.343639) (xy 81.662161 -135.358721) (xy 81.575646 -135.366309) (xy 81.532222 -135.36676)
			(xy 81.48554 -135.366217) (xy 81.392585 -135.35749) (xy 81.300853 -135.34011) (xy 81.211148 -135.31423)
			(xy 81.124256 -135.280077) (xy 81.040937 -135.237949) (xy 80.961921 -135.188216) (xy 80.887902 -135.131314)
			(xy 80.819527 -135.06774) (xy 80.757395 -134.998052) (xy 80.702051 -134.92286) (xy 80.677512 -134.883144)
			(xy 80.674916 -134.879166) (xy 80.668523 -134.87214) (xy 80.664812 -134.869174) (xy 80.642206 -134.850974)
			(xy 80.602236 -134.808898) (xy 80.569087 -134.761263) (xy 80.543521 -134.709164) (xy 80.526127 -134.653798)
			(xy 80.517304 -134.596439) (xy 80.51673 -134.567422) (xy 80.51673 -134.56031) (xy 80.517492 -134.541514)
			(xy 80.517746 -134.539736) (xy 80.517746 -134.537704) (xy 80.519016 -134.51967) (xy 80.51927 -134.516876)
			(xy 80.519778 -134.514082) (xy 80.522318 -134.501128) (xy 80.522572 -134.499604) (xy 80.524866 -134.487378)
			(xy 80.530842 -134.46323) (xy 80.53451 -134.451344) (xy 80.535876 -134.446775) (xy 80.537034 -134.43731)
			(xy 80.536796 -134.432548) (xy 80.535846 -134.416754) (xy 80.534829 -134.385125) (xy 80.534764 -134.369302)
			(xy 80.535198 -134.326934) (xy 80.542385 -134.242505) (xy 80.556715 -134.15899) (xy 80.578084 -134.076994)
			(xy 80.606339 -133.997109) (xy 80.62341 -133.95833) (xy 80.627393 -133.948291) (xy 80.627394 -133.926713)
			(xy 80.62341 -133.916674) (xy 80.606366 -133.877885) (xy 80.57813 -133.797997) (xy 80.556766 -133.716002)
			(xy 80.542429 -133.632492) (xy 80.535222 -133.548068) (xy 80.534764 -133.505702) (xy 80.534833 -133.489816)
			(xy 80.53585 -133.45806) (xy 80.536796 -133.442202) (xy 80.536967 -133.437504) (xy 80.535817 -133.428176)
			(xy 80.53451 -133.42366) (xy 80.526243 -133.395679) (xy 80.51732 -133.338023) (xy 80.51673 -133.308852)
			(xy 80.51673 -133.30174) (xy 80.51927 -133.263386) (xy 80.521556 -133.244336) (xy 80.52181 -133.242558)
			(xy 80.522318 -133.240272) (xy 80.527652 -133.216904) (xy 80.527652 -133.215634) (xy 80.528668 -133.21284)
			(xy 80.529684 -133.20903) (xy 80.529938 -133.20776) (xy 80.5307 -133.204966) (xy 80.534764 -133.191504)
			(xy 80.535018 -133.190742) (xy 80.535526 -133.189726) (xy 80.540098 -133.175248) (xy 80.543146 -133.168644)
			(xy 80.5434 -133.168136) (xy 80.54721 -133.158738) (xy 80.548226 -133.15569) (xy 80.550258 -133.151626)
			(xy 80.560727 -133.129211) (xy 80.586606 -133.087048) (xy 80.617706 -133.048573) (xy 80.635348 -133.03123)
			(xy 80.664812 -133.00583) (xy 80.668554 -133.002898) (xy 80.674943 -132.99586) (xy 80.677512 -132.99186)
			(xy 80.702023 -132.952128) (xy 80.757382 -132.876947) (xy 80.819525 -132.80727) (xy 80.887907 -132.743704)
			(xy 80.96193 -132.686808) (xy 81.040947 -132.637078) (xy 81.124265 -132.59495) (xy 81.211156 -132.560794)
			(xy 81.300858 -132.534907) (xy 81.392588 -132.517516) (xy 81.485541 -132.508775) (xy 81.532222 -132.508244)
			(xy 81.574518 -132.508701) (xy 81.658805 -132.515886) (xy 81.742181 -132.530187) (xy 81.824045 -132.551499)
			(xy 81.903809 -132.579671) (xy 81.980899 -132.614498) (xy 82.054762 -132.655732) (xy 82.124867 -132.703075)
			(xy 82.190708 -132.756186) (xy 82.221578 -132.785104) (xy 82.22888 -132.79154) (xy 82.246907 -132.798833)
			(xy 82.25663 -132.799328) (xy 83.126072 -132.799328) (xy 83.128612 -132.797042) (xy 83.131152 -132.794502)
			(xy 83.142836 -132.781294) (xy 83.1469 -132.776722) (xy 83.152488 -132.770372) (xy 83.159346 -132.754116)
			(xy 83.159854 -132.745226) (xy 83.161446 -132.726308) (xy 83.167936 -132.688899) (xy 83.172808 -132.67055)
			(xy 83.172808 -132.670042) (xy 83.177634 -132.65404) (xy 83.177634 -132.653532) (xy 83.179666 -132.64769)
			(xy 83.178399 -132.629746) (xy 83.177003 -132.593796) (xy 83.176872 -132.575808) (xy 83.177306 -132.53344)
			(xy 83.184492 -132.449011) (xy 83.198821 -132.365496) (xy 83.220191 -132.2835) (xy 83.248445 -132.203614)
			(xy 83.265518 -132.164836) (xy 83.269502 -132.154797) (xy 83.269505 -132.133218) (xy 83.265518 -132.12318)
			(xy 83.248483 -132.084415) (xy 83.220259 -132.004576) (xy 83.198899 -131.922633) (xy 83.184558 -131.839175)
			(xy 83.177337 -131.754802) (xy 83.176872 -131.712462) (xy 83.176872 -131.711954) (xy 83.17738 -131.685538)
			(xy 83.17738 -131.68503) (xy 83.177888 -131.665726) (xy 83.171538 -131.657344) (xy 83.138518 -131.623308)
			(xy 83.13801 -131.6228) (xy 83.119722 -131.604512) (xy 83.115994 -131.600987) (xy 83.107423 -131.595349)
			(xy 83.102704 -131.593336) (xy 83.094068 -131.58978) (xy 82.826352 -131.58978) (xy 82.779606 -131.589213)
			(xy 82.686535 -131.580336) (xy 82.59472 -131.562705) (xy 82.504981 -131.536478) (xy 82.418122 -131.501888)
			(xy 82.376264 -131.481068) (xy 82.370837 -131.478486) (xy 82.359157 -131.475662) (xy 82.35315 -131.47548)
			(xy 82.246978 -131.47548) (xy 82.229198 -131.482592) (xy 82.221832 -131.489704) (xy 82.19096 -131.518641)
			(xy 82.125095 -131.571771) (xy 82.054965 -131.619127) (xy 81.981073 -131.660369) (xy 81.903951 -131.6952)
			(xy 81.824155 -131.723369) (xy 81.742259 -131.744673) (xy 81.658851 -131.758959) (xy 81.574533 -131.766125)
			(xy 81.532222 -131.766564) (xy 81.48554 -131.766021) (xy 81.392585 -131.757294) (xy 81.300853 -131.739914)
			(xy 81.211148 -131.714035) (xy 81.124255 -131.679881) (xy 81.040936 -131.637754) (xy 80.961921 -131.588021)
			(xy 80.887901 -131.531118) (xy 80.819526 -131.467545) (xy 80.757394 -131.397857) (xy 80.702049 -131.322665)
			(xy 80.677512 -131.282948) (xy 80.674916 -131.27897) (xy 80.668524 -131.271943) (xy 80.664812 -131.268978)
			(xy 80.642206 -131.250778) (xy 80.602235 -131.208703) (xy 80.569086 -131.161068) (xy 80.54352 -131.108968)
			(xy 80.526125 -131.053602) (xy 80.517301 -130.996243) (xy 80.51673 -130.967226) (xy 80.51673 -130.960114)
			(xy 80.51726 -130.940453) (xy 80.521842 -130.901387) (xy 80.525874 -130.882136) (xy 80.528922 -130.870452)
			(xy 80.53578 -130.847846) (xy 80.53578 -130.847338) (xy 80.537558 -130.842258) (xy 80.536269 -130.823997)
			(xy 80.534871 -130.787412) (xy 80.534764 -130.769106) (xy 80.535198 -130.726738) (xy 80.542384 -130.642309)
			(xy 80.556714 -130.558794) (xy 80.578083 -130.476798) (xy 80.606338 -130.396912) (xy 80.62341 -130.358134)
			(xy 80.627394 -130.348095) (xy 80.627396 -130.326516) (xy 80.62341 -130.316478) (xy 80.606366 -130.277689)
			(xy 80.578129 -130.197801) (xy 80.556765 -130.115806) (xy 80.542428 -130.032296) (xy 80.535221 -129.947872)
			(xy 80.534764 -129.905506) (xy 80.534833 -129.88962) (xy 80.53585 -129.857864) (xy 80.536796 -129.842006)
			(xy 80.536967 -129.837308) (xy 80.535818 -129.827979) (xy 80.53451 -129.823464) (xy 80.526243 -129.795483)
			(xy 80.517319 -129.737827) (xy 80.51673 -129.708656) (xy 80.51673 -129.701544) (xy 80.517215 -129.68473)
			(xy 80.520774 -129.65128) (xy 80.523842 -129.634742) (xy 80.523842 -129.634488) (xy 80.526128 -129.624582)
			(xy 80.526128 -129.624074) (xy 80.532478 -129.599944) (xy 80.532478 -129.599436) (xy 80.534002 -129.59334)
			(xy 80.543218 -129.565773) (xy 80.568823 -129.513594) (xy 80.602051 -129.465906) (xy 80.642133 -129.423814)
			(xy 80.664812 -129.405634) (xy 80.668554 -129.402702) (xy 80.674944 -129.395665) (xy 80.677512 -129.391664)
			(xy 80.702023 -129.351932) (xy 80.757382 -129.276751) (xy 80.819524 -129.207073) (xy 80.887906 -129.143507)
			(xy 80.96193 -129.086611) (xy 81.040946 -129.036881) (xy 81.124265 -128.994753) (xy 81.211155 -128.960596)
			(xy 81.300858 -128.934709) (xy 81.392587 -128.917319) (xy 81.48554 -128.908577) (xy 81.532222 -128.908048)
			(xy 81.574518 -128.908505) (xy 81.658805 -128.91569) (xy 81.742181 -128.929991) (xy 81.824045 -128.951303)
			(xy 81.903809 -128.979475) (xy 81.980899 -129.014303) (xy 82.054762 -129.055536) (xy 82.124866 -129.102879)
			(xy 82.190707 -129.155991) (xy 82.221578 -129.184908) (xy 82.22888 -129.191343) (xy 82.246907 -129.198636)
			(xy 82.25663 -129.199132) (xy 84.260182 -129.199132) (xy 84.309162 -129.199713) (xy 84.406652 -129.209315)
			(xy 84.50273 -129.228427) (xy 84.596472 -129.256865) (xy 84.641944 -129.275078) (xy 85.67166 -129.701544)
			(xy 85.681051 -129.704889) (xy 85.700967 -129.704886) (xy 85.719384 -129.697307) (xy 85.726778 -129.690622)
			(xy 85.7377 -129.6797) (xy 85.743796 -129.649474) (xy 85.732366 -129.62255) (xy 85.717272 -129.585643)
			(xy 85.692331 -129.5099) (xy 85.673519 -129.432407) (xy 85.660956 -129.353658) (xy 85.657436 -129.31394)
			(xy 85.656482 -129.305836) (xy 85.650128 -129.290816) (xy 85.64499 -129.284476) (xy 85.618859 -129.254124)
			(xy 85.570999 -129.189896) (xy 85.528456 -129.122031) (xy 85.491504 -129.050966) (xy 85.475572 -129.01422)
			(xy 85.298026 -128.59258) (xy 85.282932 -128.555673) (xy 85.257989 -128.47993) (xy 85.239175 -128.402437)
			(xy 85.226611 -128.323689) (xy 85.223096 -128.28397) (xy 85.222146 -128.275865) (xy 85.215794 -128.260842)
			(xy 85.21065 -128.254506) (xy 85.184517 -128.224155) (xy 85.136653 -128.15993) (xy 85.094105 -128.092066)
			(xy 85.057149 -128.021002) (xy 85.041232 -127.98425) (xy 84.863686 -127.56261) (xy 84.846705 -127.520901)
			(xy 84.81945 -127.435063) (xy 84.800042 -127.347118) (xy 84.793836 -127.302514) (xy 84.791296 -127.292608)
			(xy 84.777016 -127.249085) (xy 84.755623 -127.160011) (xy 84.742559 -127.069341) (xy 84.739734 -127.023622)
			(xy 84.739226 -127.01397) (xy 84.738982 -127.009605) (xy 84.737197 -127.001048) (xy 84.73567 -126.996952)
			(xy 84.718339 -126.952883) (xy 84.691112 -126.862179) (xy 84.681314 -126.81585) (xy 84.51342 -125.971046)
			(xy 84.513166 -125.970792) (xy 84.453222 -125.932946) (xy 84.447126 -125.929136) (xy 84.440014 -125.927104)
			(xy 84.421726 -125.93193) (xy 84.381248 -125.941856) (xy 84.299062 -125.95574) (xy 84.216005 -125.962719)
			(xy 84.17433 -125.963172) (xy 84.127648 -125.962629) (xy 84.034692 -125.953903) (xy 83.94296 -125.936524)
			(xy 83.853254 -125.910645) (xy 83.76636 -125.876492) (xy 83.68304 -125.834365) (xy 83.604024 -125.784633)
			(xy 83.530004 -125.727731) (xy 83.461627 -125.664158) (xy 83.399494 -125.59447) (xy 83.344149 -125.519279)
			(xy 83.31962 -125.479556) (xy 83.317024 -125.475577) (xy 83.310634 -125.468549) (xy 83.30692 -125.465586)
			(xy 83.284313 -125.447386) (xy 83.244341 -125.405312) (xy 83.21119 -125.357677) (xy 83.185622 -125.305577)
			(xy 83.168226 -125.250211) (xy 83.159401 -125.192851) (xy 83.158838 -125.163834) (xy 83.158838 -125.156722)
			(xy 83.159368 -125.137061) (xy 83.163949 -125.097995) (xy 83.167982 -125.078744) (xy 83.17103 -125.06706)
			(xy 83.177888 -125.044454) (xy 83.177888 -125.043946) (xy 83.179666 -125.038866) (xy 83.178377 -125.020605)
			(xy 83.176978 -124.98402) (xy 83.176872 -124.965714) (xy 83.177306 -124.923346) (xy 83.184491 -124.838916)
			(xy 83.19882 -124.755401) (xy 83.220189 -124.673405) (xy 83.248443 -124.593519) (xy 83.265518 -124.554742)
			(xy 83.269503 -124.544703) (xy 83.269508 -124.523123) (xy 83.265518 -124.513086) (xy 83.248474 -124.474297)
			(xy 83.220236 -124.394409) (xy 83.198871 -124.312415) (xy 83.184533 -124.228905) (xy 83.177325 -124.14448)
			(xy 83.176872 -124.102114) (xy 83.178904 -124.039122) (xy 83.179076 -124.034424) (xy 83.17793 -124.025094)
			(xy 83.176618 -124.02058) (xy 83.171884 -124.004992) (xy 83.164766 -123.973198) (xy 83.162394 -123.95708)
			(xy 83.16214 -123.955556) (xy 83.160504 -123.946276) (xy 83.151387 -123.929801) (xy 83.136912 -123.917757)
			(xy 83.128104 -123.914408) (xy 83.100698 -123.904805) (xy 83.046943 -123.882819) (xy 83.020662 -123.870466)
			(xy 83.015488 -123.868204) (xy 83.004464 -123.865765) (xy 82.998818 -123.86564) (xy 82.25663 -123.86564)
			(xy 82.246906 -123.866117) (xy 82.228875 -123.87342) (xy 82.221578 -123.879864) (xy 82.19071 -123.908783)
			(xy 82.12486 -123.96188) (xy 82.054751 -124.009211) (xy 81.980886 -124.050436) (xy 81.903795 -124.085259)
			(xy 81.824033 -124.11343) (xy 81.742173 -124.134746) (xy 81.658801 -124.149054) (xy 81.574517 -124.156252)
			(xy 81.532222 -124.156724) (xy 81.48554 -124.156181) (xy 81.392584 -124.147454) (xy 81.300851 -124.130075)
			(xy 81.211144 -124.104197) (xy 81.12425 -124.070045) (xy 81.040929 -124.027919) (xy 80.961911 -123.978188)
			(xy 80.887889 -123.921287) (xy 80.819511 -123.857715) (xy 80.757375 -123.788029) (xy 80.702027 -123.712839)
			(xy 80.677512 -123.673108) (xy 80.674919 -123.669127) (xy 80.668531 -123.662094) (xy 80.664812 -123.659138)
			(xy 80.642203 -123.640939) (xy 80.602225 -123.598866) (xy 80.569068 -123.551232) (xy 80.543494 -123.499133)
			(xy 80.526091 -123.443766) (xy 80.517258 -123.386404) (xy 80.51673 -123.357386) (xy 80.51673 -123.350274)
			(xy 80.517262 -123.330613) (xy 80.521848 -123.291548) (xy 80.525874 -123.272296) (xy 80.528922 -123.260612)
			(xy 80.53578 -123.238006) (xy 80.53578 -123.237498) (xy 80.537558 -123.232418) (xy 80.53627 -123.214157)
			(xy 80.534873 -123.177572) (xy 80.534764 -123.159266) (xy 80.5352 -123.116899) (xy 80.542389 -123.03247)
			(xy 80.556722 -122.948957) (xy 80.578094 -122.866962) (xy 80.606351 -122.787078) (xy 80.62341 -122.748294)
			(xy 80.627385 -122.738255) (xy 80.627372 -122.716683) (xy 80.62341 -122.706638) (xy 80.606368 -122.667849)
			(xy 80.578134 -122.58796) (xy 80.556774 -122.505966) (xy 80.54244 -122.422456) (xy 80.535235 -122.338031)
			(xy 80.534764 -122.295666) (xy 80.534832 -122.27978) (xy 80.535847 -122.248024) (xy 80.536796 -122.232166)
			(xy 80.536963 -122.227469) (xy 80.535807 -122.218142) (xy 80.53451 -122.213624) (xy 80.526238 -122.185644)
			(xy 80.517305 -122.127987) (xy 80.51673 -122.098816) (xy 80.51673 -122.091704) (xy 80.517217 -122.074891)
			(xy 80.520779 -122.041441) (xy 80.523842 -122.024902) (xy 80.523842 -122.024648) (xy 80.526128 -122.014742)
			(xy 80.526128 -122.014234) (xy 80.532478 -121.990104) (xy 80.532478 -121.989596) (xy 80.534002 -121.9835)
			(xy 80.54322 -121.955935) (xy 80.568829 -121.903759) (xy 80.602061 -121.856075) (xy 80.642144 -121.813987)
			(xy 80.664812 -121.795794) (xy 80.668557 -121.792865) (xy 80.674954 -121.785832) (xy 80.677512 -121.781824)
			(xy 80.702024 -121.742093) (xy 80.757385 -121.666915) (xy 80.819528 -121.59724) (xy 80.887911 -121.533676)
			(xy 80.961935 -121.476782) (xy 81.040951 -121.427054) (xy 81.124269 -121.384928) (xy 81.211159 -121.350773)
			(xy 81.300861 -121.324887) (xy 81.392589 -121.307497) (xy 81.485541 -121.298756) (xy 81.532222 -121.298208)
			(xy 81.574518 -121.298665) (xy 81.658805 -121.305851) (xy 81.742179 -121.320152) (xy 81.824042 -121.341465)
			(xy 81.903805 -121.369638) (xy 81.980895 -121.404468) (xy 82.054756 -121.445703) (xy 82.124858 -121.493048)
			(xy 82.190697 -121.546162) (xy 82.221578 -121.575068) (xy 82.228878 -121.581507) (xy 82.246906 -121.588806)
			(xy 82.25663 -121.589292) (xy 83.126072 -121.589292) (xy 83.128612 -121.587006) (xy 83.131152 -121.584466)
			(xy 83.142836 -121.571258) (xy 83.1469 -121.566686) (xy 83.152488 -121.560336) (xy 83.159346 -121.54408)
			(xy 83.159854 -121.53519) (xy 83.161448 -121.516272) (xy 83.167941 -121.478864) (xy 83.172808 -121.460514)
			(xy 83.172808 -121.460006) (xy 83.177634 -121.444004) (xy 83.177634 -121.443496) (xy 83.179666 -121.437654)
			(xy 83.178398 -121.41971) (xy 83.176999 -121.38376) (xy 83.176872 -121.365772) (xy 83.177308 -121.323405)
			(xy 83.184497 -121.238976) (xy 83.198829 -121.155462) (xy 83.220201 -121.073467) (xy 83.248458 -120.993583)
			(xy 83.265518 -120.9548) (xy 83.269494 -120.944761) (xy 83.269483 -120.923188) (xy 83.265518 -120.913144)
			(xy 83.248475 -120.874355) (xy 83.220241 -120.794466) (xy 83.19888 -120.712472) (xy 83.184545 -120.628962)
			(xy 83.17734 -120.544537) (xy 83.176872 -120.502172) (xy 83.17738 -120.472962) (xy 83.177888 -120.458484)
			(xy 83.175856 -120.453912) (xy 83.1723 -120.446038) (xy 83.131914 -120.40235) (xy 83.12531 -120.395238)
			(xy 83.090766 -120.378474) (xy 83.08086 -120.377712) (xy 83.03256 -120.373835) (xy 82.936984 -120.357841)
			(xy 82.843428 -120.332588) (xy 82.797904 -120.31599) (xy 82.79765 -120.315736) (xy 82.787744 -120.311926)
			(xy 82.744564 -120.294146) (xy 82.743548 -120.293638) (xy 82.691986 -120.270778) (xy 82.691478 -120.270778)
			(xy 82.681318 -120.265952) (xy 82.25663 -120.265952) (xy 82.246932 -120.266383) (xy 82.228913 -120.273563)
			(xy 82.221578 -120.279922) (xy 82.190721 -120.308826) (xy 82.124895 -120.361897) (xy 82.05481 -120.409201)
			(xy 81.980971 -120.4504) (xy 81.903907 -120.485198) (xy 81.824174 -120.513344) (xy 81.742344 -120.534636)
			(xy 81.659004 -120.548921) (xy 81.574754 -120.556097) (xy 81.532476 -120.556528) (xy 81.532222 -120.556528)
			(xy 81.485531 -120.555981) (xy 81.392559 -120.547247) (xy 81.300809 -120.529863) (xy 81.211086 -120.503981)
			(xy 81.124174 -120.469828) (xy 81.040834 -120.427703) (xy 80.961795 -120.377973) (xy 80.887749 -120.321076)
			(xy 80.819345 -120.257507) (xy 80.75718 -120.187824) (xy 80.701799 -120.112637) (xy 80.677258 -120.072912)
			(xy 80.674736 -120.068936) (xy 80.668464 -120.061915) (xy 80.664812 -120.058942) (xy 80.642424 -120.040969)
			(xy 80.602789 -119.999437) (xy 80.569822 -119.952436) (xy 80.544267 -119.901027) (xy 80.526702 -119.84637)
			(xy 80.517523 -119.789698) (xy 80.51673 -119.761) (xy 80.51673 -119.751856) (xy 80.517543 -119.72358)
			(xy 80.526465 -119.667723) (xy 80.53451 -119.640604) (xy 80.53586 -119.636097) (xy 80.537013 -119.626761)
			(xy 80.536796 -119.622062) (xy 80.534764 -119.559324) (xy 80.535197 -119.516956) (xy 80.542382 -119.432526)
			(xy 80.55671 -119.349011) (xy 80.578078 -119.267014) (xy 80.606331 -119.187127) (xy 80.62341 -119.148352)
			(xy 80.627398 -119.138313) (xy 80.627407 -119.116731) (xy 80.62341 -119.106696) (xy 80.606365 -119.067907)
			(xy 80.578127 -118.988019) (xy 80.556762 -118.906025) (xy 80.542423 -118.822515) (xy 80.535214 -118.73809)
			(xy 80.534764 -118.695724) (xy 80.534833 -118.679838) (xy 80.535849 -118.648082) (xy 80.536796 -118.632224)
			(xy 80.537042 -118.627536) (xy 80.536023 -118.618205) (xy 80.534764 -118.613682) (xy 80.5307 -118.60022)
			(xy 80.52514 -118.579151) (xy 80.518261 -118.536121) (xy 80.516984 -118.514368) (xy 80.51673 -118.508272)
			(xy 80.51673 -118.495826) (xy 80.517438 -118.466952) (xy 80.526483 -118.409908) (xy 80.544009 -118.354874)
			(xy 80.569616 -118.303105) (xy 80.602722 -118.255778) (xy 80.642572 -118.213971) (xy 80.665066 -118.195852)
			(xy 80.668726 -118.19289) (xy 80.674984 -118.185855) (xy 80.677512 -118.181882) (xy 80.702035 -118.142165)
			(xy 80.757414 -118.067017) (xy 80.81957 -117.997371) (xy 80.887961 -117.933835) (xy 80.961988 -117.876967)
			(xy 81.041004 -117.827262) (xy 81.124317 -117.785157) (xy 81.2112 -117.751018) (xy 81.300892 -117.725145)
			(xy 81.392608 -117.707764) (xy 81.485548 -117.699027) (xy 81.532222 -117.69852) (xy 81.532476 -117.69852)
			(xy 81.574752 -117.698978) (xy 81.659 -117.70616) (xy 81.742337 -117.720448) (xy 81.824165 -117.741741)
			(xy 81.903897 -117.769884) (xy 81.98096 -117.804677) (xy 82.0548 -117.845869) (xy 82.124888 -117.893164)
			(xy 82.190721 -117.946224) (xy 82.221578 -117.975126) (xy 82.228896 -117.981518) (xy 82.246922 -117.988722)
			(xy 82.25663 -117.989096) (xy 84.221828 -117.989096) (xy 84.263791 -117.989538) (xy 84.347418 -117.996609)
			(xy 84.430155 -118.010681) (xy 84.511417 -118.031656) (xy 84.59063 -118.059384) (xy 84.667233 -118.09367)
			(xy 84.740684 -118.134271) (xy 84.775802 -118.157244) (xy 85.240782 -118.467886) (xy 97.482404 -118.467886)
			(xy 97.486475 -118.412264) (xy 97.498601 -118.357827) (xy 97.518524 -118.305736) (xy 97.54582 -118.257101)
			(xy 97.579906 -118.212958) (xy 97.620055 -118.174249) (xy 97.665413 -118.141798) (xy 97.715013 -118.116297)
			(xy 97.767797 -118.09829) (xy 97.82264 -118.08816) (xy 97.878374 -118.086123) (xy 97.933811 -118.092223)
			(xy 97.987768 -118.106329) (xy 98.039097 -118.128141) (xy 98.086703 -118.157195) (xy 98.129571 -118.19287)
			(xy 98.166788 -118.234407) (xy 98.197561 -118.28092) (xy 98.221233 -118.331417) (xy 98.237301 -118.384824)
			(xy 98.245421 -118.44) (xy 98.24593 -118.467886) (xy 98.245421 -118.495772) (xy 98.237301 -118.550948)
			(xy 98.221233 -118.604355) (xy 98.197561 -118.654852) (xy 98.166788 -118.701365) (xy 98.129571 -118.742902)
			(xy 98.108737 -118.76024) (xy 102.564436 -118.76024) (xy 102.568507 -118.704618) (xy 102.580633 -118.650181)
			(xy 102.600556 -118.59809) (xy 102.627852 -118.549455) (xy 102.661938 -118.505312) (xy 102.702087 -118.466603)
			(xy 102.747445 -118.434152) (xy 102.797045 -118.408651) (xy 102.849829 -118.390644) (xy 102.904672 -118.380514)
			(xy 102.960406 -118.378477) (xy 103.015843 -118.384577) (xy 103.0698 -118.398683) (xy 103.121129 -118.420495)
			(xy 103.168735 -118.449549) (xy 103.211603 -118.485224) (xy 103.24882 -118.526761) (xy 103.279593 -118.573274)
			(xy 103.303265 -118.623771) (xy 103.319333 -118.677178) (xy 103.327453 -118.732354) (xy 103.327962 -118.76024)
			(xy 103.327453 -118.788126) (xy 103.319333 -118.843302) (xy 103.303265 -118.896709) (xy 103.279593 -118.947206)
			(xy 103.24882 -118.993719) (xy 103.211603 -119.035256) (xy 103.168735 -119.070931) (xy 103.121129 -119.099985)
			(xy 103.0698 -119.121797) (xy 103.015843 -119.135903) (xy 102.960406 -119.142003) (xy 102.904672 -119.139966)
			(xy 102.849829 -119.129836) (xy 102.797045 -119.111829) (xy 102.747445 -119.086328) (xy 102.702087 -119.053877)
			(xy 102.661938 -119.015168) (xy 102.627852 -118.971025) (xy 102.600556 -118.92239) (xy 102.580633 -118.870299)
			(xy 102.568507 -118.815862) (xy 102.564436 -118.76024) (xy 98.108737 -118.76024) (xy 98.086703 -118.778577)
			(xy 98.039097 -118.807631) (xy 97.987768 -118.829443) (xy 97.933811 -118.843549) (xy 97.878374 -118.849649)
			(xy 97.82264 -118.847612) (xy 97.767797 -118.837482) (xy 97.715013 -118.819475) (xy 97.665413 -118.793974)
			(xy 97.620055 -118.761523) (xy 97.579906 -118.722814) (xy 97.54582 -118.678671) (xy 97.518524 -118.630036)
			(xy 97.498601 -118.577945) (xy 97.486475 -118.523508) (xy 97.482404 -118.467886) (xy 85.240782 -118.467886)
			(xy 86.647311 -119.407554) (xy 94.499632 -119.407554) (xy 94.499632 -119.353046) (xy 94.507389 -119.299093)
			(xy 94.522745 -119.246794) (xy 94.545388 -119.197211) (xy 94.574856 -119.151356) (xy 94.61055 -119.110162)
			(xy 94.651743 -119.074466) (xy 94.697597 -119.044995) (xy 94.747179 -119.022351) (xy 94.799478 -119.006992)
			(xy 94.85343 -118.999233) (xy 94.880684 -118.998746) (xy 94.908054 -118.99921) (xy 94.962234 -119.007027)
			(xy 95.014738 -119.022516) (xy 95.064484 -119.045358) (xy 95.110451 -119.075084) (xy 95.131382 -119.092726)
			(xy 95.131636 -119.09298) (xy 95.13873 -119.098555) (xy 95.155641 -119.104807) (xy 95.164656 -119.105172)
			(xy 95.231712 -119.105172) (xy 95.24073 -119.104827) (xy 95.257647 -119.098572) (xy 95.264732 -119.09298)
			(xy 95.264732 -119.092726) (xy 95.264986 -119.092726) (xy 95.285916 -119.075084) (xy 95.331889 -119.045372)
			(xy 95.381637 -119.022536) (xy 95.434138 -119.007046) (xy 95.488315 -118.999219) (xy 95.515684 -118.998746)
			(xy 95.542934 -118.9993) (xy 95.59688 -119.007054) (xy 95.649174 -119.022407) (xy 95.69875 -119.045046)
			(xy 95.7446 -119.07451) (xy 95.785789 -119.110199) (xy 95.82148 -119.151387) (xy 95.850946 -119.197236)
			(xy 95.873587 -119.246811) (xy 95.888942 -119.299104) (xy 95.896699 -119.35305) (xy 95.896699 -119.40755)
			(xy 95.888942 -119.461496) (xy 95.884381 -119.477028) (xy 99.60813 -119.477028) (xy 99.612201 -119.421406)
			(xy 99.624327 -119.366969) (xy 99.64425 -119.314878) (xy 99.671546 -119.266243) (xy 99.705632 -119.2221)
			(xy 99.745781 -119.183391) (xy 99.791139 -119.15094) (xy 99.840739 -119.125439) (xy 99.893523 -119.107432)
			(xy 99.948366 -119.097302) (xy 100.0041 -119.095265) (xy 100.059537 -119.101365) (xy 100.113494 -119.115471)
			(xy 100.164823 -119.137283) (xy 100.212429 -119.166337) (xy 100.255297 -119.202012) (xy 100.292514 -119.243549)
			(xy 100.323287 -119.290062) (xy 100.346959 -119.340559) (xy 100.363027 -119.393966) (xy 100.371147 -119.449142)
			(xy 100.371656 -119.477028) (xy 100.371147 -119.504914) (xy 100.363027 -119.56009) (xy 100.346959 -119.613497)
			(xy 100.323287 -119.663994) (xy 100.292514 -119.710507) (xy 100.255297 -119.752044) (xy 100.226222 -119.77624)
			(xy 100.535992 -119.77624) (xy 100.540063 -119.720618) (xy 100.552189 -119.666181) (xy 100.572112 -119.61409)
			(xy 100.599408 -119.565455) (xy 100.633494 -119.521312) (xy 100.673643 -119.482603) (xy 100.719001 -119.450152)
			(xy 100.768601 -119.424651) (xy 100.821385 -119.406644) (xy 100.876228 -119.396514) (xy 100.931962 -119.394477)
			(xy 100.987399 -119.400577) (xy 101.041356 -119.414683) (xy 101.092685 -119.436495) (xy 101.140291 -119.465549)
			(xy 101.183159 -119.501224) (xy 101.220376 -119.542761) (xy 101.251149 -119.589274) (xy 101.274821 -119.639771)
			(xy 101.290889 -119.693178) (xy 101.294665 -119.718836) (xy 107.536486 -119.718836) (xy 107.540557 -119.663214)
			(xy 107.552683 -119.608777) (xy 107.572606 -119.556686) (xy 107.599902 -119.508051) (xy 107.633988 -119.463908)
			(xy 107.674137 -119.425199) (xy 107.719495 -119.392748) (xy 107.769095 -119.367247) (xy 107.821879 -119.34924)
			(xy 107.876722 -119.33911) (xy 107.932456 -119.337073) (xy 107.987893 -119.343173) (xy 108.04185 -119.357279)
			(xy 108.093179 -119.379091) (xy 108.140785 -119.408145) (xy 108.183653 -119.44382) (xy 108.22087 -119.485357)
			(xy 108.251643 -119.53187) (xy 108.275315 -119.582367) (xy 108.291383 -119.635774) (xy 108.299503 -119.69095)
			(xy 108.300012 -119.718836) (xy 108.299503 -119.746722) (xy 108.291383 -119.801898) (xy 108.275315 -119.855305)
			(xy 108.251643 -119.905802) (xy 108.22087 -119.952315) (xy 108.183653 -119.993852) (xy 108.140785 -120.029527)
			(xy 108.093179 -120.058581) (xy 108.04185 -120.080393) (xy 107.987893 -120.094499) (xy 107.932456 -120.100599)
			(xy 107.876722 -120.098562) (xy 107.821879 -120.088432) (xy 107.769095 -120.070425) (xy 107.719495 -120.044924)
			(xy 107.674137 -120.012473) (xy 107.633988 -119.973764) (xy 107.599902 -119.929621) (xy 107.572606 -119.880986)
			(xy 107.552683 -119.828895) (xy 107.540557 -119.774458) (xy 107.536486 -119.718836) (xy 101.294665 -119.718836)
			(xy 101.299009 -119.748354) (xy 101.299518 -119.77624) (xy 101.299009 -119.804126) (xy 101.290889 -119.859302)
			(xy 101.274821 -119.912709) (xy 101.251149 -119.963206) (xy 101.220376 -120.009719) (xy 101.183159 -120.051256)
			(xy 101.140291 -120.086931) (xy 101.092685 -120.115985) (xy 101.041356 -120.137797) (xy 100.987399 -120.151903)
			(xy 100.931962 -120.158003) (xy 100.876228 -120.155966) (xy 100.821385 -120.145836) (xy 100.768601 -120.127829)
			(xy 100.719001 -120.102328) (xy 100.673643 -120.069877) (xy 100.633494 -120.031168) (xy 100.599408 -119.987025)
			(xy 100.572112 -119.93839) (xy 100.552189 -119.886299) (xy 100.540063 -119.831862) (xy 100.535992 -119.77624)
			(xy 100.226222 -119.77624) (xy 100.212429 -119.787719) (xy 100.164823 -119.816773) (xy 100.113494 -119.838585)
			(xy 100.059537 -119.852691) (xy 100.0041 -119.858791) (xy 99.948366 -119.856754) (xy 99.893523 -119.846624)
			(xy 99.840739 -119.828617) (xy 99.791139 -119.803116) (xy 99.745781 -119.770665) (xy 99.705632 -119.731956)
			(xy 99.671546 -119.687813) (xy 99.64425 -119.639178) (xy 99.624327 -119.587087) (xy 99.612201 -119.53265)
			(xy 99.60813 -119.477028) (xy 95.884381 -119.477028) (xy 95.873587 -119.513789) (xy 95.850946 -119.563364)
			(xy 95.82148 -119.609213) (xy 95.785789 -119.650401) (xy 95.7446 -119.68609) (xy 95.69875 -119.715554)
			(xy 95.649174 -119.738193) (xy 95.59688 -119.753546) (xy 95.542934 -119.7613) (xy 95.515684 -119.761762)
			(xy 95.488313 -119.761315) (xy 95.434133 -119.753494) (xy 95.381629 -119.738001) (xy 95.331882 -119.715155)
			(xy 95.285917 -119.685426) (xy 95.264986 -119.667782) (xy 95.264732 -119.667528) (xy 95.257647 -119.66194)
			(xy 95.240729 -119.655696) (xy 95.231712 -119.655336) (xy 95.164656 -119.655336) (xy 95.155641 -119.655712)
			(xy 95.138723 -119.661946) (xy 95.131636 -119.667528) (xy 95.131636 -119.667782) (xy 95.131382 -119.667782)
			(xy 95.110428 -119.685393) (xy 95.064461 -119.71511) (xy 95.014719 -119.737952) (xy 94.962224 -119.753449)
			(xy 94.908052 -119.761284) (xy 94.880684 -119.761762) (xy 94.85343 -119.761367) (xy 94.799478 -119.753608)
			(xy 94.747179 -119.738249) (xy 94.697597 -119.715605) (xy 94.651743 -119.686134) (xy 94.61055 -119.650438)
			(xy 94.574856 -119.609244) (xy 94.545388 -119.563389) (xy 94.522745 -119.513806) (xy 94.507389 -119.461507)
			(xy 94.499632 -119.407554) (xy 86.647311 -119.407554) (xy 87.374064 -119.89308) (xy 97.569018 -119.89308)
			(xy 97.573089 -119.837458) (xy 97.585215 -119.783021) (xy 97.605138 -119.73093) (xy 97.632434 -119.682295)
			(xy 97.66652 -119.638152) (xy 97.706669 -119.599443) (xy 97.752027 -119.566992) (xy 97.801627 -119.541491)
			(xy 97.854411 -119.523484) (xy 97.909254 -119.513354) (xy 97.964988 -119.511317) (xy 98.020425 -119.517417)
			(xy 98.074382 -119.531523) (xy 98.125711 -119.553335) (xy 98.173317 -119.582389) (xy 98.216185 -119.618064)
			(xy 98.253402 -119.659601) (xy 98.284175 -119.706114) (xy 98.307847 -119.756611) (xy 98.323915 -119.810018)
			(xy 98.332035 -119.865194) (xy 98.332544 -119.89308) (xy 98.332035 -119.920966) (xy 98.323915 -119.976142)
			(xy 98.307847 -120.029549) (xy 98.284175 -120.080046) (xy 98.253402 -120.126559) (xy 98.216185 -120.168096)
			(xy 98.173317 -120.203771) (xy 98.125711 -120.232825) (xy 98.074382 -120.254637) (xy 98.020425 -120.268743)
			(xy 97.964988 -120.274843) (xy 97.909254 -120.272806) (xy 97.854411 -120.262676) (xy 97.801627 -120.244669)
			(xy 97.752027 -120.219168) (xy 97.706669 -120.186717) (xy 97.66652 -120.148008) (xy 97.632434 -120.103865)
			(xy 97.605138 -120.05523) (xy 97.585215 -120.003139) (xy 97.573089 -119.948702) (xy 97.569018 -119.89308)
			(xy 87.374064 -119.89308) (xy 87.719662 -120.123966) (xy 87.75434 -120.147627) (xy 87.82001 -120.199935)
			(xy 87.881047 -120.257583) (xy 87.937017 -120.320161) (xy 87.987525 -120.387226) (xy 88.032211 -120.458303)
			(xy 88.07076 -120.532887) (xy 88.0872 -120.571514) (xy 88.758363 -122.192034) (xy 89.450672 -122.192034)
			(xy 89.45114 -122.164664) (xy 89.458955 -122.110484) (xy 89.474443 -122.05798) (xy 89.497284 -122.008233)
			(xy 89.52701 -121.962267) (xy 89.544652 -121.941336) (xy 89.544906 -121.941082) (xy 89.550507 -121.934005)
			(xy 89.556745 -121.917081) (xy 89.557098 -121.908062) (xy 89.557098 -121.841006) (xy 89.556739 -121.831989)
			(xy 89.550493 -121.815072) (xy 89.544906 -121.807986) (xy 89.544652 -121.807986) (xy 89.544652 -121.807732)
			(xy 89.527044 -121.786773) (xy 89.497316 -121.74081) (xy 89.474467 -121.691068) (xy 89.458967 -121.63857)
			(xy 89.451134 -121.584395) (xy 89.451131 -121.529656) (xy 89.458956 -121.47548) (xy 89.474449 -121.42298)
			(xy 89.497291 -121.373235) (xy 89.527013 -121.327268) (xy 89.544652 -121.306336) (xy 89.544906 -121.306082)
			(xy 89.550507 -121.299005) (xy 89.556745 -121.282081) (xy 89.557098 -121.273062) (xy 89.557098 -121.206006)
			(xy 89.556739 -121.196989) (xy 89.550493 -121.180072) (xy 89.544906 -121.172986) (xy 89.544652 -121.172986)
			(xy 89.544652 -121.172732) (xy 89.527044 -121.151773) (xy 89.497316 -121.10581) (xy 89.474467 -121.056068)
			(xy 89.458967 -121.00357) (xy 89.451134 -120.949395) (xy 89.451131 -120.894656) (xy 89.458956 -120.84048)
			(xy 89.474449 -120.78798) (xy 89.497291 -120.738235) (xy 89.527013 -120.692268) (xy 89.544652 -120.671336)
			(xy 89.544906 -120.671082) (xy 89.550507 -120.664005) (xy 89.556745 -120.647081) (xy 89.557098 -120.638062)
			(xy 89.557098 -120.571006) (xy 89.556739 -120.561989) (xy 89.550493 -120.545072) (xy 89.544906 -120.537986)
			(xy 89.544652 -120.537986) (xy 89.544652 -120.537732) (xy 89.527023 -120.516792) (xy 89.497307 -120.470822)
			(xy 89.474469 -120.421077) (xy 89.458976 -120.368578) (xy 89.451146 -120.314403) (xy 89.450672 -120.287034)
			(xy 89.451158 -120.259783) (xy 89.458914 -120.205835) (xy 89.474269 -120.15354) (xy 89.496911 -120.103963)
			(xy 89.526377 -120.058113) (xy 89.562068 -120.016922) (xy 89.603259 -119.981231) (xy 89.649109 -119.951765)
			(xy 89.698686 -119.929123) (xy 89.750981 -119.913768) (xy 89.804929 -119.906012) (xy 89.859431 -119.906012)
			(xy 89.913379 -119.913768) (xy 89.965674 -119.929123) (xy 90.015251 -119.951765) (xy 90.061101 -119.981231)
			(xy 90.102292 -120.016922) (xy 90.137983 -120.058113) (xy 90.167449 -120.103963) (xy 90.190091 -120.15354)
			(xy 90.205446 -120.205835) (xy 90.213202 -120.259783) (xy 90.213688 -120.287034) (xy 90.213245 -120.314405)
			(xy 90.205422 -120.368585) (xy 90.189928 -120.421089) (xy 90.167081 -120.470835) (xy 90.152727 -120.493028)
			(xy 99.604066 -120.493028) (xy 99.608137 -120.437406) (xy 99.620263 -120.382969) (xy 99.640186 -120.330878)
			(xy 99.667482 -120.282243) (xy 99.701568 -120.2381) (xy 99.741717 -120.199391) (xy 99.787075 -120.16694)
			(xy 99.836675 -120.141439) (xy 99.889459 -120.123432) (xy 99.944302 -120.113302) (xy 100.000036 -120.111265)
			(xy 100.055473 -120.117365) (xy 100.10943 -120.131471) (xy 100.160759 -120.153283) (xy 100.208365 -120.182337)
			(xy 100.251233 -120.218012) (xy 100.28845 -120.259549) (xy 100.319223 -120.306062) (xy 100.342895 -120.356559)
			(xy 100.358963 -120.409966) (xy 100.367083 -120.465142) (xy 100.367592 -120.493028) (xy 100.367083 -120.520914)
			(xy 100.358963 -120.57609) (xy 100.342895 -120.629497) (xy 100.319223 -120.679994) (xy 100.28845 -120.726507)
			(xy 100.251233 -120.768044) (xy 100.222158 -120.79224) (xy 100.535992 -120.79224) (xy 100.540063 -120.736618)
			(xy 100.552189 -120.682181) (xy 100.572112 -120.63009) (xy 100.599408 -120.581455) (xy 100.633494 -120.537312)
			(xy 100.673643 -120.498603) (xy 100.719001 -120.466152) (xy 100.768601 -120.440651) (xy 100.821385 -120.422644)
			(xy 100.876228 -120.412514) (xy 100.931962 -120.410477) (xy 100.987399 -120.416577) (xy 101.041356 -120.430683)
			(xy 101.092685 -120.452495) (xy 101.140291 -120.481549) (xy 101.183159 -120.517224) (xy 101.220376 -120.558761)
			(xy 101.251149 -120.605274) (xy 101.274821 -120.655771) (xy 101.290889 -120.709178) (xy 101.299009 -120.764354)
			(xy 101.299518 -120.79224) (xy 102.691436 -120.79224) (xy 102.695507 -120.736618) (xy 102.707633 -120.682181)
			(xy 102.727556 -120.63009) (xy 102.754852 -120.581455) (xy 102.788938 -120.537312) (xy 102.829087 -120.498603)
			(xy 102.874445 -120.466152) (xy 102.924045 -120.440651) (xy 102.976829 -120.422644) (xy 103.031672 -120.412514)
			(xy 103.087406 -120.410477) (xy 103.142843 -120.416577) (xy 103.1968 -120.430683) (xy 103.248129 -120.452495)
			(xy 103.295735 -120.481549) (xy 103.338603 -120.517224) (xy 103.346737 -120.526302) (xy 105.993436 -120.526302)
			(xy 105.997507 -120.47068) (xy 106.009633 -120.416243) (xy 106.029556 -120.364152) (xy 106.056852 -120.315517)
			(xy 106.090938 -120.271374) (xy 106.131087 -120.232665) (xy 106.176445 -120.200214) (xy 106.226045 -120.174713)
			(xy 106.278829 -120.156706) (xy 106.333672 -120.146576) (xy 106.389406 -120.144539) (xy 106.444843 -120.150639)
			(xy 106.4988 -120.164745) (xy 106.550129 -120.186557) (xy 106.597735 -120.215611) (xy 106.640603 -120.251286)
			(xy 106.67782 -120.292823) (xy 106.708593 -120.339336) (xy 106.732265 -120.389833) (xy 106.748333 -120.44324)
			(xy 106.756453 -120.498416) (xy 106.756962 -120.526302) (xy 106.756453 -120.554188) (xy 106.748333 -120.609364)
			(xy 106.732265 -120.662771) (xy 106.708593 -120.713268) (xy 106.67782 -120.759781) (xy 106.640603 -120.801318)
			(xy 106.597735 -120.836993) (xy 106.550129 -120.866047) (xy 106.4988 -120.887859) (xy 106.444843 -120.901965)
			(xy 106.389406 -120.908065) (xy 106.333672 -120.906028) (xy 106.278829 -120.895898) (xy 106.226045 -120.877891)
			(xy 106.176445 -120.85239) (xy 106.131087 -120.819939) (xy 106.090938 -120.78123) (xy 106.056852 -120.737087)
			(xy 106.029556 -120.688452) (xy 106.009633 -120.636361) (xy 105.997507 -120.581924) (xy 105.993436 -120.526302)
			(xy 103.346737 -120.526302) (xy 103.37582 -120.558761) (xy 103.406593 -120.605274) (xy 103.430265 -120.655771)
			(xy 103.446333 -120.709178) (xy 103.454453 -120.764354) (xy 103.454962 -120.79224) (xy 103.454453 -120.820126)
			(xy 103.446333 -120.875302) (xy 103.430265 -120.928709) (xy 103.406593 -120.979206) (xy 103.37582 -121.025719)
			(xy 103.338603 -121.067256) (xy 103.295735 -121.102931) (xy 103.248129 -121.131985) (xy 103.1968 -121.153797)
			(xy 103.142843 -121.167903) (xy 103.087406 -121.174003) (xy 103.031672 -121.171966) (xy 102.976829 -121.161836)
			(xy 102.924045 -121.143829) (xy 102.874445 -121.118328) (xy 102.829087 -121.085877) (xy 102.788938 -121.047168)
			(xy 102.754852 -121.003025) (xy 102.727556 -120.95439) (xy 102.707633 -120.902299) (xy 102.695507 -120.847862)
			(xy 102.691436 -120.79224) (xy 101.299518 -120.79224) (xy 101.299009 -120.820126) (xy 101.290889 -120.875302)
			(xy 101.274821 -120.928709) (xy 101.251149 -120.979206) (xy 101.220376 -121.025719) (xy 101.183159 -121.067256)
			(xy 101.140291 -121.102931) (xy 101.092685 -121.131985) (xy 101.041356 -121.153797) (xy 100.987399 -121.167903)
			(xy 100.931962 -121.174003) (xy 100.876228 -121.171966) (xy 100.821385 -121.161836) (xy 100.768601 -121.143829)
			(xy 100.719001 -121.118328) (xy 100.673643 -121.085877) (xy 100.633494 -121.047168) (xy 100.599408 -121.003025)
			(xy 100.572112 -120.95439) (xy 100.552189 -120.902299) (xy 100.540063 -120.847862) (xy 100.535992 -120.79224)
			(xy 100.222158 -120.79224) (xy 100.208365 -120.803719) (xy 100.160759 -120.832773) (xy 100.10943 -120.854585)
			(xy 100.055473 -120.868691) (xy 100.000036 -120.874791) (xy 99.944302 -120.872754) (xy 99.889459 -120.862624)
			(xy 99.836675 -120.844617) (xy 99.787075 -120.819116) (xy 99.741717 -120.786665) (xy 99.701568 -120.747956)
			(xy 99.667482 -120.703813) (xy 99.640186 -120.655178) (xy 99.620263 -120.603087) (xy 99.608137 -120.54865)
			(xy 99.604066 -120.493028) (xy 90.152727 -120.493028) (xy 90.137351 -120.516801) (xy 90.119708 -120.537732)
			(xy 90.119454 -120.537986) (xy 90.113862 -120.545068) (xy 90.10762 -120.561989) (xy 90.107262 -120.571006)
			(xy 90.107262 -120.638062) (xy 90.107645 -120.647076) (xy 90.113876 -120.663993) (xy 90.119454 -120.671082)
			(xy 90.119708 -120.671082) (xy 90.119708 -120.671336) (xy 90.137381 -120.692242) (xy 90.167101 -120.738216)
			(xy 90.189943 -120.787966) (xy 90.205435 -120.840472) (xy 90.213259 -120.894654) (xy 90.213256 -120.949397)
			(xy 90.205424 -121.003578) (xy 90.189925 -121.056082) (xy 90.167077 -121.105829) (xy 90.13735 -121.151799)
			(xy 90.119708 -121.172732) (xy 90.119454 -121.172986) (xy 90.113862 -121.180068) (xy 90.10762 -121.196989)
			(xy 90.10755 -121.198753) (xy 90.48544 -121.198753) (xy 90.48544 -121.144247) (xy 90.493196 -121.090297)
			(xy 90.508551 -121.038) (xy 90.531192 -120.98842) (xy 90.560659 -120.942566) (xy 90.59635 -120.901373)
			(xy 90.637541 -120.865678) (xy 90.683392 -120.836208) (xy 90.73297 -120.813562) (xy 90.785266 -120.798203)
			(xy 90.839216 -120.790442) (xy 90.866468 -120.789954) (xy 90.893838 -120.790426) (xy 90.948018 -120.79824)
			(xy 91.000521 -120.813727) (xy 91.050268 -120.836568) (xy 91.096235 -120.866293) (xy 91.117166 -120.883934)
			(xy 91.11742 -120.884188) (xy 91.124498 -120.889788) (xy 91.141421 -120.896027) (xy 91.15044 -120.89638)
			(xy 91.217496 -120.89638) (xy 91.226513 -120.896026) (xy 91.24343 -120.889777) (xy 91.250516 -120.884188)
			(xy 91.250516 -120.883934) (xy 91.25077 -120.883934) (xy 91.271707 -120.866301) (xy 91.317678 -120.836587)
			(xy 91.367424 -120.813749) (xy 91.419924 -120.798257) (xy 91.474099 -120.790428) (xy 91.501468 -120.789954)
			(xy 91.52872 -120.790491) (xy 91.582669 -120.798244) (xy 91.634965 -120.813595) (xy 91.684544 -120.836234)
			(xy 91.730397 -120.865698) (xy 91.771589 -120.901388) (xy 91.807283 -120.942577) (xy 91.836751 -120.988428)
			(xy 91.859394 -121.038005) (xy 91.87475 -121.0903) (xy 91.882507 -121.144248) (xy 91.882507 -121.198752)
			(xy 91.87475 -121.2527) (xy 91.859394 -121.304995) (xy 91.836751 -121.354572) (xy 91.807283 -121.400423)
			(xy 91.771589 -121.441612) (xy 91.730397 -121.477302) (xy 91.684544 -121.506766) (xy 91.634965 -121.529405)
			(xy 91.582669 -121.544756) (xy 91.52872 -121.552509) (xy 91.501468 -121.55297) (xy 91.474097 -121.55253)
			(xy 91.419916 -121.544707) (xy 91.367413 -121.529212) (xy 91.317666 -121.506365) (xy 91.271701 -121.476634)
			(xy 91.25077 -121.45899) (xy 91.250516 -121.458736) (xy 91.243435 -121.453142) (xy 91.226514 -121.446902)
			(xy 91.217496 -121.446544) (xy 91.15044 -121.446544) (xy 91.141424 -121.446911) (xy 91.124506 -121.45315)
			(xy 91.11742 -121.458736) (xy 91.11742 -121.45899) (xy 91.117166 -121.45899) (xy 91.096219 -121.47661)
			(xy 91.05025 -121.506325) (xy 91.000507 -121.529165) (xy 90.948009 -121.54466) (xy 90.893836 -121.552493)
			(xy 90.866468 -121.55297) (xy 90.839216 -121.552558) (xy 90.785266 -121.544797) (xy 90.73297 -121.529438)
			(xy 90.683392 -121.506792) (xy 90.637541 -121.477322) (xy 90.59635 -121.441627) (xy 90.560659 -121.400434)
			(xy 90.531192 -121.35458) (xy 90.508551 -121.305) (xy 90.493196 -121.252703) (xy 90.48544 -121.198753)
			(xy 90.10755 -121.198753) (xy 90.107262 -121.206006) (xy 90.107262 -121.273062) (xy 90.107645 -121.282076)
			(xy 90.113876 -121.298993) (xy 90.119454 -121.306082) (xy 90.119708 -121.306082) (xy 90.119708 -121.306336)
			(xy 90.137381 -121.327242) (xy 90.167101 -121.373216) (xy 90.189943 -121.422966) (xy 90.205435 -121.475472)
			(xy 90.213259 -121.529654) (xy 90.213256 -121.581672) (xy 91.994736 -121.581672) (xy 91.995177 -121.554301)
			(xy 92.002999 -121.50012) (xy 92.018494 -121.447617) (xy 92.041341 -121.39787) (xy 92.071072 -121.351905)
			(xy 92.088716 -121.330974) (xy 92.08897 -121.33072) (xy 92.094563 -121.323638) (xy 92.100804 -121.306717)
			(xy 92.101162 -121.2977) (xy 92.101162 -121.230644) (xy 92.100792 -121.221628) (xy 92.094554 -121.204711)
			(xy 92.08897 -121.197624) (xy 92.088716 -121.197624) (xy 92.088716 -121.19737) (xy 92.071099 -121.17642)
			(xy 92.041383 -121.130453) (xy 92.018543 -121.08071) (xy 92.003047 -121.028213) (xy 91.995213 -120.97404)
			(xy 91.994736 -120.946672) (xy 91.995129 -120.919416) (xy 92.002891 -120.865461) (xy 92.018253 -120.813159)
			(xy 92.040902 -120.763576) (xy 92.070377 -120.71772) (xy 92.106078 -120.676527) (xy 92.147278 -120.640834)
			(xy 92.193139 -120.611367) (xy 92.242726 -120.588728) (xy 92.295031 -120.573376) (xy 92.348988 -120.565624)
			(xy 92.376244 -120.565164) (xy 92.405365 -120.565735) (xy 92.462934 -120.574566) (xy 92.518491 -120.592047)
			(xy 92.570744 -120.617772) (xy 92.618478 -120.651142) (xy 92.660584 -120.691381) (xy 92.696083 -120.737554)
			(xy 92.724149 -120.788588) (xy 92.74413 -120.843295) (xy 92.750386 -120.871742) (xy 92.752672 -120.883426)
			(xy 92.76715 -120.902222) (xy 92.851224 -120.942608) (xy 92.862036 -120.947177) (xy 92.885477 -120.946915)
			(xy 92.896182 -120.9421) (xy 92.89669 -120.9421) (xy 92.923744 -120.928808) (xy 92.981022 -120.910034)
			(xy 93.040542 -120.900519) (xy 93.07068 -120.899936) (xy 93.097934 -120.900374) (xy 93.151888 -120.908129)
			(xy 93.20419 -120.923485) (xy 93.253772 -120.946129) (xy 93.299628 -120.975599) (xy 93.340822 -121.011295)
			(xy 93.376516 -121.052491) (xy 93.405983 -121.098349) (xy 93.428623 -121.147933) (xy 93.443976 -121.200235)
			(xy 93.449513 -121.238772) (xy 97.584258 -121.238772) (xy 97.588329 -121.18315) (xy 97.600455 -121.128713)
			(xy 97.620378 -121.076622) (xy 97.647674 -121.027987) (xy 97.68176 -120.983844) (xy 97.721909 -120.945135)
			(xy 97.767267 -120.912684) (xy 97.816867 -120.887183) (xy 97.869651 -120.869176) (xy 97.924494 -120.859046)
			(xy 97.980228 -120.857009) (xy 98.035665 -120.863109) (xy 98.089622 -120.877215) (xy 98.140951 -120.899027)
			(xy 98.188557 -120.928081) (xy 98.231425 -120.963756) (xy 98.268642 -121.005293) (xy 98.299415 -121.051806)
			(xy 98.323087 -121.102303) (xy 98.339155 -121.15571) (xy 98.347275 -121.210886) (xy 98.347784 -121.238772)
			(xy 98.347275 -121.266658) (xy 98.339155 -121.321834) (xy 98.323087 -121.375241) (xy 98.299415 -121.425738)
			(xy 98.268642 -121.472251) (xy 98.231425 -121.513788) (xy 98.188557 -121.549463) (xy 98.140951 -121.578517)
			(xy 98.089622 -121.600329) (xy 98.035665 -121.614435) (xy 97.980228 -121.620535) (xy 97.924494 -121.618498)
			(xy 97.869651 -121.608368) (xy 97.816867 -121.590361) (xy 97.767267 -121.56486) (xy 97.721909 -121.532409)
			(xy 97.68176 -121.4937) (xy 97.647674 -121.449557) (xy 97.620378 -121.400922) (xy 97.600455 -121.348831)
			(xy 97.588329 -121.294394) (xy 97.584258 -121.238772) (xy 93.449513 -121.238772) (xy 93.451728 -121.25419)
			(xy 93.452188 -121.281444) (xy 93.451692 -121.308813) (xy 93.443882 -121.362991) (xy 93.4284 -121.415494)
			(xy 93.405565 -121.465241) (xy 93.375846 -121.511209) (xy 93.358208 -121.532142) (xy 93.357954 -121.532396)
			(xy 93.352357 -121.539476) (xy 93.346118 -121.556398) (xy 93.345762 -121.565416) (xy 93.345762 -121.632472)
			(xy 93.346141 -121.641486) (xy 93.352374 -121.658403) (xy 93.357954 -121.665492) (xy 93.358208 -121.665492)
			(xy 93.358208 -121.665746) (xy 93.375836 -121.686687) (xy 93.40555 -121.732657) (xy 93.428387 -121.782403)
			(xy 93.443881 -121.834901) (xy 93.451712 -121.889075) (xy 93.452188 -121.916444) (xy 93.451763 -121.943697)
			(xy 93.444 -121.997648) (xy 93.428638 -122.049945) (xy 93.405991 -122.099524) (xy 93.376518 -122.145375)
			(xy 93.34082 -122.186565) (xy 93.299624 -122.222256) (xy 93.253768 -122.251721) (xy 93.204185 -122.274361)
			(xy 93.151886 -122.289714) (xy 93.097933 -122.297468) (xy 93.07068 -122.297952) (xy 93.041557 -122.297438)
			(xy 92.983987 -122.288596) (xy 92.928429 -122.271105) (xy 92.876177 -122.245372) (xy 92.828443 -122.211995)
			(xy 92.786338 -122.171749) (xy 92.75084 -122.125571) (xy 92.722774 -122.074533) (xy 92.702793 -122.019822)
			(xy 92.696538 -121.991374) (xy 92.694252 -121.97969) (xy 92.679774 -121.960894) (xy 92.5957 -121.920508)
			(xy 92.584883 -121.915953) (xy 92.561446 -121.916206) (xy 92.550742 -121.921016) (xy 92.550234 -121.921016)
			(xy 92.523177 -121.934301) (xy 92.4659 -121.953077) (xy 92.406381 -121.962596) (xy 92.376244 -121.96318)
			(xy 92.348991 -121.962704) (xy 92.295039 -121.954952) (xy 92.24274 -121.9396) (xy 92.193158 -121.916961)
			(xy 92.147303 -121.887495) (xy 92.106109 -121.851802) (xy 92.070415 -121.81061) (xy 92.040947 -121.764756)
			(xy 92.018305 -121.715175) (xy 92.002951 -121.662877) (xy 91.995197 -121.608925) (xy 91.994736 -121.581672)
			(xy 90.213256 -121.581672) (xy 90.213256 -121.584397) (xy 90.205424 -121.638578) (xy 90.189925 -121.691082)
			(xy 90.167077 -121.740829) (xy 90.13735 -121.786799) (xy 90.119708 -121.807732) (xy 90.119454 -121.807986)
			(xy 90.113862 -121.815068) (xy 90.10762 -121.831989) (xy 90.107262 -121.841006) (xy 90.107262 -121.908062)
			(xy 90.107645 -121.917076) (xy 90.113876 -121.933993) (xy 90.119454 -121.941082) (xy 90.119708 -121.941082)
			(xy 90.119708 -121.941336) (xy 90.137332 -121.96228) (xy 90.167046 -122.00825) (xy 90.189884 -122.057994)
			(xy 90.205379 -122.110492) (xy 90.213212 -122.164666) (xy 90.213688 -122.192034) (xy 90.213202 -122.219285)
			(xy 90.205446 -122.273233) (xy 90.190091 -122.325528) (xy 90.167449 -122.375105) (xy 90.137983 -122.420955)
			(xy 90.102292 -122.462146) (xy 90.061101 -122.497837) (xy 90.015251 -122.527303) (xy 89.965674 -122.549945)
			(xy 89.913379 -122.5653) (xy 89.859431 -122.573056) (xy 89.804929 -122.573056) (xy 89.750981 -122.5653)
			(xy 89.698686 -122.549945) (xy 89.649109 -122.527303) (xy 89.603259 -122.497837) (xy 89.562068 -122.462146)
			(xy 89.526377 -122.420955) (xy 89.496911 -122.375105) (xy 89.474269 -122.325528) (xy 89.458914 -122.273233)
			(xy 89.451158 -122.219285) (xy 89.450672 -122.192034) (xy 88.758363 -122.192034) (xy 89.24398 -123.364553)
			(xy 94.064275 -123.364553) (xy 94.064275 -123.310047) (xy 94.072033 -123.256097) (xy 94.087389 -123.203799)
			(xy 94.110033 -123.15422) (xy 94.139502 -123.108368) (xy 94.175197 -123.067177) (xy 94.21639 -123.031485)
			(xy 94.262245 -123.002019) (xy 94.311826 -122.97938) (xy 94.364124 -122.964027) (xy 94.418075 -122.956273)
			(xy 94.445328 -122.955812) (xy 94.472699 -122.956259) (xy 94.526879 -122.964081) (xy 94.579382 -122.979574)
			(xy 94.629129 -123.00242) (xy 94.675095 -123.032149) (xy 94.696026 -123.049792) (xy 94.69628 -123.050046)
			(xy 94.703364 -123.055636) (xy 94.720283 -123.061879) (xy 94.7293 -123.062238) (xy 94.796356 -123.062238)
			(xy 94.80537 -123.061852) (xy 94.822286 -123.055624) (xy 94.829376 -123.050046) (xy 94.829376 -123.049792)
			(xy 94.82963 -123.049792) (xy 94.850563 -123.032151) (xy 94.896531 -123.002427) (xy 94.946277 -122.979581)
			(xy 94.998779 -122.964085) (xy 95.052957 -122.956256) (xy 95.107699 -122.956256) (xy 95.161877 -122.964085)
			(xy 95.214379 -122.979581) (xy 95.264125 -123.002427) (xy 95.310093 -123.032151) (xy 95.331026 -123.049792)
			(xy 95.33128 -123.050046) (xy 95.338364 -123.055636) (xy 95.355283 -123.061879) (xy 95.3643 -123.062238)
			(xy 95.431356 -123.062238) (xy 95.44037 -123.061852) (xy 95.457286 -123.055624) (xy 95.464376 -123.050046)
			(xy 95.464376 -123.049792) (xy 95.46463 -123.049792) (xy 95.485577 -123.032171) (xy 95.531546 -123.002457)
			(xy 95.581289 -122.979617) (xy 95.633787 -122.964122) (xy 95.68796 -122.956289) (xy 95.715328 -122.955812)
			(xy 95.742579 -122.95626) (xy 95.796527 -122.96402) (xy 95.848821 -122.979378) (xy 95.898397 -123.002022)
			(xy 95.944247 -123.031491) (xy 95.985436 -123.067184) (xy 96.021126 -123.108376) (xy 96.050591 -123.154227)
			(xy 96.073232 -123.203805) (xy 96.088586 -123.256101) (xy 96.096342 -123.310049) (xy 96.096342 -123.364551)
			(xy 96.088586 -123.4185) (xy 96.073232 -123.470795) (xy 96.050591 -123.520373) (xy 96.021126 -123.566224)
			(xy 95.985436 -123.607416) (xy 95.944247 -123.643109) (xy 95.898397 -123.672578) (xy 95.848821 -123.695222)
			(xy 95.796527 -123.71058) (xy 95.742579 -123.71834) (xy 95.715328 -123.718828) (xy 95.687958 -123.718363)
			(xy 95.633778 -123.710548) (xy 95.581274 -123.695059) (xy 95.531527 -123.672217) (xy 95.485561 -123.64249)
			(xy 95.46463 -123.624848) (xy 95.464376 -123.624594) (xy 95.457301 -123.618991) (xy 95.440375 -123.612754)
			(xy 95.431356 -123.612402) (xy 95.3643 -123.612402) (xy 95.355283 -123.612759) (xy 95.338366 -123.619006)
			(xy 95.33128 -123.624594) (xy 95.33128 -123.624848) (xy 95.331026 -123.624848) (xy 95.310093 -123.642489)
			(xy 95.264125 -123.672213) (xy 95.214379 -123.695059) (xy 95.161877 -123.710555) (xy 95.107699 -123.718384)
			(xy 95.052957 -123.718384) (xy 94.998779 -123.710555) (xy 94.946277 -123.695059) (xy 94.896531 -123.672213)
			(xy 94.850563 -123.642489) (xy 94.82963 -123.624848) (xy 94.829376 -123.624594) (xy 94.822301 -123.618991)
			(xy 94.805375 -123.612754) (xy 94.796356 -123.612402) (xy 94.7293 -123.612402) (xy 94.720283 -123.612759)
			(xy 94.703366 -123.619006) (xy 94.69628 -123.624594) (xy 94.69628 -123.624848) (xy 94.696026 -123.624848)
			(xy 94.675088 -123.64248) (xy 94.629118 -123.672195) (xy 94.579372 -123.695033) (xy 94.526872 -123.710525)
			(xy 94.472697 -123.718354) (xy 94.445328 -123.718828) (xy 94.418075 -123.718327) (xy 94.364124 -123.710573)
			(xy 94.311826 -123.69522) (xy 94.262245 -123.672581) (xy 94.21639 -123.643115) (xy 94.175197 -123.607423)
			(xy 94.139502 -123.566232) (xy 94.110033 -123.52038) (xy 94.087389 -123.470801) (xy 94.072033 -123.418503)
			(xy 94.064275 -123.364553) (xy 89.24398 -123.364553) (xy 89.410974 -123.76776) (xy 97.442306 -123.76776)
			(xy 97.45006 -123.713817) (xy 97.465412 -123.661528) (xy 97.488049 -123.611955) (xy 97.51751 -123.566108)
			(xy 97.553197 -123.524921) (xy 97.594381 -123.489231) (xy 97.640225 -123.459765) (xy 97.689796 -123.437124)
			(xy 97.742084 -123.421767) (xy 97.796026 -123.414008) (xy 97.823274 -123.41352) (xy 97.823782 -123.41352)
			(xy 97.834154 -123.413603) (xy 97.854866 -123.414745) (xy 97.865184 -123.415806) (xy 97.879729 -123.41691)
			(xy 97.908422 -123.411704) (xy 97.934478 -123.398612) (xy 97.955781 -123.378698) (xy 97.970599 -123.353583)
			(xy 97.977727 -123.325307) (xy 97.976586 -123.296168) (xy 97.972372 -123.282202) (xy 97.963011 -123.252595)
			(xy 97.952934 -123.191327) (xy 97.952306 -123.160282) (xy 97.952306 -123.160028) (xy 97.952725 -123.132773)
			(xy 97.960479 -123.078817) (xy 97.975832 -123.026514) (xy 97.998473 -122.976928) (xy 98.02794 -122.931069)
			(xy 98.063634 -122.889871) (xy 98.104828 -122.854171) (xy 98.150683 -122.824698) (xy 98.200266 -122.80205)
			(xy 98.252567 -122.78669) (xy 98.306522 -122.778929) (xy 98.361032 -122.778925) (xy 98.414988 -122.78668)
			(xy 98.467291 -122.802034) (xy 98.516876 -122.824675) (xy 98.562735 -122.854143) (xy 98.603933 -122.889837)
			(xy 98.639632 -122.931032) (xy 98.669105 -122.976887) (xy 98.691751 -123.02647) (xy 98.707111 -123.078771)
			(xy 98.714872 -123.132726) (xy 98.714874 -123.187236) (xy 98.707119 -123.241192) (xy 98.691765 -123.293495)
			(xy 98.669122 -123.34308) (xy 98.639654 -123.388939) (xy 98.603959 -123.430136) (xy 98.562765 -123.465834)
			(xy 98.516909 -123.495307) (xy 98.467326 -123.517953) (xy 98.415024 -123.533312) (xy 98.361069 -123.541072)
			(xy 98.333814 -123.541536) (xy 98.333306 -123.541536) (xy 98.322934 -123.541454) (xy 98.302222 -123.540311)
			(xy 98.291904 -123.53925) (xy 98.277358 -123.538193) (xy 98.248676 -123.5434) (xy 98.222628 -123.556487)
			(xy 98.20133 -123.576392) (xy 98.186512 -123.601496) (xy 98.179379 -123.629761) (xy 98.18051 -123.658891)
			(xy 98.184716 -123.672854) (xy 98.194067 -123.702464) (xy 98.204151 -123.763729) (xy 98.204782 -123.794774)
			(xy 98.204782 -123.795028) (xy 98.204292 -123.822276) (xy 98.196532 -123.876218) (xy 98.181176 -123.928506)
			(xy 98.158534 -123.978077) (xy 98.129068 -124.023921) (xy 98.093378 -124.065105) (xy 98.05219 -124.100791)
			(xy 98.006343 -124.130252) (xy 97.956771 -124.152889) (xy 97.904481 -124.168241) (xy 97.850538 -124.175995)
			(xy 97.796042 -124.175993) (xy 97.7421 -124.168236) (xy 97.689811 -124.152882) (xy 97.640239 -124.130242)
			(xy 97.594394 -124.100779) (xy 97.553208 -124.065091) (xy 97.51752 -124.023905) (xy 97.488057 -123.978059)
			(xy 97.465417 -123.928487) (xy 97.450063 -123.876198) (xy 97.442307 -123.822256) (xy 97.442306 -123.76776)
			(xy 89.410974 -123.76776) (xy 89.596265 -124.215144) (xy 94.606616 -124.215144) (xy 94.610687 -124.159522)
			(xy 94.622813 -124.105085) (xy 94.642736 -124.052994) (xy 94.670032 -124.004359) (xy 94.704118 -123.960216)
			(xy 94.744267 -123.921507) (xy 94.789625 -123.889056) (xy 94.839225 -123.863555) (xy 94.892009 -123.845548)
			(xy 94.946852 -123.835418) (xy 95.002586 -123.833381) (xy 95.058023 -123.839481) (xy 95.11198 -123.853587)
			(xy 95.163309 -123.875399) (xy 95.210915 -123.904453) (xy 95.253783 -123.940128) (xy 95.291 -123.981665)
			(xy 95.321773 -124.028178) (xy 95.345445 -124.078675) (xy 95.361513 -124.132082) (xy 95.369633 -124.187258)
			(xy 95.370142 -124.215144) (xy 95.369633 -124.24303) (xy 95.361513 -124.298206) (xy 95.345445 -124.351613)
			(xy 95.321773 -124.40211) (xy 95.291 -124.448623) (xy 95.253783 -124.49016) (xy 95.210915 -124.525835)
			(xy 95.163309 -124.554889) (xy 95.11198 -124.576701) (xy 95.058023 -124.590807) (xy 95.002586 -124.596907)
			(xy 94.946852 -124.59487) (xy 94.892009 -124.58474) (xy 94.839225 -124.566733) (xy 94.789625 -124.541232)
			(xy 94.744267 -124.508781) (xy 94.704118 -124.470072) (xy 94.670032 -124.425929) (xy 94.642736 -124.377294)
			(xy 94.622813 -124.325203) (xy 94.610687 -124.270766) (xy 94.606616 -124.215144) (xy 89.596265 -124.215144)
			(xy 89.920064 -124.996956) (xy 89.93632 -125.011942) (xy 89.942162 -125.01372) (xy 89.967791 -125.021922)
			(xy 90.016624 -125.044526) (xy 90.061796 -125.073767) (xy 90.102413 -125.109064) (xy 90.137668 -125.149717)
			(xy 90.166863 -125.194919) (xy 90.189417 -125.243775) (xy 90.204885 -125.295315) (xy 90.212958 -125.348516)
			(xy 90.213688 -125.375416) (xy 90.213688 -125.385068) (xy 90.213473 -125.395382) (xy 90.212077 -125.415968)
			(xy 90.210894 -125.426216) (xy 90.207511 -125.450219) (xy 90.195459 -125.497173) (xy 90.17757 -125.542226)
			(xy 90.16619 -125.56363) (xy 90.165174 -125.565154) (xy 90.164412 -125.586998) (xy 90.290572 -125.891544)
			(xy 95.17507 -125.891544) (xy 95.17551 -125.865229) (xy 95.182752 -125.8131) (xy 95.197077 -125.762457)
			(xy 95.218214 -125.714258) (xy 95.245765 -125.669415) (xy 95.279207 -125.628776) (xy 95.29826 -125.61062)
			(xy 95.305649 -125.603087) (xy 95.314182 -125.583816) (xy 95.31477 -125.573282) (xy 95.31477 -125.498606)
			(xy 95.31426 -125.488054) (xy 95.305712 -125.468758) (xy 95.29826 -125.461268) (xy 95.279188 -125.443129)
			(xy 95.245734 -125.402495) (xy 95.218178 -125.357651) (xy 95.197043 -125.309447) (xy 95.182729 -125.258797)
			(xy 95.175507 -125.206661) (xy 95.17507 -125.180344) (xy 95.175556 -125.153093) (xy 95.183312 -125.099145)
			(xy 95.198667 -125.04685) (xy 95.221309 -124.997273) (xy 95.250775 -124.951423) (xy 95.286466 -124.910232)
			(xy 95.327657 -124.874541) (xy 95.373507 -124.845075) (xy 95.423084 -124.822433) (xy 95.475379 -124.807078)
			(xy 95.529327 -124.799322) (xy 95.583829 -124.799322) (xy 95.637777 -124.807078) (xy 95.690072 -124.822433)
			(xy 95.739649 -124.845075) (xy 95.785499 -124.874541) (xy 95.82669 -124.910232) (xy 95.862381 -124.951423)
			(xy 95.891847 -124.997273) (xy 95.914489 -125.04685) (xy 95.929844 -125.099145) (xy 95.9376 -125.153093)
			(xy 95.938086 -125.180344) (xy 95.937652 -125.206659) (xy 95.930411 -125.258789) (xy 95.916086 -125.309433)
			(xy 95.894947 -125.357632) (xy 95.867395 -125.402474) (xy 95.83395 -125.443112) (xy 95.814896 -125.461268)
			(xy 95.807506 -125.468799) (xy 95.798975 -125.488072) (xy 95.798386 -125.498606) (xy 95.798386 -125.573282)
			(xy 95.798916 -125.583831) (xy 95.807451 -125.603127) (xy 95.814896 -125.61062) (xy 95.833953 -125.628774)
			(xy 95.867411 -125.669404) (xy 95.894969 -125.714244) (xy 95.916108 -125.762445) (xy 95.930424 -125.813093)
			(xy 95.937648 -125.865228) (xy 95.938086 -125.891544) (xy 95.9376 -125.918795) (xy 95.929844 -125.972743)
			(xy 95.914489 -126.025038) (xy 95.891847 -126.074615) (xy 95.862381 -126.120465) (xy 95.82669 -126.161656)
			(xy 95.785499 -126.197347) (xy 95.739649 -126.226813) (xy 95.690072 -126.249455) (xy 95.637777 -126.26481)
			(xy 95.583829 -126.272566) (xy 95.529327 -126.272566) (xy 95.475379 -126.26481) (xy 95.423084 -126.249455)
			(xy 95.373507 -126.226813) (xy 95.327657 -126.197347) (xy 95.286466 -126.161656) (xy 95.250775 -126.120465)
			(xy 95.221309 -126.074615) (xy 95.198667 -126.025038) (xy 95.183312 -125.972743) (xy 95.175556 -125.918795)
			(xy 95.17507 -125.891544) (xy 90.290572 -125.891544) (xy 92.073222 -130.194812) (xy 92.075226 -130.199378)
			(xy 92.080719 -130.207699) (xy 92.084144 -130.211322) (xy 92.252038 -130.37947) (xy 92.286257 -130.414489)
			(xy 92.348432 -130.490134) (xy 92.402897 -130.571506) (xy 92.449127 -130.657822) (xy 92.468446 -130.702812)
			(xy 92.887827 -131.715256) (xy 95.345756 -131.715256) (xy 95.349827 -131.659634) (xy 95.361953 -131.605197)
			(xy 95.381876 -131.553106) (xy 95.409172 -131.504471) (xy 95.443258 -131.460328) (xy 95.483407 -131.421619)
			(xy 95.528765 -131.389168) (xy 95.578365 -131.363667) (xy 95.631149 -131.34566) (xy 95.685992 -131.33553)
			(xy 95.741726 -131.333493) (xy 95.797163 -131.339593) (xy 95.85112 -131.353699) (xy 95.902449 -131.375511)
			(xy 95.950055 -131.404565) (xy 95.992923 -131.44024) (xy 96.03014 -131.481777) (xy 96.060913 -131.52829)
			(xy 96.084585 -131.578787) (xy 96.100653 -131.632194) (xy 96.108773 -131.68737) (xy 96.109282 -131.715256)
			(xy 96.108773 -131.743142) (xy 96.100653 -131.798318) (xy 96.084585 -131.851725) (xy 96.060913 -131.902222)
			(xy 96.03014 -131.948735) (xy 95.992923 -131.990272) (xy 95.950055 -132.025947) (xy 95.902449 -132.055001)
			(xy 95.85112 -132.076813) (xy 95.797163 -132.090919) (xy 95.741726 -132.097019) (xy 95.685992 -132.094982)
			(xy 95.631149 -132.084852) (xy 95.578365 -132.066845) (xy 95.528765 -132.041344) (xy 95.483407 -132.008893)
			(xy 95.443258 -131.970184) (xy 95.409172 -131.926041) (xy 95.381876 -131.877406) (xy 95.361953 -131.825315)
			(xy 95.349827 -131.770878) (xy 95.345756 -131.715256) (xy 92.887827 -131.715256) (xy 101.093016 -151.5237)
			(xy 101.11111 -151.56904) (xy 101.139408 -151.662476) (xy 101.158455 -151.758227) (xy 101.168069 -151.855379)
			(xy 101.168708 -151.904192) (xy 101.168708 -159.966914) (xy 101.168242 -160.010296) (xy 101.160704 -160.096732)
			(xy 101.145678 -160.182185) (xy 101.134926 -160.224216) (xy 100.78466 -161.535364) (xy 100.772974 -161.57737)
			(xy 100.743234 -161.65934) (xy 100.70646 -161.738403) (xy 100.685092 -161.77641) (xy 92.180664 -176.514506)
			(xy 92.175584 -176.526444) (xy 91.38793 -179.413916) (xy 91.386152 -179.422806) (xy 91.295407 -180.459953)
			(xy 91.824765 -180.459953) (xy 91.824765 -180.405447) (xy 91.832522 -180.351497) (xy 91.847879 -180.2992)
			(xy 91.870521 -180.24962) (xy 91.899989 -180.203768) (xy 91.935683 -180.162576) (xy 91.976876 -180.126883)
			(xy 92.022729 -180.097416) (xy 92.072309 -180.074775) (xy 92.124607 -180.05942) (xy 92.178557 -180.051665)
			(xy 92.20581 -180.051202) (xy 92.232634 -180.051673) (xy 92.285755 -180.059185) (xy 92.3373 -180.074059)
			(xy 92.386256 -180.096004) (xy 92.431657 -180.124586) (xy 92.47261 -180.159242) (xy 92.490798 -180.178964)
			(xy 92.49791 -180.187092) (xy 92.51823 -180.195982) (xy 92.61729 -180.194966) (xy 92.637102 -180.185568)
			(xy 92.644214 -180.177186) (xy 92.662401 -180.156397) (xy 92.703771 -180.119799) (xy 92.74999 -180.089556)
			(xy 92.800091 -180.066302) (xy 92.853024 -180.050522) (xy 92.907681 -180.042549) (xy 92.935298 -180.042058)
			(xy 92.962549 -180.042589) (xy 93.016495 -180.050345) (xy 93.068788 -180.0657) (xy 93.118364 -180.08834)
			(xy 93.164214 -180.117805) (xy 93.205403 -180.153496) (xy 93.241093 -180.194685) (xy 93.270559 -180.240534)
			(xy 93.2932 -180.29011) (xy 93.308554 -180.342403) (xy 93.316311 -180.396349) (xy 93.316311 -180.450851)
			(xy 93.308554 -180.504797) (xy 93.2932 -180.55709) (xy 93.270559 -180.606666) (xy 93.241093 -180.652515)
			(xy 93.205403 -180.693704) (xy 93.164214 -180.729395) (xy 93.118364 -180.75886) (xy 93.068788 -180.7815)
			(xy 93.016495 -180.796855) (xy 92.962549 -180.804611) (xy 92.935298 -180.805074) (xy 92.908473 -180.804606)
			(xy 92.855353 -180.797094) (xy 92.803807 -180.78222) (xy 92.754851 -180.760275) (xy 92.70945 -180.731692)
			(xy 92.668498 -180.697034) (xy 92.65031 -180.677312) (xy 92.643198 -180.669184) (xy 92.622878 -180.660294)
			(xy 92.523818 -180.66131) (xy 92.504006 -180.670708) (xy 92.496894 -180.67909) (xy 92.478698 -180.69987)
			(xy 92.43733 -180.73647) (xy 92.391113 -180.766715) (xy 92.341014 -180.789971) (xy 92.288082 -180.805752)
			(xy 92.233427 -180.813726) (xy 92.20581 -180.814218) (xy 92.178557 -180.813735) (xy 92.124607 -180.80598)
			(xy 92.072309 -180.790625) (xy 92.022729 -180.767984) (xy 91.976876 -180.738517) (xy 91.935683 -180.702824)
			(xy 91.899989 -180.661632) (xy 91.870521 -180.61578) (xy 91.847879 -180.5662) (xy 91.832522 -180.513903)
			(xy 91.824765 -180.459953) (xy 91.295407 -180.459953) (xy 90.518742 -189.33668) (xy 90.518377 -189.34668)
			(xy 90.524425 -189.365733) (xy 90.537304 -189.381021) (xy 90.555052 -189.390218) (xy 90.56497 -189.391544)
			(xy 90.579194 -189.392814) (xy 90.604594 -189.380368) (xy 90.612214 -189.36843) (xy 90.629769 -189.341835)
			(xy 90.669734 -189.292196) (xy 90.69197 -189.26937) (xy 93.93301 -186.02833) (xy 93.939855 -186.020932)
			(xy 93.947578 -186.002333) (xy 93.947996 -185.992262) (xy 93.947996 -174.4472) (xy 93.94846 -174.414045)
			(xy 93.95588 -174.348151) (xy 93.970626 -174.283502) (xy 93.992514 -174.220908) (xy 94.021269 -174.161157)
			(xy 94.056528 -174.104999) (xy 94.097851 -174.053139) (xy 94.12097 -174.02937) (xy 101.68001 -166.47033)
			(xy 101.686855 -166.462932) (xy 101.694578 -166.444333) (xy 101.694996 -166.434262) (xy 101.694996 -125.2982)
			(xy 101.69546 -125.265045) (xy 101.70288 -125.199151) (xy 101.717626 -125.134502) (xy 101.739514 -125.071908)
			(xy 101.768269 -125.012157) (xy 101.803528 -124.955999) (xy 101.844851 -124.904139) (xy 101.86797 -124.88037)
			(xy 104.30637 -122.44197) (xy 104.330148 -122.41886) (xy 104.382001 -122.377528) (xy 104.438156 -122.342261)
			(xy 104.497906 -122.313502) (xy 104.560499 -122.291614) (xy 104.62515 -122.276871) (xy 104.691045 -122.269458)
			(xy 104.7242 -122.268996) (xy 106.845862 -122.268996) (xy 106.855927 -122.268561) (xy 106.874515 -122.260831)
			(xy 106.88193 -122.25401) (xy 121.06021 -108.07573) (xy 121.067055 -108.068332) (xy 121.074778 -108.049733)
			(xy 121.075196 -108.039662) (xy 121.075196 -105.9942) (xy 121.07566 -105.961045) (xy 121.08308 -105.895151)
			(xy 121.097826 -105.830502) (xy 121.119714 -105.767908) (xy 121.148469 -105.708157) (xy 121.183728 -105.651999)
			(xy 121.225051 -105.600139) (xy 121.24817 -105.57637) (xy 131.67741 -95.14713) (xy 131.684255 -95.139732)
			(xy 131.691978 -95.121133) (xy 131.692396 -95.111062) (xy 131.692396 -88.4428) (xy 131.69286 -88.409645)
			(xy 131.70028 -88.343751) (xy 131.715026 -88.279102) (xy 131.736914 -88.216508) (xy 131.765669 -88.156757)
			(xy 131.800928 -88.100599) (xy 131.842251 -88.048739) (xy 131.86537 -88.02497) (xy 133.87197 -86.01837)
			(xy 133.895748 -85.99526) (xy 133.947601 -85.953928) (xy 134.003756 -85.918661) (xy 134.063506 -85.889902)
			(xy 134.126099 -85.868014) (xy 134.19075 -85.853271) (xy 134.256645 -85.845858) (xy 134.2898 -85.845396)
			(xy 145.415508 -85.845396) (xy 145.449822 -85.845908) (xy 145.517984 -85.853887) (xy 145.584764 -85.869702)
			(xy 145.617184 -85.880956) (xy 145.625566 -85.884004) (xy 145.66392 -85.884004) (xy 145.696574 -85.884463)
			(xy 145.761471 -85.891776) (xy 145.825141 -85.906309) (xy 145.886785 -85.927878) (xy 145.945626 -85.956212)
			(xy 146.000925 -85.990955) (xy 146.051987 -86.031671) (xy 146.0754 -86.054438) (xy 146.24812 -86.227158)
			(xy 173.06366 -86.227158) (xy 173.067731 -86.171536) (xy 173.079857 -86.117099) (xy 173.09978 -86.065008)
			(xy 173.127076 -86.016373) (xy 173.161162 -85.97223) (xy 173.201311 -85.933521) (xy 173.246669 -85.90107)
			(xy 173.296269 -85.875569) (xy 173.349053 -85.857562) (xy 173.403896 -85.847432) (xy 173.45963 -85.845395)
			(xy 173.515067 -85.851495) (xy 173.569024 -85.865601) (xy 173.620353 -85.887413) (xy 173.667959 -85.916467)
			(xy 173.710827 -85.952142) (xy 173.748044 -85.993679) (xy 173.778817 -86.040192) (xy 173.802489 -86.090689)
			(xy 173.818557 -86.144096) (xy 173.826677 -86.199272) (xy 173.827186 -86.227158) (xy 173.826695 -86.254082)
			(xy 174.747426 -86.254082) (xy 174.751497 -86.19846) (xy 174.763623 -86.144023) (xy 174.783546 -86.091932)
			(xy 174.810842 -86.043297) (xy 174.844928 -85.999154) (xy 174.885077 -85.960445) (xy 174.930435 -85.927994)
			(xy 174.980035 -85.902493) (xy 175.032819 -85.884486) (xy 175.087662 -85.874356) (xy 175.143396 -85.872319)
			(xy 175.198833 -85.878419) (xy 175.25279 -85.892525) (xy 175.304119 -85.914337) (xy 175.351725 -85.943391)
			(xy 175.394593 -85.979066) (xy 175.43181 -86.020603) (xy 175.462583 -86.067116) (xy 175.486255 -86.117613)
			(xy 175.502323 -86.17102) (xy 175.510443 -86.226196) (xy 175.510841 -86.247986) (xy 191.338452 -86.247986)
			(xy 191.342523 -86.192364) (xy 191.354649 -86.137927) (xy 191.374572 -86.085836) (xy 191.401868 -86.037201)
			(xy 191.435954 -85.993058) (xy 191.476103 -85.954349) (xy 191.521461 -85.921898) (xy 191.571061 -85.896397)
			(xy 191.623845 -85.87839) (xy 191.678688 -85.86826) (xy 191.734422 -85.866223) (xy 191.789859 -85.872323)
			(xy 191.843816 -85.886429) (xy 191.895145 -85.908241) (xy 191.942751 -85.937295) (xy 191.985619 -85.97297)
			(xy 192.022836 -86.014507) (xy 192.053609 -86.06102) (xy 192.077281 -86.111517) (xy 192.093349 -86.164924)
			(xy 192.101469 -86.2201) (xy 192.101978 -86.247986) (xy 192.101469 -86.275872) (xy 192.093349 -86.331048)
			(xy 192.077281 -86.384455) (xy 192.053609 -86.434952) (xy 192.022836 -86.481465) (xy 191.985619 -86.523002)
			(xy 191.942751 -86.558677) (xy 191.895145 -86.587731) (xy 191.843816 -86.609543) (xy 191.789859 -86.623649)
			(xy 191.734422 -86.629749) (xy 191.678688 -86.627712) (xy 191.623845 -86.617582) (xy 191.571061 -86.599575)
			(xy 191.521461 -86.574074) (xy 191.476103 -86.541623) (xy 191.435954 -86.502914) (xy 191.401868 -86.458771)
			(xy 191.374572 -86.410136) (xy 191.354649 -86.358045) (xy 191.342523 -86.303608) (xy 191.338452 -86.247986)
			(xy 175.510841 -86.247986) (xy 175.510952 -86.254082) (xy 175.510443 -86.281968) (xy 175.502323 -86.337144)
			(xy 175.486255 -86.390551) (xy 175.462583 -86.441048) (xy 175.43181 -86.487561) (xy 175.394593 -86.529098)
			(xy 175.351725 -86.564773) (xy 175.304119 -86.593827) (xy 175.25279 -86.615639) (xy 175.198833 -86.629745)
			(xy 175.143396 -86.635845) (xy 175.087662 -86.633808) (xy 175.032819 -86.623678) (xy 174.980035 -86.605671)
			(xy 174.930435 -86.58017) (xy 174.885077 -86.547719) (xy 174.844928 -86.50901) (xy 174.810842 -86.464867)
			(xy 174.783546 -86.416232) (xy 174.763623 -86.364141) (xy 174.751497 -86.309704) (xy 174.747426 -86.254082)
			(xy 173.826695 -86.254082) (xy 173.826677 -86.255044) (xy 173.818557 -86.31022) (xy 173.802489 -86.363627)
			(xy 173.778817 -86.414124) (xy 173.748044 -86.460637) (xy 173.710827 -86.502174) (xy 173.667959 -86.537849)
			(xy 173.620353 -86.566903) (xy 173.569024 -86.588715) (xy 173.515067 -86.602821) (xy 173.45963 -86.608921)
			(xy 173.403896 -86.606884) (xy 173.349053 -86.596754) (xy 173.296269 -86.578747) (xy 173.246669 -86.553246)
			(xy 173.201311 -86.520795) (xy 173.161162 -86.482086) (xy 173.127076 -86.437943) (xy 173.09978 -86.389308)
			(xy 173.079857 -86.337217) (xy 173.067731 -86.28278) (xy 173.06366 -86.227158) (xy 146.24812 -86.227158)
			(xy 146.994372 -86.97341) (xy 147.00177 -86.980255) (xy 147.020369 -86.987977) (xy 147.03044 -86.988396)
			(xy 194.365372 -86.988396) (xy 194.375436 -86.987959) (xy 194.394021 -86.980226) (xy 194.40144 -86.97341)
			(xy 195.05676 -86.31809) (xy 195.080162 -86.295311) (xy 195.131223 -86.254589) (xy 195.186522 -86.219841)
			(xy 195.245365 -86.191505) (xy 195.307011 -86.169936) (xy 195.370685 -86.155405) (xy 195.435585 -86.148096)
			(xy 195.46824 -86.147656) (xy 201.0791 -86.147656) (xy 201.089111 -86.148143) (xy 201.10761 -86.155801)
			(xy 201.121774 -86.169953) (xy 201.129448 -86.188446) (xy 201.1299 -86.198456) (xy 201.1299 -86.226396)
			(xy 201.130319 -86.236418) (xy 201.137988 -86.254936) (xy 201.15216 -86.26911) (xy 201.170678 -86.27678)
			(xy 201.1807 -86.277196) (xy 204.686662 -86.277196) (xy 204.696727 -86.276761) (xy 204.715315 -86.269031)
			(xy 204.72273 -86.26221) (xy 206.00797 -84.97697) (xy 206.031748 -84.95386) (xy 206.083601 -84.912528)
			(xy 206.139756 -84.877261) (xy 206.199506 -84.848502) (xy 206.262099 -84.826614) (xy 206.32675 -84.811871)
			(xy 206.392645 -84.804458) (xy 206.4258 -84.803996) (xy 219.8116 -84.803996) (xy 219.844755 -84.80446)
			(xy 219.910649 -84.81188) (xy 219.975298 -84.826626) (xy 220.037892 -84.848514) (xy 220.097643 -84.877269)
			(xy 220.153801 -84.912528) (xy 220.205661 -84.953851) (xy 220.22943 -84.97697) (xy 220.39707 -85.14461)
			(xy 220.404468 -85.151455) (xy 220.423067 -85.159178) (xy 220.433138 -85.159596) (xy 220.57614 -85.159596)
			(xy 220.585573 -85.159227) (xy 220.603165 -85.152415) (xy 220.617095 -85.139694) (xy 220.621606 -85.131402)
			(xy 220.662246 -85.049614) (xy 220.66612 -85.040987) (xy 220.66784 -85.022166) (xy 220.662611 -85.004005)
			(xy 220.657166 -84.996274) (xy 220.638854 -84.971223) (xy 220.609748 -84.916425) (xy 220.589896 -84.857637)
			(xy 220.579822 -84.796412) (xy 220.579188 -84.765388) (xy 220.579674 -84.738137) (xy 220.58743 -84.684189)
			(xy 220.602785 -84.631894) (xy 220.625427 -84.582317) (xy 220.654893 -84.536467) (xy 220.690584 -84.495276)
			(xy 220.731775 -84.459585) (xy 220.777625 -84.430119) (xy 220.827202 -84.407477) (xy 220.879497 -84.392122)
			(xy 220.933445 -84.384366) (xy 220.987947 -84.384366) (xy 221.041895 -84.392122) (xy 221.09419 -84.407477)
			(xy 221.143767 -84.430119) (xy 221.189617 -84.459585) (xy 221.230808 -84.495276) (xy 221.266499 -84.536467)
			(xy 221.295965 -84.582317) (xy 221.318607 -84.631894) (xy 221.331402 -84.675472) (xy 222.62414 -84.675472)
			(xy 222.628211 -84.61985) (xy 222.640337 -84.565413) (xy 222.66026 -84.513322) (xy 222.687556 -84.464687)
			(xy 222.721642 -84.420544) (xy 222.761791 -84.381835) (xy 222.807149 -84.349384) (xy 222.856749 -84.323883)
			(xy 222.909533 -84.305876) (xy 222.964376 -84.295746) (xy 223.02011 -84.293709) (xy 223.075547 -84.299809)
			(xy 223.129504 -84.313915) (xy 223.180833 -84.335727) (xy 223.228439 -84.364781) (xy 223.271307 -84.400456)
			(xy 223.308524 -84.441993) (xy 223.339297 -84.488506) (xy 223.362969 -84.539003) (xy 223.379037 -84.59241)
			(xy 223.387157 -84.647586) (xy 223.387666 -84.675472) (xy 224.650044 -84.675472) (xy 224.654115 -84.61985)
			(xy 224.666241 -84.565413) (xy 224.686164 -84.513322) (xy 224.71346 -84.464687) (xy 224.747546 -84.420544)
			(xy 224.787695 -84.381835) (xy 224.833053 -84.349384) (xy 224.882653 -84.323883) (xy 224.935437 -84.305876)
			(xy 224.99028 -84.295746) (xy 225.046014 -84.293709) (xy 225.101451 -84.299809) (xy 225.155408 -84.313915)
			(xy 225.206737 -84.335727) (xy 225.254343 -84.364781) (xy 225.297211 -84.400456) (xy 225.334428 -84.441993)
			(xy 225.365201 -84.488506) (xy 225.388873 -84.539003) (xy 225.404941 -84.59241) (xy 225.413061 -84.647586)
			(xy 225.41357 -84.675472) (xy 225.413061 -84.703358) (xy 225.404941 -84.758534) (xy 225.388873 -84.811941)
			(xy 225.365201 -84.862438) (xy 225.334428 -84.908951) (xy 225.297211 -84.950488) (xy 225.254343 -84.986163)
			(xy 225.206737 -85.015217) (xy 225.155408 -85.037029) (xy 225.101451 -85.051135) (xy 225.046014 -85.057235)
			(xy 224.99028 -85.055198) (xy 224.935437 -85.045068) (xy 224.882653 -85.027061) (xy 224.833053 -85.00156)
			(xy 224.787695 -84.969109) (xy 224.747546 -84.9304) (xy 224.71346 -84.886257) (xy 224.686164 -84.837622)
			(xy 224.666241 -84.785531) (xy 224.654115 -84.731094) (xy 224.650044 -84.675472) (xy 223.387666 -84.675472)
			(xy 223.387157 -84.703358) (xy 223.379037 -84.758534) (xy 223.362969 -84.811941) (xy 223.339297 -84.862438)
			(xy 223.308524 -84.908951) (xy 223.271307 -84.950488) (xy 223.228439 -84.986163) (xy 223.180833 -85.015217)
			(xy 223.129504 -85.037029) (xy 223.075547 -85.051135) (xy 223.02011 -85.057235) (xy 222.964376 -85.055198)
			(xy 222.909533 -85.045068) (xy 222.856749 -85.027061) (xy 222.807149 -85.00156) (xy 222.761791 -84.969109)
			(xy 222.721642 -84.9304) (xy 222.687556 -84.886257) (xy 222.66026 -84.837622) (xy 222.640337 -84.785531)
			(xy 222.628211 -84.731094) (xy 222.62414 -84.675472) (xy 221.331402 -84.675472) (xy 221.333962 -84.684189)
			(xy 221.341718 -84.738137) (xy 221.342204 -84.765388) (xy 221.341574 -84.796411) (xy 221.331489 -84.857634)
			(xy 221.311633 -84.916418) (xy 221.282528 -84.971216) (xy 221.264226 -84.996274) (xy 221.258819 -85.004021)
			(xy 221.253614 -85.022169) (xy 221.255325 -85.040972) (xy 221.259146 -85.049614) (xy 221.299786 -85.131402)
			(xy 221.304373 -85.139633) (xy 221.318287 -85.152314) (xy 221.335839 -85.159122) (xy 221.345252 -85.159596)
			(xy 225.286062 -85.159596) (xy 225.296127 -85.159161) (xy 225.314715 -85.151431) (xy 225.32213 -85.14461)
			(xy 230.18877 -80.27797) (xy 230.212548 -80.25486) (xy 230.264401 -80.213528) (xy 230.320556 -80.178261)
			(xy 230.380306 -80.149502) (xy 230.442899 -80.127614) (xy 230.50755 -80.112871) (xy 230.573445 -80.105458)
			(xy 230.6066 -80.104996) (xy 235.966 -80.104996) (xy 235.999155 -80.10546) (xy 236.065049 -80.11288)
			(xy 236.129698 -80.127626) (xy 236.192292 -80.149514) (xy 236.252043 -80.178269) (xy 236.308201 -80.213528)
			(xy 236.360061 -80.254851) (xy 236.38383 -80.27797) (xy 236.75467 -80.64881) (xy 236.762068 -80.655655)
			(xy 236.780667 -80.663378) (xy 236.790738 -80.663796) (xy 237.586012 -80.663796) (xy 237.595858 -80.663351)
			(xy 237.614098 -80.655937) (xy 237.62818 -80.642176) (xy 237.632494 -80.633316) (xy 237.676182 -80.534002)
			(xy 237.671356 -80.504538) (xy 237.660942 -80.493362) (xy 237.642088 -80.472214) (xy 237.609197 -80.426081)
			(xy 237.582249 -80.376242) (xy 237.561657 -80.323458) (xy 237.547735 -80.268537) (xy 237.540697 -80.212319)
			(xy 237.540292 -80.18399) (xy 237.540292 -79.319882) (xy 237.540782 -79.289914) (xy 237.548605 -79.230492)
			(xy 237.564118 -79.172599) (xy 237.587054 -79.117226) (xy 237.617021 -79.06532) (xy 237.653508 -79.01777)
			(xy 237.695888 -78.97539) (xy 237.743438 -78.938903) (xy 237.795344 -78.908936) (xy 237.850717 -78.886)
			(xy 237.90861 -78.870487) (xy 237.968032 -78.862664) (xy 238.027968 -78.862664) (xy 238.08739 -78.870487)
			(xy 238.145283 -78.886) (xy 238.200656 -78.908936) (xy 238.252562 -78.938903) (xy 238.300112 -78.97539)
			(xy 238.342492 -79.01777) (xy 238.378979 -79.06532) (xy 238.408946 -79.117226) (xy 238.431882 -79.172599)
			(xy 238.447395 -79.230492) (xy 238.455218 -79.289914) (xy 238.455708 -79.319882) (xy 238.455708 -79.779368)
			(xy 250.4473 -79.779368) (xy 250.451371 -79.723746) (xy 250.463497 -79.669309) (xy 250.48342 -79.617218)
			(xy 250.510716 -79.568583) (xy 250.544802 -79.52444) (xy 250.584951 -79.485731) (xy 250.630309 -79.45328)
			(xy 250.679909 -79.427779) (xy 250.732693 -79.409772) (xy 250.787536 -79.399642) (xy 250.84327 -79.397605)
			(xy 250.898707 -79.403705) (xy 250.952664 -79.417811) (xy 251.003993 -79.439623) (xy 251.051599 -79.468677)
			(xy 251.094467 -79.504352) (xy 251.131684 -79.545889) (xy 251.162457 -79.592402) (xy 251.186129 -79.642899)
			(xy 251.202197 -79.696306) (xy 251.210317 -79.751482) (xy 251.210826 -79.779368) (xy 251.210317 -79.807254)
			(xy 251.202197 -79.86243) (xy 251.186129 -79.915837) (xy 251.162457 -79.966334) (xy 251.131684 -80.012847)
			(xy 251.094467 -80.054384) (xy 251.051599 -80.090059) (xy 251.003993 -80.119113) (xy 250.952664 -80.140925)
			(xy 250.898707 -80.155031) (xy 250.84327 -80.161131) (xy 250.787536 -80.159094) (xy 250.732693 -80.148964)
			(xy 250.679909 -80.130957) (xy 250.630309 -80.105456) (xy 250.584951 -80.073005) (xy 250.544802 -80.034296)
			(xy 250.510716 -79.990153) (xy 250.48342 -79.941518) (xy 250.463497 -79.889427) (xy 250.451371 -79.83499)
			(xy 250.4473 -79.779368) (xy 238.455708 -79.779368) (xy 238.455708 -80.18399) (xy 238.455272 -80.212319)
			(xy 238.448252 -80.26854) (xy 238.434344 -80.323465) (xy 238.41376 -80.376251) (xy 238.386816 -80.426092)
			(xy 238.353923 -80.472224) (xy 238.335058 -80.493362) (xy 238.324644 -80.504538) (xy 238.319818 -80.534002)
			(xy 238.363506 -80.633316) (xy 238.367861 -80.642152) (xy 238.381938 -80.655906) (xy 238.400149 -80.66337)
			(xy 238.409988 -80.663796) (xy 238.870744 -80.663796) (xy 238.903898 -80.664262) (xy 238.969789 -80.671686)
			(xy 239.034436 -80.686437) (xy 239.097026 -80.708328) (xy 239.156774 -80.737086) (xy 239.190936 -80.758538)
			(xy 241.160044 -80.758538) (xy 241.164115 -80.702916) (xy 241.176241 -80.648479) (xy 241.196164 -80.596388)
			(xy 241.22346 -80.547753) (xy 241.257546 -80.50361) (xy 241.297695 -80.464901) (xy 241.343053 -80.43245)
			(xy 241.392653 -80.406949) (xy 241.445437 -80.388942) (xy 241.50028 -80.378812) (xy 241.556014 -80.376775)
			(xy 241.611451 -80.382875) (xy 241.665408 -80.396981) (xy 241.716737 -80.418793) (xy 241.764343 -80.447847)
			(xy 241.807211 -80.483522) (xy 241.844428 -80.525059) (xy 241.875201 -80.571572) (xy 241.898873 -80.622069)
			(xy 241.914941 -80.675476) (xy 241.923061 -80.730652) (xy 241.92357 -80.758538) (xy 241.923061 -80.786424)
			(xy 241.918642 -80.81645) (xy 251.98019 -80.81645) (xy 251.984261 -80.760828) (xy 251.996387 -80.706391)
			(xy 252.01631 -80.6543) (xy 252.043606 -80.605665) (xy 252.077692 -80.561522) (xy 252.117841 -80.522813)
			(xy 252.163199 -80.490362) (xy 252.212799 -80.464861) (xy 252.265583 -80.446854) (xy 252.320426 -80.436724)
			(xy 252.37616 -80.434687) (xy 252.431597 -80.440787) (xy 252.485554 -80.454893) (xy 252.536883 -80.476705)
			(xy 252.584489 -80.505759) (xy 252.627357 -80.541434) (xy 252.664574 -80.582971) (xy 252.695347 -80.629484)
			(xy 252.719019 -80.679981) (xy 252.735087 -80.733388) (xy 252.740994 -80.773524) (xy 253.898652 -80.773524)
			(xy 253.902723 -80.717902) (xy 253.914849 -80.663465) (xy 253.934772 -80.611374) (xy 253.962068 -80.562739)
			(xy 253.996154 -80.518596) (xy 254.036303 -80.479887) (xy 254.081661 -80.447436) (xy 254.131261 -80.421935)
			(xy 254.184045 -80.403928) (xy 254.238888 -80.393798) (xy 254.294622 -80.391761) (xy 254.350059 -80.397861)
			(xy 254.404016 -80.411967) (xy 254.455345 -80.433779) (xy 254.502951 -80.462833) (xy 254.545819 -80.498508)
			(xy 254.583036 -80.540045) (xy 254.613809 -80.586558) (xy 254.637481 -80.637055) (xy 254.653549 -80.690462)
			(xy 254.661669 -80.745638) (xy 254.662178 -80.773524) (xy 254.661669 -80.80141) (xy 254.653549 -80.856586)
			(xy 254.637481 -80.909993) (xy 254.613809 -80.96049) (xy 254.583036 -81.007003) (xy 254.545819 -81.04854)
			(xy 254.502951 -81.084215) (xy 254.455345 -81.113269) (xy 254.404016 -81.135081) (xy 254.350059 -81.149187)
			(xy 254.294622 -81.155287) (xy 254.238888 -81.15325) (xy 254.184045 -81.14312) (xy 254.131261 -81.125113)
			(xy 254.081661 -81.099612) (xy 254.036303 -81.067161) (xy 253.996154 -81.028452) (xy 253.962068 -80.984309)
			(xy 253.934772 -80.935674) (xy 253.914849 -80.883583) (xy 253.902723 -80.829146) (xy 253.898652 -80.773524)
			(xy 252.740994 -80.773524) (xy 252.743207 -80.788564) (xy 252.743716 -80.81645) (xy 252.743207 -80.844336)
			(xy 252.735087 -80.899512) (xy 252.719019 -80.952919) (xy 252.695347 -81.003416) (xy 252.664574 -81.049929)
			(xy 252.627357 -81.091466) (xy 252.584489 -81.127141) (xy 252.536883 -81.156195) (xy 252.485554 -81.178007)
			(xy 252.431597 -81.192113) (xy 252.37616 -81.198213) (xy 252.320426 -81.196176) (xy 252.265583 -81.186046)
			(xy 252.212799 -81.168039) (xy 252.163199 -81.142538) (xy 252.117841 -81.110087) (xy 252.077692 -81.071378)
			(xy 252.043606 -81.027235) (xy 252.01631 -80.9786) (xy 251.996387 -80.926509) (xy 251.984261 -80.872072)
			(xy 251.98019 -80.81645) (xy 241.918642 -80.81645) (xy 241.914941 -80.8416) (xy 241.898873 -80.895007)
			(xy 241.875201 -80.945504) (xy 241.844428 -80.992017) (xy 241.807211 -81.033554) (xy 241.764343 -81.069229)
			(xy 241.716737 -81.098283) (xy 241.665408 -81.120095) (xy 241.611451 -81.134201) (xy 241.556014 -81.140301)
			(xy 241.50028 -81.138264) (xy 241.445437 -81.128134) (xy 241.392653 -81.110127) (xy 241.343053 -81.084626)
			(xy 241.297695 -81.052175) (xy 241.257546 -81.013466) (xy 241.22346 -80.969323) (xy 241.196164 -80.920688)
			(xy 241.176241 -80.868597) (xy 241.164115 -80.81416) (xy 241.160044 -80.758538) (xy 239.190936 -80.758538)
			(xy 239.212929 -80.772348) (xy 239.264785 -80.813672) (xy 239.288574 -80.83677) (xy 239.580674 -81.12887)
			(xy 239.603782 -81.152649) (xy 239.640503 -81.19872) (xy 240.342164 -81.19872) (xy 240.346235 -81.143098)
			(xy 240.358361 -81.088661) (xy 240.378284 -81.03657) (xy 240.40558 -80.987935) (xy 240.439666 -80.943792)
			(xy 240.479815 -80.905083) (xy 240.525173 -80.872632) (xy 240.574773 -80.847131) (xy 240.627557 -80.829124)
			(xy 240.6824 -80.818994) (xy 240.738134 -80.816957) (xy 240.793571 -80.823057) (xy 240.847528 -80.837163)
			(xy 240.898857 -80.858975) (xy 240.946463 -80.888029) (xy 240.989331 -80.923704) (xy 241.026548 -80.965241)
			(xy 241.057321 -81.011754) (xy 241.080993 -81.062251) (xy 241.097061 -81.115658) (xy 241.105181 -81.170834)
			(xy 241.10569 -81.19872) (xy 241.105181 -81.226606) (xy 241.097061 -81.281782) (xy 241.080993 -81.335189)
			(xy 241.057321 -81.385686) (xy 241.026548 -81.432199) (xy 240.989331 -81.473736) (xy 240.946463 -81.509411)
			(xy 240.898857 -81.538465) (xy 240.847528 -81.560277) (xy 240.837281 -81.562956) (xy 264.230864 -81.562956)
			(xy 264.234935 -81.507334) (xy 264.247061 -81.452897) (xy 264.266984 -81.400806) (xy 264.29428 -81.352171)
			(xy 264.328366 -81.308028) (xy 264.368515 -81.269319) (xy 264.413873 -81.236868) (xy 264.463473 -81.211367)
			(xy 264.516257 -81.19336) (xy 264.5711 -81.18323) (xy 264.626834 -81.181193) (xy 264.682271 -81.187293)
			(xy 264.736228 -81.201399) (xy 264.787557 -81.223211) (xy 264.835163 -81.252265) (xy 264.878031 -81.28794)
			(xy 264.915248 -81.329477) (xy 264.946021 -81.37599) (xy 264.969693 -81.426487) (xy 264.985761 -81.479894)
			(xy 264.993881 -81.53507) (xy 264.99439 -81.562956) (xy 264.993881 -81.590842) (xy 264.985761 -81.646018)
			(xy 264.969693 -81.699425) (xy 264.946021 -81.749922) (xy 264.915248 -81.796435) (xy 264.878031 -81.837972)
			(xy 264.835163 -81.873647) (xy 264.787557 -81.902701) (xy 264.736228 -81.924513) (xy 264.682271 -81.938619)
			(xy 264.626834 -81.944719) (xy 264.5711 -81.942682) (xy 264.516257 -81.932552) (xy 264.463473 -81.914545)
			(xy 264.413873 -81.889044) (xy 264.368515 -81.856593) (xy 264.328366 -81.817884) (xy 264.29428 -81.773741)
			(xy 264.266984 -81.725106) (xy 264.247061 -81.673015) (xy 264.234935 -81.618578) (xy 264.230864 -81.562956)
			(xy 240.837281 -81.562956) (xy 240.793571 -81.574383) (xy 240.738134 -81.580483) (xy 240.6824 -81.578446)
			(xy 240.627557 -81.568316) (xy 240.574773 -81.550309) (xy 240.525173 -81.524808) (xy 240.479815 -81.492357)
			(xy 240.439666 -81.453648) (xy 240.40558 -81.409505) (xy 240.378284 -81.36087) (xy 240.358361 -81.308779)
			(xy 240.346235 -81.254342) (xy 240.342164 -81.19872) (xy 239.640503 -81.19872) (xy 239.645112 -81.204503)
			(xy 239.680376 -81.260658) (xy 239.709132 -81.320408) (xy 239.731019 -81.383001) (xy 239.745761 -81.447651)
			(xy 239.753173 -81.513545) (xy 239.753648 -81.5467) (xy 239.753648 -81.750408) (xy 239.754074 -81.760476)
			(xy 239.761796 -81.779074) (xy 239.768634 -81.786476) (xy 239.871504 -81.889346) (xy 239.894644 -81.913106)
			(xy 239.936012 -81.964949) (xy 239.971315 -82.021099) (xy 239.988364 -82.056478) (xy 254.425956 -82.056478)
			(xy 254.430027 -82.000856) (xy 254.442153 -81.946419) (xy 254.462076 -81.894328) (xy 254.489372 -81.845693)
			(xy 254.523458 -81.80155) (xy 254.563607 -81.762841) (xy 254.608965 -81.73039) (xy 254.658565 -81.704889)
			(xy 254.711349 -81.686882) (xy 254.766192 -81.676752) (xy 254.821926 -81.674715) (xy 254.877363 -81.680815)
			(xy 254.93132 -81.694921) (xy 254.982649 -81.716733) (xy 255.030255 -81.745787) (xy 255.073123 -81.781462)
			(xy 255.11034 -81.822999) (xy 255.141113 -81.869512) (xy 255.164785 -81.920009) (xy 255.180853 -81.973416)
			(xy 255.188973 -82.028592) (xy 255.189482 -82.056478) (xy 255.188973 -82.084364) (xy 255.180853 -82.13954)
			(xy 255.164785 -82.192947) (xy 255.141113 -82.243444) (xy 255.11034 -82.289957) (xy 255.073123 -82.331494)
			(xy 255.030255 -82.367169) (xy 254.982649 -82.396223) (xy 254.93132 -82.418035) (xy 254.877363 -82.432141)
			(xy 254.821926 -82.438241) (xy 254.766192 -82.436204) (xy 254.711349 -82.426074) (xy 254.658565 -82.408067)
			(xy 254.608965 -82.382566) (xy 254.563607 -82.350115) (xy 254.523458 -82.311406) (xy 254.489372 -82.267263)
			(xy 254.462076 -82.218628) (xy 254.442153 -82.166537) (xy 254.430027 -82.1121) (xy 254.425956 -82.056478)
			(xy 239.988364 -82.056478) (xy 240.000108 -82.080849) (xy 240.02203 -82.143447) (xy 240.036804 -82.208106)
			(xy 240.044244 -82.274013) (xy 240.044732 -82.307176) (xy 240.044285 -82.34034) (xy 240.036859 -82.406252)
			(xy 240.022099 -82.470917) (xy 240.000189 -82.533522) (xy 239.971405 -82.593279) (xy 239.93611 -82.649437)
			(xy 239.894748 -82.701289) (xy 239.847838 -82.748182) (xy 239.795972 -82.789527) (xy 239.739802 -82.824803)
			(xy 239.680035 -82.853566) (xy 239.617422 -82.875455) (xy 239.552752 -82.890193) (xy 239.486838 -82.897596)
			(xy 239.453674 -82.89798) (xy 239.42137 -82.897556) (xy 239.357144 -82.89053) (xy 239.294068 -82.876543)
			(xy 239.232893 -82.855761) (xy 239.174349 -82.828432) (xy 239.119134 -82.794883) (xy 239.093248 -82.775552)
			(xy 239.086644 -82.770472) (xy 239.070896 -82.764884) (xy 238.972852 -82.764884) (xy 238.957104 -82.770472)
			(xy 238.9505 -82.775552) (xy 238.924662 -82.794879) (xy 238.869529 -82.828409) (xy 238.811069 -82.855726)
			(xy 238.749979 -82.876507) (xy 238.686988 -82.890504) (xy 238.622846 -82.897548) (xy 238.590582 -82.89798)
			(xy 238.590074 -82.89798) (xy 238.554728 -82.897461) (xy 238.484541 -82.889025) (xy 238.415861 -82.872276)
			(xy 238.349671 -82.847453) (xy 238.286914 -82.814911) (xy 238.228487 -82.775115) (xy 238.175225 -82.728633)
			(xy 238.127889 -82.67613) (xy 238.087154 -82.618354) (xy 238.053602 -82.556131) (xy 238.027713 -82.49035)
			(xy 238.009857 -82.42195) (xy 238.000287 -82.351908) (xy 237.99927 -82.316574) (xy 237.99927 -82.31632)
			(xy 237.998484 -82.304733) (xy 237.987909 -82.284084) (xy 237.97895 -82.276696) (xy 237.905036 -82.221324)
			(xy 237.881668 -82.217006) (xy 237.870492 -82.220308) (xy 237.831706 -82.230344) (xy 237.752309 -82.241052)
			(xy 237.71225 -82.241644) (xy 237.21695 -82.241644) (xy 237.181133 -82.241119) (xy 237.110025 -82.232461)
			(xy 237.040483 -82.215278) (xy 236.973525 -82.189821) (xy 236.910133 -82.156464) (xy 236.8804 -82.136488)
			(xy 236.873901 -82.132302) (xy 236.859168 -82.127645) (xy 236.851444 -82.127344) (xy 236.40796 -82.127344)
			(xy 236.374806 -82.126878) (xy 236.308914 -82.119455) (xy 236.244266 -82.104705) (xy 236.181675 -82.082815)
			(xy 236.121925 -82.05406) (xy 236.065769 -82.018799) (xy 236.01391 -81.977477) (xy 235.99013 -81.95437)
			(xy 235.61929 -81.58353) (xy 235.611892 -81.576682) (xy 235.593294 -81.568946) (xy 235.583222 -81.568544)
			(xy 235.182156 -81.568544) (xy 235.174423 -81.568805) (xy 235.159673 -81.573451) (xy 235.1532 -81.577688)
			(xy 235.123464 -81.597664) (xy 235.060084 -81.631053) (xy 234.993129 -81.656527) (xy 234.923583 -81.67371)
			(xy 234.852469 -81.68235) (xy 234.81665 -81.682844) (xy 234.32135 -81.682844) (xy 234.285533 -81.682319)
			(xy 234.214425 -81.673661) (xy 234.144883 -81.656478) (xy 234.077925 -81.631021) (xy 234.014533 -81.597664)
			(xy 233.9848 -81.577688) (xy 233.978301 -81.573502) (xy 233.963568 -81.568845) (xy 233.955844 -81.568544)
			(xy 232.616756 -81.568544) (xy 232.609023 -81.568805) (xy 232.594273 -81.573451) (xy 232.5878 -81.577688)
			(xy 232.558064 -81.597664) (xy 232.494684 -81.631053) (xy 232.427729 -81.656527) (xy 232.358183 -81.67371)
			(xy 232.287069 -81.68235) (xy 232.25125 -81.682844) (xy 231.75595 -81.682844) (xy 231.720133 -81.682319)
			(xy 231.649025 -81.673661) (xy 231.579483 -81.656478) (xy 231.512525 -81.631021) (xy 231.449133 -81.597664)
			(xy 231.4194 -81.577688) (xy 231.412901 -81.573502) (xy 231.398168 -81.568845) (xy 231.390444 -81.568544)
			(xy 230.989378 -81.568544) (xy 230.979311 -81.568972) (xy 230.960716 -81.576697) (xy 230.95331 -81.58353)
			(xy 229.169882 -83.367118) (xy 232.68432 -83.367118) (xy 232.68432 -82.503518) (xy 232.68481 -82.47355)
			(xy 232.692633 -82.414128) (xy 232.708146 -82.356235) (xy 232.731082 -82.300862) (xy 232.761049 -82.248956)
			(xy 232.797536 -82.201406) (xy 232.839916 -82.159026) (xy 232.887466 -82.122539) (xy 232.939372 -82.092572)
			(xy 232.994745 -82.069636) (xy 233.052638 -82.054123) (xy 233.11206 -82.0463) (xy 233.171996 -82.0463)
			(xy 233.231418 -82.054123) (xy 233.289311 -82.069636) (xy 233.344684 -82.092572) (xy 233.39659 -82.122539)
			(xy 233.44414 -82.159026) (xy 233.48652 -82.201406) (xy 233.523007 -82.248956) (xy 233.552974 -82.300862)
			(xy 233.57591 -82.356235) (xy 233.591423 -82.414128) (xy 233.599246 -82.47355) (xy 233.599736 -82.503518)
			(xy 233.599736 -83.367118) (xy 233.599246 -83.397086) (xy 233.591423 -83.456508) (xy 233.57591 -83.514401)
			(xy 233.552974 -83.569774) (xy 233.523007 -83.62168) (xy 233.48652 -83.66923) (xy 233.44414 -83.71161)
			(xy 233.39659 -83.748097) (xy 233.344684 -83.778064) (xy 233.289311 -83.801) (xy 233.231418 -83.816513)
			(xy 233.171996 -83.824336) (xy 233.11206 -83.824336) (xy 233.052638 -83.816513) (xy 232.994745 -83.801)
			(xy 232.939372 -83.778064) (xy 232.887466 -83.748097) (xy 232.839916 -83.71161) (xy 232.797536 -83.66923)
			(xy 232.761049 -83.62168) (xy 232.731082 -83.569774) (xy 232.708146 -83.514401) (xy 232.692633 -83.456508)
			(xy 232.68481 -83.397086) (xy 232.68432 -83.367118) (xy 229.169882 -83.367118) (xy 228.128576 -84.408518)
			(xy 228.121689 -84.416116) (xy 228.114056 -84.435131) (xy 228.11441 -84.455618) (xy 228.118162 -84.46516)
			(xy 228.163374 -84.566252) (xy 228.190298 -84.582508) (xy 228.206046 -84.581492) (xy 228.227382 -84.580984)
			(xy 228.254636 -84.581446) (xy 228.308589 -84.589201) (xy 228.360889 -84.604555) (xy 228.410472 -84.627196)
			(xy 228.456328 -84.656664) (xy 228.497523 -84.692357) (xy 228.53322 -84.73355) (xy 228.56269 -84.779404)
			(xy 228.585335 -84.828985) (xy 228.600693 -84.881284) (xy 228.608452 -84.935237) (xy 228.608453 -84.989744)
			(xy 228.600697 -85.043697) (xy 228.585342 -85.095997) (xy 228.562699 -85.14558) (xy 228.533231 -85.191435)
			(xy 228.497537 -85.23263) (xy 228.456343 -85.268325) (xy 228.410489 -85.297795) (xy 228.360907 -85.320438)
			(xy 228.308607 -85.335795) (xy 228.254654 -85.343553) (xy 228.200147 -85.343553) (xy 228.146194 -85.335795)
			(xy 228.093894 -85.320439) (xy 228.044313 -85.297795) (xy 227.998458 -85.268326) (xy 227.957264 -85.232631)
			(xy 227.92157 -85.191436) (xy 227.892101 -85.145581) (xy 227.869459 -85.095999) (xy 227.854103 -85.043699)
			(xy 227.846347 -84.989746) (xy 227.845874 -84.962492) (xy 227.846382 -84.941156) (xy 227.847398 -84.925408)
			(xy 227.831142 -84.898484) (xy 227.73005 -84.853272) (xy 227.720509 -84.849498) (xy 227.700014 -84.849105)
			(xy 227.68101 -84.856791) (xy 227.673408 -84.863686) (xy 227.078393 -85.458587) (xy 232.264389 -85.458587)
			(xy 232.264389 -85.398613) (xy 232.272218 -85.339151) (xy 232.28774 -85.28122) (xy 232.310692 -85.225811)
			(xy 232.34068 -85.173871) (xy 232.377191 -85.126291) (xy 232.4196 -85.083883) (xy 232.467181 -85.047373)
			(xy 232.519122 -85.017387) (xy 232.574531 -84.994437) (xy 232.632463 -84.978915) (xy 232.691925 -84.971088)
			(xy 232.721912 -84.97062) (xy 233.585512 -84.97062) (xy 233.615495 -84.971147) (xy 233.674947 -84.978975)
			(xy 233.732868 -84.994497) (xy 233.788268 -85.017445) (xy 233.840199 -85.047429) (xy 233.887772 -85.083934)
			(xy 233.930174 -85.126337) (xy 233.963295 -85.169502) (xy 238.555276 -85.169502) (xy 238.555276 -84.305902)
			(xy 238.555766 -84.275918) (xy 238.563594 -84.216462) (xy 238.579115 -84.158537) (xy 238.602064 -84.103133)
			(xy 238.632048 -84.051199) (xy 238.668554 -84.003623) (xy 238.710959 -83.961218) (xy 238.758535 -83.924712)
			(xy 238.810469 -83.894728) (xy 238.865873 -83.871779) (xy 238.923798 -83.856258) (xy 238.983254 -83.84843)
			(xy 239.043222 -83.84843) (xy 239.102678 -83.856258) (xy 239.160603 -83.871779) (xy 239.216007 -83.894728)
			(xy 239.267941 -83.924712) (xy 239.315517 -83.961218) (xy 239.357922 -84.003623) (xy 239.394428 -84.051199)
			(xy 239.424412 -84.103133) (xy 239.447361 -84.158537) (xy 239.462882 -84.216462) (xy 239.47071 -84.275918)
			(xy 239.4712 -84.305902) (xy 239.4712 -84.320888) (xy 247.814082 -84.320888) (xy 247.818153 -84.265266)
			(xy 247.830279 -84.210829) (xy 247.850202 -84.158738) (xy 247.877498 -84.110103) (xy 247.911584 -84.06596)
			(xy 247.951733 -84.027251) (xy 247.997091 -83.9948) (xy 248.046691 -83.969299) (xy 248.099475 -83.951292)
			(xy 248.154318 -83.941162) (xy 248.210052 -83.939125) (xy 248.265489 -83.945225) (xy 248.319446 -83.959331)
			(xy 248.370775 -83.981143) (xy 248.418381 -84.010197) (xy 248.461249 -84.045872) (xy 248.498466 -84.087409)
			(xy 248.529239 -84.133922) (xy 248.552911 -84.184419) (xy 248.568979 -84.237826) (xy 248.577099 -84.293002)
			(xy 248.577608 -84.320888) (xy 248.577099 -84.348774) (xy 248.568979 -84.40395) (xy 248.553926 -84.453984)
			(xy 254.399286 -84.453984) (xy 254.403357 -84.398362) (xy 254.415483 -84.343925) (xy 254.435406 -84.291834)
			(xy 254.462702 -84.243199) (xy 254.496788 -84.199056) (xy 254.536937 -84.160347) (xy 254.582295 -84.127896)
			(xy 254.631895 -84.102395) (xy 254.684679 -84.084388) (xy 254.739522 -84.074258) (xy 254.795256 -84.072221)
			(xy 254.850693 -84.078321) (xy 254.90465 -84.092427) (xy 254.955979 -84.114239) (xy 255.003585 -84.143293)
			(xy 255.046453 -84.178968) (xy 255.08367 -84.220505) (xy 255.114443 -84.267018) (xy 255.138115 -84.317515)
			(xy 255.154183 -84.370922) (xy 255.162303 -84.426098) (xy 255.162812 -84.453984) (xy 255.162303 -84.48187)
			(xy 255.154183 -84.537046) (xy 255.138115 -84.590453) (xy 255.114443 -84.64095) (xy 255.08367 -84.687463)
			(xy 255.046453 -84.729) (xy 255.010664 -84.758784) (xy 264.526774 -84.758784) (xy 264.530845 -84.703162)
			(xy 264.542971 -84.648725) (xy 264.562894 -84.596634) (xy 264.59019 -84.547999) (xy 264.624276 -84.503856)
			(xy 264.664425 -84.465147) (xy 264.709783 -84.432696) (xy 264.759383 -84.407195) (xy 264.812167 -84.389188)
			(xy 264.86701 -84.379058) (xy 264.922744 -84.377021) (xy 264.978181 -84.383121) (xy 265.032138 -84.397227)
			(xy 265.083467 -84.419039) (xy 265.131073 -84.448093) (xy 265.173941 -84.483768) (xy 265.211158 -84.525305)
			(xy 265.241931 -84.571818) (xy 265.265603 -84.622315) (xy 265.281671 -84.675722) (xy 265.289791 -84.730898)
			(xy 265.2903 -84.758784) (xy 265.289791 -84.78667) (xy 265.281671 -84.841846) (xy 265.265603 -84.895253)
			(xy 265.241931 -84.94575) (xy 265.211158 -84.992263) (xy 265.173941 -85.0338) (xy 265.131073 -85.069475)
			(xy 265.083467 -85.098529) (xy 265.032138 -85.120341) (xy 264.978181 -85.134447) (xy 264.922744 -85.140547)
			(xy 264.86701 -85.13851) (xy 264.812167 -85.12838) (xy 264.759383 -85.110373) (xy 264.709783 -85.084872)
			(xy 264.664425 -85.052421) (xy 264.624276 -85.013712) (xy 264.59019 -84.969569) (xy 264.562894 -84.920934)
			(xy 264.542971 -84.868843) (xy 264.530845 -84.814406) (xy 264.526774 -84.758784) (xy 255.010664 -84.758784)
			(xy 255.003585 -84.764675) (xy 254.955979 -84.793729) (xy 254.90465 -84.815541) (xy 254.850693 -84.829647)
			(xy 254.795256 -84.835747) (xy 254.739522 -84.83371) (xy 254.684679 -84.82358) (xy 254.631895 -84.805573)
			(xy 254.582295 -84.780072) (xy 254.536937 -84.747621) (xy 254.496788 -84.708912) (xy 254.462702 -84.664769)
			(xy 254.435406 -84.616134) (xy 254.415483 -84.564043) (xy 254.403357 -84.509606) (xy 254.399286 -84.453984)
			(xy 248.553926 -84.453984) (xy 248.552911 -84.457357) (xy 248.529239 -84.507854) (xy 248.498466 -84.554367)
			(xy 248.461249 -84.595904) (xy 248.418381 -84.631579) (xy 248.370775 -84.660633) (xy 248.319446 -84.682445)
			(xy 248.265489 -84.696551) (xy 248.210052 -84.702651) (xy 248.154318 -84.700614) (xy 248.099475 -84.690484)
			(xy 248.046691 -84.672477) (xy 247.997091 -84.646976) (xy 247.951733 -84.614525) (xy 247.911584 -84.575816)
			(xy 247.877498 -84.531673) (xy 247.850202 -84.483038) (xy 247.830279 -84.430947) (xy 247.818153 -84.37651)
			(xy 247.814082 -84.320888) (xy 239.4712 -84.320888) (xy 239.4712 -85.169502) (xy 239.47071 -85.199486)
			(xy 239.462882 -85.258942) (xy 239.447361 -85.316867) (xy 239.424412 -85.372271) (xy 239.394428 -85.424205)
			(xy 239.357922 -85.471781) (xy 239.315517 -85.514186) (xy 239.267941 -85.550692) (xy 239.216007 -85.580676)
			(xy 239.160603 -85.603625) (xy 239.102678 -85.619146) (xy 239.043222 -85.626974) (xy 238.983254 -85.626974)
			(xy 238.923798 -85.619146) (xy 238.865873 -85.603625) (xy 238.810469 -85.580676) (xy 238.758535 -85.550692)
			(xy 238.710959 -85.514186) (xy 238.668554 -85.471781) (xy 238.632048 -85.424205) (xy 238.602064 -85.372271)
			(xy 238.579115 -85.316867) (xy 238.563594 -85.258942) (xy 238.555766 -85.199486) (xy 238.555276 -85.169502)
			(xy 233.963295 -85.169502) (xy 233.966678 -85.173911) (xy 233.99666 -85.225842) (xy 234.019607 -85.281243)
			(xy 234.035127 -85.339165) (xy 234.042954 -85.398617) (xy 234.042954 -85.458583) (xy 234.035127 -85.518035)
			(xy 234.019607 -85.575957) (xy 233.99666 -85.631358) (xy 233.966678 -85.683289) (xy 233.930174 -85.730863)
			(xy 233.887772 -85.773266) (xy 233.840199 -85.809771) (xy 233.788268 -85.839755) (xy 233.732868 -85.862703)
			(xy 233.674947 -85.878225) (xy 233.615495 -85.886053) (xy 233.585512 -85.886544) (xy 232.721912 -85.886544)
			(xy 232.691925 -85.886112) (xy 232.632463 -85.878285) (xy 232.574531 -85.862763) (xy 232.519122 -85.839813)
			(xy 232.467181 -85.809827) (xy 232.4196 -85.773317) (xy 232.377191 -85.730909) (xy 232.34068 -85.683329)
			(xy 232.310692 -85.631389) (xy 232.28774 -85.57598) (xy 232.272218 -85.518049) (xy 232.264389 -85.458587)
			(xy 227.078393 -85.458587) (xy 226.437969 -86.098888) (xy 247.814082 -86.098888) (xy 247.818153 -86.043266)
			(xy 247.830279 -85.988829) (xy 247.850202 -85.936738) (xy 247.877498 -85.888103) (xy 247.911584 -85.84396)
			(xy 247.951733 -85.805251) (xy 247.997091 -85.7728) (xy 248.046691 -85.747299) (xy 248.099475 -85.729292)
			(xy 248.154318 -85.719162) (xy 248.210052 -85.717125) (xy 248.265489 -85.723225) (xy 248.319446 -85.737331)
			(xy 248.370775 -85.759143) (xy 248.418381 -85.788197) (xy 248.461249 -85.823872) (xy 248.498466 -85.865409)
			(xy 248.529239 -85.911922) (xy 248.552911 -85.962419) (xy 248.568979 -86.015826) (xy 248.577099 -86.071002)
			(xy 248.577608 -86.098888) (xy 248.577099 -86.126774) (xy 248.568979 -86.18195) (xy 248.552911 -86.235357)
			(xy 248.529239 -86.285854) (xy 248.498466 -86.332367) (xy 248.461249 -86.373904) (xy 248.418381 -86.409579)
			(xy 248.370775 -86.438633) (xy 248.319446 -86.460445) (xy 248.265489 -86.474551) (xy 248.210052 -86.480651)
			(xy 248.154318 -86.478614) (xy 248.099475 -86.468484) (xy 248.046691 -86.450477) (xy 247.997091 -86.424976)
			(xy 247.951733 -86.392525) (xy 247.911584 -86.353816) (xy 247.877498 -86.309673) (xy 247.850202 -86.261038)
			(xy 247.830279 -86.208947) (xy 247.818153 -86.15451) (xy 247.814082 -86.098888) (xy 226.437969 -86.098888)
			(xy 226.349052 -86.187788) (xy 226.342245 -86.195218) (xy 226.334576 -86.213836) (xy 226.334618 -86.233971)
			(xy 226.33813 -86.243414) (xy 226.342397 -86.252431) (xy 226.356492 -86.266519) (xy 226.374902 -86.274148)
			(xy 226.384866 -86.274656) (xy 230.19004 -86.274656) (xy 230.223194 -86.275122) (xy 230.289086 -86.282545)
			(xy 230.353734 -86.297295) (xy 230.416325 -86.319185) (xy 230.476075 -86.34794) (xy 230.532231 -86.383201)
			(xy 230.58409 -86.424523) (xy 230.60787 -86.44763) (xy 231.604306 -87.444066) (xy 232.194882 -87.444066)
			(xy 232.194882 -87.384134) (xy 232.202704 -87.324714) (xy 232.218215 -87.266824) (xy 232.241149 -87.211454)
			(xy 232.271114 -87.15955) (xy 232.307596 -87.112002) (xy 232.349973 -87.069621) (xy 232.397519 -87.033135)
			(xy 232.44942 -87.003166) (xy 232.504788 -86.980227) (xy 232.562677 -86.964712) (xy 232.622096 -86.956884)
			(xy 232.652062 -86.956392) (xy 233.515662 -86.956392) (xy 233.545633 -86.956859) (xy 233.605062 -86.964678)
			(xy 233.662961 -86.980188) (xy 233.718341 -87.003123) (xy 233.770254 -87.033091) (xy 233.81781 -87.069578)
			(xy 233.860197 -87.111961) (xy 233.896688 -87.159515) (xy 233.92666 -87.211425) (xy 233.9496 -87.266803)
			(xy 233.965115 -87.324701) (xy 233.972939 -87.384129) (xy 233.972939 -87.416385) (xy 234.381521 -87.416385)
			(xy 234.381521 -87.356415) (xy 234.389349 -87.296959) (xy 234.40487 -87.239032) (xy 234.42782 -87.183628)
			(xy 234.457804 -87.131692) (xy 234.494312 -87.084115) (xy 234.536717 -87.04171) (xy 234.584294 -87.005203)
			(xy 234.636229 -86.975219) (xy 234.691634 -86.952269) (xy 234.749561 -86.936748) (xy 234.809017 -86.928921)
			(xy 234.839002 -86.928452) (xy 235.702602 -86.928452) (xy 235.732587 -86.928914) (xy 235.792044 -86.936742)
			(xy 235.849971 -86.952264) (xy 235.905376 -86.975214) (xy 235.957312 -87.005199) (xy 236.004889 -87.041707)
			(xy 236.047295 -87.084112) (xy 236.083802 -87.13169) (xy 236.113787 -87.183626) (xy 236.136737 -87.239031)
			(xy 236.152258 -87.296958) (xy 236.160086 -87.356415) (xy 236.160086 -87.416385) (xy 236.152258 -87.475842)
			(xy 236.136737 -87.533769) (xy 236.113787 -87.589174) (xy 236.083802 -87.64111) (xy 236.047295 -87.688688)
			(xy 236.004889 -87.731093) (xy 235.957312 -87.767601) (xy 235.905376 -87.797586) (xy 235.849971 -87.820536)
			(xy 235.792044 -87.836058) (xy 235.732587 -87.843886) (xy 235.702602 -87.844376) (xy 234.839002 -87.844376)
			(xy 234.809017 -87.843879) (xy 234.749561 -87.836052) (xy 234.691634 -87.820531) (xy 234.636229 -87.797581)
			(xy 234.584294 -87.767597) (xy 234.536717 -87.73109) (xy 234.494312 -87.688685) (xy 234.457804 -87.641108)
			(xy 234.42782 -87.589172) (xy 234.40487 -87.533768) (xy 234.389349 -87.475841) (xy 234.381521 -87.416385)
			(xy 233.972939 -87.416385) (xy 233.972939 -87.444071) (xy 233.965115 -87.503499) (xy 233.9496 -87.561397)
			(xy 233.92666 -87.616775) (xy 233.896688 -87.668685) (xy 233.860197 -87.716239) (xy 233.81781 -87.758622)
			(xy 233.770254 -87.795109) (xy 233.718341 -87.825077) (xy 233.662961 -87.848012) (xy 233.605062 -87.863522)
			(xy 233.545633 -87.871341) (xy 233.515662 -87.871808) (xy 232.652062 -87.871808) (xy 232.622096 -87.871316)
			(xy 232.562677 -87.863488) (xy 232.504788 -87.847973) (xy 232.44942 -87.825034) (xy 232.397519 -87.795065)
			(xy 232.349973 -87.758579) (xy 232.307596 -87.716198) (xy 232.271114 -87.66865) (xy 232.241149 -87.616746)
			(xy 232.218215 -87.561376) (xy 232.202704 -87.503486) (xy 232.194882 -87.444066) (xy 231.604306 -87.444066)
			(xy 233.44251 -89.28227) (xy 233.449908 -89.289118) (xy 233.468506 -89.296854) (xy 233.478578 -89.297256)
			(xy 234.147106 -89.297256) (xy 234.15669 -89.29684) (xy 234.174525 -89.289813) (xy 234.18857 -89.276766)
			(xy 234.19308 -89.2683) (xy 234.23245 -89.184988) (xy 234.236151 -89.176151) (xy 234.237395 -89.157046)
			(xy 234.231597 -89.1388) (xy 234.225846 -89.13114) (xy 234.209586 -89.110622) (xy 234.182249 -89.065975)
			(xy 234.16128 -89.018006) (xy 234.147073 -88.967619) (xy 234.139896 -88.915762) (xy 234.139486 -88.889586)
			(xy 234.139972 -88.862335) (xy 234.147728 -88.808387) (xy 234.163083 -88.756092) (xy 234.185725 -88.706515)
			(xy 234.215191 -88.660665) (xy 234.250882 -88.619474) (xy 234.292073 -88.583783) (xy 234.337923 -88.554317)
			(xy 234.3875 -88.531675) (xy 234.439795 -88.51632) (xy 234.493743 -88.508564) (xy 234.548245 -88.508564)
			(xy 234.602193 -88.51632) (xy 234.654488 -88.531675) (xy 234.704065 -88.554317) (xy 234.749915 -88.583783)
			(xy 234.791106 -88.619474) (xy 234.826797 -88.660665) (xy 234.856263 -88.706515) (xy 234.878905 -88.756092)
			(xy 234.89426 -88.808387) (xy 234.902016 -88.862335) (xy 234.902502 -88.889586) (xy 234.902052 -88.915759)
			(xy 234.894864 -88.96761) (xy 234.880661 -89.017994) (xy 234.859709 -89.065965) (xy 234.832402 -89.110626)
			(xy 234.816142 -89.13114) (xy 234.810368 -89.1388) (xy 234.804494 -89.157046) (xy 234.805758 -89.176173)
			(xy 234.809538 -89.184988) (xy 234.848908 -89.2683) (xy 234.853384 -89.276797) (xy 234.867412 -89.289891)
			(xy 234.885285 -89.296878) (xy 234.894882 -89.297256) (xy 235.532422 -89.297256) (xy 235.542489 -89.296828)
			(xy 235.561084 -89.289103) (xy 235.56849 -89.28227) (xy 236.32033 -88.53043) (xy 236.344109 -88.50732)
			(xy 236.395962 -88.465987) (xy 236.452116 -88.430718) (xy 236.511865 -88.401958) (xy 236.574459 -88.380067)
			(xy 236.639109 -88.36532) (xy 236.705004 -88.357904) (xy 236.73816 -88.357456) (xy 237.94847 -88.357456)
			(xy 237.961203 -88.356754) (xy 237.983594 -88.344621) (xy 237.991142 -88.334342) (xy 238.044736 -88.252046)
			(xy 238.046768 -88.226646) (xy 238.041434 -88.214708) (xy 238.029472 -88.18658) (xy 238.010753 -88.12839)
			(xy 237.998147 -88.068577) (xy 237.991788 -88.007781) (xy 237.991396 -87.977218) (xy 237.991396 -87.976202)
			(xy 237.991935 -87.940491) (xy 238.000541 -87.869589) (xy 238.017627 -87.800241) (xy 238.042946 -87.733457)
			(xy 238.076128 -87.67021) (xy 238.116689 -87.611423) (xy 238.164038 -87.557951) (xy 238.217485 -87.510575)
			(xy 238.276252 -87.469984) (xy 238.339481 -87.43677) (xy 238.406252 -87.411417) (xy 238.475592 -87.394295)
			(xy 238.546489 -87.385653) (xy 238.5822 -87.385144) (xy 238.614512 -87.385579) (xy 238.678751 -87.392632)
			(xy 238.741837 -87.406655) (xy 238.803014 -87.42748) (xy 238.861554 -87.454858) (xy 238.916755 -87.488461)
			(xy 238.942626 -87.507826) (xy 238.948976 -87.512906) (xy 238.964978 -87.51824) (xy 239.063022 -87.51824)
			(xy 239.079024 -87.512906) (xy 239.085374 -87.507826) (xy 239.111242 -87.488459) (xy 239.166446 -87.45486)
			(xy 239.224986 -87.427487) (xy 239.286165 -87.406666) (xy 239.34925 -87.392645) (xy 239.413488 -87.385592)
			(xy 239.4458 -87.385144) (xy 239.481494 -87.385682) (xy 239.552361 -87.394285) (xy 239.621675 -87.411366)
			(xy 239.688425 -87.436674) (xy 239.751639 -87.469843) (xy 239.810395 -87.510388) (xy 239.863837 -87.557718)
			(xy 239.911185 -87.611143) (xy 239.95175 -87.669885) (xy 239.984941 -87.733087) (xy 240.010273 -87.799829)
			(xy 240.027378 -87.869137) (xy 240.036005 -87.940001) (xy 240.036604 -87.975694) (xy 240.036604 -87.976202)
			(xy 240.03614 -88.009357) (xy 240.02872 -88.07525) (xy 240.013973 -88.1399) (xy 239.992085 -88.202493)
			(xy 239.963331 -88.262244) (xy 239.928071 -88.318402) (xy 239.886748 -88.370262) (xy 239.86363 -88.394032)
			(xy 239.76076 -88.496902) (xy 239.753987 -88.504328) (xy 239.7464 -88.522925) (xy 239.746028 -88.53297)
			(xy 239.746028 -88.86063) (xy 239.745546 -88.893791) (xy 239.738086 -88.959692) (xy 239.723299 -89.024345)
			(xy 239.701369 -89.086936) (xy 239.672572 -89.146681) (xy 239.63727 -89.202827) (xy 239.595906 -89.254669)
			(xy 239.5728 -89.27846) (xy 239.20323 -89.64803) (xy 239.179452 -89.67114) (xy 239.127599 -89.712472)
			(xy 239.071444 -89.747739) (xy 239.011694 -89.776498) (xy 238.949101 -89.798386) (xy 238.88445 -89.813129)
			(xy 238.818555 -89.820542) (xy 238.7854 -89.821004) (xy 237.6551 -89.821004) (xy 237.645673 -89.821383)
			(xy 237.628098 -89.828208) (xy 237.614185 -89.840932) (xy 237.609634 -89.849198) (xy 237.56874 -89.930732)
			(xy 237.56494 -89.939322) (xy 237.563179 -89.958007) (xy 237.568252 -89.976075) (xy 237.573566 -89.983818)
			(xy 237.591511 -90.008739) (xy 237.620043 -90.063116) (xy 237.639496 -90.12136) (xy 237.649369 -90.181969)
			(xy 237.65002 -90.212672) (xy 237.649559 -90.239927) (xy 237.641805 -90.293881) (xy 237.626452 -90.346183)
			(xy 237.603811 -90.395768) (xy 237.574344 -90.441625) (xy 237.538651 -90.482822) (xy 237.497457 -90.51852)
			(xy 237.451603 -90.547992) (xy 237.402021 -90.570638) (xy 237.34972 -90.585997) (xy 237.295766 -90.593756)
			(xy 237.268512 -90.59418) (xy 237.241007 -90.593706) (xy 237.186566 -90.585817) (xy 237.133824 -90.570185)
			(xy 237.083875 -90.547137) (xy 237.037758 -90.51715) (xy 236.996428 -90.480846) (xy 236.960745 -90.43898)
			(xy 236.931449 -90.39242) (xy 236.909148 -90.342134) (xy 236.894305 -90.289165) (xy 236.890306 -90.261948)
			(xy 236.888528 -90.24747) (xy 236.87024 -90.225118) (xy 236.76991 -90.191082) (xy 236.760808 -90.188476)
			(xy 236.74191 -90.189311) (xy 236.724582 -90.196897) (xy 236.717586 -90.203274) (xy 236.33303 -90.58783)
			(xy 236.307956 -90.612151) (xy 236.253057 -90.655346) (xy 236.19345 -90.691771) (xy 236.129965 -90.720915)
			(xy 236.063488 -90.742374) (xy 235.994945 -90.755848) (xy 235.960158 -90.759026) (xy 235.948821 -90.760579)
			(xy 235.929081 -90.772092) (xy 235.916249 -90.791001) (xy 235.91393 -90.802206) (xy 235.909471 -90.828962)
			(xy 235.893979 -90.880943) (xy 235.871281 -90.930207) (xy 235.841836 -90.97576) (xy 235.806237 -91.016684)
			(xy 235.765201 -91.052155) (xy 235.719556 -91.081457) (xy 235.70311 -91.088972) (xy 236.971838 -91.088972)
			(xy 236.975909 -91.03335) (xy 236.988035 -90.978913) (xy 237.007958 -90.926822) (xy 237.035254 -90.878187)
			(xy 237.06934 -90.834044) (xy 237.109489 -90.795335) (xy 237.154847 -90.762884) (xy 237.204447 -90.737383)
			(xy 237.257231 -90.719376) (xy 237.312074 -90.709246) (xy 237.367808 -90.707209) (xy 237.423245 -90.713309)
			(xy 237.477202 -90.727415) (xy 237.528531 -90.749227) (xy 237.576137 -90.778281) (xy 237.619005 -90.813956)
			(xy 237.656222 -90.855493) (xy 237.686995 -90.902006) (xy 237.710667 -90.952503) (xy 237.726735 -91.00591)
			(xy 237.734855 -91.061086) (xy 237.735364 -91.088972) (xy 237.734855 -91.116858) (xy 237.726735 -91.172034)
			(xy 237.710667 -91.225441) (xy 237.686995 -91.275938) (xy 237.656222 -91.322451) (xy 237.619005 -91.363988)
			(xy 237.576137 -91.399663) (xy 237.528531 -91.428717) (xy 237.477202 -91.450529) (xy 237.423245 -91.464635)
			(xy 237.367808 -91.470735) (xy 237.312074 -91.468698) (xy 237.257231 -91.458568) (xy 237.204447 -91.440561)
			(xy 237.154847 -91.41506) (xy 237.109489 -91.382609) (xy 237.06934 -91.3439) (xy 237.035254 -91.299757)
			(xy 237.007958 -91.251122) (xy 236.988035 -91.199031) (xy 236.975909 -91.144594) (xy 236.971838 -91.088972)
			(xy 235.70311 -91.088972) (xy 235.670221 -91.104) (xy 235.618191 -91.119329) (xy 235.564515 -91.127136)
			(xy 235.510274 -91.127264) (xy 235.456562 -91.119709) (xy 235.404461 -91.104624) (xy 235.355021 -91.082313)
			(xy 235.309239 -91.053225) (xy 235.268037 -91.017948) (xy 235.232246 -90.977191) (xy 235.202587 -90.931777)
			(xy 235.179659 -90.88262) (xy 235.163922 -90.830712) (xy 235.159296 -90.803984) (xy 235.157599 -90.795104)
			(xy 235.148883 -90.779278) (xy 235.135213 -90.767465) (xy 235.118291 -90.761137) (xy 235.109258 -90.760804)
			(xy 234.460034 -90.760804) (xy 234.451013 -90.761209) (xy 234.434115 -90.767542) (xy 234.420453 -90.779331)
			(xy 234.411714 -90.795119) (xy 234.409996 -90.803984) (xy 234.405404 -90.830663) (xy 234.389677 -90.882461)
			(xy 234.366788 -90.931518) (xy 234.337196 -90.976848) (xy 234.301497 -91.017542) (xy 234.260405 -91.052783)
			(xy 234.214746 -91.081863) (xy 234.165435 -91.1042) (xy 234.113463 -91.119346) (xy 234.059873 -91.126995)
			(xy 234.005739 -91.126995) (xy 233.952149 -91.119346) (xy 233.900177 -91.1042) (xy 233.850866 -91.081863)
			(xy 233.805207 -91.052783) (xy 233.764115 -91.017542) (xy 233.728416 -90.976848) (xy 233.698824 -90.931518)
			(xy 233.675935 -90.882461) (xy 233.660208 -90.830663) (xy 233.655616 -90.803984) (xy 233.653917 -90.79511)
			(xy 233.645197 -90.779299) (xy 233.631525 -90.767506) (xy 233.614605 -90.761202) (xy 233.605578 -90.760804)
			(xy 233.0958 -90.760804) (xy 233.062645 -90.76034) (xy 232.996751 -90.75292) (xy 232.932102 -90.738174)
			(xy 232.869508 -90.716286) (xy 232.809757 -90.687531) (xy 232.753599 -90.652272) (xy 232.701739 -90.610949)
			(xy 232.67797 -90.58783) (xy 229.84333 -87.75319) (xy 229.835932 -87.746345) (xy 229.817333 -87.738622)
			(xy 229.807262 -87.738204) (xy 224.878138 -87.738204) (xy 224.868073 -87.738639) (xy 224.849485 -87.746369)
			(xy 224.84207 -87.75319) (xy 222.89643 -89.69883) (xy 222.872652 -89.72194) (xy 222.820799 -89.763272)
			(xy 222.764644 -89.798539) (xy 222.704894 -89.827298) (xy 222.642301 -89.849186) (xy 222.57765 -89.863929)
			(xy 222.511755 -89.871342) (xy 222.4786 -89.871804) (xy 212.305138 -89.871804) (xy 212.295073 -89.872239)
			(xy 212.276485 -89.879969) (xy 212.26907 -89.88679) (xy 212.05063 -90.10523) (xy 212.026852 -90.12834)
			(xy 211.974999 -90.169672) (xy 211.918844 -90.204939) (xy 211.859094 -90.233698) (xy 211.796501 -90.255586)
			(xy 211.73185 -90.270329) (xy 211.665955 -90.277742) (xy 211.6328 -90.278204) (xy 207.829658 -90.278204)
			(xy 207.824639 -90.278295) (xy 207.814786 -90.280214) (xy 207.8101 -90.282014) (xy 207.361812 -90.467688)
			(xy 214.358472 -90.467688) (xy 214.362543 -90.412066) (xy 214.374669 -90.357629) (xy 214.394592 -90.305538)
			(xy 214.421888 -90.256903) (xy 214.455974 -90.21276) (xy 214.496123 -90.174051) (xy 214.541481 -90.1416)
			(xy 214.591081 -90.116099) (xy 214.643865 -90.098092) (xy 214.698708 -90.087962) (xy 214.754442 -90.085925)
			(xy 214.809879 -90.092025) (xy 214.863836 -90.106131) (xy 214.915165 -90.127943) (xy 214.962771 -90.156997)
			(xy 215.005639 -90.192672) (xy 215.042856 -90.234209) (xy 215.073629 -90.280722) (xy 215.097301 -90.331219)
			(xy 215.113369 -90.384626) (xy 215.121489 -90.439802) (xy 215.121998 -90.467688) (xy 215.121489 -90.495574)
			(xy 215.113369 -90.55075) (xy 215.097301 -90.604157) (xy 215.096977 -90.604848) (xy 216.170508 -90.604848)
			(xy 216.174579 -90.549226) (xy 216.186705 -90.494789) (xy 216.206628 -90.442698) (xy 216.233924 -90.394063)
			(xy 216.26801 -90.34992) (xy 216.308159 -90.311211) (xy 216.353517 -90.27876) (xy 216.403117 -90.253259)
			(xy 216.455901 -90.235252) (xy 216.510744 -90.225122) (xy 216.566478 -90.223085) (xy 216.621915 -90.229185)
			(xy 216.675872 -90.243291) (xy 216.727201 -90.265103) (xy 216.774807 -90.294157) (xy 216.817675 -90.329832)
			(xy 216.854892 -90.371369) (xy 216.885665 -90.417882) (xy 216.909337 -90.468379) (xy 216.925405 -90.521786)
			(xy 216.926938 -90.532204) (xy 217.059508 -90.532204) (xy 217.063579 -90.476582) (xy 217.075705 -90.422145)
			(xy 217.095628 -90.370054) (xy 217.122924 -90.321419) (xy 217.15701 -90.277276) (xy 217.197159 -90.238567)
			(xy 217.242517 -90.206116) (xy 217.292117 -90.180615) (xy 217.344901 -90.162608) (xy 217.399744 -90.152478)
			(xy 217.455478 -90.150441) (xy 217.510915 -90.156541) (xy 217.564872 -90.170647) (xy 217.616201 -90.192459)
			(xy 217.663807 -90.221513) (xy 217.706675 -90.257188) (xy 217.743892 -90.298725) (xy 217.774665 -90.345238)
			(xy 217.798337 -90.395735) (xy 217.814405 -90.449142) (xy 217.822525 -90.504318) (xy 217.823034 -90.532204)
			(xy 217.822525 -90.56009) (xy 217.814405 -90.615266) (xy 217.798337 -90.668673) (xy 217.774665 -90.71917)
			(xy 217.743892 -90.765683) (xy 217.706675 -90.80722) (xy 217.663807 -90.842895) (xy 217.616201 -90.871949)
			(xy 217.564872 -90.893761) (xy 217.510915 -90.907867) (xy 217.455478 -90.913967) (xy 217.399744 -90.91193)
			(xy 217.344901 -90.9018) (xy 217.292117 -90.883793) (xy 217.242517 -90.858292) (xy 217.197159 -90.825841)
			(xy 217.15701 -90.787132) (xy 217.122924 -90.742989) (xy 217.095628 -90.694354) (xy 217.075705 -90.642263)
			(xy 217.063579 -90.587826) (xy 217.059508 -90.532204) (xy 216.926938 -90.532204) (xy 216.933525 -90.576962)
			(xy 216.934034 -90.604848) (xy 216.933525 -90.632734) (xy 216.925405 -90.68791) (xy 216.909337 -90.741317)
			(xy 216.885665 -90.791814) (xy 216.854892 -90.838327) (xy 216.817675 -90.879864) (xy 216.774807 -90.915539)
			(xy 216.727201 -90.944593) (xy 216.675872 -90.966405) (xy 216.621915 -90.980511) (xy 216.566478 -90.986611)
			(xy 216.510744 -90.984574) (xy 216.455901 -90.974444) (xy 216.403117 -90.956437) (xy 216.353517 -90.930936)
			(xy 216.308159 -90.898485) (xy 216.26801 -90.859776) (xy 216.233924 -90.815633) (xy 216.206628 -90.766998)
			(xy 216.186705 -90.714907) (xy 216.174579 -90.66047) (xy 216.170508 -90.604848) (xy 215.096977 -90.604848)
			(xy 215.073629 -90.654654) (xy 215.042856 -90.701167) (xy 215.005639 -90.742704) (xy 214.962771 -90.778379)
			(xy 214.915165 -90.807433) (xy 214.863836 -90.829245) (xy 214.809879 -90.843351) (xy 214.754442 -90.849451)
			(xy 214.698708 -90.847414) (xy 214.643865 -90.837284) (xy 214.591081 -90.819277) (xy 214.541481 -90.793776)
			(xy 214.496123 -90.761325) (xy 214.455974 -90.722616) (xy 214.421888 -90.678473) (xy 214.394592 -90.629838)
			(xy 214.374669 -90.577747) (xy 214.362543 -90.52331) (xy 214.358472 -90.467688) (xy 207.361812 -90.467688)
			(xy 204.493628 -91.655646) (xy 215.233248 -91.655646) (xy 215.237319 -91.600024) (xy 215.249445 -91.545587)
			(xy 215.269368 -91.493496) (xy 215.296664 -91.444861) (xy 215.33075 -91.400718) (xy 215.370899 -91.362009)
			(xy 215.416257 -91.329558) (xy 215.465857 -91.304057) (xy 215.518641 -91.28605) (xy 215.573484 -91.27592)
			(xy 215.629218 -91.273883) (xy 215.684655 -91.279983) (xy 215.738612 -91.294089) (xy 215.789941 -91.315901)
			(xy 215.837547 -91.344955) (xy 215.880415 -91.38063) (xy 215.917632 -91.422167) (xy 215.923045 -91.430348)
			(xy 221.146114 -91.430348) (xy 221.150185 -91.374726) (xy 221.162311 -91.320289) (xy 221.182234 -91.268198)
			(xy 221.20953 -91.219563) (xy 221.243616 -91.17542) (xy 221.283765 -91.136711) (xy 221.329123 -91.10426)
			(xy 221.378723 -91.078759) (xy 221.431507 -91.060752) (xy 221.48635 -91.050622) (xy 221.542084 -91.048585)
			(xy 221.597521 -91.054685) (xy 221.651478 -91.068791) (xy 221.702807 -91.090603) (xy 221.750413 -91.119657)
			(xy 221.793281 -91.155332) (xy 221.830498 -91.196869) (xy 221.861271 -91.243382) (xy 221.884943 -91.293879)
			(xy 221.901011 -91.347286) (xy 221.909131 -91.402462) (xy 221.90964 -91.430348) (xy 221.909131 -91.458234)
			(xy 221.901011 -91.51341) (xy 221.884943 -91.566817) (xy 221.861271 -91.617314) (xy 221.830498 -91.663827)
			(xy 221.793281 -91.705364) (xy 221.750413 -91.741039) (xy 221.702807 -91.770093) (xy 221.651478 -91.791905)
			(xy 221.597521 -91.806011) (xy 221.542084 -91.812111) (xy 221.48635 -91.810074) (xy 221.431507 -91.799944)
			(xy 221.378723 -91.781937) (xy 221.329123 -91.756436) (xy 221.283765 -91.723985) (xy 221.243616 -91.685276)
			(xy 221.20953 -91.641133) (xy 221.182234 -91.592498) (xy 221.162311 -91.540407) (xy 221.150185 -91.48597)
			(xy 221.146114 -91.430348) (xy 215.923045 -91.430348) (xy 215.948405 -91.46868) (xy 215.972077 -91.519177)
			(xy 215.988145 -91.572584) (xy 215.996265 -91.62776) (xy 215.996774 -91.655646) (xy 215.996265 -91.683532)
			(xy 215.988145 -91.738708) (xy 215.972077 -91.792115) (xy 215.948405 -91.842612) (xy 215.917632 -91.889125)
			(xy 215.880415 -91.930662) (xy 215.837547 -91.966337) (xy 215.789941 -91.995391) (xy 215.738612 -92.017203)
			(xy 215.684655 -92.031309) (xy 215.629218 -92.037409) (xy 215.573484 -92.035372) (xy 215.518641 -92.025242)
			(xy 215.465857 -92.007235) (xy 215.416257 -91.981734) (xy 215.370899 -91.949283) (xy 215.33075 -91.910574)
			(xy 215.296664 -91.866431) (xy 215.269368 -91.817796) (xy 215.249445 -91.765705) (xy 215.237319 -91.711268)
			(xy 215.233248 -91.655646) (xy 204.493628 -91.655646) (xy 202.531218 -92.468446) (xy 202.495252 -92.482686)
			(xy 202.420531 -92.502703) (xy 202.343836 -92.512794) (xy 202.305158 -92.513404) (xy 151.218138 -92.513404)
			(xy 151.208073 -92.513839) (xy 151.189485 -92.521569) (xy 151.18207 -92.52839) (xy 148.495512 -95.214948)
			(xy 163.374592 -95.214948) (xy 163.378545 -95.123133) (xy 163.390377 -95.031997) (xy 163.41 -94.942216)
			(xy 163.437268 -94.854454) (xy 163.471979 -94.769362) (xy 163.513877 -94.687568) (xy 163.562652 -94.609679)
			(xy 163.617941 -94.53627) (xy 163.679336 -94.467887) (xy 163.746383 -94.405035) (xy 163.818585 -94.348178)
			(xy 163.895406 -94.29774) (xy 163.97628 -94.254091) (xy 164.060606 -94.217557) (xy 164.147761 -94.188407)
			(xy 164.237099 -94.166857) (xy 164.327959 -94.153067) (xy 164.419668 -94.147139) (xy 164.511547 -94.149116)
			(xy 164.602916 -94.158984) (xy 164.693098 -94.176671) (xy 164.781426 -94.202044) (xy 164.867246 -94.234917)
			(xy 164.949923 -94.275045) (xy 165.028843 -94.322132) (xy 165.103424 -94.37583) (xy 165.173113 -94.435739)
			(xy 165.237393 -94.501418) (xy 165.29579 -94.57238) (xy 165.34787 -94.648098) (xy 165.393248 -94.728014)
			(xy 165.431588 -94.811535) (xy 165.462606 -94.898042) (xy 165.486074 -94.986896) (xy 165.501815 -95.077438)
			(xy 165.509716 -95.168998) (xy 165.51021 -95.214948) (xy 187.739796 -95.214948) (xy 187.743748 -95.123155)
			(xy 187.755578 -95.032041) (xy 187.775195 -94.942281) (xy 187.802457 -94.85454) (xy 187.83716 -94.769468)
			(xy 187.879048 -94.687693) (xy 187.927811 -94.609822) (xy 187.983087 -94.536432) (xy 188.044468 -94.468065)
			(xy 188.111499 -94.405227) (xy 188.183683 -94.348385) (xy 188.260487 -94.297958) (xy 188.341341 -94.25432)
			(xy 188.425647 -94.217794) (xy 188.512781 -94.188651) (xy 188.602098 -94.167106) (xy 188.692936 -94.15332)
			(xy 188.784623 -94.147393) (xy 188.87648 -94.14937) (xy 188.967828 -94.159236) (xy 189.057988 -94.176918)
			(xy 189.146296 -94.202285) (xy 189.232095 -94.23515) (xy 189.314752 -94.275269) (xy 189.393654 -94.322345)
			(xy 189.468217 -94.376029) (xy 189.537889 -94.435925) (xy 189.602154 -94.501588) (xy 189.660537 -94.572532)
			(xy 189.712604 -94.648233) (xy 189.757972 -94.72813) (xy 189.796303 -94.81163) (xy 189.827314 -94.898117)
			(xy 189.850775 -94.98695) (xy 189.866514 -95.07747) (xy 189.870442 -95.123) (xy 216.555826 -95.123)
			(xy 216.559897 -95.067378) (xy 216.572023 -95.012941) (xy 216.591946 -94.96085) (xy 216.619242 -94.912215)
			(xy 216.653328 -94.868072) (xy 216.693477 -94.829363) (xy 216.738835 -94.796912) (xy 216.788435 -94.771411)
			(xy 216.841219 -94.753404) (xy 216.896062 -94.743274) (xy 216.951796 -94.741237) (xy 217.007233 -94.747337)
			(xy 217.06119 -94.761443) (xy 217.112519 -94.783255) (xy 217.160125 -94.812309) (xy 217.202993 -94.847984)
			(xy 217.24021 -94.889521) (xy 217.270983 -94.936034) (xy 217.294655 -94.986531) (xy 217.310723 -95.039938)
			(xy 217.318843 -95.095114) (xy 217.319352 -95.123) (xy 217.698826 -95.123) (xy 217.702897 -95.067378)
			(xy 217.715023 -95.012941) (xy 217.734946 -94.96085) (xy 217.762242 -94.912215) (xy 217.796328 -94.868072)
			(xy 217.836477 -94.829363) (xy 217.881835 -94.796912) (xy 217.931435 -94.771411) (xy 217.984219 -94.753404)
			(xy 218.039062 -94.743274) (xy 218.094796 -94.741237) (xy 218.150233 -94.747337) (xy 218.20419 -94.761443)
			(xy 218.255519 -94.783255) (xy 218.303125 -94.812309) (xy 218.345993 -94.847984) (xy 218.38321 -94.889521)
			(xy 218.413983 -94.936034) (xy 218.437655 -94.986531) (xy 218.453723 -95.039938) (xy 218.461843 -95.095114)
			(xy 218.462352 -95.123) (xy 218.841826 -95.123) (xy 218.845897 -95.067378) (xy 218.858023 -95.012941)
			(xy 218.877946 -94.96085) (xy 218.905242 -94.912215) (xy 218.939328 -94.868072) (xy 218.979477 -94.829363)
			(xy 219.024835 -94.796912) (xy 219.074435 -94.771411) (xy 219.127219 -94.753404) (xy 219.182062 -94.743274)
			(xy 219.237796 -94.741237) (xy 219.293233 -94.747337) (xy 219.34719 -94.761443) (xy 219.398519 -94.783255)
			(xy 219.446125 -94.812309) (xy 219.488993 -94.847984) (xy 219.52621 -94.889521) (xy 219.556983 -94.936034)
			(xy 219.580655 -94.986531) (xy 219.596723 -95.039938) (xy 219.604843 -95.095114) (xy 219.605352 -95.123)
			(xy 219.604843 -95.150886) (xy 219.596723 -95.206062) (xy 219.580655 -95.259469) (xy 219.556983 -95.309966)
			(xy 219.52621 -95.356479) (xy 219.488993 -95.398016) (xy 219.446125 -95.433691) (xy 219.398519 -95.462745)
			(xy 219.34719 -95.484557) (xy 219.293233 -95.498663) (xy 219.237796 -95.504763) (xy 219.182062 -95.502726)
			(xy 219.127219 -95.492596) (xy 219.074435 -95.474589) (xy 219.024835 -95.449088) (xy 218.979477 -95.416637)
			(xy 218.939328 -95.377928) (xy 218.905242 -95.333785) (xy 218.877946 -95.28515) (xy 218.858023 -95.233059)
			(xy 218.845897 -95.178622) (xy 218.841826 -95.123) (xy 218.462352 -95.123) (xy 218.461843 -95.150886)
			(xy 218.453723 -95.206062) (xy 218.437655 -95.259469) (xy 218.413983 -95.309966) (xy 218.38321 -95.356479)
			(xy 218.345993 -95.398016) (xy 218.303125 -95.433691) (xy 218.255519 -95.462745) (xy 218.20419 -95.484557)
			(xy 218.150233 -95.498663) (xy 218.094796 -95.504763) (xy 218.039062 -95.502726) (xy 217.984219 -95.492596)
			(xy 217.931435 -95.474589) (xy 217.881835 -95.449088) (xy 217.836477 -95.416637) (xy 217.796328 -95.377928)
			(xy 217.762242 -95.333785) (xy 217.734946 -95.28515) (xy 217.715023 -95.233059) (xy 217.702897 -95.178622)
			(xy 217.698826 -95.123) (xy 217.319352 -95.123) (xy 217.318843 -95.150886) (xy 217.310723 -95.206062)
			(xy 217.294655 -95.259469) (xy 217.270983 -95.309966) (xy 217.24021 -95.356479) (xy 217.202993 -95.398016)
			(xy 217.160125 -95.433691) (xy 217.112519 -95.462745) (xy 217.06119 -95.484557) (xy 217.007233 -95.498663)
			(xy 216.951796 -95.504763) (xy 216.896062 -95.502726) (xy 216.841219 -95.492596) (xy 216.788435 -95.474589)
			(xy 216.738835 -95.449088) (xy 216.693477 -95.416637) (xy 216.653328 -95.377928) (xy 216.619242 -95.333785)
			(xy 216.591946 -95.28515) (xy 216.572023 -95.233059) (xy 216.559897 -95.178622) (xy 216.555826 -95.123)
			(xy 189.870442 -95.123) (xy 189.874412 -95.169009) (xy 189.874906 -95.214948) (xy 189.874412 -95.260887)
			(xy 189.866514 -95.352426) (xy 189.850775 -95.442946) (xy 189.827314 -95.531779) (xy 189.796303 -95.618266)
			(xy 189.757972 -95.701766) (xy 189.712604 -95.781663) (xy 189.660537 -95.857364) (xy 189.602154 -95.928308)
			(xy 189.54212 -95.989648) (xy 191.663826 -95.989648) (xy 191.667897 -95.934026) (xy 191.680023 -95.879589)
			(xy 191.699946 -95.827498) (xy 191.727242 -95.778863) (xy 191.761328 -95.73472) (xy 191.801477 -95.696011)
			(xy 191.846835 -95.66356) (xy 191.896435 -95.638059) (xy 191.949219 -95.620052) (xy 192.004062 -95.609922)
			(xy 192.059796 -95.607885) (xy 192.115233 -95.613985) (xy 192.16919 -95.628091) (xy 192.220519 -95.649903)
			(xy 192.268125 -95.678957) (xy 192.310993 -95.714632) (xy 192.34821 -95.756169) (xy 192.378983 -95.802682)
			(xy 192.402655 -95.853179) (xy 192.418723 -95.906586) (xy 192.426843 -95.961762) (xy 192.427352 -95.989648)
			(xy 194.269358 -95.989648) (xy 194.273429 -95.934026) (xy 194.285555 -95.879589) (xy 194.305478 -95.827498)
			(xy 194.332774 -95.778863) (xy 194.36686 -95.73472) (xy 194.407009 -95.696011) (xy 194.452367 -95.66356)
			(xy 194.501967 -95.638059) (xy 194.554751 -95.620052) (xy 194.609594 -95.609922) (xy 194.665328 -95.607885)
			(xy 194.720765 -95.613985) (xy 194.774722 -95.628091) (xy 194.826051 -95.649903) (xy 194.873657 -95.678957)
			(xy 194.916525 -95.714632) (xy 194.953742 -95.756169) (xy 194.984515 -95.802682) (xy 195.008187 -95.853179)
			(xy 195.024255 -95.906586) (xy 195.032375 -95.961762) (xy 195.032884 -95.989648) (xy 195.032375 -96.017534)
			(xy 195.024255 -96.07271) (xy 195.008187 -96.126117) (xy 194.984515 -96.176614) (xy 194.953742 -96.223127)
			(xy 194.916525 -96.264664) (xy 194.873657 -96.300339) (xy 194.826051 -96.329393) (xy 194.774722 -96.351205)
			(xy 194.720765 -96.365311) (xy 194.665328 -96.371411) (xy 194.609594 -96.369374) (xy 194.554751 -96.359244)
			(xy 194.501967 -96.341237) (xy 194.452367 -96.315736) (xy 194.407009 -96.283285) (xy 194.36686 -96.244576)
			(xy 194.332774 -96.200433) (xy 194.305478 -96.151798) (xy 194.285555 -96.099707) (xy 194.273429 -96.04527)
			(xy 194.269358 -95.989648) (xy 192.427352 -95.989648) (xy 192.426843 -96.017534) (xy 192.418723 -96.07271)
			(xy 192.402655 -96.126117) (xy 192.378983 -96.176614) (xy 192.34821 -96.223127) (xy 192.310993 -96.264664)
			(xy 192.268125 -96.300339) (xy 192.220519 -96.329393) (xy 192.16919 -96.351205) (xy 192.115233 -96.365311)
			(xy 192.059796 -96.371411) (xy 192.004062 -96.369374) (xy 191.949219 -96.359244) (xy 191.896435 -96.341237)
			(xy 191.846835 -96.315736) (xy 191.801477 -96.283285) (xy 191.761328 -96.244576) (xy 191.727242 -96.200433)
			(xy 191.699946 -96.151798) (xy 191.680023 -96.099707) (xy 191.667897 -96.04527) (xy 191.663826 -95.989648)
			(xy 189.54212 -95.989648) (xy 189.537889 -95.993971) (xy 189.468217 -96.053867) (xy 189.393654 -96.107551)
			(xy 189.314752 -96.154627) (xy 189.232095 -96.194746) (xy 189.146296 -96.227611) (xy 189.057988 -96.252978)
			(xy 188.967828 -96.27066) (xy 188.87648 -96.280526) (xy 188.784623 -96.282503) (xy 188.692936 -96.276576)
			(xy 188.602098 -96.26279) (xy 188.512781 -96.241245) (xy 188.425647 -96.212102) (xy 188.341341 -96.175576)
			(xy 188.260487 -96.131938) (xy 188.183683 -96.081511) (xy 188.111499 -96.024669) (xy 188.044468 -95.961831)
			(xy 187.983087 -95.893464) (xy 187.927811 -95.820074) (xy 187.879048 -95.742203) (xy 187.83716 -95.660428)
			(xy 187.802457 -95.575356) (xy 187.775195 -95.487615) (xy 187.755578 -95.397855) (xy 187.743748 -95.306741)
			(xy 187.739796 -95.214948) (xy 165.51021 -95.214948) (xy 165.509716 -95.260898) (xy 165.501815 -95.352458)
			(xy 165.486074 -95.443) (xy 165.462606 -95.531854) (xy 165.431588 -95.618361) (xy 165.430916 -95.619824)
			(xy 174.129952 -95.619824) (xy 174.134023 -95.564202) (xy 174.146149 -95.509765) (xy 174.166072 -95.457674)
			(xy 174.193368 -95.409039) (xy 174.227454 -95.364896) (xy 174.267603 -95.326187) (xy 174.312961 -95.293736)
			(xy 174.362561 -95.268235) (xy 174.415345 -95.250228) (xy 174.470188 -95.240098) (xy 174.525922 -95.238061)
			(xy 174.581359 -95.244161) (xy 174.635316 -95.258267) (xy 174.686645 -95.280079) (xy 174.734251 -95.309133)
			(xy 174.777119 -95.344808) (xy 174.814336 -95.386345) (xy 174.845109 -95.432858) (xy 174.868781 -95.483355)
			(xy 174.884849 -95.536762) (xy 174.892969 -95.591938) (xy 174.893478 -95.619824) (xy 174.892969 -95.64771)
			(xy 174.884849 -95.702886) (xy 174.868781 -95.756293) (xy 174.845109 -95.80679) (xy 174.814336 -95.853303)
			(xy 174.777119 -95.89484) (xy 174.734251 -95.930515) (xy 174.686645 -95.959569) (xy 174.635316 -95.981381)
			(xy 174.581359 -95.995487) (xy 174.525922 -96.001587) (xy 174.470188 -95.99955) (xy 174.415345 -95.98942)
			(xy 174.362561 -95.971413) (xy 174.312961 -95.945912) (xy 174.267603 -95.913461) (xy 174.227454 -95.874752)
			(xy 174.193368 -95.830609) (xy 174.166072 -95.781974) (xy 174.146149 -95.729883) (xy 174.134023 -95.675446)
			(xy 174.129952 -95.619824) (xy 165.430916 -95.619824) (xy 165.393248 -95.701882) (xy 165.34787 -95.781798)
			(xy 165.29579 -95.857516) (xy 165.237393 -95.928478) (xy 165.173113 -95.994157) (xy 165.103424 -96.054066)
			(xy 165.028843 -96.107764) (xy 164.949923 -96.154851) (xy 164.867246 -96.194979) (xy 164.781426 -96.227852)
			(xy 164.693098 -96.253225) (xy 164.602916 -96.270912) (xy 164.511547 -96.28078) (xy 164.419668 -96.282757)
			(xy 164.327959 -96.276829) (xy 164.237099 -96.263039) (xy 164.147761 -96.241489) (xy 164.060606 -96.212339)
			(xy 163.97628 -96.175805) (xy 163.895406 -96.132156) (xy 163.818585 -96.081718) (xy 163.746383 -96.024861)
			(xy 163.679336 -95.962009) (xy 163.617941 -95.893626) (xy 163.562652 -95.820217) (xy 163.513877 -95.742328)
			(xy 163.471979 -95.660534) (xy 163.437268 -95.575442) (xy 163.41 -95.48768) (xy 163.390377 -95.397899)
			(xy 163.378545 -95.306763) (xy 163.374592 -95.214948) (xy 148.495512 -95.214948) (xy 134.96163 -108.74883)
			(xy 134.937852 -108.77194) (xy 134.885999 -108.813272) (xy 134.829844 -108.848539) (xy 134.770094 -108.877298)
			(xy 134.707501 -108.899186) (xy 134.64285 -108.913929) (xy 134.576955 -108.921342) (xy 134.5438 -108.921804)
			(xy 130.161538 -108.921804) (xy 130.151473 -108.922239) (xy 130.132885 -108.929969) (xy 130.12547 -108.93679)
			(xy 127.877824 -111.184436) (xy 127.871022 -111.19176) (xy 127.863305 -111.210181) (xy 127.863251 -111.230153)
			(xy 127.866648 -111.239554) (xy 127.902462 -111.326422) (xy 127.906683 -111.335446) (xy 127.920676 -111.349597)
			(xy 127.938999 -111.357365) (xy 127.948944 -111.357918) (xy 127.949198 -111.357918) (xy 127.976355 -111.35854)
			(xy 128.030085 -111.366527) (xy 128.082139 -111.382055) (xy 128.131464 -111.404809) (xy 128.177062 -111.43433)
			(xy 128.218012 -111.470021) (xy 128.253485 -111.511159) (xy 128.282764 -111.556914) (xy 128.305256 -111.606359)
			(xy 128.320508 -111.658494) (xy 128.328209 -111.712266) (xy 128.328674 -111.739426) (xy 128.328209 -111.766677)
			(xy 128.320449 -111.820623) (xy 128.30509 -111.872916) (xy 128.282446 -111.922491) (xy 128.252976 -111.968338)
			(xy 128.217282 -112.009525) (xy 128.17609 -112.045212) (xy 128.130238 -112.074674) (xy 128.08066 -112.097311)
			(xy 128.028364 -112.112661) (xy 127.974417 -112.120413) (xy 127.947166 -112.120934) (xy 127.920008 -112.120453)
			(xy 127.866241 -112.112745) (xy 127.814111 -112.097489) (xy 127.764672 -112.074995) (xy 127.718922 -112.045716)
			(xy 127.677787 -112.010246) (xy 127.642099 -111.969299) (xy 127.612578 -111.923706) (xy 127.589822 -111.874386)
			(xy 127.57429 -111.822338) (xy 127.566297 -111.768613) (xy 127.565658 -111.741458) (xy 127.565658 -111.741204)
			(xy 127.565083 -111.731261) (xy 127.557328 -111.712939) (xy 127.54318 -111.69895) (xy 127.534162 -111.694722)
			(xy 127.447294 -111.658908) (xy 127.437879 -111.655622) (xy 127.417956 -111.655733) (xy 127.399561 -111.663384)
			(xy 127.392176 -111.670084) (xy 126.522226 -112.540034) (xy 129.905504 -112.540034) (xy 129.909575 -112.484412)
			(xy 129.921701 -112.429975) (xy 129.941624 -112.377884) (xy 129.96892 -112.329249) (xy 130.003006 -112.285106)
			(xy 130.043155 -112.246397) (xy 130.088513 -112.213946) (xy 130.138113 -112.188445) (xy 130.190897 -112.170438)
			(xy 130.24574 -112.160308) (xy 130.301474 -112.158271) (xy 130.356911 -112.164371) (xy 130.410868 -112.178477)
			(xy 130.462197 -112.200289) (xy 130.509803 -112.229343) (xy 130.552671 -112.265018) (xy 130.589888 -112.306555)
			(xy 130.620661 -112.353068) (xy 130.644333 -112.403565) (xy 130.649627 -112.421162) (xy 131.907024 -112.421162)
			(xy 131.911095 -112.36554) (xy 131.923221 -112.311103) (xy 131.943144 -112.259012) (xy 131.97044 -112.210377)
			(xy 132.004526 -112.166234) (xy 132.044675 -112.127525) (xy 132.090033 -112.095074) (xy 132.139633 -112.069573)
			(xy 132.192417 -112.051566) (xy 132.24726 -112.041436) (xy 132.302994 -112.039399) (xy 132.358431 -112.045499)
			(xy 132.412388 -112.059605) (xy 132.463717 -112.081417) (xy 132.511323 -112.110471) (xy 132.554191 -112.146146)
			(xy 132.591408 -112.187683) (xy 132.622181 -112.234196) (xy 132.645853 -112.284693) (xy 132.661921 -112.3381)
			(xy 132.670041 -112.393276) (xy 132.67055 -112.421162) (xy 132.670041 -112.449048) (xy 132.661921 -112.504224)
			(xy 132.645853 -112.557631) (xy 132.622181 -112.608128) (xy 132.591408 -112.654641) (xy 132.554191 -112.696178)
			(xy 132.511323 -112.731853) (xy 132.463717 -112.760907) (xy 132.412388 -112.782719) (xy 132.358431 -112.796825)
			(xy 132.302994 -112.802925) (xy 132.24726 -112.800888) (xy 132.192417 -112.790758) (xy 132.139633 -112.772751)
			(xy 132.090033 -112.74725) (xy 132.044675 -112.714799) (xy 132.004526 -112.67609) (xy 131.97044 -112.631947)
			(xy 131.943144 -112.583312) (xy 131.923221 -112.531221) (xy 131.911095 -112.476784) (xy 131.907024 -112.421162)
			(xy 130.649627 -112.421162) (xy 130.660401 -112.456972) (xy 130.668521 -112.512148) (xy 130.66903 -112.540034)
			(xy 130.668521 -112.56792) (xy 130.660401 -112.623096) (xy 130.644333 -112.676503) (xy 130.620661 -112.727)
			(xy 130.589888 -112.773513) (xy 130.552671 -112.81505) (xy 130.509803 -112.850725) (xy 130.462197 -112.879779)
			(xy 130.410868 -112.901591) (xy 130.356911 -112.915697) (xy 130.301474 -112.921797) (xy 130.24574 -112.91976)
			(xy 130.190897 -112.90963) (xy 130.138113 -112.891623) (xy 130.088513 -112.866122) (xy 130.043155 -112.833671)
			(xy 130.003006 -112.794962) (xy 129.96892 -112.750819) (xy 129.941624 -112.702184) (xy 129.921701 -112.650093)
			(xy 129.909575 -112.595656) (xy 129.905504 -112.540034) (xy 126.522226 -112.540034) (xy 125.163834 -113.898426)
			(xy 127.55321 -113.898426) (xy 127.557281 -113.842804) (xy 127.569407 -113.788367) (xy 127.58933 -113.736276)
			(xy 127.616626 -113.687641) (xy 127.650712 -113.643498) (xy 127.690861 -113.604789) (xy 127.736219 -113.572338)
			(xy 127.785819 -113.546837) (xy 127.838603 -113.52883) (xy 127.893446 -113.5187) (xy 127.94918 -113.516663)
			(xy 128.004617 -113.522763) (xy 128.058574 -113.536869) (xy 128.109903 -113.558681) (xy 128.157509 -113.587735)
			(xy 128.200377 -113.62341) (xy 128.237594 -113.664947) (xy 128.268367 -113.71146) (xy 128.292039 -113.761957)
			(xy 128.308107 -113.815364) (xy 128.316227 -113.87054) (xy 128.316736 -113.898426) (xy 128.316227 -113.926312)
			(xy 128.308107 -113.981488) (xy 128.292039 -114.034895) (xy 128.268367 -114.085392) (xy 128.237594 -114.131905)
			(xy 128.200377 -114.173442) (xy 128.157509 -114.209117) (xy 128.109903 -114.238171) (xy 128.058574 -114.259983)
			(xy 128.004617 -114.274089) (xy 127.94918 -114.280189) (xy 127.893446 -114.278152) (xy 127.838603 -114.268022)
			(xy 127.785819 -114.250015) (xy 127.736219 -114.224514) (xy 127.690861 -114.192063) (xy 127.650712 -114.153354)
			(xy 127.616626 -114.109211) (xy 127.58933 -114.060576) (xy 127.569407 -114.008485) (xy 127.557281 -113.954048)
			(xy 127.55321 -113.898426) (xy 125.163834 -113.898426) (xy 122.52579 -116.53647) (xy 122.518945 -116.543868)
			(xy 122.511222 -116.562467) (xy 122.510804 -116.572538) (xy 122.510804 -116.672106) (xy 128.968754 -116.672106)
			(xy 128.96921 -116.644735) (xy 128.977029 -116.590555) (xy 128.992519 -116.538052) (xy 129.015363 -116.488305)
			(xy 129.045091 -116.442339) (xy 129.062734 -116.421408) (xy 129.062988 -116.421154) (xy 129.068557 -116.414055)
			(xy 129.074815 -116.397148) (xy 129.07518 -116.388134) (xy 129.07518 -116.321078) (xy 129.074838 -116.31206)
			(xy 129.06858 -116.295142) (xy 129.062988 -116.288058) (xy 129.062734 -116.288058) (xy 129.062734 -116.287804)
			(xy 129.045099 -116.266867) (xy 129.015373 -116.2209) (xy 128.992527 -116.171154) (xy 128.97703 -116.118653)
			(xy 128.969201 -116.064475) (xy 128.9692 -116.009734) (xy 128.977028 -115.955556) (xy 128.992524 -115.903054)
			(xy 129.015369 -115.853308) (xy 129.045093 -115.807341) (xy 129.062734 -115.786408) (xy 129.062988 -115.786154)
			(xy 129.068557 -115.779055) (xy 129.074815 -115.762148) (xy 129.07518 -115.753134) (xy 129.07518 -115.686078)
			(xy 129.074838 -115.67706) (xy 129.06858 -115.660142) (xy 129.062988 -115.653058) (xy 129.062734 -115.653058)
			(xy 129.062734 -115.652804) (xy 129.045089 -115.631877) (xy 129.015377 -115.585903) (xy 128.992541 -115.536155)
			(xy 128.977052 -115.483653) (xy 128.969226 -115.429476) (xy 128.968754 -115.402106) (xy 128.969283 -115.374857)
			(xy 128.977038 -115.320912) (xy 128.99239 -115.268621) (xy 129.015028 -115.219046) (xy 129.04449 -115.173198)
			(xy 129.080177 -115.132008) (xy 129.121362 -115.096317) (xy 129.167207 -115.066849) (xy 129.21678 -115.044206)
			(xy 129.269069 -115.028847) (xy 129.323013 -115.021086) (xy 129.350262 -115.020598) (xy 129.377631 -115.021087)
			(xy 129.431809 -115.028899) (xy 129.484312 -115.044383) (xy 129.53406 -115.06722) (xy 129.580027 -115.096939)
			(xy 129.60096 -115.114578) (xy 129.601214 -115.114832) (xy 129.60829 -115.120434) (xy 129.625215 -115.12667)
			(xy 129.634234 -115.127024) (xy 129.70129 -115.127024) (xy 129.710306 -115.126657) (xy 129.727222 -115.120416)
			(xy 129.73431 -115.114832) (xy 129.73431 -115.114578) (xy 129.734564 -115.114578) (xy 129.755496 -115.096939)
			(xy 129.801469 -115.067228) (xy 129.851217 -115.044392) (xy 129.903717 -115.028901) (xy 129.957893 -115.021072)
			(xy 129.985262 -115.020598) (xy 130.012514 -115.021091) (xy 130.066464 -115.028843) (xy 130.118762 -115.044194)
			(xy 130.168342 -115.066833) (xy 130.214196 -115.096297) (xy 130.255389 -115.131988) (xy 130.291084 -115.173178)
			(xy 130.320552 -115.219029) (xy 130.343195 -115.268608) (xy 130.358551 -115.320904) (xy 130.366307 -115.374854)
			(xy 130.36677 -115.402106) (xy 130.366315 -115.429477) (xy 130.358495 -115.483657) (xy 130.343004 -115.53616)
			(xy 130.32016 -115.585907) (xy 130.290433 -115.631873) (xy 130.27279 -115.652804) (xy 130.272536 -115.653058)
			(xy 130.266953 -115.660147) (xy 130.260706 -115.677062) (xy 130.260344 -115.686078) (xy 130.260344 -115.753134)
			(xy 130.260675 -115.762154) (xy 130.26694 -115.779071) (xy 130.272536 -115.786154) (xy 130.27279 -115.786154)
			(xy 130.27279 -115.786408) (xy 130.290436 -115.807336) (xy 130.320159 -115.853305) (xy 130.343003 -115.903052)
			(xy 130.358498 -115.955555) (xy 130.366326 -116.009734) (xy 130.366325 -116.064475) (xy 130.358496 -116.118654)
			(xy 130.343 -116.171156) (xy 130.320155 -116.220903) (xy 130.29043 -116.266871) (xy 130.27279 -116.287804)
			(xy 130.272536 -116.288058) (xy 130.266953 -116.295147) (xy 130.260706 -116.312062) (xy 130.260344 -116.321078)
			(xy 130.260344 -116.388134) (xy 130.260675 -116.397154) (xy 130.26694 -116.414071) (xy 130.272536 -116.421154)
			(xy 130.27279 -116.421154) (xy 130.27279 -116.421408) (xy 130.290445 -116.442327) (xy 130.320155 -116.488304)
			(xy 130.342988 -116.538054) (xy 130.358475 -116.590558) (xy 130.366299 -116.644736) (xy 130.36677 -116.672106)
			(xy 130.366631 -116.680234) (xy 131.250942 -116.680234) (xy 131.255013 -116.624612) (xy 131.267139 -116.570175)
			(xy 131.287062 -116.518084) (xy 131.314358 -116.469449) (xy 131.348444 -116.425306) (xy 131.388593 -116.386597)
			(xy 131.433951 -116.354146) (xy 131.483551 -116.328645) (xy 131.536335 -116.310638) (xy 131.591178 -116.300508)
			(xy 131.646912 -116.298471) (xy 131.702349 -116.304571) (xy 131.756306 -116.318677) (xy 131.807635 -116.340489)
			(xy 131.855241 -116.369543) (xy 131.898109 -116.405218) (xy 131.935326 -116.446755) (xy 131.966099 -116.493268)
			(xy 131.989771 -116.543765) (xy 132.005839 -116.597172) (xy 132.013959 -116.652348) (xy 132.014468 -116.680234)
			(xy 132.013959 -116.70812) (xy 132.005839 -116.763296) (xy 131.989771 -116.816703) (xy 131.966099 -116.8672)
			(xy 131.935326 -116.913713) (xy 131.898109 -116.95525) (xy 131.855241 -116.990925) (xy 131.807635 -117.019979)
			(xy 131.756306 -117.041791) (xy 131.702349 -117.055897) (xy 131.646912 -117.061997) (xy 131.591178 -117.05996)
			(xy 131.536335 -117.04983) (xy 131.483551 -117.031823) (xy 131.433951 -117.006322) (xy 131.388593 -116.973871)
			(xy 131.348444 -116.935162) (xy 131.314358 -116.891019) (xy 131.287062 -116.842384) (xy 131.267139 -116.790293)
			(xy 131.255013 -116.735856) (xy 131.250942 -116.680234) (xy 130.366631 -116.680234) (xy 130.366317 -116.698663)
			(xy 130.358948 -116.751262) (xy 130.344354 -116.802331) (xy 130.334004 -116.826792) (xy 130.329655 -116.83816)
			(xy 130.331003 -116.862434) (xy 130.336544 -116.873274) (xy 130.377946 -116.944394) (xy 130.38471 -116.95444)
			(xy 130.405096 -116.967442) (xy 130.417062 -116.969286) (xy 130.445045 -116.972458) (xy 130.499709 -116.985996)
			(xy 130.551788 -117.007424) (xy 130.600151 -117.036276) (xy 130.643746 -117.071926) (xy 130.681627 -117.113597)
			(xy 130.712968 -117.160385) (xy 130.73709 -117.211273) (xy 130.753467 -117.265155) (xy 130.758909 -117.301772)
			(xy 132.398006 -117.301772) (xy 132.402077 -117.24615) (xy 132.414203 -117.191713) (xy 132.434126 -117.139622)
			(xy 132.461422 -117.090987) (xy 132.495508 -117.046844) (xy 132.535657 -117.008135) (xy 132.581015 -116.975684)
			(xy 132.630615 -116.950183) (xy 132.683399 -116.932176) (xy 132.738242 -116.922046) (xy 132.793976 -116.920009)
			(xy 132.849413 -116.926109) (xy 132.90337 -116.940215) (xy 132.954699 -116.962027) (xy 133.002305 -116.991081)
			(xy 133.045173 -117.026756) (xy 133.08239 -117.068293) (xy 133.113163 -117.114806) (xy 133.136835 -117.165303)
			(xy 133.152903 -117.21871) (xy 133.158922 -117.259608) (xy 133.277356 -117.259608) (xy 133.277813 -117.232237)
			(xy 133.285631 -117.178057) (xy 133.301121 -117.125554) (xy 133.323966 -117.075807) (xy 133.353693 -117.029841)
			(xy 133.371336 -117.00891) (xy 133.37159 -117.008656) (xy 133.377158 -117.001557) (xy 133.383416 -116.98465)
			(xy 133.383782 -116.975636) (xy 133.383782 -116.90858) (xy 133.383438 -116.899562) (xy 133.377182 -116.882645)
			(xy 133.37159 -116.87556) (xy 133.371336 -116.87556) (xy 133.371336 -116.875306) (xy 133.353703 -116.854367)
			(xy 133.323977 -116.808401) (xy 133.301131 -116.758655) (xy 133.285633 -116.706154) (xy 133.277804 -116.651976)
			(xy 133.277803 -116.597236) (xy 133.285631 -116.543058) (xy 133.301126 -116.490556) (xy 133.323971 -116.44081)
			(xy 133.353696 -116.394843) (xy 133.371336 -116.37391) (xy 133.37159 -116.373656) (xy 133.377158 -116.366557)
			(xy 133.383416 -116.34965) (xy 133.383782 -116.340636) (xy 133.383782 -116.27358) (xy 133.383438 -116.264562)
			(xy 133.377182 -116.247645) (xy 133.37159 -116.24056) (xy 133.371336 -116.24056) (xy 133.371336 -116.240306)
			(xy 133.353692 -116.219378) (xy 133.32398 -116.173405) (xy 133.301144 -116.123656) (xy 133.285654 -116.071154)
			(xy 133.277828 -116.016978) (xy 133.277356 -115.989608) (xy 133.277885 -115.962359) (xy 133.28564 -115.908414)
			(xy 133.300992 -115.856123) (xy 133.323629 -115.806548) (xy 133.353092 -115.760699) (xy 133.388778 -115.71951)
			(xy 133.429964 -115.683818) (xy 133.475809 -115.654351) (xy 133.525381 -115.631707) (xy 133.577671 -115.616349)
			(xy 133.631615 -115.608588) (xy 133.658864 -115.6081) (xy 133.686233 -115.608587) (xy 133.740412 -115.6164)
			(xy 133.792915 -115.631884) (xy 133.842662 -115.654721) (xy 133.88863 -115.684441) (xy 133.909562 -115.70208)
			(xy 133.909816 -115.702334) (xy 133.916891 -115.707937) (xy 133.933817 -115.714173) (xy 133.942836 -115.714526)
			(xy 134.009892 -115.714526) (xy 134.018908 -115.714159) (xy 134.035824 -115.707918) (xy 134.042912 -115.702334)
			(xy 134.042912 -115.70208) (xy 134.043166 -115.70208) (xy 134.064097 -115.68444) (xy 134.110071 -115.654729)
			(xy 134.159818 -115.631894) (xy 134.212319 -115.616403) (xy 134.266495 -115.608574) (xy 134.293864 -115.6081)
			(xy 134.321116 -115.608589) (xy 134.375067 -115.616341) (xy 134.427365 -115.631693) (xy 134.476945 -115.654332)
			(xy 134.522799 -115.683797) (xy 134.563992 -115.719488) (xy 134.599686 -115.760679) (xy 134.629155 -115.80653)
			(xy 134.651797 -115.856109) (xy 134.667153 -115.908406) (xy 134.674909 -115.962356) (xy 134.675372 -115.989608)
			(xy 134.674917 -116.016979) (xy 134.667098 -116.071159) (xy 134.651606 -116.123662) (xy 134.628762 -116.173409)
			(xy 134.599035 -116.219375) (xy 134.581392 -116.240306) (xy 134.581138 -116.24056) (xy 134.575555 -116.247649)
			(xy 134.569308 -116.264564) (xy 134.568946 -116.27358) (xy 134.568946 -116.340636) (xy 134.569276 -116.349656)
			(xy 134.575541 -116.366573) (xy 134.581138 -116.373656) (xy 134.581392 -116.373656) (xy 134.581392 -116.37391)
			(xy 134.59904 -116.394837) (xy 134.628763 -116.440806) (xy 134.651606 -116.490553) (xy 134.667101 -116.543056)
			(xy 134.674929 -116.597235) (xy 134.674928 -116.651977) (xy 134.667099 -116.706156) (xy 134.651602 -116.758658)
			(xy 134.628757 -116.808405) (xy 134.599032 -116.854373) (xy 134.581392 -116.875306) (xy 134.581138 -116.87556)
			(xy 134.575555 -116.882649) (xy 134.569308 -116.899564) (xy 134.568946 -116.90858) (xy 134.568946 -116.975636)
			(xy 134.569276 -116.984656) (xy 134.575541 -117.001573) (xy 134.581138 -117.008656) (xy 134.581392 -117.008656)
			(xy 134.581392 -117.00891) (xy 134.599048 -117.029828) (xy 134.628758 -117.075805) (xy 134.65159 -117.125556)
			(xy 134.667077 -117.17806) (xy 134.674901 -117.232238) (xy 134.675372 -117.259608) (xy 134.674952 -117.286863)
			(xy 134.667193 -117.340817) (xy 134.651834 -117.393118) (xy 134.629188 -117.4427) (xy 134.599716 -117.488555)
			(xy 134.564018 -117.529749) (xy 134.52282 -117.565442) (xy 134.476962 -117.594909) (xy 134.427377 -117.61755)
			(xy 134.375074 -117.632902) (xy 134.321119 -117.640655) (xy 134.293864 -117.641116) (xy 134.266492 -117.640692)
			(xy 134.21231 -117.632867) (xy 134.159806 -117.617369) (xy 134.11006 -117.594518) (xy 134.064095 -117.564783)
			(xy 134.043166 -117.547136) (xy 134.042912 -117.546882) (xy 134.035828 -117.541292) (xy 134.018909 -117.535048)
			(xy 134.009892 -117.53469) (xy 133.942836 -117.53469) (xy 133.933821 -117.535066) (xy 133.916904 -117.541301)
			(xy 133.909816 -117.546882) (xy 133.909816 -117.547136) (xy 133.909562 -117.547136) (xy 133.888622 -117.564765)
			(xy 133.842651 -117.594477) (xy 133.792905 -117.617314) (xy 133.740407 -117.632808) (xy 133.686233 -117.64064)
			(xy 133.658864 -117.641116) (xy 133.631612 -117.640656) (xy 133.577664 -117.632894) (xy 133.525369 -117.617535)
			(xy 133.475792 -117.59489) (xy 133.429943 -117.565421) (xy 133.388753 -117.529727) (xy 133.353062 -117.488535)
			(xy 133.323596 -117.442683) (xy 133.300955 -117.393104) (xy 133.2856 -117.340809) (xy 133.277842 -117.28686)
			(xy 133.277356 -117.259608) (xy 133.158922 -117.259608) (xy 133.161023 -117.273886) (xy 133.161532 -117.301772)
			(xy 133.161023 -117.329658) (xy 133.152903 -117.384834) (xy 133.136835 -117.438241) (xy 133.113163 -117.488738)
			(xy 133.08239 -117.535251) (xy 133.045173 -117.576788) (xy 133.002305 -117.612463) (xy 132.954699 -117.641517)
			(xy 132.90337 -117.663329) (xy 132.849413 -117.677435) (xy 132.793976 -117.683535) (xy 132.738242 -117.681498)
			(xy 132.683399 -117.671368) (xy 132.630615 -117.653361) (xy 132.581015 -117.62786) (xy 132.535657 -117.595409)
			(xy 132.495508 -117.5567) (xy 132.461422 -117.512557) (xy 132.434126 -117.463922) (xy 132.414203 -117.411831)
			(xy 132.402077 -117.357394) (xy 132.398006 -117.301772) (xy 130.758909 -117.301772) (xy 130.761745 -117.320858)
			(xy 130.762248 -117.349016) (xy 130.761762 -117.376267) (xy 130.754006 -117.430215) (xy 130.738651 -117.48251)
			(xy 130.716009 -117.532087) (xy 130.686543 -117.577937) (xy 130.650852 -117.619128) (xy 130.609661 -117.654819)
			(xy 130.563811 -117.684285) (xy 130.514234 -117.706927) (xy 130.461939 -117.722282) (xy 130.407991 -117.730038)
			(xy 130.353489 -117.730038) (xy 130.299541 -117.722282) (xy 130.247246 -117.706927) (xy 130.197669 -117.684285)
			(xy 130.151819 -117.654819) (xy 130.110628 -117.619128) (xy 130.074937 -117.577937) (xy 130.045471 -117.532087)
			(xy 130.022829 -117.48251) (xy 130.007474 -117.430215) (xy 129.999718 -117.376267) (xy 129.999232 -117.349016)
			(xy 129.999692 -117.32246) (xy 130.007058 -117.26986) (xy 130.02165 -117.218791) (xy 130.031998 -117.19433)
			(xy 130.036333 -117.182957) (xy 130.034994 -117.158688) (xy 130.029458 -117.147848) (xy 129.988056 -117.076728)
			(xy 129.981359 -117.066629) (xy 129.960923 -117.053657) (xy 129.94894 -117.051836) (xy 129.919467 -117.048452)
			(xy 129.861998 -117.033735) (xy 129.807501 -117.010297) (xy 129.757291 -116.978703) (xy 129.734564 -116.959634)
			(xy 129.73431 -116.95938) (xy 129.727226 -116.953789) (xy 129.710307 -116.947546) (xy 129.70129 -116.947188)
			(xy 129.634234 -116.947188) (xy 129.625219 -116.947564) (xy 129.608302 -116.953799) (xy 129.601214 -116.95938)
			(xy 129.601214 -116.959634) (xy 129.60096 -116.959634) (xy 129.58002 -116.977264) (xy 129.534049 -117.006976)
			(xy 129.484304 -117.029813) (xy 129.431805 -117.045306) (xy 129.377631 -117.053138) (xy 129.350262 -117.053614)
			(xy 129.32301 -117.053158) (xy 129.269062 -117.045396) (xy 129.216767 -117.030036) (xy 129.16719 -117.007391)
			(xy 129.12134 -116.977922) (xy 129.08015 -116.942227) (xy 129.044459 -116.901035) (xy 129.014993 -116.855182)
			(xy 128.992352 -116.805603) (xy 128.976997 -116.753307) (xy 128.96924 -116.699358) (xy 128.968754 -116.672106)
			(xy 122.510804 -116.672106) (xy 122.510804 -117.327426) (xy 125.787148 -117.327426) (xy 125.791219 -117.271804)
			(xy 125.803345 -117.217367) (xy 125.823268 -117.165276) (xy 125.850564 -117.116641) (xy 125.88465 -117.072498)
			(xy 125.924799 -117.033789) (xy 125.970157 -117.001338) (xy 126.019757 -116.975837) (xy 126.072541 -116.95783)
			(xy 126.127384 -116.9477) (xy 126.183118 -116.945663) (xy 126.238555 -116.951763) (xy 126.292512 -116.965869)
			(xy 126.343841 -116.987681) (xy 126.391447 -117.016735) (xy 126.434315 -117.05241) (xy 126.471532 -117.093947)
			(xy 126.502305 -117.14046) (xy 126.525977 -117.190957) (xy 126.528826 -117.200426) (xy 127.819148 -117.200426)
			(xy 127.823219 -117.144804) (xy 127.835345 -117.090367) (xy 127.855268 -117.038276) (xy 127.882564 -116.989641)
			(xy 127.91665 -116.945498) (xy 127.956799 -116.906789) (xy 128.002157 -116.874338) (xy 128.051757 -116.848837)
			(xy 128.104541 -116.83083) (xy 128.159384 -116.8207) (xy 128.215118 -116.818663) (xy 128.270555 -116.824763)
			(xy 128.324512 -116.838869) (xy 128.375841 -116.860681) (xy 128.423447 -116.889735) (xy 128.466315 -116.92541)
			(xy 128.503532 -116.966947) (xy 128.534305 -117.01346) (xy 128.557977 -117.063957) (xy 128.574045 -117.117364)
			(xy 128.582165 -117.17254) (xy 128.582674 -117.200426) (xy 128.582165 -117.228312) (xy 128.574045 -117.283488)
			(xy 128.557977 -117.336895) (xy 128.534305 -117.387392) (xy 128.503532 -117.433905) (xy 128.466315 -117.475442)
			(xy 128.423447 -117.511117) (xy 128.375841 -117.540171) (xy 128.324512 -117.561983) (xy 128.270555 -117.576089)
			(xy 128.215118 -117.582189) (xy 128.159384 -117.580152) (xy 128.104541 -117.570022) (xy 128.051757 -117.552015)
			(xy 128.002157 -117.526514) (xy 127.956799 -117.494063) (xy 127.91665 -117.455354) (xy 127.882564 -117.411211)
			(xy 127.855268 -117.362576) (xy 127.835345 -117.310485) (xy 127.823219 -117.256048) (xy 127.819148 -117.200426)
			(xy 126.528826 -117.200426) (xy 126.542045 -117.244364) (xy 126.550165 -117.29954) (xy 126.550674 -117.327426)
			(xy 126.550165 -117.355312) (xy 126.542045 -117.410488) (xy 126.525977 -117.463895) (xy 126.502305 -117.514392)
			(xy 126.471532 -117.560905) (xy 126.434315 -117.602442) (xy 126.391447 -117.638117) (xy 126.343841 -117.667171)
			(xy 126.292512 -117.688983) (xy 126.238555 -117.703089) (xy 126.183118 -117.709189) (xy 126.127384 -117.707152)
			(xy 126.072541 -117.697022) (xy 126.019757 -117.679015) (xy 125.970157 -117.653514) (xy 125.924799 -117.621063)
			(xy 125.88465 -117.582354) (xy 125.850564 -117.538211) (xy 125.823268 -117.489576) (xy 125.803345 -117.437485)
			(xy 125.791219 -117.383048) (xy 125.787148 -117.327426) (xy 122.510804 -117.327426) (xy 122.510804 -118.64721)
			(xy 122.511395 -118.658909) (xy 122.521761 -118.679886) (xy 122.540343 -118.694104) (xy 122.551698 -118.696994)
			(xy 122.578664 -118.702876) (xy 122.630664 -118.721369) (xy 122.679456 -118.747162) (xy 122.724023 -118.779717)
			(xy 122.763433 -118.818354) (xy 122.796864 -118.862267) (xy 122.823619 -118.910539) (xy 122.843138 -118.962163)
			(xy 122.855015 -119.016061) (xy 122.859001 -119.071107) (xy 122.855013 -119.126153) (xy 122.843134 -119.180051)
			(xy 122.823613 -119.231674) (xy 122.796857 -119.279945) (xy 122.763424 -119.323856) (xy 122.724012 -119.362492)
			(xy 122.679444 -119.395046) (xy 122.630651 -119.420837) (xy 122.57865 -119.439328) (xy 122.551698 -119.445278)
			(xy 122.540351 -119.44815) (xy 122.521814 -119.462401) (xy 122.511475 -119.483372) (xy 122.5113 -119.486426)
			(xy 125.787148 -119.486426) (xy 125.791219 -119.430804) (xy 125.803345 -119.376367) (xy 125.823268 -119.324276)
			(xy 125.850564 -119.275641) (xy 125.88465 -119.231498) (xy 125.924799 -119.192789) (xy 125.970157 -119.160338)
			(xy 126.019757 -119.134837) (xy 126.072541 -119.11683) (xy 126.127384 -119.1067) (xy 126.183118 -119.104663)
			(xy 126.238555 -119.110763) (xy 126.292512 -119.124869) (xy 126.343841 -119.146681) (xy 126.391447 -119.175735)
			(xy 126.434315 -119.21141) (xy 126.471532 -119.252947) (xy 126.502305 -119.29946) (xy 126.525977 -119.349957)
			(xy 126.527756 -119.35587) (xy 126.803148 -119.35587) (xy 126.807219 -119.300248) (xy 126.819345 -119.245811)
			(xy 126.839268 -119.19372) (xy 126.866564 -119.145085) (xy 126.90065 -119.100942) (xy 126.940799 -119.062233)
			(xy 126.986157 -119.029782) (xy 127.035757 -119.004281) (xy 127.088541 -118.986274) (xy 127.143384 -118.976144)
			(xy 127.199118 -118.974107) (xy 127.254555 -118.980207) (xy 127.308512 -118.994313) (xy 127.359841 -119.016125)
			(xy 127.407447 -119.045179) (xy 127.450315 -119.080854) (xy 127.487532 -119.122391) (xy 127.518305 -119.168904)
			(xy 127.541977 -119.219401) (xy 127.558045 -119.272808) (xy 127.566165 -119.327984) (xy 127.566674 -119.35587)
			(xy 127.819148 -119.35587) (xy 127.823219 -119.300248) (xy 127.835345 -119.245811) (xy 127.855268 -119.19372)
			(xy 127.882564 -119.145085) (xy 127.91665 -119.100942) (xy 127.956799 -119.062233) (xy 128.002157 -119.029782)
			(xy 128.051757 -119.004281) (xy 128.104541 -118.986274) (xy 128.159384 -118.976144) (xy 128.215118 -118.974107)
			(xy 128.270555 -118.980207) (xy 128.324512 -118.994313) (xy 128.375841 -119.016125) (xy 128.423447 -119.045179)
			(xy 128.466315 -119.080854) (xy 128.503532 -119.122391) (xy 128.534305 -119.168904) (xy 128.557977 -119.219401)
			(xy 128.574045 -119.272808) (xy 128.582165 -119.327984) (xy 128.582674 -119.35587) (xy 128.582165 -119.383756)
			(xy 128.581036 -119.39143) (xy 131.014722 -119.39143) (xy 131.018793 -119.335808) (xy 131.030919 -119.281371)
			(xy 131.050842 -119.22928) (xy 131.078138 -119.180645) (xy 131.112224 -119.136502) (xy 131.152373 -119.097793)
			(xy 131.197731 -119.065342) (xy 131.247331 -119.039841) (xy 131.300115 -119.021834) (xy 131.354958 -119.011704)
			(xy 131.410692 -119.009667) (xy 131.466129 -119.015767) (xy 131.520086 -119.029873) (xy 131.571415 -119.051685)
			(xy 131.619021 -119.080739) (xy 131.661889 -119.116414) (xy 131.699106 -119.157951) (xy 131.729879 -119.204464)
			(xy 131.753551 -119.254961) (xy 131.769619 -119.308368) (xy 131.777739 -119.363544) (xy 131.778248 -119.39143)
			(xy 131.777739 -119.419316) (xy 131.769619 -119.474492) (xy 131.753551 -119.527899) (xy 131.729879 -119.578396)
			(xy 131.699106 -119.624909) (xy 131.661889 -119.666446) (xy 131.619021 -119.702121) (xy 131.571415 -119.731175)
			(xy 131.520086 -119.752987) (xy 131.466129 -119.767093) (xy 131.410692 -119.773193) (xy 131.354958 -119.771156)
			(xy 131.300115 -119.761026) (xy 131.247331 -119.743019) (xy 131.197731 -119.717518) (xy 131.152373 -119.685067)
			(xy 131.112224 -119.646358) (xy 131.078138 -119.602215) (xy 131.050842 -119.55358) (xy 131.030919 -119.501489)
			(xy 131.018793 -119.447052) (xy 131.014722 -119.39143) (xy 128.581036 -119.39143) (xy 128.574045 -119.438932)
			(xy 128.557977 -119.492339) (xy 128.534305 -119.542836) (xy 128.503532 -119.589349) (xy 128.466315 -119.630886)
			(xy 128.423447 -119.666561) (xy 128.375841 -119.695615) (xy 128.324512 -119.717427) (xy 128.270555 -119.731533)
			(xy 128.215118 -119.737633) (xy 128.159384 -119.735596) (xy 128.104541 -119.725466) (xy 128.051757 -119.707459)
			(xy 128.002157 -119.681958) (xy 127.956799 -119.649507) (xy 127.91665 -119.610798) (xy 127.882564 -119.566655)
			(xy 127.855268 -119.51802) (xy 127.835345 -119.465929) (xy 127.823219 -119.411492) (xy 127.819148 -119.35587)
			(xy 127.566674 -119.35587) (xy 127.566165 -119.383756) (xy 127.558045 -119.438932) (xy 127.541977 -119.492339)
			(xy 127.518305 -119.542836) (xy 127.487532 -119.589349) (xy 127.450315 -119.630886) (xy 127.407447 -119.666561)
			(xy 127.359841 -119.695615) (xy 127.308512 -119.717427) (xy 127.254555 -119.731533) (xy 127.199118 -119.737633)
			(xy 127.143384 -119.735596) (xy 127.088541 -119.725466) (xy 127.035757 -119.707459) (xy 126.986157 -119.681958)
			(xy 126.940799 -119.649507) (xy 126.90065 -119.610798) (xy 126.866564 -119.566655) (xy 126.839268 -119.51802)
			(xy 126.819345 -119.465929) (xy 126.807219 -119.411492) (xy 126.803148 -119.35587) (xy 126.527756 -119.35587)
			(xy 126.542045 -119.403364) (xy 126.550165 -119.45854) (xy 126.550674 -119.486426) (xy 126.550165 -119.514312)
			(xy 126.542045 -119.569488) (xy 126.525977 -119.622895) (xy 126.502305 -119.673392) (xy 126.471532 -119.719905)
			(xy 126.434315 -119.761442) (xy 126.391447 -119.797117) (xy 126.343841 -119.826171) (xy 126.292512 -119.847983)
			(xy 126.238555 -119.862089) (xy 126.183118 -119.868189) (xy 126.127384 -119.866152) (xy 126.072541 -119.856022)
			(xy 126.019757 -119.838015) (xy 125.970157 -119.812514) (xy 125.924799 -119.780063) (xy 125.88465 -119.741354)
			(xy 125.850564 -119.697211) (xy 125.823268 -119.648576) (xy 125.803345 -119.596485) (xy 125.791219 -119.542048)
			(xy 125.787148 -119.486426) (xy 122.5113 -119.486426) (xy 122.510804 -119.495062) (xy 122.510804 -119.66321)
			(xy 122.511395 -119.674909) (xy 122.521761 -119.695886) (xy 122.540343 -119.710104) (xy 122.551698 -119.712994)
			(xy 122.578664 -119.718876) (xy 122.630664 -119.737369) (xy 122.679456 -119.763162) (xy 122.724023 -119.795717)
			(xy 122.763433 -119.834354) (xy 122.796864 -119.878267) (xy 122.823619 -119.926539) (xy 122.843138 -119.978163)
			(xy 122.855015 -120.032061) (xy 122.859001 -120.087107) (xy 122.855013 -120.142153) (xy 122.843134 -120.196051)
			(xy 122.823613 -120.247674) (xy 122.796857 -120.295945) (xy 122.763424 -120.339856) (xy 122.724012 -120.378492)
			(xy 122.679444 -120.411046) (xy 122.630651 -120.436837) (xy 122.57865 -120.455328) (xy 122.551698 -120.461278)
			(xy 122.540351 -120.46415) (xy 122.521814 -120.478401) (xy 122.511475 -120.499372) (xy 122.510804 -120.511062)
			(xy 122.510804 -120.67921) (xy 122.511395 -120.690909) (xy 122.521761 -120.711886) (xy 122.540343 -120.726104)
			(xy 122.551698 -120.728994) (xy 122.578664 -120.734876) (xy 122.630664 -120.753369) (xy 122.679456 -120.779162)
			(xy 122.724023 -120.811717) (xy 122.763433 -120.850354) (xy 122.796864 -120.894267) (xy 122.823619 -120.942539)
			(xy 122.843138 -120.994163) (xy 122.855015 -121.048061) (xy 122.859001 -121.103107) (xy 122.855013 -121.158153)
			(xy 122.843134 -121.212051) (xy 122.823613 -121.263674) (xy 122.796857 -121.311945) (xy 122.763424 -121.355856)
			(xy 122.724012 -121.394492) (xy 122.679444 -121.427046) (xy 122.630651 -121.452837) (xy 122.57865 -121.471328)
			(xy 122.551698 -121.477278) (xy 122.540351 -121.48015) (xy 122.521814 -121.494401) (xy 122.511475 -121.515372)
			(xy 122.510804 -121.527062) (xy 122.510804 -121.57075) (xy 129.719832 -121.57075) (xy 129.720256 -121.544434)
			(xy 129.727498 -121.492304) (xy 129.741825 -121.44166) (xy 129.762966 -121.393461) (xy 129.79052 -121.348618)
			(xy 129.823967 -121.307981) (xy 129.843022 -121.289826) (xy 129.850417 -121.2823) (xy 129.858945 -121.263023)
			(xy 129.859532 -121.252488) (xy 129.859532 -121.177812) (xy 129.859001 -121.167263) (xy 129.850466 -121.147968)
			(xy 129.843022 -121.140474) (xy 129.823965 -121.12232) (xy 129.790507 -121.08169) (xy 129.762948 -121.03685)
			(xy 129.741809 -120.988649) (xy 129.727493 -120.938001) (xy 129.72027 -120.885866) (xy 129.719832 -120.85955)
			(xy 129.720318 -120.832299) (xy 129.728074 -120.778351) (xy 129.743429 -120.726056) (xy 129.766071 -120.676479)
			(xy 129.795537 -120.630629) (xy 129.831228 -120.589438) (xy 129.872419 -120.553747) (xy 129.918269 -120.524281)
			(xy 129.967846 -120.501639) (xy 130.020141 -120.486284) (xy 130.074089 -120.478528) (xy 130.128591 -120.478528)
			(xy 130.182539 -120.486284) (xy 130.234834 -120.501639) (xy 130.284411 -120.524281) (xy 130.330261 -120.553747)
			(xy 130.371452 -120.589438) (xy 130.407143 -120.630629) (xy 130.436609 -120.676479) (xy 130.459251 -120.726056)
			(xy 130.474606 -120.778351) (xy 130.482362 -120.832299) (xy 130.482848 -120.85955) (xy 130.482431 -120.885866)
			(xy 130.475188 -120.937997) (xy 130.46086 -120.988642) (xy 130.439718 -121.036841) (xy 130.412163 -121.081683)
			(xy 130.378714 -121.12232) (xy 130.359658 -121.140474) (xy 130.352274 -121.148011) (xy 130.343738 -121.167279)
			(xy 130.343148 -121.177812) (xy 130.343148 -121.252488) (xy 130.343656 -121.263041) (xy 130.352204 -121.282337)
			(xy 130.359658 -121.289826) (xy 130.37873 -121.307965) (xy 130.412184 -121.348599) (xy 130.439739 -121.393443)
			(xy 130.460874 -121.441647) (xy 130.475188 -121.492297) (xy 130.482411 -121.544433) (xy 130.482848 -121.57075)
			(xy 130.482362 -121.598001) (xy 130.474606 -121.651949) (xy 130.459251 -121.704244) (xy 130.436609 -121.753821)
			(xy 130.407143 -121.799671) (xy 130.371452 -121.840862) (xy 130.330261 -121.876553) (xy 130.284411 -121.906019)
			(xy 130.234834 -121.928661) (xy 130.182539 -121.944016) (xy 130.128591 -121.951772) (xy 130.074089 -121.951772)
			(xy 130.020141 -121.944016) (xy 129.967846 -121.928661) (xy 129.918269 -121.906019) (xy 129.872419 -121.876553)
			(xy 129.831228 -121.840862) (xy 129.795537 -121.799671) (xy 129.766071 -121.753821) (xy 129.743429 -121.704244)
			(xy 129.728074 -121.651949) (xy 129.720318 -121.598001) (xy 129.719832 -121.57075) (xy 122.510804 -121.57075)
			(xy 122.510804 -122.292618) (xy 125.880112 -122.292618) (xy 125.884183 -122.236996) (xy 125.896309 -122.182559)
			(xy 125.916232 -122.130468) (xy 125.943528 -122.081833) (xy 125.977614 -122.03769) (xy 126.017763 -121.998981)
			(xy 126.063121 -121.96653) (xy 126.112721 -121.941029) (xy 126.165505 -121.923022) (xy 126.220348 -121.912892)
			(xy 126.276082 -121.910855) (xy 126.331519 -121.916955) (xy 126.385476 -121.931061) (xy 126.436805 -121.952873)
			(xy 126.484411 -121.981927) (xy 126.527279 -122.017602) (xy 126.564496 -122.059139) (xy 126.595269 -122.105652)
			(xy 126.618941 -122.156149) (xy 126.635009 -122.209556) (xy 126.643129 -122.264732) (xy 126.643638 -122.292618)
			(xy 126.643129 -122.320504) (xy 126.635009 -122.37568) (xy 126.618941 -122.429087) (xy 126.599804 -122.46991)
			(xy 127.036828 -122.46991) (xy 127.040899 -122.414288) (xy 127.053025 -122.359851) (xy 127.072948 -122.30776)
			(xy 127.100244 -122.259125) (xy 127.13433 -122.214982) (xy 127.174479 -122.176273) (xy 127.219837 -122.143822)
			(xy 127.269437 -122.118321) (xy 127.322221 -122.100314) (xy 127.377064 -122.090184) (xy 127.432798 -122.088147)
			(xy 127.488235 -122.094247) (xy 127.542192 -122.108353) (xy 127.593521 -122.130165) (xy 127.641127 -122.159219)
			(xy 127.683995 -122.194894) (xy 127.721212 -122.236431) (xy 127.751985 -122.282944) (xy 127.775657 -122.333441)
			(xy 127.791725 -122.386848) (xy 127.799845 -122.442024) (xy 127.800354 -122.46991) (xy 127.799845 -122.497796)
			(xy 127.791725 -122.552972) (xy 127.775657 -122.606379) (xy 127.751985 -122.656876) (xy 127.721212 -122.703389)
			(xy 127.683995 -122.744926) (xy 127.641127 -122.780601) (xy 127.593521 -122.809655) (xy 127.542192 -122.831467)
			(xy 127.488235 -122.845573) (xy 127.432798 -122.851673) (xy 127.377064 -122.849636) (xy 127.322221 -122.839506)
			(xy 127.269437 -122.821499) (xy 127.219837 -122.795998) (xy 127.174479 -122.763547) (xy 127.13433 -122.724838)
			(xy 127.100244 -122.680695) (xy 127.072948 -122.63206) (xy 127.053025 -122.579969) (xy 127.040899 -122.525532)
			(xy 127.036828 -122.46991) (xy 126.599804 -122.46991) (xy 126.595269 -122.479584) (xy 126.564496 -122.526097)
			(xy 126.527279 -122.567634) (xy 126.484411 -122.603309) (xy 126.436805 -122.632363) (xy 126.385476 -122.654175)
			(xy 126.331519 -122.668281) (xy 126.276082 -122.674381) (xy 126.220348 -122.672344) (xy 126.165505 -122.662214)
			(xy 126.112721 -122.644207) (xy 126.063121 -122.618706) (xy 126.017763 -122.586255) (xy 125.977614 -122.547546)
			(xy 125.943528 -122.503403) (xy 125.916232 -122.454768) (xy 125.896309 -122.402677) (xy 125.884183 -122.34824)
			(xy 125.880112 -122.292618) (xy 122.510804 -122.292618) (xy 122.510804 -123.249752) (xy 128.009867 -123.249752)
			(xy 128.009867 -123.195248) (xy 128.017624 -123.141298) (xy 128.03298 -123.089002) (xy 128.055622 -123.039423)
			(xy 128.085089 -122.993571) (xy 128.120782 -122.95238) (xy 128.161974 -122.916687) (xy 128.207826 -122.88722)
			(xy 128.257405 -122.864579) (xy 128.309702 -122.849223) (xy 128.363652 -122.841467) (xy 128.390904 -122.841004)
			(xy 128.417934 -122.841497) (xy 128.471452 -122.849135) (xy 128.523353 -122.864259) (xy 128.572597 -122.886563)
			(xy 128.618196 -122.915602) (xy 128.659234 -122.950791) (xy 128.677416 -122.970798) (xy 128.67767 -122.971052)
			(xy 128.685148 -122.978659) (xy 128.704606 -122.98735) (xy 128.715262 -122.987816) (xy 128.802892 -122.988324)
			(xy 128.82245 -122.979688) (xy 128.829816 -122.971306) (xy 128.847975 -122.951581) (xy 128.888876 -122.916917)
			(xy 128.934232 -122.888329) (xy 128.983148 -122.86638) (xy 129.034657 -122.851505) (xy 129.087743 -122.843997)
			(xy 129.11455 -122.843544) (xy 129.14192 -122.844029) (xy 129.196098 -122.85184) (xy 129.248602 -122.867324)
			(xy 129.298349 -122.890162) (xy 129.344316 -122.919884) (xy 129.365248 -122.937524) (xy 129.365502 -122.937778)
			(xy 129.372577 -122.943381) (xy 129.389503 -122.949616) (xy 129.398522 -122.94997) (xy 129.465578 -122.94997)
			(xy 129.474595 -122.949609) (xy 129.491512 -122.943365) (xy 129.498598 -122.937778) (xy 129.498598 -122.937524)
			(xy 129.498852 -122.937524) (xy 129.519785 -122.919883) (xy 129.565753 -122.890159) (xy 129.615499 -122.867313)
			(xy 129.668001 -122.851817) (xy 129.722179 -122.843988) (xy 129.776921 -122.843988) (xy 129.831099 -122.851817)
			(xy 129.883601 -122.867313) (xy 129.933347 -122.890159) (xy 129.979315 -122.919883) (xy 130.000248 -122.937524)
			(xy 130.000502 -122.937778) (xy 130.007577 -122.943381) (xy 130.024503 -122.949616) (xy 130.033522 -122.94997)
			(xy 130.100578 -122.94997) (xy 130.109595 -122.949609) (xy 130.126512 -122.943365) (xy 130.133598 -122.937778)
			(xy 130.134106 -122.937524) (xy 130.14684 -122.926579) (xy 130.173931 -122.906738) (xy 130.188208 -122.8979)
			(xy 130.197098 -122.892566) (xy 130.20929 -122.875548) (xy 130.22961 -122.78233) (xy 130.225292 -122.761756)
			(xy 130.21945 -122.75312) (xy 130.203451 -122.729056) (xy 130.178109 -122.677124) (xy 130.160884 -122.621966)
			(xy 130.152168 -122.564842) (xy 130.151632 -122.53595) (xy 130.152118 -122.508699) (xy 130.159874 -122.454751)
			(xy 130.175229 -122.402456) (xy 130.197871 -122.352879) (xy 130.227337 -122.307029) (xy 130.263028 -122.265838)
			(xy 130.304219 -122.230147) (xy 130.350069 -122.200681) (xy 130.399646 -122.178039) (xy 130.451941 -122.162684)
			(xy 130.505889 -122.154928) (xy 130.560391 -122.154928) (xy 130.614339 -122.162684) (xy 130.666634 -122.178039)
			(xy 130.716211 -122.200681) (xy 130.762061 -122.230147) (xy 130.803252 -122.265838) (xy 130.838943 -122.307029)
			(xy 130.868409 -122.352879) (xy 130.891051 -122.402456) (xy 130.906406 -122.454751) (xy 130.914162 -122.508699)
			(xy 130.914648 -122.53595) (xy 130.914099 -122.564039) (xy 130.90588 -122.619613) (xy 130.889597 -122.673381)
			(xy 130.865603 -122.724177) (xy 130.834417 -122.770905) (xy 130.796714 -122.812552) (xy 130.753308 -122.848217)
			(xy 130.729482 -122.863102) (xy 130.720592 -122.868436) (xy 130.7084 -122.885454) (xy 130.68808 -122.978672)
			(xy 130.692398 -122.999246) (xy 130.69824 -123.007882) (xy 130.714239 -123.031946) (xy 130.739581 -123.083878)
			(xy 130.756807 -123.139036) (xy 130.765523 -123.19616) (xy 130.766058 -123.225052) (xy 130.7656 -123.252306)
			(xy 130.757848 -123.30626) (xy 130.742496 -123.358561) (xy 130.719855 -123.408144) (xy 130.690387 -123.454)
			(xy 130.654693 -123.495194) (xy 130.613498 -123.530889) (xy 130.567642 -123.560356) (xy 130.518059 -123.582996)
			(xy 130.465758 -123.598349) (xy 130.411804 -123.6061) (xy 130.38455 -123.60656) (xy 130.35718 -123.606074)
			(xy 130.303002 -123.598263) (xy 130.250498 -123.582779) (xy 130.200751 -123.559941) (xy 130.154784 -123.53022)
			(xy 130.133852 -123.51258) (xy 130.133598 -123.512326) (xy 130.126522 -123.506724) (xy 130.109597 -123.500488)
			(xy 130.100578 -123.500134) (xy 130.033522 -123.500134) (xy 130.024505 -123.500494) (xy 130.007588 -123.506739)
			(xy 130.000502 -123.512326) (xy 130.000502 -123.51258) (xy 130.000248 -123.51258) (xy 129.979315 -123.530221)
			(xy 129.933347 -123.559945) (xy 129.883601 -123.582791) (xy 129.831099 -123.598287) (xy 129.776921 -123.606116)
			(xy 129.722179 -123.606116) (xy 129.668001 -123.598287) (xy 129.615499 -123.582791) (xy 129.565753 -123.559945)
			(xy 129.519785 -123.530221) (xy 129.498852 -123.51258) (xy 129.498598 -123.512326) (xy 129.491522 -123.506724)
			(xy 129.474597 -123.500488) (xy 129.465578 -123.500134) (xy 129.398522 -123.500134) (xy 129.389505 -123.500494)
			(xy 129.372588 -123.506739) (xy 129.365502 -123.512326) (xy 129.365502 -123.51258) (xy 129.365248 -123.51258)
			(xy 129.344306 -123.530207) (xy 129.298336 -123.559921) (xy 129.248591 -123.58276) (xy 129.196093 -123.598254)
			(xy 129.141919 -123.606085) (xy 129.11455 -123.60656) (xy 129.08752 -123.606077) (xy 129.034003 -123.598433)
			(xy 128.982102 -123.583307) (xy 128.932859 -123.561) (xy 128.88726 -123.531961) (xy 128.846221 -123.496772)
			(xy 128.828038 -123.476766) (xy 128.827784 -123.476512) (xy 128.820315 -123.468894) (xy 128.80085 -123.460207)
			(xy 128.790192 -123.459748) (xy 128.702562 -123.45924) (xy 128.683004 -123.467876) (xy 128.675638 -123.476258)
			(xy 128.657465 -123.495969) (xy 128.616566 -123.530632) (xy 128.571212 -123.559221) (xy 128.522299 -123.581171)
			(xy 128.470793 -123.59605) (xy 128.41771 -123.603564) (xy 128.390904 -123.60402) (xy 128.363652 -123.603533)
			(xy 128.309702 -123.595777) (xy 128.257405 -123.580421) (xy 128.207826 -123.55778) (xy 128.161974 -123.528313)
			(xy 128.120782 -123.49262) (xy 128.085089 -123.451429) (xy 128.055622 -123.405577) (xy 128.03298 -123.355998)
			(xy 128.017624 -123.303702) (xy 128.009867 -123.249752) (xy 122.510804 -123.249752) (xy 122.510804 -124.963428)
			(xy 124.772926 -124.963428) (xy 124.776997 -124.907806) (xy 124.789123 -124.853369) (xy 124.809046 -124.801278)
			(xy 124.836342 -124.752643) (xy 124.870428 -124.7085) (xy 124.910577 -124.669791) (xy 124.955935 -124.63734)
			(xy 125.005535 -124.611839) (xy 125.058319 -124.593832) (xy 125.113162 -124.583702) (xy 125.168896 -124.581665)
			(xy 125.224333 -124.587765) (xy 125.27829 -124.601871) (xy 125.329619 -124.623683) (xy 125.377225 -124.652737)
			(xy 125.420093 -124.688412) (xy 125.45731 -124.729949) (xy 125.488083 -124.776462) (xy 125.511755 -124.826959)
			(xy 125.527823 -124.880366) (xy 125.535943 -124.935542) (xy 125.536452 -124.963428) (xy 125.536137 -124.9807)
			(xy 126.928878 -124.9807) (xy 126.932949 -124.925078) (xy 126.945075 -124.870641) (xy 126.964998 -124.81855)
			(xy 126.992294 -124.769915) (xy 127.02638 -124.725772) (xy 127.066529 -124.687063) (xy 127.111887 -124.654612)
			(xy 127.161487 -124.629111) (xy 127.214271 -124.611104) (xy 127.269114 -124.600974) (xy 127.324848 -124.598937)
			(xy 127.380285 -124.605037) (xy 127.434242 -124.619143) (xy 127.485571 -124.640955) (xy 127.533177 -124.670009)
			(xy 127.576045 -124.705684) (xy 127.613262 -124.747221) (xy 127.644035 -124.793734) (xy 127.667707 -124.844231)
			(xy 127.683775 -124.897638) (xy 127.691895 -124.952814) (xy 127.692404 -124.9807) (xy 127.691895 -125.008586)
			(xy 127.683775 -125.063762) (xy 127.667707 -125.117169) (xy 127.644035 -125.167666) (xy 127.613262 -125.214179)
			(xy 127.576045 -125.255716) (xy 127.533177 -125.291391) (xy 127.485571 -125.320445) (xy 127.434242 -125.342257)
			(xy 127.380285 -125.356363) (xy 127.324848 -125.362463) (xy 127.269114 -125.360426) (xy 127.214271 -125.350296)
			(xy 127.161487 -125.332289) (xy 127.111887 -125.306788) (xy 127.066529 -125.274337) (xy 127.02638 -125.235628)
			(xy 126.992294 -125.191485) (xy 126.964998 -125.14285) (xy 126.945075 -125.090759) (xy 126.932949 -125.036322)
			(xy 126.928878 -124.9807) (xy 125.536137 -124.9807) (xy 125.535943 -124.991314) (xy 125.527823 -125.04649)
			(xy 125.511755 -125.099897) (xy 125.488083 -125.150394) (xy 125.45731 -125.196907) (xy 125.420093 -125.238444)
			(xy 125.377225 -125.274119) (xy 125.329619 -125.303173) (xy 125.27829 -125.324985) (xy 125.224333 -125.339091)
			(xy 125.168896 -125.345191) (xy 125.113162 -125.343154) (xy 125.058319 -125.333024) (xy 125.005535 -125.315017)
			(xy 124.955935 -125.289516) (xy 124.910577 -125.257065) (xy 124.870428 -125.218356) (xy 124.836342 -125.174213)
			(xy 124.809046 -125.125578) (xy 124.789123 -125.073487) (xy 124.776997 -125.01905) (xy 124.772926 -124.963428)
			(xy 122.510804 -124.963428) (xy 122.510804 -125.403356) (xy 131.644136 -125.403356) (xy 131.644626 -125.375987)
			(xy 131.652437 -125.321808) (xy 131.66792 -125.269305) (xy 131.690756 -125.219558) (xy 131.720477 -125.17359)
			(xy 131.738116 -125.152658) (xy 131.73837 -125.152404) (xy 131.743969 -125.145326) (xy 131.750206 -125.128402)
			(xy 131.750562 -125.119384) (xy 131.750562 -125.052328) (xy 131.7502 -125.043312) (xy 131.743957 -125.026394)
			(xy 131.73837 -125.019308) (xy 131.738116 -125.019308) (xy 131.738116 -125.019054) (xy 131.720491 -124.99811)
			(xy 131.690777 -124.952141) (xy 131.667938 -124.902396) (xy 131.652443 -124.849898) (xy 131.644612 -124.795724)
			(xy 131.644136 -124.768356) (xy 131.644622 -124.741105) (xy 131.652378 -124.687157) (xy 131.667733 -124.634862)
			(xy 131.690375 -124.585285) (xy 131.719841 -124.539435) (xy 131.755532 -124.498244) (xy 131.796723 -124.462553)
			(xy 131.842573 -124.433087) (xy 131.89215 -124.410445) (xy 131.944445 -124.39509) (xy 131.998393 -124.387334)
			(xy 132.052895 -124.387334) (xy 132.106843 -124.39509) (xy 132.159138 -124.410445) (xy 132.208715 -124.433087)
			(xy 132.254565 -124.462553) (xy 132.295756 -124.498244) (xy 132.331447 -124.539435) (xy 132.360913 -124.585285)
			(xy 132.383555 -124.634862) (xy 132.39891 -124.687157) (xy 132.406666 -124.741105) (xy 132.407152 -124.768356)
			(xy 132.406672 -124.795726) (xy 132.398859 -124.849905) (xy 132.383374 -124.902408) (xy 132.360535 -124.952155)
			(xy 132.330813 -124.998122) (xy 132.313172 -125.019054) (xy 132.312918 -125.019308) (xy 132.307324 -125.02639)
			(xy 132.301082 -125.04331) (xy 132.300726 -125.052328) (xy 132.300726 -125.119384) (xy 132.301085 -125.128401)
			(xy 132.307331 -125.145318) (xy 132.312918 -125.152404) (xy 132.313172 -125.152404) (xy 132.313172 -125.152658)
			(xy 132.330801 -125.173599) (xy 132.360515 -125.219569) (xy 132.383353 -125.269314) (xy 132.398847 -125.321813)
			(xy 132.406677 -125.375987) (xy 132.407152 -125.403356) (xy 132.406666 -125.430607) (xy 132.39891 -125.484555)
			(xy 132.383555 -125.53685) (xy 132.360913 -125.586427) (xy 132.331447 -125.632277) (xy 132.295756 -125.673468)
			(xy 132.254565 -125.709159) (xy 132.208715 -125.738625) (xy 132.159138 -125.761267) (xy 132.106843 -125.776622)
			(xy 132.052895 -125.784378) (xy 131.998393 -125.784378) (xy 131.944445 -125.776622) (xy 131.89215 -125.761267)
			(xy 131.842573 -125.738625) (xy 131.796723 -125.709159) (xy 131.755532 -125.673468) (xy 131.719841 -125.632277)
			(xy 131.690375 -125.586427) (xy 131.667733 -125.53685) (xy 131.652378 -125.484555) (xy 131.644622 -125.430607)
			(xy 131.644136 -125.403356) (xy 122.510804 -125.403356) (xy 122.510804 -125.979428) (xy 124.772926 -125.979428)
			(xy 124.776997 -125.923806) (xy 124.789123 -125.869369) (xy 124.809046 -125.817278) (xy 124.836342 -125.768643)
			(xy 124.870428 -125.7245) (xy 124.910577 -125.685791) (xy 124.955935 -125.65334) (xy 125.005535 -125.627839)
			(xy 125.058319 -125.609832) (xy 125.113162 -125.599702) (xy 125.168896 -125.597665) (xy 125.224333 -125.603765)
			(xy 125.27829 -125.617871) (xy 125.329619 -125.639683) (xy 125.377225 -125.668737) (xy 125.420093 -125.704412)
			(xy 125.45731 -125.745949) (xy 125.488083 -125.792462) (xy 125.511755 -125.842959) (xy 125.527823 -125.896366)
			(xy 125.535943 -125.951542) (xy 125.536151 -125.962918) (xy 127.251204 -125.962918) (xy 127.255275 -125.907296)
			(xy 127.267401 -125.852859) (xy 127.287324 -125.800768) (xy 127.31462 -125.752133) (xy 127.348706 -125.70799)
			(xy 127.388855 -125.669281) (xy 127.434213 -125.63683) (xy 127.483813 -125.611329) (xy 127.536597 -125.593322)
			(xy 127.59144 -125.583192) (xy 127.647174 -125.581155) (xy 127.702611 -125.587255) (xy 127.756568 -125.601361)
			(xy 127.807897 -125.623173) (xy 127.855503 -125.652227) (xy 127.898371 -125.687902) (xy 127.935588 -125.729439)
			(xy 127.966361 -125.775952) (xy 127.990033 -125.826449) (xy 127.998231 -125.853698) (xy 132.584698 -125.853698)
			(xy 132.585163 -125.826328) (xy 132.592981 -125.772149) (xy 132.608471 -125.719646) (xy 132.631313 -125.669899)
			(xy 132.661037 -125.623932) (xy 132.678678 -125.603) (xy 132.678932 -125.602746) (xy 132.684509 -125.595653)
			(xy 132.69076 -125.578741) (xy 132.691124 -125.569726) (xy 132.691124 -125.50267) (xy 132.690776 -125.493652)
			(xy 132.684522 -125.476736) (xy 132.678932 -125.46965) (xy 132.678678 -125.46965) (xy 132.678678 -125.469396)
			(xy 132.66102 -125.448479) (xy 132.631312 -125.402502) (xy 132.60848 -125.35275) (xy 132.592993 -125.300246)
			(xy 132.58517 -125.246068) (xy 132.584698 -125.218698) (xy 132.585184 -125.191447) (xy 132.59294 -125.137499)
			(xy 132.608295 -125.085204) (xy 132.630937 -125.035627) (xy 132.660403 -124.989777) (xy 132.696094 -124.948586)
			(xy 132.737285 -124.912895) (xy 132.783135 -124.883429) (xy 132.832712 -124.860787) (xy 132.885007 -124.845432)
			(xy 132.938955 -124.837676) (xy 132.993457 -124.837676) (xy 133.047405 -124.845432) (xy 133.0997 -124.860787)
			(xy 133.149277 -124.883429) (xy 133.195127 -124.912895) (xy 133.236318 -124.948586) (xy 133.272009 -124.989777)
			(xy 133.301475 -125.035627) (xy 133.324117 -125.085204) (xy 133.339472 -125.137499) (xy 133.347228 -125.191447)
			(xy 133.347714 -125.218698) (xy 133.347243 -125.246068) (xy 133.339426 -125.300247) (xy 133.323938 -125.35275)
			(xy 133.301097 -125.402497) (xy 133.271374 -125.448464) (xy 133.253734 -125.469396) (xy 133.25348 -125.46965)
			(xy 133.247906 -125.476745) (xy 133.241652 -125.493655) (xy 133.241288 -125.50267) (xy 133.241288 -125.569726)
			(xy 133.241635 -125.578744) (xy 133.24789 -125.59566) (xy 133.25348 -125.602746) (xy 133.253734 -125.602746)
			(xy 133.253734 -125.603) (xy 133.271392 -125.623917) (xy 133.3011 -125.669894) (xy 133.323931 -125.719646)
			(xy 133.339418 -125.77215) (xy 133.347242 -125.826328) (xy 133.347714 -125.853698) (xy 133.347228 -125.880949)
			(xy 133.339472 -125.934897) (xy 133.324117 -125.987192) (xy 133.301475 -126.036769) (xy 133.272009 -126.082619)
			(xy 133.236318 -126.12381) (xy 133.195127 -126.159501) (xy 133.149277 -126.188967) (xy 133.0997 -126.211609)
			(xy 133.047405 -126.226964) (xy 132.993457 -126.23472) (xy 132.938955 -126.23472) (xy 132.885007 -126.226964)
			(xy 132.832712 -126.211609) (xy 132.783135 -126.188967) (xy 132.737285 -126.159501) (xy 132.696094 -126.12381)
			(xy 132.660403 -126.082619) (xy 132.630937 -126.036769) (xy 132.608295 -125.987192) (xy 132.59294 -125.934897)
			(xy 132.585184 -125.880949) (xy 132.584698 -125.853698) (xy 127.998231 -125.853698) (xy 128.006101 -125.879856)
			(xy 128.014221 -125.935032) (xy 128.01473 -125.962918) (xy 128.014221 -125.990804) (xy 128.006101 -126.04598)
			(xy 127.990033 -126.099387) (xy 127.966361 -126.149884) (xy 127.935588 -126.196397) (xy 127.898371 -126.237934)
			(xy 127.855503 -126.273609) (xy 127.807897 -126.302663) (xy 127.756568 -126.324475) (xy 127.702611 -126.338581)
			(xy 127.647174 -126.344681) (xy 127.59144 -126.342644) (xy 127.536597 -126.332514) (xy 127.483813 -126.314507)
			(xy 127.434213 -126.289006) (xy 127.388855 -126.256555) (xy 127.348706 -126.217846) (xy 127.31462 -126.173703)
			(xy 127.287324 -126.125068) (xy 127.267401 -126.072977) (xy 127.255275 -126.01854) (xy 127.251204 -125.962918)
			(xy 125.536151 -125.962918) (xy 125.536452 -125.979428) (xy 125.535943 -126.007314) (xy 125.527823 -126.06249)
			(xy 125.511755 -126.115897) (xy 125.488083 -126.166394) (xy 125.45731 -126.212907) (xy 125.420093 -126.254444)
			(xy 125.377225 -126.290119) (xy 125.329619 -126.319173) (xy 125.27829 -126.340985) (xy 125.224333 -126.355091)
			(xy 125.168896 -126.361191) (xy 125.113162 -126.359154) (xy 125.058319 -126.349024) (xy 125.005535 -126.331017)
			(xy 124.955935 -126.305516) (xy 124.910577 -126.273065) (xy 124.870428 -126.234356) (xy 124.836342 -126.190213)
			(xy 124.809046 -126.141578) (xy 124.789123 -126.089487) (xy 124.776997 -126.03505) (xy 124.772926 -125.979428)
			(xy 122.510804 -125.979428) (xy 122.510804 -126.530354) (xy 133.79323 -126.530354) (xy 133.79377 -126.50269)
			(xy 133.801763 -126.447941) (xy 133.817574 -126.39492) (xy 133.840871 -126.344735) (xy 133.871169 -126.298439)
			(xy 133.907831 -126.257) (xy 133.95009 -126.221287) (xy 133.973316 -126.20625) (xy 133.982968 -126.199582)
			(xy 133.995426 -126.179744) (xy 133.997192 -126.16815) (xy 134.005066 -126.08814) (xy 134.005661 -126.076503)
			(xy 133.997606 -126.054668) (xy 133.989572 -126.04623) (xy 133.989318 -126.045976) (xy 133.970746 -126.027885)
			(xy 133.938166 -125.987556) (xy 133.911352 -125.943184) (xy 133.890797 -125.895587) (xy 133.876882 -125.845644)
			(xy 133.869863 -125.794277) (xy 133.86943 -125.768354) (xy 133.869835 -125.7411) (xy 133.877599 -125.687147)
			(xy 133.892962 -125.634849) (xy 133.915611 -125.585269) (xy 133.945086 -125.539417) (xy 133.980786 -125.498226)
			(xy 134.021984 -125.462535) (xy 134.067843 -125.433071) (xy 134.117428 -125.410432) (xy 134.169729 -125.395081)
			(xy 134.223684 -125.387329) (xy 134.250938 -125.386846) (xy 134.278307 -125.387337) (xy 134.332486 -125.395147)
			(xy 134.384989 -125.41063) (xy 134.434737 -125.433466) (xy 134.480704 -125.463187) (xy 134.501636 -125.480826)
			(xy 134.50189 -125.48108) (xy 134.508968 -125.486678) (xy 134.525892 -125.492916) (xy 134.53491 -125.493272)
			(xy 134.601966 -125.493272) (xy 134.610982 -125.492905) (xy 134.627899 -125.486665) (xy 134.634986 -125.48108)
			(xy 134.634986 -125.480826) (xy 134.63524 -125.480826) (xy 134.656187 -125.463206) (xy 134.702155 -125.43349)
			(xy 134.751899 -125.41065) (xy 134.804397 -125.395155) (xy 134.85857 -125.387322) (xy 134.885938 -125.386846)
			(xy 134.913188 -125.387342) (xy 134.967133 -125.395103) (xy 135.019425 -125.41046) (xy 135.068999 -125.433103)
			(xy 135.114847 -125.462569) (xy 135.156036 -125.498259) (xy 135.191727 -125.539447) (xy 135.221194 -125.585294)
			(xy 135.243837 -125.634868) (xy 135.259195 -125.687159) (xy 135.266957 -125.741104) (xy 135.267446 -125.768354)
			(xy 135.266915 -125.797271) (xy 135.258192 -125.854442) (xy 135.240938 -125.909642) (xy 135.215548 -125.961604)
			(xy 135.182606 -126.009138) (xy 135.142865 -126.051154) (xy 135.12038 -126.069344) (xy 135.111559 -126.076938)
			(xy 135.101384 -126.097849) (xy 135.100822 -126.109476) (xy 135.100822 -126.189232) (xy 135.101349 -126.200866)
			(xy 135.111546 -126.221775) (xy 135.12038 -126.229364) (xy 135.142842 -126.24758) (xy 135.18258 -126.289594)
			(xy 135.215522 -126.337124) (xy 135.240914 -126.38908) (xy 135.258175 -126.444273) (xy 135.266908 -126.501439)
			(xy 135.267446 -126.530354) (xy 135.266902 -126.557604) (xy 135.259152 -126.61155) (xy 135.247051 -126.652782)
			(xy 135.538718 -126.652782) (xy 135.539169 -126.625411) (xy 135.54699 -126.571231) (xy 135.562482 -126.518728)
			(xy 135.585327 -126.468981) (xy 135.615055 -126.423015) (xy 135.632698 -126.402084) (xy 135.632952 -126.40183)
			(xy 135.638538 -126.394744) (xy 135.644784 -126.377826) (xy 135.645144 -126.36881) (xy 135.645144 -126.301754)
			(xy 135.644773 -126.292738) (xy 135.638537 -126.275821) (xy 135.632952 -126.268734) (xy 135.632698 -126.268734)
			(xy 135.632698 -126.26848) (xy 135.615041 -126.247561) (xy 135.585319 -126.20159) (xy 135.562476 -126.151841)
			(xy 135.546983 -126.099337) (xy 135.539157 -126.045158) (xy 135.539159 -125.990415) (xy 135.546989 -125.936236)
			(xy 135.562486 -125.883733) (xy 135.585332 -125.833986) (xy 135.615057 -125.788017) (xy 135.632698 -125.767084)
			(xy 135.632952 -125.76683) (xy 135.638538 -125.759744) (xy 135.644784 -125.742826) (xy 135.645144 -125.73381)
			(xy 135.645144 -125.666754) (xy 135.644773 -125.657738) (xy 135.638537 -125.640821) (xy 135.632952 -125.633734)
			(xy 135.632698 -125.633734) (xy 135.632698 -125.63348) (xy 135.615041 -125.612561) (xy 135.585319 -125.56659)
			(xy 135.562476 -125.516841) (xy 135.546983 -125.464337) (xy 135.539157 -125.410158) (xy 135.539159 -125.355415)
			(xy 135.546989 -125.301236) (xy 135.562486 -125.248733) (xy 135.585332 -125.198986) (xy 135.615057 -125.153017)
			(xy 135.632698 -125.132084) (xy 135.632952 -125.13183) (xy 135.638538 -125.124744) (xy 135.644784 -125.107826)
			(xy 135.645144 -125.09881) (xy 135.645144 -125.031754) (xy 135.644773 -125.022738) (xy 135.638537 -125.005821)
			(xy 135.632952 -124.998734) (xy 135.632698 -124.998734) (xy 135.632698 -124.99848) (xy 135.615083 -124.977529)
			(xy 135.585367 -124.931561) (xy 135.562527 -124.881819) (xy 135.54703 -124.829322) (xy 135.539196 -124.77515)
			(xy 135.538718 -124.747782) (xy 135.539204 -124.720531) (xy 135.54696 -124.666583) (xy 135.562315 -124.614288)
			(xy 135.584957 -124.564711) (xy 135.614423 -124.518861) (xy 135.650114 -124.47767) (xy 135.691305 -124.441979)
			(xy 135.737155 -124.412513) (xy 135.786732 -124.389871) (xy 135.839027 -124.374516) (xy 135.892975 -124.36676)
			(xy 135.947477 -124.36676) (xy 136.001425 -124.374516) (xy 136.05372 -124.389871) (xy 136.103297 -124.412513)
			(xy 136.149147 -124.441979) (xy 136.190338 -124.47767) (xy 136.226029 -124.518861) (xy 136.255495 -124.564711)
			(xy 136.278137 -124.614288) (xy 136.293492 -124.666583) (xy 136.301248 -124.720531) (xy 136.301734 -124.747782)
			(xy 136.301273 -124.775153) (xy 136.293457 -124.829333) (xy 136.277967 -124.881836) (xy 136.255124 -124.931583)
			(xy 136.225397 -124.977549) (xy 136.207754 -124.99848) (xy 136.2075 -124.998734) (xy 136.201935 -125.005835)
			(xy 136.195675 -125.022741) (xy 136.195308 -125.031754) (xy 136.195308 -125.09881) (xy 136.195659 -125.107828)
			(xy 136.20191 -125.124745) (xy 136.2075 -125.13183) (xy 136.207754 -125.13183) (xy 136.207754 -125.132084)
			(xy 136.225378 -125.153031) (xy 136.255105 -125.198996) (xy 136.277952 -125.248739) (xy 136.293451 -125.30124)
			(xy 136.301282 -125.355416) (xy 136.301284 -125.410156) (xy 136.293457 -125.464334) (xy 136.277962 -125.516835)
			(xy 136.255118 -125.566581) (xy 136.225394 -125.612548) (xy 136.207754 -125.63348) (xy 136.2075 -125.633734)
			(xy 136.201935 -125.640835) (xy 136.195675 -125.657741) (xy 136.195308 -125.666754) (xy 136.195308 -125.73381)
			(xy 136.195659 -125.742828) (xy 136.20191 -125.759745) (xy 136.2075 -125.76683) (xy 136.207754 -125.76683)
			(xy 136.207754 -125.767084) (xy 136.225378 -125.788031) (xy 136.255105 -125.833996) (xy 136.277952 -125.883739)
			(xy 136.293451 -125.93624) (xy 136.301282 -125.990416) (xy 136.301284 -126.045156) (xy 136.293457 -126.099334)
			(xy 136.277962 -126.151835) (xy 136.255118 -126.201581) (xy 136.225394 -126.247548) (xy 136.207754 -126.26848)
			(xy 136.2075 -126.268734) (xy 136.201935 -126.275835) (xy 136.195675 -126.292741) (xy 136.195308 -126.301754)
			(xy 136.195308 -126.36881) (xy 136.195659 -126.377828) (xy 136.20191 -126.394745) (xy 136.2075 -126.40183)
			(xy 136.207754 -126.40183) (xy 136.207754 -126.402084) (xy 136.225392 -126.423017) (xy 136.255105 -126.468989)
			(xy 136.277942 -126.518736) (xy 136.293434 -126.571237) (xy 136.301261 -126.625413) (xy 136.301734 -126.652782)
			(xy 136.301248 -126.680033) (xy 136.293492 -126.733981) (xy 136.278137 -126.786276) (xy 136.255495 -126.835853)
			(xy 136.226029 -126.881703) (xy 136.190338 -126.922894) (xy 136.149147 -126.958585) (xy 136.103297 -126.988051)
			(xy 136.05372 -127.010693) (xy 136.001425 -127.026048) (xy 135.947477 -127.033804) (xy 135.892975 -127.033804)
			(xy 135.839027 -127.026048) (xy 135.786732 -127.010693) (xy 135.737155 -126.988051) (xy 135.691305 -126.958585)
			(xy 135.650114 -126.922894) (xy 135.614423 -126.881703) (xy 135.584957 -126.835853) (xy 135.562315 -126.786276)
			(xy 135.54696 -126.733981) (xy 135.539204 -126.680033) (xy 135.538718 -126.652782) (xy 135.247051 -126.652782)
			(xy 135.243804 -126.663844) (xy 135.22117 -126.713422) (xy 135.19171 -126.759273) (xy 135.156025 -126.800465)
			(xy 135.11484 -126.83616) (xy 135.068995 -126.865629) (xy 135.019423 -126.888275) (xy 134.967132 -126.903634)
			(xy 134.913188 -126.911396) (xy 134.885938 -126.911862) (xy 134.859622 -126.911448) (xy 134.807491 -126.904204)
			(xy 134.756847 -126.889875) (xy 134.708647 -126.868733) (xy 134.663805 -126.841177) (xy 134.623169 -126.807728)
			(xy 134.605014 -126.788672) (xy 134.59748 -126.781285) (xy 134.57821 -126.77275) (xy 134.567676 -126.772162)
			(xy 134.493 -126.772162) (xy 134.48245 -126.772689) (xy 134.463156 -126.781227) (xy 134.455662 -126.788672)
			(xy 134.437512 -126.807734) (xy 134.396882 -126.841191) (xy 134.352041 -126.86875) (xy 134.303839 -126.889888)
			(xy 134.25319 -126.904203) (xy 134.201055 -126.911425) (xy 134.174738 -126.911862) (xy 134.147484 -126.911409)
			(xy 134.09353 -126.903656) (xy 134.041229 -126.888303) (xy 133.991646 -126.865661) (xy 133.945791 -126.836193)
			(xy 133.904597 -126.800498) (xy 133.868902 -126.759303) (xy 133.839435 -126.713447) (xy 133.816795 -126.663863)
			(xy 133.801442 -126.611562) (xy 133.79369 -126.557608) (xy 133.79323 -126.530354) (xy 122.510804 -126.530354)
			(xy 122.510804 -127.051308) (xy 126.844042 -127.051308) (xy 126.848113 -126.995686) (xy 126.860239 -126.941249)
			(xy 126.880162 -126.889158) (xy 126.907458 -126.840523) (xy 126.941544 -126.79638) (xy 126.981693 -126.757671)
			(xy 127.027051 -126.72522) (xy 127.076651 -126.699719) (xy 127.129435 -126.681712) (xy 127.184278 -126.671582)
			(xy 127.240012 -126.669545) (xy 127.295449 -126.675645) (xy 127.349406 -126.689751) (xy 127.400735 -126.711563)
			(xy 127.448341 -126.740617) (xy 127.491209 -126.776292) (xy 127.528426 -126.817829) (xy 127.559199 -126.864342)
			(xy 127.582871 -126.914839) (xy 127.598939 -126.968246) (xy 127.607059 -127.023422) (xy 127.607568 -127.051308)
			(xy 127.607059 -127.079194) (xy 127.598939 -127.13437) (xy 127.582871 -127.187777) (xy 127.559199 -127.238274)
			(xy 127.528426 -127.284787) (xy 127.491209 -127.326324) (xy 127.448341 -127.361999) (xy 127.400735 -127.391053)
			(xy 127.349406 -127.412865) (xy 127.295449 -127.426971) (xy 127.240012 -127.433071) (xy 127.184278 -127.431034)
			(xy 127.129435 -127.420904) (xy 127.076651 -127.402897) (xy 127.027051 -127.377396) (xy 126.981693 -127.344945)
			(xy 126.941544 -127.306236) (xy 126.907458 -127.262093) (xy 126.880162 -127.213458) (xy 126.860239 -127.161367)
			(xy 126.848113 -127.10693) (xy 126.844042 -127.051308) (xy 122.510804 -127.051308) (xy 122.510804 -128.252748)
			(xy 125.828328 -128.252748) (xy 125.828328 -128.198252) (xy 125.836084 -128.144312) (xy 125.851437 -128.092024)
			(xy 125.874075 -128.042454) (xy 125.903537 -127.99661) (xy 125.939223 -127.955425) (xy 125.980408 -127.919738)
			(xy 126.026252 -127.890276) (xy 126.075822 -127.867637) (xy 126.12811 -127.852284) (xy 126.18205 -127.844528)
			(xy 126.209298 -127.844042) (xy 126.236669 -127.844499) (xy 126.290849 -127.852317) (xy 126.343352 -127.867808)
			(xy 126.393099 -127.890652) (xy 126.439065 -127.920379) (xy 126.459996 -127.938022) (xy 126.46025 -127.938276)
			(xy 126.46734 -127.943857) (xy 126.484254 -127.950105) (xy 126.49327 -127.950468) (xy 126.560326 -127.950468)
			(xy 126.569345 -127.95013) (xy 126.586262 -127.94387) (xy 126.593346 -127.938276) (xy 126.593346 -127.938022)
			(xy 126.5936 -127.938022) (xy 126.614533 -127.920381) (xy 126.660501 -127.890657) (xy 126.710247 -127.867811)
			(xy 126.762749 -127.852315) (xy 126.816927 -127.844486) (xy 126.871669 -127.844486) (xy 126.925847 -127.852315)
			(xy 126.978349 -127.867811) (xy 127.028095 -127.890657) (xy 127.074063 -127.920381) (xy 127.094996 -127.938022)
			(xy 127.09525 -127.938276) (xy 127.10234 -127.943857) (xy 127.119254 -127.950105) (xy 127.12827 -127.950468)
			(xy 127.195326 -127.950468) (xy 127.204345 -127.95013) (xy 127.221262 -127.94387) (xy 127.228346 -127.938276)
			(xy 127.228346 -127.938022) (xy 127.2286 -127.938022) (xy 127.249524 -127.920373) (xy 127.295499 -127.890662)
			(xy 127.345248 -127.867827) (xy 127.397751 -127.852339) (xy 127.451928 -127.844514) (xy 127.479298 -127.844042)
			(xy 127.506555 -127.844405) (xy 127.560513 -127.852163) (xy 127.612818 -127.86752) (xy 127.662405 -127.890166)
			(xy 127.708264 -127.919638) (xy 127.749463 -127.955336) (xy 127.785161 -127.996534) (xy 127.814633 -128.042393)
			(xy 127.837279 -128.09198) (xy 127.852637 -128.144285) (xy 127.860395 -128.198243) (xy 127.860395 -128.252757)
			(xy 127.852637 -128.306715) (xy 127.837279 -128.35902) (xy 127.814633 -128.408607) (xy 127.785161 -128.454466)
			(xy 127.749463 -128.495664) (xy 127.708264 -128.531362) (xy 127.662405 -128.560834) (xy 127.612818 -128.58348)
			(xy 127.560513 -128.598837) (xy 127.506555 -128.606595) (xy 127.479298 -128.607058) (xy 127.451927 -128.606603)
			(xy 127.397747 -128.598784) (xy 127.345244 -128.583293) (xy 127.295497 -128.560449) (xy 127.249531 -128.530721)
			(xy 127.2286 -128.513078) (xy 127.228346 -128.512824) (xy 127.221257 -128.507242) (xy 127.204342 -128.500994)
			(xy 127.195326 -128.500632) (xy 127.12827 -128.500632) (xy 127.119251 -128.500968) (xy 127.102334 -128.507229)
			(xy 127.09525 -128.512824) (xy 127.09525 -128.513078) (xy 127.094996 -128.513078) (xy 127.074063 -128.530719)
			(xy 127.028095 -128.560443) (xy 126.978349 -128.583289) (xy 126.925847 -128.598785) (xy 126.871669 -128.606614)
			(xy 126.816927 -128.606614) (xy 126.762749 -128.598785) (xy 126.710247 -128.583289) (xy 126.660501 -128.560443)
			(xy 126.614533 -128.530719) (xy 126.5936 -128.513078) (xy 126.593346 -128.512824) (xy 126.586257 -128.507242)
			(xy 126.569342 -128.500994) (xy 126.560326 -128.500632) (xy 126.49327 -128.500632) (xy 126.484251 -128.500968)
			(xy 126.467334 -128.507229) (xy 126.46025 -128.512824) (xy 126.46025 -128.513078) (xy 126.459996 -128.513078)
			(xy 126.439073 -128.530729) (xy 126.393098 -128.56044) (xy 126.343348 -128.583274) (xy 126.290846 -128.598762)
			(xy 126.236668 -128.606586) (xy 126.209298 -128.607058) (xy 126.18205 -128.606472) (xy 126.12811 -128.598716)
			(xy 126.075822 -128.583363) (xy 126.026252 -128.560724) (xy 125.980408 -128.531262) (xy 125.939223 -128.495575)
			(xy 125.903537 -128.45439) (xy 125.874075 -128.408546) (xy 125.851437 -128.358976) (xy 125.836084 -128.306688)
			(xy 125.828328 -128.252748) (xy 122.510804 -128.252748) (xy 122.510804 -131.447157) (xy 125.813209 -131.447157)
			(xy 125.813209 -131.392643) (xy 125.820967 -131.338685) (xy 125.836326 -131.28638) (xy 125.858972 -131.236793)
			(xy 125.888445 -131.190933) (xy 125.924144 -131.149735) (xy 125.965343 -131.114037) (xy 126.011203 -131.084566)
			(xy 126.060791 -131.061922) (xy 126.113096 -131.046565) (xy 126.167055 -131.038808) (xy 126.194312 -131.038346)
			(xy 126.221683 -131.038794) (xy 126.275863 -131.046614) (xy 126.328367 -131.062107) (xy 126.378114 -131.084953)
			(xy 126.424079 -131.114682) (xy 126.44501 -131.132326) (xy 126.445264 -131.13258) (xy 126.45235 -131.138167)
			(xy 126.469268 -131.144411) (xy 126.478284 -131.144772) (xy 126.54534 -131.144772) (xy 126.55436 -131.14444)
			(xy 126.571277 -131.138176) (xy 126.57836 -131.13258) (xy 126.57836 -131.132326) (xy 126.578614 -131.132326)
			(xy 126.599547 -131.114685) (xy 126.645515 -131.084961) (xy 126.695261 -131.062115) (xy 126.747763 -131.046619)
			(xy 126.801941 -131.03879) (xy 126.856683 -131.03879) (xy 126.910861 -131.046619) (xy 126.963363 -131.062115)
			(xy 127.013109 -131.084961) (xy 127.059077 -131.114685) (xy 127.08001 -131.132326) (xy 127.080264 -131.13258)
			(xy 127.08735 -131.138167) (xy 127.104268 -131.144411) (xy 127.113284 -131.144772) (xy 127.18034 -131.144772)
			(xy 127.18936 -131.14444) (xy 127.206277 -131.138176) (xy 127.21336 -131.13258) (xy 127.21336 -131.132326)
			(xy 127.213614 -131.132326) (xy 127.234571 -131.114718) (xy 127.280537 -131.085) (xy 127.330278 -131.062158)
			(xy 127.382773 -131.04666) (xy 127.436944 -131.038824) (xy 127.464312 -131.038346) (xy 127.491559 -131.038925)
			(xy 127.545499 -131.046682) (xy 127.597786 -131.062036) (xy 127.647356 -131.084675) (xy 127.693199 -131.114138)
			(xy 127.734383 -131.149826) (xy 127.770069 -131.19101) (xy 127.79953 -131.236855) (xy 127.822168 -131.286425)
			(xy 127.837521 -131.338712) (xy 127.845276 -131.392653) (xy 127.845276 -131.447147) (xy 127.837521 -131.501087)
			(xy 127.822168 -131.553375) (xy 127.79953 -131.602945) (xy 127.770069 -131.64879) (xy 127.734383 -131.689974)
			(xy 127.693199 -131.725662) (xy 127.647356 -131.755125) (xy 127.597786 -131.777764) (xy 127.545499 -131.793118)
			(xy 127.491559 -131.800875) (xy 127.464312 -131.801362) (xy 127.436942 -131.800898) (xy 127.382762 -131.793081)
			(xy 127.330259 -131.777592) (xy 127.280512 -131.75475) (xy 127.234545 -131.725024) (xy 127.213614 -131.707382)
			(xy 127.21336 -131.707128) (xy 127.206267 -131.701552) (xy 127.189355 -131.695301) (xy 127.18034 -131.694936)
			(xy 127.113284 -131.694936) (xy 127.104265 -131.695277) (xy 127.087348 -131.701535) (xy 127.080264 -131.707128)
			(xy 127.080264 -131.707382) (xy 127.08001 -131.707382) (xy 127.059077 -131.725023) (xy 127.013109 -131.754747)
			(xy 126.963363 -131.777593) (xy 126.910861 -131.793089) (xy 126.856683 -131.800918) (xy 126.801941 -131.800918)
			(xy 126.747763 -131.793089) (xy 126.695261 -131.777593) (xy 126.645515 -131.754747) (xy 126.599547 -131.725023)
			(xy 126.578614 -131.707382) (xy 126.57836 -131.707128) (xy 126.571267 -131.701552) (xy 126.554355 -131.695301)
			(xy 126.54534 -131.694936) (xy 126.478284 -131.694936) (xy 126.469265 -131.695277) (xy 126.452348 -131.701535)
			(xy 126.445264 -131.707128) (xy 126.445264 -131.707382) (xy 126.44501 -131.707382) (xy 126.424083 -131.725027)
			(xy 126.378109 -131.754739) (xy 126.32836 -131.777574) (xy 126.275858 -131.793063) (xy 126.221682 -131.800889)
			(xy 126.194312 -131.801362) (xy 126.167055 -131.800992) (xy 126.113096 -131.793235) (xy 126.060791 -131.777878)
			(xy 126.011203 -131.755234) (xy 125.965343 -131.725763) (xy 125.924144 -131.690065) (xy 125.888445 -131.648867)
			(xy 125.858972 -131.603007) (xy 125.836326 -131.55342) (xy 125.820967 -131.501115) (xy 125.813209 -131.447157)
			(xy 122.510804 -131.447157) (xy 122.510804 -132.1562) (xy 122.51034 -132.189355) (xy 122.50292 -132.255249)
			(xy 122.488174 -132.319898) (xy 122.466286 -132.382492) (xy 122.437531 -132.442243) (xy 122.402272 -132.498401)
			(xy 122.360949 -132.550261) (xy 122.33783 -132.57403) (xy 122.09399 -132.81787) (xy 122.087145 -132.825268)
			(xy 122.079422 -132.843867) (xy 122.079004 -132.853938) (xy 122.079004 -133.443726) (xy 127.222758 -133.443726)
			(xy 127.223224 -133.417412) (xy 127.230457 -133.365282) (xy 127.244775 -133.314639) (xy 127.265907 -133.26644)
			(xy 127.293455 -133.221596) (xy 127.326895 -133.180958) (xy 127.345948 -133.162802) (xy 127.353343 -133.155275)
			(xy 127.361873 -133.135999) (xy 127.362458 -133.125464) (xy 127.362458 -133.050788) (xy 127.361961 -133.040234)
			(xy 127.353405 -133.020938) (xy 127.345948 -133.01345) (xy 127.326865 -132.995322) (xy 127.293413 -132.954685)
			(xy 127.265858 -132.909839) (xy 127.244725 -132.861633) (xy 127.230413 -132.810981) (xy 127.223194 -132.758844)
			(xy 127.222758 -132.732526) (xy 127.223244 -132.705275) (xy 127.231 -132.651327) (xy 127.246355 -132.599032)
			(xy 127.268997 -132.549455) (xy 127.298463 -132.503605) (xy 127.334154 -132.462414) (xy 127.375345 -132.426723)
			(xy 127.421195 -132.397257) (xy 127.470772 -132.374615) (xy 127.523067 -132.35926) (xy 127.577015 -132.351504)
			(xy 127.631517 -132.351504) (xy 127.685465 -132.35926) (xy 127.73776 -132.374615) (xy 127.787337 -132.397257)
			(xy 127.833187 -132.426723) (xy 127.874378 -132.462414) (xy 127.910069 -132.503605) (xy 127.939535 -132.549455)
			(xy 127.962177 -132.599032) (xy 127.977532 -132.651327) (xy 127.985288 -132.705275) (xy 127.985774 -132.732526)
			(xy 127.985332 -132.758841) (xy 127.978093 -132.810971) (xy 127.96377 -132.861614) (xy 127.942633 -132.909814)
			(xy 127.915082 -132.954656) (xy 127.881638 -132.995294) (xy 127.862584 -133.01345) (xy 127.855156 -133.020949)
			(xy 127.846647 -133.040246) (xy 127.846074 -133.050788) (xy 127.846074 -133.125464) (xy 127.846617 -133.136012)
			(xy 127.855143 -133.155307) (xy 127.862584 -133.162802) (xy 127.88163 -133.180967) (xy 127.915089 -133.221594)
			(xy 127.94265 -133.266432) (xy 127.96379 -133.314631) (xy 127.978109 -133.365277) (xy 127.985335 -133.41741)
			(xy 127.985774 -133.443726) (xy 127.985288 -133.470977) (xy 127.977532 -133.524925) (xy 127.962177 -133.57722)
			(xy 127.939535 -133.626797) (xy 127.910069 -133.672647) (xy 127.874378 -133.713838) (xy 127.833187 -133.749529)
			(xy 127.787337 -133.778995) (xy 127.73776 -133.801637) (xy 127.685465 -133.816992) (xy 127.631517 -133.824748)
			(xy 127.577015 -133.824748) (xy 127.523067 -133.816992) (xy 127.470772 -133.801637) (xy 127.421195 -133.778995)
			(xy 127.375345 -133.749529) (xy 127.334154 -133.713838) (xy 127.298463 -133.672647) (xy 127.268997 -133.626797)
			(xy 127.246355 -133.57722) (xy 127.231 -133.524925) (xy 127.223244 -133.470977) (xy 127.222758 -133.443726)
			(xy 122.079004 -133.443726) (xy 122.079004 -134.042404) (xy 122.275852 -134.042404) (xy 122.279923 -133.986782)
			(xy 122.292049 -133.932345) (xy 122.311972 -133.880254) (xy 122.339268 -133.831619) (xy 122.373354 -133.787476)
			(xy 122.413503 -133.748767) (xy 122.458861 -133.716316) (xy 122.508461 -133.690815) (xy 122.561245 -133.672808)
			(xy 122.616088 -133.662678) (xy 122.671822 -133.660641) (xy 122.727259 -133.666741) (xy 122.781216 -133.680847)
			(xy 122.832545 -133.702659) (xy 122.880151 -133.731713) (xy 122.923019 -133.767388) (xy 122.960236 -133.808925)
			(xy 122.991009 -133.855438) (xy 123.014681 -133.905935) (xy 123.030749 -133.959342) (xy 123.038869 -134.014518)
			(xy 123.039378 -134.042404) (xy 123.038869 -134.07029) (xy 123.030749 -134.125466) (xy 123.014681 -134.178873)
			(xy 122.991009 -134.22937) (xy 122.960236 -134.275883) (xy 122.923019 -134.31742) (xy 122.880151 -134.353095)
			(xy 122.832545 -134.382149) (xy 122.781216 -134.403961) (xy 122.727259 -134.418067) (xy 122.671822 -134.424167)
			(xy 122.616088 -134.42213) (xy 122.561245 -134.412) (xy 122.508461 -134.393993) (xy 122.458861 -134.368492)
			(xy 122.413503 -134.336041) (xy 122.373354 -134.297332) (xy 122.339268 -134.253189) (xy 122.311972 -134.204554)
			(xy 122.292049 -134.152463) (xy 122.279923 -134.098026) (xy 122.275852 -134.042404) (xy 122.079004 -134.042404)
			(xy 122.079004 -135.142051) (xy 125.46177 -135.142051) (xy 125.46177 -135.087549) (xy 125.469526 -135.033603)
			(xy 125.48488 -134.981309) (xy 125.50752 -134.931732) (xy 125.536985 -134.885882) (xy 125.572674 -134.844691)
			(xy 125.613862 -134.808999) (xy 125.659711 -134.779531) (xy 125.709286 -134.756888) (xy 125.761579 -134.741531)
			(xy 125.815525 -134.733771) (xy 125.842776 -134.733284) (xy 125.871694 -134.733788) (xy 125.928867 -134.742515)
			(xy 125.984068 -134.759774) (xy 126.03603 -134.785168) (xy 126.083563 -134.818116) (xy 126.125578 -134.857862)
			(xy 126.143766 -134.88035) (xy 126.151557 -134.889338) (xy 126.173023 -134.899526) (xy 126.184914 -134.899908)
			(xy 126.278386 -134.897876) (xy 126.299722 -134.8867) (xy 126.30658 -134.876794) (xy 126.321977 -134.855883)
			(xy 126.357555 -134.818056) (xy 126.397935 -134.785404) (xy 126.442369 -134.75853) (xy 126.490038 -134.737929)
			(xy 126.54006 -134.723985) (xy 126.591511 -134.716952) (xy 126.617476 -134.71652) (xy 126.644846 -134.716995)
			(xy 126.699025 -134.72481) (xy 126.751528 -134.740297) (xy 126.801275 -134.763137) (xy 126.847242 -134.792859)
			(xy 126.868174 -134.8105) (xy 126.868428 -134.810754) (xy 126.875526 -134.816323) (xy 126.892434 -134.822579)
			(xy 126.901448 -134.822946) (xy 126.968504 -134.822946) (xy 126.977522 -134.822602) (xy 126.99444 -134.816347)
			(xy 127.001524 -134.810754) (xy 127.001524 -134.8105) (xy 127.001778 -134.8105) (xy 127.022711 -134.792859)
			(xy 127.068679 -134.763135) (xy 127.118425 -134.740289) (xy 127.170927 -134.724793) (xy 127.225105 -134.716964)
			(xy 127.279847 -134.716964) (xy 127.334025 -134.724793) (xy 127.386527 -134.740289) (xy 127.436273 -134.763135)
			(xy 127.482241 -134.792859) (xy 127.503174 -134.8105) (xy 127.503428 -134.810754) (xy 127.510526 -134.816323)
			(xy 127.527434 -134.822579) (xy 127.536448 -134.822946) (xy 127.603504 -134.822946) (xy 127.612522 -134.822602)
			(xy 127.62944 -134.816347) (xy 127.636524 -134.810754) (xy 127.637032 -134.8105) (xy 127.64977 -134.79956)
			(xy 127.676859 -134.779716) (xy 127.691134 -134.770876) (xy 127.700024 -134.765542) (xy 127.712216 -134.748524)
			(xy 127.732536 -134.655306) (xy 127.728218 -134.634732) (xy 127.722376 -134.626096) (xy 127.706369 -134.602036)
			(xy 127.681029 -134.550103) (xy 127.663805 -134.494944) (xy 127.655092 -134.437819) (xy 127.654558 -134.408926)
			(xy 127.655044 -134.381675) (xy 127.6628 -134.327727) (xy 127.678155 -134.275432) (xy 127.700797 -134.225855)
			(xy 127.730263 -134.180005) (xy 127.765954 -134.138814) (xy 127.807145 -134.103123) (xy 127.852995 -134.073657)
			(xy 127.902572 -134.051015) (xy 127.954867 -134.03566) (xy 128.008815 -134.027904) (xy 128.063317 -134.027904)
			(xy 128.117265 -134.03566) (xy 128.16956 -134.051015) (xy 128.219137 -134.073657) (xy 128.264987 -134.103123)
			(xy 128.306178 -134.138814) (xy 128.341869 -134.180005) (xy 128.371335 -134.225855) (xy 128.393977 -134.275432)
			(xy 128.409332 -134.327727) (xy 128.417088 -134.381675) (xy 128.417574 -134.408926) (xy 128.417121 -134.437019)
			(xy 128.408889 -134.492599) (xy 128.392592 -134.54637) (xy 128.368583 -134.597169) (xy 128.337381 -134.643895)
			(xy 128.299662 -134.685539) (xy 128.256242 -134.721198) (xy 128.232408 -134.736078) (xy 128.223518 -134.741412)
			(xy 128.211326 -134.75843) (xy 128.191006 -134.851648) (xy 128.195324 -134.872222) (xy 128.201166 -134.880858)
			(xy 128.217146 -134.904934) (xy 128.242495 -134.956861) (xy 128.259726 -135.012015) (xy 128.268447 -135.069136)
			(xy 128.268984 -135.098028) (xy 128.268548 -135.125281) (xy 128.260787 -135.179232) (xy 128.245427 -135.231529)
			(xy 128.222781 -135.281108) (xy 128.19331 -135.326959) (xy 128.157613 -135.36815) (xy 128.116418 -135.403841)
			(xy 128.070562 -135.433306) (xy 128.02098 -135.455946) (xy 127.968681 -135.471298) (xy 127.914729 -135.479052)
			(xy 127.887476 -135.479536) (xy 127.860105 -135.4791) (xy 127.805924 -135.471277) (xy 127.753419 -135.455782)
			(xy 127.703673 -135.432933) (xy 127.657708 -135.403201) (xy 127.636778 -135.385556) (xy 127.636524 -135.385302)
			(xy 127.629435 -135.37972) (xy 127.61252 -135.37347) (xy 127.603504 -135.37311) (xy 127.536448 -135.37311)
			(xy 127.527433 -135.373488) (xy 127.510516 -135.379721) (xy 127.503428 -135.385302) (xy 127.503428 -135.385556)
			(xy 127.503174 -135.385556) (xy 127.482241 -135.403197) (xy 127.436273 -135.432921) (xy 127.386527 -135.455767)
			(xy 127.334025 -135.471263) (xy 127.279847 -135.479092) (xy 127.225105 -135.479092) (xy 127.170927 -135.471263)
			(xy 127.118425 -135.455767) (xy 127.068679 -135.432921) (xy 127.022711 -135.403197) (xy 127.001778 -135.385556)
			(xy 127.001524 -135.385302) (xy 126.994435 -135.37972) (xy 126.97752 -135.37347) (xy 126.968504 -135.37311)
			(xy 126.901448 -135.37311) (xy 126.892433 -135.373488) (xy 126.875516 -135.379721) (xy 126.868428 -135.385302)
			(xy 126.868428 -135.385556) (xy 126.868174 -135.385556) (xy 126.847219 -135.403167) (xy 126.801253 -135.432885)
			(xy 126.751512 -135.455727) (xy 126.699016 -135.471224) (xy 126.644844 -135.479059) (xy 126.617476 -135.479536)
			(xy 126.58856 -135.478987) (xy 126.531389 -135.470268) (xy 126.47619 -135.453018) (xy 126.424227 -135.427632)
			(xy 126.376693 -135.394692) (xy 126.334676 -135.354954) (xy 126.316486 -135.33247) (xy 126.308668 -135.323509)
			(xy 126.287222 -135.313305) (xy 126.275338 -135.312912) (xy 126.181866 -135.314944) (xy 126.16053 -135.32612)
			(xy 126.153672 -135.336026) (xy 126.138249 -135.356917) (xy 126.102675 -135.394743) (xy 126.062299 -135.427397)
			(xy 126.017869 -135.454273) (xy 125.970205 -135.474877) (xy 125.920187 -135.488826) (xy 125.868739 -135.495864)
			(xy 125.842776 -135.4963) (xy 125.815525 -135.495829) (xy 125.761579 -135.488069) (xy 125.709286 -135.472712)
			(xy 125.659711 -135.450069) (xy 125.613862 -135.420601) (xy 125.572674 -135.384909) (xy 125.536985 -135.343718)
			(xy 125.50752 -135.297868) (xy 125.48488 -135.248291) (xy 125.469526 -135.195997) (xy 125.46177 -135.142051)
			(xy 122.079004 -135.142051) (xy 122.079004 -135.699246) (xy 122.258326 -135.699246) (xy 122.262397 -135.643624)
			(xy 122.274523 -135.589187) (xy 122.294446 -135.537096) (xy 122.321742 -135.488461) (xy 122.355828 -135.444318)
			(xy 122.395977 -135.405609) (xy 122.441335 -135.373158) (xy 122.490935 -135.347657) (xy 122.543719 -135.32965)
			(xy 122.598562 -135.31952) (xy 122.654296 -135.317483) (xy 122.709733 -135.323583) (xy 122.76369 -135.337689)
			(xy 122.815019 -135.359501) (xy 122.862625 -135.388555) (xy 122.905493 -135.42423) (xy 122.94271 -135.465767)
			(xy 122.973483 -135.51228) (xy 122.997155 -135.562777) (xy 123.013223 -135.616184) (xy 123.021343 -135.67136)
			(xy 123.021852 -135.699246) (xy 123.021343 -135.727132) (xy 123.013223 -135.782308) (xy 122.997155 -135.835715)
			(xy 122.982543 -135.866886) (xy 124.539754 -135.866886) (xy 124.543825 -135.811264) (xy 124.555951 -135.756827)
			(xy 124.575874 -135.704736) (xy 124.60317 -135.656101) (xy 124.637256 -135.611958) (xy 124.677405 -135.573249)
			(xy 124.722763 -135.540798) (xy 124.772363 -135.515297) (xy 124.825147 -135.49729) (xy 124.87999 -135.48716)
			(xy 124.935724 -135.485123) (xy 124.991161 -135.491223) (xy 125.045118 -135.505329) (xy 125.096447 -135.527141)
			(xy 125.144053 -135.556195) (xy 125.186921 -135.59187) (xy 125.224138 -135.633407) (xy 125.254911 -135.67992)
			(xy 125.278583 -135.730417) (xy 125.294651 -135.783824) (xy 125.302771 -135.839) (xy 125.30328 -135.866886)
			(xy 125.302771 -135.894772) (xy 125.294651 -135.949948) (xy 125.278583 -136.003355) (xy 125.254911 -136.053852)
			(xy 125.224138 -136.100365) (xy 125.186921 -136.141902) (xy 125.144053 -136.177577) (xy 125.096447 -136.206631)
			(xy 125.045118 -136.228443) (xy 124.991161 -136.242549) (xy 124.935724 -136.248649) (xy 124.87999 -136.246612)
			(xy 124.825147 -136.236482) (xy 124.772363 -136.218475) (xy 124.722763 -136.192974) (xy 124.677405 -136.160523)
			(xy 124.637256 -136.121814) (xy 124.60317 -136.077671) (xy 124.575874 -136.029036) (xy 124.555951 -135.976945)
			(xy 124.543825 -135.922508) (xy 124.539754 -135.866886) (xy 122.982543 -135.866886) (xy 122.973483 -135.886212)
			(xy 122.94271 -135.932725) (xy 122.905493 -135.974262) (xy 122.862625 -136.009937) (xy 122.815019 -136.038991)
			(xy 122.76369 -136.060803) (xy 122.709733 -136.074909) (xy 122.654296 -136.081009) (xy 122.598562 -136.078972)
			(xy 122.543719 -136.068842) (xy 122.490935 -136.050835) (xy 122.441335 -136.025334) (xy 122.395977 -135.992883)
			(xy 122.355828 -135.954174) (xy 122.321742 -135.910031) (xy 122.294446 -135.861396) (xy 122.274523 -135.809305)
			(xy 122.262397 -135.754868) (xy 122.258326 -135.699246) (xy 122.079004 -135.699246) (xy 122.079004 -137.44829)
			(xy 124.445012 -137.44829) (xy 124.449083 -137.392668) (xy 124.461209 -137.338231) (xy 124.481132 -137.28614)
			(xy 124.508428 -137.237505) (xy 124.542514 -137.193362) (xy 124.582663 -137.154653) (xy 124.628021 -137.122202)
			(xy 124.677621 -137.096701) (xy 124.730405 -137.078694) (xy 124.785248 -137.068564) (xy 124.840982 -137.066527)
			(xy 124.896419 -137.072627) (xy 124.950376 -137.086733) (xy 125.001705 -137.108545) (xy 125.049311 -137.137599)
			(xy 125.092179 -137.173274) (xy 125.129396 -137.214811) (xy 125.160169 -137.261324) (xy 125.167204 -137.276332)
			(xy 129.147062 -137.276332) (xy 129.147532 -137.248962) (xy 129.155346 -137.194782) (xy 129.170834 -137.142279)
			(xy 129.193675 -137.092532) (xy 129.2234 -137.046565) (xy 129.241042 -137.025634) (xy 129.241296 -137.02538)
			(xy 129.246897 -137.018303) (xy 129.253135 -137.001379) (xy 129.253488 -136.99236) (xy 129.253488 -136.925304)
			(xy 129.253132 -136.916287) (xy 129.246884 -136.89937) (xy 129.241296 -136.892284) (xy 129.241042 -136.892284)
			(xy 129.241042 -136.89203) (xy 129.22341 -136.871092) (xy 129.193696 -136.825122) (xy 129.170858 -136.775376)
			(xy 129.155365 -136.722876) (xy 129.147536 -136.668701) (xy 129.147062 -136.641332) (xy 129.147548 -136.614081)
			(xy 129.155304 -136.560133) (xy 129.170659 -136.507838) (xy 129.193301 -136.458261) (xy 129.222767 -136.412411)
			(xy 129.258458 -136.37122) (xy 129.299649 -136.335529) (xy 129.345499 -136.306063) (xy 129.395076 -136.283421)
			(xy 129.447371 -136.268066) (xy 129.501319 -136.26031) (xy 129.555821 -136.26031) (xy 129.609769 -136.268066)
			(xy 129.662064 -136.283421) (xy 129.711641 -136.306063) (xy 129.757491 -136.335529) (xy 129.798682 -136.37122)
			(xy 129.834373 -136.412411) (xy 129.863839 -136.458261) (xy 129.886481 -136.507838) (xy 129.901836 -136.560133)
			(xy 129.909592 -136.614081) (xy 129.910078 -136.641332) (xy 129.909636 -136.668703) (xy 129.901813 -136.722883)
			(xy 129.886319 -136.775387) (xy 129.863472 -136.825134) (xy 129.833742 -136.871099) (xy 129.816098 -136.89203)
			(xy 129.815844 -136.892284) (xy 129.810251 -136.899366) (xy 129.80401 -136.916287) (xy 129.803652 -136.925304)
			(xy 129.803652 -136.99236) (xy 129.804017 -137.001376) (xy 129.810258 -137.018294) (xy 129.815844 -137.02538)
			(xy 129.816098 -137.02538) (xy 129.816098 -137.025634) (xy 129.833719 -137.04658) (xy 129.863434 -137.092549)
			(xy 129.886273 -137.142293) (xy 129.901769 -137.194791) (xy 129.909601 -137.248964) (xy 129.910078 -137.276332)
			(xy 129.909592 -137.303583) (xy 129.901836 -137.357531) (xy 129.886481 -137.409826) (xy 129.863839 -137.459403)
			(xy 129.834373 -137.505253) (xy 129.798682 -137.546444) (xy 129.757491 -137.582135) (xy 129.711641 -137.611601)
			(xy 129.662064 -137.634243) (xy 129.609769 -137.649598) (xy 129.555821 -137.657354) (xy 129.501319 -137.657354)
			(xy 129.447371 -137.649598) (xy 129.395076 -137.634243) (xy 129.345499 -137.611601) (xy 129.299649 -137.582135)
			(xy 129.258458 -137.546444) (xy 129.222767 -137.505253) (xy 129.193301 -137.459403) (xy 129.170659 -137.409826)
			(xy 129.155304 -137.357531) (xy 129.147548 -137.303583) (xy 129.147062 -137.276332) (xy 125.167204 -137.276332)
			(xy 125.183841 -137.311821) (xy 125.199909 -137.365228) (xy 125.208029 -137.420404) (xy 125.208538 -137.44829)
			(xy 125.208029 -137.476176) (xy 125.199909 -137.531352) (xy 125.183841 -137.584759) (xy 125.160169 -137.635256)
			(xy 125.129396 -137.681769) (xy 125.092179 -137.723306) (xy 125.088132 -137.726674) (xy 130.087624 -137.726674)
			(xy 130.088069 -137.699303) (xy 130.095891 -137.645123) (xy 130.111385 -137.592619) (xy 130.134231 -137.542873)
			(xy 130.16396 -137.496907) (xy 130.181604 -137.475976) (xy 130.181858 -137.475722) (xy 130.187448 -137.468638)
			(xy 130.193691 -137.451719) (xy 130.19405 -137.442702) (xy 130.19405 -137.375646) (xy 130.193682 -137.36663)
			(xy 130.187443 -137.349712) (xy 130.181858 -137.342626) (xy 130.181604 -137.342626) (xy 130.181604 -137.342372)
			(xy 130.163986 -137.321423) (xy 130.134271 -137.275455) (xy 130.111431 -137.225712) (xy 130.095935 -137.173215)
			(xy 130.088101 -137.119042) (xy 130.087624 -137.091674) (xy 130.08811 -137.064423) (xy 130.095866 -137.010475)
			(xy 130.111221 -136.95818) (xy 130.133863 -136.908603) (xy 130.163329 -136.862753) (xy 130.19902 -136.821562)
			(xy 130.240211 -136.785871) (xy 130.286061 -136.756405) (xy 130.335638 -136.733763) (xy 130.387933 -136.718408)
			(xy 130.441881 -136.710652) (xy 130.496383 -136.710652) (xy 130.550331 -136.718408) (xy 130.602626 -136.733763)
			(xy 130.652203 -136.756405) (xy 130.698053 -136.785871) (xy 130.739244 -136.821562) (xy 130.774935 -136.862753)
			(xy 130.804401 -136.908603) (xy 130.827043 -136.95818) (xy 130.842398 -137.010475) (xy 130.850154 -137.064423)
			(xy 130.85064 -137.091674) (xy 130.850173 -137.119044) (xy 130.842358 -137.173224) (xy 130.82687 -137.225728)
			(xy 130.804028 -137.275475) (xy 130.774302 -137.321441) (xy 130.75666 -137.342372) (xy 130.756406 -137.342626)
			(xy 130.750845 -137.34973) (xy 130.744583 -137.366633) (xy 130.744214 -137.375646) (xy 130.744214 -137.442702)
			(xy 130.744567 -137.451719) (xy 130.750817 -137.468636) (xy 130.756406 -137.475722) (xy 130.75666 -137.475722)
			(xy 130.75666 -137.475976) (xy 130.774295 -137.496911) (xy 130.804009 -137.542883) (xy 130.826846 -137.592629)
			(xy 130.842338 -137.645129) (xy 130.850166 -137.699305) (xy 130.85064 -137.726674) (xy 130.850154 -137.753925)
			(xy 130.842398 -137.807873) (xy 130.827043 -137.860168) (xy 130.804401 -137.909745) (xy 130.774935 -137.955595)
			(xy 130.739244 -137.996786) (xy 130.698053 -138.032477) (xy 130.652203 -138.061943) (xy 130.602626 -138.084585)
			(xy 130.550331 -138.09994) (xy 130.496383 -138.107696) (xy 130.441881 -138.107696) (xy 130.387933 -138.09994)
			(xy 130.335638 -138.084585) (xy 130.286061 -138.061943) (xy 130.240211 -138.032477) (xy 130.19902 -137.996786)
			(xy 130.163329 -137.955595) (xy 130.133863 -137.909745) (xy 130.111221 -137.860168) (xy 130.095866 -137.807873)
			(xy 130.08811 -137.753925) (xy 130.087624 -137.726674) (xy 125.088132 -137.726674) (xy 125.049311 -137.758981)
			(xy 125.001705 -137.788035) (xy 124.950376 -137.809847) (xy 124.896419 -137.823953) (xy 124.840982 -137.830053)
			(xy 124.785248 -137.828016) (xy 124.730405 -137.817886) (xy 124.677621 -137.799879) (xy 124.628021 -137.774378)
			(xy 124.582663 -137.741927) (xy 124.542514 -137.703218) (xy 124.508428 -137.659075) (xy 124.481132 -137.61044)
			(xy 124.461209 -137.558349) (xy 124.449083 -137.503912) (xy 124.445012 -137.44829) (xy 122.079004 -137.44829)
			(xy 122.079004 -138.360404) (xy 122.275852 -138.360404) (xy 122.279923 -138.304782) (xy 122.292049 -138.250345)
			(xy 122.311972 -138.198254) (xy 122.339268 -138.149619) (xy 122.373354 -138.105476) (xy 122.413503 -138.066767)
			(xy 122.458861 -138.034316) (xy 122.508461 -138.008815) (xy 122.561245 -137.990808) (xy 122.616088 -137.980678)
			(xy 122.671822 -137.978641) (xy 122.727259 -137.984741) (xy 122.781216 -137.998847) (xy 122.832545 -138.020659)
			(xy 122.880151 -138.049713) (xy 122.923019 -138.085388) (xy 122.960236 -138.126925) (xy 122.991009 -138.173438)
			(xy 123.014681 -138.223935) (xy 123.030749 -138.277342) (xy 123.038869 -138.332518) (xy 123.039378 -138.360404)
			(xy 123.038869 -138.38829) (xy 123.036656 -138.40333) (xy 131.296156 -138.40333) (xy 131.296666 -138.375664)
			(xy 131.304662 -138.320914) (xy 131.320477 -138.267891) (xy 131.34378 -138.217706) (xy 131.374082 -138.17141)
			(xy 131.41075 -138.129973) (xy 131.453014 -138.094262) (xy 131.476242 -138.079226) (xy 131.485908 -138.072576)
			(xy 131.498358 -138.052725) (xy 131.500118 -138.041126) (xy 131.507992 -137.961116) (xy 131.508594 -137.949479)
			(xy 131.500533 -137.927644) (xy 131.492498 -137.919206) (xy 131.492244 -137.918952) (xy 131.473666 -137.900868)
			(xy 131.441085 -137.860538) (xy 131.414271 -137.816164) (xy 131.393717 -137.768566) (xy 131.379804 -137.718622)
			(xy 131.372787 -137.667253) (xy 131.372356 -137.64133) (xy 131.372906 -137.614081) (xy 131.380658 -137.560138)
			(xy 131.396007 -137.507846) (xy 131.418642 -137.458272) (xy 131.448102 -137.412423) (xy 131.483787 -137.371233)
			(xy 131.52497 -137.335541) (xy 131.570814 -137.306074) (xy 131.620384 -137.28343) (xy 131.672673 -137.268072)
			(xy 131.726615 -137.260311) (xy 131.753864 -137.259822) (xy 131.781234 -137.260304) (xy 131.835412 -137.268117)
			(xy 131.887915 -137.283602) (xy 131.937663 -137.30644) (xy 131.98363 -137.336162) (xy 132.004562 -137.353802)
			(xy 132.004816 -137.354056) (xy 132.011889 -137.359662) (xy 132.028816 -137.365896) (xy 132.037836 -137.366248)
			(xy 132.104892 -137.366248) (xy 132.11391 -137.365898) (xy 132.130827 -137.359647) (xy 132.137912 -137.354056)
			(xy 132.137912 -137.353802) (xy 132.138166 -137.353802) (xy 132.1591 -137.336166) (xy 132.205072 -137.306453)
			(xy 132.254819 -137.283617) (xy 132.30732 -137.268125) (xy 132.361495 -137.260296) (xy 132.388864 -137.259822)
			(xy 132.416117 -137.260289) (xy 132.47007 -137.268042) (xy 132.522369 -137.283395) (xy 132.571951 -137.306035)
			(xy 132.617806 -137.335502) (xy 132.659 -137.371196) (xy 132.694694 -137.412389) (xy 132.724162 -137.458243)
			(xy 132.746803 -137.507825) (xy 132.762157 -137.560124) (xy 132.769911 -137.614077) (xy 132.770372 -137.64133)
			(xy 132.769814 -137.670246) (xy 132.761095 -137.727415) (xy 132.743846 -137.782614) (xy 132.718461 -137.834576)
			(xy 132.685524 -137.882111) (xy 132.645789 -137.924129) (xy 132.623306 -137.94232) (xy 132.614501 -137.949929)
			(xy 132.604316 -137.970828) (xy 132.603748 -137.982452) (xy 132.603748 -138.062208) (xy 132.60428 -138.073841)
			(xy 132.614472 -138.094752) (xy 132.623306 -138.10234) (xy 132.64581 -138.120507) (xy 132.685544 -138.162532)
			(xy 132.71848 -138.210072) (xy 132.743865 -138.262038) (xy 132.761117 -138.31724) (xy 132.76984 -138.374413)
			(xy 132.770372 -138.40333) (xy 132.769973 -138.430585) (xy 132.762211 -138.48454) (xy 132.746849 -138.536842)
			(xy 132.724201 -138.586424) (xy 132.694726 -138.632279) (xy 132.659026 -138.673472) (xy 132.617826 -138.709166)
			(xy 132.571966 -138.738632) (xy 132.52238 -138.761272) (xy 132.470076 -138.776625) (xy 132.416119 -138.784378)
			(xy 132.388864 -138.784838) (xy 132.362548 -138.784414) (xy 132.310417 -138.777173) (xy 132.259773 -138.762847)
			(xy 132.211573 -138.741706) (xy 132.166731 -138.714152) (xy 132.126094 -138.680704) (xy 132.10794 -138.661648)
			(xy 132.100399 -138.654269) (xy 132.081134 -138.64573) (xy 132.070602 -138.645138) (xy 131.995926 -138.645138)
			(xy 131.985375 -138.645657) (xy 131.966079 -138.654198) (xy 131.958588 -138.661648) (xy 131.940441 -138.680712)
			(xy 131.899808 -138.714166) (xy 131.854966 -138.741723) (xy 131.806764 -138.76286) (xy 131.756115 -138.777176)
			(xy 131.70398 -138.7844) (xy 131.677664 -138.784838) (xy 131.650413 -138.784356) (xy 131.596467 -138.776595)
			(xy 131.544174 -138.761237) (xy 131.494599 -138.738594) (xy 131.44875 -138.709127) (xy 131.407561 -138.673435)
			(xy 131.37187 -138.632245) (xy 131.342403 -138.586396) (xy 131.319761 -138.53682) (xy 131.304404 -138.484527)
			(xy 131.296644 -138.430581) (xy 131.296156 -138.40333) (xy 123.036656 -138.40333) (xy 123.030749 -138.443466)
			(xy 123.014681 -138.496873) (xy 122.991009 -138.54737) (xy 122.960236 -138.593883) (xy 122.923019 -138.63542)
			(xy 122.880151 -138.671095) (xy 122.832545 -138.700149) (xy 122.781216 -138.721961) (xy 122.727259 -138.736067)
			(xy 122.671822 -138.742167) (xy 122.616088 -138.74013) (xy 122.561245 -138.73) (xy 122.508461 -138.711993)
			(xy 122.458861 -138.686492) (xy 122.413503 -138.654041) (xy 122.373354 -138.615332) (xy 122.339268 -138.571189)
			(xy 122.311972 -138.522554) (xy 122.292049 -138.470463) (xy 122.279923 -138.416026) (xy 122.275852 -138.360404)
			(xy 122.079004 -138.360404) (xy 122.079004 -138.824462) (xy 124.461776 -138.824462) (xy 124.465847 -138.76884)
			(xy 124.477973 -138.714403) (xy 124.497896 -138.662312) (xy 124.525192 -138.613677) (xy 124.559278 -138.569534)
			(xy 124.599427 -138.530825) (xy 124.644785 -138.498374) (xy 124.694385 -138.472873) (xy 124.747169 -138.454866)
			(xy 124.802012 -138.444736) (xy 124.857746 -138.442699) (xy 124.913183 -138.448799) (xy 124.96714 -138.462905)
			(xy 125.018469 -138.484717) (xy 125.066075 -138.513771) (xy 125.108943 -138.549446) (xy 125.14616 -138.590983)
			(xy 125.176933 -138.637496) (xy 125.200605 -138.687993) (xy 125.216673 -138.7414) (xy 125.224793 -138.796576)
			(xy 125.225302 -138.824462) (xy 125.224793 -138.852348) (xy 125.216673 -138.907524) (xy 125.200605 -138.960931)
			(xy 125.176933 -139.011428) (xy 125.14616 -139.057941) (xy 125.108943 -139.099478) (xy 125.066075 -139.135153)
			(xy 125.018469 -139.164207) (xy 124.96714 -139.186019) (xy 124.913183 -139.200125) (xy 124.857746 -139.206225)
			(xy 124.802012 -139.204188) (xy 124.747169 -139.194058) (xy 124.694385 -139.176051) (xy 124.644785 -139.15055)
			(xy 124.599427 -139.118099) (xy 124.559278 -139.07939) (xy 124.525192 -139.035247) (xy 124.497896 -138.986612)
			(xy 124.477973 -138.934521) (xy 124.465847 -138.880084) (xy 124.461776 -138.824462) (xy 122.079004 -138.824462)
			(xy 122.079004 -139.376404) (xy 122.275852 -139.376404) (xy 122.279923 -139.320782) (xy 122.292049 -139.266345)
			(xy 122.311972 -139.214254) (xy 122.339268 -139.165619) (xy 122.373354 -139.121476) (xy 122.413503 -139.082767)
			(xy 122.458861 -139.050316) (xy 122.508461 -139.024815) (xy 122.561245 -139.006808) (xy 122.616088 -138.996678)
			(xy 122.671822 -138.994641) (xy 122.727259 -139.000741) (xy 122.781216 -139.014847) (xy 122.832545 -139.036659)
			(xy 122.880151 -139.065713) (xy 122.923019 -139.101388) (xy 122.960236 -139.142925) (xy 122.991009 -139.189438)
			(xy 123.014681 -139.239935) (xy 123.030749 -139.293342) (xy 123.038869 -139.348518) (xy 123.039378 -139.376404)
			(xy 123.038869 -139.40429) (xy 123.030749 -139.459466) (xy 123.014681 -139.512873) (xy 122.991009 -139.56337)
			(xy 122.960236 -139.609883) (xy 122.923019 -139.65142) (xy 122.880151 -139.687095) (xy 122.832545 -139.716149)
			(xy 122.781216 -139.737961) (xy 122.727259 -139.752067) (xy 122.671822 -139.758167) (xy 122.616088 -139.75613)
			(xy 122.561245 -139.746) (xy 122.508461 -139.727993) (xy 122.458861 -139.702492) (xy 122.413503 -139.670041)
			(xy 122.373354 -139.631332) (xy 122.339268 -139.587189) (xy 122.311972 -139.538554) (xy 122.292049 -139.486463)
			(xy 122.279923 -139.432026) (xy 122.275852 -139.376404) (xy 122.079004 -139.376404) (xy 122.079004 -140.392404)
			(xy 124.467618 -140.392404) (xy 124.471689 -140.336782) (xy 124.483815 -140.282345) (xy 124.503738 -140.230254)
			(xy 124.531034 -140.181619) (xy 124.56512 -140.137476) (xy 124.605269 -140.098767) (xy 124.650627 -140.066316)
			(xy 124.700227 -140.040815) (xy 124.753011 -140.022808) (xy 124.807854 -140.012678) (xy 124.863588 -140.010641)
			(xy 124.919025 -140.016741) (xy 124.972982 -140.030847) (xy 125.024311 -140.052659) (xy 125.071917 -140.081713)
			(xy 125.114785 -140.117388) (xy 125.152002 -140.158925) (xy 125.182775 -140.205438) (xy 125.206447 -140.255935)
			(xy 125.222515 -140.309342) (xy 125.230635 -140.364518) (xy 125.231144 -140.392404) (xy 125.230635 -140.42029)
			(xy 125.222515 -140.475466) (xy 125.206447 -140.528873) (xy 125.182775 -140.57937) (xy 125.152002 -140.625883)
			(xy 125.114785 -140.66742) (xy 125.071917 -140.703095) (xy 125.024311 -140.732149) (xy 124.972982 -140.753961)
			(xy 124.919025 -140.768067) (xy 124.863588 -140.774167) (xy 124.807854 -140.77213) (xy 124.753011 -140.762)
			(xy 124.700227 -140.743993) (xy 124.650627 -140.718492) (xy 124.605269 -140.686041) (xy 124.56512 -140.647332)
			(xy 124.531034 -140.603189) (xy 124.503738 -140.554554) (xy 124.483815 -140.502463) (xy 124.471689 -140.448026)
			(xy 124.467618 -140.392404) (xy 122.079004 -140.392404) (xy 122.079004 -140.399262) (xy 122.079439 -140.409327)
			(xy 122.087169 -140.427915) (xy 122.09399 -140.43533) (xy 122.31243 -140.65377) (xy 122.33554 -140.677548)
			(xy 122.376872 -140.729401) (xy 122.412139 -140.785556) (xy 122.440898 -140.845306) (xy 122.462786 -140.907899)
			(xy 122.477529 -140.97255) (xy 122.484942 -141.038445) (xy 122.485055 -141.046551) (xy 126.854954 -141.046551)
			(xy 126.854954 -140.992049) (xy 126.86271 -140.9381) (xy 126.878064 -140.885805) (xy 126.900704 -140.836227)
			(xy 126.930169 -140.790375) (xy 126.965859 -140.749183) (xy 127.007048 -140.71349) (xy 127.052897 -140.684021)
			(xy 127.102473 -140.661376) (xy 127.154767 -140.646017) (xy 127.208715 -140.638256) (xy 127.235966 -140.637768)
			(xy 127.262281 -140.638202) (xy 127.314411 -140.645445) (xy 127.365054 -140.659771) (xy 127.413252 -140.68091)
			(xy 127.458095 -140.708462) (xy 127.498734 -140.741905) (xy 127.51689 -140.760958) (xy 127.524419 -140.768351)
			(xy 127.543693 -140.776882) (xy 127.554228 -140.777468) (xy 127.628904 -140.777468) (xy 127.639457 -140.776964)
			(xy 127.658752 -140.768412) (xy 127.666242 -140.760958) (xy 127.684376 -140.741881) (xy 127.725011 -140.708427)
			(xy 127.769856 -140.680872) (xy 127.818061 -140.659738) (xy 127.868712 -140.645425) (xy 127.920849 -140.638204)
			(xy 127.947166 -140.637768) (xy 127.974419 -140.638277) (xy 128.02837 -140.64603) (xy 128.080669 -140.661382)
			(xy 128.13025 -140.684021) (xy 128.176104 -140.713486) (xy 128.217299 -140.749177) (xy 128.252994 -140.790368)
			(xy 128.282463 -140.83622) (xy 128.305106 -140.8858) (xy 128.320463 -140.938097) (xy 128.328221 -140.992047)
			(xy 128.328221 -141.046553) (xy 128.320463 -141.100503) (xy 128.305106 -141.1528) (xy 128.282463 -141.20238)
			(xy 128.252994 -141.248232) (xy 128.217299 -141.289423) (xy 128.176104 -141.325114) (xy 128.13025 -141.354579)
			(xy 128.080669 -141.377218) (xy 128.02837 -141.39257) (xy 127.974419 -141.400323) (xy 127.947166 -141.400784)
			(xy 127.920851 -141.400344) (xy 127.868721 -141.393105) (xy 127.818078 -141.37878) (xy 127.769879 -141.357643)
			(xy 127.725036 -141.330092) (xy 127.684398 -141.296648) (xy 127.666242 -141.277594) (xy 127.658707 -141.270208)
			(xy 127.639437 -141.261675) (xy 127.628904 -141.261084) (xy 127.554228 -141.261084) (xy 127.543679 -141.26162)
			(xy 127.524384 -141.270151) (xy 127.51689 -141.277594) (xy 127.498731 -141.296646) (xy 127.458102 -141.330104)
			(xy 127.413263 -141.357664) (xy 127.365063 -141.378803) (xy 127.314416 -141.39312) (xy 127.262282 -141.400345)
			(xy 127.235966 -141.400784) (xy 127.208715 -141.400344) (xy 127.154767 -141.392583) (xy 127.102473 -141.377224)
			(xy 127.052897 -141.354579) (xy 127.007048 -141.32511) (xy 126.965859 -141.289417) (xy 126.930169 -141.248225)
			(xy 126.900704 -141.202373) (xy 126.878064 -141.152795) (xy 126.86271 -141.1005) (xy 126.854954 -141.046551)
			(xy 122.485055 -141.046551) (xy 122.485404 -141.0716) (xy 122.485404 -143.078551) (xy 126.854954 -143.078551)
			(xy 126.854954 -143.024049) (xy 126.86271 -142.9701) (xy 126.878064 -142.917805) (xy 126.900704 -142.868227)
			(xy 126.930169 -142.822375) (xy 126.965859 -142.781183) (xy 127.007048 -142.74549) (xy 127.052897 -142.716021)
			(xy 127.102473 -142.693376) (xy 127.154767 -142.678017) (xy 127.208715 -142.670256) (xy 127.235966 -142.669768)
			(xy 127.262281 -142.670202) (xy 127.314411 -142.677445) (xy 127.365054 -142.691771) (xy 127.413252 -142.71291)
			(xy 127.458095 -142.740462) (xy 127.498734 -142.773905) (xy 127.51689 -142.792958) (xy 127.524419 -142.800351)
			(xy 127.543693 -142.808882) (xy 127.554228 -142.809468) (xy 127.628904 -142.809468) (xy 127.639457 -142.808964)
			(xy 127.658752 -142.800412) (xy 127.666242 -142.792958) (xy 127.684376 -142.773881) (xy 127.725011 -142.740427)
			(xy 127.769856 -142.712872) (xy 127.818061 -142.691738) (xy 127.868712 -142.677425) (xy 127.920849 -142.670204)
			(xy 127.947166 -142.669768) (xy 127.974419 -142.670277) (xy 128.02837 -142.67803) (xy 128.080669 -142.693382)
			(xy 128.13025 -142.716021) (xy 128.176104 -142.745486) (xy 128.217299 -142.781177) (xy 128.252994 -142.822368)
			(xy 128.282463 -142.86822) (xy 128.305106 -142.9178) (xy 128.320463 -142.970097) (xy 128.328221 -143.024047)
			(xy 128.328221 -143.078553) (xy 128.320463 -143.132503) (xy 128.305106 -143.1848) (xy 128.282463 -143.23438)
			(xy 128.252994 -143.280232) (xy 128.217299 -143.321423) (xy 128.176104 -143.357114) (xy 128.13025 -143.386579)
			(xy 128.080669 -143.409218) (xy 128.02837 -143.42457) (xy 127.974419 -143.432323) (xy 127.947166 -143.432784)
			(xy 127.920851 -143.432344) (xy 127.868721 -143.425105) (xy 127.818078 -143.41078) (xy 127.769879 -143.389643)
			(xy 127.725036 -143.362092) (xy 127.684398 -143.328648) (xy 127.666242 -143.309594) (xy 127.658707 -143.302208)
			(xy 127.639437 -143.293675) (xy 127.628904 -143.293084) (xy 127.554228 -143.293084) (xy 127.543679 -143.29362)
			(xy 127.524384 -143.302151) (xy 127.51689 -143.309594) (xy 127.498731 -143.328646) (xy 127.458102 -143.362104)
			(xy 127.413263 -143.389664) (xy 127.365063 -143.410803) (xy 127.314416 -143.42512) (xy 127.262282 -143.432345)
			(xy 127.235966 -143.432784) (xy 127.208715 -143.432344) (xy 127.154767 -143.424583) (xy 127.102473 -143.409224)
			(xy 127.052897 -143.386579) (xy 127.007048 -143.35711) (xy 126.965859 -143.321417) (xy 126.930169 -143.280225)
			(xy 126.900704 -143.234373) (xy 126.878064 -143.184795) (xy 126.86271 -143.1325) (xy 126.854954 -143.078551)
			(xy 122.485404 -143.078551) (xy 122.485404 -145.110551) (xy 126.854954 -145.110551) (xy 126.854954 -145.056049)
			(xy 126.86271 -145.0021) (xy 126.878064 -144.949805) (xy 126.900704 -144.900227) (xy 126.930169 -144.854375)
			(xy 126.965859 -144.813183) (xy 127.007048 -144.77749) (xy 127.052897 -144.748021) (xy 127.102473 -144.725376)
			(xy 127.154767 -144.710017) (xy 127.208715 -144.702256) (xy 127.235966 -144.701768) (xy 127.262281 -144.702202)
			(xy 127.314411 -144.709445) (xy 127.365054 -144.723771) (xy 127.413252 -144.74491) (xy 127.458095 -144.772462)
			(xy 127.498734 -144.805905) (xy 127.51689 -144.824958) (xy 127.524419 -144.832351) (xy 127.543693 -144.840882)
			(xy 127.554228 -144.841468) (xy 127.628904 -144.841468) (xy 127.639457 -144.840964) (xy 127.658752 -144.832412)
			(xy 127.666242 -144.824958) (xy 127.684376 -144.805881) (xy 127.725011 -144.772427) (xy 127.769856 -144.744872)
			(xy 127.818061 -144.723738) (xy 127.868712 -144.709425) (xy 127.920849 -144.702204) (xy 127.947166 -144.701768)
			(xy 127.974419 -144.702277) (xy 128.02837 -144.71003) (xy 128.080669 -144.725382) (xy 128.13025 -144.748021)
			(xy 128.176104 -144.777486) (xy 128.217299 -144.813177) (xy 128.252994 -144.854368) (xy 128.282463 -144.90022)
			(xy 128.305106 -144.9498) (xy 128.306411 -144.954244) (xy 134.038848 -144.954244) (xy 134.039419 -144.926996)
			(xy 134.047168 -144.873054) (xy 134.062516 -144.820763) (xy 134.085149 -144.771189) (xy 134.114606 -144.725341)
			(xy 134.150289 -144.684151) (xy 134.19147 -144.648459) (xy 134.237312 -144.618991) (xy 134.286881 -144.596347)
			(xy 134.339167 -144.580987) (xy 134.393108 -144.573225) (xy 134.420356 -144.572736) (xy 134.44913 -144.573257)
			(xy 134.506025 -144.581907) (xy 134.560976 -144.599004) (xy 134.612736 -144.624159) (xy 134.660132 -144.656801)
			(xy 134.681468 -144.676114) (xy 134.689342 -144.68348) (xy 134.709154 -144.690592) (xy 134.80542 -144.683226)
			(xy 134.824216 -144.67332) (xy 134.83082 -144.664938) (xy 134.849055 -144.642762) (xy 134.890987 -144.603551)
			(xy 134.938321 -144.571063) (xy 134.989987 -144.546033) (xy 135.04482 -144.529025) (xy 135.101581 -144.520423)
			(xy 135.130286 -144.519904) (xy 135.157539 -144.520368) (xy 135.211491 -144.528124) (xy 135.263789 -144.543479)
			(xy 135.31337 -144.56612) (xy 135.359224 -144.595588) (xy 135.400417 -144.631282) (xy 135.436111 -144.672475)
			(xy 135.465579 -144.718328) (xy 135.488221 -144.767909) (xy 135.503576 -144.820207) (xy 135.511331 -144.874159)
			(xy 135.511794 -144.901412) (xy 135.511345 -144.928315) (xy 135.503772 -144.981586) (xy 135.48879 -145.033265)
			(xy 135.466698 -145.082327) (xy 135.437933 -145.127799) (xy 135.403067 -145.16878) (xy 135.362789 -145.204457)
			(xy 135.340598 -145.219674) (xy 135.329676 -145.226786) (xy 135.317738 -145.249646) (xy 135.31977 -145.361914)
			(xy 135.332724 -145.384266) (xy 135.3439 -145.391124) (xy 135.367501 -145.406046) (xy 135.410453 -145.441725)
			(xy 135.447747 -145.483283) (xy 135.478584 -145.529833) (xy 135.502308 -145.58038) (xy 135.51841 -145.633846)
			(xy 135.526548 -145.689087) (xy 135.527034 -145.717006) (xy 135.526579 -145.744) (xy 135.518972 -145.797448)
			(xy 135.50391 -145.849292) (xy 135.481695 -145.898496) (xy 135.452769 -145.94408) (xy 135.435594 -145.96491)
			(xy 135.428482 -145.973038) (xy 135.422386 -145.993612) (xy 135.433308 -146.078956) (xy 135.435097 -146.089497)
			(xy 135.446141 -146.107781) (xy 135.454644 -146.114262) (xy 135.47585 -146.129648) (xy 135.514304 -146.16523)
			(xy 135.547524 -146.205741) (xy 135.574886 -146.250418) (xy 135.595874 -146.298421) (xy 135.610092 -146.348845)
			(xy 135.617273 -146.400741) (xy 135.617712 -146.426936) (xy 135.617226 -146.454187) (xy 135.60947 -146.508135)
			(xy 135.594115 -146.56043) (xy 135.571473 -146.610007) (xy 135.542007 -146.655857) (xy 135.506316 -146.697048)
			(xy 135.465125 -146.732739) (xy 135.419275 -146.762205) (xy 135.369698 -146.784847) (xy 135.317403 -146.800202)
			(xy 135.263455 -146.807958) (xy 135.208953 -146.807958) (xy 135.155005 -146.800202) (xy 135.10271 -146.784847)
			(xy 135.053133 -146.762205) (xy 135.007283 -146.732739) (xy 134.966092 -146.697048) (xy 134.930401 -146.655857)
			(xy 134.900935 -146.610007) (xy 134.878293 -146.56043) (xy 134.862938 -146.508135) (xy 134.855182 -146.454187)
			(xy 134.854696 -146.426936) (xy 134.855192 -146.399944) (xy 134.862792 -146.346498) (xy 134.877845 -146.294656)
			(xy 134.90005 -146.24545) (xy 134.928966 -146.199864) (xy 134.946136 -146.179032) (xy 134.953248 -146.170904)
			(xy 134.959344 -146.15033) (xy 134.948422 -146.064986) (xy 134.94665 -146.054441) (xy 134.935593 -146.036159)
			(xy 134.927086 -146.02968) (xy 134.902785 -146.012068) (xy 134.859526 -145.970472) (xy 134.84098 -145.946876)
			(xy 134.835138 -145.939002) (xy 134.817612 -145.928588) (xy 134.727188 -145.91538) (xy 134.707884 -145.920206)
			(xy 134.70001 -145.926048) (xy 134.699756 -145.926048) (xy 134.675012 -145.943552) (xy 134.62116 -145.971355)
			(xy 134.563588 -145.990291) (xy 134.503745 -145.999883) (xy 134.473442 -146.00047) (xy 134.446188 -146.000006)
			(xy 134.392236 -145.992253) (xy 134.339935 -145.976901) (xy 134.290353 -145.95426) (xy 134.244498 -145.924793)
			(xy 134.203304 -145.889099) (xy 134.167609 -145.847905) (xy 134.138142 -145.802051) (xy 134.115501 -145.752468)
			(xy 134.100148 -145.700168) (xy 134.092395 -145.646216) (xy 134.091934 -145.618962) (xy 134.092369 -145.592928)
			(xy 134.09946 -145.541345) (xy 134.113493 -145.491203) (xy 134.134206 -145.443432) (xy 134.161217 -145.398918)
			(xy 134.177278 -145.378424) (xy 134.183019 -145.370666) (xy 134.18876 -145.352256) (xy 134.188454 -145.34261)
			(xy 134.182104 -145.262854) (xy 134.173468 -145.245074) (xy 134.166102 -145.238724) (xy 134.146463 -145.220535)
			(xy 134.111937 -145.179632) (xy 134.083465 -145.134305) (xy 134.061605 -145.085444) (xy 134.046787 -145.034009)
			(xy 134.039302 -144.981008) (xy 134.038848 -144.954244) (xy 128.306411 -144.954244) (xy 128.320463 -145.002097)
			(xy 128.328221 -145.056047) (xy 128.328221 -145.110553) (xy 128.320463 -145.164503) (xy 128.305106 -145.2168)
			(xy 128.282463 -145.26638) (xy 128.252994 -145.312232) (xy 128.217299 -145.353423) (xy 128.176104 -145.389114)
			(xy 128.13025 -145.418579) (xy 128.080669 -145.441218) (xy 128.02837 -145.45657) (xy 127.974419 -145.464323)
			(xy 127.947166 -145.464784) (xy 127.920851 -145.464344) (xy 127.868721 -145.457105) (xy 127.818078 -145.44278)
			(xy 127.769879 -145.421643) (xy 127.725036 -145.394092) (xy 127.684398 -145.360648) (xy 127.666242 -145.341594)
			(xy 127.658707 -145.334208) (xy 127.639437 -145.325675) (xy 127.628904 -145.325084) (xy 127.554228 -145.325084)
			(xy 127.543679 -145.32562) (xy 127.524384 -145.334151) (xy 127.51689 -145.341594) (xy 127.498731 -145.360646)
			(xy 127.458102 -145.394104) (xy 127.413263 -145.421664) (xy 127.365063 -145.442803) (xy 127.314416 -145.45712)
			(xy 127.262282 -145.464345) (xy 127.235966 -145.464784) (xy 127.208715 -145.464344) (xy 127.154767 -145.456583)
			(xy 127.102473 -145.441224) (xy 127.052897 -145.418579) (xy 127.007048 -145.38911) (xy 126.965859 -145.353417)
			(xy 126.930169 -145.312225) (xy 126.900704 -145.266373) (xy 126.878064 -145.216795) (xy 126.86271 -145.1645)
			(xy 126.854954 -145.110551) (xy 122.485404 -145.110551) (xy 122.485404 -146.91487) (xy 135.716008 -146.91487)
			(xy 135.720079 -146.859248) (xy 135.732205 -146.804811) (xy 135.752128 -146.75272) (xy 135.779424 -146.704085)
			(xy 135.81351 -146.659942) (xy 135.853659 -146.621233) (xy 135.899017 -146.588782) (xy 135.948617 -146.563281)
			(xy 136.001401 -146.545274) (xy 136.056244 -146.535144) (xy 136.111978 -146.533107) (xy 136.167415 -146.539207)
			(xy 136.221372 -146.553313) (xy 136.272701 -146.575125) (xy 136.320307 -146.604179) (xy 136.363175 -146.639854)
			(xy 136.400392 -146.681391) (xy 136.431165 -146.727904) (xy 136.454837 -146.778401) (xy 136.470905 -146.831808)
			(xy 136.479025 -146.886984) (xy 136.479534 -146.91487) (xy 136.479025 -146.942756) (xy 136.470905 -146.997932)
			(xy 136.454837 -147.051339) (xy 136.449631 -147.062444) (xy 137.094212 -147.062444) (xy 137.098283 -147.006822)
			(xy 137.110409 -146.952385) (xy 137.130332 -146.900294) (xy 137.157628 -146.851659) (xy 137.191714 -146.807516)
			(xy 137.231863 -146.768807) (xy 137.277221 -146.736356) (xy 137.326821 -146.710855) (xy 137.379605 -146.692848)
			(xy 137.434448 -146.682718) (xy 137.490182 -146.680681) (xy 137.545619 -146.686781) (xy 137.599576 -146.700887)
			(xy 137.650905 -146.722699) (xy 137.698511 -146.751753) (xy 137.741379 -146.787428) (xy 137.778596 -146.828965)
			(xy 137.809369 -146.875478) (xy 137.833041 -146.925975) (xy 137.849109 -146.979382) (xy 137.857229 -147.034558)
			(xy 137.857738 -147.062444) (xy 137.857229 -147.09033) (xy 137.849109 -147.145506) (xy 137.833041 -147.198913)
			(xy 137.809369 -147.24941) (xy 137.778596 -147.295923) (xy 137.741379 -147.33746) (xy 137.698511 -147.373135)
			(xy 137.650905 -147.402189) (xy 137.599576 -147.424001) (xy 137.545619 -147.438107) (xy 137.490182 -147.444207)
			(xy 137.434448 -147.44217) (xy 137.379605 -147.43204) (xy 137.326821 -147.414033) (xy 137.277221 -147.388532)
			(xy 137.231863 -147.356081) (xy 137.191714 -147.317372) (xy 137.157628 -147.273229) (xy 137.130332 -147.224594)
			(xy 137.110409 -147.172503) (xy 137.098283 -147.118066) (xy 137.094212 -147.062444) (xy 136.449631 -147.062444)
			(xy 136.431165 -147.101836) (xy 136.400392 -147.148349) (xy 136.363175 -147.189886) (xy 136.320307 -147.225561)
			(xy 136.272701 -147.254615) (xy 136.221372 -147.276427) (xy 136.167415 -147.290533) (xy 136.111978 -147.296633)
			(xy 136.056244 -147.294596) (xy 136.001401 -147.284466) (xy 135.948617 -147.266459) (xy 135.899017 -147.240958)
			(xy 135.853659 -147.208507) (xy 135.81351 -147.169798) (xy 135.779424 -147.125655) (xy 135.752128 -147.07702)
			(xy 135.732205 -147.024929) (xy 135.720079 -146.970492) (xy 135.716008 -146.91487) (xy 122.485404 -146.91487)
			(xy 122.485404 -147.657656) (xy 127.250343 -147.657656) (xy 127.250343 -147.603144) (xy 127.258101 -147.549188)
			(xy 127.27346 -147.496885) (xy 127.296107 -147.4473) (xy 127.32558 -147.401443) (xy 127.361279 -147.360248)
			(xy 127.402478 -147.324553) (xy 127.448339 -147.295085) (xy 127.497926 -147.272445) (xy 127.550231 -147.257092)
			(xy 127.604188 -147.24934) (xy 127.631444 -147.24888) (xy 127.657759 -147.249324) (xy 127.709888 -147.256565)
			(xy 127.760531 -147.270889) (xy 127.80873 -147.292026) (xy 127.853573 -147.319576) (xy 127.894212 -147.353017)
			(xy 127.912368 -147.37207) (xy 127.919904 -147.379455) (xy 127.939173 -147.38799) (xy 127.949706 -147.38858)
			(xy 128.024382 -147.38858) (xy 128.034933 -147.388061) (xy 128.054229 -147.379519) (xy 128.06172 -147.37207)
			(xy 128.08154 -147.351282) (xy 128.126312 -147.315307) (xy 128.17597 -147.286447) (xy 128.229392 -147.265354)
			(xy 128.285371 -147.252505) (xy 128.342644 -147.24819) (xy 128.399917 -147.252505) (xy 128.455896 -147.265354)
			(xy 128.509318 -147.286447) (xy 128.558976 -147.315307) (xy 128.603748 -147.351282) (xy 128.623568 -147.37207)
			(xy 128.631104 -147.379455) (xy 128.650373 -147.38799) (xy 128.660906 -147.38858) (xy 128.735582 -147.38858)
			(xy 128.746133 -147.388061) (xy 128.765429 -147.379519) (xy 128.77292 -147.37207) (xy 128.791067 -147.353006)
			(xy 128.831699 -147.319551) (xy 128.876541 -147.291994) (xy 128.924744 -147.270857) (xy 128.975393 -147.256541)
			(xy 129.027527 -147.249318) (xy 129.053844 -147.24888) (xy 129.081092 -147.249393) (xy 129.135034 -147.257155)
			(xy 129.187321 -147.272513) (xy 129.236891 -147.295156) (xy 129.282735 -147.324622) (xy 129.323918 -147.360313)
			(xy 129.359604 -147.401501) (xy 129.389065 -147.447347) (xy 129.411702 -147.49692) (xy 129.427055 -147.54921)
			(xy 129.43481 -147.603152) (xy 129.43481 -147.657648) (xy 129.427055 -147.71159) (xy 129.411702 -147.76388)
			(xy 129.389065 -147.813453) (xy 129.359604 -147.859299) (xy 129.323918 -147.900487) (xy 129.282735 -147.936178)
			(xy 129.236891 -147.965644) (xy 129.187321 -147.988287) (xy 129.135034 -148.003645) (xy 129.081092 -148.011407)
			(xy 129.053844 -148.011896) (xy 129.027529 -148.011467) (xy 128.975398 -148.004225) (xy 128.924755 -147.989898)
			(xy 128.876556 -147.968758) (xy 128.831714 -147.941205) (xy 128.791076 -147.90776) (xy 128.77292 -147.888706)
			(xy 128.765392 -147.881312) (xy 128.746117 -147.872783) (xy 128.735582 -147.872196) (xy 128.660906 -147.872196)
			(xy 128.650355 -147.872716) (xy 128.63106 -147.881258) (xy 128.623568 -147.888706) (xy 128.603748 -147.909494)
			(xy 128.558976 -147.945469) (xy 128.509318 -147.974329) (xy 128.455896 -147.995422) (xy 128.399917 -148.008271)
			(xy 128.342644 -148.012586) (xy 128.285371 -148.008271) (xy 128.229392 -147.995422) (xy 128.17597 -147.974329)
			(xy 128.126312 -147.945469) (xy 128.08154 -147.909494) (xy 128.06172 -147.888706) (xy 128.054192 -147.881312)
			(xy 128.034917 -147.872783) (xy 128.024382 -147.872196) (xy 127.949706 -147.872196) (xy 127.939155 -147.872716)
			(xy 127.91986 -147.881258) (xy 127.912368 -147.888706) (xy 127.894222 -147.907771) (xy 127.85359 -147.941227)
			(xy 127.808748 -147.968785) (xy 127.760545 -147.989922) (xy 127.709896 -148.004237) (xy 127.657761 -148.011459)
			(xy 127.631444 -148.011896) (xy 127.604188 -148.01146) (xy 127.550231 -148.003708) (xy 127.497926 -147.988355)
			(xy 127.448339 -147.965715) (xy 127.402478 -147.936247) (xy 127.361279 -147.900552) (xy 127.32558 -147.859357)
			(xy 127.296107 -147.8135) (xy 127.27346 -147.763915) (xy 127.258101 -147.711612) (xy 127.250343 -147.657656)
			(xy 122.485404 -147.657656) (xy 122.485404 -148.017738) (xy 132.077458 -148.017738) (xy 132.081529 -147.962116)
			(xy 132.093655 -147.907679) (xy 132.113578 -147.855588) (xy 132.140874 -147.806953) (xy 132.17496 -147.76281)
			(xy 132.215109 -147.724101) (xy 132.260467 -147.69165) (xy 132.310067 -147.666149) (xy 132.362851 -147.648142)
			(xy 132.417694 -147.638012) (xy 132.473428 -147.635975) (xy 132.528865 -147.642075) (xy 132.582822 -147.656181)
			(xy 132.634151 -147.677993) (xy 132.681757 -147.707047) (xy 132.724625 -147.742722) (xy 132.761842 -147.784259)
			(xy 132.792615 -147.830772) (xy 132.816287 -147.881269) (xy 132.832355 -147.934676) (xy 132.840475 -147.989852)
			(xy 132.840984 -148.017738) (xy 132.840475 -148.045624) (xy 132.832355 -148.1008) (xy 132.816287 -148.154207)
			(xy 132.792615 -148.204704) (xy 132.761842 -148.251217) (xy 132.724625 -148.292754) (xy 132.681757 -148.328429)
			(xy 132.634151 -148.357483) (xy 132.582822 -148.379295) (xy 132.528865 -148.393401) (xy 132.473428 -148.399501)
			(xy 132.417694 -148.397464) (xy 132.362851 -148.387334) (xy 132.310067 -148.369327) (xy 132.260467 -148.343826)
			(xy 132.215109 -148.311375) (xy 132.17496 -148.272666) (xy 132.140874 -148.228523) (xy 132.113578 -148.179888)
			(xy 132.093655 -148.127797) (xy 132.081529 -148.07336) (xy 132.077458 -148.017738) (xy 122.485404 -148.017738)
			(xy 122.485404 -150.195854) (xy 127.250365 -150.195854) (xy 127.250365 -150.141346) (xy 127.258123 -150.087392)
			(xy 127.273481 -150.035093) (xy 127.296126 -149.985511) (xy 127.325598 -149.939657) (xy 127.361295 -149.898464)
			(xy 127.402492 -149.862771) (xy 127.448349 -149.833305) (xy 127.497934 -149.810666) (xy 127.550236 -149.795314)
			(xy 127.60419 -149.787562) (xy 127.631444 -149.787102) (xy 127.657759 -149.787539) (xy 127.709889 -149.79478)
			(xy 127.760532 -149.809105) (xy 127.808731 -149.830243) (xy 127.853574 -149.857795) (xy 127.894212 -149.891238)
			(xy 127.912368 -149.910292) (xy 127.919901 -149.91768) (xy 127.939172 -149.926212) (xy 127.949706 -149.926802)
			(xy 128.024382 -149.926802) (xy 128.034932 -149.926276) (xy 128.054227 -149.917738) (xy 128.06172 -149.910292)
			(xy 128.08154 -149.889504) (xy 128.126312 -149.853529) (xy 128.17597 -149.824669) (xy 128.229392 -149.803576)
			(xy 128.285371 -149.790727) (xy 128.342644 -149.786412) (xy 128.399917 -149.790727) (xy 128.455896 -149.803576)
			(xy 128.509318 -149.824669) (xy 128.558976 -149.853529) (xy 128.603748 -149.889504) (xy 128.623568 -149.910292)
			(xy 128.631101 -149.91768) (xy 128.650372 -149.926212) (xy 128.660906 -149.926802) (xy 128.735582 -149.926802)
			(xy 128.746132 -149.926276) (xy 128.765427 -149.917738) (xy 128.77292 -149.910292) (xy 128.791071 -149.891232)
			(xy 128.831702 -149.857776) (xy 128.876543 -149.830218) (xy 128.924745 -149.80908) (xy 128.975393 -149.794764)
			(xy 129.027528 -149.78754) (xy 129.053844 -149.787102) (xy 129.081094 -149.787571) (xy 129.135038 -149.795333)
			(xy 129.187329 -149.810692) (xy 129.236902 -149.833336) (xy 129.282748 -149.862804) (xy 129.323934 -149.898497)
			(xy 129.359622 -149.939687) (xy 129.389085 -149.985537) (xy 129.411723 -150.035112) (xy 129.420045 -150.063454)
			(xy 131.938012 -150.063454) (xy 131.942083 -150.007832) (xy 131.954209 -149.953395) (xy 131.974132 -149.901304)
			(xy 132.001428 -149.852669) (xy 132.035514 -149.808526) (xy 132.075663 -149.769817) (xy 132.121021 -149.737366)
			(xy 132.170621 -149.711865) (xy 132.223405 -149.693858) (xy 132.278248 -149.683728) (xy 132.333982 -149.681691)
			(xy 132.389419 -149.687791) (xy 132.443376 -149.701897) (xy 132.494705 -149.723709) (xy 132.542311 -149.752763)
			(xy 132.585179 -149.788438) (xy 132.622396 -149.829975) (xy 132.653169 -149.876488) (xy 132.676841 -149.926985)
			(xy 132.692909 -149.980392) (xy 132.701029 -150.035568) (xy 132.701538 -150.063454) (xy 132.701029 -150.09134)
			(xy 132.692909 -150.146516) (xy 132.676841 -150.199923) (xy 132.653169 -150.25042) (xy 132.622396 -150.296933)
			(xy 132.585179 -150.33847) (xy 132.542311 -150.374145) (xy 132.494705 -150.403199) (xy 132.443376 -150.425011)
			(xy 132.389419 -150.439117) (xy 132.333982 -150.445217) (xy 132.278248 -150.44318) (xy 132.223405 -150.43305)
			(xy 132.170621 -150.415043) (xy 132.121021 -150.389542) (xy 132.075663 -150.357091) (xy 132.035514 -150.318382)
			(xy 132.001428 -150.274239) (xy 131.974132 -150.225604) (xy 131.954209 -150.173513) (xy 131.942083 -150.119076)
			(xy 131.938012 -150.063454) (xy 129.420045 -150.063454) (xy 129.427077 -150.087405) (xy 129.434832 -150.14135)
			(xy 129.434832 -150.19585) (xy 129.427077 -150.249795) (xy 129.411723 -150.302088) (xy 129.389085 -150.351663)
			(xy 129.359622 -150.397513) (xy 129.323934 -150.438703) (xy 129.282748 -150.474396) (xy 129.236902 -150.503864)
			(xy 129.187329 -150.526508) (xy 129.135038 -150.541867) (xy 129.081094 -150.549629) (xy 129.053844 -150.550118)
			(xy 129.027529 -150.549682) (xy 128.975399 -150.54244) (xy 128.924756 -150.528114) (xy 128.876558 -150.506976)
			(xy 128.831715 -150.479425) (xy 128.791076 -150.445982) (xy 128.77292 -150.426928) (xy 128.765389 -150.419537)
			(xy 128.746116 -150.411006) (xy 128.735582 -150.410418) (xy 128.660906 -150.410418) (xy 128.650354 -150.410932)
			(xy 128.631059 -150.419477) (xy 128.623568 -150.426928) (xy 128.603748 -150.447716) (xy 128.558976 -150.483691)
			(xy 128.509318 -150.512551) (xy 128.455896 -150.533644) (xy 128.399917 -150.546493) (xy 128.342644 -150.550808)
			(xy 128.285371 -150.546493) (xy 128.229392 -150.533644) (xy 128.17597 -150.512551) (xy 128.126312 -150.483691)
			(xy 128.08154 -150.447716) (xy 128.06172 -150.426928) (xy 128.054189 -150.419537) (xy 128.034916 -150.411006)
			(xy 128.024382 -150.410418) (xy 127.949706 -150.410418) (xy 127.939154 -150.410932) (xy 127.919859 -150.419477)
			(xy 127.912368 -150.426928) (xy 127.894226 -150.445997) (xy 127.853593 -150.479452) (xy 127.80875 -150.507009)
			(xy 127.760546 -150.528145) (xy 127.709897 -150.542459) (xy 127.657761 -150.549681) (xy 127.631444 -150.550118)
			(xy 127.60419 -150.549638) (xy 127.550236 -150.541886) (xy 127.497934 -150.526534) (xy 127.448349 -150.503895)
			(xy 127.402492 -150.474429) (xy 127.361295 -150.438736) (xy 127.325598 -150.397543) (xy 127.296126 -150.351689)
			(xy 127.273481 -150.302107) (xy 127.258123 -150.249808) (xy 127.250365 -150.195854) (xy 122.485404 -150.195854)
			(xy 122.485404 -151.67102) (xy 131.893562 -151.67102) (xy 131.897633 -151.615398) (xy 131.909759 -151.560961)
			(xy 131.929682 -151.50887) (xy 131.956978 -151.460235) (xy 131.991064 -151.416092) (xy 132.031213 -151.377383)
			(xy 132.076571 -151.344932) (xy 132.126171 -151.319431) (xy 132.178955 -151.301424) (xy 132.233798 -151.291294)
			(xy 132.289532 -151.289257) (xy 132.344969 -151.295357) (xy 132.398926 -151.309463) (xy 132.450255 -151.331275)
			(xy 132.497861 -151.360329) (xy 132.540729 -151.396004) (xy 132.577946 -151.437541) (xy 132.608719 -151.484054)
			(xy 132.632391 -151.534551) (xy 132.648459 -151.587958) (xy 132.656579 -151.643134) (xy 132.657088 -151.67102)
			(xy 132.656615 -151.696928) (xy 132.909562 -151.696928) (xy 132.913633 -151.641306) (xy 132.925759 -151.586869)
			(xy 132.945682 -151.534778) (xy 132.972978 -151.486143) (xy 133.007064 -151.442) (xy 133.047213 -151.403291)
			(xy 133.092571 -151.37084) (xy 133.142171 -151.345339) (xy 133.194955 -151.327332) (xy 133.249798 -151.317202)
			(xy 133.305532 -151.315165) (xy 133.360969 -151.321265) (xy 133.414926 -151.335371) (xy 133.466255 -151.357183)
			(xy 133.513861 -151.386237) (xy 133.538337 -151.406606) (xy 134.136636 -151.406606) (xy 134.140707 -151.350984)
			(xy 134.152833 -151.296547) (xy 134.172756 -151.244456) (xy 134.200052 -151.195821) (xy 134.234138 -151.151678)
			(xy 134.274287 -151.112969) (xy 134.319645 -151.080518) (xy 134.369245 -151.055017) (xy 134.422029 -151.03701)
			(xy 134.476872 -151.02688) (xy 134.532606 -151.024843) (xy 134.588043 -151.030943) (xy 134.642 -151.045049)
			(xy 134.693329 -151.066861) (xy 134.740935 -151.095915) (xy 134.783803 -151.13159) (xy 134.82102 -151.173127)
			(xy 134.851793 -151.21964) (xy 134.875465 -151.270137) (xy 134.891533 -151.323544) (xy 134.899653 -151.37872)
			(xy 134.900162 -151.406606) (xy 134.899653 -151.434492) (xy 134.891533 -151.489668) (xy 134.875465 -151.543075)
			(xy 134.856923 -151.582628) (xy 135.462262 -151.582628) (xy 135.466333 -151.527006) (xy 135.478459 -151.472569)
			(xy 135.498382 -151.420478) (xy 135.525678 -151.371843) (xy 135.559764 -151.3277) (xy 135.599913 -151.288991)
			(xy 135.645271 -151.25654) (xy 135.694871 -151.231039) (xy 135.747655 -151.213032) (xy 135.802498 -151.202902)
			(xy 135.858232 -151.200865) (xy 135.913669 -151.206965) (xy 135.967626 -151.221071) (xy 136.018955 -151.242883)
			(xy 136.066561 -151.271937) (xy 136.109429 -151.307612) (xy 136.146646 -151.349149) (xy 136.177419 -151.395662)
			(xy 136.201091 -151.446159) (xy 136.217159 -151.499566) (xy 136.225279 -151.554742) (xy 136.225542 -151.569166)
			(xy 136.973562 -151.569166) (xy 136.977633 -151.513544) (xy 136.989759 -151.459107) (xy 137.009682 -151.407016)
			(xy 137.036978 -151.358381) (xy 137.071064 -151.314238) (xy 137.111213 -151.275529) (xy 137.156571 -151.243078)
			(xy 137.206171 -151.217577) (xy 137.258955 -151.19957) (xy 137.313798 -151.18944) (xy 137.369532 -151.187403)
			(xy 137.424969 -151.193503) (xy 137.478926 -151.207609) (xy 137.530255 -151.229421) (xy 137.577861 -151.258475)
			(xy 137.620729 -151.29415) (xy 137.657946 -151.335687) (xy 137.688719 -151.3822) (xy 137.712391 -151.432697)
			(xy 137.728459 -151.486104) (xy 137.736579 -151.54128) (xy 137.737088 -151.569166) (xy 137.736579 -151.597052)
			(xy 137.728459 -151.652228) (xy 137.712391 -151.705635) (xy 137.688719 -151.756132) (xy 137.657946 -151.802645)
			(xy 137.620729 -151.844182) (xy 137.577861 -151.879857) (xy 137.530255 -151.908911) (xy 137.478926 -151.930723)
			(xy 137.424969 -151.944829) (xy 137.369532 -151.950929) (xy 137.313798 -151.948892) (xy 137.258955 -151.938762)
			(xy 137.206171 -151.920755) (xy 137.156571 -151.895254) (xy 137.111213 -151.862803) (xy 137.071064 -151.824094)
			(xy 137.036978 -151.779951) (xy 137.009682 -151.731316) (xy 136.989759 -151.679225) (xy 136.977633 -151.624788)
			(xy 136.973562 -151.569166) (xy 136.225542 -151.569166) (xy 136.225788 -151.582628) (xy 136.225279 -151.610514)
			(xy 136.217159 -151.66569) (xy 136.201091 -151.719097) (xy 136.177419 -151.769594) (xy 136.146646 -151.816107)
			(xy 136.109429 -151.857644) (xy 136.066561 -151.893319) (xy 136.018955 -151.922373) (xy 135.967626 -151.944185)
			(xy 135.913669 -151.958291) (xy 135.858232 -151.964391) (xy 135.802498 -151.962354) (xy 135.747655 -151.952224)
			(xy 135.694871 -151.934217) (xy 135.645271 -151.908716) (xy 135.599913 -151.876265) (xy 135.559764 -151.837556)
			(xy 135.525678 -151.793413) (xy 135.498382 -151.744778) (xy 135.478459 -151.692687) (xy 135.466333 -151.63825)
			(xy 135.462262 -151.582628) (xy 134.856923 -151.582628) (xy 134.851793 -151.593572) (xy 134.82102 -151.640085)
			(xy 134.783803 -151.681622) (xy 134.740935 -151.717297) (xy 134.693329 -151.746351) (xy 134.642 -151.768163)
			(xy 134.588043 -151.782269) (xy 134.532606 -151.788369) (xy 134.476872 -151.786332) (xy 134.422029 -151.776202)
			(xy 134.369245 -151.758195) (xy 134.319645 -151.732694) (xy 134.274287 -151.700243) (xy 134.234138 -151.661534)
			(xy 134.200052 -151.617391) (xy 134.172756 -151.568756) (xy 134.152833 -151.516665) (xy 134.140707 -151.462228)
			(xy 134.136636 -151.406606) (xy 133.538337 -151.406606) (xy 133.556729 -151.421912) (xy 133.593946 -151.463449)
			(xy 133.624719 -151.509962) (xy 133.648391 -151.560459) (xy 133.664459 -151.613866) (xy 133.672579 -151.669042)
			(xy 133.673088 -151.696928) (xy 133.672579 -151.724814) (xy 133.664459 -151.77999) (xy 133.648391 -151.833397)
			(xy 133.624719 -151.883894) (xy 133.593946 -151.930407) (xy 133.556729 -151.971944) (xy 133.513861 -152.007619)
			(xy 133.466255 -152.036673) (xy 133.414926 -152.058485) (xy 133.360969 -152.072591) (xy 133.305532 -152.078691)
			(xy 133.249798 -152.076654) (xy 133.194955 -152.066524) (xy 133.142171 -152.048517) (xy 133.092571 -152.023016)
			(xy 133.047213 -151.990565) (xy 133.007064 -151.951856) (xy 132.972978 -151.907713) (xy 132.945682 -151.859078)
			(xy 132.925759 -151.806987) (xy 132.913633 -151.75255) (xy 132.909562 -151.696928) (xy 132.656615 -151.696928)
			(xy 132.656579 -151.698906) (xy 132.648459 -151.754082) (xy 132.632391 -151.807489) (xy 132.608719 -151.857986)
			(xy 132.577946 -151.904499) (xy 132.540729 -151.946036) (xy 132.497861 -151.981711) (xy 132.450255 -152.010765)
			(xy 132.398926 -152.032577) (xy 132.344969 -152.046683) (xy 132.289532 -152.052783) (xy 132.233798 -152.050746)
			(xy 132.178955 -152.040616) (xy 132.126171 -152.022609) (xy 132.076571 -151.997108) (xy 132.031213 -151.964657)
			(xy 131.991064 -151.925948) (xy 131.956978 -151.881805) (xy 131.929682 -151.83317) (xy 131.909759 -151.781079)
			(xy 131.897633 -151.726642) (xy 131.893562 -151.67102) (xy 122.485404 -151.67102) (xy 122.485404 -153.782522)
			(xy 130.877562 -153.782522) (xy 130.881633 -153.7269) (xy 130.893759 -153.672463) (xy 130.913682 -153.620372)
			(xy 130.940978 -153.571737) (xy 130.975064 -153.527594) (xy 131.015213 -153.488885) (xy 131.060571 -153.456434)
			(xy 131.110171 -153.430933) (xy 131.162955 -153.412926) (xy 131.217798 -153.402796) (xy 131.273532 -153.400759)
			(xy 131.328969 -153.406859) (xy 131.382926 -153.420965) (xy 131.434255 -153.442777) (xy 131.481861 -153.471831)
			(xy 131.524729 -153.507506) (xy 131.561946 -153.549043) (xy 131.592719 -153.595556) (xy 131.616391 -153.646053)
			(xy 131.632459 -153.69946) (xy 131.640579 -153.754636) (xy 131.641088 -153.782522) (xy 131.893562 -153.782522)
			(xy 131.897633 -153.7269) (xy 131.909759 -153.672463) (xy 131.929682 -153.620372) (xy 131.956978 -153.571737)
			(xy 131.991064 -153.527594) (xy 132.031213 -153.488885) (xy 132.076571 -153.456434) (xy 132.126171 -153.430933)
			(xy 132.178955 -153.412926) (xy 132.233798 -153.402796) (xy 132.289532 -153.400759) (xy 132.344969 -153.406859)
			(xy 132.398926 -153.420965) (xy 132.450255 -153.442777) (xy 132.497861 -153.471831) (xy 132.540729 -153.507506)
			(xy 132.577946 -153.549043) (xy 132.608719 -153.595556) (xy 132.632391 -153.646053) (xy 132.648459 -153.69946)
			(xy 132.656579 -153.754636) (xy 132.657088 -153.782522) (xy 132.656579 -153.810408) (xy 132.653431 -153.831798)
			(xy 132.909562 -153.831798) (xy 132.913633 -153.776176) (xy 132.925759 -153.721739) (xy 132.945682 -153.669648)
			(xy 132.972978 -153.621013) (xy 133.007064 -153.57687) (xy 133.047213 -153.538161) (xy 133.092571 -153.50571)
			(xy 133.142171 -153.480209) (xy 133.194955 -153.462202) (xy 133.249798 -153.452072) (xy 133.305532 -153.450035)
			(xy 133.360969 -153.456135) (xy 133.414926 -153.470241) (xy 133.466255 -153.492053) (xy 133.513861 -153.521107)
			(xy 133.556729 -153.556782) (xy 133.593946 -153.598319) (xy 133.624719 -153.644832) (xy 133.648391 -153.695329)
			(xy 133.664459 -153.748736) (xy 133.669431 -153.782522) (xy 135.957562 -153.782522) (xy 135.961633 -153.7269)
			(xy 135.973759 -153.672463) (xy 135.993682 -153.620372) (xy 136.020978 -153.571737) (xy 136.055064 -153.527594)
			(xy 136.095213 -153.488885) (xy 136.140571 -153.456434) (xy 136.190171 -153.430933) (xy 136.242955 -153.412926)
			(xy 136.297798 -153.402796) (xy 136.353532 -153.400759) (xy 136.408969 -153.406859) (xy 136.462926 -153.420965)
			(xy 136.514255 -153.442777) (xy 136.561861 -153.471831) (xy 136.604729 -153.507506) (xy 136.641946 -153.549043)
			(xy 136.672719 -153.595556) (xy 136.696391 -153.646053) (xy 136.712459 -153.69946) (xy 136.720579 -153.754636)
			(xy 136.721088 -153.782522) (xy 136.720579 -153.810408) (xy 136.712459 -153.865584) (xy 136.696391 -153.918991)
			(xy 136.672719 -153.969488) (xy 136.641946 -154.016001) (xy 136.604729 -154.057538) (xy 136.561861 -154.093213)
			(xy 136.514255 -154.122267) (xy 136.462926 -154.144079) (xy 136.408969 -154.158185) (xy 136.353532 -154.164285)
			(xy 136.297798 -154.162248) (xy 136.242955 -154.152118) (xy 136.190171 -154.134111) (xy 136.140571 -154.10861)
			(xy 136.095213 -154.076159) (xy 136.055064 -154.03745) (xy 136.020978 -153.993307) (xy 135.993682 -153.944672)
			(xy 135.973759 -153.892581) (xy 135.961633 -153.838144) (xy 135.957562 -153.782522) (xy 133.669431 -153.782522)
			(xy 133.672579 -153.803912) (xy 133.673088 -153.831798) (xy 133.672579 -153.859684) (xy 133.664459 -153.91486)
			(xy 133.648391 -153.968267) (xy 133.624719 -154.018764) (xy 133.593946 -154.065277) (xy 133.556729 -154.106814)
			(xy 133.513861 -154.142489) (xy 133.466255 -154.171543) (xy 133.414926 -154.193355) (xy 133.360969 -154.207461)
			(xy 133.305532 -154.213561) (xy 133.249798 -154.211524) (xy 133.194955 -154.201394) (xy 133.142171 -154.183387)
			(xy 133.092571 -154.157886) (xy 133.047213 -154.125435) (xy 133.007064 -154.086726) (xy 132.972978 -154.042583)
			(xy 132.945682 -153.993948) (xy 132.925759 -153.941857) (xy 132.913633 -153.88742) (xy 132.909562 -153.831798)
			(xy 132.653431 -153.831798) (xy 132.648459 -153.865584) (xy 132.632391 -153.918991) (xy 132.608719 -153.969488)
			(xy 132.577946 -154.016001) (xy 132.540729 -154.057538) (xy 132.497861 -154.093213) (xy 132.450255 -154.122267)
			(xy 132.398926 -154.144079) (xy 132.344969 -154.158185) (xy 132.289532 -154.164285) (xy 132.233798 -154.162248)
			(xy 132.178955 -154.152118) (xy 132.126171 -154.134111) (xy 132.076571 -154.10861) (xy 132.031213 -154.076159)
			(xy 131.991064 -154.03745) (xy 131.956978 -153.993307) (xy 131.929682 -153.944672) (xy 131.909759 -153.892581)
			(xy 131.897633 -153.838144) (xy 131.893562 -153.782522) (xy 131.641088 -153.782522) (xy 131.640579 -153.810408)
			(xy 131.632459 -153.865584) (xy 131.616391 -153.918991) (xy 131.592719 -153.969488) (xy 131.561946 -154.016001)
			(xy 131.524729 -154.057538) (xy 131.481861 -154.093213) (xy 131.434255 -154.122267) (xy 131.382926 -154.144079)
			(xy 131.328969 -154.158185) (xy 131.273532 -154.164285) (xy 131.217798 -154.162248) (xy 131.162955 -154.152118)
			(xy 131.110171 -154.134111) (xy 131.060571 -154.10861) (xy 131.015213 -154.076159) (xy 130.975064 -154.03745)
			(xy 130.940978 -153.993307) (xy 130.913682 -153.944672) (xy 130.893759 -153.892581) (xy 130.881633 -153.838144)
			(xy 130.877562 -153.782522) (xy 122.485404 -153.782522) (xy 122.485404 -155.212034) (xy 123.369068 -155.212034)
			(xy 123.373139 -155.156412) (xy 123.385265 -155.101975) (xy 123.405188 -155.049884) (xy 123.432484 -155.001249)
			(xy 123.46657 -154.957106) (xy 123.506719 -154.918397) (xy 123.552077 -154.885946) (xy 123.601677 -154.860445)
			(xy 123.654461 -154.842438) (xy 123.709304 -154.832308) (xy 123.765038 -154.830271) (xy 123.820475 -154.836371)
			(xy 123.874432 -154.850477) (xy 123.925761 -154.872289) (xy 123.973367 -154.901343) (xy 124.016235 -154.937018)
			(xy 124.053452 -154.978555) (xy 124.084225 -155.025068) (xy 124.107897 -155.075565) (xy 124.108988 -155.079192)
			(xy 125.969774 -155.079192) (xy 125.973845 -155.02357) (xy 125.985971 -154.969133) (xy 126.005894 -154.917042)
			(xy 126.03319 -154.868407) (xy 126.067276 -154.824264) (xy 126.107425 -154.785555) (xy 126.152783 -154.753104)
			(xy 126.202383 -154.727603) (xy 126.255167 -154.709596) (xy 126.31001 -154.699466) (xy 126.365744 -154.697429)
			(xy 126.421181 -154.703529) (xy 126.475138 -154.717635) (xy 126.526467 -154.739447) (xy 126.574073 -154.768501)
			(xy 126.616941 -154.804176) (xy 126.654158 -154.845713) (xy 126.684931 -154.892226) (xy 126.708603 -154.942723)
			(xy 126.724671 -154.99613) (xy 126.732791 -155.051306) (xy 126.7333 -155.079192) (xy 126.733235 -155.082748)
			(xy 127.293624 -155.082748) (xy 127.294049 -155.056433) (xy 127.301292 -155.004302) (xy 127.315618 -154.953658)
			(xy 127.336759 -154.905459) (xy 127.364313 -154.860617) (xy 127.397759 -154.819979) (xy 127.416814 -154.801824)
			(xy 127.424209 -154.794297) (xy 127.432737 -154.775021) (xy 127.433324 -154.764486) (xy 127.433324 -154.68981)
			(xy 127.432796 -154.67926) (xy 127.424259 -154.659965) (xy 127.416814 -154.652472) (xy 127.397755 -154.63432)
			(xy 127.364297 -154.59369) (xy 127.336738 -154.548849) (xy 127.3156 -154.500648) (xy 127.301284 -154.449999)
			(xy 127.294061 -154.397864) (xy 127.293624 -154.371548) (xy 127.2941 -154.344295) (xy 127.301851 -154.290343)
			(xy 127.317203 -154.238043) (xy 127.339842 -154.188461) (xy 127.369308 -154.142606) (xy 127.405001 -154.101412)
			(xy 127.446193 -154.065718) (xy 127.492047 -154.03625) (xy 127.541628 -154.013608) (xy 127.593927 -153.998255)
			(xy 127.647879 -153.990501) (xy 127.675132 -153.99004) (xy 127.701447 -153.990473) (xy 127.753578 -153.997713)
			(xy 127.804222 -154.012038) (xy 127.852421 -154.033177) (xy 127.897263 -154.06073) (xy 127.937901 -154.094175)
			(xy 127.956056 -154.11323) (xy 127.963601 -154.120604) (xy 127.982863 -154.129147) (xy 127.993394 -154.12974)
			(xy 128.06807 -154.12974) (xy 128.078618 -154.129197) (xy 128.097913 -154.12067) (xy 128.105408 -154.11323)
			(xy 128.125228 -154.092442) (xy 128.17 -154.056467) (xy 128.219658 -154.027607) (xy 128.27308 -154.006514)
			(xy 128.329059 -153.993665) (xy 128.386332 -153.98935) (xy 128.443605 -153.993665) (xy 128.499584 -154.006514)
			(xy 128.553006 -154.027607) (xy 128.602664 -154.056467) (xy 128.647436 -154.092442) (xy 128.667256 -154.11323)
			(xy 128.674801 -154.120604) (xy 128.694063 -154.129147) (xy 128.704594 -154.12974) (xy 128.77927 -154.12974)
			(xy 128.789818 -154.129197) (xy 128.809113 -154.12067) (xy 128.816608 -154.11323) (xy 128.836428 -154.092442)
			(xy 128.8812 -154.056467) (xy 128.930858 -154.027607) (xy 128.98428 -154.006514) (xy 129.040259 -153.993665)
			(xy 129.097532 -153.98935) (xy 129.154805 -153.993665) (xy 129.210784 -154.006514) (xy 129.264206 -154.027607)
			(xy 129.313864 -154.056467) (xy 129.358636 -154.092442) (xy 129.378456 -154.11323) (xy 129.386001 -154.120604)
			(xy 129.405263 -154.129147) (xy 129.415794 -154.12974) (xy 129.49047 -154.12974) (xy 129.501018 -154.129197)
			(xy 129.520313 -154.12067) (xy 129.527808 -154.11323) (xy 129.545973 -154.094183) (xy 129.5866 -154.060724)
			(xy 129.631438 -154.033163) (xy 129.679637 -154.012023) (xy 129.730283 -153.997704) (xy 129.782416 -153.990479)
			(xy 129.808732 -153.99004) (xy 129.835988 -153.990425) (xy 129.889944 -153.998188) (xy 129.942246 -154.01355)
			(xy 129.99183 -154.0362) (xy 130.037685 -154.065676) (xy 130.078879 -154.101378) (xy 130.114572 -154.142579)
			(xy 130.144038 -154.18844) (xy 130.166678 -154.238029) (xy 130.182029 -154.290334) (xy 130.18978 -154.344292)
			(xy 130.19024 -154.371548) (xy 130.189824 -154.397864) (xy 130.182581 -154.449995) (xy 130.168253 -154.50064)
			(xy 130.147111 -154.548839) (xy 130.119555 -154.593681) (xy 130.086107 -154.634318) (xy 130.06705 -154.652472)
			(xy 130.059666 -154.660009) (xy 130.05113 -154.679277) (xy 130.05054 -154.68981) (xy 130.05054 -154.764486)
			(xy 130.051051 -154.775038) (xy 130.059598 -154.794334) (xy 130.06705 -154.801824) (xy 130.08612 -154.819965)
			(xy 130.119574 -154.860599) (xy 130.14713 -154.905443) (xy 130.168265 -154.953646) (xy 130.18258 -155.004296)
			(xy 130.189802 -155.056431) (xy 130.19024 -155.082748) (xy 130.189767 -155.109999) (xy 130.182005 -155.163945)
			(xy 130.166645 -155.216238) (xy 130.144001 -155.265814) (xy 130.114532 -155.311662) (xy 130.07884 -155.352851)
			(xy 130.03765 -155.388542) (xy 129.9918 -155.418008) (xy 129.942223 -155.440651) (xy 129.88993 -155.456008)
			(xy 129.835983 -155.463768) (xy 129.808732 -155.464256) (xy 129.782416 -155.463848) (xy 129.730284 -155.456603)
			(xy 129.67964 -155.442273) (xy 129.631441 -155.42113) (xy 129.586599 -155.393572) (xy 129.545962 -155.360123)
			(xy 129.527808 -155.341066) (xy 129.520277 -155.333676) (xy 129.501004 -155.325143) (xy 129.49047 -155.324556)
			(xy 129.415794 -155.324556) (xy 129.405244 -155.325082) (xy 129.38595 -155.333621) (xy 129.378456 -155.341066)
			(xy 129.358636 -155.361854) (xy 129.313864 -155.397829) (xy 129.264206 -155.426689) (xy 129.210784 -155.447782)
			(xy 129.154805 -155.460631) (xy 129.097532 -155.464946) (xy 129.040259 -155.460631) (xy 128.98428 -155.447782)
			(xy 128.930858 -155.426689) (xy 128.8812 -155.397829) (xy 128.836428 -155.361854) (xy 128.816608 -155.341066)
			(xy 128.809077 -155.333676) (xy 128.789804 -155.325143) (xy 128.77927 -155.324556) (xy 128.704594 -155.324556)
			(xy 128.694044 -155.325082) (xy 128.67475 -155.333621) (xy 128.667256 -155.341066) (xy 128.647436 -155.361854)
			(xy 128.602664 -155.397829) (xy 128.553006 -155.426689) (xy 128.499584 -155.447782) (xy 128.443605 -155.460631)
			(xy 128.386332 -155.464946) (xy 128.329059 -155.460631) (xy 128.27308 -155.447782) (xy 128.219658 -155.426689)
			(xy 128.17 -155.397829) (xy 128.125228 -155.361854) (xy 128.105408 -155.341066) (xy 128.097877 -155.333676)
			(xy 128.078604 -155.325143) (xy 128.06807 -155.324556) (xy 127.993394 -155.324556) (xy 127.982844 -155.325082)
			(xy 127.96355 -155.333621) (xy 127.956056 -155.341066) (xy 127.937928 -155.360148) (xy 127.897291 -155.393601)
			(xy 127.852444 -155.421154) (xy 127.804238 -155.442288) (xy 127.753587 -155.4566) (xy 127.701449 -155.46382)
			(xy 127.675132 -155.464256) (xy 127.647884 -155.463692) (xy 127.593941 -155.455941) (xy 127.541651 -155.440593)
			(xy 127.492077 -155.417959) (xy 127.446229 -155.3885) (xy 127.40504 -155.352817) (xy 127.369348 -155.311635)
			(xy 127.33988 -155.265793) (xy 127.317235 -155.216224) (xy 127.301876 -155.163937) (xy 127.294114 -155.109996)
			(xy 127.293624 -155.082748) (xy 126.733235 -155.082748) (xy 126.732791 -155.107078) (xy 126.724671 -155.162254)
			(xy 126.708603 -155.215661) (xy 126.684931 -155.266158) (xy 126.654158 -155.312671) (xy 126.616941 -155.354208)
			(xy 126.574073 -155.389883) (xy 126.526467 -155.418937) (xy 126.475138 -155.440749) (xy 126.421181 -155.454855)
			(xy 126.365744 -155.460955) (xy 126.31001 -155.458918) (xy 126.255167 -155.448788) (xy 126.202383 -155.430781)
			(xy 126.152783 -155.40528) (xy 126.107425 -155.372829) (xy 126.067276 -155.33412) (xy 126.03319 -155.289977)
			(xy 126.005894 -155.241342) (xy 125.985971 -155.189251) (xy 125.973845 -155.134814) (xy 125.969774 -155.079192)
			(xy 124.108988 -155.079192) (xy 124.123965 -155.128972) (xy 124.132085 -155.184148) (xy 124.132594 -155.212034)
			(xy 124.132085 -155.23992) (xy 124.123965 -155.295096) (xy 124.107897 -155.348503) (xy 124.084225 -155.399)
			(xy 124.053452 -155.445513) (xy 124.016235 -155.48705) (xy 123.973367 -155.522725) (xy 123.925761 -155.551779)
			(xy 123.874432 -155.573591) (xy 123.820475 -155.587697) (xy 123.765038 -155.593797) (xy 123.709304 -155.59176)
			(xy 123.654461 -155.58163) (xy 123.601677 -155.563623) (xy 123.552077 -155.538122) (xy 123.506719 -155.505671)
			(xy 123.46657 -155.466962) (xy 123.432484 -155.422819) (xy 123.405188 -155.374184) (xy 123.385265 -155.322093)
			(xy 123.373139 -155.267656) (xy 123.369068 -155.212034) (xy 122.485404 -155.212034) (xy 122.485404 -156.69387)
			(xy 124.987302 -156.69387) (xy 124.991373 -156.638248) (xy 125.003499 -156.583811) (xy 125.023422 -156.53172)
			(xy 125.050718 -156.483085) (xy 125.084804 -156.438942) (xy 125.124953 -156.400233) (xy 125.170311 -156.367782)
			(xy 125.219911 -156.342281) (xy 125.272695 -156.324274) (xy 125.327538 -156.314144) (xy 125.383272 -156.312107)
			(xy 125.438709 -156.318207) (xy 125.492666 -156.332313) (xy 125.543995 -156.354125) (xy 125.591601 -156.383179)
			(xy 125.634469 -156.418854) (xy 125.671686 -156.460391) (xy 125.702459 -156.506904) (xy 125.726131 -156.557401)
			(xy 125.742199 -156.610808) (xy 125.750319 -156.665984) (xy 125.750828 -156.69387) (xy 125.750319 -156.721756)
			(xy 125.742199 -156.776932) (xy 125.726131 -156.830339) (xy 125.702459 -156.880836) (xy 125.671686 -156.927349)
			(xy 125.634469 -156.968886) (xy 125.591601 -157.004561) (xy 125.543995 -157.033615) (xy 125.492666 -157.055427)
			(xy 125.438709 -157.069533) (xy 125.383272 -157.075633) (xy 125.327538 -157.073596) (xy 125.272695 -157.063466)
			(xy 125.219911 -157.045459) (xy 125.170311 -157.019958) (xy 125.124953 -156.987507) (xy 125.084804 -156.948798)
			(xy 125.050718 -156.904655) (xy 125.023422 -156.85602) (xy 125.003499 -156.803929) (xy 124.991373 -156.749492)
			(xy 124.987302 -156.69387) (xy 122.485404 -156.69387) (xy 122.485404 -157.812994) (xy 122.75007 -157.812994)
			(xy 122.754141 -157.757372) (xy 122.766267 -157.702935) (xy 122.78619 -157.650844) (xy 122.813486 -157.602209)
			(xy 122.847572 -157.558066) (xy 122.887721 -157.519357) (xy 122.933079 -157.486906) (xy 122.982679 -157.461405)
			(xy 123.035463 -157.443398) (xy 123.090306 -157.433268) (xy 123.14604 -157.431231) (xy 123.201477 -157.437331)
			(xy 123.255434 -157.451437) (xy 123.306763 -157.473249) (xy 123.354369 -157.502303) (xy 123.397237 -157.537978)
			(xy 123.434454 -157.579515) (xy 123.465227 -157.626028) (xy 123.475477 -157.647894) (xy 127.113792 -157.647894)
			(xy 127.114327 -157.621251) (xy 127.12285 -157.568653) (xy 127.139707 -157.518105) (xy 127.164461 -157.470918)
			(xy 127.196468 -157.428318) (xy 127.2349 -157.391409) (xy 127.25654 -157.37586) (xy 127.267829 -157.367502)
			(xy 127.28568 -157.345826) (xy 127.296959 -157.320111) (xy 127.300815 -157.292297) (xy 127.296957 -157.264483)
			(xy 127.285677 -157.238768) (xy 127.267824 -157.217094) (xy 127.25654 -157.208728) (xy 127.234939 -157.193131)
			(xy 127.196524 -157.156217) (xy 127.164523 -157.113623) (xy 127.139765 -157.066449) (xy 127.12289 -157.015916)
			(xy 127.114334 -156.963332) (xy 127.113792 -156.936694) (xy 127.114302 -156.910707) (xy 127.122432 -156.859372)
			(xy 127.138493 -156.809942) (xy 127.162089 -156.763632) (xy 127.192639 -156.721584) (xy 127.22939 -156.684833)
			(xy 127.271438 -156.654283) (xy 127.317748 -156.630687) (xy 127.367178 -156.614626) (xy 127.418513 -156.606496)
			(xy 127.470487 -156.606496) (xy 127.521822 -156.614626) (xy 127.571252 -156.630687) (xy 127.617562 -156.654283)
			(xy 127.65961 -156.684833) (xy 127.696361 -156.721584) (xy 127.726911 -156.763632) (xy 127.750507 -156.809942)
			(xy 127.766568 -156.859372) (xy 127.774698 -156.910707) (xy 127.775208 -156.936694) (xy 127.774664 -156.963336)
			(xy 127.766143 -157.015935) (xy 127.749288 -157.066482) (xy 127.724536 -157.113669) (xy 127.69253 -157.156269)
			(xy 127.6541 -157.193179) (xy 127.63246 -157.208728) (xy 127.621182 -157.217101) (xy 127.603332 -157.238773)
			(xy 127.592052 -157.264485) (xy 127.588195 -157.292297) (xy 127.59205 -157.320108) (xy 127.603328 -157.345821)
			(xy 127.621177 -157.367494) (xy 127.63246 -157.37586) (xy 127.654056 -157.391465) (xy 127.692471 -157.428377)
			(xy 127.724472 -157.47097) (xy 127.749231 -157.518142) (xy 127.766107 -157.568673) (xy 127.774665 -157.621257)
			(xy 127.775208 -157.647894) (xy 128.013714 -157.647894) (xy 128.014239 -157.621251) (xy 128.022763 -157.568651)
			(xy 128.039622 -157.518103) (xy 128.064377 -157.470916) (xy 128.096387 -157.428316) (xy 128.13482 -157.391408)
			(xy 128.156462 -157.37586) (xy 128.167749 -157.3675) (xy 128.185596 -157.345824) (xy 128.196873 -157.320109)
			(xy 128.200728 -157.292297) (xy 128.196871 -157.264484) (xy 128.185593 -157.238771) (xy 128.167744 -157.217095)
			(xy 128.156462 -157.208728) (xy 128.134866 -157.193124) (xy 128.096449 -157.156213) (xy 128.064448 -157.11362)
			(xy 128.039689 -157.066447) (xy 128.022813 -157.015915) (xy 128.014256 -156.963332) (xy 128.013714 -156.936694)
			(xy 128.014224 -156.910707) (xy 128.022354 -156.859372) (xy 128.038415 -156.809942) (xy 128.062011 -156.763632)
			(xy 128.092561 -156.721584) (xy 128.129312 -156.684833) (xy 128.17136 -156.654283) (xy 128.21767 -156.630687)
			(xy 128.2671 -156.614626) (xy 128.318435 -156.606496) (xy 128.370409 -156.606496) (xy 128.421744 -156.614626)
			(xy 128.471174 -156.630687) (xy 128.517484 -156.654283) (xy 128.559532 -156.684833) (xy 128.596283 -156.721584)
			(xy 128.626833 -156.763632) (xy 128.650429 -156.809942) (xy 128.66649 -156.859372) (xy 128.67462 -156.910707)
			(xy 128.67513 -156.936694) (xy 128.67462 -156.963338) (xy 128.666096 -157.01594) (xy 128.649236 -157.06649)
			(xy 128.624478 -157.113677) (xy 128.592465 -157.156276) (xy 128.554026 -157.193182) (xy 128.532382 -157.208728)
			(xy 128.521103 -157.2171) (xy 128.503248 -157.238771) (xy 128.491966 -157.264484) (xy 128.488108 -157.292297)
			(xy 128.491964 -157.320109) (xy 128.503245 -157.345823) (xy 128.521098 -157.367495) (xy 128.532382 -157.37586)
			(xy 128.553982 -157.391458) (xy 128.592396 -157.428372) (xy 128.624396 -157.470967) (xy 128.649154 -157.51814)
			(xy 128.66603 -157.568673) (xy 128.674587 -157.621256) (xy 128.67513 -157.647894) (xy 128.913636 -157.647894)
			(xy 128.914152 -157.62125) (xy 128.922677 -157.56865) (xy 128.939536 -157.5181) (xy 128.964293 -157.470914)
			(xy 128.996305 -157.428314) (xy 129.034741 -157.391407) (xy 129.056384 -157.37586) (xy 129.067678 -157.367505)
			(xy 129.085539 -157.345831) (xy 129.096824 -157.320115) (xy 129.100683 -157.292297) (xy 129.096823 -157.264479)
			(xy 129.085535 -157.238763) (xy 129.067673 -157.217091) (xy 129.056384 -157.208728) (xy 129.034792 -157.193118)
			(xy 128.996375 -157.156208) (xy 128.964372 -157.113617) (xy 128.939612 -157.066446) (xy 128.922735 -157.015914)
			(xy 128.914178 -156.963331) (xy 128.913636 -156.936694) (xy 128.914146 -156.910707) (xy 128.922276 -156.859372)
			(xy 128.938337 -156.809942) (xy 128.961933 -156.763632) (xy 128.992483 -156.721584) (xy 129.029234 -156.684833)
			(xy 129.071282 -156.654283) (xy 129.117592 -156.630687) (xy 129.167022 -156.614626) (xy 129.218357 -156.606496)
			(xy 129.270331 -156.606496) (xy 129.321666 -156.614626) (xy 129.371096 -156.630687) (xy 129.417406 -156.654283)
			(xy 129.459454 -156.684833) (xy 129.496205 -156.721584) (xy 129.526755 -156.763632) (xy 129.550351 -156.809942)
			(xy 129.566412 -156.859372) (xy 129.574542 -156.910707) (xy 129.575052 -156.936694) (xy 129.574532 -156.963338)
			(xy 129.566009 -157.015938) (xy 129.549151 -157.066488) (xy 129.524395 -157.113674) (xy 129.492383 -157.156274)
			(xy 129.453947 -157.193181) (xy 129.432304 -157.208728) (xy 129.421023 -157.217099) (xy 129.403164 -157.238769)
			(xy 129.39188 -157.264482) (xy 129.38802 -157.292297) (xy 129.391878 -157.320111) (xy 129.403161 -157.345825)
			(xy 129.421018 -157.367497) (xy 129.432304 -157.37586) (xy 129.453887 -157.391481) (xy 129.492306 -157.428388)
			(xy 129.52431 -157.470977) (xy 129.549072 -157.518146) (xy 129.56595 -157.568676) (xy 129.574509 -157.621257)
			(xy 129.575052 -157.647894) (xy 129.813812 -157.647894) (xy 129.814338 -157.621251) (xy 129.822862 -157.568651)
			(xy 129.83972 -157.518103) (xy 129.864475 -157.470916) (xy 129.896485 -157.428316) (xy 129.934919 -157.391408)
			(xy 129.95656 -157.37586) (xy 129.967847 -157.3675) (xy 129.985695 -157.345824) (xy 129.996971 -157.320109)
			(xy 130.000827 -157.292297) (xy 129.99697 -157.264484) (xy 129.985691 -157.23877) (xy 129.967842 -157.217095)
			(xy 129.95656 -157.208728) (xy 129.934963 -157.193125) (xy 129.896547 -157.156213) (xy 129.864545 -157.11362)
			(xy 129.839786 -157.066447) (xy 129.822911 -157.015915) (xy 129.814354 -156.963332) (xy 129.813812 -156.936694)
			(xy 129.814322 -156.910707) (xy 129.822452 -156.859372) (xy 129.838513 -156.809942) (xy 129.862109 -156.763632)
			(xy 129.892659 -156.721584) (xy 129.92941 -156.684833) (xy 129.971458 -156.654283) (xy 130.017768 -156.630687)
			(xy 130.067198 -156.614626) (xy 130.118533 -156.606496) (xy 130.170507 -156.606496) (xy 130.221842 -156.614626)
			(xy 130.271272 -156.630687) (xy 130.317582 -156.654283) (xy 130.35963 -156.684833) (xy 130.396381 -156.721584)
			(xy 130.426931 -156.763632) (xy 130.450527 -156.809942) (xy 130.466588 -156.859372) (xy 130.474718 -156.910707)
			(xy 130.475228 -156.936694) (xy 130.474719 -156.963338) (xy 130.466195 -157.01594) (xy 130.449335 -157.06649)
			(xy 130.424577 -157.113677) (xy 130.392563 -157.156276) (xy 130.354124 -157.193182) (xy 130.33248 -157.208728)
			(xy 130.321201 -157.2171) (xy 130.303346 -157.238771) (xy 130.292064 -157.264484) (xy 130.288206 -157.292297)
			(xy 130.292063 -157.320109) (xy 130.303343 -157.345823) (xy 130.321196 -157.367495) (xy 130.33248 -157.37586)
			(xy 130.35408 -157.391459) (xy 130.392494 -157.428373) (xy 130.424494 -157.470967) (xy 130.449252 -157.518141)
			(xy 130.466128 -157.568673) (xy 130.474685 -157.621256) (xy 130.475187 -157.645862) (xy 131.429252 -157.645862)
			(xy 131.429677 -157.619546) (xy 131.436919 -157.567415) (xy 131.451245 -157.516771) (xy 131.472385 -157.468572)
			(xy 131.499939 -157.42373) (xy 131.533386 -157.383093) (xy 131.552442 -157.364938) (xy 131.55982 -157.357396)
			(xy 131.56836 -157.338132) (xy 131.568952 -157.3276) (xy 131.568952 -157.252924) (xy 131.568437 -157.242372)
			(xy 131.559893 -157.223076) (xy 131.552442 -157.215586) (xy 131.533376 -157.197442) (xy 131.499922 -157.156808)
			(xy 131.472366 -157.111965) (xy 131.451229 -157.063762) (xy 131.436914 -157.013114) (xy 131.42969 -156.960979)
			(xy 131.429252 -156.934662) (xy 131.429738 -156.907411) (xy 131.437494 -156.853463) (xy 131.452849 -156.801168)
			(xy 131.475491 -156.751591) (xy 131.504957 -156.705741) (xy 131.540648 -156.66455) (xy 131.581839 -156.628859)
			(xy 131.627689 -156.599393) (xy 131.677266 -156.576751) (xy 131.729561 -156.561396) (xy 131.783509 -156.55364)
			(xy 131.838011 -156.55364) (xy 131.891959 -156.561396) (xy 131.944254 -156.576751) (xy 131.993831 -156.599393)
			(xy 132.039681 -156.628859) (xy 132.058426 -156.645101) (xy 133.41382 -156.645101) (xy 133.418135 -156.587828)
			(xy 133.430985 -156.531848) (xy 133.452079 -156.478427) (xy 133.48094 -156.428769) (xy 133.516917 -156.383997)
			(xy 133.537706 -156.364178) (xy 133.54512 -156.356667) (xy 133.553637 -156.337379) (xy 133.554216 -156.32684)
			(xy 133.554216 -156.252164) (xy 133.553661 -156.241617) (xy 133.545144 -156.222322) (xy 133.537706 -156.214826)
			(xy 133.518671 -156.196649) (xy 133.485212 -156.156024) (xy 133.45765 -156.111189) (xy 133.436508 -156.062992)
			(xy 133.422186 -156.012348) (xy 133.414957 -155.960217) (xy 133.414516 -155.933902) (xy 133.415002 -155.906651)
			(xy 133.422758 -155.852703) (xy 133.438113 -155.800408) (xy 133.460755 -155.750831) (xy 133.490221 -155.704981)
			(xy 133.525912 -155.66379) (xy 133.567103 -155.628099) (xy 133.612953 -155.598633) (xy 133.66253 -155.575991)
			(xy 133.714825 -155.560636) (xy 133.768773 -155.55288) (xy 133.823275 -155.55288) (xy 133.877223 -155.560636)
			(xy 133.929518 -155.575991) (xy 133.979095 -155.598633) (xy 134.024945 -155.628099) (xy 134.066136 -155.66379)
			(xy 134.101827 -155.704981) (xy 134.131293 -155.750831) (xy 134.153935 -155.800408) (xy 134.16929 -155.852703)
			(xy 134.177046 -155.906651) (xy 134.177532 -155.933902) (xy 134.177056 -155.960216) (xy 134.169821 -156.012343)
			(xy 134.155503 -156.062985) (xy 134.134372 -156.111184) (xy 134.106828 -156.156028) (xy 134.073392 -156.196669)
			(xy 134.054342 -156.214826) (xy 134.046933 -156.222342) (xy 134.038412 -156.241626) (xy 134.037832 -156.252164)
			(xy 134.037832 -156.32684) (xy 134.038371 -156.337389) (xy 134.046898 -156.356685) (xy 134.054342 -156.364178)
			(xy 134.075131 -156.383997) (xy 134.111104 -156.42877) (xy 134.139961 -156.478428) (xy 134.161053 -156.53185)
			(xy 134.173901 -156.587829) (xy 134.178216 -156.645101) (xy 134.1739 -156.702373) (xy 134.172764 -156.707322)
			(xy 136.479628 -156.707322) (xy 136.48394 -156.650052) (xy 136.496786 -156.594075) (xy 136.517874 -156.540656)
			(xy 136.54673 -156.490999) (xy 136.5827 -156.446228) (xy 136.603486 -156.426408) (xy 136.610884 -156.418883)
			(xy 136.619411 -156.399606) (xy 136.619996 -156.38907) (xy 136.619996 -156.314394) (xy 136.619485 -156.303842)
			(xy 136.610937 -156.284547) (xy 136.603486 -156.277056) (xy 136.584413 -156.258918) (xy 136.550958 -156.218284)
			(xy 136.523402 -156.17344) (xy 136.502267 -156.125236) (xy 136.487953 -156.074585) (xy 136.480732 -156.022449)
			(xy 136.480296 -155.996132) (xy 136.480782 -155.968881) (xy 136.488538 -155.914933) (xy 136.503893 -155.862638)
			(xy 136.526535 -155.813061) (xy 136.556001 -155.767211) (xy 136.591692 -155.72602) (xy 136.632883 -155.690329)
			(xy 136.678733 -155.660863) (xy 136.72831 -155.638221) (xy 136.780605 -155.622866) (xy 136.834553 -155.61511)
			(xy 136.889055 -155.61511) (xy 136.943003 -155.622866) (xy 136.995298 -155.638221) (xy 137.044875 -155.660863)
			(xy 137.090725 -155.690329) (xy 137.131916 -155.72602) (xy 137.167607 -155.767211) (xy 137.197073 -155.813061)
			(xy 137.219715 -155.862638) (xy 137.23507 -155.914933) (xy 137.242826 -155.968881) (xy 137.243312 -155.996132)
			(xy 137.242862 -156.022447) (xy 137.235623 -156.074576) (xy 137.2213 -156.125219) (xy 137.200165 -156.173417)
			(xy 137.172616 -156.21826) (xy 137.139175 -156.2589) (xy 137.120122 -156.277056) (xy 137.112741 -156.284595)
			(xy 137.104204 -156.303862) (xy 137.103612 -156.314394) (xy 137.103612 -156.38907) (xy 137.10414 -156.39962)
			(xy 137.112676 -156.418915) (xy 137.120122 -156.426408) (xy 137.140942 -156.446196) (xy 137.176916 -156.490973)
			(xy 137.205775 -156.540636) (xy 137.226865 -156.594062) (xy 137.239712 -156.650045) (xy 137.244024 -156.707322)
			(xy 137.239705 -156.764598) (xy 137.226852 -156.820579) (xy 137.205756 -156.874003) (xy 137.176892 -156.923663)
			(xy 137.140912 -156.968436) (xy 137.120122 -156.988256) (xy 137.112741 -156.995795) (xy 137.104204 -157.015062)
			(xy 137.103612 -157.025594) (xy 137.103612 -157.10027) (xy 137.10414 -157.11082) (xy 137.112676 -157.130115)
			(xy 137.120122 -157.137608) (xy 137.139179 -157.155762) (xy 137.172635 -157.196393) (xy 137.200193 -157.241234)
			(xy 137.221331 -157.289434) (xy 137.235648 -157.340082) (xy 137.242873 -157.392216) (xy 137.243312 -157.418532)
			(xy 137.242826 -157.445783) (xy 137.23507 -157.499731) (xy 137.219715 -157.552026) (xy 137.197073 -157.601603)
			(xy 137.167607 -157.647453) (xy 137.131916 -157.688644) (xy 137.090725 -157.724335) (xy 137.044875 -157.753801)
			(xy 136.995298 -157.776443) (xy 136.943003 -157.791798) (xy 136.889055 -157.799554) (xy 136.834553 -157.799554)
			(xy 136.780605 -157.791798) (xy 136.72831 -157.776443) (xy 136.678733 -157.753801) (xy 136.632883 -157.724335)
			(xy 136.591692 -157.688644) (xy 136.556001 -157.647453) (xy 136.526535 -157.601603) (xy 136.503893 -157.552026)
			(xy 136.488538 -157.499731) (xy 136.480782 -157.445783) (xy 136.480296 -157.418532) (xy 136.480719 -157.392217)
			(xy 136.487963 -157.340086) (xy 136.502291 -157.289443) (xy 136.523432 -157.241244) (xy 136.550986 -157.196401)
			(xy 136.584431 -157.155764) (xy 136.603486 -157.137608) (xy 136.610884 -157.130083) (xy 136.619411 -157.110806)
			(xy 136.619996 -157.10027) (xy 136.619996 -157.025594) (xy 136.619485 -157.015042) (xy 136.610937 -156.995747)
			(xy 136.603486 -156.988256) (xy 136.58273 -156.968404) (xy 136.546754 -156.923636) (xy 136.517893 -156.873983)
			(xy 136.496798 -156.820566) (xy 136.483947 -156.764591) (xy 136.479628 -156.707322) (xy 134.172764 -156.707322)
			(xy 134.161052 -156.758352) (xy 134.13996 -156.811774) (xy 134.111102 -156.861432) (xy 134.075129 -156.906205)
			(xy 134.054342 -156.926026) (xy 134.046933 -156.933542) (xy 134.038412 -156.952826) (xy 134.037832 -156.963364)
			(xy 134.037832 -157.03804) (xy 134.038371 -157.048589) (xy 134.046898 -157.067885) (xy 134.054342 -157.075378)
			(xy 134.073388 -157.093543) (xy 134.106844 -157.134172) (xy 134.134404 -157.17901) (xy 134.155543 -157.227209)
			(xy 134.169863 -157.277854) (xy 134.177091 -157.329987) (xy 134.177532 -157.356302) (xy 134.177046 -157.383553)
			(xy 134.16929 -157.437501) (xy 134.153935 -157.489796) (xy 134.131293 -157.539373) (xy 134.101827 -157.585223)
			(xy 134.066136 -157.626414) (xy 134.024945 -157.662105) (xy 133.979095 -157.691571) (xy 133.929518 -157.714213)
			(xy 133.877223 -157.729568) (xy 133.823275 -157.737324) (xy 133.768773 -157.737324) (xy 133.714825 -157.729568)
			(xy 133.66253 -157.714213) (xy 133.612953 -157.691571) (xy 133.567103 -157.662105) (xy 133.525912 -157.626414)
			(xy 133.490221 -157.585223) (xy 133.460755 -157.539373) (xy 133.438113 -157.489796) (xy 133.422758 -157.437501)
			(xy 133.415002 -157.383553) (xy 133.414516 -157.356302) (xy 133.41498 -157.329988) (xy 133.422215 -157.277859)
			(xy 133.436534 -157.227216) (xy 133.457667 -157.179017) (xy 133.485214 -157.134174) (xy 133.518654 -157.093534)
			(xy 133.537706 -157.075378) (xy 133.54512 -157.067867) (xy 133.553637 -157.048579) (xy 133.554216 -157.03804)
			(xy 133.554216 -156.963364) (xy 133.553661 -156.952817) (xy 133.545144 -156.933522) (xy 133.537706 -156.926026)
			(xy 133.516919 -156.906205) (xy 133.480942 -156.861433) (xy 133.45208 -156.811776) (xy 133.430986 -156.758354)
			(xy 133.418136 -156.702375) (xy 133.41382 -156.645101) (xy 132.058426 -156.645101) (xy 132.080872 -156.66455)
			(xy 132.116563 -156.705741) (xy 132.146029 -156.751591) (xy 132.168671 -156.801168) (xy 132.184026 -156.853463)
			(xy 132.191782 -156.907411) (xy 132.192268 -156.934662) (xy 132.191852 -156.960978) (xy 132.184608 -157.013109)
			(xy 132.17028 -157.063753) (xy 132.149138 -157.111952) (xy 132.121582 -157.156794) (xy 132.088134 -157.197431)
			(xy 132.069078 -157.215586) (xy 132.061677 -157.223108) (xy 132.053153 -157.242388) (xy 132.052568 -157.252924)
			(xy 132.052568 -157.3276) (xy 132.053093 -157.33815) (xy 132.061632 -157.357445) (xy 132.069078 -157.364938)
			(xy 132.088141 -157.383086) (xy 132.121598 -157.423717) (xy 132.149157 -157.468559) (xy 132.170294 -157.516761)
			(xy 132.184609 -157.56741) (xy 132.191831 -157.619545) (xy 132.192268 -157.645862) (xy 132.191782 -157.673113)
			(xy 132.184026 -157.727061) (xy 132.168671 -157.779356) (xy 132.146029 -157.828933) (xy 132.116563 -157.874783)
			(xy 132.080872 -157.915974) (xy 132.039681 -157.951665) (xy 131.993831 -157.981131) (xy 131.944254 -158.003773)
			(xy 131.891959 -158.019128) (xy 131.838011 -158.026884) (xy 131.783509 -158.026884) (xy 131.729561 -158.019128)
			(xy 131.677266 -158.003773) (xy 131.627689 -157.981131) (xy 131.581839 -157.951665) (xy 131.540648 -157.915974)
			(xy 131.504957 -157.874783) (xy 131.475491 -157.828933) (xy 131.452849 -157.779356) (xy 131.437494 -157.727061)
			(xy 131.429738 -157.673113) (xy 131.429252 -157.645862) (xy 130.475187 -157.645862) (xy 130.475228 -157.647894)
			(xy 130.474718 -157.673881) (xy 130.466588 -157.725216) (xy 130.450527 -157.774646) (xy 130.426931 -157.820956)
			(xy 130.396381 -157.863004) (xy 130.35963 -157.899755) (xy 130.317582 -157.930305) (xy 130.271272 -157.953901)
			(xy 130.221842 -157.969962) (xy 130.170507 -157.978092) (xy 130.118533 -157.978092) (xy 130.067198 -157.969962)
			(xy 130.017768 -157.953901) (xy 129.971458 -157.930305) (xy 129.92941 -157.899755) (xy 129.892659 -157.863004)
			(xy 129.862109 -157.820956) (xy 129.838513 -157.774646) (xy 129.822452 -157.725216) (xy 129.814322 -157.673881)
			(xy 129.813812 -157.647894) (xy 129.575052 -157.647894) (xy 129.574542 -157.673881) (xy 129.566412 -157.725216)
			(xy 129.550351 -157.774646) (xy 129.526755 -157.820956) (xy 129.496205 -157.863004) (xy 129.459454 -157.899755)
			(xy 129.417406 -157.930305) (xy 129.371096 -157.953901) (xy 129.321666 -157.969962) (xy 129.270331 -157.978092)
			(xy 129.218357 -157.978092) (xy 129.167022 -157.969962) (xy 129.117592 -157.953901) (xy 129.071282 -157.930305)
			(xy 129.029234 -157.899755) (xy 128.992483 -157.863004) (xy 128.961933 -157.820956) (xy 128.938337 -157.774646)
			(xy 128.922276 -157.725216) (xy 128.914146 -157.673881) (xy 128.913636 -157.647894) (xy 128.67513 -157.647894)
			(xy 128.67462 -157.673881) (xy 128.66649 -157.725216) (xy 128.650429 -157.774646) (xy 128.626833 -157.820956)
			(xy 128.596283 -157.863004) (xy 128.559532 -157.899755) (xy 128.517484 -157.930305) (xy 128.471174 -157.953901)
			(xy 128.421744 -157.969962) (xy 128.370409 -157.978092) (xy 128.318435 -157.978092) (xy 128.2671 -157.969962)
			(xy 128.21767 -157.953901) (xy 128.17136 -157.930305) (xy 128.129312 -157.899755) (xy 128.092561 -157.863004)
			(xy 128.062011 -157.820956) (xy 128.038415 -157.774646) (xy 128.022354 -157.725216) (xy 128.014224 -157.673881)
			(xy 128.013714 -157.647894) (xy 127.775208 -157.647894) (xy 127.774698 -157.673881) (xy 127.766568 -157.725216)
			(xy 127.750507 -157.774646) (xy 127.726911 -157.820956) (xy 127.696361 -157.863004) (xy 127.65961 -157.899755)
			(xy 127.617562 -157.930305) (xy 127.571252 -157.953901) (xy 127.521822 -157.969962) (xy 127.470487 -157.978092)
			(xy 127.418513 -157.978092) (xy 127.367178 -157.969962) (xy 127.317748 -157.953901) (xy 127.271438 -157.930305)
			(xy 127.22939 -157.899755) (xy 127.192639 -157.863004) (xy 127.162089 -157.820956) (xy 127.138493 -157.774646)
			(xy 127.122432 -157.725216) (xy 127.114302 -157.673881) (xy 127.113792 -157.647894) (xy 123.475477 -157.647894)
			(xy 123.488899 -157.676525) (xy 123.504967 -157.729932) (xy 123.513087 -157.785108) (xy 123.513596 -157.812994)
			(xy 123.513087 -157.84088) (xy 123.504967 -157.896056) (xy 123.488899 -157.949463) (xy 123.465227 -157.99996)
			(xy 123.434454 -158.046473) (xy 123.421984 -158.06039) (xy 124.93955 -158.06039) (xy 124.943621 -158.004768)
			(xy 124.955747 -157.950331) (xy 124.97567 -157.89824) (xy 125.002966 -157.849605) (xy 125.037052 -157.805462)
			(xy 125.077201 -157.766753) (xy 125.122559 -157.734302) (xy 125.172159 -157.708801) (xy 125.224943 -157.690794)
			(xy 125.279786 -157.680664) (xy 125.33552 -157.678627) (xy 125.390957 -157.684727) (xy 125.444914 -157.698833)
			(xy 125.496243 -157.720645) (xy 125.543849 -157.749699) (xy 125.586717 -157.785374) (xy 125.623934 -157.826911)
			(xy 125.654707 -157.873424) (xy 125.678379 -157.923921) (xy 125.694447 -157.977328) (xy 125.702567 -158.032504)
			(xy 125.703076 -158.06039) (xy 125.702567 -158.088276) (xy 125.694447 -158.143452) (xy 125.678379 -158.196859)
			(xy 125.654707 -158.247356) (xy 125.623934 -158.293869) (xy 125.586717 -158.335406) (xy 125.543849 -158.371081)
			(xy 125.496243 -158.400135) (xy 125.444914 -158.421947) (xy 125.390957 -158.436053) (xy 125.33552 -158.442153)
			(xy 125.279786 -158.440116) (xy 125.224943 -158.429986) (xy 125.172159 -158.411979) (xy 125.122559 -158.386478)
			(xy 125.077201 -158.354027) (xy 125.037052 -158.315318) (xy 125.002966 -158.271175) (xy 124.97567 -158.22254)
			(xy 124.955747 -158.170449) (xy 124.943621 -158.116012) (xy 124.93955 -158.06039) (xy 123.421984 -158.06039)
			(xy 123.397237 -158.08801) (xy 123.354369 -158.123685) (xy 123.306763 -158.152739) (xy 123.255434 -158.174551)
			(xy 123.201477 -158.188657) (xy 123.14604 -158.194757) (xy 123.090306 -158.19272) (xy 123.035463 -158.18259)
			(xy 122.982679 -158.164583) (xy 122.933079 -158.139082) (xy 122.887721 -158.106631) (xy 122.847572 -158.067922)
			(xy 122.813486 -158.023779) (xy 122.78619 -157.975144) (xy 122.766267 -157.923053) (xy 122.754141 -157.868616)
			(xy 122.75007 -157.812994) (xy 122.485404 -157.812994) (xy 122.485404 -158.828994) (xy 122.75007 -158.828994)
			(xy 122.754141 -158.773372) (xy 122.766267 -158.718935) (xy 122.78619 -158.666844) (xy 122.813486 -158.618209)
			(xy 122.847572 -158.574066) (xy 122.887721 -158.535357) (xy 122.933079 -158.502906) (xy 122.982679 -158.477405)
			(xy 123.035463 -158.459398) (xy 123.090306 -158.449268) (xy 123.14604 -158.447231) (xy 123.201477 -158.453331)
			(xy 123.255434 -158.467437) (xy 123.306763 -158.489249) (xy 123.354369 -158.518303) (xy 123.397237 -158.553978)
			(xy 123.434454 -158.595515) (xy 123.465227 -158.642028) (xy 123.488899 -158.692525) (xy 123.504967 -158.745932)
			(xy 123.506052 -158.753302) (xy 132.616446 -158.753302) (xy 132.620517 -158.69768) (xy 132.632643 -158.643243)
			(xy 132.652566 -158.591152) (xy 132.679862 -158.542517) (xy 132.713948 -158.498374) (xy 132.754097 -158.459665)
			(xy 132.799455 -158.427214) (xy 132.849055 -158.401713) (xy 132.901839 -158.383706) (xy 132.956682 -158.373576)
			(xy 133.012416 -158.371539) (xy 133.067853 -158.377639) (xy 133.12181 -158.391745) (xy 133.173139 -158.413557)
			(xy 133.220745 -158.442611) (xy 133.263613 -158.478286) (xy 133.30083 -158.519823) (xy 133.331603 -158.566336)
			(xy 133.355275 -158.616833) (xy 133.371343 -158.67024) (xy 133.379463 -158.725416) (xy 133.379972 -158.753302)
			(xy 133.379463 -158.781188) (xy 133.371343 -158.836364) (xy 133.355275 -158.889771) (xy 133.331603 -158.940268)
			(xy 133.30083 -158.986781) (xy 133.263613 -159.028318) (xy 133.220745 -159.063993) (xy 133.173139 -159.093047)
			(xy 133.12181 -159.114859) (xy 133.067853 -159.128965) (xy 133.012416 -159.135065) (xy 132.956682 -159.133028)
			(xy 132.901839 -159.122898) (xy 132.849055 -159.104891) (xy 132.799455 -159.07939) (xy 132.754097 -159.046939)
			(xy 132.713948 -159.00823) (xy 132.679862 -158.964087) (xy 132.652566 -158.915452) (xy 132.632643 -158.863361)
			(xy 132.620517 -158.808924) (xy 132.616446 -158.753302) (xy 123.506052 -158.753302) (xy 123.513087 -158.801108)
			(xy 123.513596 -158.828994) (xy 123.513087 -158.85688) (xy 123.504967 -158.912056) (xy 123.488899 -158.965463)
			(xy 123.465227 -159.01596) (xy 123.434454 -159.062473) (xy 123.397237 -159.10401) (xy 123.354369 -159.139685)
			(xy 123.306763 -159.168739) (xy 123.255434 -159.190551) (xy 123.201477 -159.204657) (xy 123.14604 -159.210757)
			(xy 123.090306 -159.20872) (xy 123.035463 -159.19859) (xy 122.982679 -159.180583) (xy 122.933079 -159.155082)
			(xy 122.887721 -159.122631) (xy 122.847572 -159.083922) (xy 122.813486 -159.039779) (xy 122.78619 -158.991144)
			(xy 122.766267 -158.939053) (xy 122.754141 -158.884616) (xy 122.75007 -158.828994) (xy 122.485404 -158.828994)
			(xy 122.485404 -159.439102) (xy 125.007876 -159.439102) (xy 125.011947 -159.38348) (xy 125.024073 -159.329043)
			(xy 125.043996 -159.276952) (xy 125.071292 -159.228317) (xy 125.105378 -159.184174) (xy 125.145527 -159.145465)
			(xy 125.190885 -159.113014) (xy 125.240485 -159.087513) (xy 125.293269 -159.069506) (xy 125.348112 -159.059376)
			(xy 125.403846 -159.057339) (xy 125.459283 -159.063439) (xy 125.51324 -159.077545) (xy 125.564569 -159.099357)
			(xy 125.612175 -159.128411) (xy 125.655043 -159.164086) (xy 125.69226 -159.205623) (xy 125.723033 -159.252136)
			(xy 125.746705 -159.302633) (xy 125.762773 -159.35604) (xy 125.770893 -159.411216) (xy 125.771402 -159.439102)
			(xy 125.770893 -159.466988) (xy 125.762773 -159.522164) (xy 125.75987 -159.531812) (xy 128.212594 -159.531812)
			(xy 128.216665 -159.47619) (xy 128.228791 -159.421753) (xy 128.248714 -159.369662) (xy 128.27601 -159.321027)
			(xy 128.310096 -159.276884) (xy 128.350245 -159.238175) (xy 128.395603 -159.205724) (xy 128.445203 -159.180223)
			(xy 128.497987 -159.162216) (xy 128.55283 -159.152086) (xy 128.608564 -159.150049) (xy 128.664001 -159.156149)
			(xy 128.717958 -159.170255) (xy 128.769287 -159.192067) (xy 128.816893 -159.221121) (xy 128.859761 -159.256796)
			(xy 128.896978 -159.298333) (xy 128.927751 -159.344846) (xy 128.951423 -159.395343) (xy 128.967491 -159.44875)
			(xy 128.97336 -159.488632) (xy 130.4958 -159.488632) (xy 130.499871 -159.43301) (xy 130.511997 -159.378573)
			(xy 130.53192 -159.326482) (xy 130.559216 -159.277847) (xy 130.593302 -159.233704) (xy 130.633451 -159.194995)
			(xy 130.678809 -159.162544) (xy 130.728409 -159.137043) (xy 130.781193 -159.119036) (xy 130.836036 -159.108906)
			(xy 130.89177 -159.106869) (xy 130.947207 -159.112969) (xy 131.001164 -159.127075) (xy 131.052493 -159.148887)
			(xy 131.100099 -159.177941) (xy 131.142967 -159.213616) (xy 131.180184 -159.255153) (xy 131.210957 -159.301666)
			(xy 131.234629 -159.352163) (xy 131.250697 -159.40557) (xy 131.258817 -159.460746) (xy 131.259326 -159.488632)
			(xy 131.258817 -159.516518) (xy 131.250697 -159.571694) (xy 131.234629 -159.625101) (xy 131.210957 -159.675598)
			(xy 131.180184 -159.722111) (xy 131.142967 -159.763648) (xy 131.100099 -159.799323) (xy 131.052493 -159.828377)
			(xy 131.001164 -159.850189) (xy 130.947207 -159.864295) (xy 130.89177 -159.870395) (xy 130.836036 -159.868358)
			(xy 130.781193 -159.858228) (xy 130.728409 -159.840221) (xy 130.678809 -159.81472) (xy 130.633451 -159.782269)
			(xy 130.593302 -159.74356) (xy 130.559216 -159.699417) (xy 130.53192 -159.650782) (xy 130.511997 -159.598691)
			(xy 130.499871 -159.544254) (xy 130.4958 -159.488632) (xy 128.97336 -159.488632) (xy 128.975611 -159.503926)
			(xy 128.97612 -159.531812) (xy 128.975611 -159.559698) (xy 128.967491 -159.614874) (xy 128.951423 -159.668281)
			(xy 128.927751 -159.718778) (xy 128.896978 -159.765291) (xy 128.859761 -159.806828) (xy 128.816893 -159.842503)
			(xy 128.769287 -159.871557) (xy 128.717958 -159.893369) (xy 128.664001 -159.907475) (xy 128.608564 -159.913575)
			(xy 128.55283 -159.911538) (xy 128.497987 -159.901408) (xy 128.445203 -159.883401) (xy 128.395603 -159.8579)
			(xy 128.350245 -159.825449) (xy 128.310096 -159.78674) (xy 128.27601 -159.742597) (xy 128.248714 -159.693962)
			(xy 128.228791 -159.641871) (xy 128.216665 -159.587434) (xy 128.212594 -159.531812) (xy 125.75987 -159.531812)
			(xy 125.746705 -159.575571) (xy 125.723033 -159.626068) (xy 125.69226 -159.672581) (xy 125.655043 -159.714118)
			(xy 125.612175 -159.749793) (xy 125.564569 -159.778847) (xy 125.51324 -159.800659) (xy 125.459283 -159.814765)
			(xy 125.403846 -159.820865) (xy 125.348112 -159.818828) (xy 125.293269 -159.808698) (xy 125.240485 -159.790691)
			(xy 125.190885 -159.76519) (xy 125.145527 -159.732739) (xy 125.105378 -159.69403) (xy 125.071292 -159.649887)
			(xy 125.043996 -159.601252) (xy 125.024073 -159.549161) (xy 125.011947 -159.494724) (xy 125.007876 -159.439102)
			(xy 122.485404 -159.439102) (xy 122.485404 -159.844994) (xy 122.75007 -159.844994) (xy 122.754141 -159.789372)
			(xy 122.766267 -159.734935) (xy 122.78619 -159.682844) (xy 122.813486 -159.634209) (xy 122.847572 -159.590066)
			(xy 122.887721 -159.551357) (xy 122.933079 -159.518906) (xy 122.982679 -159.493405) (xy 123.035463 -159.475398)
			(xy 123.090306 -159.465268) (xy 123.14604 -159.463231) (xy 123.201477 -159.469331) (xy 123.255434 -159.483437)
			(xy 123.306763 -159.505249) (xy 123.354369 -159.534303) (xy 123.397237 -159.569978) (xy 123.434454 -159.611515)
			(xy 123.465227 -159.658028) (xy 123.488899 -159.708525) (xy 123.504967 -159.761932) (xy 123.513087 -159.817108)
			(xy 123.513596 -159.844994) (xy 123.513087 -159.87288) (xy 123.504967 -159.928056) (xy 123.488899 -159.981463)
			(xy 123.465227 -160.03196) (xy 123.434454 -160.078473) (xy 123.397237 -160.12001) (xy 123.354369 -160.155685)
			(xy 123.306763 -160.184739) (xy 123.255434 -160.206551) (xy 123.201477 -160.220657) (xy 123.14604 -160.226757)
			(xy 123.090306 -160.22472) (xy 123.035463 -160.21459) (xy 122.982679 -160.196583) (xy 122.933079 -160.171082)
			(xy 122.887721 -160.138631) (xy 122.847572 -160.099922) (xy 122.813486 -160.055779) (xy 122.78619 -160.007144)
			(xy 122.766267 -159.955053) (xy 122.754141 -159.900616) (xy 122.75007 -159.844994) (xy 122.485404 -159.844994)
			(xy 122.485404 -160.965896) (xy 125.037594 -160.965896) (xy 125.041665 -160.910274) (xy 125.053791 -160.855837)
			(xy 125.073714 -160.803746) (xy 125.10101 -160.755111) (xy 125.135096 -160.710968) (xy 125.175245 -160.672259)
			(xy 125.220603 -160.639808) (xy 125.270203 -160.614307) (xy 125.322987 -160.5963) (xy 125.37783 -160.58617)
			(xy 125.433564 -160.584133) (xy 125.489001 -160.590233) (xy 125.542958 -160.604339) (xy 125.594287 -160.626151)
			(xy 125.641893 -160.655205) (xy 125.684761 -160.69088) (xy 125.721978 -160.732417) (xy 125.752751 -160.77893)
			(xy 125.776423 -160.829427) (xy 125.792491 -160.882834) (xy 125.800611 -160.93801) (xy 125.801083 -160.963864)
			(xy 126.429514 -160.963864) (xy 126.433585 -160.908242) (xy 126.445711 -160.853805) (xy 126.465634 -160.801714)
			(xy 126.49293 -160.753079) (xy 126.527016 -160.708936) (xy 126.567165 -160.670227) (xy 126.612523 -160.637776)
			(xy 126.662123 -160.612275) (xy 126.714907 -160.594268) (xy 126.76975 -160.584138) (xy 126.825484 -160.582101)
			(xy 126.880921 -160.588201) (xy 126.934878 -160.602307) (xy 126.986207 -160.624119) (xy 127.033813 -160.653173)
			(xy 127.076681 -160.688848) (xy 127.113898 -160.730385) (xy 127.144671 -160.776898) (xy 127.168343 -160.827395)
			(xy 127.184411 -160.880802) (xy 127.192531 -160.935978) (xy 127.19304 -160.963864) (xy 127.192947 -160.968944)
			(xy 127.701292 -160.968944) (xy 127.705363 -160.913322) (xy 127.717489 -160.858885) (xy 127.737412 -160.806794)
			(xy 127.764708 -160.758159) (xy 127.798794 -160.714016) (xy 127.838943 -160.675307) (xy 127.884301 -160.642856)
			(xy 127.933901 -160.617355) (xy 127.986685 -160.599348) (xy 128.041528 -160.589218) (xy 128.097262 -160.587181)
			(xy 128.152699 -160.593281) (xy 128.206656 -160.607387) (xy 128.257985 -160.629199) (xy 128.305591 -160.658253)
			(xy 128.348459 -160.693928) (xy 128.385676 -160.735465) (xy 128.416449 -160.781978) (xy 128.440121 -160.832475)
			(xy 128.456189 -160.885882) (xy 128.458582 -160.902142) (xy 129.482594 -160.902142) (xy 129.486665 -160.84652)
			(xy 129.498791 -160.792083) (xy 129.518714 -160.739992) (xy 129.54601 -160.691357) (xy 129.580096 -160.647214)
			(xy 129.620245 -160.608505) (xy 129.665603 -160.576054) (xy 129.715203 -160.550553) (xy 129.767987 -160.532546)
			(xy 129.82283 -160.522416) (xy 129.878564 -160.520379) (xy 129.934001 -160.526479) (xy 129.987958 -160.540585)
			(xy 130.039287 -160.562397) (xy 130.086893 -160.591451) (xy 130.129761 -160.627126) (xy 130.166978 -160.668663)
			(xy 130.197751 -160.715176) (xy 130.221423 -160.765673) (xy 130.237491 -160.81908) (xy 130.245611 -160.874256)
			(xy 130.24612 -160.902142) (xy 130.245611 -160.930028) (xy 130.237491 -160.985204) (xy 130.221423 -161.038611)
			(xy 130.197751 -161.089108) (xy 130.166978 -161.135621) (xy 130.129761 -161.177158) (xy 130.086893 -161.212833)
			(xy 130.039287 -161.241887) (xy 129.987958 -161.263699) (xy 129.934001 -161.277805) (xy 129.878564 -161.283905)
			(xy 129.82283 -161.281868) (xy 129.767987 -161.271738) (xy 129.715203 -161.253731) (xy 129.665603 -161.22823)
			(xy 129.620245 -161.195779) (xy 129.580096 -161.15707) (xy 129.54601 -161.112927) (xy 129.518714 -161.064292)
			(xy 129.498791 -161.012201) (xy 129.486665 -160.957764) (xy 129.482594 -160.902142) (xy 128.458582 -160.902142)
			(xy 128.464309 -160.941058) (xy 128.464818 -160.968944) (xy 128.464309 -160.99683) (xy 128.456189 -161.052006)
			(xy 128.440121 -161.105413) (xy 128.416449 -161.15591) (xy 128.385676 -161.202423) (xy 128.348459 -161.24396)
			(xy 128.305591 -161.279635) (xy 128.257985 -161.308689) (xy 128.206656 -161.330501) (xy 128.152699 -161.344607)
			(xy 128.097262 -161.350707) (xy 128.041528 -161.34867) (xy 127.986685 -161.33854) (xy 127.933901 -161.320533)
			(xy 127.884301 -161.295032) (xy 127.838943 -161.262581) (xy 127.798794 -161.223872) (xy 127.764708 -161.179729)
			(xy 127.737412 -161.131094) (xy 127.717489 -161.079003) (xy 127.705363 -161.024566) (xy 127.701292 -160.968944)
			(xy 127.192947 -160.968944) (xy 127.192531 -160.99175) (xy 127.184411 -161.046926) (xy 127.168343 -161.100333)
			(xy 127.144671 -161.15083) (xy 127.113898 -161.197343) (xy 127.076681 -161.23888) (xy 127.033813 -161.274555)
			(xy 126.986207 -161.303609) (xy 126.934878 -161.325421) (xy 126.880921 -161.339527) (xy 126.825484 -161.345627)
			(xy 126.76975 -161.34359) (xy 126.714907 -161.33346) (xy 126.662123 -161.315453) (xy 126.612523 -161.289952)
			(xy 126.567165 -161.257501) (xy 126.527016 -161.218792) (xy 126.49293 -161.174649) (xy 126.465634 -161.126014)
			(xy 126.445711 -161.073923) (xy 126.433585 -161.019486) (xy 126.429514 -160.963864) (xy 125.801083 -160.963864)
			(xy 125.80112 -160.965896) (xy 125.800611 -160.993782) (xy 125.792491 -161.048958) (xy 125.776423 -161.102365)
			(xy 125.752751 -161.152862) (xy 125.721978 -161.199375) (xy 125.684761 -161.240912) (xy 125.641893 -161.276587)
			(xy 125.594287 -161.305641) (xy 125.542958 -161.327453) (xy 125.489001 -161.341559) (xy 125.433564 -161.347659)
			(xy 125.37783 -161.345622) (xy 125.322987 -161.335492) (xy 125.270203 -161.317485) (xy 125.220603 -161.291984)
			(xy 125.175245 -161.259533) (xy 125.135096 -161.220824) (xy 125.10101 -161.176681) (xy 125.073714 -161.128046)
			(xy 125.053791 -161.075955) (xy 125.041665 -161.021518) (xy 125.037594 -160.965896) (xy 122.485404 -160.965896)
			(xy 122.485404 -161.024062) (xy 122.485839 -161.034127) (xy 122.493569 -161.052715) (xy 122.50039 -161.06013)
			(xy 124.554996 -163.114736) (xy 132.149594 -163.114736) (xy 132.153665 -163.059114) (xy 132.165791 -163.004677)
			(xy 132.185714 -162.952586) (xy 132.21301 -162.903951) (xy 132.247096 -162.859808) (xy 132.287245 -162.821099)
			(xy 132.332603 -162.788648) (xy 132.382203 -162.763147) (xy 132.434987 -162.74514) (xy 132.48983 -162.73501)
			(xy 132.545564 -162.732973) (xy 132.601001 -162.739073) (xy 132.654958 -162.753179) (xy 132.706287 -162.774991)
			(xy 132.753893 -162.804045) (xy 132.796761 -162.83972) (xy 132.833978 -162.881257) (xy 132.864751 -162.92777)
			(xy 132.888423 -162.978267) (xy 132.904491 -163.031674) (xy 132.912611 -163.08685) (xy 132.91312 -163.114736)
			(xy 132.912611 -163.142622) (xy 132.904491 -163.197798) (xy 132.888423 -163.251205) (xy 132.864751 -163.301702)
			(xy 132.833978 -163.348215) (xy 132.796761 -163.389752) (xy 132.753893 -163.425427) (xy 132.706287 -163.454481)
			(xy 132.654958 -163.476293) (xy 132.601001 -163.490399) (xy 132.545564 -163.496499) (xy 132.48983 -163.494462)
			(xy 132.434987 -163.484332) (xy 132.382203 -163.466325) (xy 132.332603 -163.440824) (xy 132.287245 -163.408373)
			(xy 132.247096 -163.369664) (xy 132.21301 -163.325521) (xy 132.185714 -163.276886) (xy 132.165791 -163.224795)
			(xy 132.153665 -163.170358) (xy 132.149594 -163.114736) (xy 124.554996 -163.114736) (xy 125.55347 -164.11321)
			(xy 125.560868 -164.120055) (xy 125.579467 -164.127778) (xy 125.589538 -164.128196) (xy 136.73074 -164.128196)
			(xy 136.765485 -164.128717) (xy 136.834493 -164.136904) (xy 136.902064 -164.153124) (xy 136.967268 -164.177154)
			(xy 137.029206 -164.208663) (xy 137.0584 -164.22751) (xy 138.311636 -165.064694) (xy 138.340316 -165.08448)
			(xy 138.393286 -165.12975) (xy 138.440568 -165.180932) (xy 138.481506 -165.237316) (xy 138.515532 -165.298122)
			(xy 138.529314 -165.330124) (xy 139.561316 -167.821356) (xy 139.565329 -167.829985) (xy 139.57852 -167.843682)
			(xy 139.59579 -167.851644) (xy 139.605258 -167.852598) (xy 139.69619 -167.858186) (xy 139.705658 -167.858433)
			(xy 139.723704 -167.852725) (xy 139.738416 -167.840819) (xy 139.743434 -167.832786) (xy 139.758106 -167.808144)
			(xy 139.793685 -167.763167) (xy 139.835593 -167.724019) (xy 139.882887 -167.691583) (xy 139.934503 -167.666588)
			(xy 139.989276 -167.649598) (xy 140.045976 -167.640995) (xy 140.07465 -167.640508) (xy 140.101904 -167.640968)
			(xy 140.155858 -167.648719) (xy 140.20816 -167.66407) (xy 140.257744 -167.686709) (xy 140.303602 -167.716174)
			(xy 140.344799 -167.751866) (xy 140.380496 -167.793058) (xy 140.409967 -167.838912) (xy 140.432613 -167.888493)
			(xy 140.447971 -167.940793) (xy 140.455729 -167.994746) (xy 140.455729 -168.049254) (xy 140.447971 -168.103207)
			(xy 140.432613 -168.155507) (xy 140.409967 -168.205088) (xy 140.380496 -168.250942) (xy 140.344799 -168.292134)
			(xy 140.303602 -168.327826) (xy 140.257744 -168.357291) (xy 140.20816 -168.37993) (xy 140.155858 -168.395281)
			(xy 140.101904 -168.403032) (xy 140.07465 -168.403524) (xy 140.074396 -168.403524) (xy 140.049003 -168.403125)
			(xy 139.998667 -168.396368) (xy 139.974066 -168.390062) (xy 139.960096 -168.386252) (xy 139.93241 -168.39438)
			(xy 139.862306 -168.473882) (xy 139.856355 -168.481272) (xy 139.849913 -168.499105) (xy 139.850396 -168.51806)
			(xy 139.85367 -168.526968) (xy 141.134846 -171.620688) (xy 141.149086 -171.656654) (xy 141.169101 -171.731375)
			(xy 141.179193 -171.80807) (xy 141.179804 -171.846748) (xy 141.179804 -174.805086) (xy 141.546072 -174.805086)
			(xy 141.546072 -173.941486) (xy 141.546562 -173.911518) (xy 141.554385 -173.852096) (xy 141.569898 -173.794203)
			(xy 141.592834 -173.73883) (xy 141.622801 -173.686924) (xy 141.659288 -173.639374) (xy 141.701668 -173.596994)
			(xy 141.749218 -173.560507) (xy 141.801124 -173.53054) (xy 141.856497 -173.507604) (xy 141.91439 -173.492091)
			(xy 141.973812 -173.484268) (xy 142.033748 -173.484268) (xy 142.09317 -173.492091) (xy 142.151063 -173.507604)
			(xy 142.206436 -173.53054) (xy 142.258342 -173.560507) (xy 142.305892 -173.596994) (xy 142.348272 -173.639374)
			(xy 142.384759 -173.686924) (xy 142.414726 -173.73883) (xy 142.437662 -173.794203) (xy 142.453175 -173.852096)
			(xy 142.460998 -173.911518) (xy 142.461488 -173.941486) (xy 142.461488 -174.805086) (xy 142.460998 -174.835054)
			(xy 142.453175 -174.894476) (xy 142.437662 -174.952369) (xy 142.414726 -175.007742) (xy 142.384759 -175.059648)
			(xy 142.348272 -175.107198) (xy 142.305892 -175.149578) (xy 142.258342 -175.186065) (xy 142.206436 -175.216032)
			(xy 142.151063 -175.238968) (xy 142.09317 -175.254481) (xy 142.033748 -175.262304) (xy 141.973812 -175.262304)
			(xy 141.91439 -175.254481) (xy 141.856497 -175.238968) (xy 141.801124 -175.216032) (xy 141.749218 -175.186065)
			(xy 141.701668 -175.149578) (xy 141.659288 -175.107198) (xy 141.622801 -175.059648) (xy 141.592834 -175.007742)
			(xy 141.569898 -174.952369) (xy 141.554385 -174.894476) (xy 141.546562 -174.835054) (xy 141.546072 -174.805086)
			(xy 141.179804 -174.805086) (xy 141.179804 -176.837086) (xy 142.181072 -176.837086) (xy 142.181072 -175.973486)
			(xy 142.181562 -175.943518) (xy 142.189385 -175.884096) (xy 142.204898 -175.826203) (xy 142.227834 -175.77083)
			(xy 142.257801 -175.718924) (xy 142.294288 -175.671374) (xy 142.336668 -175.628994) (xy 142.384218 -175.592507)
			(xy 142.436124 -175.56254) (xy 142.491497 -175.539604) (xy 142.54939 -175.524091) (xy 142.608812 -175.516268)
			(xy 142.668748 -175.516268) (xy 142.72817 -175.524091) (xy 142.786063 -175.539604) (xy 142.841436 -175.56254)
			(xy 142.893342 -175.592507) (xy 142.940892 -175.628994) (xy 142.983272 -175.671374) (xy 143.019759 -175.718924)
			(xy 143.049726 -175.77083) (xy 143.072662 -175.826203) (xy 143.088175 -175.884096) (xy 143.095998 -175.943518)
			(xy 143.096488 -175.973486) (xy 143.096488 -176.837086) (xy 143.095998 -176.867054) (xy 143.088175 -176.926476)
			(xy 143.072662 -176.984369) (xy 143.049726 -177.039742) (xy 143.019759 -177.091648) (xy 142.983272 -177.139198)
			(xy 142.940892 -177.181578) (xy 142.893342 -177.218065) (xy 142.841436 -177.248032) (xy 142.786063 -177.270968)
			(xy 142.72817 -177.286481) (xy 142.668748 -177.294304) (xy 142.608812 -177.294304) (xy 142.54939 -177.286481)
			(xy 142.491497 -177.270968) (xy 142.436124 -177.248032) (xy 142.384218 -177.218065) (xy 142.336668 -177.181578)
			(xy 142.294288 -177.139198) (xy 142.257801 -177.091648) (xy 142.227834 -177.039742) (xy 142.204898 -176.984369)
			(xy 142.189385 -176.926476) (xy 142.181562 -176.867054) (xy 142.181072 -176.837086) (xy 141.179804 -176.837086)
			(xy 141.179804 -178.869086) (xy 141.546072 -178.869086) (xy 141.546072 -178.005486) (xy 141.546562 -177.975518)
			(xy 141.554385 -177.916096) (xy 141.569898 -177.858203) (xy 141.592834 -177.80283) (xy 141.622801 -177.750924)
			(xy 141.659288 -177.703374) (xy 141.701668 -177.660994) (xy 141.749218 -177.624507) (xy 141.801124 -177.59454)
			(xy 141.856497 -177.571604) (xy 141.91439 -177.556091) (xy 141.973812 -177.548268) (xy 142.033748 -177.548268)
			(xy 142.09317 -177.556091) (xy 142.151063 -177.571604) (xy 142.206436 -177.59454) (xy 142.258342 -177.624507)
			(xy 142.305892 -177.660994) (xy 142.348272 -177.703374) (xy 142.384759 -177.750924) (xy 142.414726 -177.80283)
			(xy 142.437662 -177.858203) (xy 142.453175 -177.916096) (xy 142.460998 -177.975518) (xy 142.461488 -178.005486)
			(xy 142.461488 -178.869086) (xy 142.460998 -178.899054) (xy 142.453175 -178.958476) (xy 142.437662 -179.016369)
			(xy 142.414726 -179.071742) (xy 142.384759 -179.123648) (xy 142.348272 -179.171198) (xy 142.305892 -179.213578)
			(xy 142.258342 -179.250065) (xy 142.206436 -179.280032) (xy 142.151063 -179.302968) (xy 142.09317 -179.318481)
			(xy 142.033748 -179.326304) (xy 141.973812 -179.326304) (xy 141.91439 -179.318481) (xy 141.856497 -179.302968)
			(xy 141.801124 -179.280032) (xy 141.749218 -179.250065) (xy 141.701668 -179.213578) (xy 141.659288 -179.171198)
			(xy 141.622801 -179.123648) (xy 141.592834 -179.071742) (xy 141.569898 -179.016369) (xy 141.554385 -178.958476)
			(xy 141.546562 -178.899054) (xy 141.546072 -178.869086) (xy 141.179804 -178.869086) (xy 141.179804 -180.901086)
			(xy 142.181072 -180.901086) (xy 142.181072 -180.037486) (xy 142.181562 -180.007518) (xy 142.189385 -179.948096)
			(xy 142.204898 -179.890203) (xy 142.227834 -179.83483) (xy 142.257801 -179.782924) (xy 142.294288 -179.735374)
			(xy 142.336668 -179.692994) (xy 142.384218 -179.656507) (xy 142.436124 -179.62654) (xy 142.491497 -179.603604)
			(xy 142.54939 -179.588091) (xy 142.608812 -179.580268) (xy 142.668748 -179.580268) (xy 142.72817 -179.588091)
			(xy 142.786063 -179.603604) (xy 142.841436 -179.62654) (xy 142.893342 -179.656507) (xy 142.940892 -179.692994)
			(xy 142.983272 -179.735374) (xy 143.019759 -179.782924) (xy 143.049726 -179.83483) (xy 143.072662 -179.890203)
			(xy 143.088175 -179.948096) (xy 143.095998 -180.007518) (xy 143.096488 -180.037486) (xy 143.096488 -180.901086)
			(xy 143.095998 -180.931054) (xy 143.088175 -180.990476) (xy 143.072662 -181.048369) (xy 143.049726 -181.103742)
			(xy 143.019759 -181.155648) (xy 142.983272 -181.203198) (xy 142.940892 -181.245578) (xy 142.893342 -181.282065)
			(xy 142.841436 -181.312032) (xy 142.786063 -181.334968) (xy 142.72817 -181.350481) (xy 142.668748 -181.358304)
			(xy 142.608812 -181.358304) (xy 142.54939 -181.350481) (xy 142.491497 -181.334968) (xy 142.436124 -181.312032)
			(xy 142.384218 -181.282065) (xy 142.336668 -181.245578) (xy 142.294288 -181.203198) (xy 142.257801 -181.155648)
			(xy 142.227834 -181.103742) (xy 142.204898 -181.048369) (xy 142.189385 -180.990476) (xy 142.181562 -180.931054)
			(xy 142.181072 -180.901086) (xy 141.179804 -180.901086) (xy 141.179804 -182.933594) (xy 141.546072 -182.933594)
			(xy 141.546072 -182.069486) (xy 141.546562 -182.039518) (xy 141.554385 -181.980096) (xy 141.569898 -181.922203)
			(xy 141.592834 -181.86683) (xy 141.622801 -181.814924) (xy 141.659288 -181.767374) (xy 141.701668 -181.724994)
			(xy 141.749218 -181.688507) (xy 141.801124 -181.65854) (xy 141.856497 -181.635604) (xy 141.91439 -181.620091)
			(xy 141.973812 -181.612268) (xy 142.033748 -181.612268) (xy 142.09317 -181.620091) (xy 142.151063 -181.635604)
			(xy 142.206436 -181.65854) (xy 142.258342 -181.688507) (xy 142.305892 -181.724994) (xy 142.348272 -181.767374)
			(xy 142.384759 -181.814924) (xy 142.414726 -181.86683) (xy 142.437662 -181.922203) (xy 142.453175 -181.980096)
			(xy 142.460998 -182.039518) (xy 142.461488 -182.069486) (xy 142.461488 -182.933086) (xy 142.461368 -182.951323)
			(xy 142.458569 -182.987689) (xy 142.4559 -183.00573) (xy 142.45482 -183.015233) (xy 142.458872 -183.033903)
			(xy 142.469488 -183.049788) (xy 142.485187 -183.060676) (xy 142.503785 -183.065049) (xy 142.522692 -183.0623)
			(xy 142.539274 -183.05281) (xy 142.545562 -183.045608) (xy 142.563811 -183.023798) (xy 142.605621 -182.985255)
			(xy 142.652687 -182.953343) (xy 142.703968 -182.928769) (xy 142.758328 -182.912078) (xy 142.814564 -182.903639)
			(xy 142.842996 -182.903114) (xy 142.870251 -182.903533) (xy 142.924205 -182.91129) (xy 142.976507 -182.926646)
			(xy 143.02609 -182.94929) (xy 143.071946 -182.978759) (xy 143.113142 -183.014455) (xy 143.148838 -183.05565)
			(xy 143.178308 -183.101506) (xy 143.200952 -183.15109) (xy 143.21631 -183.203391) (xy 143.224067 -183.257345)
			(xy 143.224067 -183.311855) (xy 143.21631 -183.365809) (xy 143.200952 -183.41811) (xy 143.178308 -183.467694)
			(xy 143.148838 -183.51355) (xy 143.113142 -183.554745) (xy 143.071946 -183.590441) (xy 143.02609 -183.61991)
			(xy 142.976507 -183.642554) (xy 142.924205 -183.65791) (xy 142.870251 -183.665667) (xy 142.842996 -183.66613)
			(xy 142.815988 -183.665684) (xy 142.762509 -183.658078) (xy 142.710639 -183.643002) (xy 142.661414 -183.62076)
			(xy 142.615819 -183.591796) (xy 142.574767 -183.556689) (xy 142.539078 -183.516142) (xy 142.509465 -183.470965)
			(xy 142.486523 -183.422063) (xy 142.470708 -183.370413) (xy 142.46606 -183.343804) (xy 142.464028 -183.330088)
			(xy 142.446756 -183.309006) (xy 142.35049 -183.273192) (xy 142.341985 -183.270451) (xy 142.324127 -183.270396)
			(xy 142.307318 -183.276426) (xy 142.300198 -183.281828) (xy 142.29969 -183.282336) (xy 142.274795 -183.302764)
			(xy 142.220337 -183.337135) (xy 142.161597 -183.363532) (xy 142.099737 -183.381434) (xy 142.035979 -183.390487)
			(xy 142.00378 -183.391048) (xy 141.973824 -183.390538) (xy 141.914425 -183.382718) (xy 141.856553 -183.367216)
			(xy 141.801199 -183.344296) (xy 141.749308 -183.31435) (xy 141.701768 -183.277889) (xy 141.659392 -183.235538)
			(xy 141.622903 -183.18802) (xy 141.592925 -183.136147) (xy 141.569972 -183.080806) (xy 141.554435 -183.022944)
			(xy 141.54658 -182.96355) (xy 141.546072 -182.933594) (xy 141.179804 -182.933594) (xy 141.179804 -186.089848)
			(xy 141.507498 -186.089848) (xy 141.507498 -186.035352) (xy 141.515253 -185.98141) (xy 141.530606 -185.929121)
			(xy 141.553243 -185.879549) (xy 141.582704 -185.833703) (xy 141.61839 -185.792516) (xy 141.659574 -185.756826)
			(xy 141.705417 -185.72736) (xy 141.754987 -185.704718) (xy 141.807275 -185.689361) (xy 141.861216 -185.681601)
			(xy 141.888464 -185.681112) (xy 141.916961 -185.681633) (xy 141.973321 -185.690107) (xy 142.027793 -185.706871)
			(xy 142.079165 -185.731552) (xy 142.126293 -185.763602) (xy 142.168129 -185.802306) (xy 142.203742 -185.846803)
			(xy 142.232338 -185.896104) (xy 142.243302 -185.922412) (xy 142.248869 -185.935335) (xy 142.265945 -185.957689)
			(xy 142.288471 -185.974537) (xy 142.314739 -185.984601) (xy 142.342756 -185.987118) (xy 142.370397 -185.981897)
			(xy 142.395566 -185.969334) (xy 142.416353 -185.950382) (xy 142.42415 -185.938668) (xy 142.439172 -185.915414)
			(xy 142.474842 -185.87308) (xy 142.51626 -185.836349) (xy 142.562554 -185.805994) (xy 142.612752 -185.782653)
			(xy 142.665797 -185.766817) (xy 142.720575 -185.758819) (xy 142.748254 -185.758328) (xy 142.775512 -185.758716)
			(xy 142.829473 -185.766468) (xy 142.881781 -185.781822) (xy 142.931372 -185.804464) (xy 142.977235 -185.833933)
			(xy 143.018437 -185.86963) (xy 143.054139 -185.910828) (xy 143.083614 -185.956688) (xy 143.106262 -186.006276)
			(xy 143.121622 -186.058582) (xy 143.121728 -186.059318) (xy 145.916648 -186.059318) (xy 145.920719 -186.003696)
			(xy 145.932845 -185.949259) (xy 145.952768 -185.897168) (xy 145.980064 -185.848533) (xy 146.01415 -185.80439)
			(xy 146.054299 -185.765681) (xy 146.099657 -185.73323) (xy 146.149257 -185.707729) (xy 146.202041 -185.689722)
			(xy 146.256884 -185.679592) (xy 146.312618 -185.677555) (xy 146.368055 -185.683655) (xy 146.422012 -185.697761)
			(xy 146.473341 -185.719573) (xy 146.520947 -185.748627) (xy 146.563815 -185.784302) (xy 146.601032 -185.825839)
			(xy 146.631805 -185.872352) (xy 146.655477 -185.922849) (xy 146.671545 -185.976256) (xy 146.679665 -186.031432)
			(xy 146.680174 -186.059318) (xy 146.679665 -186.087204) (xy 146.671545 -186.14238) (xy 146.655477 -186.195787)
			(xy 146.631805 -186.246284) (xy 146.601032 -186.292797) (xy 146.563815 -186.334334) (xy 146.520947 -186.370009)
			(xy 146.473341 -186.399063) (xy 146.422012 -186.420875) (xy 146.368055 -186.434981) (xy 146.312618 -186.441081)
			(xy 146.256884 -186.439044) (xy 146.202041 -186.428914) (xy 146.149257 -186.410907) (xy 146.099657 -186.385406)
			(xy 146.054299 -186.352955) (xy 146.01415 -186.314246) (xy 145.980064 -186.270103) (xy 145.952768 -186.221468)
			(xy 145.932845 -186.169377) (xy 145.920719 -186.11494) (xy 145.916648 -186.059318) (xy 143.121728 -186.059318)
			(xy 143.129381 -186.112542) (xy 143.129381 -186.167058) (xy 143.121622 -186.221018) (xy 143.106262 -186.273324)
			(xy 143.083614 -186.322912) (xy 143.054139 -186.368772) (xy 143.018437 -186.40997) (xy 142.977235 -186.445667)
			(xy 142.931372 -186.475136) (xy 142.881781 -186.497778) (xy 142.829473 -186.513132) (xy 142.775512 -186.520884)
			(xy 142.748254 -186.521344) (xy 142.719756 -186.520835) (xy 142.663395 -186.512363) (xy 142.608921 -186.495599)
			(xy 142.557547 -186.470917) (xy 142.510418 -186.438865) (xy 142.468582 -186.400158) (xy 142.432971 -186.355658)
			(xy 142.404378 -186.306354) (xy 142.393416 -186.280044) (xy 142.387818 -186.267133) (xy 142.370752 -186.244772)
			(xy 142.348232 -186.227916) (xy 142.321967 -186.217847) (xy 142.29395 -186.215327) (xy 142.26631 -186.220548)
			(xy 142.241143 -186.233114) (xy 142.220362 -186.252071) (xy 142.212568 -186.263788) (xy 142.197553 -186.287046)
			(xy 142.161879 -186.329378) (xy 142.12046 -186.366107) (xy 142.074164 -186.39646) (xy 142.023966 -186.4198)
			(xy 141.970921 -186.435636) (xy 141.916143 -186.443636) (xy 141.888464 -186.444128) (xy 141.861216 -186.443599)
			(xy 141.807275 -186.435839) (xy 141.754987 -186.420482) (xy 141.705417 -186.39784) (xy 141.659574 -186.368374)
			(xy 141.61839 -186.332684) (xy 141.582704 -186.291497) (xy 141.553243 -186.245651) (xy 141.530606 -186.196079)
			(xy 141.515253 -186.14379) (xy 141.507498 -186.089848) (xy 141.179804 -186.089848) (xy 141.179804 -187.8584)
			(xy 142.670782 -187.8584) (xy 142.674853 -187.802778) (xy 142.686979 -187.748341) (xy 142.706902 -187.69625)
			(xy 142.734198 -187.647615) (xy 142.768284 -187.603472) (xy 142.808433 -187.564763) (xy 142.853791 -187.532312)
			(xy 142.903391 -187.506811) (xy 142.956175 -187.488804) (xy 143.011018 -187.478674) (xy 143.066752 -187.476637)
			(xy 143.122189 -187.482737) (xy 143.176146 -187.496843) (xy 143.227475 -187.518655) (xy 143.275081 -187.547709)
			(xy 143.317949 -187.583384) (xy 143.355166 -187.624921) (xy 143.385939 -187.671434) (xy 143.409611 -187.721931)
			(xy 143.425679 -187.775338) (xy 143.433799 -187.830514) (xy 143.434308 -187.8584) (xy 143.433799 -187.886286)
			(xy 143.425679 -187.941462) (xy 143.409611 -187.994869) (xy 143.385939 -188.045366) (xy 143.355166 -188.091879)
			(xy 143.317949 -188.133416) (xy 143.275081 -188.169091) (xy 143.227475 -188.198145) (xy 143.176146 -188.219957)
			(xy 143.122189 -188.234063) (xy 143.066752 -188.240163) (xy 143.011018 -188.238126) (xy 142.956175 -188.227996)
			(xy 142.903391 -188.209989) (xy 142.853791 -188.184488) (xy 142.808433 -188.152037) (xy 142.768284 -188.113328)
			(xy 142.734198 -188.069185) (xy 142.706902 -188.02055) (xy 142.686979 -187.968459) (xy 142.674853 -187.914022)
			(xy 142.670782 -187.8584) (xy 141.179804 -187.8584) (xy 141.179804 -189.128146) (xy 141.31112 -189.128146)
			(xy 141.315191 -189.072524) (xy 141.327317 -189.018087) (xy 141.34724 -188.965996) (xy 141.374536 -188.917361)
			(xy 141.408622 -188.873218) (xy 141.448771 -188.834509) (xy 141.494129 -188.802058) (xy 141.543729 -188.776557)
			(xy 141.596513 -188.75855) (xy 141.651356 -188.74842) (xy 141.70709 -188.746383) (xy 141.762527 -188.752483)
			(xy 141.816484 -188.766589) (xy 141.867813 -188.788401) (xy 141.915419 -188.817455) (xy 141.958287 -188.85313)
			(xy 141.995504 -188.894667) (xy 142.026277 -188.94118) (xy 142.049949 -188.991677) (xy 142.066017 -189.045084)
			(xy 142.074137 -189.10026) (xy 142.074646 -189.128146) (xy 142.074137 -189.156032) (xy 142.066017 -189.211208)
			(xy 142.049949 -189.264615) (xy 142.026277 -189.315112) (xy 141.995504 -189.361625) (xy 141.958287 -189.403162)
			(xy 141.915419 -189.438837) (xy 141.867813 -189.467891) (xy 141.816484 -189.489703) (xy 141.762527 -189.503809)
			(xy 141.70709 -189.509909) (xy 141.651356 -189.507872) (xy 141.596513 -189.497742) (xy 141.543729 -189.479735)
			(xy 141.494129 -189.454234) (xy 141.448771 -189.421783) (xy 141.408622 -189.383074) (xy 141.374536 -189.338931)
			(xy 141.34724 -189.290296) (xy 141.327317 -189.238205) (xy 141.315191 -189.183768) (xy 141.31112 -189.128146)
			(xy 141.179804 -189.128146) (xy 141.179804 -189.848998) (xy 145.357594 -189.848998) (xy 145.361665 -189.793376)
			(xy 145.373791 -189.738939) (xy 145.393714 -189.686848) (xy 145.42101 -189.638213) (xy 145.455096 -189.59407)
			(xy 145.495245 -189.555361) (xy 145.540603 -189.52291) (xy 145.590203 -189.497409) (xy 145.642987 -189.479402)
			(xy 145.69783 -189.469272) (xy 145.753564 -189.467235) (xy 145.809001 -189.473335) (xy 145.862958 -189.487441)
			(xy 145.914287 -189.509253) (xy 145.961893 -189.538307) (xy 146.004761 -189.573982) (xy 146.041978 -189.615519)
			(xy 146.072751 -189.662032) (xy 146.096423 -189.712529) (xy 146.112491 -189.765936) (xy 146.120611 -189.821112)
			(xy 146.12112 -189.848998) (xy 146.120611 -189.876884) (xy 146.112491 -189.93206) (xy 146.096423 -189.985467)
			(xy 146.072751 -190.035964) (xy 146.041978 -190.082477) (xy 146.004761 -190.124014) (xy 145.961893 -190.159689)
			(xy 145.914287 -190.188743) (xy 145.862958 -190.210555) (xy 145.809001 -190.224661) (xy 145.753564 -190.230761)
			(xy 145.69783 -190.228724) (xy 145.642987 -190.218594) (xy 145.590203 -190.200587) (xy 145.540603 -190.175086)
			(xy 145.495245 -190.142635) (xy 145.455096 -190.103926) (xy 145.42101 -190.059783) (xy 145.393714 -190.011148)
			(xy 145.373791 -189.959057) (xy 145.361665 -189.90462) (xy 145.357594 -189.848998) (xy 141.179804 -189.848998)
			(xy 141.179804 -190.716154) (xy 141.286736 -190.716154) (xy 141.290807 -190.660532) (xy 141.302933 -190.606095)
			(xy 141.322856 -190.554004) (xy 141.350152 -190.505369) (xy 141.384238 -190.461226) (xy 141.424387 -190.422517)
			(xy 141.469745 -190.390066) (xy 141.519345 -190.364565) (xy 141.572129 -190.346558) (xy 141.626972 -190.336428)
			(xy 141.682706 -190.334391) (xy 141.738143 -190.340491) (xy 141.7921 -190.354597) (xy 141.843429 -190.376409)
			(xy 141.891035 -190.405463) (xy 141.933903 -190.441138) (xy 141.97112 -190.482675) (xy 142.001893 -190.529188)
			(xy 142.005475 -190.53683) (xy 143.744694 -190.53683) (xy 143.748765 -190.481208) (xy 143.760891 -190.426771)
			(xy 143.780814 -190.37468) (xy 143.80811 -190.326045) (xy 143.842196 -190.281902) (xy 143.882345 -190.243193)
			(xy 143.927703 -190.210742) (xy 143.977303 -190.185241) (xy 144.030087 -190.167234) (xy 144.08493 -190.157104)
			(xy 144.140664 -190.155067) (xy 144.196101 -190.161167) (xy 144.250058 -190.175273) (xy 144.301387 -190.197085)
			(xy 144.348993 -190.226139) (xy 144.391861 -190.261814) (xy 144.429078 -190.303351) (xy 144.459851 -190.349864)
			(xy 144.483523 -190.400361) (xy 144.499591 -190.453768) (xy 144.507711 -190.508944) (xy 144.50822 -190.53683)
			(xy 144.507711 -190.564716) (xy 144.499591 -190.619892) (xy 144.483523 -190.673299) (xy 144.459851 -190.723796)
			(xy 144.429078 -190.770309) (xy 144.391861 -190.811846) (xy 144.348993 -190.847521) (xy 144.301387 -190.876575)
			(xy 144.250058 -190.898387) (xy 144.196101 -190.912493) (xy 144.140664 -190.918593) (xy 144.08493 -190.916556)
			(xy 144.030087 -190.906426) (xy 143.977303 -190.888419) (xy 143.927703 -190.862918) (xy 143.882345 -190.830467)
			(xy 143.842196 -190.791758) (xy 143.80811 -190.747615) (xy 143.780814 -190.69898) (xy 143.760891 -190.646889)
			(xy 143.748765 -190.592452) (xy 143.744694 -190.53683) (xy 142.005475 -190.53683) (xy 142.025565 -190.579685)
			(xy 142.041633 -190.633092) (xy 142.049753 -190.688268) (xy 142.050262 -190.716154) (xy 142.049753 -190.74404)
			(xy 142.041633 -190.799216) (xy 142.025565 -190.852623) (xy 142.001893 -190.90312) (xy 141.97112 -190.949633)
			(xy 141.933903 -190.99117) (xy 141.891035 -191.026845) (xy 141.843429 -191.055899) (xy 141.7921 -191.077711)
			(xy 141.738143 -191.091817) (xy 141.71734 -191.094106) (xy 144.407634 -191.094106) (xy 144.411705 -191.038484)
			(xy 144.423831 -190.984047) (xy 144.443754 -190.931956) (xy 144.47105 -190.883321) (xy 144.505136 -190.839178)
			(xy 144.545285 -190.800469) (xy 144.590643 -190.768018) (xy 144.640243 -190.742517) (xy 144.693027 -190.72451)
			(xy 144.74787 -190.71438) (xy 144.803604 -190.712343) (xy 144.859041 -190.718443) (xy 144.912998 -190.732549)
			(xy 144.964327 -190.754361) (xy 145.011933 -190.783415) (xy 145.054801 -190.81909) (xy 145.092018 -190.860627)
			(xy 145.122791 -190.90714) (xy 145.146463 -190.957637) (xy 145.162531 -191.011044) (xy 145.170651 -191.06622)
			(xy 145.17116 -191.094106) (xy 145.170651 -191.121992) (xy 145.162531 -191.177168) (xy 145.146463 -191.230575)
			(xy 145.122791 -191.281072) (xy 145.092018 -191.327585) (xy 145.054801 -191.369122) (xy 145.011933 -191.404797)
			(xy 144.964327 -191.433851) (xy 144.912998 -191.455663) (xy 144.859041 -191.469769) (xy 144.803604 -191.475869)
			(xy 144.74787 -191.473832) (xy 144.693027 -191.463702) (xy 144.640243 -191.445695) (xy 144.590643 -191.420194)
			(xy 144.545285 -191.387743) (xy 144.505136 -191.349034) (xy 144.47105 -191.304891) (xy 144.443754 -191.256256)
			(xy 144.423831 -191.204165) (xy 144.411705 -191.149728) (xy 144.407634 -191.094106) (xy 141.71734 -191.094106)
			(xy 141.682706 -191.097917) (xy 141.626972 -191.09588) (xy 141.572129 -191.08575) (xy 141.519345 -191.067743)
			(xy 141.469745 -191.042242) (xy 141.424387 -191.009791) (xy 141.384238 -190.971082) (xy 141.350152 -190.926939)
			(xy 141.322856 -190.878304) (xy 141.302933 -190.826213) (xy 141.290807 -190.771776) (xy 141.286736 -190.716154)
			(xy 141.179804 -190.716154) (xy 141.179804 -191.173862) (xy 141.180239 -191.183927) (xy 141.187969 -191.202515)
			(xy 141.19479 -191.20993) (xy 141.92123 -191.93637) (xy 141.94434 -191.960148) (xy 141.985672 -192.012001)
			(xy 142.020939 -192.068156) (xy 142.049698 -192.127906) (xy 142.071586 -192.190499) (xy 142.086329 -192.25515)
			(xy 142.093742 -192.321045) (xy 142.094204 -192.3542) (xy 142.094204 -192.526666) (xy 142.96593 -192.526666)
			(xy 142.970001 -192.471044) (xy 142.982127 -192.416607) (xy 143.00205 -192.364516) (xy 143.029346 -192.315881)
			(xy 143.063432 -192.271738) (xy 143.103581 -192.233029) (xy 143.148939 -192.200578) (xy 143.198539 -192.175077)
			(xy 143.251323 -192.15707) (xy 143.306166 -192.14694) (xy 143.3619 -192.144903) (xy 143.417337 -192.151003)
			(xy 143.471294 -192.165109) (xy 143.522623 -192.186921) (xy 143.570229 -192.215975) (xy 143.613097 -192.25165)
			(xy 143.650314 -192.293187) (xy 143.681087 -192.3397) (xy 143.704759 -192.390197) (xy 143.720827 -192.443604)
			(xy 143.728947 -192.49878) (xy 143.729456 -192.526666) (xy 143.728947 -192.554552) (xy 143.720827 -192.609728)
			(xy 143.704759 -192.663135) (xy 143.681087 -192.713632) (xy 143.650314 -192.760145) (xy 143.613097 -192.801682)
			(xy 143.570229 -192.837357) (xy 143.522623 -192.866411) (xy 143.471294 -192.888223) (xy 143.417337 -192.902329)
			(xy 143.3619 -192.908429) (xy 143.306166 -192.906392) (xy 143.251323 -192.896262) (xy 143.198539 -192.878255)
			(xy 143.148939 -192.852754) (xy 143.103581 -192.820303) (xy 143.063432 -192.781594) (xy 143.029346 -192.737451)
			(xy 143.00205 -192.688816) (xy 142.982127 -192.636725) (xy 142.970001 -192.582288) (xy 142.96593 -192.526666)
			(xy 142.094204 -192.526666) (xy 142.094204 -193.82486) (xy 144.777204 -193.82486) (xy 144.781275 -193.769238)
			(xy 144.793401 -193.714801) (xy 144.813324 -193.66271) (xy 144.84062 -193.614075) (xy 144.874706 -193.569932)
			(xy 144.914855 -193.531223) (xy 144.960213 -193.498772) (xy 145.009813 -193.473271) (xy 145.062597 -193.455264)
			(xy 145.11744 -193.445134) (xy 145.173174 -193.443097) (xy 145.228611 -193.449197) (xy 145.282568 -193.463303)
			(xy 145.333897 -193.485115) (xy 145.381503 -193.514169) (xy 145.424371 -193.549844) (xy 145.461588 -193.591381)
			(xy 145.492361 -193.637894) (xy 145.516033 -193.688391) (xy 145.532101 -193.741798) (xy 145.540221 -193.796974)
			(xy 145.54073 -193.82486) (xy 145.540221 -193.852746) (xy 145.532101 -193.907922) (xy 145.516033 -193.961329)
			(xy 145.492361 -194.011826) (xy 145.461588 -194.058339) (xy 145.424371 -194.099876) (xy 145.381503 -194.135551)
			(xy 145.333897 -194.164605) (xy 145.282568 -194.186417) (xy 145.228611 -194.200523) (xy 145.173174 -194.206623)
			(xy 145.11744 -194.204586) (xy 145.062597 -194.194456) (xy 145.009813 -194.176449) (xy 144.960213 -194.150948)
			(xy 144.914855 -194.118497) (xy 144.874706 -194.079788) (xy 144.84062 -194.035645) (xy 144.813324 -193.98701)
			(xy 144.793401 -193.934919) (xy 144.781275 -193.880482) (xy 144.777204 -193.82486) (xy 142.094204 -193.82486)
			(xy 142.094204 -195.4022) (xy 142.09374 -195.435355) (xy 142.08632 -195.501249) (xy 142.071574 -195.565898)
			(xy 142.049686 -195.628492) (xy 142.020931 -195.688243) (xy 141.985672 -195.744401) (xy 141.944349 -195.796261)
			(xy 141.92123 -195.82003) (xy 139.858743 -197.882764) (xy 143.667986 -197.882764) (xy 143.672057 -197.827142)
			(xy 143.684183 -197.772705) (xy 143.704106 -197.720614) (xy 143.731402 -197.671979) (xy 143.765488 -197.627836)
			(xy 143.805637 -197.589127) (xy 143.850995 -197.556676) (xy 143.900595 -197.531175) (xy 143.953379 -197.513168)
			(xy 144.008222 -197.503038) (xy 144.063956 -197.501001) (xy 144.119393 -197.507101) (xy 144.17335 -197.521207)
			(xy 144.224679 -197.543019) (xy 144.272285 -197.572073) (xy 144.315153 -197.607748) (xy 144.35237 -197.649285)
			(xy 144.383143 -197.695798) (xy 144.406815 -197.746295) (xy 144.422883 -197.799702) (xy 144.431003 -197.854878)
			(xy 144.431512 -197.882764) (xy 144.431003 -197.91065) (xy 144.422883 -197.965826) (xy 144.406815 -198.019233)
			(xy 144.383143 -198.06973) (xy 144.35237 -198.116243) (xy 144.315153 -198.15778) (xy 144.272285 -198.193455)
			(xy 144.224679 -198.222509) (xy 144.17335 -198.244321) (xy 144.119393 -198.258427) (xy 144.063956 -198.264527)
			(xy 144.008222 -198.26249) (xy 143.953379 -198.25236) (xy 143.900595 -198.234353) (xy 143.850995 -198.208852)
			(xy 143.805637 -198.176401) (xy 143.765488 -198.137692) (xy 143.731402 -198.093549) (xy 143.704106 -198.044914)
			(xy 143.684183 -197.992823) (xy 143.672057 -197.938386) (xy 143.667986 -197.882764) (xy 139.858743 -197.882764)
			(xy 139.803886 -197.937628) (xy 139.797035 -197.945024) (xy 139.789297 -197.963623) (xy 139.7889 -197.973696)
			(xy 139.7889 -197.980046) (xy 139.79652 -197.998334) (xy 139.906502 -198.10857) (xy 139.92961 -198.13235)
			(xy 139.970937 -198.184205) (xy 140.006199 -198.24036) (xy 140.034954 -198.30011) (xy 140.05684 -198.362703)
			(xy 140.071581 -198.427352) (xy 140.078993 -198.493245) (xy 140.079476 -198.5264) (xy 140.078959 -198.562105)
			(xy 140.070351 -198.632995) (xy 140.058623 -198.680578) (xy 141.924784 -198.680578) (xy 141.928855 -198.624956)
			(xy 141.940981 -198.570519) (xy 141.960904 -198.518428) (xy 141.9882 -198.469793) (xy 142.022286 -198.42565)
			(xy 142.062435 -198.386941) (xy 142.107793 -198.35449) (xy 142.157393 -198.328989) (xy 142.210177 -198.310982)
			(xy 142.26502 -198.300852) (xy 142.320754 -198.298815) (xy 142.376191 -198.304915) (xy 142.430148 -198.319021)
			(xy 142.481477 -198.340833) (xy 142.529083 -198.369887) (xy 142.571951 -198.405562) (xy 142.609168 -198.447099)
			(xy 142.639941 -198.493612) (xy 142.663613 -198.544109) (xy 142.679681 -198.597516) (xy 142.687801 -198.652692)
			(xy 142.68831 -198.680578) (xy 142.687801 -198.708464) (xy 142.679681 -198.76364) (xy 142.663613 -198.817047)
			(xy 142.639941 -198.867544) (xy 142.609168 -198.914057) (xy 142.571951 -198.955594) (xy 142.529083 -198.991269)
			(xy 142.481477 -199.020323) (xy 142.430148 -199.042135) (xy 142.376191 -199.056241) (xy 142.320754 -199.062341)
			(xy 142.26502 -199.060304) (xy 142.210177 -199.050174) (xy 142.157393 -199.032167) (xy 142.107793 -199.006666)
			(xy 142.062435 -198.974215) (xy 142.022286 -198.935506) (xy 141.9882 -198.891363) (xy 141.960904 -198.842728)
			(xy 141.940981 -198.790637) (xy 141.928855 -198.7362) (xy 141.924784 -198.680578) (xy 140.058623 -198.680578)
			(xy 140.053261 -198.70233) (xy 140.027937 -198.769099) (xy 139.994751 -198.83233) (xy 139.954184 -198.891098)
			(xy 139.906829 -198.944549) (xy 139.853376 -198.991901) (xy 139.794606 -199.032465) (xy 139.731374 -199.065649)
			(xy 139.664603 -199.090969) (xy 139.595267 -199.108056) (xy 139.524377 -199.11666) (xy 139.488672 -199.117204)
			(xy 139.453856 -199.116697) (xy 139.384707 -199.108516) (xy 139.316998 -199.092269) (xy 139.251665 -199.068182)
			(xy 139.189614 -199.036589) (xy 139.131703 -198.997926) (xy 139.104878 -198.975726) (xy 139.097846 -198.970174)
			(xy 139.081063 -198.963938) (xy 139.072112 -198.963534) (xy 139.041632 -198.963534) (xy 139.032682 -198.96393)
			(xy 139.015905 -198.970183) (xy 139.008866 -198.975726) (xy 138.982052 -198.997938) (xy 138.924138 -199.036597)
			(xy 138.862084 -199.068186) (xy 138.796749 -199.092267) (xy 138.729038 -199.108508) (xy 138.659888 -199.116683)
			(xy 138.625072 -199.117204) (xy 138.589369 -199.116663) (xy 138.518483 -199.108053) (xy 138.449152 -199.090962)
			(xy 138.382386 -199.065638) (xy 138.31916 -199.032452) (xy 138.260394 -198.991886) (xy 138.206947 -198.944533)
			(xy 138.159596 -198.891084) (xy 138.119034 -198.832316) (xy 138.08585 -198.769088) (xy 138.06053 -198.702322)
			(xy 138.043442 -198.63299) (xy 138.034835 -198.562103) (xy 138.034268 -198.5264) (xy 138.034732 -198.493245)
			(xy 138.042151 -198.427351) (xy 138.056897 -198.362701) (xy 138.078784 -198.300107) (xy 138.107538 -198.240355)
			(xy 138.142797 -198.184195) (xy 138.184118 -198.132334) (xy 138.207242 -198.10857) (xy 138.310112 -198.0057)
			(xy 138.316888 -197.998275) (xy 138.32448 -197.979678) (xy 138.324844 -197.969632) (xy 138.324844 -197.590918)
			(xy 138.325324 -197.557756) (xy 138.332778 -197.491852) (xy 138.34756 -197.427196) (xy 138.369485 -197.3646)
			(xy 138.398278 -197.304851) (xy 138.433577 -197.2487) (xy 138.474937 -197.196852) (xy 138.498072 -197.173088)
			(xy 140.61567 -195.05549) (xy 140.622518 -195.048092) (xy 140.630254 -195.029494) (xy 140.630656 -195.019422)
			(xy 140.630656 -192.736978) (xy 140.630228 -192.726911) (xy 140.622503 -192.708316) (xy 140.61567 -192.70091)
			(xy 139.88923 -191.97447) (xy 139.86612 -191.950691) (xy 139.824787 -191.898838) (xy 139.789518 -191.842684)
			(xy 139.760758 -191.782935) (xy 139.738867 -191.720341) (xy 139.72412 -191.655691) (xy 139.716704 -191.589796)
			(xy 139.716256 -191.55664) (xy 139.716256 -172.030644) (xy 139.716163 -172.025625) (xy 139.714244 -172.015773)
			(xy 139.712446 -172.011086) (xy 137.284206 -166.14902) (xy 137.281117 -166.142205) (xy 137.271693 -166.130592)
			(xy 137.265664 -166.12616) (xy 136.47801 -165.60038) (xy 136.471648 -165.596407) (xy 136.457312 -165.592024)
			(xy 136.449816 -165.591744) (xy 125.20676 -165.591744) (xy 125.173606 -165.591278) (xy 125.107714 -165.583855)
			(xy 125.043066 -165.569105) (xy 124.980475 -165.547215) (xy 124.920725 -165.51846) (xy 124.864569 -165.483199)
			(xy 124.81271 -165.441877) (xy 124.78893 -165.41877) (xy 121.19483 -161.82467) (xy 121.17172 -161.800891)
			(xy 121.130387 -161.749038) (xy 121.095118 -161.692884) (xy 121.066358 -161.633135) (xy 121.044467 -161.570541)
			(xy 121.02972 -161.505891) (xy 121.022304 -161.439996) (xy 121.021856 -161.40684) (xy 121.021856 -141.454378)
			(xy 121.021428 -141.444311) (xy 121.013703 -141.425716) (xy 121.00687 -141.41831) (xy 120.78843 -141.19987)
			(xy 120.76532 -141.176091) (xy 120.723987 -141.124238) (xy 120.688718 -141.068084) (xy 120.659958 -141.008335)
			(xy 120.638067 -140.945741) (xy 120.62332 -140.881091) (xy 120.615904 -140.815196) (xy 120.615456 -140.78204)
			(xy 120.615456 -132.47116) (xy 120.615922 -132.438006) (xy 120.623345 -132.372114) (xy 120.638095 -132.307466)
			(xy 120.659985 -132.244875) (xy 120.68874 -132.185125) (xy 120.724001 -132.128969) (xy 120.765323 -132.07711)
			(xy 120.78843 -132.05333) (xy 121.03227 -131.80949) (xy 121.039118 -131.802092) (xy 121.046854 -131.783494)
			(xy 121.047256 -131.773422) (xy 121.047256 -125.474476) (xy 121.046826 -125.464435) (xy 121.039111 -125.445893)
			(xy 121.024872 -125.431732) (xy 121.01576 -125.427486) (xy 121.001536 -125.42139) (xy 120.971564 -125.427486)
			(xy 119.390414 -127.008636) (xy 119.386242 -127.012987) (xy 119.379944 -127.023261) (xy 119.377968 -127.028956)
			(xy 119.377968 -127.02921) (xy 119.36953 -127.054766) (xy 119.346475 -127.103396) (xy 119.316816 -127.148305)
			(xy 119.281141 -127.1886) (xy 119.240158 -127.223484) (xy 119.194681 -127.252264) (xy 119.145612 -127.274368)
			(xy 119.093923 -127.289359) (xy 119.040641 -127.296939) (xy 119.013732 -127.297434) (xy 118.986477 -127.296973)
			(xy 118.932521 -127.28922) (xy 118.880218 -127.273867) (xy 118.830632 -127.251227) (xy 118.784773 -127.22176)
			(xy 118.743574 -127.186067) (xy 118.707875 -127.144874) (xy 118.678401 -127.099019) (xy 118.655753 -127.049437)
			(xy 118.640392 -126.997136) (xy 118.632631 -126.943181) (xy 118.632224 -126.915926) (xy 118.632683 -126.889023)
			(xy 118.640238 -126.835751) (xy 118.655201 -126.784068) (xy 118.677277 -126.735) (xy 118.706027 -126.68952)
			(xy 118.74088 -126.648529) (xy 118.781147 -126.612841) (xy 118.826027 -126.583163) (xy 118.874631 -126.560085)
			(xy 118.900194 -126.55169) (xy 118.900702 -126.55169) (xy 118.906365 -126.549647) (xy 118.916631 -126.543363)
			(xy 118.921022 -126.539244) (xy 119.011192 -126.449074) (xy 119.017606 -126.4422) (xy 119.025283 -126.425053)
			(xy 119.026245 -126.40629) (xy 119.023638 -126.397258) (xy 118.991126 -126.29769) (xy 118.969282 -126.279148)
			(xy 118.955058 -126.276862) (xy 118.928427 -126.272237) (xy 118.87673 -126.25646) (xy 118.827776 -126.233544)
			(xy 118.782548 -126.203949) (xy 118.741949 -126.168266) (xy 118.706793 -126.12721) (xy 118.677783 -126.081603)
			(xy 118.655501 -126.032358) (xy 118.640393 -125.980461) (xy 118.63276 -125.926952) (xy 118.632224 -125.899926)
			(xy 118.632686 -125.872673) (xy 118.64044 -125.818721) (xy 118.655794 -125.766422) (xy 118.678435 -125.71684)
			(xy 118.707903 -125.670986) (xy 118.743597 -125.629793) (xy 118.784791 -125.594099) (xy 118.830646 -125.564632)
			(xy 118.880227 -125.541992) (xy 118.932527 -125.526638) (xy 118.986479 -125.518885) (xy 119.013732 -125.518418)
			(xy 119.040764 -125.518884) (xy 119.094288 -125.526507) (xy 119.1462 -125.541612) (xy 119.195459 -125.563894)
			(xy 119.241079 -125.592907) (xy 119.282145 -125.628071) (xy 119.317836 -125.66868) (xy 119.347435 -125.713922)
			(xy 119.370351 -125.762889) (xy 119.386123 -125.814602) (xy 119.390668 -125.841252) (xy 119.392954 -125.855476)
			(xy 119.411496 -125.87732) (xy 119.511064 -125.909832) (xy 119.520108 -125.912324) (xy 119.538827 -125.911336)
			(xy 119.555949 -125.90371) (xy 119.56288 -125.897386) (xy 120.48109 -124.97943) (xy 120.487926 -124.972028)
			(xy 120.495637 -124.95343) (xy 120.496076 -124.943362) (xy 120.496076 -121.254774) (xy 120.495452 -121.24364)
			(xy 120.485975 -121.223482) (xy 120.477788 -121.215912) (xy 120.417844 -121.165874) (xy 120.409037 -121.159157)
			(xy 120.387689 -121.153353) (xy 120.376696 -121.154698) (xy 120.376442 -121.154698) (xy 120.359757 -121.15752)
			(xy 120.326053 -121.160572) (xy 120.309132 -121.160794) (xy 120.281879 -121.160333) (xy 120.227926 -121.15258)
			(xy 120.175626 -121.137227) (xy 120.126044 -121.114587) (xy 120.080189 -121.085121) (xy 120.038994 -121.049429)
			(xy 120.003298 -121.008237) (xy 119.973828 -120.962384) (xy 119.951184 -120.912804) (xy 119.935827 -120.860505)
			(xy 119.928069 -120.806553) (xy 119.928069 -120.752047) (xy 119.935827 -120.698095) (xy 119.951184 -120.645796)
			(xy 119.973828 -120.596216) (xy 120.003298 -120.550363) (xy 120.038994 -120.509171) (xy 120.080189 -120.473479)
			(xy 120.126044 -120.444013) (xy 120.175626 -120.421373) (xy 120.227926 -120.40602) (xy 120.281879 -120.398267)
			(xy 120.309132 -120.397778) (xy 120.32599 -120.39799) (xy 120.359568 -120.401041) (xy 120.376188 -120.403874)
			(xy 120.376696 -120.403874) (xy 120.387872 -120.405906) (xy 120.409208 -120.400064) (xy 120.477788 -120.34266)
			(xy 120.485985 -120.335099) (xy 120.495447 -120.314935) (xy 120.496076 -120.303798) (xy 120.496076 -119.984774)
			(xy 120.495452 -119.97364) (xy 120.485975 -119.953482) (xy 120.477788 -119.945912) (xy 120.417844 -119.895874)
			(xy 120.409037 -119.889157) (xy 120.387689 -119.883353) (xy 120.376696 -119.884698) (xy 120.376442 -119.884698)
			(xy 120.359757 -119.88752) (xy 120.326053 -119.890572) (xy 120.309132 -119.890794) (xy 120.281879 -119.890333)
			(xy 120.227926 -119.88258) (xy 120.175626 -119.867227) (xy 120.126044 -119.844587) (xy 120.080189 -119.815121)
			(xy 120.038994 -119.779429) (xy 120.003298 -119.738237) (xy 119.973828 -119.692384) (xy 119.951184 -119.642804)
			(xy 119.935827 -119.590505) (xy 119.928069 -119.536553) (xy 119.928069 -119.482047) (xy 119.935827 -119.428095)
			(xy 119.951184 -119.375796) (xy 119.973828 -119.326216) (xy 120.003298 -119.280363) (xy 120.038994 -119.239171)
			(xy 120.080189 -119.203479) (xy 120.126044 -119.174013) (xy 120.175626 -119.151373) (xy 120.227926 -119.13602)
			(xy 120.281879 -119.128267) (xy 120.309132 -119.127778) (xy 120.32599 -119.12799) (xy 120.359568 -119.131041)
			(xy 120.376188 -119.133874) (xy 120.376696 -119.133874) (xy 120.387872 -119.135906) (xy 120.409208 -119.130064)
			(xy 120.477788 -119.07266) (xy 120.485985 -119.065099) (xy 120.495447 -119.044935) (xy 120.496076 -119.033798)
			(xy 120.496076 -113.203482) (xy 120.496601 -113.177458) (xy 120.504764 -113.126052) (xy 120.520855 -113.076552)
			(xy 120.54448 -113.030173) (xy 120.575059 -112.988053) (xy 120.593104 -112.969294) (xy 121.920508 -111.64189)
			(xy 121.92468 -111.637539) (xy 121.930981 -111.627266) (xy 121.932954 -111.62157) (xy 121.932954 -111.621316)
			(xy 121.94139 -111.595759) (xy 121.964444 -111.547128) (xy 121.994103 -111.502218) (xy 122.029777 -111.461922)
			(xy 122.07076 -111.427038) (xy 122.116238 -111.398259) (xy 122.165308 -111.376155) (xy 122.216998 -111.361166)
			(xy 122.270281 -111.353588) (xy 122.29719 -111.353092) (xy 122.324443 -111.353555) (xy 122.378395 -111.36131)
			(xy 122.430694 -111.376666) (xy 122.480276 -111.399308) (xy 122.52613 -111.428775) (xy 122.567324 -111.464469)
			(xy 122.603019 -111.505662) (xy 122.632488 -111.551515) (xy 122.655131 -111.601096) (xy 122.670487 -111.653395)
			(xy 122.678245 -111.707347) (xy 122.678698 -111.7346) (xy 122.678685 -111.735362) (xy 122.931172 -111.735362)
			(xy 122.935243 -111.67974) (xy 122.947369 -111.625303) (xy 122.967292 -111.573212) (xy 122.994588 -111.524577)
			(xy 123.028674 -111.480434) (xy 123.068823 -111.441725) (xy 123.114181 -111.409274) (xy 123.163781 -111.383773)
			(xy 123.216565 -111.365766) (xy 123.271408 -111.355636) (xy 123.327142 -111.353599) (xy 123.382579 -111.359699)
			(xy 123.436536 -111.373805) (xy 123.487865 -111.395617) (xy 123.535471 -111.424671) (xy 123.578339 -111.460346)
			(xy 123.615556 -111.501883) (xy 123.646329 -111.548396) (xy 123.670001 -111.598893) (xy 123.686069 -111.6523)
			(xy 123.694189 -111.707476) (xy 123.694698 -111.735362) (xy 123.947172 -111.735362) (xy 123.951243 -111.67974)
			(xy 123.963369 -111.625303) (xy 123.983292 -111.573212) (xy 124.010588 -111.524577) (xy 124.044674 -111.480434)
			(xy 124.084823 -111.441725) (xy 124.130181 -111.409274) (xy 124.179781 -111.383773) (xy 124.232565 -111.365766)
			(xy 124.287408 -111.355636) (xy 124.343142 -111.353599) (xy 124.398579 -111.359699) (xy 124.452536 -111.373805)
			(xy 124.503865 -111.395617) (xy 124.551471 -111.424671) (xy 124.594339 -111.460346) (xy 124.631556 -111.501883)
			(xy 124.662329 -111.548396) (xy 124.686001 -111.598893) (xy 124.702069 -111.6523) (xy 124.710189 -111.707476)
			(xy 124.710698 -111.735362) (xy 124.710189 -111.763248) (xy 124.702069 -111.818424) (xy 124.686001 -111.871831)
			(xy 124.662329 -111.922328) (xy 124.631556 -111.968841) (xy 124.594339 -112.010378) (xy 124.551471 -112.046053)
			(xy 124.503865 -112.075107) (xy 124.452536 -112.096919) (xy 124.398579 -112.111025) (xy 124.343142 -112.117125)
			(xy 124.287408 -112.115088) (xy 124.232565 -112.104958) (xy 124.179781 -112.086951) (xy 124.130181 -112.06145)
			(xy 124.084823 -112.028999) (xy 124.044674 -111.99029) (xy 124.010588 -111.946147) (xy 123.983292 -111.897512)
			(xy 123.963369 -111.845421) (xy 123.951243 -111.790984) (xy 123.947172 -111.735362) (xy 123.694698 -111.735362)
			(xy 123.694189 -111.763248) (xy 123.686069 -111.818424) (xy 123.670001 -111.871831) (xy 123.646329 -111.922328)
			(xy 123.615556 -111.968841) (xy 123.578339 -112.010378) (xy 123.535471 -112.046053) (xy 123.487865 -112.075107)
			(xy 123.436536 -112.096919) (xy 123.382579 -112.111025) (xy 123.327142 -112.117125) (xy 123.271408 -112.115088)
			(xy 123.216565 -112.104958) (xy 123.163781 -112.086951) (xy 123.114181 -112.06145) (xy 123.068823 -112.028999)
			(xy 123.028674 -111.99029) (xy 122.994588 -111.946147) (xy 122.967292 -111.897512) (xy 122.947369 -111.845421)
			(xy 122.935243 -111.790984) (xy 122.931172 -111.735362) (xy 122.678685 -111.735362) (xy 122.678237 -111.7615)
			(xy 122.670678 -111.814767) (xy 122.65571 -111.866444) (xy 122.633631 -111.915505) (xy 122.604878 -111.960977)
			(xy 122.570021 -112.001959) (xy 122.529753 -112.037638) (xy 122.484871 -112.067304) (xy 122.436266 -112.090371)
			(xy 122.410728 -112.098836) (xy 122.41022 -112.098836) (xy 122.404559 -112.100883) (xy 122.394298 -112.107172)
			(xy 122.3899 -112.111282) (xy 121.17451 -113.326418) (xy 121.167665 -113.333817) (xy 121.159936 -113.352415)
			(xy 121.159524 -113.362486) (xy 121.159524 -115.709954) (xy 121.160062 -115.719904) (xy 121.167729 -115.738276)
			(xy 121.181782 -115.752376) (xy 121.190766 -115.75669) (xy 121.200209 -115.760226) (xy 121.220356 -115.760314)
			(xy 121.238963 -115.752589) (xy 121.246392 -115.745768) (xy 125.005846 -111.986314) (xy 125.013293 -111.97805)
			(xy 125.020892 -111.957169) (xy 125.018993 -111.935029) (xy 125.013974 -111.9251) (xy 125.002025 -111.903375)
			(xy 124.983216 -111.857498) (xy 124.970498 -111.809574) (xy 124.964084 -111.760407) (xy 124.963682 -111.735616)
			(xy 124.963682 -111.735362) (xy 124.96417 -111.708112) (xy 124.971931 -111.654168) (xy 124.98729 -111.601877)
			(xy 125.009933 -111.552304) (xy 125.0394 -111.506458) (xy 125.075091 -111.465271) (xy 125.11628 -111.429583)
			(xy 125.162129 -111.400119) (xy 125.211704 -111.37748) (xy 125.263996 -111.362125) (xy 125.31794 -111.354368)
			(xy 125.34519 -111.353854) (xy 125.345444 -111.353854) (xy 125.370238 -111.354229) (xy 125.419413 -111.360619)
			(xy 125.467342 -111.373338) (xy 125.513215 -111.392169) (xy 125.534928 -111.404146) (xy 125.54484 -111.409241)
			(xy 125.567014 -111.411191) (xy 125.587916 -111.403535) (xy 125.596142 -111.396018) (xy 129.36093 -107.63123)
			(xy 129.384709 -107.60812) (xy 129.436562 -107.566787) (xy 129.492716 -107.531518) (xy 129.552465 -107.502758)
			(xy 129.615059 -107.480867) (xy 129.679709 -107.46612) (xy 129.745604 -107.458704) (xy 129.77876 -107.458256)
			(xy 134.161022 -107.458256) (xy 134.171089 -107.457828) (xy 134.189684 -107.450103) (xy 134.19709 -107.44327)
			(xy 150.41753 -91.22283) (xy 150.441309 -91.19972) (xy 150.493162 -91.158387) (xy 150.549316 -91.123118)
			(xy 150.609065 -91.094358) (xy 150.671659 -91.072467) (xy 150.736309 -91.05772) (xy 150.802204 -91.050304)
			(xy 150.83536 -91.049856) (xy 180.667406 -91.049856) (xy 180.677289 -91.049443) (xy 180.695613 -91.042045)
			(xy 180.709754 -91.028243) (xy 180.714142 -91.019376) (xy 180.75148 -90.934286) (xy 180.75504 -90.925155)
			(xy 180.755655 -90.905584) (xy 180.74884 -90.887228) (xy 180.74259 -90.879676) (xy 180.742336 -90.879422)
			(xy 180.723615 -90.858208) (xy 180.691997 -90.81129) (xy 180.667654 -90.760217) (xy 180.651119 -90.70611)
			(xy 180.642755 -90.650155) (xy 180.64226 -90.621866) (xy 180.642746 -90.594615) (xy 180.650502 -90.540667)
			(xy 180.665857 -90.488372) (xy 180.688499 -90.438795) (xy 180.717965 -90.392945) (xy 180.753656 -90.351754)
			(xy 180.794847 -90.316063) (xy 180.840697 -90.286597) (xy 180.890274 -90.263955) (xy 180.942569 -90.2486)
			(xy 180.996517 -90.240844) (xy 181.051019 -90.240844) (xy 181.104967 -90.2486) (xy 181.157262 -90.263955)
			(xy 181.206839 -90.286597) (xy 181.252689 -90.316063) (xy 181.29388 -90.351754) (xy 181.329571 -90.392945)
			(xy 181.359037 -90.438795) (xy 181.381679 -90.488372) (xy 181.397034 -90.540667) (xy 181.40479 -90.594615)
			(xy 181.405276 -90.621866) (xy 181.404764 -90.650154) (xy 181.396411 -90.706111) (xy 181.379882 -90.76022)
			(xy 181.355541 -90.811293) (xy 181.323922 -90.85821) (xy 181.3052 -90.879422) (xy 181.304946 -90.879676)
			(xy 181.298718 -90.887232) (xy 181.291967 -90.905594) (xy 181.292535 -90.92515) (xy 181.296056 -90.934286)
			(xy 181.333394 -91.019376) (xy 181.337784 -91.028229) (xy 181.351952 -91.041978) (xy 181.370258 -91.049372)
			(xy 181.38013 -91.049856) (xy 201.651362 -91.049856) (xy 201.66069 -91.049445) (xy 201.678113 -91.042774)
			(xy 201.691988 -91.030302) (xy 201.696574 -91.02217) (xy 201.737722 -90.941652) (xy 201.74165 -90.933187)
			(xy 201.743738 -90.914659) (xy 201.739036 -90.896617) (xy 201.733912 -90.88882) (xy 201.733658 -90.888566)
			(xy 201.716671 -90.864042) (xy 201.68972 -90.810823) (xy 201.671385 -90.754056) (xy 201.662111 -90.695127)
			(xy 201.661522 -90.6653) (xy 201.662008 -90.638049) (xy 201.669764 -90.584101) (xy 201.685119 -90.531806)
			(xy 201.707761 -90.482229) (xy 201.737227 -90.436379) (xy 201.772918 -90.395188) (xy 201.814109 -90.359497)
			(xy 201.859959 -90.330031) (xy 201.909536 -90.307389) (xy 201.961831 -90.292034) (xy 202.015779 -90.284278)
			(xy 202.070281 -90.284278) (xy 202.124229 -90.292034) (xy 202.176524 -90.307389) (xy 202.226101 -90.330031)
			(xy 202.271951 -90.359497) (xy 202.313142 -90.395188) (xy 202.348833 -90.436379) (xy 202.378299 -90.482229)
			(xy 202.400941 -90.531806) (xy 202.416296 -90.584101) (xy 202.424052 -90.638049) (xy 202.424538 -90.6653)
			(xy 202.424168 -90.688655) (xy 202.418434 -90.735013) (xy 202.413108 -90.757756) (xy 202.409552 -90.771726)
			(xy 202.418188 -90.798904) (xy 202.498198 -90.867738) (xy 202.505592 -90.873499) (xy 202.523243 -90.879766)
			(xy 202.541967 -90.879321) (xy 202.550776 -90.87612) (xy 207.419702 -88.859614) (xy 207.455677 -88.845402)
			(xy 207.530395 -88.82539) (xy 207.607086 -88.815302) (xy 207.645762 -88.814656) (xy 208.571846 -88.814656)
			(xy 208.581387 -88.814203) (xy 208.599125 -88.807151) (xy 208.613092 -88.794138) (xy 208.617566 -88.7857)
			(xy 208.66354 -88.689434) (xy 208.659984 -88.660478) (xy 208.650586 -88.649048) (xy 208.634563 -88.628567)
			(xy 208.607622 -88.58409) (xy 208.586969 -88.536368) (xy 208.572986 -88.486283) (xy 208.565932 -88.434764)
			(xy 208.565496 -88.408764) (xy 208.565982 -88.381513) (xy 208.573738 -88.327565) (xy 208.589093 -88.27527)
			(xy 208.611735 -88.225693) (xy 208.641201 -88.179843) (xy 208.676892 -88.138652) (xy 208.718083 -88.102961)
			(xy 208.763933 -88.073495) (xy 208.81351 -88.050853) (xy 208.865805 -88.035498) (xy 208.919753 -88.027742)
			(xy 208.974255 -88.027742) (xy 209.028203 -88.035498) (xy 209.080498 -88.050853) (xy 209.130075 -88.073495)
			(xy 209.175925 -88.102961) (xy 209.217116 -88.138652) (xy 209.252807 -88.179843) (xy 209.282273 -88.225693)
			(xy 209.304915 -88.27527) (xy 209.32027 -88.327565) (xy 209.328026 -88.381513) (xy 209.328512 -88.408764)
			(xy 209.328069 -88.434762) (xy 209.321003 -88.486276) (xy 209.307013 -88.536355) (xy 209.286355 -88.584072)
			(xy 209.259414 -88.628544) (xy 209.243422 -88.649048) (xy 209.234024 -88.660478) (xy 209.230468 -88.689434)
			(xy 209.276442 -88.7857) (xy 209.28089 -88.79417) (xy 209.294832 -88.807248) (xy 209.312604 -88.814286)
			(xy 209.322162 -88.814656) (xy 211.250022 -88.814656) (xy 211.260089 -88.814228) (xy 211.278684 -88.806503)
			(xy 211.28609 -88.79967) (xy 211.50453 -88.58123) (xy 211.528309 -88.55812) (xy 211.580162 -88.516787)
			(xy 211.636316 -88.481518) (xy 211.696065 -88.452758) (xy 211.758659 -88.430867) (xy 211.823309 -88.41612)
			(xy 211.889204 -88.408704) (xy 211.92236 -88.408256) (xy 222.095822 -88.408256) (xy 222.105889 -88.407828)
			(xy 222.124484 -88.400103) (xy 222.13189 -88.39327) (xy 223.815148 -86.710012) (xy 223.821955 -86.702582)
			(xy 223.829624 -86.683964) (xy 223.829582 -86.663829) (xy 223.82607 -86.654386) (xy 223.821803 -86.645369)
			(xy 223.807708 -86.631281) (xy 223.789298 -86.623652) (xy 223.779334 -86.623144) (xy 222.390208 -86.623144)
			(xy 222.378537 -86.623718) (xy 222.357579 -86.633998) (xy 222.343293 -86.652458) (xy 222.340424 -86.663784)
			(xy 222.334398 -86.690582) (xy 222.315683 -86.742222) (xy 222.289757 -86.790644) (xy 222.257155 -86.834848)
			(xy 222.218551 -86.87392) (xy 222.174743 -86.907052) (xy 222.126636 -86.93356) (xy 222.075226 -86.952896)
			(xy 222.021574 -86.964659) (xy 221.96679 -86.968608) (xy 221.912006 -86.964659) (xy 221.858354 -86.952896)
			(xy 221.806944 -86.93356) (xy 221.758837 -86.907052) (xy 221.715029 -86.87392) (xy 221.676425 -86.834848)
			(xy 221.643823 -86.790644) (xy 221.617897 -86.742222) (xy 221.599182 -86.690582) (xy 221.593156 -86.663784)
			(xy 221.590263 -86.652462) (xy 221.575997 -86.633986) (xy 221.555044 -86.623699) (xy 221.543372 -86.623144)
			(xy 221.423992 -86.623144) (xy 221.413949 -86.623571) (xy 221.395403 -86.631283) (xy 221.381236 -86.645522)
			(xy 221.377002 -86.65464) (xy 221.3356 -86.755986) (xy 221.341696 -86.786212) (xy 221.352618 -86.797134)
			(xy 221.373774 -86.818788) (xy 221.409652 -86.867547) (xy 221.437382 -86.921358) (xy 221.456269 -86.978872)
			(xy 221.465839 -87.038646) (xy 221.46641 -87.068914) (xy 221.465924 -87.096165) (xy 221.458168 -87.150113)
			(xy 221.442813 -87.202408) (xy 221.420171 -87.251985) (xy 221.390705 -87.297835) (xy 221.355014 -87.339026)
			(xy 221.313823 -87.374717) (xy 221.267973 -87.404183) (xy 221.218396 -87.426825) (xy 221.166101 -87.44218)
			(xy 221.112153 -87.449936) (xy 221.057651 -87.449936) (xy 221.003703 -87.44218) (xy 220.951408 -87.426825)
			(xy 220.901831 -87.404183) (xy 220.855981 -87.374717) (xy 220.81479 -87.339026) (xy 220.779099 -87.297835)
			(xy 220.749633 -87.251985) (xy 220.726991 -87.202408) (xy 220.711636 -87.150113) (xy 220.70388 -87.096165)
			(xy 220.703394 -87.068914) (xy 220.703973 -87.038646) (xy 220.713534 -86.97887) (xy 220.732416 -86.921354)
			(xy 220.760147 -86.867543) (xy 220.79603 -86.818788) (xy 220.817186 -86.797134) (xy 220.828108 -86.786212)
			(xy 220.834204 -86.755986) (xy 220.792802 -86.65464) (xy 220.788598 -86.645502) (xy 220.774422 -86.631251)
			(xy 220.755862 -86.623533) (xy 220.745812 -86.623144) (xy 220.05036 -86.623144) (xy 220.017206 -86.622678)
			(xy 219.951314 -86.615255) (xy 219.886666 -86.600505) (xy 219.824075 -86.578615) (xy 219.764325 -86.54986)
			(xy 219.708169 -86.514599) (xy 219.65631 -86.473277) (xy 219.63253 -86.45017) (xy 219.46489 -86.28253)
			(xy 219.457492 -86.275682) (xy 219.438894 -86.267946) (xy 219.428822 -86.267544) (xy 215.293956 -86.267544)
			(xy 215.286223 -86.267805) (xy 215.271473 -86.272451) (xy 215.265 -86.276688) (xy 215.235264 -86.296664)
			(xy 215.171884 -86.330053) (xy 215.104929 -86.355527) (xy 215.035383 -86.37271) (xy 214.964269 -86.38135)
			(xy 214.92845 -86.381844) (xy 214.432642 -86.381844) (xy 214.39691 -86.381308) (xy 214.32597 -86.372653)
			(xy 214.256594 -86.3555) (xy 214.189795 -86.3301) (xy 214.12655 -86.296824) (xy 214.096854 -86.276942)
			(xy 214.090344 -86.272804) (xy 214.075608 -86.268271) (xy 214.067898 -86.268052) (xy 214.058246 -86.268052)
			(xy 214.027812 -86.289609) (xy 213.962549 -86.325709) (xy 213.893256 -86.353294) (xy 213.821039 -86.371927)
			(xy 213.747049 -86.381309) (xy 213.709758 -86.381844) (xy 213.213442 -86.381844) (xy 213.17771 -86.381308)
			(xy 213.10677 -86.372653) (xy 213.037394 -86.3555) (xy 212.970595 -86.3301) (xy 212.90735 -86.296824)
			(xy 212.877654 -86.276942) (xy 212.871144 -86.272804) (xy 212.856408 -86.268271) (xy 212.848698 -86.268052)
			(xy 212.839046 -86.268052) (xy 212.808612 -86.289609) (xy 212.743349 -86.325709) (xy 212.674056 -86.353294)
			(xy 212.601839 -86.371927) (xy 212.527849 -86.381309) (xy 212.490558 -86.381844) (xy 211.994242 -86.381844)
			(xy 211.95851 -86.381308) (xy 211.88757 -86.372653) (xy 211.818194 -86.3555) (xy 211.751395 -86.3301)
			(xy 211.68815 -86.296824) (xy 211.658454 -86.276942) (xy 211.651944 -86.272804) (xy 211.637208 -86.268271)
			(xy 211.629498 -86.268052) (xy 211.619846 -86.268052) (xy 211.589412 -86.289609) (xy 211.524149 -86.325709)
			(xy 211.454856 -86.353294) (xy 211.382639 -86.371927) (xy 211.308649 -86.381309) (xy 211.271358 -86.381844)
			(xy 210.77555 -86.381844) (xy 210.739733 -86.381319) (xy 210.668625 -86.372661) (xy 210.599083 -86.355478)
			(xy 210.532125 -86.330021) (xy 210.468733 -86.296664) (xy 210.439 -86.276688) (xy 210.432501 -86.272502)
			(xy 210.417768 -86.267845) (xy 210.410044 -86.267544) (xy 206.808578 -86.267544) (xy 206.798511 -86.267972)
			(xy 206.779916 -86.275697) (xy 206.77251 -86.28253) (xy 205.931516 -87.123524) (xy 218.507562 -87.123524)
			(xy 218.511633 -87.067902) (xy 218.523759 -87.013465) (xy 218.543682 -86.961374) (xy 218.570978 -86.912739)
			(xy 218.605064 -86.868596) (xy 218.645213 -86.829887) (xy 218.690571 -86.797436) (xy 218.740171 -86.771935)
			(xy 218.792955 -86.753928) (xy 218.847798 -86.743798) (xy 218.903532 -86.741761) (xy 218.958969 -86.747861)
			(xy 219.012926 -86.761967) (xy 219.064255 -86.783779) (xy 219.111861 -86.812833) (xy 219.154729 -86.848508)
			(xy 219.191946 -86.890045) (xy 219.222719 -86.936558) (xy 219.246391 -86.987055) (xy 219.262459 -87.040462)
			(xy 219.270579 -87.095638) (xy 219.271088 -87.123524) (xy 219.270579 -87.15141) (xy 219.262459 -87.206586)
			(xy 219.246391 -87.259993) (xy 219.222719 -87.31049) (xy 219.191946 -87.357003) (xy 219.154729 -87.39854)
			(xy 219.111861 -87.434215) (xy 219.064255 -87.463269) (xy 219.012926 -87.485081) (xy 218.958969 -87.499187)
			(xy 218.903532 -87.505287) (xy 218.847798 -87.50325) (xy 218.792955 -87.49312) (xy 218.740171 -87.475113)
			(xy 218.690571 -87.449612) (xy 218.645213 -87.417161) (xy 218.605064 -87.378452) (xy 218.570978 -87.334309)
			(xy 218.543682 -87.285674) (xy 218.523759 -87.233583) (xy 218.511633 -87.179146) (xy 218.507562 -87.123524)
			(xy 205.931516 -87.123524) (xy 205.48727 -87.56777) (xy 205.463491 -87.59088) (xy 205.411638 -87.632213)
			(xy 205.374316 -87.655654) (xy 209.414616 -87.655654) (xy 209.418687 -87.600032) (xy 209.430813 -87.545595)
			(xy 209.450736 -87.493504) (xy 209.478032 -87.444869) (xy 209.512118 -87.400726) (xy 209.552267 -87.362017)
			(xy 209.597625 -87.329566) (xy 209.647225 -87.304065) (xy 209.700009 -87.286058) (xy 209.754852 -87.275928)
			(xy 209.810586 -87.273891) (xy 209.866023 -87.279991) (xy 209.91998 -87.294097) (xy 209.971309 -87.315909)
			(xy 210.018915 -87.344963) (xy 210.061783 -87.380638) (xy 210.099 -87.422175) (xy 210.129773 -87.468688)
			(xy 210.153445 -87.519185) (xy 210.169513 -87.572592) (xy 210.177633 -87.627768) (xy 210.178142 -87.655654)
			(xy 210.307172 -87.655654) (xy 210.311243 -87.600032) (xy 210.323369 -87.545595) (xy 210.343292 -87.493504)
			(xy 210.370588 -87.444869) (xy 210.404674 -87.400726) (xy 210.444823 -87.362017) (xy 210.490181 -87.329566)
			(xy 210.539781 -87.304065) (xy 210.592565 -87.286058) (xy 210.647408 -87.275928) (xy 210.703142 -87.273891)
			(xy 210.758579 -87.279991) (xy 210.812536 -87.294097) (xy 210.863865 -87.315909) (xy 210.911471 -87.344963)
			(xy 210.954339 -87.380638) (xy 210.991556 -87.422175) (xy 211.022329 -87.468688) (xy 211.046001 -87.519185)
			(xy 211.062069 -87.572592) (xy 211.067415 -87.608918) (xy 221.615252 -87.608918) (xy 221.619323 -87.553296)
			(xy 221.631449 -87.498859) (xy 221.651372 -87.446768) (xy 221.678668 -87.398133) (xy 221.712754 -87.35399)
			(xy 221.752903 -87.315281) (xy 221.798261 -87.28283) (xy 221.847861 -87.257329) (xy 221.900645 -87.239322)
			(xy 221.955488 -87.229192) (xy 222.011222 -87.227155) (xy 222.066659 -87.233255) (xy 222.120616 -87.247361)
			(xy 222.171945 -87.269173) (xy 222.219551 -87.298227) (xy 222.262419 -87.333902) (xy 222.299636 -87.375439)
			(xy 222.330409 -87.421952) (xy 222.354081 -87.472449) (xy 222.370149 -87.525856) (xy 222.378269 -87.581032)
			(xy 222.378778 -87.608918) (xy 222.378269 -87.636804) (xy 222.370149 -87.69198) (xy 222.354081 -87.745387)
			(xy 222.330409 -87.795884) (xy 222.299636 -87.842397) (xy 222.262419 -87.883934) (xy 222.219551 -87.919609)
			(xy 222.171945 -87.948663) (xy 222.120616 -87.970475) (xy 222.066659 -87.984581) (xy 222.011222 -87.990681)
			(xy 221.955488 -87.988644) (xy 221.900645 -87.978514) (xy 221.847861 -87.960507) (xy 221.798261 -87.935006)
			(xy 221.752903 -87.902555) (xy 221.712754 -87.863846) (xy 221.678668 -87.819703) (xy 221.651372 -87.771068)
			(xy 221.631449 -87.718977) (xy 221.619323 -87.66454) (xy 221.615252 -87.608918) (xy 211.067415 -87.608918)
			(xy 211.070189 -87.627768) (xy 211.070698 -87.655654) (xy 211.070189 -87.68354) (xy 211.062069 -87.738716)
			(xy 211.046001 -87.792123) (xy 211.022329 -87.84262) (xy 210.991556 -87.889133) (xy 210.954339 -87.93067)
			(xy 210.911471 -87.966345) (xy 210.863865 -87.995399) (xy 210.812536 -88.017211) (xy 210.758579 -88.031317)
			(xy 210.703142 -88.037417) (xy 210.647408 -88.03538) (xy 210.592565 -88.02525) (xy 210.539781 -88.007243)
			(xy 210.490181 -87.981742) (xy 210.444823 -87.949291) (xy 210.404674 -87.910582) (xy 210.370588 -87.866439)
			(xy 210.343292 -87.817804) (xy 210.323369 -87.765713) (xy 210.311243 -87.711276) (xy 210.307172 -87.655654)
			(xy 210.178142 -87.655654) (xy 210.177633 -87.68354) (xy 210.169513 -87.738716) (xy 210.153445 -87.792123)
			(xy 210.129773 -87.84262) (xy 210.099 -87.889133) (xy 210.061783 -87.93067) (xy 210.018915 -87.966345)
			(xy 209.971309 -87.995399) (xy 209.91998 -88.017211) (xy 209.866023 -88.031317) (xy 209.810586 -88.037417)
			(xy 209.754852 -88.03538) (xy 209.700009 -88.02525) (xy 209.647225 -88.007243) (xy 209.597625 -87.981742)
			(xy 209.552267 -87.949291) (xy 209.512118 -87.910582) (xy 209.478032 -87.866439) (xy 209.450736 -87.817804)
			(xy 209.430813 -87.765713) (xy 209.418687 -87.711276) (xy 209.414616 -87.655654) (xy 205.374316 -87.655654)
			(xy 205.355484 -87.667482) (xy 205.295735 -87.696242) (xy 205.233141 -87.718133) (xy 205.168491 -87.73288)
			(xy 205.102596 -87.740296) (xy 205.06944 -87.740744) (xy 195.784978 -87.740744) (xy 195.774911 -87.741172)
			(xy 195.756316 -87.748897) (xy 195.74891 -87.75573) (xy 195.22567 -88.27897) (xy 195.200033 -88.303905)
			(xy 195.143756 -88.348039) (xy 195.097532 -88.375998) (xy 195.924168 -88.375998) (xy 195.928239 -88.320376)
			(xy 195.940365 -88.265939) (xy 195.960288 -88.213848) (xy 195.987584 -88.165213) (xy 196.02167 -88.12107)
			(xy 196.061819 -88.082361) (xy 196.107177 -88.04991) (xy 196.156777 -88.024409) (xy 196.209561 -88.006402)
			(xy 196.264404 -87.996272) (xy 196.320138 -87.994235) (xy 196.375575 -88.000335) (xy 196.429532 -88.014441)
			(xy 196.480861 -88.036253) (xy 196.528467 -88.065307) (xy 196.571335 -88.100982) (xy 196.608552 -88.142519)
			(xy 196.639325 -88.189032) (xy 196.662997 -88.239529) (xy 196.679065 -88.292936) (xy 196.687185 -88.348112)
			(xy 196.687694 -88.375998) (xy 196.687332 -88.39581) (xy 197.35749 -88.39581) (xy 197.361561 -88.340188)
			(xy 197.373687 -88.285751) (xy 197.39361 -88.23366) (xy 197.420906 -88.185025) (xy 197.454992 -88.140882)
			(xy 197.495141 -88.102173) (xy 197.540499 -88.069722) (xy 197.590099 -88.044221) (xy 197.642883 -88.026214)
			(xy 197.697726 -88.016084) (xy 197.75346 -88.014047) (xy 197.808897 -88.020147) (xy 197.862854 -88.034253)
			(xy 197.914183 -88.056065) (xy 197.961789 -88.085119) (xy 198.004657 -88.120794) (xy 198.041874 -88.162331)
			(xy 198.072647 -88.208844) (xy 198.096319 -88.259341) (xy 198.112387 -88.312748) (xy 198.120507 -88.367924)
			(xy 198.121016 -88.39581) (xy 198.120507 -88.423696) (xy 198.112387 -88.478872) (xy 198.096319 -88.532279)
			(xy 198.072647 -88.582776) (xy 198.041874 -88.629289) (xy 198.004657 -88.670826) (xy 197.961789 -88.706501)
			(xy 197.914183 -88.735555) (xy 197.862854 -88.757367) (xy 197.808897 -88.771473) (xy 197.75346 -88.777573)
			(xy 197.697726 -88.775536) (xy 197.642883 -88.765406) (xy 197.590099 -88.747399) (xy 197.540499 -88.721898)
			(xy 197.495141 -88.689447) (xy 197.454992 -88.650738) (xy 197.420906 -88.606595) (xy 197.39361 -88.55796)
			(xy 197.373687 -88.505869) (xy 197.361561 -88.451432) (xy 197.35749 -88.39581) (xy 196.687332 -88.39581)
			(xy 196.687185 -88.403884) (xy 196.679065 -88.45906) (xy 196.662997 -88.512467) (xy 196.639325 -88.562964)
			(xy 196.608552 -88.609477) (xy 196.571335 -88.651014) (xy 196.528467 -88.686689) (xy 196.480861 -88.715743)
			(xy 196.429532 -88.737555) (xy 196.375575 -88.751661) (xy 196.320138 -88.757761) (xy 196.264404 -88.755724)
			(xy 196.209561 -88.745594) (xy 196.156777 -88.727587) (xy 196.107177 -88.702086) (xy 196.061819 -88.669635)
			(xy 196.02167 -88.630926) (xy 195.987584 -88.586783) (xy 195.960288 -88.538148) (xy 195.940365 -88.486057)
			(xy 195.928239 -88.43162) (xy 195.924168 -88.375998) (xy 195.097532 -88.375998) (xy 195.082561 -88.385053)
			(xy 195.017344 -88.414406) (xy 194.983354 -88.425528) (xy 194.979211 -88.426914) (xy 194.971427 -88.430879)
			(xy 194.96786 -88.433402) (xy 194.942579 -88.451962) (xy 194.888749 -88.484149) (xy 194.831773 -88.510367)
			(xy 194.772311 -88.530313) (xy 194.71105 -88.543756) (xy 194.648699 -88.55054) (xy 194.61734 -88.551004)
			(xy 146.778472 -88.551004) (xy 146.744022 -88.550483) (xy 146.675607 -88.542326) (xy 146.608633 -88.526151)
			(xy 146.544036 -88.502186) (xy 146.482718 -88.470765) (xy 146.45386 -88.451944) (xy 146.44116 -88.451944)
			(xy 146.408006 -88.451478) (xy 146.342114 -88.444055) (xy 146.277466 -88.429305) (xy 146.214875 -88.407415)
			(xy 146.155125 -88.37866) (xy 146.098969 -88.343399) (xy 146.04711 -88.302077) (xy 146.02333 -88.27897)
			(xy 145.081498 -87.337138) (xy 145.074101 -87.330288) (xy 145.055503 -87.322548) (xy 145.04543 -87.322152)
			(xy 143.316198 -87.322152) (xy 143.308929 -87.322384) (xy 143.294992 -87.32652) (xy 143.288766 -87.33028)
			(xy 143.260189 -87.347993) (xy 143.199796 -87.377546) (xy 143.136435 -87.400041) (xy 143.070927 -87.415186)
			(xy 143.004122 -87.422785) (xy 142.970504 -87.423244) (xy 142.474188 -87.423244) (xy 142.440623 -87.422741)
			(xy 142.373932 -87.415075) (xy 142.308537 -87.39991) (xy 142.245278 -87.377443) (xy 142.184969 -87.347961)
			(xy 142.156434 -87.33028) (xy 142.150338 -87.326216) (xy 142.136368 -87.322152) (xy 142.089632 -87.322152)
			(xy 142.075662 -87.326216) (xy 142.069566 -87.33028) (xy 142.041033 -87.347968) (xy 141.980737 -87.377487)
			(xy 141.917479 -87.399969) (xy 141.852078 -87.415126) (xy 141.785379 -87.42276) (xy 141.751812 -87.423244)
			(xy 141.254988 -87.423244) (xy 141.221423 -87.422741) (xy 141.154732 -87.415075) (xy 141.089337 -87.39991)
			(xy 141.026078 -87.377443) (xy 140.965769 -87.347961) (xy 140.937234 -87.33028) (xy 140.931138 -87.326216)
			(xy 140.917168 -87.322152) (xy 140.870432 -87.322152) (xy 140.856462 -87.326216) (xy 140.850366 -87.33028)
			(xy 140.821833 -87.347968) (xy 140.761537 -87.377487) (xy 140.698279 -87.399969) (xy 140.632878 -87.415126)
			(xy 140.566179 -87.42276) (xy 140.532612 -87.423244) (xy 140.477748 -87.423244) (xy 140.468361 -87.423674)
			(xy 140.450841 -87.430422) (xy 140.436904 -87.443002) (xy 140.432282 -87.451184) (xy 140.385038 -87.545672)
			(xy 140.387324 -87.57412) (xy 140.39596 -87.58555) (xy 140.413756 -87.610422) (xy 140.442029 -87.664649)
			(xy 140.461287 -87.722692) (xy 140.471038 -87.783065) (xy 140.471652 -87.813642) (xy 140.471166 -87.840893)
			(xy 140.46341 -87.894841) (xy 140.448055 -87.947136) (xy 140.425413 -87.996713) (xy 140.395947 -88.042563)
			(xy 140.360256 -88.083754) (xy 140.319065 -88.119445) (xy 140.273215 -88.148911) (xy 140.223638 -88.171553)
			(xy 140.171343 -88.186908) (xy 140.117395 -88.194664) (xy 140.062893 -88.194664) (xy 140.008945 -88.186908)
			(xy 139.95665 -88.171553) (xy 139.907073 -88.148911) (xy 139.861223 -88.119445) (xy 139.820032 -88.083754)
			(xy 139.784341 -88.042563) (xy 139.754875 -87.996713) (xy 139.732233 -87.947136) (xy 139.716878 -87.894841)
			(xy 139.709122 -87.840893) (xy 139.708636 -87.813642) (xy 139.709047 -87.788032) (xy 139.715893 -87.73727)
			(xy 139.729469 -87.687882) (xy 139.749531 -87.640753) (xy 139.775717 -87.596732) (xy 139.807556 -87.556609)
			(xy 139.82573 -87.53856) (xy 139.834376 -87.529431) (xy 139.842228 -87.505578) (xy 139.840716 -87.493094)
			(xy 139.823952 -87.397336) (xy 139.808458 -87.377524) (xy 139.79652 -87.372444) (xy 139.776218 -87.363221)
			(xy 139.736934 -87.342113) (xy 139.718034 -87.33028) (xy 139.711785 -87.326574) (xy 139.697861 -87.322443)
			(xy 139.690602 -87.322152) (xy 139.429998 -87.322152) (xy 139.422729 -87.322384) (xy 139.408792 -87.32652)
			(xy 139.402566 -87.33028) (xy 139.373989 -87.347993) (xy 139.313596 -87.377546) (xy 139.250235 -87.400041)
			(xy 139.184727 -87.415186) (xy 139.117922 -87.422785) (xy 139.084304 -87.423244) (xy 138.58875 -87.423244)
			(xy 138.552933 -87.422719) (xy 138.481825 -87.414061) (xy 138.412283 -87.396878) (xy 138.345325 -87.371421)
			(xy 138.281933 -87.338064) (xy 138.2522 -87.318088) (xy 138.245701 -87.313902) (xy 138.230968 -87.309245)
			(xy 138.223244 -87.308944) (xy 134.672578 -87.308944) (xy 134.662511 -87.309372) (xy 134.643916 -87.317097)
			(xy 134.63651 -87.32393) (xy 133.299962 -88.660478) (xy 134.653526 -88.660478) (xy 134.657597 -88.604856)
			(xy 134.669723 -88.550419) (xy 134.689646 -88.498328) (xy 134.716942 -88.449693) (xy 134.751028 -88.40555)
			(xy 134.791177 -88.366841) (xy 134.836535 -88.33439) (xy 134.886135 -88.308889) (xy 134.938919 -88.290882)
			(xy 134.993762 -88.280752) (xy 135.049496 -88.278715) (xy 135.104933 -88.284815) (xy 135.15889 -88.298921)
			(xy 135.210219 -88.320733) (xy 135.257825 -88.349787) (xy 135.300693 -88.385462) (xy 135.33791 -88.426999)
			(xy 135.368683 -88.473512) (xy 135.392355 -88.524009) (xy 135.408423 -88.577416) (xy 135.416543 -88.632592)
			(xy 135.417052 -88.660478) (xy 135.416543 -88.688364) (xy 135.408423 -88.74354) (xy 135.392355 -88.796947)
			(xy 135.368683 -88.847444) (xy 135.33791 -88.893957) (xy 135.300693 -88.935494) (xy 135.275281 -88.956642)
			(xy 139.708126 -88.956642) (xy 139.712197 -88.90102) (xy 139.724323 -88.846583) (xy 139.744246 -88.794492)
			(xy 139.771542 -88.745857) (xy 139.805628 -88.701714) (xy 139.845777 -88.663005) (xy 139.891135 -88.630554)
			(xy 139.940735 -88.605053) (xy 139.993519 -88.587046) (xy 140.048362 -88.576916) (xy 140.104096 -88.574879)
			(xy 140.159533 -88.580979) (xy 140.21349 -88.595085) (xy 140.264819 -88.616897) (xy 140.312425 -88.645951)
			(xy 140.355293 -88.681626) (xy 140.39251 -88.723163) (xy 140.423283 -88.769676) (xy 140.446955 -88.820173)
			(xy 140.463023 -88.87358) (xy 140.471143 -88.928756) (xy 140.471652 -88.956642) (xy 140.471143 -88.984528)
			(xy 140.469827 -88.993472) (xy 202.091796 -88.993472) (xy 202.095867 -88.93785) (xy 202.107993 -88.883413)
			(xy 202.127916 -88.831322) (xy 202.155212 -88.782687) (xy 202.189298 -88.738544) (xy 202.229447 -88.699835)
			(xy 202.274805 -88.667384) (xy 202.324405 -88.641883) (xy 202.377189 -88.623876) (xy 202.432032 -88.613746)
			(xy 202.487766 -88.611709) (xy 202.543203 -88.617809) (xy 202.59716 -88.631915) (xy 202.648489 -88.653727)
			(xy 202.696095 -88.682781) (xy 202.738963 -88.718456) (xy 202.77618 -88.759993) (xy 202.806953 -88.806506)
			(xy 202.830625 -88.857003) (xy 202.846693 -88.91041) (xy 202.854813 -88.965586) (xy 202.855322 -88.993472)
			(xy 202.854813 -89.021358) (xy 202.846693 -89.076534) (xy 202.830625 -89.129941) (xy 202.806953 -89.180438)
			(xy 202.77618 -89.226951) (xy 202.738963 -89.268488) (xy 202.696095 -89.304163) (xy 202.648489 -89.333217)
			(xy 202.59716 -89.355029) (xy 202.543203 -89.369135) (xy 202.487766 -89.375235) (xy 202.432032 -89.373198)
			(xy 202.377189 -89.363068) (xy 202.324405 -89.345061) (xy 202.274805 -89.31956) (xy 202.229447 -89.287109)
			(xy 202.189298 -89.2484) (xy 202.155212 -89.204257) (xy 202.127916 -89.155622) (xy 202.107993 -89.103531)
			(xy 202.095867 -89.049094) (xy 202.091796 -88.993472) (xy 140.469827 -88.993472) (xy 140.463023 -89.039704)
			(xy 140.446955 -89.093111) (xy 140.423283 -89.143608) (xy 140.39251 -89.190121) (xy 140.355293 -89.231658)
			(xy 140.312425 -89.267333) (xy 140.264819 -89.296387) (xy 140.21349 -89.318199) (xy 140.159533 -89.332305)
			(xy 140.104096 -89.338405) (xy 140.048362 -89.336368) (xy 139.993519 -89.326238) (xy 139.940735 -89.308231)
			(xy 139.891135 -89.28273) (xy 139.845777 -89.250279) (xy 139.805628 -89.21157) (xy 139.771542 -89.167427)
			(xy 139.744246 -89.118792) (xy 139.724323 -89.066701) (xy 139.712197 -89.012264) (xy 139.708126 -88.956642)
			(xy 135.275281 -88.956642) (xy 135.257825 -88.971169) (xy 135.210219 -89.000223) (xy 135.15889 -89.022035)
			(xy 135.104933 -89.036141) (xy 135.049496 -89.042241) (xy 134.993762 -89.040204) (xy 134.938919 -89.030074)
			(xy 134.886135 -89.012067) (xy 134.836535 -88.986566) (xy 134.791177 -88.954115) (xy 134.751028 -88.915406)
			(xy 134.716942 -88.871263) (xy 134.689646 -88.822628) (xy 134.669723 -88.770537) (xy 134.657597 -88.7161)
			(xy 134.653526 -88.660478) (xy 133.299962 -88.660478) (xy 133.17093 -88.78951) (xy 133.164082 -88.796908)
			(xy 133.156346 -88.815506) (xy 133.155944 -88.825578) (xy 133.155944 -89.230454) (xy 133.320534 -89.230454)
			(xy 133.324605 -89.174832) (xy 133.336731 -89.120395) (xy 133.356654 -89.068304) (xy 133.38395 -89.019669)
			(xy 133.418036 -88.975526) (xy 133.458185 -88.936817) (xy 133.503543 -88.904366) (xy 133.553143 -88.878865)
			(xy 133.605927 -88.860858) (xy 133.66077 -88.850728) (xy 133.716504 -88.848691) (xy 133.771941 -88.854791)
			(xy 133.825898 -88.868897) (xy 133.877227 -88.890709) (xy 133.924833 -88.919763) (xy 133.967701 -88.955438)
			(xy 134.004918 -88.996975) (xy 134.035691 -89.043488) (xy 134.059363 -89.093985) (xy 134.075431 -89.147392)
			(xy 134.083551 -89.202568) (xy 134.08406 -89.230454) (xy 134.083551 -89.25834) (xy 134.075431 -89.313516)
			(xy 134.059363 -89.366923) (xy 134.035691 -89.41742) (xy 134.004918 -89.463933) (xy 133.967701 -89.50547)
			(xy 133.924833 -89.541145) (xy 133.877227 -89.570199) (xy 133.825898 -89.592011) (xy 133.771941 -89.606117)
			(xy 133.716504 -89.612217) (xy 133.66077 -89.61018) (xy 133.605927 -89.60005) (xy 133.553143 -89.582043)
			(xy 133.503543 -89.556542) (xy 133.458185 -89.524091) (xy 133.418036 -89.485382) (xy 133.38395 -89.441239)
			(xy 133.356654 -89.392604) (xy 133.336731 -89.340513) (xy 133.324605 -89.286076) (xy 133.320534 -89.230454)
			(xy 133.155944 -89.230454) (xy 133.155944 -89.517728) (xy 133.156284 -89.526905) (xy 133.162662 -89.54411)
			(xy 133.174697 -89.557961) (xy 133.190844 -89.566679) (xy 133.199886 -89.568274) (xy 133.226954 -89.572446)
			(xy 133.279601 -89.587538) (xy 133.329548 -89.610004) (xy 133.375768 -89.639383) (xy 133.417311 -89.67507)
			(xy 133.453323 -89.716332) (xy 133.483064 -89.76232) (xy 133.505921 -89.812089) (xy 133.521425 -89.864616)
			(xy 133.529258 -89.91882) (xy 133.529257 -89.973587) (xy 133.527595 -89.985088) (xy 134.64743 -89.985088)
			(xy 134.651501 -89.929466) (xy 134.663627 -89.875029) (xy 134.68355 -89.822938) (xy 134.710846 -89.774303)
			(xy 134.744932 -89.73016) (xy 134.785081 -89.691451) (xy 134.830439 -89.659) (xy 134.880039 -89.633499)
			(xy 134.932823 -89.615492) (xy 134.987666 -89.605362) (xy 135.0434 -89.603325) (xy 135.098837 -89.609425)
			(xy 135.152794 -89.623531) (xy 135.204123 -89.645343) (xy 135.251729 -89.674397) (xy 135.294597 -89.710072)
			(xy 135.331814 -89.751609) (xy 135.362587 -89.798122) (xy 135.386259 -89.848619) (xy 135.402327 -89.902026)
			(xy 135.410447 -89.957202) (xy 135.410956 -89.985088) (xy 135.410447 -90.012974) (xy 135.402327 -90.06815)
			(xy 135.392852 -90.099642) (xy 139.708126 -90.099642) (xy 139.712197 -90.04402) (xy 139.724323 -89.989583)
			(xy 139.744246 -89.937492) (xy 139.771542 -89.888857) (xy 139.805628 -89.844714) (xy 139.845777 -89.806005)
			(xy 139.891135 -89.773554) (xy 139.940735 -89.748053) (xy 139.993519 -89.730046) (xy 140.048362 -89.719916)
			(xy 140.104096 -89.717879) (xy 140.159533 -89.723979) (xy 140.21349 -89.738085) (xy 140.264819 -89.759897)
			(xy 140.312425 -89.788951) (xy 140.355293 -89.824626) (xy 140.39251 -89.866163) (xy 140.418928 -89.906094)
			(xy 192.562478 -89.906094) (xy 192.566549 -89.850472) (xy 192.578675 -89.796035) (xy 192.598598 -89.743944)
			(xy 192.625894 -89.695309) (xy 192.65998 -89.651166) (xy 192.700129 -89.612457) (xy 192.745487 -89.580006)
			(xy 192.795087 -89.554505) (xy 192.847871 -89.536498) (xy 192.902714 -89.526368) (xy 192.958448 -89.524331)
			(xy 193.013885 -89.530431) (xy 193.067842 -89.544537) (xy 193.119171 -89.566349) (xy 193.166777 -89.595403)
			(xy 193.209645 -89.631078) (xy 193.246862 -89.672615) (xy 193.277635 -89.719128) (xy 193.301307 -89.769625)
			(xy 193.304844 -89.78138) (xy 196.320408 -89.78138) (xy 196.324479 -89.725758) (xy 196.336605 -89.671321)
			(xy 196.356528 -89.61923) (xy 196.383824 -89.570595) (xy 196.41791 -89.526452) (xy 196.458059 -89.487743)
			(xy 196.503417 -89.455292) (xy 196.553017 -89.429791) (xy 196.605801 -89.411784) (xy 196.660644 -89.401654)
			(xy 196.716378 -89.399617) (xy 196.771815 -89.405717) (xy 196.825772 -89.419823) (xy 196.877101 -89.441635)
			(xy 196.924707 -89.470689) (xy 196.967575 -89.506364) (xy 197.004792 -89.547901) (xy 197.035565 -89.594414)
			(xy 197.059237 -89.644911) (xy 197.075305 -89.698318) (xy 197.083425 -89.753494) (xy 197.083934 -89.78138)
			(xy 197.083425 -89.809266) (xy 197.075305 -89.864442) (xy 197.059237 -89.917849) (xy 197.035565 -89.968346)
			(xy 197.004792 -90.014859) (xy 196.967575 -90.056396) (xy 196.924707 -90.092071) (xy 196.877101 -90.121125)
			(xy 196.825772 -90.142937) (xy 196.771815 -90.157043) (xy 196.716378 -90.163143) (xy 196.660644 -90.161106)
			(xy 196.605801 -90.150976) (xy 196.553017 -90.132969) (xy 196.503417 -90.107468) (xy 196.458059 -90.075017)
			(xy 196.41791 -90.036308) (xy 196.383824 -89.992165) (xy 196.356528 -89.94353) (xy 196.336605 -89.891439)
			(xy 196.324479 -89.837002) (xy 196.320408 -89.78138) (xy 193.304844 -89.78138) (xy 193.317375 -89.823032)
			(xy 193.325495 -89.878208) (xy 193.326004 -89.906094) (xy 193.325495 -89.93398) (xy 193.317375 -89.989156)
			(xy 193.301307 -90.042563) (xy 193.277635 -90.09306) (xy 193.246862 -90.139573) (xy 193.209645 -90.18111)
			(xy 193.166777 -90.216785) (xy 193.119171 -90.245839) (xy 193.067842 -90.267651) (xy 193.013885 -90.281757)
			(xy 192.958448 -90.287857) (xy 192.902714 -90.28582) (xy 192.847871 -90.27569) (xy 192.795087 -90.257683)
			(xy 192.745487 -90.232182) (xy 192.700129 -90.199731) (xy 192.65998 -90.161022) (xy 192.625894 -90.116879)
			(xy 192.598598 -90.068244) (xy 192.578675 -90.016153) (xy 192.566549 -89.961716) (xy 192.562478 -89.906094)
			(xy 140.418928 -89.906094) (xy 140.423283 -89.912676) (xy 140.446955 -89.963173) (xy 140.463023 -90.01658)
			(xy 140.471143 -90.071756) (xy 140.471652 -90.099642) (xy 140.471143 -90.127528) (xy 140.463023 -90.182704)
			(xy 140.446955 -90.236111) (xy 140.423283 -90.286608) (xy 140.39251 -90.333121) (xy 140.355293 -90.374658)
			(xy 140.312425 -90.410333) (xy 140.264819 -90.439387) (xy 140.21349 -90.461199) (xy 140.159533 -90.475305)
			(xy 140.104096 -90.481405) (xy 140.048362 -90.479368) (xy 139.993519 -90.469238) (xy 139.940735 -90.451231)
			(xy 139.891135 -90.42573) (xy 139.845777 -90.393279) (xy 139.805628 -90.35457) (xy 139.771542 -90.310427)
			(xy 139.744246 -90.261792) (xy 139.724323 -90.209701) (xy 139.712197 -90.155264) (xy 139.708126 -90.099642)
			(xy 135.392852 -90.099642) (xy 135.386259 -90.121557) (xy 135.362587 -90.172054) (xy 135.331814 -90.218567)
			(xy 135.294597 -90.260104) (xy 135.251729 -90.295779) (xy 135.204123 -90.324833) (xy 135.152794 -90.346645)
			(xy 135.098837 -90.360751) (xy 135.0434 -90.366851) (xy 134.987666 -90.364814) (xy 134.932823 -90.354684)
			(xy 134.880039 -90.336677) (xy 134.830439 -90.311176) (xy 134.785081 -90.278725) (xy 134.744932 -90.240016)
			(xy 134.710846 -90.195873) (xy 134.68355 -90.147238) (xy 134.663627 -90.095147) (xy 134.651501 -90.04071)
			(xy 134.64743 -89.985088) (xy 133.527595 -89.985088) (xy 133.521424 -90.027791) (xy 133.505919 -90.080317)
			(xy 133.48306 -90.130086) (xy 133.453319 -90.176074) (xy 133.417306 -90.217335) (xy 133.375762 -90.253022)
			(xy 133.329541 -90.282399) (xy 133.279594 -90.304865) (xy 133.226947 -90.319955) (xy 133.199886 -90.324178)
			(xy 133.190852 -90.325805) (xy 133.174716 -90.334527) (xy 133.162676 -90.348365) (xy 133.156269 -90.365552)
			(xy 133.155944 -90.374724) (xy 133.155944 -91.327478) (xy 134.913368 -91.327478) (xy 134.917439 -91.271856)
			(xy 134.929565 -91.217419) (xy 134.949488 -91.165328) (xy 134.976784 -91.116693) (xy 135.01087 -91.07255)
			(xy 135.051019 -91.033841) (xy 135.096377 -91.00139) (xy 135.145977 -90.975889) (xy 135.198761 -90.957882)
			(xy 135.253604 -90.947752) (xy 135.309338 -90.945715) (xy 135.364775 -90.951815) (xy 135.418732 -90.965921)
			(xy 135.470061 -90.987733) (xy 135.517667 -91.016787) (xy 135.560535 -91.052462) (xy 135.597752 -91.093999)
			(xy 135.628525 -91.140512) (xy 135.652197 -91.191009) (xy 135.667731 -91.242642) (xy 139.708126 -91.242642)
			(xy 139.712197 -91.18702) (xy 139.724323 -91.132583) (xy 139.744246 -91.080492) (xy 139.771542 -91.031857)
			(xy 139.805628 -90.987714) (xy 139.845777 -90.949005) (xy 139.891135 -90.916554) (xy 139.940735 -90.891053)
			(xy 139.993519 -90.873046) (xy 140.048362 -90.862916) (xy 140.104096 -90.860879) (xy 140.159533 -90.866979)
			(xy 140.21349 -90.881085) (xy 140.264819 -90.902897) (xy 140.312425 -90.931951) (xy 140.355293 -90.967626)
			(xy 140.39251 -91.009163) (xy 140.423283 -91.055676) (xy 140.446955 -91.106173) (xy 140.463023 -91.15958)
			(xy 140.471143 -91.214756) (xy 140.471652 -91.242642) (xy 140.471143 -91.270528) (xy 140.463023 -91.325704)
			(xy 140.446955 -91.379111) (xy 140.423283 -91.429608) (xy 140.39251 -91.476121) (xy 140.355293 -91.517658)
			(xy 140.312425 -91.553333) (xy 140.264819 -91.582387) (xy 140.21349 -91.604199) (xy 140.159533 -91.618305)
			(xy 140.104096 -91.624405) (xy 140.048362 -91.622368) (xy 139.993519 -91.612238) (xy 139.940735 -91.594231)
			(xy 139.891135 -91.56873) (xy 139.845777 -91.536279) (xy 139.805628 -91.49757) (xy 139.771542 -91.453427)
			(xy 139.744246 -91.404792) (xy 139.724323 -91.352701) (xy 139.712197 -91.298264) (xy 139.708126 -91.242642)
			(xy 135.667731 -91.242642) (xy 135.668265 -91.244416) (xy 135.676385 -91.299592) (xy 135.676894 -91.327478)
			(xy 135.676385 -91.355364) (xy 135.668265 -91.41054) (xy 135.652197 -91.463947) (xy 135.628525 -91.514444)
			(xy 135.597752 -91.560957) (xy 135.560535 -91.602494) (xy 135.517667 -91.638169) (xy 135.470061 -91.667223)
			(xy 135.418732 -91.689035) (xy 135.364775 -91.703141) (xy 135.309338 -91.709241) (xy 135.253604 -91.707204)
			(xy 135.198761 -91.697074) (xy 135.145977 -91.679067) (xy 135.096377 -91.653566) (xy 135.051019 -91.621115)
			(xy 135.01087 -91.582406) (xy 134.976784 -91.538263) (xy 134.949488 -91.489628) (xy 134.929565 -91.437537)
			(xy 134.917439 -91.3831) (xy 134.913368 -91.327478) (xy 133.155944 -91.327478) (xy 133.155944 -92.645484)
			(xy 135.053576 -92.645484) (xy 135.057647 -92.589862) (xy 135.069773 -92.535425) (xy 135.089696 -92.483334)
			(xy 135.116992 -92.434699) (xy 135.151078 -92.390556) (xy 135.191227 -92.351847) (xy 135.236585 -92.319396)
			(xy 135.286185 -92.293895) (xy 135.338969 -92.275888) (xy 135.393812 -92.265758) (xy 135.449546 -92.263721)
			(xy 135.504983 -92.269821) (xy 135.55894 -92.283927) (xy 135.610269 -92.305739) (xy 135.657875 -92.334793)
			(xy 135.700743 -92.370468) (xy 135.714339 -92.385642) (xy 139.708126 -92.385642) (xy 139.712197 -92.33002)
			(xy 139.724323 -92.275583) (xy 139.744246 -92.223492) (xy 139.771542 -92.174857) (xy 139.805628 -92.130714)
			(xy 139.845777 -92.092005) (xy 139.891135 -92.059554) (xy 139.940735 -92.034053) (xy 139.993519 -92.016046)
			(xy 140.048362 -92.005916) (xy 140.104096 -92.003879) (xy 140.159533 -92.009979) (xy 140.21349 -92.024085)
			(xy 140.264819 -92.045897) (xy 140.312425 -92.074951) (xy 140.355293 -92.110626) (xy 140.39251 -92.152163)
			(xy 140.423283 -92.198676) (xy 140.446955 -92.249173) (xy 140.463023 -92.30258) (xy 140.471143 -92.357756)
			(xy 140.471652 -92.385642) (xy 140.471143 -92.413528) (xy 140.463023 -92.468704) (xy 140.446955 -92.522111)
			(xy 140.423283 -92.572608) (xy 140.39251 -92.619121) (xy 140.355293 -92.660658) (xy 140.312425 -92.696333)
			(xy 140.264819 -92.725387) (xy 140.21349 -92.747199) (xy 140.159533 -92.761305) (xy 140.104096 -92.767405)
			(xy 140.048362 -92.765368) (xy 139.993519 -92.755238) (xy 139.940735 -92.737231) (xy 139.891135 -92.71173)
			(xy 139.845777 -92.679279) (xy 139.805628 -92.64057) (xy 139.771542 -92.596427) (xy 139.744246 -92.547792)
			(xy 139.724323 -92.495701) (xy 139.712197 -92.441264) (xy 139.708126 -92.385642) (xy 135.714339 -92.385642)
			(xy 135.73796 -92.412005) (xy 135.768733 -92.458518) (xy 135.792405 -92.509015) (xy 135.808473 -92.562422)
			(xy 135.816593 -92.617598) (xy 135.817102 -92.645484) (xy 135.816593 -92.67337) (xy 135.808473 -92.728546)
			(xy 135.792405 -92.781953) (xy 135.768733 -92.83245) (xy 135.73796 -92.878963) (xy 135.700743 -92.9205)
			(xy 135.657875 -92.956175) (xy 135.610269 -92.985229) (xy 135.55894 -93.007041) (xy 135.504983 -93.021147)
			(xy 135.449546 -93.027247) (xy 135.393812 -93.02521) (xy 135.338969 -93.01508) (xy 135.286185 -92.997073)
			(xy 135.236585 -92.971572) (xy 135.191227 -92.939121) (xy 135.151078 -92.900412) (xy 135.116992 -92.856269)
			(xy 135.089696 -92.807634) (xy 135.069773 -92.755543) (xy 135.057647 -92.701106) (xy 135.053576 -92.645484)
			(xy 133.155944 -92.645484) (xy 133.155944 -93.767656) (xy 133.93623 -93.767656) (xy 133.940301 -93.712034)
			(xy 133.952427 -93.657597) (xy 133.97235 -93.605506) (xy 133.999646 -93.556871) (xy 134.033732 -93.512728)
			(xy 134.073881 -93.474019) (xy 134.119239 -93.441568) (xy 134.168839 -93.416067) (xy 134.221623 -93.39806)
			(xy 134.276466 -93.38793) (xy 134.3322 -93.385893) (xy 134.387637 -93.391993) (xy 134.441594 -93.406099)
			(xy 134.492923 -93.427911) (xy 134.540529 -93.456965) (xy 134.583397 -93.49264) (xy 134.615655 -93.528642)
			(xy 139.708126 -93.528642) (xy 139.712197 -93.47302) (xy 139.724323 -93.418583) (xy 139.744246 -93.366492)
			(xy 139.771542 -93.317857) (xy 139.805628 -93.273714) (xy 139.845777 -93.235005) (xy 139.891135 -93.202554)
			(xy 139.940735 -93.177053) (xy 139.993519 -93.159046) (xy 140.048362 -93.148916) (xy 140.104096 -93.146879)
			(xy 140.159533 -93.152979) (xy 140.21349 -93.167085) (xy 140.264819 -93.188897) (xy 140.312425 -93.217951)
			(xy 140.355293 -93.253626) (xy 140.39251 -93.295163) (xy 140.423283 -93.341676) (xy 140.446955 -93.392173)
			(xy 140.463023 -93.44558) (xy 140.471143 -93.500756) (xy 140.471652 -93.528642) (xy 140.471143 -93.556528)
			(xy 140.463023 -93.611704) (xy 140.446955 -93.665111) (xy 140.423283 -93.715608) (xy 140.39251 -93.762121)
			(xy 140.355293 -93.803658) (xy 140.312425 -93.839333) (xy 140.264819 -93.868387) (xy 140.21349 -93.890199)
			(xy 140.159533 -93.904305) (xy 140.104096 -93.910405) (xy 140.048362 -93.908368) (xy 139.993519 -93.898238)
			(xy 139.940735 -93.880231) (xy 139.891135 -93.85473) (xy 139.845777 -93.822279) (xy 139.805628 -93.78357)
			(xy 139.771542 -93.739427) (xy 139.744246 -93.690792) (xy 139.724323 -93.638701) (xy 139.712197 -93.584264)
			(xy 139.708126 -93.528642) (xy 134.615655 -93.528642) (xy 134.620614 -93.534177) (xy 134.651387 -93.58069)
			(xy 134.675059 -93.631187) (xy 134.691127 -93.684594) (xy 134.699247 -93.73977) (xy 134.699756 -93.767656)
			(xy 134.699247 -93.795542) (xy 134.691127 -93.850718) (xy 134.675059 -93.904125) (xy 134.651387 -93.954622)
			(xy 134.620614 -94.001135) (xy 134.583397 -94.042672) (xy 134.540529 -94.078347) (xy 134.492923 -94.107401)
			(xy 134.441594 -94.129213) (xy 134.387637 -94.143319) (xy 134.3322 -94.149419) (xy 134.276466 -94.147382)
			(xy 134.221623 -94.137252) (xy 134.168839 -94.119245) (xy 134.119239 -94.093744) (xy 134.073881 -94.061293)
			(xy 134.033732 -94.022584) (xy 133.999646 -93.978441) (xy 133.97235 -93.929806) (xy 133.952427 -93.877715)
			(xy 133.940301 -93.823278) (xy 133.93623 -93.767656) (xy 133.155944 -93.767656) (xy 133.155944 -94.451424)
			(xy 135.029192 -94.451424) (xy 135.033263 -94.395802) (xy 135.045389 -94.341365) (xy 135.065312 -94.289274)
			(xy 135.092608 -94.240639) (xy 135.126694 -94.196496) (xy 135.166843 -94.157787) (xy 135.212201 -94.125336)
			(xy 135.261801 -94.099835) (xy 135.314585 -94.081828) (xy 135.369428 -94.071698) (xy 135.425162 -94.069661)
			(xy 135.480599 -94.075761) (xy 135.534556 -94.089867) (xy 135.585885 -94.111679) (xy 135.633491 -94.140733)
			(xy 135.676359 -94.176408) (xy 135.713576 -94.217945) (xy 135.744349 -94.264458) (xy 135.768021 -94.314955)
			(xy 135.784089 -94.368362) (xy 135.792209 -94.423538) (xy 135.792718 -94.451424) (xy 135.792209 -94.47931)
			(xy 135.784089 -94.534486) (xy 135.768021 -94.587893) (xy 135.744349 -94.63839) (xy 135.722349 -94.671642)
			(xy 139.708126 -94.671642) (xy 139.712197 -94.61602) (xy 139.724323 -94.561583) (xy 139.744246 -94.509492)
			(xy 139.771542 -94.460857) (xy 139.805628 -94.416714) (xy 139.845777 -94.378005) (xy 139.891135 -94.345554)
			(xy 139.940735 -94.320053) (xy 139.993519 -94.302046) (xy 140.048362 -94.291916) (xy 140.104096 -94.289879)
			(xy 140.159533 -94.295979) (xy 140.21349 -94.310085) (xy 140.264819 -94.331897) (xy 140.312425 -94.360951)
			(xy 140.355293 -94.396626) (xy 140.39251 -94.438163) (xy 140.423283 -94.484676) (xy 140.446955 -94.535173)
			(xy 140.463023 -94.58858) (xy 140.471143 -94.643756) (xy 140.471652 -94.671642) (xy 140.471143 -94.699528)
			(xy 140.463023 -94.754704) (xy 140.446955 -94.808111) (xy 140.423283 -94.858608) (xy 140.39251 -94.905121)
			(xy 140.355293 -94.946658) (xy 140.312425 -94.982333) (xy 140.264819 -95.011387) (xy 140.21349 -95.033199)
			(xy 140.159533 -95.047305) (xy 140.104096 -95.053405) (xy 140.048362 -95.051368) (xy 139.993519 -95.041238)
			(xy 139.940735 -95.023231) (xy 139.891135 -94.99773) (xy 139.845777 -94.965279) (xy 139.805628 -94.92657)
			(xy 139.771542 -94.882427) (xy 139.744246 -94.833792) (xy 139.724323 -94.781701) (xy 139.712197 -94.727264)
			(xy 139.708126 -94.671642) (xy 135.722349 -94.671642) (xy 135.713576 -94.684903) (xy 135.676359 -94.72644)
			(xy 135.633491 -94.762115) (xy 135.585885 -94.791169) (xy 135.534556 -94.812981) (xy 135.480599 -94.827087)
			(xy 135.425162 -94.833187) (xy 135.369428 -94.83115) (xy 135.314585 -94.82102) (xy 135.261801 -94.803013)
			(xy 135.212201 -94.777512) (xy 135.166843 -94.745061) (xy 135.126694 -94.706352) (xy 135.092608 -94.662209)
			(xy 135.065312 -94.613574) (xy 135.045389 -94.561483) (xy 135.033263 -94.507046) (xy 135.029192 -94.451424)
			(xy 133.155944 -94.451424) (xy 133.155944 -95.49384) (xy 133.15558 -95.519748) (xy 134.274558 -95.519748)
			(xy 134.278629 -95.464126) (xy 134.290755 -95.409689) (xy 134.310678 -95.357598) (xy 134.337974 -95.308963)
			(xy 134.37206 -95.26482) (xy 134.412209 -95.226111) (xy 134.457567 -95.19366) (xy 134.507167 -95.168159)
			(xy 134.559951 -95.150152) (xy 134.614794 -95.140022) (xy 134.670528 -95.137985) (xy 134.725965 -95.144085)
			(xy 134.779922 -95.158191) (xy 134.819642 -95.17507) (xy 145.281648 -95.17507) (xy 145.285719 -95.119448)
			(xy 145.297845 -95.065011) (xy 145.317768 -95.01292) (xy 145.345064 -94.964285) (xy 145.37915 -94.920142)
			(xy 145.419299 -94.881433) (xy 145.464657 -94.848982) (xy 145.514257 -94.823481) (xy 145.567041 -94.805474)
			(xy 145.621884 -94.795344) (xy 145.677618 -94.793307) (xy 145.733055 -94.799407) (xy 145.787012 -94.813513)
			(xy 145.838341 -94.835325) (xy 145.885947 -94.864379) (xy 145.928815 -94.900054) (xy 145.966032 -94.941591)
			(xy 145.996805 -94.988104) (xy 146.020477 -95.038601) (xy 146.036545 -95.092008) (xy 146.044665 -95.147184)
			(xy 146.045174 -95.17507) (xy 146.044665 -95.202956) (xy 146.036545 -95.258132) (xy 146.020477 -95.311539)
			(xy 145.996805 -95.362036) (xy 145.966032 -95.408549) (xy 145.928815 -95.450086) (xy 145.885947 -95.485761)
			(xy 145.838341 -95.514815) (xy 145.787012 -95.536627) (xy 145.733055 -95.550733) (xy 145.677618 -95.556833)
			(xy 145.621884 -95.554796) (xy 145.567041 -95.544666) (xy 145.514257 -95.526659) (xy 145.464657 -95.501158)
			(xy 145.419299 -95.468707) (xy 145.37915 -95.429998) (xy 145.345064 -95.385855) (xy 145.317768 -95.33722)
			(xy 145.297845 -95.285129) (xy 145.285719 -95.230692) (xy 145.281648 -95.17507) (xy 134.819642 -95.17507)
			(xy 134.831251 -95.180003) (xy 134.878857 -95.209057) (xy 134.921725 -95.244732) (xy 134.958942 -95.286269)
			(xy 134.989715 -95.332782) (xy 135.013387 -95.383279) (xy 135.029455 -95.436686) (xy 135.037575 -95.491862)
			(xy 135.038084 -95.519748) (xy 135.037575 -95.547634) (xy 135.029455 -95.60281) (xy 135.013387 -95.656217)
			(xy 134.989715 -95.706714) (xy 134.958942 -95.753227) (xy 134.921725 -95.794764) (xy 134.897839 -95.814642)
			(xy 139.708126 -95.814642) (xy 139.712197 -95.75902) (xy 139.724323 -95.704583) (xy 139.744246 -95.652492)
			(xy 139.771542 -95.603857) (xy 139.805628 -95.559714) (xy 139.845777 -95.521005) (xy 139.891135 -95.488554)
			(xy 139.940735 -95.463053) (xy 139.993519 -95.445046) (xy 140.048362 -95.434916) (xy 140.104096 -95.432879)
			(xy 140.159533 -95.438979) (xy 140.21349 -95.453085) (xy 140.264819 -95.474897) (xy 140.312425 -95.503951)
			(xy 140.355293 -95.539626) (xy 140.39251 -95.581163) (xy 140.423283 -95.627676) (xy 140.446955 -95.678173)
			(xy 140.463023 -95.73158) (xy 140.471143 -95.786756) (xy 140.471652 -95.814642) (xy 140.471143 -95.842528)
			(xy 140.463023 -95.897704) (xy 140.446955 -95.951111) (xy 140.423283 -96.001608) (xy 140.39251 -96.048121)
			(xy 140.355293 -96.089658) (xy 140.351856 -96.092518) (xy 144.382234 -96.092518) (xy 144.386305 -96.036896)
			(xy 144.398431 -95.982459) (xy 144.418354 -95.930368) (xy 144.44565 -95.881733) (xy 144.479736 -95.83759)
			(xy 144.519885 -95.798881) (xy 144.565243 -95.76643) (xy 144.614843 -95.740929) (xy 144.667627 -95.722922)
			(xy 144.72247 -95.712792) (xy 144.778204 -95.710755) (xy 144.833641 -95.716855) (xy 144.887598 -95.730961)
			(xy 144.938927 -95.752773) (xy 144.986533 -95.781827) (xy 145.029401 -95.817502) (xy 145.066618 -95.859039)
			(xy 145.097391 -95.905552) (xy 145.121063 -95.956049) (xy 145.137131 -96.009456) (xy 145.145251 -96.064632)
			(xy 145.14576 -96.092518) (xy 145.145251 -96.120404) (xy 145.137131 -96.17558) (xy 145.121063 -96.228987)
			(xy 145.097391 -96.279484) (xy 145.066618 -96.325997) (xy 145.029401 -96.367534) (xy 144.986533 -96.403209)
			(xy 144.938927 -96.432263) (xy 144.887598 -96.454075) (xy 144.833641 -96.468181) (xy 144.778204 -96.474281)
			(xy 144.72247 -96.472244) (xy 144.667627 -96.462114) (xy 144.614843 -96.444107) (xy 144.565243 -96.418606)
			(xy 144.519885 -96.386155) (xy 144.479736 -96.347446) (xy 144.44565 -96.303303) (xy 144.418354 -96.254668)
			(xy 144.398431 -96.202577) (xy 144.386305 -96.14814) (xy 144.382234 -96.092518) (xy 140.351856 -96.092518)
			(xy 140.312425 -96.125333) (xy 140.264819 -96.154387) (xy 140.21349 -96.176199) (xy 140.159533 -96.190305)
			(xy 140.104096 -96.196405) (xy 140.048362 -96.194368) (xy 139.993519 -96.184238) (xy 139.940735 -96.166231)
			(xy 139.891135 -96.14073) (xy 139.845777 -96.108279) (xy 139.805628 -96.06957) (xy 139.771542 -96.025427)
			(xy 139.744246 -95.976792) (xy 139.724323 -95.924701) (xy 139.712197 -95.870264) (xy 139.708126 -95.814642)
			(xy 134.897839 -95.814642) (xy 134.878857 -95.830439) (xy 134.831251 -95.859493) (xy 134.779922 -95.881305)
			(xy 134.725965 -95.895411) (xy 134.670528 -95.901511) (xy 134.614794 -95.899474) (xy 134.559951 -95.889344)
			(xy 134.507167 -95.871337) (xy 134.457567 -95.845836) (xy 134.412209 -95.813385) (xy 134.37206 -95.774676)
			(xy 134.337974 -95.730533) (xy 134.310678 -95.681898) (xy 134.290755 -95.629807) (xy 134.278629 -95.57537)
			(xy 134.274558 -95.519748) (xy 133.15558 -95.519748) (xy 133.155478 -95.526994) (xy 133.148055 -95.592886)
			(xy 133.133305 -95.657534) (xy 133.111415 -95.720125) (xy 133.08266 -95.779875) (xy 133.047399 -95.836031)
			(xy 133.006077 -95.88789) (xy 132.98297 -95.91167) (xy 132.184394 -96.710246) (xy 134.734044 -96.710246)
			(xy 134.738115 -96.654624) (xy 134.750241 -96.600187) (xy 134.770164 -96.548096) (xy 134.79746 -96.499461)
			(xy 134.831546 -96.455318) (xy 134.871695 -96.416609) (xy 134.917053 -96.384158) (xy 134.966653 -96.358657)
			(xy 135.019437 -96.34065) (xy 135.07428 -96.33052) (xy 135.130014 -96.328483) (xy 135.185451 -96.334583)
			(xy 135.239408 -96.348689) (xy 135.290737 -96.370501) (xy 135.338343 -96.399555) (xy 135.381211 -96.43523)
			(xy 135.418428 -96.476767) (xy 135.449201 -96.52328) (xy 135.472873 -96.573777) (xy 135.488941 -96.627184)
			(xy 135.497061 -96.68236) (xy 135.49757 -96.710246) (xy 135.497061 -96.738132) (xy 135.488941 -96.793308)
			(xy 135.472873 -96.846715) (xy 135.449201 -96.897212) (xy 135.418428 -96.943725) (xy 135.405958 -96.957642)
			(xy 139.708126 -96.957642) (xy 139.712197 -96.90202) (xy 139.724323 -96.847583) (xy 139.744246 -96.795492)
			(xy 139.771542 -96.746857) (xy 139.805628 -96.702714) (xy 139.845777 -96.664005) (xy 139.891135 -96.631554)
			(xy 139.940735 -96.606053) (xy 139.993519 -96.588046) (xy 140.048362 -96.577916) (xy 140.104096 -96.575879)
			(xy 140.159533 -96.581979) (xy 140.21349 -96.596085) (xy 140.264819 -96.617897) (xy 140.312425 -96.646951)
			(xy 140.355293 -96.682626) (xy 140.39251 -96.724163) (xy 140.423283 -96.770676) (xy 140.446955 -96.821173)
			(xy 140.463023 -96.87458) (xy 140.471143 -96.929756) (xy 140.471652 -96.957642) (xy 140.471143 -96.985528)
			(xy 140.463023 -97.040704) (xy 140.446955 -97.094111) (xy 140.423283 -97.144608) (xy 140.39251 -97.191121)
			(xy 140.355293 -97.232658) (xy 140.312425 -97.268333) (xy 140.264819 -97.297387) (xy 140.21349 -97.319199)
			(xy 140.159533 -97.333305) (xy 140.104096 -97.339405) (xy 140.048362 -97.337368) (xy 139.993519 -97.327238)
			(xy 139.940735 -97.309231) (xy 139.891135 -97.28373) (xy 139.845777 -97.251279) (xy 139.805628 -97.21257)
			(xy 139.771542 -97.168427) (xy 139.744246 -97.119792) (xy 139.724323 -97.067701) (xy 139.712197 -97.013264)
			(xy 139.708126 -96.957642) (xy 135.405958 -96.957642) (xy 135.381211 -96.985262) (xy 135.338343 -97.020937)
			(xy 135.290737 -97.049991) (xy 135.239408 -97.071803) (xy 135.185451 -97.085909) (xy 135.130014 -97.092009)
			(xy 135.07428 -97.089972) (xy 135.019437 -97.079842) (xy 134.966653 -97.061835) (xy 134.917053 -97.036334)
			(xy 134.871695 -97.003883) (xy 134.831546 -96.965174) (xy 134.79746 -96.921031) (xy 134.770164 -96.872396)
			(xy 134.750241 -96.820305) (xy 134.738115 -96.765868) (xy 134.734044 -96.710246) (xy 132.184394 -96.710246)
			(xy 130.914394 -97.980246) (xy 134.734044 -97.980246) (xy 134.738115 -97.924624) (xy 134.750241 -97.870187)
			(xy 134.770164 -97.818096) (xy 134.79746 -97.769461) (xy 134.831546 -97.725318) (xy 134.871695 -97.686609)
			(xy 134.917053 -97.654158) (xy 134.966653 -97.628657) (xy 135.019437 -97.61065) (xy 135.07428 -97.60052)
			(xy 135.130014 -97.598483) (xy 135.185451 -97.604583) (xy 135.239408 -97.618689) (xy 135.290737 -97.640501)
			(xy 135.338343 -97.669555) (xy 135.381211 -97.70523) (xy 135.418428 -97.746767) (xy 135.449201 -97.79328)
			(xy 135.472873 -97.843777) (xy 135.488941 -97.897184) (xy 135.497061 -97.95236) (xy 135.49757 -97.980246)
			(xy 135.497061 -98.008132) (xy 135.488941 -98.063308) (xy 135.477709 -98.100642) (xy 137.211306 -98.100642)
			(xy 137.215377 -98.04502) (xy 137.227503 -97.990583) (xy 137.247426 -97.938492) (xy 137.274722 -97.889857)
			(xy 137.308808 -97.845714) (xy 137.348957 -97.807005) (xy 137.394315 -97.774554) (xy 137.443915 -97.749053)
			(xy 137.496699 -97.731046) (xy 137.551542 -97.720916) (xy 137.607276 -97.718879) (xy 137.662713 -97.724979)
			(xy 137.71667 -97.739085) (xy 137.767999 -97.760897) (xy 137.810275 -97.786698) (xy 140.222984 -97.786698)
			(xy 140.227055 -97.731076) (xy 140.239181 -97.676639) (xy 140.259104 -97.624548) (xy 140.2864 -97.575913)
			(xy 140.320486 -97.53177) (xy 140.360635 -97.493061) (xy 140.405993 -97.46061) (xy 140.455593 -97.435109)
			(xy 140.508377 -97.417102) (xy 140.56322 -97.406972) (xy 140.618954 -97.404935) (xy 140.674391 -97.411035)
			(xy 140.728348 -97.425141) (xy 140.779677 -97.446953) (xy 140.827283 -97.476007) (xy 140.870151 -97.511682)
			(xy 140.907368 -97.553219) (xy 140.938141 -97.599732) (xy 140.961813 -97.650229) (xy 140.977881 -97.703636)
			(xy 140.986001 -97.758812) (xy 140.98651 -97.786698) (xy 140.986001 -97.814584) (xy 140.977881 -97.86976)
			(xy 140.961813 -97.923167) (xy 140.938141 -97.973664) (xy 140.907368 -98.020177) (xy 140.870151 -98.061714)
			(xy 140.827283 -98.097389) (xy 140.779677 -98.126443) (xy 140.728348 -98.148255) (xy 140.674391 -98.162361)
			(xy 140.618954 -98.168461) (xy 140.56322 -98.166424) (xy 140.508377 -98.156294) (xy 140.455593 -98.138287)
			(xy 140.405993 -98.112786) (xy 140.360635 -98.080335) (xy 140.320486 -98.041626) (xy 140.2864 -97.997483)
			(xy 140.259104 -97.948848) (xy 140.239181 -97.896757) (xy 140.227055 -97.84232) (xy 140.222984 -97.786698)
			(xy 137.810275 -97.786698) (xy 137.815605 -97.789951) (xy 137.858473 -97.825626) (xy 137.89569 -97.867163)
			(xy 137.926463 -97.913676) (xy 137.950135 -97.964173) (xy 137.966203 -98.01758) (xy 137.974323 -98.072756)
			(xy 137.974832 -98.100642) (xy 137.974323 -98.128528) (xy 137.966203 -98.183704) (xy 137.950135 -98.237111)
			(xy 137.926463 -98.287608) (xy 137.89569 -98.334121) (xy 137.858473 -98.375658) (xy 137.815605 -98.411333)
			(xy 137.767999 -98.440387) (xy 137.71667 -98.462199) (xy 137.662713 -98.476305) (xy 137.607276 -98.482405)
			(xy 137.551542 -98.480368) (xy 137.496699 -98.470238) (xy 137.443915 -98.452231) (xy 137.394315 -98.42673)
			(xy 137.348957 -98.394279) (xy 137.308808 -98.35557) (xy 137.274722 -98.311427) (xy 137.247426 -98.262792)
			(xy 137.227503 -98.210701) (xy 137.215377 -98.156264) (xy 137.211306 -98.100642) (xy 135.477709 -98.100642)
			(xy 135.472873 -98.116715) (xy 135.449201 -98.167212) (xy 135.418428 -98.213725) (xy 135.381211 -98.255262)
			(xy 135.338343 -98.290937) (xy 135.290737 -98.319991) (xy 135.239408 -98.341803) (xy 135.185451 -98.355909)
			(xy 135.130014 -98.362009) (xy 135.07428 -98.359972) (xy 135.019437 -98.349842) (xy 134.966653 -98.331835)
			(xy 134.917053 -98.306334) (xy 134.871695 -98.273883) (xy 134.831546 -98.235174) (xy 134.79746 -98.191031)
			(xy 134.770164 -98.142396) (xy 134.750241 -98.090305) (xy 134.738115 -98.035868) (xy 134.734044 -97.980246)
			(xy 130.914394 -97.980246) (xy 129.650998 -99.243642) (xy 135.047988 -99.243642) (xy 135.052059 -99.18802)
			(xy 135.064185 -99.133583) (xy 135.084108 -99.081492) (xy 135.111404 -99.032857) (xy 135.14549 -98.988714)
			(xy 135.185639 -98.950005) (xy 135.230997 -98.917554) (xy 135.280597 -98.892053) (xy 135.333381 -98.874046)
			(xy 135.388224 -98.863916) (xy 135.443958 -98.861879) (xy 135.499395 -98.867979) (xy 135.553352 -98.882085)
			(xy 135.604681 -98.903897) (xy 135.652287 -98.932951) (xy 135.695155 -98.968626) (xy 135.732372 -99.010163)
			(xy 135.763145 -99.056676) (xy 135.786817 -99.107173) (xy 135.802885 -99.16058) (xy 135.811005 -99.215756)
			(xy 135.811514 -99.243642) (xy 135.811005 -99.271528) (xy 135.802885 -99.326704) (xy 135.786817 -99.380111)
			(xy 135.763145 -99.430608) (xy 135.732372 -99.477121) (xy 135.695155 -99.518658) (xy 135.652287 -99.554333)
			(xy 135.604681 -99.583387) (xy 135.553352 -99.605199) (xy 135.499395 -99.619305) (xy 135.483209 -99.621086)
			(xy 137.294618 -99.621086) (xy 137.298689 -99.565464) (xy 137.310815 -99.511027) (xy 137.330738 -99.458936)
			(xy 137.358034 -99.410301) (xy 137.39212 -99.366158) (xy 137.432269 -99.327449) (xy 137.477627 -99.294998)
			(xy 137.527227 -99.269497) (xy 137.580011 -99.25149) (xy 137.634854 -99.24136) (xy 137.690588 -99.239323)
			(xy 137.729839 -99.243642) (xy 139.729462 -99.243642) (xy 139.733533 -99.18802) (xy 139.745659 -99.133583)
			(xy 139.765582 -99.081492) (xy 139.792878 -99.032857) (xy 139.826964 -98.988714) (xy 139.867113 -98.950005)
			(xy 139.912471 -98.917554) (xy 139.962071 -98.892053) (xy 140.014855 -98.874046) (xy 140.069698 -98.863916)
			(xy 140.125432 -98.861879) (xy 140.180869 -98.867979) (xy 140.234826 -98.882085) (xy 140.286155 -98.903897)
			(xy 140.333761 -98.932951) (xy 140.376629 -98.968626) (xy 140.413846 -99.010163) (xy 140.444619 -99.056676)
			(xy 140.468291 -99.107173) (xy 140.484359 -99.16058) (xy 140.492479 -99.215756) (xy 140.492988 -99.243642)
			(xy 140.492479 -99.271528) (xy 140.484359 -99.326704) (xy 140.468291 -99.380111) (xy 140.444619 -99.430608)
			(xy 140.413846 -99.477121) (xy 140.376629 -99.518658) (xy 140.333761 -99.554333) (xy 140.286155 -99.583387)
			(xy 140.234826 -99.605199) (xy 140.180869 -99.619305) (xy 140.125432 -99.625405) (xy 140.069698 -99.623368)
			(xy 140.014855 -99.613238) (xy 139.962071 -99.595231) (xy 139.912471 -99.56973) (xy 139.867113 -99.537279)
			(xy 139.826964 -99.49857) (xy 139.792878 -99.454427) (xy 139.765582 -99.405792) (xy 139.745659 -99.353701)
			(xy 139.733533 -99.299264) (xy 139.729462 -99.243642) (xy 137.729839 -99.243642) (xy 137.746025 -99.245423)
			(xy 137.799982 -99.259529) (xy 137.851311 -99.281341) (xy 137.898917 -99.310395) (xy 137.941785 -99.34607)
			(xy 137.979002 -99.387607) (xy 138.009775 -99.43412) (xy 138.033447 -99.484617) (xy 138.049515 -99.538024)
			(xy 138.057635 -99.5932) (xy 138.058144 -99.621086) (xy 138.057635 -99.648972) (xy 138.049515 -99.704148)
			(xy 138.033447 -99.757555) (xy 138.009775 -99.808052) (xy 137.979002 -99.854565) (xy 137.941785 -99.896102)
			(xy 137.898917 -99.931777) (xy 137.851311 -99.960831) (xy 137.799982 -99.982643) (xy 137.746025 -99.996749)
			(xy 137.690588 -100.002849) (xy 137.634854 -100.000812) (xy 137.580011 -99.990682) (xy 137.527227 -99.972675)
			(xy 137.477627 -99.947174) (xy 137.432269 -99.914723) (xy 137.39212 -99.876014) (xy 137.358034 -99.831871)
			(xy 137.330738 -99.783236) (xy 137.310815 -99.731145) (xy 137.298689 -99.676708) (xy 137.294618 -99.621086)
			(xy 135.483209 -99.621086) (xy 135.443958 -99.625405) (xy 135.388224 -99.623368) (xy 135.333381 -99.613238)
			(xy 135.280597 -99.595231) (xy 135.230997 -99.56973) (xy 135.185639 -99.537279) (xy 135.14549 -99.49857)
			(xy 135.111404 -99.454427) (xy 135.084108 -99.405792) (xy 135.064185 -99.353701) (xy 135.052059 -99.299264)
			(xy 135.047988 -99.243642) (xy 129.650998 -99.243642) (xy 127.916432 -100.978208) (xy 134.74395 -100.978208)
			(xy 134.748021 -100.922586) (xy 134.760147 -100.868149) (xy 134.78007 -100.816058) (xy 134.807366 -100.767423)
			(xy 134.841452 -100.72328) (xy 134.881601 -100.684571) (xy 134.926959 -100.65212) (xy 134.976559 -100.626619)
			(xy 135.029343 -100.608612) (xy 135.084186 -100.598482) (xy 135.13992 -100.596445) (xy 135.195357 -100.602545)
			(xy 135.249314 -100.616651) (xy 135.300643 -100.638463) (xy 135.348249 -100.667517) (xy 135.391117 -100.703192)
			(xy 135.428334 -100.744729) (xy 135.459107 -100.791242) (xy 135.482779 -100.841739) (xy 135.498847 -100.895146)
			(xy 135.506967 -100.950322) (xy 135.507476 -100.978208) (xy 135.506967 -101.006094) (xy 135.498847 -101.06127)
			(xy 135.482779 -101.114677) (xy 135.459107 -101.165174) (xy 135.428334 -101.211687) (xy 135.391117 -101.253224)
			(xy 135.348249 -101.288899) (xy 135.300643 -101.317953) (xy 135.249314 -101.339765) (xy 135.195357 -101.353871)
			(xy 135.13992 -101.359971) (xy 135.084186 -101.357934) (xy 135.029343 -101.347804) (xy 134.976559 -101.329797)
			(xy 134.926959 -101.304296) (xy 134.881601 -101.271845) (xy 134.841452 -101.233136) (xy 134.807366 -101.188993)
			(xy 134.78007 -101.140358) (xy 134.760147 -101.088267) (xy 134.748021 -101.03383) (xy 134.74395 -100.978208)
			(xy 127.916432 -100.978208) (xy 124.709428 -104.185212) (xy 124.703118 -104.192152) (xy 124.695551 -104.209297)
			(xy 124.694644 -104.228016) (xy 124.697236 -104.237028) (xy 124.730002 -104.33685) (xy 124.751846 -104.355392)
			(xy 124.766324 -104.357424) (xy 124.793124 -104.361889) (xy 124.845188 -104.377415) (xy 124.894522 -104.400171)
			(xy 124.940128 -104.429697) (xy 124.981083 -104.465397) (xy 125.016557 -104.506546) (xy 125.045833 -104.552313)
			(xy 125.068319 -104.601771) (xy 125.083559 -104.65392) (xy 125.091245 -104.707703) (xy 125.091698 -104.734868)
			(xy 125.091237 -104.762122) (xy 125.083484 -104.816076) (xy 125.06813 -104.868377) (xy 125.045489 -104.917961)
			(xy 125.016022 -104.963817) (xy 124.980328 -105.005013) (xy 124.939135 -105.040709) (xy 124.89328 -105.070179)
			(xy 124.843698 -105.092822) (xy 124.791397 -105.108179) (xy 124.737444 -105.115935) (xy 124.71019 -105.116376)
			(xy 124.683032 -105.115889) (xy 124.629267 -105.108174) (xy 124.577139 -105.092914) (xy 124.5277 -105.070418)
			(xy 124.48195 -105.04114) (xy 124.440813 -105.005672) (xy 124.40512 -104.96473) (xy 124.375591 -104.919142)
			(xy 124.352824 -104.869828) (xy 124.337277 -104.817785) (xy 124.332746 -104.791002) (xy 124.330714 -104.776524)
			(xy 124.312172 -104.75468) (xy 124.21235 -104.721914) (xy 124.20333 -104.719375) (xy 124.18463 -104.720275)
			(xy 124.167503 -104.727838) (xy 124.160534 -104.734106) (xy 122.884438 -106.010202) (xy 122.876549 -106.018969)
			(xy 122.869044 -106.041301) (xy 122.872208 -106.064647) (xy 122.878342 -106.074718) (xy 122.893982 -106.09864)
			(xy 122.91875 -106.150146) (xy 122.935578 -106.204765) (xy 122.94409 -106.26128) (xy 122.944408 -106.277918)
			(xy 123.681234 -106.277918) (xy 123.685305 -106.222296) (xy 123.697431 -106.167859) (xy 123.717354 -106.115768)
			(xy 123.74465 -106.067133) (xy 123.778736 -106.02299) (xy 123.818885 -105.984281) (xy 123.864243 -105.95183)
			(xy 123.913843 -105.926329) (xy 123.966627 -105.908322) (xy 124.02147 -105.898192) (xy 124.077204 -105.896155)
			(xy 124.132641 -105.902255) (xy 124.186598 -105.916361) (xy 124.237927 -105.938173) (xy 124.285533 -105.967227)
			(xy 124.328401 -106.002902) (xy 124.365618 -106.044439) (xy 124.396391 -106.090952) (xy 124.420063 -106.141449)
			(xy 124.436131 -106.194856) (xy 124.444251 -106.250032) (xy 124.44476 -106.277918) (xy 124.444251 -106.305804)
			(xy 124.436131 -106.36098) (xy 124.420063 -106.414387) (xy 124.396391 -106.464884) (xy 124.365618 -106.511397)
			(xy 124.328401 -106.552934) (xy 124.285533 -106.588609) (xy 124.237927 -106.617663) (xy 124.186598 -106.639475)
			(xy 124.132641 -106.653581) (xy 124.077204 -106.659681) (xy 124.02147 -106.657644) (xy 123.966627 -106.647514)
			(xy 123.913843 -106.629507) (xy 123.864243 -106.604006) (xy 123.818885 -106.571555) (xy 123.778736 -106.532846)
			(xy 123.74465 -106.488703) (xy 123.717354 -106.440068) (xy 123.697431 -106.387977) (xy 123.685305 -106.33354)
			(xy 123.681234 -106.277918) (xy 122.944408 -106.277918) (xy 122.944636 -106.289856) (xy 122.944176 -106.317112)
			(xy 122.936424 -106.371069) (xy 122.921072 -106.423374) (xy 122.898433 -106.472961) (xy 122.868966 -106.518822)
			(xy 122.833273 -106.560022) (xy 122.79208 -106.595723) (xy 122.746224 -106.625198) (xy 122.696641 -106.647847)
			(xy 122.644339 -106.663209) (xy 122.590384 -106.670971) (xy 122.563128 -106.671364) (xy 122.538744 -106.670602)
			(xy 122.538744 -108.42244) (xy 122.538278 -108.455594) (xy 122.530855 -108.521486) (xy 122.516105 -108.586134)
			(xy 122.494215 -108.648725) (xy 122.46546 -108.708475) (xy 122.430199 -108.764631) (xy 122.388877 -108.81649)
			(xy 122.36577 -108.84027) (xy 121.499122 -109.706918) (xy 121.915172 -109.706918) (xy 121.919243 -109.651296)
			(xy 121.931369 -109.596859) (xy 121.951292 -109.544768) (xy 121.978588 -109.496133) (xy 122.012674 -109.45199)
			(xy 122.052823 -109.413281) (xy 122.098181 -109.38083) (xy 122.147781 -109.355329) (xy 122.200565 -109.337322)
			(xy 122.255408 -109.327192) (xy 122.311142 -109.325155) (xy 122.366579 -109.331255) (xy 122.420536 -109.345361)
			(xy 122.471865 -109.367173) (xy 122.519471 -109.396227) (xy 122.562339 -109.431902) (xy 122.599556 -109.473439)
			(xy 122.630329 -109.519952) (xy 122.654001 -109.570449) (xy 122.65685 -109.579918) (xy 123.947172 -109.579918)
			(xy 123.951243 -109.524296) (xy 123.963369 -109.469859) (xy 123.983292 -109.417768) (xy 124.010588 -109.369133)
			(xy 124.044674 -109.32499) (xy 124.084823 -109.286281) (xy 124.130181 -109.25383) (xy 124.179781 -109.228329)
			(xy 124.232565 -109.210322) (xy 124.287408 -109.200192) (xy 124.343142 -109.198155) (xy 124.398579 -109.204255)
			(xy 124.452536 -109.218361) (xy 124.503865 -109.240173) (xy 124.551471 -109.269227) (xy 124.594339 -109.304902)
			(xy 124.631556 -109.346439) (xy 124.662329 -109.392952) (xy 124.686001 -109.443449) (xy 124.702069 -109.496856)
			(xy 124.710189 -109.552032) (xy 124.710698 -109.579918) (xy 124.710189 -109.607804) (xy 124.702069 -109.66298)
			(xy 124.686001 -109.716387) (xy 124.662329 -109.766884) (xy 124.631556 -109.813397) (xy 124.594339 -109.854934)
			(xy 124.551471 -109.890609) (xy 124.503865 -109.919663) (xy 124.452536 -109.941475) (xy 124.398579 -109.955581)
			(xy 124.343142 -109.961681) (xy 124.287408 -109.959644) (xy 124.232565 -109.949514) (xy 124.179781 -109.931507)
			(xy 124.130181 -109.906006) (xy 124.084823 -109.873555) (xy 124.044674 -109.834846) (xy 124.010588 -109.790703)
			(xy 123.983292 -109.742068) (xy 123.963369 -109.689977) (xy 123.951243 -109.63554) (xy 123.947172 -109.579918)
			(xy 122.65685 -109.579918) (xy 122.670069 -109.623856) (xy 122.678189 -109.679032) (xy 122.678698 -109.706918)
			(xy 122.678189 -109.734804) (xy 122.670069 -109.78998) (xy 122.654001 -109.843387) (xy 122.630329 -109.893884)
			(xy 122.599556 -109.940397) (xy 122.562339 -109.981934) (xy 122.519471 -110.017609) (xy 122.471865 -110.046663)
			(xy 122.420536 -110.068475) (xy 122.366579 -110.082581) (xy 122.311142 -110.088681) (xy 122.255408 -110.086644)
			(xy 122.200565 -110.076514) (xy 122.147781 -110.058507) (xy 122.098181 -110.033006) (xy 122.052823 -110.000555)
			(xy 122.012674 -109.961846) (xy 121.978588 -109.917703) (xy 121.951292 -109.869068) (xy 121.931369 -109.816977)
			(xy 121.919243 -109.76254) (xy 121.915172 -109.706918) (xy 121.499122 -109.706918) (xy 114.228286 -116.977754)
			(xy 116.998945 -116.977754) (xy 116.998945 -116.923246) (xy 117.006702 -116.869293) (xy 117.022059 -116.816994)
			(xy 117.044702 -116.767412) (xy 117.074171 -116.721558) (xy 117.109866 -116.680364) (xy 117.151061 -116.644669)
			(xy 117.196916 -116.6152) (xy 117.246498 -116.592557) (xy 117.298797 -116.577201) (xy 117.35275 -116.569445)
			(xy 117.380004 -116.568982) (xy 117.408923 -116.569466) (xy 117.466097 -116.578198) (xy 117.521298 -116.595461)
			(xy 117.57326 -116.620859) (xy 117.620793 -116.65381) (xy 117.662806 -116.693559) (xy 117.680994 -116.716048)
			(xy 117.688605 -116.72485) (xy 117.709503 -116.735035) (xy 117.721126 -116.735606) (xy 117.800882 -116.735606)
			(xy 117.81251 -116.73504) (xy 117.83342 -116.72487) (xy 117.841014 -116.716048) (xy 117.859184 -116.693547)
			(xy 117.90121 -116.653815) (xy 117.948749 -116.62088) (xy 118.000715 -116.595495) (xy 118.055915 -116.578242)
			(xy 118.113087 -116.569516) (xy 118.142004 -116.568982) (xy 118.169254 -116.569489) (xy 118.2232 -116.577245)
			(xy 118.275493 -116.5926) (xy 118.325068 -116.615241) (xy 118.370917 -116.644707) (xy 118.412106 -116.680397)
			(xy 118.447796 -116.721586) (xy 118.477261 -116.767435) (xy 118.499901 -116.817011) (xy 118.515256 -116.869304)
			(xy 118.523012 -116.92325) (xy 118.523012 -116.97775) (xy 118.515256 -117.031696) (xy 118.499901 -117.083989)
			(xy 118.477261 -117.133565) (xy 118.447796 -117.179414) (xy 118.412106 -117.220603) (xy 118.370917 -117.256293)
			(xy 118.325068 -117.285759) (xy 118.275493 -117.3084) (xy 118.2232 -117.323755) (xy 118.169254 -117.331511)
			(xy 118.142004 -117.331998) (xy 118.113087 -117.331477) (xy 118.055916 -117.322749) (xy 118.000717 -117.305491)
			(xy 117.948756 -117.2801) (xy 117.901222 -117.247157) (xy 117.859204 -117.207417) (xy 117.841014 -117.184932)
			(xy 117.833403 -117.17613) (xy 117.812505 -117.165946) (xy 117.800882 -117.165374) (xy 117.721126 -117.165374)
			(xy 117.709494 -117.165916) (xy 117.688582 -117.1761) (xy 117.680994 -117.184932) (xy 117.662814 -117.207425)
			(xy 117.620791 -117.247158) (xy 117.573254 -117.280095) (xy 117.52129 -117.305482) (xy 117.466091 -117.322736)
			(xy 117.408921 -117.331464) (xy 117.380004 -117.331998) (xy 117.35275 -117.331555) (xy 117.298797 -117.323799)
			(xy 117.246498 -117.308443) (xy 117.196916 -117.2858) (xy 117.151061 -117.256331) (xy 117.109866 -117.220636)
			(xy 117.074171 -117.179442) (xy 117.044702 -117.133588) (xy 117.022059 -117.084006) (xy 117.006702 -117.031707)
			(xy 116.998945 -116.977754) (xy 114.228286 -116.977754) (xy 113.47196 -117.73408) (xy 116.39626 -117.73408)
			(xy 116.400331 -117.678458) (xy 116.412457 -117.624021) (xy 116.43238 -117.57193) (xy 116.459676 -117.523295)
			(xy 116.493762 -117.479152) (xy 116.533911 -117.440443) (xy 116.579269 -117.407992) (xy 116.628869 -117.382491)
			(xy 116.681653 -117.364484) (xy 116.736496 -117.354354) (xy 116.79223 -117.352317) (xy 116.847667 -117.358417)
			(xy 116.901624 -117.372523) (xy 116.952953 -117.394335) (xy 117.000559 -117.423389) (xy 117.043427 -117.459064)
			(xy 117.080644 -117.500601) (xy 117.111417 -117.547114) (xy 117.135089 -117.597611) (xy 117.151157 -117.651018)
			(xy 117.159277 -117.706194) (xy 117.159786 -117.73408) (xy 117.159277 -117.761966) (xy 117.151157 -117.817142)
			(xy 117.135089 -117.870549) (xy 117.111417 -117.921046) (xy 117.080644 -117.967559) (xy 117.043427 -118.009096)
			(xy 117.021849 -118.027053) (xy 117.690342 -118.027053) (xy 117.690342 -117.972547) (xy 117.698099 -117.918594)
			(xy 117.713455 -117.866295) (xy 117.736098 -117.816714) (xy 117.765566 -117.77086) (xy 117.80126 -117.729666)
			(xy 117.842453 -117.693971) (xy 117.888307 -117.664502) (xy 117.937888 -117.641858) (xy 117.990187 -117.626501)
			(xy 118.044139 -117.618742) (xy 118.071392 -117.618256) (xy 118.10031 -117.618759) (xy 118.157483 -117.627488)
			(xy 118.212683 -117.644748) (xy 118.264645 -117.670142) (xy 118.312178 -117.703089) (xy 118.354193 -117.742834)
			(xy 118.372382 -117.765322) (xy 118.380003 -117.774115) (xy 118.400893 -117.784306) (xy 118.412514 -117.78488)
			(xy 118.49227 -117.78488) (xy 118.503899 -117.784316) (xy 118.524809 -117.774146) (xy 118.532402 -117.765322)
			(xy 118.550597 -117.742842) (xy 118.592616 -117.703106) (xy 118.640149 -117.670166) (xy 118.69211 -117.644776)
			(xy 118.747307 -117.62752) (xy 118.804476 -117.618791) (xy 118.833392 -117.618256) (xy 118.860643 -117.618791)
			(xy 118.914589 -117.626546) (xy 118.966883 -117.6419) (xy 119.01646 -117.66454) (xy 119.062309 -117.694005)
			(xy 119.103499 -117.729695) (xy 119.13919 -117.770884) (xy 119.168656 -117.816733) (xy 119.191297 -117.866309)
			(xy 119.206652 -117.918603) (xy 119.214409 -117.972549) (xy 119.214409 -118.027051) (xy 119.206652 -118.080997)
			(xy 119.191297 -118.133291) (xy 119.168656 -118.182867) (xy 119.13919 -118.228716) (xy 119.103499 -118.269905)
			(xy 119.062309 -118.305595) (xy 119.01646 -118.33506) (xy 118.966883 -118.3577) (xy 118.914589 -118.373054)
			(xy 118.860643 -118.380809) (xy 118.833392 -118.381272) (xy 118.804477 -118.380698) (xy 118.747308 -118.371982)
			(xy 118.69211 -118.354736) (xy 118.640148 -118.329355) (xy 118.592612 -118.29642) (xy 118.550594 -118.256687)
			(xy 118.532402 -118.234206) (xy 118.524783 -118.225411) (xy 118.503891 -118.21522) (xy 118.49227 -118.214648)
			(xy 118.412514 -118.214648) (xy 118.400882 -118.215193) (xy 118.379972 -118.225376) (xy 118.372382 -118.234206)
			(xy 118.354203 -118.256699) (xy 118.31218 -118.296434) (xy 118.264643 -118.329371) (xy 118.212679 -118.354758)
			(xy 118.15748 -118.372012) (xy 118.100309 -118.380738) (xy 118.071392 -118.381272) (xy 118.044139 -118.380858)
			(xy 117.990187 -118.373099) (xy 117.937888 -118.357742) (xy 117.888307 -118.335098) (xy 117.842453 -118.305629)
			(xy 117.80126 -118.269934) (xy 117.765566 -118.22874) (xy 117.736098 -118.182886) (xy 117.713455 -118.133305)
			(xy 117.698099 -118.081006) (xy 117.690342 -118.027053) (xy 117.021849 -118.027053) (xy 117.000559 -118.044771)
			(xy 116.952953 -118.073825) (xy 116.901624 -118.095637) (xy 116.847667 -118.109743) (xy 116.79223 -118.115843)
			(xy 116.736496 -118.113806) (xy 116.681653 -118.103676) (xy 116.628869 -118.085669) (xy 116.579269 -118.060168)
			(xy 116.533911 -118.027717) (xy 116.493762 -117.989008) (xy 116.459676 -117.944865) (xy 116.43238 -117.89623)
			(xy 116.412457 -117.844139) (xy 116.400331 -117.789702) (xy 116.39626 -117.73408) (xy 113.47196 -117.73408)
			(xy 112.458754 -118.747286) (xy 112.451388 -118.761002) (xy 112.450118 -118.768622) (xy 112.443214 -118.803799)
			(xy 112.422005 -118.872278) (xy 112.392674 -118.937692) (xy 112.355653 -118.999081) (xy 112.311483 -119.055546)
			(xy 112.290232 -119.077486) (xy 114.209068 -119.077486) (xy 114.209565 -119.050235) (xy 114.217322 -118.996289)
			(xy 114.232678 -118.943996) (xy 114.255319 -118.894421) (xy 114.284785 -118.848571) (xy 114.320475 -118.807382)
			(xy 114.361663 -118.771691) (xy 114.407512 -118.742224) (xy 114.457087 -118.719582) (xy 114.50938 -118.704225)
			(xy 114.563326 -118.696465) (xy 114.590576 -118.695978) (xy 114.617487 -118.696426) (xy 114.670771 -118.704012)
			(xy 114.722461 -118.719009) (xy 114.771532 -118.74112) (xy 114.817009 -118.769905) (xy 114.857991 -118.804795)
			(xy 114.893664 -118.845096) (xy 114.923322 -118.890009) (xy 114.946376 -118.938644) (xy 114.954812 -118.964202)
			(xy 114.954812 -118.964456) (xy 114.956795 -118.970148) (xy 114.963089 -118.980423) (xy 114.967258 -118.984776)
			(xy 115.029488 -119.047006) (xy 116.309138 -119.047006) (xy 116.313209 -118.991384) (xy 116.325335 -118.936947)
			(xy 116.345258 -118.884856) (xy 116.372554 -118.836221) (xy 116.40664 -118.792078) (xy 116.446789 -118.753369)
			(xy 116.492147 -118.720918) (xy 116.541747 -118.695417) (xy 116.594531 -118.67741) (xy 116.649374 -118.66728)
			(xy 116.705108 -118.665243) (xy 116.760545 -118.671343) (xy 116.814502 -118.685449) (xy 116.865831 -118.707261)
			(xy 116.913437 -118.736315) (xy 116.956305 -118.77199) (xy 116.993522 -118.813527) (xy 117.024295 -118.86004)
			(xy 117.047967 -118.910537) (xy 117.064035 -118.963944) (xy 117.072155 -119.01912) (xy 117.072664 -119.047006)
			(xy 117.072155 -119.074892) (xy 117.064035 -119.130068) (xy 117.047967 -119.183475) (xy 117.024295 -119.233972)
			(xy 116.993522 -119.280485) (xy 116.956305 -119.322022) (xy 116.913437 -119.357697) (xy 116.865831 -119.386751)
			(xy 116.814502 -119.408563) (xy 116.760545 -119.422669) (xy 116.705108 -119.428769) (xy 116.649374 -119.426732)
			(xy 116.594531 -119.416602) (xy 116.541747 -119.398595) (xy 116.492147 -119.373094) (xy 116.446789 -119.340643)
			(xy 116.40664 -119.301934) (xy 116.372554 -119.257791) (xy 116.345258 -119.209156) (xy 116.325335 -119.157065)
			(xy 116.313209 -119.102628) (xy 116.309138 -119.047006) (xy 115.029488 -119.047006) (xy 116.194586 -120.212104)
			(xy 116.203718 -120.220169) (xy 116.226931 -120.227457) (xy 116.239036 -120.226074) (xy 116.33327 -120.209564)
			(xy 116.352828 -120.194832) (xy 116.358162 -120.18391) (xy 116.358162 -120.183402) (xy 116.370064 -120.159232)
			(xy 116.399725 -120.114256) (xy 116.435418 -120.073899) (xy 116.476431 -120.038962) (xy 116.52195 -120.010141)
			(xy 116.57107 -119.988008) (xy 116.622815 -119.973004) (xy 116.676156 -119.965426) (xy 116.703094 -119.964962)
			(xy 116.730344 -119.965483) (xy 116.784289 -119.973238) (xy 116.836581 -119.988591) (xy 116.886156 -120.011229)
			(xy 116.932005 -120.040692) (xy 116.973195 -120.07638) (xy 117.008886 -120.117566) (xy 117.038353 -120.163412)
			(xy 117.060996 -120.212985) (xy 117.076354 -120.265276) (xy 117.084114 -120.31922) (xy 117.084602 -120.34647)
			(xy 117.084026 -120.375026) (xy 117.07553 -120.431501) (xy 117.05871 -120.486078) (xy 117.03394 -120.537538)
			(xy 117.001775 -120.58473) (xy 116.962934 -120.626598) (xy 116.918284 -120.662208) (xy 116.868824 -120.690763)
			(xy 116.81566 -120.711624) (xy 116.75998 -120.724326) (xy 116.731542 -120.726962) (xy 116.721765 -120.728189)
			(xy 116.704126 -120.736923) (xy 116.697252 -120.74398) (xy 116.67617 -120.76811) (xy 116.669982 -120.775695)
			(xy 116.663458 -120.794134) (xy 116.66347 -120.803924) (xy 116.663724 -120.81891) (xy 116.663724 -121.067152)
			(xy 117.690368 -121.067152) (xy 117.690368 -121.012648) (xy 117.698124 -120.9587) (xy 117.713479 -120.906404)
			(xy 117.736121 -120.856826) (xy 117.765587 -120.810975) (xy 117.801278 -120.769784) (xy 117.842469 -120.734092)
			(xy 117.888319 -120.704624) (xy 117.937897 -120.681982) (xy 117.990192 -120.666626) (xy 118.04414 -120.658868)
			(xy 118.071392 -120.658382) (xy 118.10031 -120.658875) (xy 118.157484 -120.667605) (xy 118.212685 -120.684866)
			(xy 118.264647 -120.710262) (xy 118.31218 -120.743212) (xy 118.354194 -120.782959) (xy 118.372382 -120.805448)
			(xy 118.379999 -120.814245) (xy 118.400892 -120.824432) (xy 118.412514 -120.825006) (xy 118.49227 -120.825006)
			(xy 118.503898 -120.824433) (xy 118.524807 -120.814268) (xy 118.532402 -120.805448) (xy 118.550579 -120.782953)
			(xy 118.592603 -120.743221) (xy 118.640141 -120.710285) (xy 118.692105 -120.684899) (xy 118.747305 -120.667644)
			(xy 118.804475 -120.658917) (xy 118.833392 -120.658382) (xy 118.860645 -120.658865) (xy 118.914595 -120.666621)
			(xy 118.966892 -120.681976) (xy 119.016472 -120.704617) (xy 119.062325 -120.734084) (xy 119.103518 -120.769777)
			(xy 119.139211 -120.810969) (xy 119.168679 -120.856821) (xy 119.191322 -120.9064) (xy 119.206678 -120.958697)
			(xy 119.214435 -121.012647) (xy 119.214435 -121.067153) (xy 119.206678 -121.121103) (xy 119.191322 -121.1734)
			(xy 119.168679 -121.222979) (xy 119.139211 -121.268831) (xy 119.103518 -121.310023) (xy 119.062325 -121.345716)
			(xy 119.016472 -121.375183) (xy 118.966892 -121.397824) (xy 118.914595 -121.413179) (xy 118.860645 -121.420935)
			(xy 118.833392 -121.421398) (xy 118.804477 -121.420815) (xy 118.747309 -121.412099) (xy 118.692112 -121.394854)
			(xy 118.64015 -121.369475) (xy 118.592614 -121.336543) (xy 118.550594 -121.296812) (xy 118.532402 -121.274332)
			(xy 118.524796 -121.265524) (xy 118.503894 -121.255344) (xy 118.49227 -121.254774) (xy 118.412514 -121.254774)
			(xy 118.400881 -121.25531) (xy 118.37997 -121.265498) (xy 118.372382 -121.274332) (xy 118.354209 -121.296831)
			(xy 118.312185 -121.336564) (xy 118.264646 -121.3695) (xy 118.212681 -121.394885) (xy 118.157481 -121.412139)
			(xy 118.100309 -121.420865) (xy 118.071392 -121.421398) (xy 118.04414 -121.420932) (xy 117.990192 -121.413174)
			(xy 117.937897 -121.397818) (xy 117.888319 -121.375176) (xy 117.842469 -121.345708) (xy 117.801278 -121.310016)
			(xy 117.765587 -121.268825) (xy 117.736121 -121.222974) (xy 117.713479 -121.173396) (xy 117.698124 -121.1211)
			(xy 117.690368 -121.067152) (xy 116.663724 -121.067152) (xy 116.663724 -124.40412) (xy 116.6642 -124.414924)
			(xy 116.673016 -124.434652) (xy 116.680742 -124.44222) (xy 116.745766 -124.499878) (xy 116.766594 -124.506228)
			(xy 116.777262 -124.504958) (xy 116.788398 -124.503747) (xy 116.810765 -124.502477) (xy 116.821966 -124.502418)
			(xy 116.849222 -124.502827) (xy 116.903181 -124.51058) (xy 116.955486 -124.525934) (xy 117.005074 -124.548576)
			(xy 117.050935 -124.578046) (xy 117.092134 -124.613742) (xy 117.127834 -124.654938) (xy 117.157307 -124.700796)
			(xy 117.179954 -124.750382) (xy 117.195313 -124.802686) (xy 117.203071 -124.856644) (xy 117.203071 -124.911156)
			(xy 117.195313 -124.965114) (xy 117.179954 -125.017418) (xy 117.157307 -125.067004) (xy 117.127834 -125.112862)
			(xy 117.092134 -125.154058) (xy 117.050935 -125.189754) (xy 117.005074 -125.219224) (xy 116.955486 -125.241866)
			(xy 116.903181 -125.25722) (xy 116.849222 -125.264973) (xy 116.821966 -125.265434) (xy 116.810765 -125.265371)
			(xy 116.788398 -125.264102) (xy 116.777262 -125.262894) (xy 116.766594 -125.261624) (xy 116.745766 -125.267974)
			(xy 116.680742 -125.325632) (xy 116.672986 -125.333181) (xy 116.664163 -125.352919) (xy 116.663724 -125.363732)
			(xy 116.663724 -125.71857) (xy 116.66425 -125.729462) (xy 116.673172 -125.749331) (xy 116.680996 -125.756924)
			(xy 116.738654 -125.80747) (xy 116.747087 -125.814101) (xy 116.767574 -125.820389) (xy 116.778278 -125.819662)
			(xy 116.778786 -125.819662) (xy 116.790986 -125.818147) (xy 116.815515 -125.816492) (xy 116.827808 -125.81636)
			(xy 116.855057 -125.816911) (xy 116.908999 -125.824668) (xy 116.961288 -125.840022) (xy 117.01086 -125.862662)
			(xy 117.056706 -125.892126) (xy 117.097891 -125.927814) (xy 117.133579 -125.969001) (xy 117.163042 -126.014847)
			(xy 117.185681 -126.064419) (xy 117.201034 -126.116709) (xy 117.20879 -126.170651) (xy 117.20879 -126.225149)
			(xy 117.201034 -126.279091) (xy 117.185681 -126.331381) (xy 117.163042 -126.380953) (xy 117.133579 -126.426799)
			(xy 117.097891 -126.467986) (xy 117.056706 -126.503674) (xy 117.01086 -126.533138) (xy 116.961288 -126.555778)
			(xy 116.908999 -126.571132) (xy 116.855057 -126.578889) (xy 116.827808 -126.579376) (xy 116.815452 -126.579245)
			(xy 116.790795 -126.577594) (xy 116.778532 -126.576074) (xy 116.778278 -126.576074) (xy 116.767561 -126.575224)
			(xy 116.747033 -126.581532) (xy 116.738654 -126.588266) (xy 116.680996 -126.638812) (xy 116.673147 -126.646393)
			(xy 116.664189 -126.666265) (xy 116.663724 -126.677166) (xy 116.663724 -127.049276) (xy 116.664028 -127.057893)
			(xy 116.669697 -127.074164) (xy 116.680464 -127.087616) (xy 116.6876 -127.092456) (xy 116.772182 -127.145034)
			(xy 116.797836 -127.146558) (xy 116.809774 -127.140716) (xy 116.835862 -127.128607) (xy 116.890779 -127.111517)
			(xy 116.947641 -127.102881) (xy 116.976398 -127.102362) (xy 117.003649 -127.102885) (xy 117.057596 -127.110641)
			(xy 117.10989 -127.125996) (xy 117.159466 -127.148637) (xy 117.205316 -127.178102) (xy 117.246506 -127.213793)
			(xy 117.282197 -127.254982) (xy 117.311663 -127.300832) (xy 117.334303 -127.350408) (xy 117.349658 -127.402702)
			(xy 117.357415 -127.456649) (xy 117.357415 -127.511151) (xy 117.349658 -127.565098) (xy 117.334303 -127.617392)
			(xy 117.311663 -127.666968) (xy 117.282197 -127.712818) (xy 117.246506 -127.754007) (xy 117.205316 -127.789698)
			(xy 117.159466 -127.819163) (xy 117.10989 -127.841804) (xy 117.057596 -127.857159) (xy 117.003649 -127.864915)
			(xy 116.976398 -127.865378) (xy 116.947643 -127.864851) (xy 116.890787 -127.856192) (xy 116.83587 -127.839113)
			(xy 116.809774 -127.827024) (xy 116.797836 -127.821182) (xy 116.772182 -127.822706) (xy 116.6876 -127.875284)
			(xy 116.680509 -127.880171) (xy 116.66978 -127.893625) (xy 116.664075 -127.909861) (xy 116.663724 -127.918464)
			(xy 116.663724 -128.833118) (xy 116.664134 -128.843189) (xy 116.671865 -128.861787) (xy 116.67871 -128.869186)
			(xy 116.84254 -129.032762) (xy 116.846937 -129.036874) (xy 116.857198 -129.043162) (xy 116.86286 -129.045208)
			(xy 116.863368 -129.045208) (xy 116.888897 -129.053697) (xy 116.937498 -129.076765) (xy 116.982377 -129.10643)
			(xy 117.022644 -129.142106) (xy 117.0575 -129.183085) (xy 117.086255 -129.228553) (xy 117.108337 -129.27761)
			(xy 117.123308 -129.329282) (xy 117.130873 -129.382545) (xy 117.131338 -129.409444) (xy 117.130863 -129.436695)
			(xy 117.123101 -129.490642) (xy 117.107742 -129.542935) (xy 117.087735 -129.586736) (xy 117.524528 -129.586736)
			(xy 117.528599 -129.531114) (xy 117.540725 -129.476677) (xy 117.560648 -129.424586) (xy 117.587944 -129.375951)
			(xy 117.62203 -129.331808) (xy 117.662179 -129.293099) (xy 117.707537 -129.260648) (xy 117.757137 -129.235147)
			(xy 117.809921 -129.21714) (xy 117.864764 -129.20701) (xy 117.920498 -129.204973) (xy 117.975935 -129.211073)
			(xy 118.029892 -129.225179) (xy 118.081221 -129.246991) (xy 118.128827 -129.276045) (xy 118.171695 -129.31172)
			(xy 118.208912 -129.353257) (xy 118.239685 -129.39977) (xy 118.263357 -129.450267) (xy 118.279425 -129.503674)
			(xy 118.287545 -129.55885) (xy 118.288054 -129.586736) (xy 118.287545 -129.614622) (xy 118.279425 -129.669798)
			(xy 118.263357 -129.723205) (xy 118.239685 -129.773702) (xy 118.208912 -129.820215) (xy 118.171695 -129.861752)
			(xy 118.128827 -129.897427) (xy 118.081221 -129.926481) (xy 118.029892 -129.948293) (xy 117.975935 -129.962399)
			(xy 117.920498 -129.968499) (xy 117.864764 -129.966462) (xy 117.809921 -129.956332) (xy 117.757137 -129.938325)
			(xy 117.707537 -129.912824) (xy 117.662179 -129.880373) (xy 117.62203 -129.841664) (xy 117.587944 -129.797521)
			(xy 117.560648 -129.748886) (xy 117.540725 -129.696795) (xy 117.528599 -129.642358) (xy 117.524528 -129.586736)
			(xy 117.087735 -129.586736) (xy 117.085098 -129.59251) (xy 117.05563 -129.638359) (xy 117.019938 -129.679548)
			(xy 116.978748 -129.715239) (xy 116.932898 -129.744705) (xy 116.883321 -129.767347) (xy 116.831028 -129.782704)
			(xy 116.777081 -129.790464) (xy 116.74983 -129.790952) (xy 116.72292 -129.790478) (xy 116.669638 -129.782893)
			(xy 116.61795 -129.767898) (xy 116.568881 -129.74579) (xy 116.523404 -129.717008) (xy 116.482422 -129.682122)
			(xy 116.446747 -129.641825) (xy 116.417088 -129.596916) (xy 116.394032 -129.548285) (xy 116.385594 -129.522728)
			(xy 116.385594 -129.522474) (xy 116.383602 -129.516786) (xy 116.377314 -129.506509) (xy 116.373148 -129.502154)
			(xy 116.097304 -129.22631) (xy 116.079261 -129.207549) (xy 116.048682 -129.165429) (xy 116.025057 -129.119051)
			(xy 116.008965 -129.069551) (xy 116.000801 -129.018146) (xy 116.000276 -128.992122) (xy 116.000276 -120.977406)
			(xy 115.999854 -120.967336) (xy 115.992132 -120.948738) (xy 115.98529 -120.941338) (xy 114.497866 -119.454168)
			(xy 114.493476 -119.450048) (xy 114.483209 -119.443766) (xy 114.477546 -119.441722) (xy 114.477038 -119.441722)
			(xy 114.451488 -119.43329) (xy 114.402883 -119.410218) (xy 114.358002 -119.380546) (xy 114.317734 -119.344864)
			(xy 114.282879 -119.303878) (xy 114.254128 -119.258401) (xy 114.23205 -119.209337) (xy 114.217085 -119.157657)
			(xy 114.209528 -119.104387) (xy 114.209068 -119.077486) (xy 112.290232 -119.077486) (xy 112.286542 -119.081296)
			(xy 111.936022 -119.431816) (xy 111.910337 -119.456758) (xy 111.853962 -119.500894) (xy 111.79267 -119.537899)
			(xy 111.727358 -119.567232) (xy 111.658981 -119.588463) (xy 111.623856 -119.595392) (xy 111.616306 -119.597012)
			(xy 111.602609 -119.604127) (xy 111.596932 -119.609362) (xy 111.590328 -119.615966) (xy 111.584057 -119.652809)
			(xy 111.56343 -119.724644) (xy 111.533915 -119.793306) (xy 111.495982 -119.857701) (xy 111.450236 -119.916803)
			(xy 111.424212 -119.943626) (xy 111.073692 -120.294146) (xy 111.048008 -120.319088) (xy 110.991634 -120.363227)
			(xy 110.930342 -120.400233) (xy 110.86503 -120.429566) (xy 110.796652 -120.450797) (xy 110.761526 -120.457722)
			(xy 110.753972 -120.459333) (xy 110.740264 -120.466439) (xy 110.734602 -120.471692) (xy 110.727998 -120.478296)
			(xy 110.721725 -120.515138) (xy 110.701094 -120.58697) (xy 110.671575 -120.655629) (xy 110.633639 -120.72002)
			(xy 110.58789 -120.779118) (xy 110.561882 -120.805956) (xy 110.211362 -121.156476) (xy 110.185679 -121.181421)
			(xy 110.129306 -121.225563) (xy 110.068016 -121.262575) (xy 110.002704 -121.291914) (xy 109.934328 -121.313152)
			(xy 109.899196 -121.320052) (xy 109.891642 -121.321665) (xy 109.877934 -121.328769) (xy 109.872272 -121.334022)
			(xy 109.865668 -121.340626) (xy 109.859387 -121.377443) (xy 109.838745 -121.449223) (xy 109.80922 -121.517829)
			(xy 109.771285 -121.582167) (xy 109.725544 -121.64121) (xy 109.699552 -121.668032) (xy 109.349032 -122.018552)
			(xy 109.323332 -122.043515) (xy 109.266918 -122.087682) (xy 109.205577 -122.124703) (xy 109.140207 -122.154032)
			(xy 109.071771 -122.175239) (xy 109.036612 -122.182128) (xy 109.028992 -122.183398) (xy 109.015276 -122.190764)
			(xy 107.64647 -123.55957) (xy 107.622691 -123.58268) (xy 107.570838 -123.624013) (xy 107.514684 -123.659282)
			(xy 107.454935 -123.688042) (xy 107.392341 -123.709933) (xy 107.327691 -123.72468) (xy 107.261796 -123.732096)
			(xy 107.22864 -123.732544) (xy 105.106978 -123.732544) (xy 105.096911 -123.732972) (xy 105.078316 -123.740697)
			(xy 105.07091 -123.74753) (xy 103.17353 -125.64491) (xy 103.166682 -125.652308) (xy 103.158946 -125.670906)
			(xy 103.158544 -125.680978) (xy 103.158544 -126.992126) (xy 104.844342 -126.992126) (xy 104.844813 -126.964756)
			(xy 104.852628 -126.910577) (xy 104.868115 -126.858073) (xy 104.890956 -126.808326) (xy 104.920681 -126.762359)
			(xy 104.938322 -126.741428) (xy 104.938576 -126.741174) (xy 104.944147 -126.734077) (xy 104.950401 -126.717168)
			(xy 104.950768 -126.708154) (xy 104.950768 -126.641098) (xy 104.950419 -126.63208) (xy 104.944167 -126.615163)
			(xy 104.938576 -126.608078) (xy 104.938322 -126.608078) (xy 104.938322 -126.607824) (xy 104.920707 -126.586871)
			(xy 104.890982 -126.540906) (xy 104.868135 -126.491163) (xy 104.852637 -126.438664) (xy 104.844806 -126.384489)
			(xy 104.844803 -126.32975) (xy 104.852629 -126.275574) (xy 104.868121 -126.223073) (xy 104.890963 -126.173328)
			(xy 104.920683 -126.127361) (xy 104.938322 -126.106428) (xy 104.938576 -126.106174) (xy 104.944147 -126.099077)
			(xy 104.950401 -126.082168) (xy 104.950768 -126.073154) (xy 104.950768 -126.006098) (xy 104.950419 -125.99708)
			(xy 104.944167 -125.980163) (xy 104.938576 -125.973078) (xy 104.938322 -125.973078) (xy 104.938322 -125.972824)
			(xy 104.920707 -125.951871) (xy 104.890982 -125.905906) (xy 104.868135 -125.856163) (xy 104.852637 -125.803664)
			(xy 104.844806 -125.749489) (xy 104.844803 -125.69475) (xy 104.852629 -125.640574) (xy 104.868121 -125.588073)
			(xy 104.890963 -125.538328) (xy 104.920683 -125.492361) (xy 104.938322 -125.471428) (xy 104.938576 -125.471174)
			(xy 104.944147 -125.464077) (xy 104.950401 -125.447168) (xy 104.950768 -125.438154) (xy 104.950768 -125.371098)
			(xy 104.950419 -125.36208) (xy 104.944167 -125.345163) (xy 104.938576 -125.338078) (xy 104.938322 -125.338078)
			(xy 104.938322 -125.337824) (xy 104.920684 -125.316891) (xy 104.890971 -125.270919) (xy 104.868135 -125.221172)
			(xy 104.852644 -125.168671) (xy 104.844816 -125.114495) (xy 104.844342 -125.087126) (xy 104.844828 -125.059875)
			(xy 104.852584 -125.005927) (xy 104.867939 -124.953632) (xy 104.890581 -124.904055) (xy 104.920047 -124.858205)
			(xy 104.955738 -124.817014) (xy 104.996929 -124.781323) (xy 105.042779 -124.751857) (xy 105.092356 -124.729215)
			(xy 105.144651 -124.71386) (xy 105.198599 -124.706104) (xy 105.253101 -124.706104) (xy 105.307049 -124.71386)
			(xy 105.359344 -124.729215) (xy 105.408921 -124.751857) (xy 105.454771 -124.781323) (xy 105.495962 -124.817014)
			(xy 105.531653 -124.858205) (xy 105.561119 -124.904055) (xy 105.583761 -124.953632) (xy 105.599116 -125.005927)
			(xy 105.606872 -125.059875) (xy 105.607358 -125.087126) (xy 105.606917 -125.114497) (xy 105.599095 -125.168678)
			(xy 105.583601 -125.221182) (xy 105.560753 -125.270928) (xy 105.531022 -125.316893) (xy 105.513378 -125.337824)
			(xy 105.513124 -125.338078) (xy 105.507532 -125.34516) (xy 105.50129 -125.362081) (xy 105.500932 -125.371098)
			(xy 105.500932 -125.438154) (xy 105.501304 -125.447169) (xy 105.50754 -125.464087) (xy 105.513124 -125.471174)
			(xy 105.513378 -125.471174) (xy 105.513378 -125.471428) (xy 105.531044 -125.49234) (xy 105.560767 -125.538312)
			(xy 105.583611 -125.588061) (xy 105.599105 -125.640567) (xy 105.606931 -125.694748) (xy 105.606928 -125.749491)
			(xy 105.599097 -125.803672) (xy 105.583597 -125.856175) (xy 105.560748 -125.905923) (xy 105.53102 -125.951891)
			(xy 105.513378 -125.972824) (xy 105.513124 -125.973078) (xy 105.507532 -125.98016) (xy 105.50129 -125.997081)
			(xy 105.500932 -126.006098) (xy 105.500932 -126.073154) (xy 105.501304 -126.082169) (xy 105.50754 -126.099087)
			(xy 105.513124 -126.106174) (xy 105.513378 -126.106174) (xy 105.513378 -126.106428) (xy 105.531044 -126.12734)
			(xy 105.560767 -126.173312) (xy 105.583611 -126.223061) (xy 105.599105 -126.275567) (xy 105.606931 -126.329748)
			(xy 105.606928 -126.384491) (xy 105.599097 -126.438672) (xy 105.583597 -126.491175) (xy 105.560748 -126.540923)
			(xy 105.53102 -126.586891) (xy 105.513378 -126.607824) (xy 105.513124 -126.608078) (xy 105.507532 -126.61516)
			(xy 105.50129 -126.632081) (xy 105.500932 -126.641098) (xy 105.500932 -126.708154) (xy 105.501304 -126.717169)
			(xy 105.50754 -126.734087) (xy 105.513124 -126.741174) (xy 105.513378 -126.741174) (xy 105.513378 -126.741428)
			(xy 105.530993 -126.762379) (xy 105.56071 -126.808346) (xy 105.58355 -126.858089) (xy 105.599047 -126.910586)
			(xy 105.606881 -126.964758) (xy 105.607358 -126.992126) (xy 105.606872 -127.019377) (xy 105.602208 -127.051816)
			(xy 107.500166 -127.051816) (xy 107.500625 -127.024445) (xy 107.508442 -126.970265) (xy 107.523932 -126.917762)
			(xy 107.546776 -126.868015) (xy 107.576503 -126.822049) (xy 107.594146 -126.801118) (xy 107.5944 -126.800864)
			(xy 107.599966 -126.793763) (xy 107.606225 -126.776857) (xy 107.606592 -126.767844) (xy 107.606592 -126.700788)
			(xy 107.606242 -126.69177) (xy 107.59999 -126.674853) (xy 107.5944 -126.667768) (xy 107.594146 -126.667768)
			(xy 107.594146 -126.667514) (xy 107.57652 -126.646569) (xy 107.546793 -126.600604) (xy 107.523946 -126.55086)
			(xy 107.508448 -126.498359) (xy 107.500617 -126.444182) (xy 107.500615 -126.389442) (xy 107.508442 -126.335264)
			(xy 107.523937 -126.282763) (xy 107.546782 -126.233017) (xy 107.576506 -126.18705) (xy 107.594146 -126.166118)
			(xy 107.5944 -126.165864) (xy 107.599966 -126.158763) (xy 107.606225 -126.141857) (xy 107.606592 -126.132844)
			(xy 107.606592 -126.065788) (xy 107.606242 -126.05677) (xy 107.59999 -126.039853) (xy 107.5944 -126.032768)
			(xy 107.594146 -126.032768) (xy 107.594146 -126.032514) (xy 107.57652 -126.011569) (xy 107.546793 -125.965604)
			(xy 107.523946 -125.91586) (xy 107.508448 -125.863359) (xy 107.500617 -125.809182) (xy 107.500615 -125.754442)
			(xy 107.508442 -125.700264) (xy 107.523937 -125.647763) (xy 107.546782 -125.598017) (xy 107.576506 -125.55205)
			(xy 107.594146 -125.531118) (xy 107.5944 -125.530864) (xy 107.599966 -125.523763) (xy 107.606225 -125.506857)
			(xy 107.606592 -125.497844) (xy 107.606592 -125.430788) (xy 107.606242 -125.42177) (xy 107.59999 -125.404853)
			(xy 107.5944 -125.397768) (xy 107.594146 -125.397768) (xy 107.594146 -125.397514) (xy 107.576507 -125.376582)
			(xy 107.546794 -125.33061) (xy 107.523957 -125.280862) (xy 107.508466 -125.228361) (xy 107.500639 -125.174185)
			(xy 107.500166 -125.146816) (xy 107.500652 -125.119565) (xy 107.508408 -125.065617) (xy 107.523763 -125.013322)
			(xy 107.546405 -124.963745) (xy 107.575871 -124.917895) (xy 107.611562 -124.876704) (xy 107.652753 -124.841013)
			(xy 107.698603 -124.811547) (xy 107.74818 -124.788905) (xy 107.800475 -124.77355) (xy 107.854423 -124.765794)
			(xy 107.908925 -124.765794) (xy 107.962873 -124.77355) (xy 108.015168 -124.788905) (xy 108.064745 -124.811547)
			(xy 108.110595 -124.841013) (xy 108.151786 -124.876704) (xy 108.187477 -124.917895) (xy 108.216943 -124.963745)
			(xy 108.239585 -125.013322) (xy 108.25494 -125.065617) (xy 108.262696 -125.119565) (xy 108.263182 -125.146816)
			(xy 108.26273 -125.174187) (xy 108.254909 -125.228367) (xy 108.239417 -125.28087) (xy 108.216572 -125.330617)
			(xy 108.186845 -125.376583) (xy 108.169202 -125.397514) (xy 108.168948 -125.397768) (xy 108.163362 -125.404855)
			(xy 108.157116 -125.421772) (xy 108.156756 -125.430788) (xy 108.156756 -125.497844) (xy 108.157128 -125.50686)
			(xy 108.163364 -125.523777) (xy 108.168948 -125.530864) (xy 108.169202 -125.530864) (xy 108.169202 -125.531118)
			(xy 108.186857 -125.552039) (xy 108.216579 -125.598009) (xy 108.239422 -125.647758) (xy 108.254916 -125.700261)
			(xy 108.262742 -125.754441) (xy 108.26274 -125.809183) (xy 108.25491 -125.863362) (xy 108.239413 -125.915865)
			(xy 108.216567 -125.965612) (xy 108.186843 -126.011581) (xy 108.169202 -126.032514) (xy 108.168948 -126.032768)
			(xy 108.163362 -126.039855) (xy 108.157116 -126.056772) (xy 108.156756 -126.065788) (xy 108.156756 -126.132844)
			(xy 108.157128 -126.14186) (xy 108.163364 -126.158777) (xy 108.168948 -126.165864) (xy 108.169202 -126.166118)
			(xy 108.186022 -126.186075) (xy 108.214608 -126.229744) (xy 108.236986 -126.276896) (xy 108.252738 -126.326655)
			(xy 108.257594 -126.3523) (xy 108.257594 -126.352554) (xy 108.259428 -126.360829) (xy 108.267719 -126.375599)
			(xy 108.280376 -126.386856) (xy 108.288074 -126.3904) (xy 108.379514 -126.429008) (xy 108.405168 -126.426214)
			(xy 108.415836 -126.418594) (xy 108.439986 -126.402441) (xy 108.492126 -126.376812) (xy 108.547549 -126.359386)
			(xy 108.604973 -126.350564) (xy 108.634022 -126.350014) (xy 108.661275 -126.350457) (xy 108.715225 -126.358217)
			(xy 108.767522 -126.373577) (xy 108.817101 -126.396222) (xy 108.862952 -126.425692) (xy 108.904143 -126.461388)
			(xy 108.939834 -126.502583) (xy 108.969299 -126.548438) (xy 108.991939 -126.598019) (xy 109.007292 -126.650318)
			(xy 109.015046 -126.704269) (xy 109.01553 -126.731522) (xy 109.015096 -126.758152) (xy 109.00769 -126.810896)
			(xy 108.993024 -126.862097) (xy 108.971382 -126.910763) (xy 108.943187 -126.955948) (xy 108.908984 -126.996776)
			(xy 108.869437 -127.032452) (xy 108.847636 -127.047752) (xy 108.837476 -127.05461) (xy 108.825792 -127.075438)
			(xy 108.821474 -127.18161) (xy 108.83138 -127.203454) (xy 108.841032 -127.211074) (xy 108.862881 -127.229325)
			(xy 108.901486 -127.27116) (xy 108.933453 -127.318263) (xy 108.95807 -127.369591) (xy 108.963528 -127.38735)
			(xy 110.308898 -127.38735) (xy 110.309418 -127.357979) (xy 110.318417 -127.29993) (xy 110.336209 -127.243946)
			(xy 110.362374 -127.191353) (xy 110.396293 -127.143393) (xy 110.41634 -127.12192) (xy 110.42272 -127.114735)
			(xy 110.430017 -127.096971) (xy 110.430564 -127.087376) (xy 110.431834 -127.008128) (xy 110.424976 -126.990094)
			(xy 110.418626 -126.982982) (xy 110.400068 -126.961814) (xy 110.368766 -126.915023) (xy 110.344678 -126.864142)
			(xy 110.328326 -126.810275) (xy 110.320065 -126.754589) (xy 110.319566 -126.726442) (xy 110.320094 -126.699191)
			(xy 110.327845 -126.645244) (xy 110.343194 -126.592949) (xy 110.36583 -126.543371) (xy 110.395291 -126.497519)
			(xy 110.430978 -126.456326) (xy 110.472164 -126.420632) (xy 110.518011 -126.391163) (xy 110.567585 -126.368518)
			(xy 110.619878 -126.353159) (xy 110.673823 -126.345399) (xy 110.701074 -126.344934) (xy 110.729754 -126.345504)
			(xy 110.786466 -126.35411) (xy 110.841253 -126.371103) (xy 110.892881 -126.3961) (xy 110.940189 -126.428538)
			(xy 110.982113 -126.467688) (xy 111.017708 -126.512669) (xy 111.046175 -126.562468) (xy 111.066872 -126.615966)
			(xy 111.079333 -126.671957) (xy 111.08182 -126.700534) (xy 111.082582 -126.713488) (xy 111.096552 -126.735332)
			(xy 111.194596 -126.788926) (xy 111.220504 -126.788926) (xy 111.231934 -126.782576) (xy 111.260181 -126.767818)
			(xy 111.320372 -126.746883) (xy 111.383205 -126.736248) (xy 111.415068 -126.735586) (xy 111.415576 -126.735586)
			(xy 111.44283 -126.73606) (xy 111.496782 -126.743814) (xy 111.549082 -126.759167) (xy 111.598664 -126.781808)
			(xy 111.64452 -126.811275) (xy 111.685715 -126.846968) (xy 111.72141 -126.888161) (xy 111.75088 -126.934014)
			(xy 111.773524 -126.983595) (xy 111.788881 -127.035894) (xy 111.796639 -127.089846) (xy 111.796639 -127.144354)
			(xy 111.788881 -127.198306) (xy 111.773524 -127.250605) (xy 111.75088 -127.300186) (xy 111.72141 -127.346039)
			(xy 111.685715 -127.387232) (xy 111.64452 -127.422925) (xy 111.598664 -127.452392) (xy 111.549082 -127.475033)
			(xy 111.496782 -127.490386) (xy 111.44283 -127.49814) (xy 111.415576 -127.498602) (xy 111.388288 -127.498128)
			(xy 111.334267 -127.49036) (xy 111.281905 -127.47497) (xy 111.232272 -127.452274) (xy 111.209074 -127.437896)
			(xy 111.20882 -127.437642) (xy 111.198527 -127.431896) (xy 111.175101 -127.429514) (xy 111.163862 -127.43307)
			(xy 111.087408 -127.461264) (xy 111.076556 -127.465943) (xy 111.060406 -127.483158) (xy 111.05642 -127.494284)
			(xy 111.05642 -127.494792) (xy 111.048249 -127.520795) (xy 111.025627 -127.570382) (xy 110.996177 -127.616243)
			(xy 110.960498 -127.657445) (xy 110.919317 -127.693147) (xy 110.873472 -127.722623) (xy 110.823899 -127.745273)
			(xy 110.771605 -127.760634) (xy 110.717657 -127.768394) (xy 110.690406 -127.768858) (xy 110.663151 -127.768439)
			(xy 110.609196 -127.760681) (xy 110.556894 -127.745324) (xy 110.507311 -127.722678) (xy 110.461455 -127.693206)
			(xy 110.420261 -127.657508) (xy 110.384567 -127.61631) (xy 110.355101 -127.570451) (xy 110.332461 -127.520865)
			(xy 110.317109 -127.468561) (xy 110.309358 -127.414605) (xy 110.308898 -127.38735) (xy 108.963528 -127.38735)
			(xy 108.974793 -127.424005) (xy 108.983252 -127.480299) (xy 108.98378 -127.508762) (xy 108.983294 -127.536013)
			(xy 108.975538 -127.589961) (xy 108.960183 -127.642256) (xy 108.937541 -127.691833) (xy 108.908075 -127.737683)
			(xy 108.872384 -127.778874) (xy 108.831193 -127.814565) (xy 108.785343 -127.844031) (xy 108.735766 -127.866673)
			(xy 108.683471 -127.882028) (xy 108.629523 -127.889784) (xy 108.575021 -127.889784) (xy 108.521073 -127.882028)
			(xy 108.468778 -127.866673) (xy 108.419201 -127.844031) (xy 108.373351 -127.814565) (xy 108.33216 -127.778874)
			(xy 108.296469 -127.737683) (xy 108.267003 -127.691833) (xy 108.244361 -127.642256) (xy 108.229006 -127.589961)
			(xy 108.22125 -127.536013) (xy 108.220764 -127.508762) (xy 108.22178 -127.479552) (xy 108.22305 -127.465582)
			(xy 108.21035 -127.440182) (xy 108.110528 -127.376936) (xy 108.082588 -127.376428) (xy 108.070396 -127.383286)
			(xy 108.048743 -127.395152) (xy 108.003045 -127.413849) (xy 107.955319 -127.426507) (xy 107.906361 -127.432913)
			(xy 107.881674 -127.433324) (xy 107.854423 -127.432846) (xy 107.800476 -127.425087) (xy 107.748182 -127.409729)
			(xy 107.698605 -127.387086) (xy 107.652756 -127.357619) (xy 107.611566 -127.321926) (xy 107.575875 -127.280736)
			(xy 107.546409 -127.234886) (xy 107.523767 -127.185309) (xy 107.508411 -127.133015) (xy 107.500653 -127.079067)
			(xy 107.500166 -127.051816) (xy 105.602208 -127.051816) (xy 105.599116 -127.073325) (xy 105.583761 -127.12562)
			(xy 105.561119 -127.175197) (xy 105.531653 -127.221047) (xy 105.495962 -127.262238) (xy 105.454771 -127.297929)
			(xy 105.408921 -127.327395) (xy 105.359344 -127.350037) (xy 105.307049 -127.365392) (xy 105.253101 -127.373148)
			(xy 105.198599 -127.373148) (xy 105.144651 -127.365392) (xy 105.092356 -127.350037) (xy 105.042779 -127.327395)
			(xy 104.996929 -127.297929) (xy 104.955738 -127.262238) (xy 104.920047 -127.221047) (xy 104.890581 -127.175197)
			(xy 104.867939 -127.12562) (xy 104.852584 -127.073325) (xy 104.844828 -127.019377) (xy 104.844342 -126.992126)
			(xy 103.158544 -126.992126) (xy 103.158544 -128.665246) (xy 112.888324 -128.665246) (xy 112.888324 -128.610754)
			(xy 112.896079 -128.556815) (xy 112.91143 -128.504529) (xy 112.934066 -128.45496) (xy 112.963526 -128.409117)
			(xy 112.99921 -128.367933) (xy 113.040391 -128.332245) (xy 113.086232 -128.302782) (xy 113.135799 -128.280142)
			(xy 113.188084 -128.264786) (xy 113.242022 -128.257026) (xy 113.269268 -128.256538) (xy 113.296638 -128.257014)
			(xy 113.350817 -128.264828) (xy 113.40332 -128.280314) (xy 113.453067 -128.303154) (xy 113.499034 -128.332877)
			(xy 113.519966 -128.350518) (xy 113.52022 -128.350772) (xy 113.527291 -128.356382) (xy 113.54422 -128.362612)
			(xy 113.55324 -128.362964) (xy 113.620296 -128.362964) (xy 113.629314 -128.362613) (xy 113.646231 -128.356362)
			(xy 113.653316 -128.350772) (xy 113.653316 -128.350518) (xy 113.65357 -128.350518) (xy 113.674503 -128.332877)
			(xy 113.720471 -128.303153) (xy 113.770217 -128.280307) (xy 113.822719 -128.264811) (xy 113.876897 -128.256982)
			(xy 113.931639 -128.256982) (xy 113.985817 -128.264811) (xy 114.038319 -128.280307) (xy 114.088065 -128.303153)
			(xy 114.134033 -128.332877) (xy 114.154966 -128.350518) (xy 114.15522 -128.350772) (xy 114.162291 -128.356382)
			(xy 114.17922 -128.362612) (xy 114.18824 -128.362964) (xy 114.255296 -128.362964) (xy 114.264314 -128.362613)
			(xy 114.281231 -128.356362) (xy 114.288316 -128.350772) (xy 114.288316 -128.350518) (xy 114.28857 -128.350518)
			(xy 114.309505 -128.332882) (xy 114.355477 -128.303169) (xy 114.405223 -128.280332) (xy 114.457724 -128.264841)
			(xy 114.511899 -128.257012) (xy 114.539268 -128.256538) (xy 114.566526 -128.256907) (xy 114.620487 -128.264661)
			(xy 114.672795 -128.280016) (xy 114.722385 -128.30266) (xy 114.768248 -128.33213) (xy 114.809449 -128.367828)
			(xy 114.845151 -128.409027) (xy 114.874625 -128.454887) (xy 114.897273 -128.504475) (xy 114.912632 -128.556782)
			(xy 114.920391 -128.610742) (xy 114.920391 -128.665258) (xy 114.912632 -128.719218) (xy 114.897273 -128.771525)
			(xy 114.874625 -128.821113) (xy 114.845151 -128.866973) (xy 114.809449 -128.908172) (xy 114.768248 -128.94387)
			(xy 114.722385 -128.97334) (xy 114.672795 -128.995984) (xy 114.620487 -129.011339) (xy 114.566526 -129.019093)
			(xy 114.539268 -129.019554) (xy 114.511897 -129.019118) (xy 114.457716 -129.011295) (xy 114.405212 -128.995799)
			(xy 114.355465 -128.97295) (xy 114.3095 -128.943219) (xy 114.28857 -128.925574) (xy 114.288316 -128.92532)
			(xy 114.281236 -128.919725) (xy 114.264314 -128.913485) (xy 114.255296 -128.913128) (xy 114.18824 -128.913128)
			(xy 114.179224 -128.913498) (xy 114.162307 -128.919736) (xy 114.15522 -128.92532) (xy 114.15522 -128.925574)
			(xy 114.154966 -128.925574) (xy 114.134033 -128.943215) (xy 114.088065 -128.972939) (xy 114.038319 -128.995785)
			(xy 113.985817 -129.011281) (xy 113.931639 -129.01911) (xy 113.876897 -129.01911) (xy 113.822719 -129.011281)
			(xy 113.770217 -128.995785) (xy 113.720471 -128.972939) (xy 113.674503 -128.943215) (xy 113.65357 -128.925574)
			(xy 113.653316 -128.92532) (xy 113.646236 -128.919725) (xy 113.629314 -128.913485) (xy 113.620296 -128.913128)
			(xy 113.55324 -128.913128) (xy 113.544224 -128.913498) (xy 113.527307 -128.919736) (xy 113.52022 -128.92532)
			(xy 113.52022 -128.925574) (xy 113.519966 -128.925574) (xy 113.499017 -128.943192) (xy 113.453049 -128.972908)
			(xy 113.403306 -128.995748) (xy 113.350809 -129.011244) (xy 113.296636 -129.019077) (xy 113.269268 -129.019554)
			(xy 113.242022 -129.018974) (xy 113.188084 -129.011214) (xy 113.135799 -128.995858) (xy 113.086232 -128.973218)
			(xy 113.040391 -128.943755) (xy 112.99921 -128.908067) (xy 112.963526 -128.866883) (xy 112.934067 -128.82104)
			(xy 112.91143 -128.771471) (xy 112.896079 -128.719185) (xy 112.888324 -128.665246) (xy 103.158544 -128.665246)
			(xy 103.158544 -129.951246) (xy 112.909426 -129.951246) (xy 112.909426 -129.896754) (xy 112.91718 -129.842818)
			(xy 112.932531 -129.790534) (xy 112.955166 -129.740966) (xy 112.984623 -129.695124) (xy 113.020305 -129.65394)
			(xy 113.061484 -129.618253) (xy 113.107322 -129.58879) (xy 113.156887 -129.566148) (xy 113.209169 -129.550791)
			(xy 113.263105 -129.54303) (xy 113.29035 -129.54254) (xy 113.31772 -129.543026) (xy 113.371898 -129.550837)
			(xy 113.424402 -129.566321) (xy 113.474149 -129.589159) (xy 113.520116 -129.61888) (xy 113.541048 -129.63652)
			(xy 113.541302 -129.636774) (xy 113.548378 -129.642376) (xy 113.565303 -129.648612) (xy 113.574322 -129.648966)
			(xy 113.641378 -129.648966) (xy 113.650395 -129.648606) (xy 113.667312 -129.642361) (xy 113.674398 -129.636774)
			(xy 113.674398 -129.63652) (xy 113.674652 -129.63652) (xy 113.695594 -129.618893) (xy 113.741564 -129.589179)
			(xy 113.791309 -129.56634) (xy 113.843807 -129.550846) (xy 113.897981 -129.543015) (xy 113.92535 -129.54254)
			(xy 113.952609 -129.542904) (xy 114.006572 -129.550656) (xy 114.058882 -129.566009) (xy 114.108475 -129.588652)
			(xy 114.15434 -129.618122) (xy 114.195544 -129.65382) (xy 114.231248 -129.69502) (xy 114.260724 -129.740881)
			(xy 114.283373 -129.790471) (xy 114.298734 -129.842779) (xy 114.306493 -129.896741) (xy 114.306493 -129.951259)
			(xy 114.298734 -130.005221) (xy 114.283373 -130.057529) (xy 114.260724 -130.107119) (xy 114.231248 -130.15298)
			(xy 114.195544 -130.19418) (xy 114.15434 -130.229878) (xy 114.108475 -130.259348) (xy 114.058882 -130.281991)
			(xy 114.006572 -130.297344) (xy 113.952609 -130.305096) (xy 113.92535 -130.305556) (xy 113.89798 -130.305071)
			(xy 113.843802 -130.29726) (xy 113.791298 -130.281776) (xy 113.741551 -130.258938) (xy 113.695584 -130.229216)
			(xy 113.674652 -130.211576) (xy 113.674398 -130.211322) (xy 113.667323 -130.205719) (xy 113.650397 -130.199484)
			(xy 113.641378 -130.19913) (xy 113.574322 -130.19913) (xy 113.565305 -130.199491) (xy 113.548388 -130.205735)
			(xy 113.541302 -130.211322) (xy 113.541302 -130.211576) (xy 113.541048 -130.211576) (xy 113.520106 -130.229202)
			(xy 113.474136 -130.258917) (xy 113.424391 -130.281756) (xy 113.371893 -130.29725) (xy 113.317719 -130.305081)
			(xy 113.29035 -130.305556) (xy 113.263105 -130.30497) (xy 113.209169 -130.297209) (xy 113.156887 -130.281852)
			(xy 113.107322 -130.259211) (xy 113.061484 -130.229747) (xy 113.020305 -130.19406) (xy 112.984623 -130.152876)
			(xy 112.955166 -130.107034) (xy 112.932531 -130.057466) (xy 112.91718 -130.005182) (xy 112.909426 -129.951246)
			(xy 103.158544 -129.951246) (xy 103.158544 -131.218686) (xy 118.631714 -131.218686) (xy 118.635785 -131.163064)
			(xy 118.647911 -131.108627) (xy 118.667834 -131.056536) (xy 118.69513 -131.007901) (xy 118.729216 -130.963758)
			(xy 118.769365 -130.925049) (xy 118.814723 -130.892598) (xy 118.864323 -130.867097) (xy 118.917107 -130.84909)
			(xy 118.97195 -130.83896) (xy 119.027684 -130.836923) (xy 119.083121 -130.843023) (xy 119.137078 -130.857129)
			(xy 119.188407 -130.878941) (xy 119.236013 -130.907995) (xy 119.278881 -130.94367) (xy 119.316098 -130.985207)
			(xy 119.346871 -131.03172) (xy 119.370543 -131.082217) (xy 119.386611 -131.135624) (xy 119.394731 -131.1908)
			(xy 119.39524 -131.218686) (xy 119.394731 -131.246572) (xy 119.386611 -131.301748) (xy 119.370543 -131.355155)
			(xy 119.346871 -131.405652) (xy 119.316098 -131.452165) (xy 119.278881 -131.493702) (xy 119.236013 -131.529377)
			(xy 119.188407 -131.558431) (xy 119.137078 -131.580243) (xy 119.083121 -131.594349) (xy 119.027684 -131.600449)
			(xy 118.97195 -131.598412) (xy 118.917107 -131.588282) (xy 118.864323 -131.570275) (xy 118.814723 -131.544774)
			(xy 118.769365 -131.512323) (xy 118.729216 -131.473614) (xy 118.69513 -131.429471) (xy 118.667834 -131.380836)
			(xy 118.647911 -131.328745) (xy 118.635785 -131.274308) (xy 118.631714 -131.218686) (xy 103.158544 -131.218686)
			(xy 103.158544 -132.030746) (xy 112.909424 -132.030746) (xy 112.909424 -131.976254) (xy 112.917178 -131.922318)
			(xy 112.932529 -131.870033) (xy 112.955164 -131.820465) (xy 112.984622 -131.774623) (xy 113.020304 -131.733439)
			(xy 113.061483 -131.697752) (xy 113.107321 -131.668288) (xy 113.156886 -131.645647) (xy 113.209169 -131.630289)
			(xy 113.263104 -131.622528) (xy 113.29035 -131.622038) (xy 113.31772 -131.622524) (xy 113.371898 -131.630336)
			(xy 113.424401 -131.64582) (xy 113.474149 -131.668657) (xy 113.520116 -131.698378) (xy 113.541048 -131.716018)
			(xy 113.541302 -131.716272) (xy 113.548378 -131.721874) (xy 113.565303 -131.728109) (xy 113.574322 -131.728464)
			(xy 113.641378 -131.728464) (xy 113.650395 -131.728104) (xy 113.667312 -131.721859) (xy 113.674398 -131.716272)
			(xy 113.674398 -131.716018) (xy 113.674652 -131.716018) (xy 113.695594 -131.698391) (xy 113.741564 -131.668677)
			(xy 113.791309 -131.645838) (xy 113.843807 -131.630344) (xy 113.897981 -131.622513) (xy 113.92535 -131.622038)
			(xy 113.952608 -131.622406) (xy 114.006571 -131.630158) (xy 114.058882 -131.645511) (xy 114.108474 -131.668154)
			(xy 114.154339 -131.697624) (xy 114.195543 -131.733322) (xy 114.231246 -131.774521) (xy 114.260722 -131.820382)
			(xy 114.283371 -131.869971) (xy 114.298732 -131.92228) (xy 114.306491 -131.976242) (xy 114.306491 -132.030758)
			(xy 114.298732 -132.08472) (xy 114.283371 -132.137029) (xy 114.260722 -132.186618) (xy 114.231246 -132.232479)
			(xy 114.195543 -132.273678) (xy 114.154339 -132.309376) (xy 114.108474 -132.338846) (xy 114.058882 -132.361489)
			(xy 114.006571 -132.376842) (xy 113.952609 -132.384594) (xy 113.92535 -132.385054) (xy 113.89798 -132.38457)
			(xy 113.843802 -132.376758) (xy 113.791298 -132.361274) (xy 113.741551 -132.338436) (xy 113.695584 -132.308714)
			(xy 113.674652 -132.291074) (xy 113.674398 -132.29082) (xy 113.667323 -132.285217) (xy 113.650397 -132.278982)
			(xy 113.641378 -132.278628) (xy 113.574322 -132.278628) (xy 113.565305 -132.27899) (xy 113.548388 -132.285233)
			(xy 113.541302 -132.29082) (xy 113.541302 -132.291074) (xy 113.541048 -132.291074) (xy 113.520105 -132.3087)
			(xy 113.474136 -132.338415) (xy 113.424391 -132.361254) (xy 113.371893 -132.376748) (xy 113.317719 -132.384579)
			(xy 113.29035 -132.385054) (xy 113.263104 -132.384472) (xy 113.209169 -132.376711) (xy 113.156886 -132.361353)
			(xy 113.107321 -132.338712) (xy 113.061483 -132.309248) (xy 113.020304 -132.273561) (xy 112.984622 -132.232377)
			(xy 112.955164 -132.186535) (xy 112.932529 -132.136967) (xy 112.917178 -132.084682) (xy 112.909424 -132.030746)
			(xy 103.158544 -132.030746) (xy 103.158544 -139.03706) (xy 106.080052 -139.03706) (xy 106.080564 -139.008321)
			(xy 106.089192 -138.951494) (xy 106.106245 -138.896603) (xy 106.131339 -138.844892) (xy 106.163905 -138.797529)
			(xy 106.183176 -138.776202) (xy 106.18978 -138.769344) (xy 106.196892 -138.75131) (xy 106.196892 -138.66241)
			(xy 106.18978 -138.644376) (xy 106.183176 -138.637518) (xy 106.163893 -138.616202) (xy 106.131327 -138.568838)
			(xy 106.106236 -138.517123) (xy 106.089188 -138.46223) (xy 106.08057 -138.4054) (xy 106.080052 -138.37666)
			(xy 106.080538 -138.349409) (xy 106.088294 -138.295461) (xy 106.103649 -138.243166) (xy 106.126291 -138.193589)
			(xy 106.155757 -138.147739) (xy 106.191448 -138.106548) (xy 106.232639 -138.070857) (xy 106.278489 -138.041391)
			(xy 106.328066 -138.018749) (xy 106.380361 -138.003394) (xy 106.434309 -137.995638) (xy 106.488811 -137.995638)
			(xy 106.542759 -138.003394) (xy 106.595054 -138.018749) (xy 106.644631 -138.041391) (xy 106.690481 -138.070857)
			(xy 106.731672 -138.106548) (xy 106.767363 -138.147739) (xy 106.796829 -138.193589) (xy 106.819471 -138.243166)
			(xy 106.834826 -138.295461) (xy 106.842582 -138.349409) (xy 106.843068 -138.37666) (xy 106.842563 -138.405399)
			(xy 106.833933 -138.462227) (xy 106.816877 -138.517117) (xy 106.791782 -138.568828) (xy 106.759215 -138.616191)
			(xy 106.739944 -138.637518) (xy 106.73334 -138.644376) (xy 106.726228 -138.66241) (xy 106.726228 -138.75131)
			(xy 106.73334 -138.769344) (xy 106.739944 -138.776202) (xy 106.759193 -138.797548) (xy 106.791763 -138.844905)
			(xy 106.81686 -138.896611) (xy 106.833916 -138.951498) (xy 106.842544 -139.008322) (xy 106.843068 -139.03706)
			(xy 106.842617 -139.062965) (xy 106.835599 -139.114299) (xy 106.821702 -139.164211) (xy 106.80118 -139.211785)
			(xy 106.774411 -139.256145) (xy 106.758486 -139.276582) (xy 106.752749 -139.284343) (xy 106.747003 -139.30275)
			(xy 106.74731 -139.312396) (xy 106.752898 -139.381992) (xy 106.753985 -139.391424) (xy 106.76222 -139.408518)
			(xy 106.7689 -139.415266) (xy 106.769408 -139.415774) (xy 106.788658 -139.433887) (xy 106.822417 -139.474559)
			(xy 106.85024 -139.5195) (xy 106.871596 -139.56785) (xy 106.886076 -139.618685) (xy 106.893402 -139.671032)
			(xy 106.893868 -139.69746) (xy 106.893363 -139.726199) (xy 106.884733 -139.783027) (xy 106.867677 -139.837917)
			(xy 106.842582 -139.889628) (xy 106.810015 -139.936991) (xy 106.790744 -139.958318) (xy 106.78414 -139.965176)
			(xy 106.777028 -139.98321) (xy 106.777028 -140.07211) (xy 106.78414 -140.090144) (xy 106.790744 -140.097002)
			(xy 106.809977 -140.118362) (xy 106.842546 -140.165718) (xy 106.867642 -140.217424) (xy 106.884696 -140.27231)
			(xy 106.893323 -140.329134) (xy 106.893328 -140.386608) (xy 106.884709 -140.443433) (xy 106.867663 -140.498321)
			(xy 106.842575 -140.550031) (xy 106.810013 -140.597392) (xy 106.790744 -140.618718) (xy 106.78414 -140.625576)
			(xy 106.777028 -140.64361) (xy 106.777028 -140.73251) (xy 106.78414 -140.750544) (xy 106.790744 -140.757402)
			(xy 106.809993 -140.778748) (xy 106.842563 -140.826105) (xy 106.86766 -140.877811) (xy 106.884716 -140.932698)
			(xy 106.893344 -140.989522) (xy 106.893868 -141.01826) (xy 108.518452 -141.01826) (xy 108.518964 -140.989521)
			(xy 108.527592 -140.932694) (xy 108.544645 -140.877803) (xy 108.569739 -140.826092) (xy 108.602305 -140.778729)
			(xy 108.621576 -140.757402) (xy 108.62818 -140.750544) (xy 108.635292 -140.73251) (xy 108.635292 -140.64361)
			(xy 108.62818 -140.625576) (xy 108.621576 -140.618718) (xy 108.602268 -140.597425) (xy 108.569708 -140.550055)
			(xy 108.544622 -140.498337) (xy 108.527577 -140.443442) (xy 108.518959 -140.386611) (xy 108.518963 -140.329131)
			(xy 108.52759 -140.272301) (xy 108.544643 -140.217408) (xy 108.569737 -140.165694) (xy 108.602304 -140.11833)
			(xy 108.621576 -140.097002) (xy 108.62818 -140.090144) (xy 108.635292 -140.07211) (xy 108.635292 -139.98321)
			(xy 108.62818 -139.965176) (xy 108.621576 -139.958318) (xy 108.602293 -139.937002) (xy 108.569727 -139.889638)
			(xy 108.544636 -139.837923) (xy 108.527588 -139.78303) (xy 108.51897 -139.7262) (xy 108.518452 -139.69746)
			(xy 108.518993 -139.668544) (xy 108.527715 -139.611373) (xy 108.544967 -139.556173) (xy 108.570354 -139.504211)
			(xy 108.603295 -139.456677) (xy 108.643033 -139.41466) (xy 108.665518 -139.39647) (xy 108.674332 -139.388869)
			(xy 108.684511 -139.367964) (xy 108.685076 -139.356338) (xy 108.685076 -139.276582) (xy 108.684541 -139.264949)
			(xy 108.67435 -139.244039) (xy 108.665518 -139.23645) (xy 108.643062 -139.218226) (xy 108.603324 -139.176214)
			(xy 108.570382 -139.128686) (xy 108.544988 -139.076731) (xy 108.527726 -139.021539) (xy 108.518991 -138.964374)
			(xy 108.518452 -138.93546) (xy 108.518964 -138.906721) (xy 108.527592 -138.849894) (xy 108.544645 -138.795003)
			(xy 108.569739 -138.743292) (xy 108.602305 -138.695929) (xy 108.621576 -138.674602) (xy 108.62818 -138.667744)
			(xy 108.635292 -138.64971) (xy 108.635292 -138.56081) (xy 108.62818 -138.542776) (xy 108.621576 -138.535918)
			(xy 108.602293 -138.514602) (xy 108.569727 -138.467238) (xy 108.544636 -138.415523) (xy 108.527588 -138.36063)
			(xy 108.51897 -138.3038) (xy 108.518452 -138.27506) (xy 108.51894 -138.24781) (xy 108.526701 -138.193864)
			(xy 108.54206 -138.141572) (xy 108.564702 -138.091997) (xy 108.594169 -138.046149) (xy 108.62986 -138.00496)
			(xy 108.671049 -137.969269) (xy 108.716897 -137.939802) (xy 108.766472 -137.91716) (xy 108.818764 -137.901801)
			(xy 108.87271 -137.89404) (xy 108.89996 -137.893552) (xy 108.929295 -137.894104) (xy 108.987274 -137.903069)
			(xy 109.043197 -137.920808) (xy 109.095742 -137.946903) (xy 109.143671 -137.980739) (xy 109.165136 -138.00074)
			(xy 109.172502 -138.007852) (xy 109.190282 -138.014964) (xy 109.281214 -138.014964) (xy 109.298994 -138.007852)
			(xy 109.30636 -138.00074) (xy 109.327833 -137.980749) (xy 109.375767 -137.946923) (xy 109.42831 -137.920828)
			(xy 109.484228 -137.903079) (xy 109.542203 -137.894094) (xy 109.571536 -137.893552) (xy 109.598786 -137.894044)
			(xy 109.652732 -137.901805) (xy 109.705024 -137.917162) (xy 109.754599 -137.939805) (xy 109.800447 -137.969271)
			(xy 109.841636 -138.004962) (xy 109.877327 -138.04615) (xy 109.906793 -138.091998) (xy 109.929436 -138.141572)
			(xy 109.944795 -138.193864) (xy 109.952556 -138.24781) (xy 109.953044 -138.27506) (xy 109.952545 -138.3038)
			(xy 109.943915 -138.360628) (xy 109.926858 -138.415518) (xy 109.901761 -138.467229) (xy 109.869192 -138.514591)
			(xy 109.84992 -138.535918) (xy 109.843316 -138.542776) (xy 109.836204 -138.56081) (xy 109.836204 -138.64971)
			(xy 109.843316 -138.667744) (xy 109.84992 -138.674602) (xy 109.869165 -138.695952) (xy 109.901736 -138.743307)
			(xy 109.926834 -138.795013) (xy 109.943891 -138.849899) (xy 109.95252 -138.906722) (xy 109.953044 -138.93546)
			(xy 112.090708 -138.93546) (xy 112.091205 -138.90672) (xy 112.099834 -138.849891) (xy 112.11689 -138.795)
			(xy 112.141988 -138.743289) (xy 112.174559 -138.695928) (xy 112.193832 -138.674602) (xy 112.200436 -138.667744)
			(xy 112.207548 -138.64971) (xy 112.207548 -138.56081) (xy 112.200436 -138.542776) (xy 112.193832 -138.535918)
			(xy 112.174541 -138.514608) (xy 112.141978 -138.467241) (xy 112.116889 -138.415525) (xy 112.099844 -138.360631)
			(xy 112.091226 -138.3038) (xy 112.090708 -138.27506) (xy 112.091194 -138.247809) (xy 112.09895 -138.193861)
			(xy 112.114305 -138.141566) (xy 112.136947 -138.091989) (xy 112.166413 -138.046139) (xy 112.202104 -138.004948)
			(xy 112.243295 -137.969257) (xy 112.289145 -137.939791) (xy 112.338722 -137.917149) (xy 112.391017 -137.901794)
			(xy 112.444965 -137.894038) (xy 112.499467 -137.894038) (xy 112.553415 -137.901794) (xy 112.60571 -137.917149)
			(xy 112.655287 -137.939791) (xy 112.701137 -137.969257) (xy 112.742328 -138.004948) (xy 112.778019 -138.046139)
			(xy 112.807485 -138.091989) (xy 112.830127 -138.141566) (xy 112.845482 -138.193861) (xy 112.853238 -138.247809)
			(xy 112.853724 -138.27506) (xy 112.85323 -138.3038) (xy 112.844599 -138.360628) (xy 112.827542 -138.415519)
			(xy 112.802444 -138.46723) (xy 112.769873 -138.514592) (xy 112.7506 -138.535918) (xy 112.743996 -138.542776)
			(xy 112.736884 -138.56081) (xy 112.736884 -138.64971) (xy 112.743996 -138.667744) (xy 112.7506 -138.674602)
			(xy 112.769841 -138.695955) (xy 112.802414 -138.743309) (xy 112.827513 -138.795014) (xy 112.84457 -138.849899)
			(xy 112.853199 -138.906723) (xy 112.853724 -138.93546) (xy 112.85327 -138.960927) (xy 112.84647 -139.011406)
			(xy 112.833011 -139.060531) (xy 112.813134 -139.107427) (xy 112.787191 -139.15126) (xy 112.755645 -139.19125)
			(xy 112.737646 -139.209272) (xy 112.73007 -139.217369) (xy 112.72217 -139.238063) (xy 112.722406 -139.24915)
			(xy 112.727994 -139.32662) (xy 112.729248 -139.337683) (xy 112.739929 -139.357188) (xy 112.748568 -139.364212)
			(xy 112.772282 -139.382359) (xy 112.81434 -139.42474) (xy 112.849289 -139.473152) (xy 112.876276 -139.526413)
			(xy 112.894644 -139.583226) (xy 112.903944 -139.642206) (xy 112.904524 -139.67206) (xy 112.90403 -139.7008)
			(xy 112.895399 -139.757628) (xy 112.878342 -139.812519) (xy 112.853244 -139.86423) (xy 112.820673 -139.911592)
			(xy 112.8014 -139.932918) (xy 112.794796 -139.939776) (xy 112.787684 -139.95781) (xy 112.787684 -140.04671)
			(xy 112.794796 -140.064744) (xy 112.8014 -140.071602) (xy 112.82063 -140.092964) (xy 112.853195 -140.140321)
			(xy 112.878287 -140.192027) (xy 112.895339 -140.246912) (xy 112.903964 -140.303734) (xy 112.903969 -140.361207)
			(xy 112.895352 -140.418031) (xy 112.878308 -140.472919) (xy 112.853224 -140.524629) (xy 112.820667 -140.571991)
			(xy 112.8014 -140.593318) (xy 112.794796 -140.600176) (xy 112.787684 -140.61821) (xy 112.787684 -140.70711)
			(xy 112.794796 -140.725144) (xy 112.8014 -140.732002) (xy 112.820641 -140.753355) (xy 112.853214 -140.800709)
			(xy 112.878313 -140.852414) (xy 112.89537 -140.907299) (xy 112.903999 -140.964123) (xy 112.90406 -140.96746)
			(xy 114.529108 -140.96746) (xy 114.529605 -140.93872) (xy 114.538234 -140.881891) (xy 114.55529 -140.827)
			(xy 114.580388 -140.775289) (xy 114.612959 -140.727928) (xy 114.632232 -140.706602) (xy 114.638836 -140.699744)
			(xy 114.645948 -140.68171) (xy 114.645948 -140.59281) (xy 114.638836 -140.574776) (xy 114.632232 -140.567918)
			(xy 114.612921 -140.546626) (xy 114.580357 -140.499258) (xy 114.555267 -140.44754) (xy 114.538219 -140.392644)
			(xy 114.5296 -140.335812) (xy 114.529605 -140.27833) (xy 114.538232 -140.221499) (xy 114.555288 -140.166605)
			(xy 114.580386 -140.114892) (xy 114.612958 -140.067529) (xy 114.632232 -140.046202) (xy 114.638836 -140.039344)
			(xy 114.645948 -140.02131) (xy 114.645948 -139.93241) (xy 114.638836 -139.914376) (xy 114.632232 -139.907518)
			(xy 114.612941 -139.886208) (xy 114.580378 -139.838841) (xy 114.555289 -139.787125) (xy 114.538244 -139.732231)
			(xy 114.529626 -139.6754) (xy 114.529108 -139.64666) (xy 114.529546 -139.620345) (xy 114.536787 -139.568215)
			(xy 114.551111 -139.517572) (xy 114.572249 -139.469373) (xy 114.599801 -139.42453) (xy 114.633244 -139.383892)
			(xy 114.652298 -139.365736) (xy 114.659685 -139.358203) (xy 114.668218 -139.338931) (xy 114.668808 -139.328398)
			(xy 114.668808 -139.253722) (xy 114.668278 -139.243173) (xy 114.659743 -139.223877) (xy 114.652298 -139.216384)
			(xy 114.633241 -139.19823) (xy 114.599784 -139.1576) (xy 114.572226 -139.112759) (xy 114.551087 -139.064558)
			(xy 114.53677 -139.01391) (xy 114.529546 -138.961776) (xy 114.529108 -138.93546) (xy 114.529605 -138.90672)
			(xy 114.538234 -138.849891) (xy 114.55529 -138.795) (xy 114.580388 -138.743289) (xy 114.612959 -138.695928)
			(xy 114.632232 -138.674602) (xy 114.638836 -138.667744) (xy 114.645948 -138.64971) (xy 114.645948 -138.56081)
			(xy 114.638836 -138.542776) (xy 114.632232 -138.535918) (xy 114.612941 -138.514608) (xy 114.580378 -138.467241)
			(xy 114.555289 -138.415525) (xy 114.538244 -138.360631) (xy 114.529626 -138.3038) (xy 114.529108 -138.27506)
			(xy 114.529541 -138.247807) (xy 114.537303 -138.193857) (xy 114.552664 -138.14156) (xy 114.575311 -138.091981)
			(xy 114.604783 -138.04613) (xy 114.64048 -138.00494) (xy 114.681675 -137.969249) (xy 114.727531 -137.939784)
			(xy 114.777112 -137.917144) (xy 114.829411 -137.901791) (xy 114.883363 -137.894037) (xy 114.910616 -137.893552)
			(xy 114.93829 -137.894058) (xy 114.993059 -137.902052) (xy 115.046094 -137.917884) (xy 115.096283 -137.94122)
			(xy 115.142567 -137.971571) (xy 115.1636 -137.989564) (xy 115.170966 -137.996168) (xy 115.188746 -138.002518)
			(xy 115.278154 -137.999724) (xy 115.295934 -137.992104) (xy 115.302792 -137.985246) (xy 115.32441 -137.964521)
			(xy 115.372875 -137.929347) (xy 115.426241 -137.90218) (xy 115.483198 -137.883689) (xy 115.542344 -137.874327)
			(xy 115.572286 -137.87374) (xy 115.599541 -137.874169) (xy 115.653495 -137.881925) (xy 115.705797 -137.897281)
			(xy 115.75538 -137.919926) (xy 115.801236 -137.949397) (xy 115.84243 -137.985094) (xy 115.878124 -138.026292)
			(xy 115.90759 -138.07215) (xy 115.93023 -138.121735) (xy 115.945582 -138.174038) (xy 115.953334 -138.227993)
			(xy 115.953794 -138.255248) (xy 115.953301 -138.283988) (xy 115.944671 -138.340817) (xy 115.927614 -138.395708)
			(xy 115.902516 -138.447419) (xy 115.869944 -138.49478) (xy 115.85067 -138.516106) (xy 115.844066 -138.522964)
			(xy 115.836954 -138.540998) (xy 115.836954 -138.578844) (xy 118.705882 -138.578844) (xy 118.709953 -138.523222)
			(xy 118.722079 -138.468785) (xy 118.742002 -138.416694) (xy 118.769298 -138.368059) (xy 118.803384 -138.323916)
			(xy 118.843533 -138.285207) (xy 118.888891 -138.252756) (xy 118.938491 -138.227255) (xy 118.991275 -138.209248)
			(xy 119.046118 -138.199118) (xy 119.101852 -138.197081) (xy 119.157289 -138.203181) (xy 119.211246 -138.217287)
			(xy 119.262575 -138.239099) (xy 119.310181 -138.268153) (xy 119.353049 -138.303828) (xy 119.390266 -138.345365)
			(xy 119.421039 -138.391878) (xy 119.444711 -138.442375) (xy 119.460779 -138.495782) (xy 119.468899 -138.550958)
			(xy 119.469408 -138.578844) (xy 119.468899 -138.60673) (xy 119.460779 -138.661906) (xy 119.444711 -138.715313)
			(xy 119.421039 -138.76581) (xy 119.390266 -138.812323) (xy 119.353049 -138.85386) (xy 119.310181 -138.889535)
			(xy 119.262575 -138.918589) (xy 119.211246 -138.940401) (xy 119.157289 -138.954507) (xy 119.101852 -138.960607)
			(xy 119.046118 -138.95857) (xy 118.991275 -138.94844) (xy 118.938491 -138.930433) (xy 118.888891 -138.904932)
			(xy 118.843533 -138.872481) (xy 118.803384 -138.833772) (xy 118.769298 -138.789629) (xy 118.742002 -138.740994)
			(xy 118.722079 -138.688903) (xy 118.709953 -138.634466) (xy 118.705882 -138.578844) (xy 115.836954 -138.578844)
			(xy 115.836954 -138.629898) (xy 115.844066 -138.647932) (xy 115.85067 -138.65479) (xy 115.869965 -138.676096)
			(xy 115.902527 -138.723464) (xy 115.927615 -138.775181) (xy 115.94466 -138.830076) (xy 115.953277 -138.886908)
			(xy 115.953794 -138.915648) (xy 115.95336 -138.941963) (xy 115.946119 -138.994093) (xy 115.931793 -139.044737)
			(xy 115.910655 -139.092936) (xy 115.883102 -139.137778) (xy 115.849658 -139.178416) (xy 115.830604 -139.196572)
			(xy 115.823213 -139.204103) (xy 115.814683 -139.223376) (xy 115.814094 -139.23391) (xy 115.814094 -139.308586)
			(xy 115.814619 -139.319136) (xy 115.823157 -139.338431) (xy 115.830604 -139.345924) (xy 115.849665 -139.364074)
			(xy 115.883121 -139.404705) (xy 115.91068 -139.449547) (xy 115.931817 -139.497748) (xy 115.946133 -139.548397)
			(xy 115.953356 -139.600532) (xy 115.953794 -139.626848) (xy 115.953301 -139.655588) (xy 115.944671 -139.712417)
			(xy 115.927614 -139.767308) (xy 115.902516 -139.819019) (xy 115.869944 -139.86638) (xy 115.85067 -139.887706)
			(xy 115.844066 -139.894564) (xy 115.836954 -139.912598) (xy 115.836954 -140.001498) (xy 115.844066 -140.019532)
			(xy 115.85067 -140.02639) (xy 115.869989 -140.047675) (xy 115.902553 -140.095045) (xy 115.927642 -140.146763)
			(xy 115.944689 -140.20166) (xy 115.953307 -140.258494) (xy 115.953302 -140.315976) (xy 115.944673 -140.372808)
			(xy 115.927616 -140.427702) (xy 115.902518 -140.479416) (xy 115.869945 -140.526779) (xy 115.85067 -140.548106)
			(xy 115.844066 -140.554964) (xy 115.836954 -140.572998) (xy 115.836954 -140.661898) (xy 115.844066 -140.679932)
			(xy 115.85067 -140.68679) (xy 115.869965 -140.708096) (xy 115.902527 -140.755464) (xy 115.927615 -140.807181)
			(xy 115.94466 -140.862076) (xy 115.953277 -140.918908) (xy 115.953794 -140.947648) (xy 115.953367 -140.974901)
			(xy 115.945603 -141.028852) (xy 115.930241 -141.081148) (xy 115.907594 -141.130727) (xy 115.878121 -141.176577)
			(xy 115.842424 -141.217767) (xy 115.801228 -141.253458) (xy 115.755372 -141.282923) (xy 115.70579 -141.305563)
			(xy 115.653491 -141.320917) (xy 115.599539 -141.328671) (xy 115.572286 -141.329156) (xy 115.544612 -141.328647)
			(xy 115.489844 -141.320653) (xy 115.436808 -141.304822) (xy 115.38662 -141.281486) (xy 115.340335 -141.251136)
			(xy 115.319302 -141.233144) (xy 115.311936 -141.22654) (xy 115.294156 -141.22019) (xy 115.204748 -141.222984)
			(xy 115.186968 -141.230604) (xy 115.18011 -141.237462) (xy 115.158536 -141.258235) (xy 115.11006 -141.293403)
			(xy 115.056682 -141.32056) (xy 114.999716 -141.33904) (xy 114.940561 -141.348388) (xy 114.910616 -141.348968)
			(xy 114.883362 -141.34853) (xy 114.829408 -141.340774) (xy 114.777107 -141.325418) (xy 114.727524 -141.302774)
			(xy 114.681669 -141.273304) (xy 114.640475 -141.237608) (xy 114.604781 -141.196412) (xy 114.575314 -141.150555)
			(xy 114.552674 -141.10097) (xy 114.537321 -141.048669) (xy 114.529569 -140.994714) (xy 114.529108 -140.96746)
			(xy 112.90406 -140.96746) (xy 112.904524 -140.99286) (xy 112.904038 -141.020111) (xy 112.896282 -141.074059)
			(xy 112.880927 -141.126354) (xy 112.858285 -141.175931) (xy 112.828819 -141.221781) (xy 112.793128 -141.262972)
			(xy 112.751937 -141.298663) (xy 112.706087 -141.328129) (xy 112.65651 -141.350771) (xy 112.604215 -141.366126)
			(xy 112.550267 -141.373882) (xy 112.495765 -141.373882) (xy 112.441817 -141.366126) (xy 112.389522 -141.350771)
			(xy 112.339945 -141.328129) (xy 112.294095 -141.298663) (xy 112.252904 -141.262972) (xy 112.217213 -141.221781)
			(xy 112.187747 -141.175931) (xy 112.165105 -141.126354) (xy 112.14975 -141.074059) (xy 112.141994 -141.020111)
			(xy 112.141508 -140.99286) (xy 112.142005 -140.96412) (xy 112.150634 -140.907291) (xy 112.16769 -140.8524)
			(xy 112.192788 -140.800689) (xy 112.225359 -140.753328) (xy 112.244632 -140.732002) (xy 112.251236 -140.725144)
			(xy 112.258348 -140.70711) (xy 112.258348 -140.61821) (xy 112.251236 -140.600176) (xy 112.244632 -140.593318)
			(xy 112.225321 -140.572026) (xy 112.192757 -140.524658) (xy 112.167667 -140.47294) (xy 112.150619 -140.418044)
			(xy 112.142 -140.361212) (xy 112.142005 -140.30373) (xy 112.150632 -140.246899) (xy 112.167688 -140.192005)
			(xy 112.192786 -140.140292) (xy 112.225358 -140.092929) (xy 112.244632 -140.071602) (xy 112.251236 -140.064744)
			(xy 112.258348 -140.04671) (xy 112.258348 -139.95781) (xy 112.251236 -139.939776) (xy 112.244632 -139.932918)
			(xy 112.225341 -139.911608) (xy 112.192778 -139.864241) (xy 112.167689 -139.812525) (xy 112.150644 -139.757631)
			(xy 112.142026 -139.7008) (xy 112.141508 -139.67206) (xy 112.141965 -139.646593) (xy 112.148764 -139.596114)
			(xy 112.162221 -139.546989) (xy 112.182098 -139.500093) (xy 112.20804 -139.456259) (xy 112.239586 -139.41627)
			(xy 112.257586 -139.398248) (xy 112.265156 -139.390147) (xy 112.273059 -139.369456) (xy 112.272826 -139.35837)
			(xy 112.267238 -139.2809) (xy 112.265962 -139.269842) (xy 112.255296 -139.250335) (xy 112.246664 -139.243308)
			(xy 112.222945 -139.225168) (xy 112.18089 -139.182783) (xy 112.145944 -139.134369) (xy 112.118958 -139.081107)
			(xy 112.100591 -139.024294) (xy 112.091289 -138.965314) (xy 112.090708 -138.93546) (xy 109.953044 -138.93546)
			(xy 109.952518 -138.964377) (xy 109.943794 -139.021549) (xy 109.926539 -139.076748) (xy 109.901149 -139.128711)
			(xy 109.868205 -139.176245) (xy 109.828464 -139.218261) (xy 109.805978 -139.23645) (xy 109.7972 -139.244085)
			(xy 109.787001 -139.264965) (xy 109.78642 -139.276582) (xy 109.78642 -139.356338) (xy 109.786945 -139.367972)
			(xy 109.797143 -139.388882) (xy 109.805978 -139.39647) (xy 109.828443 -139.414684) (xy 109.86818 -139.456698)
			(xy 109.901122 -139.504228) (xy 109.926514 -139.556185) (xy 109.943774 -139.611379) (xy 109.952507 -139.668545)
			(xy 109.953044 -139.69746) (xy 109.952545 -139.7262) (xy 109.943915 -139.783028) (xy 109.926858 -139.837918)
			(xy 109.901761 -139.889629) (xy 109.869192 -139.936991) (xy 109.84992 -139.958318) (xy 109.843316 -139.965176)
			(xy 109.836204 -139.98321) (xy 109.836204 -140.07211) (xy 109.843316 -140.090144) (xy 109.84992 -140.097002)
			(xy 109.869149 -140.118364) (xy 109.901712 -140.165722) (xy 109.926803 -140.217428) (xy 109.943854 -140.272313)
			(xy 109.952479 -140.329135) (xy 109.952483 -140.386607) (xy 109.943867 -140.44343) (xy 109.926824 -140.498318)
			(xy 109.901741 -140.550028) (xy 109.869186 -140.59739) (xy 109.84992 -140.618718) (xy 109.843316 -140.625576)
			(xy 109.836204 -140.64361) (xy 109.836204 -140.73251) (xy 109.843316 -140.750544) (xy 109.84992 -140.757402)
			(xy 109.869165 -140.778752) (xy 109.901736 -140.826107) (xy 109.926834 -140.877813) (xy 109.943891 -140.932699)
			(xy 109.95252 -140.989522) (xy 109.953044 -141.01826) (xy 109.952508 -141.04551) (xy 109.944757 -141.099457)
			(xy 109.929408 -141.151751) (xy 109.906773 -141.201329) (xy 109.877312 -141.24718) (xy 109.841626 -141.288372)
			(xy 109.800441 -141.324067) (xy 109.754595 -141.353536) (xy 109.705022 -141.376181) (xy 109.652731 -141.391541)
			(xy 109.598786 -141.399302) (xy 109.571536 -141.399768) (xy 109.542202 -141.399213) (xy 109.484222 -141.390248)
			(xy 109.4283 -141.372509) (xy 109.375755 -141.346415) (xy 109.327825 -141.312581) (xy 109.30636 -141.29258)
			(xy 109.298994 -141.285468) (xy 109.281214 -141.278356) (xy 109.190282 -141.278356) (xy 109.172502 -141.285468)
			(xy 109.165136 -141.29258) (xy 109.143652 -141.312559) (xy 109.095723 -141.34639) (xy 109.043182 -141.372489)
			(xy 108.987266 -141.39024) (xy 108.929293 -141.399226) (xy 108.89996 -141.399768) (xy 108.872706 -141.399359)
			(xy 108.818753 -141.391596) (xy 108.766455 -141.376234) (xy 108.716875 -141.353585) (xy 108.671023 -141.324111)
			(xy 108.629832 -141.288412) (xy 108.594141 -141.247213) (xy 108.564676 -141.201355) (xy 108.542038 -141.15177)
			(xy 108.526687 -141.099468) (xy 108.518935 -141.045514) (xy 108.518452 -141.01826) (xy 106.893868 -141.01826)
			(xy 106.893382 -141.045511) (xy 106.885626 -141.099459) (xy 106.870271 -141.151754) (xy 106.847629 -141.201331)
			(xy 106.818163 -141.247181) (xy 106.782472 -141.288372) (xy 106.741281 -141.324063) (xy 106.695431 -141.353529)
			(xy 106.645854 -141.376171) (xy 106.593559 -141.391526) (xy 106.539611 -141.399282) (xy 106.485109 -141.399282)
			(xy 106.431161 -141.391526) (xy 106.378866 -141.376171) (xy 106.329289 -141.353529) (xy 106.283439 -141.324063)
			(xy 106.242248 -141.288372) (xy 106.206557 -141.247181) (xy 106.177091 -141.201331) (xy 106.154449 -141.151754)
			(xy 106.139094 -141.099459) (xy 106.131338 -141.045511) (xy 106.130852 -141.01826) (xy 106.131364 -140.989521)
			(xy 106.139992 -140.932694) (xy 106.157045 -140.877803) (xy 106.182139 -140.826092) (xy 106.214705 -140.778729)
			(xy 106.233976 -140.757402) (xy 106.24058 -140.750544) (xy 106.247692 -140.73251) (xy 106.247692 -140.64361)
			(xy 106.24058 -140.625576) (xy 106.233976 -140.618718) (xy 106.214668 -140.597425) (xy 106.182108 -140.550055)
			(xy 106.157022 -140.498337) (xy 106.139977 -140.443442) (xy 106.131359 -140.386611) (xy 106.131363 -140.329131)
			(xy 106.13999 -140.272301) (xy 106.157043 -140.217408) (xy 106.182137 -140.165694) (xy 106.214704 -140.11833)
			(xy 106.233976 -140.097002) (xy 106.24058 -140.090144) (xy 106.247692 -140.07211) (xy 106.247692 -139.98321)
			(xy 106.24058 -139.965176) (xy 106.233976 -139.958318) (xy 106.214693 -139.937002) (xy 106.182127 -139.889638)
			(xy 106.157036 -139.837923) (xy 106.139988 -139.78303) (xy 106.13137 -139.7262) (xy 106.130852 -139.69746)
			(xy 106.13131 -139.671555) (xy 106.138325 -139.620221) (xy 106.152221 -139.570309) (xy 106.172741 -139.522735)
			(xy 106.199509 -139.478375) (xy 106.215434 -139.457938) (xy 106.221153 -139.450166) (xy 106.226912 -139.431767)
			(xy 106.22661 -139.422124) (xy 106.221022 -139.352528) (xy 106.21992 -139.343099) (xy 106.211695 -139.326005)
			(xy 106.20502 -139.319254) (xy 106.204512 -139.318746) (xy 106.185276 -139.300619) (xy 106.151515 -139.259951)
			(xy 106.123689 -139.215013) (xy 106.102331 -139.166665) (xy 106.087848 -139.115832) (xy 106.080519 -139.063487)
			(xy 106.080052 -139.03706) (xy 103.158544 -139.03706) (xy 103.158544 -158.947612) (xy 107.304584 -158.947612)
			(xy 107.308655 -158.89199) (xy 107.320781 -158.837553) (xy 107.340704 -158.785462) (xy 107.368 -158.736827)
			(xy 107.402086 -158.692684) (xy 107.442235 -158.653975) (xy 107.487593 -158.621524) (xy 107.537193 -158.596023)
			(xy 107.589977 -158.578016) (xy 107.64482 -158.567886) (xy 107.700554 -158.565849) (xy 107.755991 -158.571949)
			(xy 107.809948 -158.586055) (xy 107.861277 -158.607867) (xy 107.908883 -158.636921) (xy 107.951751 -158.672596)
			(xy 107.988968 -158.714133) (xy 108.019741 -158.760646) (xy 108.043413 -158.811143) (xy 108.059481 -158.86455)
			(xy 108.067601 -158.919726) (xy 108.06811 -158.947612) (xy 108.067601 -158.975498) (xy 108.059481 -159.030674)
			(xy 108.043413 -159.084081) (xy 108.019741 -159.134578) (xy 107.988968 -159.181091) (xy 107.951751 -159.222628)
			(xy 107.908883 -159.258303) (xy 107.861277 -159.287357) (xy 107.809948 -159.309169) (xy 107.755991 -159.323275)
			(xy 107.700554 -159.329375) (xy 107.64482 -159.327338) (xy 107.589977 -159.317208) (xy 107.537193 -159.299201)
			(xy 107.487593 -159.2737) (xy 107.442235 -159.241249) (xy 107.402086 -159.20254) (xy 107.368 -159.158397)
			(xy 107.340704 -159.109762) (xy 107.320781 -159.057671) (xy 107.308655 -159.003234) (xy 107.304584 -158.947612)
			(xy 103.158544 -158.947612) (xy 103.158544 -159.681418) (xy 112.176558 -159.681418) (xy 112.180629 -159.625796)
			(xy 112.192755 -159.571359) (xy 112.212678 -159.519268) (xy 112.239974 -159.470633) (xy 112.27406 -159.42649)
			(xy 112.314209 -159.387781) (xy 112.359567 -159.35533) (xy 112.409167 -159.329829) (xy 112.461951 -159.311822)
			(xy 112.516794 -159.301692) (xy 112.572528 -159.299655) (xy 112.627965 -159.305755) (xy 112.681922 -159.319861)
			(xy 112.733251 -159.341673) (xy 112.780857 -159.370727) (xy 112.823725 -159.406402) (xy 112.860942 -159.447939)
			(xy 112.891715 -159.494452) (xy 112.915387 -159.544949) (xy 112.931455 -159.598356) (xy 112.939575 -159.653532)
			(xy 112.940084 -159.681418) (xy 112.939575 -159.709304) (xy 112.931455 -159.76448) (xy 112.915387 -159.817887)
			(xy 112.891715 -159.868384) (xy 112.860942 -159.914897) (xy 112.823725 -159.956434) (xy 112.780857 -159.992109)
			(xy 112.733251 -160.021163) (xy 112.681922 -160.042975) (xy 112.627965 -160.057081) (xy 112.572528 -160.063181)
			(xy 112.516794 -160.061144) (xy 112.461951 -160.051014) (xy 112.409167 -160.033007) (xy 112.359567 -160.007506)
			(xy 112.314209 -159.975055) (xy 112.27406 -159.936346) (xy 112.239974 -159.892203) (xy 112.212678 -159.843568)
			(xy 112.192755 -159.791477) (xy 112.180629 -159.73704) (xy 112.176558 -159.681418) (xy 103.158544 -159.681418)
			(xy 103.158544 -160.220406) (xy 113.389916 -160.220406) (xy 113.393987 -160.164784) (xy 113.406113 -160.110347)
			(xy 113.426036 -160.058256) (xy 113.453332 -160.009621) (xy 113.487418 -159.965478) (xy 113.527567 -159.926769)
			(xy 113.572925 -159.894318) (xy 113.622525 -159.868817) (xy 113.675309 -159.85081) (xy 113.730152 -159.84068)
			(xy 113.785886 -159.838643) (xy 113.841323 -159.844743) (xy 113.89528 -159.858849) (xy 113.946609 -159.880661)
			(xy 113.994215 -159.909715) (xy 114.037083 -159.94539) (xy 114.0743 -159.986927) (xy 114.105073 -160.03344)
			(xy 114.128745 -160.083937) (xy 114.144813 -160.137344) (xy 114.152933 -160.19252) (xy 114.153442 -160.220406)
			(xy 114.152933 -160.248292) (xy 114.144813 -160.303468) (xy 114.128745 -160.356875) (xy 114.105073 -160.407372)
			(xy 114.0743 -160.453885) (xy 114.058189 -160.471866) (xy 114.82019 -160.471866) (xy 114.824261 -160.416244)
			(xy 114.836387 -160.361807) (xy 114.85631 -160.309716) (xy 114.883606 -160.261081) (xy 114.917692 -160.216938)
			(xy 114.957841 -160.178229) (xy 115.003199 -160.145778) (xy 115.052799 -160.120277) (xy 115.105583 -160.10227)
			(xy 115.160426 -160.09214) (xy 115.21616 -160.090103) (xy 115.271597 -160.096203) (xy 115.325554 -160.110309)
			(xy 115.376883 -160.132121) (xy 115.424489 -160.161175) (xy 115.467357 -160.19685) (xy 115.504574 -160.238387)
			(xy 115.535347 -160.2849) (xy 115.559019 -160.335397) (xy 115.575087 -160.388804) (xy 115.583207 -160.44398)
			(xy 115.583716 -160.471866) (xy 115.583207 -160.499752) (xy 115.575087 -160.554928) (xy 115.559019 -160.608335)
			(xy 115.535347 -160.658832) (xy 115.504574 -160.705345) (xy 115.467357 -160.746882) (xy 115.424489 -160.782557)
			(xy 115.376883 -160.811611) (xy 115.325554 -160.833423) (xy 115.271597 -160.847529) (xy 115.21616 -160.853629)
			(xy 115.160426 -160.851592) (xy 115.105583 -160.841462) (xy 115.052799 -160.823455) (xy 115.003199 -160.797954)
			(xy 114.957841 -160.765503) (xy 114.917692 -160.726794) (xy 114.883606 -160.682651) (xy 114.85631 -160.634016)
			(xy 114.836387 -160.581925) (xy 114.824261 -160.527488) (xy 114.82019 -160.471866) (xy 114.058189 -160.471866)
			(xy 114.037083 -160.495422) (xy 113.994215 -160.531097) (xy 113.946609 -160.560151) (xy 113.89528 -160.581963)
			(xy 113.841323 -160.596069) (xy 113.785886 -160.602169) (xy 113.730152 -160.600132) (xy 113.675309 -160.590002)
			(xy 113.622525 -160.571995) (xy 113.572925 -160.546494) (xy 113.527567 -160.514043) (xy 113.487418 -160.475334)
			(xy 113.453332 -160.431191) (xy 113.426036 -160.382556) (xy 113.406113 -160.330465) (xy 113.393987 -160.276028)
			(xy 113.389916 -160.220406) (xy 103.158544 -160.220406) (xy 103.158544 -162.131502) (xy 111.67313 -162.131502)
			(xy 111.677201 -162.07588) (xy 111.689327 -162.021443) (xy 111.70925 -161.969352) (xy 111.736546 -161.920717)
			(xy 111.770632 -161.876574) (xy 111.810781 -161.837865) (xy 111.856139 -161.805414) (xy 111.905739 -161.779913)
			(xy 111.958523 -161.761906) (xy 112.013366 -161.751776) (xy 112.0691 -161.749739) (xy 112.124537 -161.755839)
			(xy 112.178494 -161.769945) (xy 112.229823 -161.791757) (xy 112.252954 -161.805874) (xy 113.226848 -161.805874)
			(xy 113.230919 -161.750252) (xy 113.243045 -161.695815) (xy 113.262968 -161.643724) (xy 113.290264 -161.595089)
			(xy 113.32435 -161.550946) (xy 113.364499 -161.512237) (xy 113.409857 -161.479786) (xy 113.459457 -161.454285)
			(xy 113.512241 -161.436278) (xy 113.567084 -161.426148) (xy 113.622818 -161.424111) (xy 113.678255 -161.430211)
			(xy 113.732212 -161.444317) (xy 113.783541 -161.466129) (xy 113.831147 -161.495183) (xy 113.874015 -161.530858)
			(xy 113.911232 -161.572395) (xy 113.942005 -161.618908) (xy 113.965677 -161.669405) (xy 113.981745 -161.722812)
			(xy 113.989865 -161.777988) (xy 113.990374 -161.805874) (xy 113.989865 -161.83376) (xy 113.981745 -161.888936)
			(xy 113.965677 -161.942343) (xy 113.942005 -161.99284) (xy 113.911232 -162.039353) (xy 113.874015 -162.08089)
			(xy 113.831147 -162.116565) (xy 113.81125 -162.128708) (xy 115.561108 -162.128708) (xy 115.565179 -162.073086)
			(xy 115.577305 -162.018649) (xy 115.597228 -161.966558) (xy 115.624524 -161.917923) (xy 115.65861 -161.87378)
			(xy 115.698759 -161.835071) (xy 115.744117 -161.80262) (xy 115.793717 -161.777119) (xy 115.846501 -161.759112)
			(xy 115.901344 -161.748982) (xy 115.957078 -161.746945) (xy 116.012515 -161.753045) (xy 116.066472 -161.767151)
			(xy 116.117801 -161.788963) (xy 116.165407 -161.818017) (xy 116.208275 -161.853692) (xy 116.245492 -161.895229)
			(xy 116.276265 -161.941742) (xy 116.299937 -161.992239) (xy 116.316005 -162.045646) (xy 116.324125 -162.100822)
			(xy 116.324634 -162.128708) (xy 116.324125 -162.156594) (xy 116.316005 -162.21177) (xy 116.299937 -162.265177)
			(xy 116.276265 -162.315674) (xy 116.245492 -162.362187) (xy 116.208275 -162.403724) (xy 116.165407 -162.439399)
			(xy 116.117801 -162.468453) (xy 116.066472 -162.490265) (xy 116.012515 -162.504371) (xy 115.957078 -162.510471)
			(xy 115.901344 -162.508434) (xy 115.846501 -162.498304) (xy 115.793717 -162.480297) (xy 115.744117 -162.454796)
			(xy 115.698759 -162.422345) (xy 115.65861 -162.383636) (xy 115.624524 -162.339493) (xy 115.597228 -162.290858)
			(xy 115.577305 -162.238767) (xy 115.565179 -162.18433) (xy 115.561108 -162.128708) (xy 113.81125 -162.128708)
			(xy 113.783541 -162.145619) (xy 113.732212 -162.167431) (xy 113.678255 -162.181537) (xy 113.622818 -162.187637)
			(xy 113.567084 -162.1856) (xy 113.512241 -162.17547) (xy 113.459457 -162.157463) (xy 113.409857 -162.131962)
			(xy 113.364499 -162.099511) (xy 113.32435 -162.060802) (xy 113.290264 -162.016659) (xy 113.262968 -161.968024)
			(xy 113.243045 -161.915933) (xy 113.230919 -161.861496) (xy 113.226848 -161.805874) (xy 112.252954 -161.805874)
			(xy 112.277429 -161.820811) (xy 112.320297 -161.856486) (xy 112.357514 -161.898023) (xy 112.388287 -161.944536)
			(xy 112.411959 -161.995033) (xy 112.428027 -162.04844) (xy 112.436147 -162.103616) (xy 112.436656 -162.131502)
			(xy 112.436147 -162.159388) (xy 112.428027 -162.214564) (xy 112.411959 -162.267971) (xy 112.388287 -162.318468)
			(xy 112.357514 -162.364981) (xy 112.320297 -162.406518) (xy 112.277429 -162.442193) (xy 112.229823 -162.471247)
			(xy 112.178494 -162.493059) (xy 112.124537 -162.507165) (xy 112.0691 -162.513265) (xy 112.013366 -162.511228)
			(xy 111.958523 -162.501098) (xy 111.905739 -162.483091) (xy 111.856139 -162.45759) (xy 111.810781 -162.425139)
			(xy 111.770632 -162.38643) (xy 111.736546 -162.342287) (xy 111.70925 -162.293652) (xy 111.689327 -162.241561)
			(xy 111.677201 -162.187124) (xy 111.67313 -162.131502) (xy 103.158544 -162.131502) (xy 103.158544 -163.41344)
			(xy 113.15268 -163.41344) (xy 113.156751 -163.357818) (xy 113.168877 -163.303381) (xy 113.1888 -163.25129)
			(xy 113.216096 -163.202655) (xy 113.250182 -163.158512) (xy 113.290331 -163.119803) (xy 113.335689 -163.087352)
			(xy 113.385289 -163.061851) (xy 113.438073 -163.043844) (xy 113.492916 -163.033714) (xy 113.54865 -163.031677)
			(xy 113.604087 -163.037777) (xy 113.658044 -163.051883) (xy 113.709373 -163.073695) (xy 113.756979 -163.102749)
			(xy 113.799847 -163.138424) (xy 113.837064 -163.179961) (xy 113.867837 -163.226474) (xy 113.891509 -163.276971)
			(xy 113.907577 -163.330378) (xy 113.915697 -163.385554) (xy 113.916206 -163.41344) (xy 113.915697 -163.441326)
			(xy 113.907577 -163.496502) (xy 113.891509 -163.549909) (xy 113.867837 -163.600406) (xy 113.837064 -163.646919)
			(xy 113.799847 -163.688456) (xy 113.756979 -163.724131) (xy 113.709373 -163.753185) (xy 113.658044 -163.774997)
			(xy 113.604087 -163.789103) (xy 113.54865 -163.795203) (xy 113.492916 -163.793166) (xy 113.438073 -163.783036)
			(xy 113.385289 -163.765029) (xy 113.335689 -163.739528) (xy 113.290331 -163.707077) (xy 113.250182 -163.668368)
			(xy 113.216096 -163.624225) (xy 113.1888 -163.57559) (xy 113.168877 -163.523499) (xy 113.156751 -163.469062)
			(xy 113.15268 -163.41344) (xy 103.158544 -163.41344) (xy 103.158544 -164.093144) (xy 121.833892 -164.093144)
			(xy 121.837963 -164.037522) (xy 121.850089 -163.983085) (xy 121.870012 -163.930994) (xy 121.897308 -163.882359)
			(xy 121.931394 -163.838216) (xy 121.971543 -163.799507) (xy 122.016901 -163.767056) (xy 122.066501 -163.741555)
			(xy 122.119285 -163.723548) (xy 122.174128 -163.713418) (xy 122.229862 -163.711381) (xy 122.285299 -163.717481)
			(xy 122.339256 -163.731587) (xy 122.390585 -163.753399) (xy 122.438191 -163.782453) (xy 122.481059 -163.818128)
			(xy 122.518276 -163.859665) (xy 122.549049 -163.906178) (xy 122.572721 -163.956675) (xy 122.588789 -164.010082)
			(xy 122.596909 -164.065258) (xy 122.597418 -164.093144) (xy 122.596909 -164.12103) (xy 122.588789 -164.176206)
			(xy 122.572721 -164.229613) (xy 122.549049 -164.28011) (xy 122.518276 -164.326623) (xy 122.481059 -164.36816)
			(xy 122.438191 -164.403835) (xy 122.390585 -164.432889) (xy 122.339256 -164.454701) (xy 122.285299 -164.468807)
			(xy 122.229862 -164.474907) (xy 122.174128 -164.47287) (xy 122.119285 -164.46274) (xy 122.066501 -164.444733)
			(xy 122.016901 -164.419232) (xy 121.971543 -164.386781) (xy 121.931394 -164.348072) (xy 121.897308 -164.303929)
			(xy 121.870012 -164.255294) (xy 121.850089 -164.203203) (xy 121.837963 -164.148766) (xy 121.833892 -164.093144)
			(xy 103.158544 -164.093144) (xy 103.158544 -166.81704) (xy 103.158078 -166.850194) (xy 103.150655 -166.916086)
			(xy 103.135905 -166.980734) (xy 103.129462 -166.999158) (xy 121.98045 -166.999158) (xy 121.984521 -166.943536)
			(xy 121.996647 -166.889099) (xy 122.01657 -166.837008) (xy 122.043866 -166.788373) (xy 122.077952 -166.74423)
			(xy 122.118101 -166.705521) (xy 122.163459 -166.67307) (xy 122.213059 -166.647569) (xy 122.265843 -166.629562)
			(xy 122.320686 -166.619432) (xy 122.37642 -166.617395) (xy 122.431857 -166.623495) (xy 122.485814 -166.637601)
			(xy 122.537143 -166.659413) (xy 122.584749 -166.688467) (xy 122.627617 -166.724142) (xy 122.664834 -166.765679)
			(xy 122.695607 -166.812192) (xy 122.719279 -166.862689) (xy 122.735347 -166.916096) (xy 122.743467 -166.971272)
			(xy 122.743976 -166.999158) (xy 122.743467 -167.027044) (xy 122.736544 -167.074088) (xy 125.212092 -167.074088)
			(xy 125.216163 -167.018466) (xy 125.228289 -166.964029) (xy 125.248212 -166.911938) (xy 125.275508 -166.863303)
			(xy 125.309594 -166.81916) (xy 125.349743 -166.780451) (xy 125.395101 -166.748) (xy 125.444701 -166.722499)
			(xy 125.497485 -166.704492) (xy 125.552328 -166.694362) (xy 125.608062 -166.692325) (xy 125.663499 -166.698425)
			(xy 125.717456 -166.712531) (xy 125.768785 -166.734343) (xy 125.816391 -166.763397) (xy 125.859259 -166.799072)
			(xy 125.896476 -166.840609) (xy 125.927249 -166.887122) (xy 125.950921 -166.937619) (xy 125.966989 -166.991026)
			(xy 125.975109 -167.046202) (xy 125.975618 -167.074088) (xy 125.975109 -167.101974) (xy 125.972552 -167.119352)
			(xy 126.499077 -167.119352) (xy 126.499077 -167.064848) (xy 126.506834 -167.010899) (xy 126.52219 -166.958604)
			(xy 126.544832 -166.909025) (xy 126.574299 -166.863174) (xy 126.609992 -166.821984) (xy 126.651184 -166.786292)
			(xy 126.697036 -166.756826) (xy 126.746615 -166.734186) (xy 126.798911 -166.718832) (xy 126.85286 -166.711076)
			(xy 126.880112 -166.710614) (xy 126.906518 -166.711069) (xy 126.958824 -166.718361) (xy 127.009626 -166.732791)
			(xy 127.057955 -166.754084) (xy 127.102889 -166.781833) (xy 127.143571 -166.81551) (xy 127.179224 -166.85447)
			(xy 127.194564 -166.875968) (xy 127.203292 -166.887861) (xy 127.226243 -166.906378) (xy 127.25353 -166.917563)
			(xy 127.282875 -166.920481) (xy 127.31183 -166.91489) (xy 127.337978 -166.901256) (xy 127.359139 -166.880717)
			(xy 127.366776 -166.868094) (xy 127.381373 -166.843114) (xy 127.416906 -166.79746) (xy 127.458926 -166.757694)
			(xy 127.506467 -166.724728) (xy 127.55844 -166.699317) (xy 127.613655 -166.682044) (xy 127.670844 -166.673305)
			(xy 127.69977 -166.672768) (xy 127.727023 -166.673277) (xy 127.780973 -166.68103) (xy 127.833271 -166.696383)
			(xy 127.882852 -166.719022) (xy 127.928706 -166.748487) (xy 127.9699 -166.784179) (xy 128.005595 -166.82537)
			(xy 128.035064 -166.871221) (xy 128.057707 -166.9208) (xy 128.073063 -166.973097) (xy 128.080821 -167.027047)
			(xy 128.080821 -167.081553) (xy 128.073063 -167.135503) (xy 128.057707 -167.1878) (xy 128.035064 -167.237379)
			(xy 128.005595 -167.28323) (xy 127.9699 -167.324421) (xy 127.928706 -167.360113) (xy 127.882852 -167.389578)
			(xy 127.833271 -167.412217) (xy 127.780973 -167.42757) (xy 127.727023 -167.435323) (xy 127.69977 -167.435784)
			(xy 127.673364 -167.435344) (xy 127.621057 -167.428049) (xy 127.570255 -167.413616) (xy 127.521926 -167.392321)
			(xy 127.476992 -167.364569) (xy 127.43631 -167.330891) (xy 127.400658 -167.291929) (xy 127.385318 -167.27043)
			(xy 127.376612 -167.25852) (xy 127.353656 -167.240002) (xy 127.326364 -167.228819) (xy 127.297015 -167.225902)
			(xy 127.268057 -167.231497) (xy 127.241905 -167.245135) (xy 127.220743 -167.265679) (xy 127.213106 -167.278304)
			(xy 127.198521 -167.303291) (xy 127.162986 -167.348945) (xy 127.120965 -167.388711) (xy 127.073421 -167.421677)
			(xy 127.021446 -167.447086) (xy 126.96623 -167.464357) (xy 126.909039 -167.473094) (xy 126.880112 -167.47363)
			(xy 126.85286 -167.473124) (xy 126.798911 -167.465368) (xy 126.746615 -167.450014) (xy 126.697036 -167.427374)
			(xy 126.651184 -167.397908) (xy 126.609992 -167.362216) (xy 126.574299 -167.321026) (xy 126.544832 -167.275175)
			(xy 126.52219 -167.225596) (xy 126.506834 -167.173301) (xy 126.499077 -167.119352) (xy 125.972552 -167.119352)
			(xy 125.966989 -167.15715) (xy 125.950921 -167.210557) (xy 125.927249 -167.261054) (xy 125.896476 -167.307567)
			(xy 125.859259 -167.349104) (xy 125.816391 -167.384779) (xy 125.768785 -167.413833) (xy 125.717456 -167.435645)
			(xy 125.663499 -167.449751) (xy 125.608062 -167.455851) (xy 125.552328 -167.453814) (xy 125.497485 -167.443684)
			(xy 125.444701 -167.425677) (xy 125.395101 -167.400176) (xy 125.349743 -167.367725) (xy 125.309594 -167.329016)
			(xy 125.275508 -167.284873) (xy 125.248212 -167.236238) (xy 125.228289 -167.184147) (xy 125.216163 -167.12971)
			(xy 125.212092 -167.074088) (xy 122.736544 -167.074088) (xy 122.735347 -167.08222) (xy 122.719279 -167.135627)
			(xy 122.695607 -167.186124) (xy 122.664834 -167.232637) (xy 122.627617 -167.274174) (xy 122.584749 -167.309849)
			(xy 122.537143 -167.338903) (xy 122.485814 -167.360715) (xy 122.431857 -167.374821) (xy 122.37642 -167.380921)
			(xy 122.320686 -167.378884) (xy 122.265843 -167.368754) (xy 122.213059 -167.350747) (xy 122.163459 -167.325246)
			(xy 122.118101 -167.292795) (xy 122.077952 -167.254086) (xy 122.043866 -167.209943) (xy 122.01657 -167.161308)
			(xy 121.996647 -167.109217) (xy 121.984521 -167.05478) (xy 121.98045 -166.999158) (xy 103.129462 -166.999158)
			(xy 103.114015 -167.043325) (xy 103.08526 -167.103075) (xy 103.049999 -167.159231) (xy 103.008677 -167.21109)
			(xy 102.98557 -167.23487) (xy 101.907594 -168.312846) (xy 122.314968 -168.312846) (xy 122.319039 -168.257224)
			(xy 122.331165 -168.202787) (xy 122.351088 -168.150696) (xy 122.378384 -168.102061) (xy 122.41247 -168.057918)
			(xy 122.452619 -168.019209) (xy 122.497977 -167.986758) (xy 122.547577 -167.961257) (xy 122.600361 -167.94325)
			(xy 122.655204 -167.93312) (xy 122.710938 -167.931083) (xy 122.766375 -167.937183) (xy 122.820332 -167.951289)
			(xy 122.871661 -167.973101) (xy 122.919267 -168.002155) (xy 122.962135 -168.03783) (xy 122.999352 -168.079367)
			(xy 123.030125 -168.12588) (xy 123.053797 -168.176377) (xy 123.069865 -168.229784) (xy 123.077985 -168.28496)
			(xy 123.078494 -168.312846) (xy 123.077985 -168.340732) (xy 123.073678 -168.369996) (xy 131.39623 -168.369996)
			(xy 131.400301 -168.314374) (xy 131.412427 -168.259937) (xy 131.43235 -168.207846) (xy 131.459646 -168.159211)
			(xy 131.493732 -168.115068) (xy 131.533881 -168.076359) (xy 131.579239 -168.043908) (xy 131.628839 -168.018407)
			(xy 131.681623 -168.0004) (xy 131.736466 -167.99027) (xy 131.7922 -167.988233) (xy 131.847637 -167.994333)
			(xy 131.901594 -168.008439) (xy 131.952923 -168.030251) (xy 132.000529 -168.059305) (xy 132.007569 -168.065164)
			(xy 135.245906 -168.065164) (xy 135.245906 -168.005236) (xy 135.253728 -167.94582) (xy 135.269237 -167.887933)
			(xy 135.29217 -167.832566) (xy 135.322132 -167.780665) (xy 135.358612 -167.733119) (xy 135.400986 -167.690742)
			(xy 135.448529 -167.654257) (xy 135.500426 -167.624289) (xy 135.555791 -167.601351) (xy 135.613677 -167.585836)
			(xy 135.673092 -167.578009) (xy 135.703056 -167.577516) (xy 136.566656 -167.577516) (xy 136.596628 -167.577934)
			(xy 136.656061 -167.585754) (xy 136.713965 -167.601264) (xy 136.769348 -167.6242) (xy 136.821264 -167.654169)
			(xy 136.868823 -167.690658) (xy 136.911213 -167.733044) (xy 136.947707 -167.7806) (xy 136.977681 -167.832512)
			(xy 137.000622 -167.887894) (xy 137.016138 -167.945796) (xy 137.023963 -168.005228) (xy 137.023963 -168.065172)
			(xy 137.016138 -168.124604) (xy 137.000622 -168.182506) (xy 136.977681 -168.237888) (xy 136.947707 -168.2898)
			(xy 136.911213 -168.337356) (xy 136.868823 -168.379742) (xy 136.821264 -168.416231) (xy 136.769348 -168.4462)
			(xy 136.713965 -168.469136) (xy 136.656061 -168.484646) (xy 136.596628 -168.492466) (xy 136.566656 -168.492932)
			(xy 135.703056 -168.492932) (xy 135.673092 -168.492391) (xy 135.613677 -168.484564) (xy 135.555791 -168.469049)
			(xy 135.500426 -168.446111) (xy 135.448529 -168.416143) (xy 135.400986 -168.379658) (xy 135.358612 -168.337281)
			(xy 135.322132 -168.289735) (xy 135.29217 -168.237834) (xy 135.269237 -168.182467) (xy 135.253728 -168.12458)
			(xy 135.245906 -168.065164) (xy 132.007569 -168.065164) (xy 132.043397 -168.09498) (xy 132.080614 -168.136517)
			(xy 132.111387 -168.18303) (xy 132.135059 -168.233527) (xy 132.151127 -168.286934) (xy 132.159247 -168.34211)
			(xy 132.159756 -168.369996) (xy 132.159247 -168.397882) (xy 132.151127 -168.453058) (xy 132.135059 -168.506465)
			(xy 132.111387 -168.556962) (xy 132.080614 -168.603475) (xy 132.043397 -168.645012) (xy 132.000529 -168.680687)
			(xy 131.968615 -168.700164) (xy 133.213906 -168.700164) (xy 133.213906 -168.640236) (xy 133.221728 -168.58082)
			(xy 133.237237 -168.522933) (xy 133.26017 -168.467566) (xy 133.290132 -168.415665) (xy 133.326612 -168.368119)
			(xy 133.368986 -168.325742) (xy 133.416529 -168.289257) (xy 133.468426 -168.259289) (xy 133.523791 -168.236351)
			(xy 133.581677 -168.220836) (xy 133.641092 -168.213009) (xy 133.671056 -168.212516) (xy 134.534656 -168.212516)
			(xy 134.564628 -168.212934) (xy 134.624061 -168.220754) (xy 134.681965 -168.236264) (xy 134.737348 -168.2592)
			(xy 134.789264 -168.289169) (xy 134.836823 -168.325658) (xy 134.879213 -168.368044) (xy 134.915707 -168.4156)
			(xy 134.945681 -168.467512) (xy 134.968622 -168.522894) (xy 134.984138 -168.580796) (xy 134.991963 -168.640228)
			(xy 134.991963 -168.700172) (xy 134.984138 -168.759604) (xy 134.968622 -168.817506) (xy 134.945681 -168.872888)
			(xy 134.915707 -168.9248) (xy 134.879213 -168.972356) (xy 134.836823 -169.014742) (xy 134.789264 -169.051231)
			(xy 134.737348 -169.0812) (xy 134.681965 -169.104136) (xy 134.624061 -169.119646) (xy 134.564628 -169.127466)
			(xy 134.534656 -169.127932) (xy 133.671056 -169.127932) (xy 133.641092 -169.127391) (xy 133.581677 -169.119564)
			(xy 133.523791 -169.104049) (xy 133.468426 -169.081111) (xy 133.416529 -169.051143) (xy 133.368986 -169.014658)
			(xy 133.326612 -168.972281) (xy 133.290132 -168.924735) (xy 133.26017 -168.872834) (xy 133.237237 -168.817467)
			(xy 133.221728 -168.75958) (xy 133.213906 -168.700164) (xy 131.968615 -168.700164) (xy 131.952923 -168.709741)
			(xy 131.901594 -168.731553) (xy 131.847637 -168.745659) (xy 131.7922 -168.751759) (xy 131.736466 -168.749722)
			(xy 131.681623 -168.739592) (xy 131.628839 -168.721585) (xy 131.579239 -168.696084) (xy 131.533881 -168.663633)
			(xy 131.493732 -168.624924) (xy 131.459646 -168.580781) (xy 131.43235 -168.532146) (xy 131.412427 -168.480055)
			(xy 131.400301 -168.425618) (xy 131.39623 -168.369996) (xy 123.073678 -168.369996) (xy 123.069865 -168.395908)
			(xy 123.053797 -168.449315) (xy 123.030125 -168.499812) (xy 122.999352 -168.546325) (xy 122.962135 -168.587862)
			(xy 122.919267 -168.623537) (xy 122.871661 -168.652591) (xy 122.820332 -168.674403) (xy 122.766375 -168.688509)
			(xy 122.710938 -168.694609) (xy 122.655204 -168.692572) (xy 122.600361 -168.682442) (xy 122.547577 -168.664435)
			(xy 122.497977 -168.638934) (xy 122.452619 -168.606483) (xy 122.41247 -168.567774) (xy 122.378384 -168.523631)
			(xy 122.351088 -168.474996) (xy 122.331165 -168.422905) (xy 122.319039 -168.368468) (xy 122.314968 -168.312846)
			(xy 101.907594 -168.312846) (xy 100.745544 -169.474896) (xy 123.764292 -169.474896) (xy 123.768363 -169.419274)
			(xy 123.780489 -169.364837) (xy 123.800412 -169.312746) (xy 123.827708 -169.264111) (xy 123.861794 -169.219968)
			(xy 123.901943 -169.181259) (xy 123.947301 -169.148808) (xy 123.996901 -169.123307) (xy 124.049685 -169.1053)
			(xy 124.104528 -169.09517) (xy 124.160262 -169.093133) (xy 124.215699 -169.099233) (xy 124.269656 -169.113339)
			(xy 124.320985 -169.135151) (xy 124.358267 -169.157904) (xy 125.619762 -169.157904) (xy 125.623833 -169.102282)
			(xy 125.635959 -169.047845) (xy 125.655882 -168.995754) (xy 125.683178 -168.947119) (xy 125.717264 -168.902976)
			(xy 125.757413 -168.864267) (xy 125.802771 -168.831816) (xy 125.852371 -168.806315) (xy 125.905155 -168.788308)
			(xy 125.959998 -168.778178) (xy 126.015732 -168.776141) (xy 126.071169 -168.782241) (xy 126.125126 -168.796347)
			(xy 126.176455 -168.818159) (xy 126.224061 -168.847213) (xy 126.266929 -168.882888) (xy 126.304146 -168.924425)
			(xy 126.334919 -168.970938) (xy 126.358591 -169.021435) (xy 126.374659 -169.074842) (xy 126.382779 -169.130018)
			(xy 126.383288 -169.157904) (xy 126.382779 -169.18579) (xy 126.374659 -169.240966) (xy 126.358591 -169.294373)
			(xy 126.351004 -169.310558) (xy 132.172454 -169.310558) (xy 132.176525 -169.254936) (xy 132.188651 -169.200499)
			(xy 132.208574 -169.148408) (xy 132.23587 -169.099773) (xy 132.269956 -169.05563) (xy 132.310105 -169.016921)
			(xy 132.355463 -168.98447) (xy 132.405063 -168.958969) (xy 132.457847 -168.940962) (xy 132.51269 -168.930832)
			(xy 132.568424 -168.928795) (xy 132.623861 -168.934895) (xy 132.677818 -168.949001) (xy 132.729147 -168.970813)
			(xy 132.776753 -168.999867) (xy 132.819621 -169.035542) (xy 132.856838 -169.077079) (xy 132.887611 -169.123592)
			(xy 132.911283 -169.174089) (xy 132.927351 -169.227496) (xy 132.935471 -169.282672) (xy 132.93598 -169.310558)
			(xy 132.935471 -169.338444) (xy 132.927351 -169.39362) (xy 132.911283 -169.447027) (xy 132.887611 -169.497524)
			(xy 132.856838 -169.544037) (xy 132.819621 -169.585574) (xy 132.776753 -169.621249) (xy 132.729147 -169.650303)
			(xy 132.677818 -169.672115) (xy 132.623861 -169.686221) (xy 132.568424 -169.692321) (xy 132.51269 -169.690284)
			(xy 132.457847 -169.680154) (xy 132.405063 -169.662147) (xy 132.355463 -169.636646) (xy 132.310105 -169.604195)
			(xy 132.269956 -169.565486) (xy 132.23587 -169.521343) (xy 132.208574 -169.472708) (xy 132.188651 -169.420617)
			(xy 132.176525 -169.36618) (xy 132.172454 -169.310558) (xy 126.351004 -169.310558) (xy 126.334919 -169.34487)
			(xy 126.304146 -169.391383) (xy 126.266929 -169.43292) (xy 126.224061 -169.468595) (xy 126.176455 -169.497649)
			(xy 126.125126 -169.519461) (xy 126.071169 -169.533567) (xy 126.015732 -169.539667) (xy 125.959998 -169.53763)
			(xy 125.905155 -169.5275) (xy 125.852371 -169.509493) (xy 125.802771 -169.483992) (xy 125.757413 -169.451541)
			(xy 125.717264 -169.412832) (xy 125.683178 -169.368689) (xy 125.655882 -169.320054) (xy 125.635959 -169.267963)
			(xy 125.623833 -169.213526) (xy 125.619762 -169.157904) (xy 124.358267 -169.157904) (xy 124.368591 -169.164205)
			(xy 124.411459 -169.19988) (xy 124.448676 -169.241417) (xy 124.479449 -169.28793) (xy 124.503121 -169.338427)
			(xy 124.519189 -169.391834) (xy 124.527309 -169.44701) (xy 124.527818 -169.474896) (xy 124.527309 -169.502782)
			(xy 124.519189 -169.557958) (xy 124.503121 -169.611365) (xy 124.479449 -169.661862) (xy 124.448676 -169.708375)
			(xy 124.411459 -169.749912) (xy 124.368591 -169.785587) (xy 124.320985 -169.814641) (xy 124.269656 -169.836453)
			(xy 124.215699 -169.850559) (xy 124.160262 -169.856659) (xy 124.104528 -169.854622) (xy 124.049685 -169.844492)
			(xy 123.996901 -169.826485) (xy 123.947301 -169.800984) (xy 123.901943 -169.768533) (xy 123.861794 -169.729824)
			(xy 123.827708 -169.685681) (xy 123.800412 -169.637046) (xy 123.780489 -169.584955) (xy 123.768363 -169.530518)
			(xy 123.764292 -169.474896) (xy 100.745544 -169.474896) (xy 97.131378 -173.089062) (xy 126.182628 -173.089062)
			(xy 126.183124 -173.061693) (xy 126.190933 -173.007515) (xy 126.206415 -172.955012) (xy 126.22925 -172.905264)
			(xy 126.258969 -172.859296) (xy 126.276608 -172.838364) (xy 126.276862 -172.83811) (xy 126.282458 -172.83103)
			(xy 126.288697 -172.814108) (xy 126.289054 -172.80509) (xy 126.289054 -172.738034) (xy 126.288691 -172.729018)
			(xy 126.282449 -172.7121) (xy 126.276862 -172.705014) (xy 126.276608 -172.705014) (xy 126.276608 -172.70476)
			(xy 126.258985 -172.683815) (xy 126.22927 -172.637846) (xy 126.206431 -172.588102) (xy 126.190936 -172.535604)
			(xy 126.183104 -172.48143) (xy 126.182628 -172.454062) (xy 126.183114 -172.426811) (xy 126.19087 -172.372863)
			(xy 126.206225 -172.320568) (xy 126.228867 -172.270991) (xy 126.258333 -172.225141) (xy 126.294024 -172.18395)
			(xy 126.335215 -172.148259) (xy 126.381065 -172.118793) (xy 126.430642 -172.096151) (xy 126.482937 -172.080796)
			(xy 126.536885 -172.07304) (xy 126.591387 -172.07304) (xy 126.645335 -172.080796) (xy 126.69763 -172.096151)
			(xy 126.747207 -172.118793) (xy 126.793057 -172.148259) (xy 126.834248 -172.18395) (xy 126.869939 -172.225141)
			(xy 126.877491 -172.236892) (xy 127.879346 -172.236892) (xy 127.883417 -172.18127) (xy 127.895543 -172.126833)
			(xy 127.915466 -172.074742) (xy 127.942762 -172.026107) (xy 127.976848 -171.981964) (xy 128.016997 -171.943255)
			(xy 128.062355 -171.910804) (xy 128.111955 -171.885303) (xy 128.164739 -171.867296) (xy 128.219582 -171.857166)
			(xy 128.275316 -171.855129) (xy 128.330753 -171.861229) (xy 128.38471 -171.875335) (xy 128.436039 -171.897147)
			(xy 128.483645 -171.926201) (xy 128.526513 -171.961876) (xy 128.56373 -172.003413) (xy 128.594503 -172.049926)
			(xy 128.618175 -172.100423) (xy 128.62217 -172.113702) (xy 132.256782 -172.113702) (xy 132.260853 -172.05808)
			(xy 132.272979 -172.003643) (xy 132.292902 -171.951552) (xy 132.320198 -171.902917) (xy 132.354284 -171.858774)
			(xy 132.394433 -171.820065) (xy 132.439791 -171.787614) (xy 132.489391 -171.762113) (xy 132.542175 -171.744106)
			(xy 132.597018 -171.733976) (xy 132.652752 -171.731939) (xy 132.708189 -171.738039) (xy 132.762146 -171.752145)
			(xy 132.813475 -171.773957) (xy 132.861081 -171.803011) (xy 132.903949 -171.838686) (xy 132.941166 -171.880223)
			(xy 132.971939 -171.926736) (xy 132.995611 -171.977233) (xy 133.011679 -172.03064) (xy 133.019799 -172.085816)
			(xy 133.020308 -172.113702) (xy 133.019799 -172.141588) (xy 133.011679 -172.196764) (xy 132.995611 -172.250171)
			(xy 132.977903 -172.287946) (xy 138.61415 -172.287946) (xy 138.614589 -172.261333) (xy 138.621988 -172.208624)
			(xy 138.636648 -172.157457) (xy 138.658284 -172.108828) (xy 138.686476 -172.063681) (xy 138.720674 -172.022896)
			(xy 138.740134 -172.004736) (xy 138.748008 -171.997624) (xy 138.756644 -171.978574) (xy 138.758168 -171.88307)
			(xy 138.750294 -171.863766) (xy 138.742674 -171.8564) (xy 138.724675 -171.838349) (xy 138.693109 -171.798322)
			(xy 138.667154 -171.754449) (xy 138.647271 -171.707511) (xy 138.633814 -171.658343) (xy 138.627022 -171.607822)
			(xy 138.626596 -171.582334) (xy 138.627082 -171.555083) (xy 138.634838 -171.501135) (xy 138.650193 -171.44884)
			(xy 138.672835 -171.399263) (xy 138.702301 -171.353413) (xy 138.737992 -171.312222) (xy 138.779183 -171.276531)
			(xy 138.825033 -171.247065) (xy 138.87461 -171.224423) (xy 138.926905 -171.209068) (xy 138.980853 -171.201312)
			(xy 139.035355 -171.201312) (xy 139.089303 -171.209068) (xy 139.141598 -171.224423) (xy 139.191175 -171.247065)
			(xy 139.237025 -171.276531) (xy 139.278216 -171.312222) (xy 139.313907 -171.353413) (xy 139.343373 -171.399263)
			(xy 139.366015 -171.44884) (xy 139.38137 -171.501135) (xy 139.389126 -171.555083) (xy 139.389612 -171.582334)
			(xy 139.389172 -171.608947) (xy 139.381775 -171.661656) (xy 139.367116 -171.712824) (xy 139.34548 -171.761454)
			(xy 139.317288 -171.8066) (xy 139.283089 -171.847385) (xy 139.263628 -171.865544) (xy 139.255754 -171.872656)
			(xy 139.247118 -171.891706) (xy 139.245594 -171.98721) (xy 139.253468 -172.006514) (xy 139.261088 -172.01388)
			(xy 139.279089 -172.031929) (xy 139.310652 -172.071958) (xy 139.336606 -172.115832) (xy 139.356488 -172.16277)
			(xy 139.369946 -172.211937) (xy 139.376738 -172.262458) (xy 139.377166 -172.287946) (xy 139.37668 -172.315197)
			(xy 139.368924 -172.369145) (xy 139.353569 -172.42144) (xy 139.330927 -172.471017) (xy 139.301461 -172.516867)
			(xy 139.26577 -172.558058) (xy 139.224579 -172.593749) (xy 139.178729 -172.623215) (xy 139.129152 -172.645857)
			(xy 139.076857 -172.661212) (xy 139.022909 -172.668968) (xy 138.968407 -172.668968) (xy 138.914459 -172.661212)
			(xy 138.862164 -172.645857) (xy 138.812587 -172.623215) (xy 138.766737 -172.593749) (xy 138.725546 -172.558058)
			(xy 138.689855 -172.516867) (xy 138.660389 -172.471017) (xy 138.637747 -172.42144) (xy 138.622392 -172.369145)
			(xy 138.614636 -172.315197) (xy 138.61415 -172.287946) (xy 132.977903 -172.287946) (xy 132.971939 -172.300668)
			(xy 132.941166 -172.347181) (xy 132.903949 -172.388718) (xy 132.861081 -172.424393) (xy 132.813475 -172.453447)
			(xy 132.762146 -172.475259) (xy 132.708189 -172.489365) (xy 132.652752 -172.495465) (xy 132.597018 -172.493428)
			(xy 132.542175 -172.483298) (xy 132.489391 -172.465291) (xy 132.439791 -172.43979) (xy 132.394433 -172.407339)
			(xy 132.354284 -172.36863) (xy 132.320198 -172.324487) (xy 132.292902 -172.275852) (xy 132.272979 -172.223761)
			(xy 132.260853 -172.169324) (xy 132.256782 -172.113702) (xy 128.62217 -172.113702) (xy 128.634243 -172.15383)
			(xy 128.642363 -172.209006) (xy 128.642872 -172.236892) (xy 128.642363 -172.264778) (xy 128.634243 -172.319954)
			(xy 128.618175 -172.373361) (xy 128.594503 -172.423858) (xy 128.56373 -172.470371) (xy 128.526513 -172.511908)
			(xy 128.483645 -172.547583) (xy 128.436039 -172.576637) (xy 128.38471 -172.598449) (xy 128.330753 -172.612555)
			(xy 128.275316 -172.618655) (xy 128.219582 -172.616618) (xy 128.164739 -172.606488) (xy 128.111955 -172.588481)
			(xy 128.062355 -172.56298) (xy 128.016997 -172.530529) (xy 127.976848 -172.49182) (xy 127.942762 -172.447677)
			(xy 127.915466 -172.399042) (xy 127.895543 -172.346951) (xy 127.883417 -172.292514) (xy 127.879346 -172.236892)
			(xy 126.877491 -172.236892) (xy 126.899405 -172.270991) (xy 126.922047 -172.320568) (xy 126.937402 -172.372863)
			(xy 126.945158 -172.426811) (xy 126.945644 -172.454062) (xy 126.945169 -172.481432) (xy 126.937356 -172.535611)
			(xy 126.921869 -172.588115) (xy 126.899029 -172.637862) (xy 126.869305 -172.683829) (xy 126.851664 -172.70476)
			(xy 126.85141 -172.705014) (xy 126.845813 -172.712093) (xy 126.839572 -172.729016) (xy 126.839218 -172.738034)
			(xy 126.839218 -172.80509) (xy 126.839576 -172.814107) (xy 126.845822 -172.831024) (xy 126.85141 -172.83811)
			(xy 126.851664 -172.83811) (xy 126.851664 -172.838364) (xy 126.869294 -172.859303) (xy 126.899009 -172.905274)
			(xy 126.921847 -172.955019) (xy 126.93734 -173.007518) (xy 126.945169 -173.061693) (xy 126.945644 -173.089062)
			(xy 126.945158 -173.116313) (xy 126.937402 -173.170261) (xy 126.922047 -173.222556) (xy 126.899405 -173.272133)
			(xy 126.869939 -173.317983) (xy 126.834248 -173.359174) (xy 126.793057 -173.394865) (xy 126.747207 -173.424331)
			(xy 126.69763 -173.446973) (xy 126.645335 -173.462328) (xy 126.591387 -173.470084) (xy 126.536885 -173.470084)
			(xy 126.482937 -173.462328) (xy 126.430642 -173.446973) (xy 126.381065 -173.424331) (xy 126.335215 -173.394865)
			(xy 126.294024 -173.359174) (xy 126.258333 -173.317983) (xy 126.228867 -173.272133) (xy 126.206225 -173.222556)
			(xy 126.19087 -173.170261) (xy 126.183114 -173.116313) (xy 126.182628 -173.089062) (xy 97.131378 -173.089062)
			(xy 96.675956 -173.544484) (xy 129.265932 -173.544484) (xy 129.270003 -173.488862) (xy 129.282129 -173.434425)
			(xy 129.302052 -173.382334) (xy 129.329348 -173.333699) (xy 129.363434 -173.289556) (xy 129.403583 -173.250847)
			(xy 129.448941 -173.218396) (xy 129.498541 -173.192895) (xy 129.551325 -173.174888) (xy 129.606168 -173.164758)
			(xy 129.661902 -173.162721) (xy 129.717339 -173.168821) (xy 129.771296 -173.182927) (xy 129.822625 -173.204739)
			(xy 129.870231 -173.233793) (xy 129.913099 -173.269468) (xy 129.950316 -173.311005) (xy 129.981089 -173.357518)
			(xy 130.004761 -173.408015) (xy 130.020829 -173.461422) (xy 130.028949 -173.516598) (xy 130.029458 -173.544484)
			(xy 130.028949 -173.57237) (xy 130.020829 -173.627546) (xy 130.004761 -173.680953) (xy 129.981089 -173.73145)
			(xy 129.950316 -173.777963) (xy 129.913099 -173.8195) (xy 129.870231 -173.855175) (xy 129.822625 -173.884229)
			(xy 129.771296 -173.906041) (xy 129.717339 -173.920147) (xy 129.661902 -173.926247) (xy 129.606168 -173.92421)
			(xy 129.551325 -173.91408) (xy 129.498541 -173.896073) (xy 129.448941 -173.870572) (xy 129.403583 -173.838121)
			(xy 129.363434 -173.799412) (xy 129.329348 -173.755269) (xy 129.302052 -173.706634) (xy 129.282129 -173.654543)
			(xy 129.270003 -173.600106) (xy 129.265932 -173.544484) (xy 96.675956 -173.544484) (xy 95.895414 -174.325026)
			(xy 132.089142 -174.325026) (xy 132.093213 -174.269404) (xy 132.105339 -174.214967) (xy 132.125262 -174.162876)
			(xy 132.152558 -174.114241) (xy 132.186644 -174.070098) (xy 132.226793 -174.031389) (xy 132.272151 -173.998938)
			(xy 132.321751 -173.973437) (xy 132.374535 -173.95543) (xy 132.429378 -173.9453) (xy 132.485112 -173.943263)
			(xy 132.540549 -173.949363) (xy 132.594506 -173.963469) (xy 132.645835 -173.985281) (xy 132.693441 -174.014335)
			(xy 132.736309 -174.05001) (xy 132.773526 -174.091547) (xy 132.804299 -174.13806) (xy 132.827971 -174.188557)
			(xy 132.844039 -174.241964) (xy 132.852159 -174.29714) (xy 132.852668 -174.325026) (xy 132.852159 -174.352912)
			(xy 132.844039 -174.408088) (xy 132.827971 -174.461495) (xy 132.804299 -174.511992) (xy 132.773526 -174.558505)
			(xy 132.736309 -174.600042) (xy 132.693441 -174.635717) (xy 132.670941 -174.649449) (xy 135.696484 -174.649449)
			(xy 135.696484 -174.594951) (xy 135.704239 -174.541009) (xy 135.719591 -174.488719) (xy 135.742229 -174.439145)
			(xy 135.77169 -174.393298) (xy 135.807376 -174.35211) (xy 135.848559 -174.316419) (xy 135.894403 -174.286952)
			(xy 135.943974 -174.264308) (xy 135.996262 -174.248949) (xy 136.050203 -174.241187) (xy 136.077452 -174.240698)
			(xy 136.077706 -174.240698) (xy 136.104205 -174.241155) (xy 136.15669 -174.248524) (xy 136.207652 -174.263076)
			(xy 136.256114 -174.284534) (xy 136.301143 -174.312484) (xy 136.3218 -174.32909) (xy 136.329166 -174.335186)
			(xy 136.3472 -174.341282) (xy 136.425686 -174.337218) (xy 136.435172 -174.336332) (xy 136.452526 -174.328503)
			(xy 136.459468 -174.321978) (xy 136.477489 -174.304161) (xy 136.517399 -174.272933) (xy 136.561092 -174.247263)
			(xy 136.607799 -174.227604) (xy 136.656697 -174.2143) (xy 136.706926 -174.207587) (xy 136.732264 -174.20717)
			(xy 136.759517 -174.207675) (xy 136.813469 -174.215427) (xy 136.865768 -174.230779) (xy 136.91535 -174.253418)
			(xy 136.961205 -174.282884) (xy 137.002399 -174.318575) (xy 137.038095 -174.359767) (xy 137.067564 -174.405619)
			(xy 137.090208 -174.455198) (xy 137.105565 -174.507496) (xy 137.113323 -174.561447) (xy 137.113323 -174.615953)
			(xy 137.105565 -174.669904) (xy 137.090208 -174.722202) (xy 137.067564 -174.771781) (xy 137.038095 -174.817633)
			(xy 137.002399 -174.858825) (xy 136.961205 -174.894516) (xy 136.91535 -174.923982) (xy 136.865768 -174.946621)
			(xy 136.813469 -174.961973) (xy 136.759517 -174.969725) (xy 136.732264 -174.970186) (xy 136.73201 -174.970186)
			(xy 136.705511 -174.969723) (xy 136.653026 -174.962357) (xy 136.602064 -174.947806) (xy 136.553603 -174.926349)
			(xy 136.508573 -174.898399) (xy 136.487916 -174.881794) (xy 136.48055 -174.875698) (xy 136.462516 -174.869602)
			(xy 136.38403 -174.873666) (xy 136.374546 -174.874564) (xy 136.357191 -174.882385) (xy 136.350248 -174.888906)
			(xy 136.332263 -174.906761) (xy 136.292345 -174.937986) (xy 136.248645 -174.963651) (xy 136.201931 -174.983304)
			(xy 136.153026 -174.996599) (xy 136.102792 -175.003303) (xy 136.077452 -175.003714) (xy 136.050203 -175.003213)
			(xy 135.996262 -174.995451) (xy 135.943974 -174.980092) (xy 135.894403 -174.957448) (xy 135.848559 -174.927981)
			(xy 135.807376 -174.89229) (xy 135.77169 -174.851102) (xy 135.742229 -174.805255) (xy 135.719591 -174.755681)
			(xy 135.704239 -174.703391) (xy 135.696484 -174.649449) (xy 132.670941 -174.649449) (xy 132.645835 -174.664771)
			(xy 132.594506 -174.686583) (xy 132.540549 -174.700689) (xy 132.485112 -174.706789) (xy 132.429378 -174.704752)
			(xy 132.374535 -174.694622) (xy 132.321751 -174.676615) (xy 132.272151 -174.651114) (xy 132.226793 -174.618663)
			(xy 132.186644 -174.579954) (xy 132.152558 -174.535811) (xy 132.125262 -174.487176) (xy 132.105339 -174.435085)
			(xy 132.093213 -174.380648) (xy 132.089142 -174.325026) (xy 95.895414 -174.325026) (xy 95.42653 -174.79391)
			(xy 95.419682 -174.801308) (xy 95.411946 -174.819906) (xy 95.411544 -174.829978) (xy 95.411544 -176.722278)
			(xy 130.560318 -176.722278) (xy 130.560719 -176.696161) (xy 130.568017 -176.64444) (xy 130.582466 -176.594244)
			(xy 130.603785 -176.546558) (xy 130.631554 -176.502317) (xy 130.665229 -176.462388) (xy 130.704151 -176.427553)
			(xy 130.747556 -176.398495) (xy 130.770884 -176.386744) (xy 130.783584 -176.380648) (xy 130.799078 -176.357026)
			(xy 130.803142 -176.25314) (xy 130.803054 -176.24395) (xy 130.797134 -176.226565) (xy 130.785492 -176.21236)
			(xy 130.777742 -176.20742) (xy 130.777488 -176.207166) (xy 130.754665 -176.193402) (xy 130.712988 -176.160184)
			(xy 130.67673 -176.121124) (xy 130.6467 -176.077096) (xy 130.623569 -176.029082) (xy 130.607855 -175.978156)
			(xy 130.599908 -175.925457) (xy 130.599434 -175.89881) (xy 130.599922 -175.870823) (xy 130.608677 -175.815538)
			(xy 130.625975 -175.762303) (xy 130.651387 -175.71243) (xy 130.684289 -175.667147) (xy 130.723871 -175.627569)
			(xy 130.769157 -175.59467) (xy 130.819032 -175.569262) (xy 130.872269 -175.55197) (xy 130.927555 -175.543219)
			(xy 130.955542 -175.542702) (xy 130.95605 -175.542702) (xy 130.984909 -175.543265) (xy 131.041862 -175.552626)
			(xy 131.096562 -175.571047) (xy 131.147576 -175.598046) (xy 131.19357 -175.632916) (xy 131.21386 -175.653446)
			(xy 131.22148 -175.661574) (xy 131.242054 -175.669956) (xy 131.329684 -175.665638) (xy 131.340595 -175.664593)
			(xy 131.360076 -175.654597) (xy 131.367276 -175.646334) (xy 131.36753 -175.64608) (xy 131.384499 -175.625173)
			(xy 131.423683 -175.588242) (xy 131.467983 -175.557635) (xy 131.516387 -175.534049) (xy 131.567792 -175.518021)
			(xy 131.621023 -175.509919) (xy 131.647946 -175.509428) (xy 131.6482 -175.509428) (xy 131.675496 -175.509931)
			(xy 131.729445 -175.518299) (xy 131.781487 -175.534795) (xy 131.830405 -175.559033) (xy 131.875057 -175.590445)
			(xy 131.895088 -175.608996) (xy 131.902454 -175.616108) (xy 131.920234 -175.62322) (xy 132.010658 -175.62322)
			(xy 132.028438 -175.616108) (xy 132.035804 -175.608996) (xy 132.055803 -175.590405) (xy 132.100448 -175.558971)
			(xy 132.149374 -175.534729) (xy 132.201429 -175.518249) (xy 132.255391 -175.509919) (xy 132.282692 -175.509428)
			(xy 132.282946 -175.509428) (xy 132.309596 -175.509857) (xy 132.362299 -175.517807) (xy 132.413229 -175.533523)
			(xy 132.461248 -175.556653) (xy 132.505284 -175.586681) (xy 132.544353 -175.622937) (xy 132.577583 -175.66461)
			(xy 132.60423 -175.71077) (xy 132.623701 -175.760386) (xy 132.635561 -175.812349) (xy 132.639544 -175.8655)
			(xy 132.63842 -175.8805) (xy 132.86459 -175.8805) (xy 132.868573 -175.827348) (xy 132.880434 -175.775383)
			(xy 132.899908 -175.725767) (xy 132.92656 -175.679607) (xy 132.959794 -175.637936) (xy 132.998867 -175.601683)
			(xy 133.042908 -175.571659) (xy 133.090931 -175.548535) (xy 133.141865 -175.532827) (xy 133.194571 -175.524886)
			(xy 133.221222 -175.524414) (xy 133.221476 -175.524414) (xy 133.248772 -175.524935) (xy 133.302719 -175.5333)
			(xy 133.354761 -175.549792) (xy 133.40368 -175.574025) (xy 133.448332 -175.605433) (xy 133.468364 -175.623982)
			(xy 133.47573 -175.631094) (xy 133.49351 -175.638206) (xy 133.583934 -175.638206) (xy 133.601714 -175.631094)
			(xy 133.60908 -175.623982) (xy 133.629106 -175.605384) (xy 133.673796 -175.573926) (xy 133.722772 -175.549674)
			(xy 133.77488 -175.533199) (xy 133.828896 -175.524889) (xy 133.856222 -175.524414) (xy 133.883543 -175.524918)
			(xy 133.937546 -175.533259) (xy 133.989643 -175.549744) (xy 134.038614 -175.573986) (xy 134.083312 -175.605417)
			(xy 134.103364 -175.623982) (xy 134.11073 -175.631094) (xy 134.12851 -175.638206) (xy 134.218934 -175.638206)
			(xy 134.236714 -175.631094) (xy 134.24408 -175.623982) (xy 134.264087 -175.6054) (xy 134.308731 -175.573965)
			(xy 134.357654 -175.549722) (xy 134.409707 -175.53324) (xy 134.463668 -175.524906) (xy 134.490968 -175.524414)
			(xy 134.491222 -175.524414) (xy 134.519207 -175.524921) (xy 134.574487 -175.53368) (xy 134.627716 -175.550979)
			(xy 134.677584 -175.576391) (xy 134.722862 -175.609292) (xy 134.762436 -175.648871) (xy 134.795332 -175.694154)
			(xy 134.820738 -175.744025) (xy 134.838031 -175.797256) (xy 134.846783 -175.852537) (xy 134.84733 -175.880522)
			(xy 134.84733 -175.880776) (xy 134.846797 -175.908071) (xy 134.838433 -175.962017) (xy 134.821943 -176.014058)
			(xy 134.797713 -176.062977) (xy 134.766309 -176.107631) (xy 134.747762 -176.127664) (xy 134.74065 -176.13503)
			(xy 134.733538 -176.15281) (xy 134.733538 -176.243234) (xy 134.74065 -176.261014) (xy 134.747762 -176.26838)
			(xy 134.766351 -176.288415) (xy 134.797812 -176.333101) (xy 134.822066 -176.382074) (xy 134.838543 -176.434182)
			(xy 134.846855 -176.488196) (xy 134.84733 -176.515522) (xy 134.846814 -176.542843) (xy 134.838474 -176.596844)
			(xy 134.821991 -176.64894) (xy 134.797752 -176.697912) (xy 134.766325 -176.742611) (xy 134.747762 -176.762664)
			(xy 134.74065 -176.77003) (xy 134.733538 -176.78781) (xy 134.733538 -176.878234) (xy 134.74065 -176.896014)
			(xy 134.747762 -176.90338) (xy 134.766351 -176.923415) (xy 134.797812 -176.968101) (xy 134.822066 -177.017074)
			(xy 134.838543 -177.069182) (xy 134.846855 -177.123196) (xy 134.84733 -177.150522) (xy 134.846814 -177.177843)
			(xy 134.838474 -177.231844) (xy 134.821991 -177.28394) (xy 134.797752 -177.332912) (xy 134.766325 -177.377611)
			(xy 134.747762 -177.397664) (xy 134.74065 -177.40503) (xy 134.733538 -177.42281) (xy 134.733538 -177.488088)
			(xy 137.565636 -177.488088) (xy 137.569707 -177.432466) (xy 137.581833 -177.378029) (xy 137.601756 -177.325938)
			(xy 137.629052 -177.277303) (xy 137.663138 -177.23316) (xy 137.703287 -177.194451) (xy 137.748645 -177.162)
			(xy 137.798245 -177.136499) (xy 137.851029 -177.118492) (xy 137.905872 -177.108362) (xy 137.961606 -177.106325)
			(xy 138.017043 -177.112425) (xy 138.071 -177.126531) (xy 138.122329 -177.148343) (xy 138.169935 -177.177397)
			(xy 138.212803 -177.213072) (xy 138.25002 -177.254609) (xy 138.280793 -177.301122) (xy 138.304465 -177.351619)
			(xy 138.320533 -177.405026) (xy 138.328653 -177.460202) (xy 138.329162 -177.488088) (xy 138.328653 -177.515974)
			(xy 138.320533 -177.57115) (xy 138.304465 -177.624557) (xy 138.280793 -177.675054) (xy 138.25002 -177.721567)
			(xy 138.212803 -177.763104) (xy 138.169935 -177.798779) (xy 138.122329 -177.827833) (xy 138.071 -177.849645)
			(xy 138.017043 -177.863751) (xy 137.961606 -177.869851) (xy 137.905872 -177.867814) (xy 137.851029 -177.857684)
			(xy 137.798245 -177.839677) (xy 137.748645 -177.814176) (xy 137.703287 -177.781725) (xy 137.663138 -177.743016)
			(xy 137.629052 -177.698873) (xy 137.601756 -177.650238) (xy 137.581833 -177.598147) (xy 137.569707 -177.54371)
			(xy 137.565636 -177.488088) (xy 134.733538 -177.488088) (xy 134.733538 -177.513234) (xy 134.74065 -177.531014)
			(xy 134.747762 -177.53838) (xy 134.766334 -177.558396) (xy 134.797773 -177.603036) (xy 134.822019 -177.651957)
			(xy 134.838503 -177.704008) (xy 134.846837 -177.757968) (xy 134.84733 -177.785268) (xy 134.84733 -177.785522)
			(xy 134.846919 -177.810307) (xy 134.840047 -177.859399) (xy 134.826427 -177.907061) (xy 134.806321 -177.95237)
			(xy 134.780119 -177.99445) (xy 134.74833 -178.032484) (xy 134.730236 -178.049428) (xy 134.722691 -178.057024)
			(xy 134.714035 -178.076582) (xy 134.713472 -178.087274) (xy 134.713726 -178.173634) (xy 134.722616 -178.193446)
			(xy 134.730744 -178.200558) (xy 134.749035 -178.217556) (xy 134.781227 -178.255724) (xy 134.807774 -178.298014)
			(xy 134.828153 -178.343598) (xy 134.841966 -178.391581) (xy 134.843218 -178.400456) (xy 135.78408 -178.400456)
			(xy 135.788151 -178.344834) (xy 135.800277 -178.290397) (xy 135.8202 -178.238306) (xy 135.847496 -178.189671)
			(xy 135.881582 -178.145528) (xy 135.921731 -178.106819) (xy 135.967089 -178.074368) (xy 136.016689 -178.048867)
			(xy 136.069473 -178.03086) (xy 136.124316 -178.02073) (xy 136.18005 -178.018693) (xy 136.235487 -178.024793)
			(xy 136.289444 -178.038899) (xy 136.340773 -178.060711) (xy 136.388379 -178.089765) (xy 136.431247 -178.12544)
			(xy 136.468464 -178.166977) (xy 136.499237 -178.21349) (xy 136.522909 -178.263987) (xy 136.538977 -178.317394)
			(xy 136.547097 -178.37257) (xy 136.547606 -178.400456) (xy 136.547097 -178.428342) (xy 136.538977 -178.483518)
			(xy 136.522909 -178.536925) (xy 136.499237 -178.587422) (xy 136.468464 -178.633935) (xy 136.431247 -178.675472)
			(xy 136.388379 -178.711147) (xy 136.340773 -178.740201) (xy 136.289444 -178.762013) (xy 136.235487 -178.776119)
			(xy 136.18005 -178.782219) (xy 136.124316 -178.780182) (xy 136.069473 -178.770052) (xy 136.016689 -178.752045)
			(xy 135.967089 -178.726544) (xy 135.921731 -178.694093) (xy 135.881582 -178.655384) (xy 135.847496 -178.611241)
			(xy 135.8202 -178.562606) (xy 135.800277 -178.510515) (xy 135.788151 -178.456078) (xy 135.78408 -178.400456)
			(xy 134.843218 -178.400456) (xy 134.848941 -178.441022) (xy 134.849362 -178.465988) (xy 134.848864 -178.492637)
			(xy 134.840921 -178.545341) (xy 134.825211 -178.596271) (xy 134.802085 -178.644292) (xy 134.772061 -178.688329)
			(xy 134.735809 -178.7274) (xy 134.694138 -178.760631) (xy 134.64798 -178.78728) (xy 134.598366 -178.806752)
			(xy 134.546404 -178.818612) (xy 134.493254 -178.822596) (xy 134.440104 -178.818612) (xy 134.388142 -178.806752)
			(xy 134.338528 -178.78728) (xy 134.29237 -178.760631) (xy 134.250699 -178.7274) (xy 134.214447 -178.688329)
			(xy 134.184423 -178.644292) (xy 134.161297 -178.596271) (xy 134.145587 -178.545341) (xy 134.137644 -178.492637)
			(xy 134.137146 -178.465988) (xy 134.137572 -178.441203) (xy 134.144441 -178.392113) (xy 134.15806 -178.344451)
			(xy 134.178163 -178.299142) (xy 134.204361 -178.257062) (xy 134.236148 -178.219027) (xy 134.25424 -178.202082)
			(xy 134.261777 -178.194479) (xy 134.270438 -178.174927) (xy 134.271004 -178.164236) (xy 134.27075 -178.077876)
			(xy 134.26186 -178.058064) (xy 134.253732 -178.050952) (xy 134.235393 -178.034004) (xy 134.203205 -177.995824)
			(xy 134.176666 -177.953524) (xy 134.156295 -177.907931) (xy 134.142493 -177.859939) (xy 134.135529 -177.81049)
			(xy 134.135114 -177.785522) (xy 134.135114 -177.785268) (xy 134.135662 -177.757973) (xy 134.14402 -177.704027)
			(xy 134.160506 -177.651986) (xy 134.184733 -177.603066) (xy 134.216135 -177.558413) (xy 134.234682 -177.53838)
			(xy 134.241794 -177.531014) (xy 134.248906 -177.513234) (xy 134.248906 -177.42281) (xy 134.241794 -177.40503)
			(xy 134.234682 -177.397664) (xy 134.216057 -177.377661) (xy 134.184603 -177.332965) (xy 134.160356 -177.283984)
			(xy 134.143888 -177.23187) (xy 134.135585 -177.17785) (xy 134.135114 -177.150522) (xy 134.135645 -177.123202)
			(xy 134.14398 -177.0692) (xy 134.160458 -177.017104) (xy 134.184694 -176.968132) (xy 134.216119 -176.923432)
			(xy 134.234682 -176.90338) (xy 134.241794 -176.896014) (xy 134.248906 -176.878234) (xy 134.248906 -176.78781)
			(xy 134.241794 -176.77003) (xy 134.234682 -176.762664) (xy 134.216074 -176.742681) (xy 134.184642 -176.698031)
			(xy 134.160404 -176.649102) (xy 134.143928 -176.597043) (xy 134.135602 -176.543078) (xy 134.135114 -176.515776)
			(xy 134.135114 -176.515522) (xy 134.135513 -176.490779) (xy 134.142358 -176.441768) (xy 134.155919 -176.394176)
			(xy 134.175936 -176.348919) (xy 134.202023 -176.306867) (xy 134.233678 -176.268829) (xy 134.2517 -176.25187)
			(xy 134.259327 -176.244408) (xy 134.268008 -176.224938) (xy 134.268464 -176.214278) (xy 134.268464 -176.181766)
			(xy 134.267871 -176.171138) (xy 134.259208 -176.15172) (xy 134.2517 -176.144174) (xy 134.24408 -176.137062)
			(xy 134.236714 -176.12995) (xy 134.218934 -176.122838) (xy 134.12851 -176.122838) (xy 134.11073 -176.12995)
			(xy 134.103364 -176.137062) (xy 134.083353 -176.155677) (xy 134.03866 -176.187135) (xy 133.989681 -176.211384)
			(xy 133.937568 -176.227855) (xy 133.883549 -176.236159) (xy 133.856222 -176.23663) (xy 133.828902 -176.236087)
			(xy 133.774902 -176.227753) (xy 133.722806 -176.211277) (xy 133.673834 -176.187044) (xy 133.629133 -176.155623)
			(xy 133.60908 -176.137062) (xy 133.601714 -176.12995) (xy 133.583934 -176.122838) (xy 133.49351 -176.122838)
			(xy 133.47573 -176.12995) (xy 133.468364 -176.137062) (xy 133.448372 -176.155661) (xy 133.403725 -176.187096)
			(xy 133.354799 -176.211337) (xy 133.302742 -176.227814) (xy 133.248778 -176.236142) (xy 133.221476 -176.23663)
			(xy 133.221222 -176.23663) (xy 133.194571 -176.236114) (xy 133.141865 -176.228173) (xy 133.090931 -176.212465)
			(xy 133.042908 -176.189341) (xy 132.998867 -176.159317) (xy 132.959794 -176.123064) (xy 132.92656 -176.081392)
			(xy 132.899908 -176.035233) (xy 132.880434 -175.985617) (xy 132.868573 -175.933652) (xy 132.86459 -175.8805)
			(xy 132.63842 -175.8805) (xy 132.635561 -175.918651) (xy 132.623701 -175.970614) (xy 132.60423 -176.02023)
			(xy 132.577583 -176.06639) (xy 132.544353 -176.108063) (xy 132.505284 -176.144319) (xy 132.461248 -176.174347)
			(xy 132.413229 -176.197477) (xy 132.362299 -176.213193) (xy 132.309596 -176.221143) (xy 132.282946 -176.221644)
			(xy 132.282692 -176.221644) (xy 132.255399 -176.221065) (xy 132.201455 -176.212712) (xy 132.149414 -176.196233)
			(xy 132.100494 -176.172013) (xy 132.055839 -176.140619) (xy 132.035804 -176.122076) (xy 132.028438 -176.114964)
			(xy 132.010658 -176.107852) (xy 131.920234 -176.107852) (xy 131.902454 -176.114964) (xy 131.895088 -176.122076)
			(xy 131.875069 -176.140682) (xy 131.830378 -176.17214) (xy 131.781401 -176.196391) (xy 131.72929 -176.212864)
			(xy 131.675273 -176.221171) (xy 131.647946 -176.221644) (xy 131.619036 -176.221112) (xy 131.561973 -176.211799)
			(xy 131.507162 -176.193393) (xy 131.456043 -176.166378) (xy 131.409957 -176.131462) (xy 131.389628 -176.1109)
			(xy 131.382008 -176.102772) (xy 131.361434 -176.09439) (xy 131.273804 -176.098708) (xy 131.262896 -176.099765)
			(xy 131.243415 -176.109754) (xy 131.236212 -176.118012) (xy 131.235958 -176.118266) (xy 131.219566 -176.138489)
			(xy 131.181872 -176.174391) (xy 131.139345 -176.204411) (xy 131.116324 -176.216564) (xy 131.103624 -176.222914)
			(xy 131.088892 -176.246536) (xy 131.086606 -176.365154) (xy 131.100576 -176.389284) (xy 131.113022 -176.396142)
			(xy 131.137625 -176.410325) (xy 131.18261 -176.444981) (xy 131.221811 -176.486066) (xy 131.25432 -176.532626)
			(xy 131.279381 -176.583583) (xy 131.296415 -176.637755) (xy 131.305025 -176.693885) (xy 131.305554 -176.722278)
			(xy 131.305033 -176.750163) (xy 131.296721 -176.80531) (xy 131.280283 -176.858602) (xy 131.256085 -176.908848)
			(xy 131.224669 -176.954927) (xy 131.186736 -176.995809) (xy 131.143134 -177.030581) (xy 131.094836 -177.058466)
			(xy 131.042921 -177.078841) (xy 130.98855 -177.091251) (xy 130.932936 -177.095419) (xy 130.877322 -177.091251)
			(xy 130.822951 -177.078841) (xy 130.771036 -177.058466) (xy 130.722738 -177.030581) (xy 130.679136 -176.995809)
			(xy 130.641203 -176.954927) (xy 130.609787 -176.908848) (xy 130.585589 -176.858602) (xy 130.569151 -176.80531)
			(xy 130.560839 -176.750163) (xy 130.560318 -176.722278) (xy 95.411544 -176.722278) (xy 95.411544 -178.995324)
			(xy 123.198636 -178.995324) (xy 123.198636 -178.131724) (xy 123.199126 -178.10174) (xy 123.206954 -178.042284)
			(xy 123.222475 -177.984359) (xy 123.245424 -177.928955) (xy 123.275408 -177.877021) (xy 123.311914 -177.829445)
			(xy 123.354319 -177.78704) (xy 123.401895 -177.750534) (xy 123.453829 -177.72055) (xy 123.509233 -177.697601)
			(xy 123.567158 -177.68208) (xy 123.626614 -177.674252) (xy 123.686582 -177.674252) (xy 123.746038 -177.68208)
			(xy 123.803963 -177.697601) (xy 123.859367 -177.72055) (xy 123.911301 -177.750534) (xy 123.958877 -177.78704)
			(xy 124.001282 -177.829445) (xy 124.037788 -177.877021) (xy 124.067772 -177.928955) (xy 124.090721 -177.984359)
			(xy 124.106242 -178.042284) (xy 124.11407 -178.10174) (xy 124.11456 -178.131724) (xy 124.11456 -178.143154)
			(xy 130.5649 -178.143154) (xy 130.568876 -178.088828) (xy 130.580719 -178.035659) (xy 130.600178 -177.984782)
			(xy 130.626838 -177.93728) (xy 130.660129 -177.894166) (xy 130.699343 -177.856359) (xy 130.743645 -177.824664)
			(xy 130.792088 -177.799758) (xy 130.843642 -177.78217) (xy 130.897208 -177.772276) (xy 130.951643 -177.770286)
			(xy 131.005788 -177.776244) (xy 131.058488 -177.790022) (xy 131.108621 -177.811326) (xy 131.155117 -177.839702)
			(xy 131.196987 -177.874546) (xy 131.233336 -177.915115) (xy 131.263392 -177.960544) (xy 131.286513 -178.009865)
			(xy 131.302206 -178.062027) (xy 131.310137 -178.115918) (xy 131.310634 -178.143154) (xy 131.310137 -178.17039)
			(xy 131.302206 -178.224281) (xy 131.286513 -178.276443) (xy 131.263392 -178.325764) (xy 131.233336 -178.371193)
			(xy 131.196987 -178.411762) (xy 131.155117 -178.446606) (xy 131.108621 -178.474982) (xy 131.058488 -178.496286)
			(xy 131.005788 -178.510064) (xy 130.951643 -178.516022) (xy 130.897208 -178.514032) (xy 130.843642 -178.504138)
			(xy 130.792088 -178.48655) (xy 130.743645 -178.461644) (xy 130.699343 -178.429949) (xy 130.660129 -178.392142)
			(xy 130.626838 -178.349028) (xy 130.600178 -178.301526) (xy 130.580719 -178.250649) (xy 130.568876 -178.19748)
			(xy 130.5649 -178.143154) (xy 124.11456 -178.143154) (xy 124.11456 -178.995324) (xy 124.11407 -179.025308)
			(xy 124.106242 -179.084764) (xy 124.090721 -179.142689) (xy 124.067772 -179.198093) (xy 124.037788 -179.250027)
			(xy 124.001282 -179.297603) (xy 123.958877 -179.340008) (xy 123.911301 -179.376514) (xy 123.859367 -179.406498)
			(xy 123.820493 -179.4226) (xy 130.601585 -179.4226) (xy 130.605755 -179.366971) (xy 130.618169 -179.312585)
			(xy 130.638551 -179.260656) (xy 130.666446 -179.212346) (xy 130.701229 -179.168734) (xy 130.742125 -179.130793)
			(xy 130.788219 -179.099371) (xy 130.838482 -179.075172) (xy 130.89179 -179.058734) (xy 130.946953 -179.050426)
			(xy 130.974846 -179.049934) (xy 131.000437 -179.050342) (xy 131.051131 -179.057392) (xy 131.100383 -179.071313)
			(xy 131.147268 -179.091843) (xy 131.190902 -179.118595) (xy 131.230465 -179.151066) (xy 131.24815 -179.169568)
			(xy 131.255704 -179.176897) (xy 131.274977 -179.185295) (xy 131.285488 -179.185824) (xy 131.360164 -179.185824)
			(xy 131.370689 -179.185353) (xy 131.389981 -179.176947) (xy 131.397502 -179.169568) (xy 131.41516 -179.15104)
			(xy 131.454728 -179.118574) (xy 131.498368 -179.091829) (xy 131.545259 -179.071311) (xy 131.594517 -179.057404)
			(xy 131.645215 -179.050371) (xy 131.670806 -179.049934) (xy 131.696761 -179.050402) (xy 131.748167 -179.057608)
			(xy 131.798077 -179.071878) (xy 131.845522 -179.092938) (xy 131.889585 -179.120378) (xy 131.929414 -179.153669)
			(xy 131.947158 -179.172616) (xy 131.954607 -179.180257) (xy 131.974087 -179.18893) (xy 131.98475 -179.18938)
			(xy 132.060442 -179.18938) (xy 132.07107 -179.188786) (xy 132.090488 -179.180124) (xy 132.098034 -179.172616)
			(xy 132.117413 -179.151956) (xy 132.161313 -179.116161) (xy 132.210127 -179.087426) (xy 132.262729 -179.066415)
			(xy 132.317906 -179.053611) (xy 132.374386 -179.04931) (xy 132.430866 -179.053611) (xy 132.486043 -179.066415)
			(xy 132.538645 -179.087426) (xy 132.587459 -179.116161) (xy 132.631359 -179.151956) (xy 132.650738 -179.172616)
			(xy 132.658195 -179.180248) (xy 132.677669 -179.188926) (xy 132.68833 -179.18938) (xy 132.764022 -179.18938)
			(xy 132.774648 -179.188775) (xy 132.794067 -179.18012) (xy 132.801614 -179.172616) (xy 132.820993 -179.151956)
			(xy 132.864893 -179.116161) (xy 132.913707 -179.087426) (xy 132.966309 -179.066415) (xy 133.021486 -179.053611)
			(xy 133.077966 -179.04931) (xy 133.134446 -179.053611) (xy 133.189623 -179.066415) (xy 133.242225 -179.087426)
			(xy 133.291039 -179.116161) (xy 133.334939 -179.151956) (xy 133.354318 -179.172616) (xy 133.361782 -179.180239)
			(xy 133.381251 -179.188922) (xy 133.39191 -179.18938) (xy 133.467602 -179.18938) (xy 133.478227 -179.188765)
			(xy 133.497646 -179.180117) (xy 133.505194 -179.172616) (xy 133.522919 -179.153649) (xy 133.562749 -179.120353)
			(xy 133.606815 -179.09291) (xy 133.654264 -179.07185) (xy 133.704178 -179.057581) (xy 133.755589 -179.05038)
			(xy 133.781546 -179.049934) (xy 133.810645 -179.050478) (xy 133.868132 -179.059541) (xy 133.923509 -179.077439)
			(xy 133.975426 -179.103735) (xy 134.022619 -179.137791) (xy 134.043674 -179.157884) (xy 134.043928 -179.158138)
			(xy 134.051887 -179.165112) (xy 134.071701 -179.172468) (xy 134.082282 -179.172362) (xy 134.168642 -179.167536)
			(xy 134.187692 -179.15763) (xy 134.19455 -179.149248) (xy 134.212347 -179.1279) (xy 134.253176 -179.090195)
			(xy 134.299154 -179.058972) (xy 134.349259 -179.034925) (xy 134.402379 -179.018587) (xy 134.457338 -179.010321)
			(xy 134.485126 -179.009802) (xy 134.513011 -179.010285) (xy 134.568158 -179.0186) (xy 134.621449 -179.035042)
			(xy 134.671695 -179.059242) (xy 134.717773 -179.090661) (xy 134.758654 -179.128595) (xy 134.793425 -179.172199)
			(xy 134.821309 -179.220498) (xy 134.841683 -179.272414) (xy 134.854093 -179.326786) (xy 134.858261 -179.3824)
			(xy 134.854093 -179.438014) (xy 134.841683 -179.492386) (xy 134.821309 -179.544302) (xy 134.793425 -179.592601)
			(xy 134.758654 -179.636205) (xy 134.717773 -179.674139) (xy 134.671695 -179.705558) (xy 134.621449 -179.729758)
			(xy 134.568158 -179.7462) (xy 134.513011 -179.754515) (xy 134.485126 -179.755038) (xy 134.456029 -179.754457)
			(xy 134.398543 -179.745405) (xy 134.343166 -179.727516) (xy 134.291248 -179.701227) (xy 134.244054 -179.667178)
			(xy 134.222998 -179.647088) (xy 134.222744 -179.646834) (xy 134.214798 -179.639843) (xy 134.194974 -179.632498)
			(xy 134.18439 -179.63261) (xy 134.108698 -179.636928) (xy 134.098117 -179.638062) (xy 134.079214 -179.647788)
			(xy 134.072122 -179.655724) (xy 134.05492 -179.67638) (xy 134.015629 -179.713062) (xy 133.971473 -179.743713)
			(xy 133.923367 -179.767695) (xy 133.872314 -179.784512) (xy 133.819372 -179.793812) (xy 133.765644 -179.795403)
			(xy 133.712245 -179.789252) (xy 133.660285 -179.775486) (xy 133.610845 -179.754392) (xy 133.564952 -179.726408)
			(xy 133.52356 -179.692116) (xy 133.505194 -179.672488) (xy 133.497725 -179.66487) (xy 133.47826 -179.656184)
			(xy 133.467602 -179.655724) (xy 133.39191 -179.655724) (xy 133.381285 -179.656344) (xy 133.361867 -179.664988)
			(xy 133.354318 -179.672488) (xy 133.334939 -179.693148) (xy 133.291039 -179.728943) (xy 133.242225 -179.757678)
			(xy 133.189623 -179.778689) (xy 133.134446 -179.791493) (xy 133.077966 -179.795794) (xy 133.021486 -179.791493)
			(xy 132.966309 -179.778689) (xy 132.913707 -179.757678) (xy 132.864893 -179.728943) (xy 132.820993 -179.693148)
			(xy 132.801614 -179.672488) (xy 132.794137 -179.664879) (xy 132.774678 -179.656188) (xy 132.764022 -179.655724)
			(xy 132.68833 -179.655724) (xy 132.677707 -179.656355) (xy 132.658288 -179.664991) (xy 132.650738 -179.672488)
			(xy 132.631359 -179.693148) (xy 132.587459 -179.728943) (xy 132.538645 -179.757678) (xy 132.486043 -179.778689)
			(xy 132.430866 -179.791493) (xy 132.374386 -179.795794) (xy 132.317906 -179.791493) (xy 132.262729 -179.778689)
			(xy 132.210127 -179.757678) (xy 132.161313 -179.728943) (xy 132.117413 -179.693148) (xy 132.098034 -179.672488)
			(xy 132.090588 -179.664843) (xy 132.071106 -179.656173) (xy 132.060442 -179.655724) (xy 131.98475 -179.655724)
			(xy 131.974122 -179.656312) (xy 131.954703 -179.664978) (xy 131.947158 -179.672488) (xy 131.929408 -179.69143)
			(xy 131.889584 -179.724728) (xy 131.845523 -179.752175) (xy 131.798078 -179.773239) (xy 131.748169 -179.787513)
			(xy 131.696761 -179.794721) (xy 131.670806 -179.79517) (xy 131.645217 -179.794726) (xy 131.594524 -179.787683)
			(xy 131.545272 -179.773769) (xy 131.498388 -179.753246) (xy 131.454753 -179.7265) (xy 131.415188 -179.694035)
			(xy 131.397502 -179.675536) (xy 131.389966 -179.668186) (xy 131.370679 -179.6598) (xy 131.360164 -179.65928)
			(xy 131.285488 -179.65928) (xy 131.27496 -179.659724) (xy 131.255668 -179.668149) (xy 131.24815 -179.675536)
			(xy 131.230468 -179.694039) (xy 131.190905 -179.726508) (xy 131.147269 -179.753255) (xy 131.100384 -179.773778)
			(xy 131.05113 -179.78769) (xy 131.000436 -179.794729) (xy 130.974846 -179.79517) (xy 130.946953 -179.794774)
			(xy 130.89179 -179.786466) (xy 130.838482 -179.770028) (xy 130.788219 -179.745829) (xy 130.742125 -179.714407)
			(xy 130.701229 -179.676466) (xy 130.666446 -179.632854) (xy 130.638551 -179.584544) (xy 130.618169 -179.532615)
			(xy 130.605755 -179.478229) (xy 130.601585 -179.4226) (xy 123.820493 -179.4226) (xy 123.803963 -179.429447)
			(xy 123.746038 -179.444968) (xy 123.686582 -179.452796) (xy 123.626614 -179.452796) (xy 123.567158 -179.444968)
			(xy 123.509233 -179.429447) (xy 123.453829 -179.406498) (xy 123.401895 -179.376514) (xy 123.354319 -179.340008)
			(xy 123.311914 -179.297603) (xy 123.275408 -179.250027) (xy 123.245424 -179.198093) (xy 123.222475 -179.142689)
			(xy 123.206954 -179.084764) (xy 123.199126 -179.025308) (xy 123.198636 -178.995324) (xy 95.411544 -178.995324)
			(xy 95.411544 -180.93944) (xy 107.97667 -180.93944) (xy 107.977165 -180.9107) (xy 107.985796 -180.853872)
			(xy 108.002853 -180.798981) (xy 108.027951 -180.74727) (xy 108.060521 -180.699908) (xy 108.079794 -180.678582)
			(xy 108.086398 -180.671724) (xy 108.09351 -180.65369) (xy 108.09351 -180.56479) (xy 108.086398 -180.546756)
			(xy 108.079794 -180.539898) (xy 108.060552 -180.518546) (xy 108.02798 -180.471192) (xy 108.002881 -180.419487)
			(xy 107.985824 -180.364601) (xy 107.977195 -180.307777) (xy 107.97667 -180.27904) (xy 107.977192 -180.251789)
			(xy 107.984943 -180.197841) (xy 108.000293 -180.145546) (xy 108.022929 -180.095968) (xy 108.052391 -180.050115)
			(xy 108.088079 -180.008923) (xy 108.129266 -179.973228) (xy 108.175113 -179.943759) (xy 108.224688 -179.921115)
			(xy 108.276981 -179.905757) (xy 108.330927 -179.897997) (xy 108.358178 -179.897532) (xy 108.383547 -179.897949)
			(xy 108.433837 -179.904672) (xy 108.482791 -179.918002) (xy 108.529547 -179.937705) (xy 108.573278 -179.963431)
			(xy 108.613213 -179.994728) (xy 108.631228 -180.012594) (xy 108.638551 -180.019352) (xy 108.656844 -180.027202)
			(xy 108.666788 -180.027834) (xy 108.74883 -180.02885) (xy 108.767118 -180.021738) (xy 108.774484 -180.014626)
			(xy 108.795961 -179.994638) (xy 108.843891 -179.960808) (xy 108.896434 -179.934711) (xy 108.952352 -179.916962)
			(xy 109.010327 -179.907978) (xy 109.03966 -179.907438) (xy 109.06703 -179.907918) (xy 109.121209 -179.915731)
			(xy 109.173712 -179.931216) (xy 109.223459 -179.954055) (xy 109.269426 -179.983778) (xy 109.290358 -180.001418)
			(xy 109.290612 -180.001672) (xy 109.297685 -180.007278) (xy 109.314612 -180.013511) (xy 109.323632 -180.013864)
			(xy 109.390688 -180.013864) (xy 109.399705 -180.013509) (xy 109.416622 -180.007261) (xy 109.423708 -180.001672)
			(xy 109.423708 -180.001418) (xy 109.423962 -180.001418) (xy 109.444895 -179.983777) (xy 109.490863 -179.954053)
			(xy 109.540609 -179.931207) (xy 109.593111 -179.915711) (xy 109.647289 -179.907882) (xy 109.702031 -179.907882)
			(xy 109.756209 -179.915711) (xy 109.808711 -179.931207) (xy 109.858457 -179.954053) (xy 109.904425 -179.983777)
			(xy 109.925358 -180.001418) (xy 109.925612 -180.001672) (xy 109.932685 -180.007278) (xy 109.949612 -180.013511)
			(xy 109.958632 -180.013864) (xy 110.025688 -180.013864) (xy 110.034705 -180.013509) (xy 110.051622 -180.007261)
			(xy 110.058708 -180.001672) (xy 110.058708 -180.001418) (xy 110.058962 -180.001418) (xy 110.079895 -179.983777)
			(xy 110.125863 -179.954053) (xy 110.175609 -179.931207) (xy 110.228111 -179.915711) (xy 110.282289 -179.907882)
			(xy 110.337031 -179.907882) (xy 110.391209 -179.915711) (xy 110.443711 -179.931207) (xy 110.493457 -179.954053)
			(xy 110.539425 -179.983777) (xy 110.560358 -180.001418) (xy 110.560612 -180.001672) (xy 110.567685 -180.007278)
			(xy 110.584612 -180.013511) (xy 110.593632 -180.013864) (xy 110.660688 -180.013864) (xy 110.669705 -180.013509)
			(xy 110.686622 -180.007261) (xy 110.693708 -180.001672) (xy 110.693708 -180.001418) (xy 110.693962 -180.001418)
			(xy 110.714895 -179.983777) (xy 110.760863 -179.954053) (xy 110.810609 -179.931207) (xy 110.863111 -179.915711)
			(xy 110.917289 -179.907882) (xy 110.972031 -179.907882) (xy 111.026209 -179.915711) (xy 111.078711 -179.931207)
			(xy 111.128457 -179.954053) (xy 111.174425 -179.983777) (xy 111.195358 -180.001418) (xy 111.195612 -180.001672)
			(xy 111.202685 -180.007278) (xy 111.219612 -180.013511) (xy 111.228632 -180.013864) (xy 111.295688 -180.013864)
			(xy 111.304705 -180.013509) (xy 111.321622 -180.007261) (xy 111.328708 -180.001672) (xy 111.328708 -180.001418)
			(xy 111.328962 -180.001418) (xy 111.3499 -179.983786) (xy 111.395871 -179.954073) (xy 111.445617 -179.931235)
			(xy 111.498116 -179.915742) (xy 111.552291 -179.907913) (xy 111.57966 -179.907438) (xy 111.606914 -179.907893)
			(xy 111.660868 -179.915645) (xy 111.713168 -179.930999) (xy 111.762751 -179.95364) (xy 111.808607 -179.983108)
			(xy 111.849801 -180.018803) (xy 111.854105 -180.02377) (xy 126.799338 -180.02377) (xy 126.803409 -179.968148)
			(xy 126.815535 -179.913711) (xy 126.835458 -179.86162) (xy 126.862754 -179.812985) (xy 126.89684 -179.768842)
			(xy 126.936989 -179.730133) (xy 126.982347 -179.697682) (xy 127.031947 -179.672181) (xy 127.084731 -179.654174)
			(xy 127.139574 -179.644044) (xy 127.195308 -179.642007) (xy 127.250745 -179.648107) (xy 127.304702 -179.662213)
			(xy 127.356031 -179.684025) (xy 127.403637 -179.713079) (xy 127.446505 -179.748754) (xy 127.483722 -179.790291)
			(xy 127.514495 -179.836804) (xy 127.538167 -179.887301) (xy 127.554235 -179.940708) (xy 127.562355 -179.995884)
			(xy 127.562864 -180.02377) (xy 127.562355 -180.051656) (xy 127.554235 -180.106832) (xy 127.538167 -180.160239)
			(xy 127.514495 -180.210736) (xy 127.483722 -180.257249) (xy 127.446505 -180.298786) (xy 127.403637 -180.334461)
			(xy 127.356031 -180.363515) (xy 127.304702 -180.385327) (xy 127.250745 -180.399433) (xy 127.195308 -180.405533)
			(xy 127.139574 -180.403496) (xy 127.084731 -180.393366) (xy 127.031947 -180.375359) (xy 126.982347 -180.349858)
			(xy 126.936989 -180.317407) (xy 126.89684 -180.278698) (xy 126.862754 -180.234555) (xy 126.835458 -180.18592)
			(xy 126.815535 -180.133829) (xy 126.803409 -180.079392) (xy 126.799338 -180.02377) (xy 111.854105 -180.02377)
			(xy 111.885496 -180.059998) (xy 111.914963 -180.105854) (xy 111.937603 -180.155437) (xy 111.952956 -180.207738)
			(xy 111.960708 -180.261692) (xy 111.961168 -180.288946) (xy 111.960654 -180.317685) (xy 111.952026 -180.374512)
			(xy 111.934973 -180.429402) (xy 111.90988 -180.481114) (xy 111.877314 -180.528477) (xy 111.858044 -180.549804)
			(xy 111.85144 -180.556662) (xy 111.844328 -180.574696) (xy 111.844328 -180.663596) (xy 111.85144 -180.68163)
			(xy 111.858044 -180.688488) (xy 111.877334 -180.709799) (xy 111.909898 -180.757165) (xy 111.934987 -180.808881)
			(xy 111.952033 -180.863775) (xy 111.96065 -180.920606) (xy 111.961168 -180.949346) (xy 111.960765 -180.9766)
			(xy 111.953001 -181.030553) (xy 111.937638 -181.082852) (xy 111.914989 -181.132432) (xy 111.885514 -181.178284)
			(xy 111.849814 -181.219475) (xy 111.808615 -181.255165) (xy 111.762756 -181.28463) (xy 111.713171 -181.307268)
			(xy 111.660869 -181.322619) (xy 111.606914 -181.330371) (xy 111.57966 -181.330854) (xy 111.552291 -181.330364)
			(xy 111.498112 -181.322554) (xy 111.445609 -181.307071) (xy 111.395861 -181.284234) (xy 111.349894 -181.254514)
			(xy 111.328962 -181.236874) (xy 111.328708 -181.23662) (xy 111.32163 -181.231021) (xy 111.304706 -181.224784)
			(xy 111.295688 -181.224428) (xy 111.228632 -181.224428) (xy 111.219616 -181.224794) (xy 111.202699 -181.231035)
			(xy 111.195612 -181.23662) (xy 111.195612 -181.236874) (xy 111.195358 -181.236874) (xy 111.174425 -181.254515)
			(xy 111.128457 -181.284239) (xy 111.078711 -181.307085) (xy 111.026209 -181.322581) (xy 110.972031 -181.33041)
			(xy 110.917289 -181.33041) (xy 110.863111 -181.322581) (xy 110.810609 -181.307085) (xy 110.760863 -181.284239)
			(xy 110.714895 -181.254515) (xy 110.693962 -181.236874) (xy 110.693708 -181.23662) (xy 110.68663 -181.231021)
			(xy 110.669706 -181.224784) (xy 110.660688 -181.224428) (xy 110.593632 -181.224428) (xy 110.584616 -181.224794)
			(xy 110.567699 -181.231035) (xy 110.560612 -181.23662) (xy 110.560612 -181.236874) (xy 110.560358 -181.236874)
			(xy 110.539425 -181.254515) (xy 110.493457 -181.284239) (xy 110.443711 -181.307085) (xy 110.391209 -181.322581)
			(xy 110.337031 -181.33041) (xy 110.282289 -181.33041) (xy 110.228111 -181.322581) (xy 110.175609 -181.307085)
			(xy 110.125863 -181.284239) (xy 110.079895 -181.254515) (xy 110.058962 -181.236874) (xy 110.058708 -181.23662)
			(xy 110.05163 -181.231021) (xy 110.034706 -181.224784) (xy 110.025688 -181.224428) (xy 109.958632 -181.224428)
			(xy 109.949616 -181.224794) (xy 109.932699 -181.231035) (xy 109.925612 -181.23662) (xy 109.925612 -181.236874)
			(xy 109.925358 -181.236874) (xy 109.904425 -181.254515) (xy 109.858457 -181.284239) (xy 109.808711 -181.307085)
			(xy 109.756209 -181.322581) (xy 109.702031 -181.33041) (xy 109.647289 -181.33041) (xy 109.593111 -181.322581)
			(xy 109.540609 -181.307085) (xy 109.490863 -181.284239) (xy 109.444895 -181.254515) (xy 109.423962 -181.236874)
			(xy 109.423708 -181.23662) (xy 109.41663 -181.231021) (xy 109.399706 -181.224784) (xy 109.390688 -181.224428)
			(xy 109.323632 -181.224428) (xy 109.314616 -181.224794) (xy 109.297699 -181.231035) (xy 109.290612 -181.23662)
			(xy 109.290612 -181.236874) (xy 109.290358 -181.236874) (xy 109.269412 -181.254495) (xy 109.223443 -181.284211)
			(xy 109.173699 -181.30705) (xy 109.121202 -181.322546) (xy 109.067028 -181.330378) (xy 109.03966 -181.330854)
			(xy 109.01429 -181.330482) (xy 108.963998 -181.32375) (xy 108.915042 -181.310411) (xy 108.868286 -181.290701)
			(xy 108.824556 -181.264966) (xy 108.784624 -181.233662) (xy 108.76661 -181.215792) (xy 108.75931 -181.209005)
			(xy 108.741 -181.201172) (xy 108.73105 -181.200552) (xy 108.649008 -181.199536) (xy 108.63072 -181.206648)
			(xy 108.623354 -181.21376) (xy 108.601875 -181.233744) (xy 108.553943 -181.267571) (xy 108.501401 -181.293668)
			(xy 108.445485 -181.311418) (xy 108.387511 -181.320405) (xy 108.358178 -181.320948) (xy 108.330928 -181.320443)
			(xy 108.276983 -181.312684) (xy 108.224691 -181.297328) (xy 108.175117 -181.274688) (xy 108.129268 -181.245223)
			(xy 108.088079 -181.209534) (xy 108.052388 -181.168346) (xy 108.022921 -181.122499) (xy 108.000278 -181.072926)
			(xy 107.98492 -181.020635) (xy 107.977158 -180.96669) (xy 107.97667 -180.93944) (xy 95.411544 -180.93944)
			(xy 95.411544 -182.475757) (xy 129.801509 -182.475757) (xy 129.801509 -182.421243) (xy 129.809267 -182.367284)
			(xy 129.824626 -182.314978) (xy 129.847273 -182.26539) (xy 129.876747 -182.219531) (xy 129.912447 -182.178333)
			(xy 129.953647 -182.142635) (xy 129.999508 -182.113163) (xy 130.049097 -182.090519) (xy 130.101403 -182.075163)
			(xy 130.155363 -182.067408) (xy 130.18262 -182.066946) (xy 130.182874 -182.066946) (xy 130.202432 -182.067454)
			(xy 130.212846 -182.067962) (xy 130.232658 -182.06085) (xy 130.293618 -182.002684) (xy 130.300754 -181.995193)
			(xy 130.308881 -181.976188) (xy 130.309366 -181.965854) (xy 130.309797 -181.938567) (xy 130.317466 -181.884535)
			(xy 130.332755 -181.832148) (xy 130.355353 -181.782474) (xy 130.384799 -181.736526) (xy 130.420491 -181.695243)
			(xy 130.461701 -181.659467) (xy 130.507588 -181.629928) (xy 130.557216 -181.607228) (xy 130.609572 -181.591831)
			(xy 130.663588 -181.584052) (xy 130.690874 -181.583584) (xy 130.718127 -181.584062) (xy 130.77208 -181.591815)
			(xy 130.82438 -181.607169) (xy 130.873962 -181.629809) (xy 130.919818 -181.659276) (xy 130.961013 -181.694969)
			(xy 130.996708 -181.736161) (xy 131.026178 -181.782015) (xy 131.048822 -181.831596) (xy 131.064179 -181.883894)
			(xy 131.071937 -181.937847) (xy 131.071937 -181.992353) (xy 131.064179 -182.046306) (xy 131.048822 -182.098604)
			(xy 131.026178 -182.148185) (xy 130.996708 -182.194039) (xy 130.961013 -182.235231) (xy 130.919818 -182.270924)
			(xy 130.873962 -182.300391) (xy 130.82438 -182.323031) (xy 130.77208 -182.338385) (xy 130.718127 -182.346138)
			(xy 130.690874 -182.3466) (xy 130.69062 -182.3466) (xy 130.671062 -182.346092) (xy 130.660648 -182.345584)
			(xy 130.640836 -182.352696) (xy 130.579876 -182.410862) (xy 130.572719 -182.418335) (xy 130.564605 -182.437354)
			(xy 130.564128 -182.447692) (xy 130.563653 -182.474978) (xy 130.555991 -182.529009) (xy 130.540708 -182.581395)
			(xy 130.518116 -182.63107) (xy 130.488675 -182.677018) (xy 130.452988 -182.718302) (xy 130.411782 -182.754079)
			(xy 130.365898 -182.783619) (xy 130.316272 -182.806319) (xy 130.263919 -182.821716) (xy 130.238408 -182.82539)
			(xy 136.874248 -182.82539) (xy 136.878319 -182.769768) (xy 136.890445 -182.715331) (xy 136.910368 -182.66324)
			(xy 136.937664 -182.614605) (xy 136.97175 -182.570462) (xy 137.011899 -182.531753) (xy 137.057257 -182.499302)
			(xy 137.106857 -182.473801) (xy 137.159641 -182.455794) (xy 137.214484 -182.445664) (xy 137.270218 -182.443627)
			(xy 137.325655 -182.449727) (xy 137.379612 -182.463833) (xy 137.430941 -182.485645) (xy 137.478547 -182.514699)
			(xy 137.521415 -182.550374) (xy 137.558632 -182.591911) (xy 137.589405 -182.638424) (xy 137.613077 -182.688921)
			(xy 137.629145 -182.742328) (xy 137.637265 -182.797504) (xy 137.637774 -182.82539) (xy 137.637265 -182.853276)
			(xy 137.629145 -182.908452) (xy 137.613077 -182.961859) (xy 137.589405 -183.012356) (xy 137.558632 -183.058869)
			(xy 137.521415 -183.100406) (xy 137.478547 -183.136081) (xy 137.430941 -183.165135) (xy 137.379612 -183.186947)
			(xy 137.325655 -183.201053) (xy 137.270218 -183.207153) (xy 137.214484 -183.205116) (xy 137.159641 -183.194986)
			(xy 137.106857 -183.176979) (xy 137.057257 -183.151478) (xy 137.011899 -183.119027) (xy 136.97175 -183.080318)
			(xy 136.937664 -183.036175) (xy 136.910368 -182.98754) (xy 136.890445 -182.935449) (xy 136.878319 -182.881012)
			(xy 136.874248 -182.82539) (xy 130.238408 -182.82539) (xy 130.209905 -182.829495) (xy 130.18262 -182.829962)
			(xy 130.155363 -182.829592) (xy 130.101403 -182.821837) (xy 130.049097 -182.806481) (xy 129.999508 -182.783837)
			(xy 129.953647 -182.754365) (xy 129.912447 -182.718667) (xy 129.876747 -182.677469) (xy 129.847273 -182.63161)
			(xy 129.824626 -182.582022) (xy 129.809267 -182.529716) (xy 129.801509 -182.475757) (xy 95.411544 -182.475757)
			(xy 95.411544 -183.004714) (xy 127.33731 -183.004714) (xy 127.341381 -182.949092) (xy 127.353507 -182.894655)
			(xy 127.37343 -182.842564) (xy 127.400726 -182.793929) (xy 127.434812 -182.749786) (xy 127.474961 -182.711077)
			(xy 127.520319 -182.678626) (xy 127.569919 -182.653125) (xy 127.622703 -182.635118) (xy 127.677546 -182.624988)
			(xy 127.73328 -182.622951) (xy 127.788717 -182.629051) (xy 127.842674 -182.643157) (xy 127.894003 -182.664969)
			(xy 127.941609 -182.694023) (xy 127.984477 -182.729698) (xy 128.021694 -182.771235) (xy 128.052467 -182.817748)
			(xy 128.076139 -182.868245) (xy 128.092207 -182.921652) (xy 128.100327 -182.976828) (xy 128.100836 -183.004714)
			(xy 128.100327 -183.0326) (xy 128.092207 -183.087776) (xy 128.076139 -183.141183) (xy 128.052467 -183.19168)
			(xy 128.021694 -183.238193) (xy 127.984477 -183.27973) (xy 127.941609 -183.315405) (xy 127.894003 -183.344459)
			(xy 127.842674 -183.366271) (xy 127.788717 -183.380377) (xy 127.73328 -183.386477) (xy 127.677546 -183.38444)
			(xy 127.622703 -183.37431) (xy 127.569919 -183.356303) (xy 127.520319 -183.330802) (xy 127.474961 -183.298351)
			(xy 127.434812 -183.259642) (xy 127.400726 -183.215499) (xy 127.37343 -183.166864) (xy 127.353507 -183.114773)
			(xy 127.341381 -183.060336) (xy 127.33731 -183.004714) (xy 95.411544 -183.004714) (xy 95.411544 -184.985914)
			(xy 107.566204 -184.985914) (xy 107.570275 -184.930292) (xy 107.582401 -184.875855) (xy 107.602324 -184.823764)
			(xy 107.62962 -184.775129) (xy 107.663706 -184.730986) (xy 107.703855 -184.692277) (xy 107.749213 -184.659826)
			(xy 107.798813 -184.634325) (xy 107.851597 -184.616318) (xy 107.90644 -184.606188) (xy 107.962174 -184.604151)
			(xy 108.017611 -184.610251) (xy 108.071568 -184.624357) (xy 108.122897 -184.646169) (xy 108.170503 -184.675223)
			(xy 108.213371 -184.710898) (xy 108.250588 -184.752435) (xy 108.281361 -184.798948) (xy 108.305033 -184.849445)
			(xy 108.321101 -184.902852) (xy 108.329221 -184.958028) (xy 108.32973 -184.985914) (xy 108.329221 -185.0138)
			(xy 108.321101 -185.068976) (xy 108.305033 -185.122383) (xy 108.281361 -185.17288) (xy 108.250588 -185.219393)
			(xy 108.213371 -185.26093) (xy 108.170503 -185.296605) (xy 108.122897 -185.325659) (xy 108.071568 -185.347471)
			(xy 108.017611 -185.361577) (xy 107.962174 -185.367677) (xy 107.90644 -185.36564) (xy 107.851597 -185.35551)
			(xy 107.798813 -185.337503) (xy 107.749213 -185.312002) (xy 107.703855 -185.279551) (xy 107.663706 -185.240842)
			(xy 107.62962 -185.196699) (xy 107.602324 -185.148064) (xy 107.582401 -185.095973) (xy 107.570275 -185.041536)
			(xy 107.566204 -184.985914) (xy 95.411544 -184.985914) (xy 95.411544 -185.674) (xy 96.382584 -185.674)
			(xy 96.386655 -185.618378) (xy 96.398781 -185.563941) (xy 96.418704 -185.51185) (xy 96.446 -185.463215)
			(xy 96.480086 -185.419072) (xy 96.520235 -185.380363) (xy 96.565593 -185.347912) (xy 96.615193 -185.322411)
			(xy 96.667977 -185.304404) (xy 96.72282 -185.294274) (xy 96.778554 -185.292237) (xy 96.833991 -185.298337)
			(xy 96.887948 -185.312443) (xy 96.939277 -185.334255) (xy 96.986883 -185.363309) (xy 97.029751 -185.398984)
			(xy 97.066968 -185.440521) (xy 97.097741 -185.487034) (xy 97.121413 -185.537531) (xy 97.137481 -185.590938)
			(xy 97.145601 -185.646114) (xy 97.14611 -185.674) (xy 97.145601 -185.701886) (xy 97.137481 -185.757062)
			(xy 97.121413 -185.810469) (xy 97.097741 -185.860966) (xy 97.066968 -185.907479) (xy 97.029751 -185.949016)
			(xy 96.986883 -185.984691) (xy 96.939277 -186.013745) (xy 96.887948 -186.035557) (xy 96.833991 -186.049663)
			(xy 96.778554 -186.055763) (xy 96.72282 -186.053726) (xy 96.667977 -186.043596) (xy 96.615193 -186.025589)
			(xy 96.565593 -186.000088) (xy 96.520235 -185.967637) (xy 96.480086 -185.928928) (xy 96.446 -185.884785)
			(xy 96.418704 -185.83615) (xy 96.398781 -185.784059) (xy 96.386655 -185.729622) (xy 96.382584 -185.674)
			(xy 95.411544 -185.674) (xy 95.411544 -186.14771) (xy 99.051362 -186.14771) (xy 99.055433 -186.092088)
			(xy 99.067559 -186.037651) (xy 99.087482 -185.98556) (xy 99.114778 -185.936925) (xy 99.148864 -185.892782)
			(xy 99.189013 -185.854073) (xy 99.234371 -185.821622) (xy 99.283971 -185.796121) (xy 99.336755 -185.778114)
			(xy 99.391598 -185.767984) (xy 99.447332 -185.765947) (xy 99.502769 -185.772047) (xy 99.556726 -185.786153)
			(xy 99.608055 -185.807965) (xy 99.655661 -185.837019) (xy 99.698529 -185.872694) (xy 99.735746 -185.914231)
			(xy 99.766519 -185.960744) (xy 99.790191 -186.011241) (xy 99.806259 -186.064648) (xy 99.814379 -186.119824)
			(xy 99.814888 -186.14771) (xy 99.814379 -186.175596) (xy 99.806259 -186.230772) (xy 99.790191 -186.284179)
			(xy 99.766519 -186.334676) (xy 99.735746 -186.381189) (xy 99.698529 -186.422726) (xy 99.655661 -186.458401)
			(xy 99.608055 -186.487455) (xy 99.556726 -186.509267) (xy 99.502769 -186.523373) (xy 99.447332 -186.529473)
			(xy 99.391598 -186.527436) (xy 99.336755 -186.517306) (xy 99.283971 -186.499299) (xy 99.234371 -186.473798)
			(xy 99.189013 -186.441347) (xy 99.148864 -186.402638) (xy 99.114778 -186.358495) (xy 99.087482 -186.30986)
			(xy 99.067559 -186.257769) (xy 99.055433 -186.203332) (xy 99.051362 -186.14771) (xy 95.411544 -186.14771)
			(xy 95.411544 -186.37504) (xy 95.411078 -186.408194) (xy 95.403655 -186.474086) (xy 95.388905 -186.538734)
			(xy 95.367015 -186.601325) (xy 95.33826 -186.661075) (xy 95.302999 -186.717231) (xy 95.261677 -186.76909)
			(xy 95.23857 -186.79287) (xy 94.906858 -187.124582) (xy 135.58115 -187.124582) (xy 135.58115 -187.064618)
			(xy 135.588977 -187.005166) (xy 135.604497 -186.947244) (xy 135.627444 -186.891844) (xy 135.657426 -186.839912)
			(xy 135.69393 -186.792339) (xy 135.736331 -186.749937) (xy 135.783904 -186.713432) (xy 135.835835 -186.683448)
			(xy 135.891235 -186.6605) (xy 135.949156 -186.644979) (xy 136.008608 -186.637151) (xy 136.03859 -186.63666)
			(xy 136.90219 -186.63666) (xy 136.932178 -186.637085) (xy 136.99164 -186.644912) (xy 137.049571 -186.660433)
			(xy 137.104981 -186.683384) (xy 137.156922 -186.713371) (xy 137.204504 -186.749881) (xy 137.246913 -186.792289)
			(xy 137.283424 -186.83987) (xy 137.313412 -186.89181) (xy 137.336363 -186.947219) (xy 137.351886 -187.005151)
			(xy 137.359715 -187.064612) (xy 137.359715 -187.124588) (xy 137.351886 -187.184049) (xy 137.336363 -187.241981)
			(xy 137.313412 -187.29739) (xy 137.283424 -187.34933) (xy 137.246913 -187.396911) (xy 137.204504 -187.439319)
			(xy 137.156922 -187.475829) (xy 137.104981 -187.505816) (xy 137.049571 -187.528767) (xy 136.99164 -187.544288)
			(xy 136.932178 -187.552115) (xy 136.90219 -187.552584) (xy 136.03859 -187.552584) (xy 136.008608 -187.552049)
			(xy 135.949156 -187.544221) (xy 135.891235 -187.5287) (xy 135.835835 -187.505752) (xy 135.783904 -187.475768)
			(xy 135.736331 -187.439263) (xy 135.69393 -187.396861) (xy 135.657426 -187.349288) (xy 135.627444 -187.297356)
			(xy 135.604497 -187.241956) (xy 135.588977 -187.184034) (xy 135.58115 -187.124582) (xy 94.906858 -187.124582)
			(xy 93.984826 -188.046614) (xy 96.614232 -188.046614) (xy 96.618303 -187.990992) (xy 96.630429 -187.936555)
			(xy 96.650352 -187.884464) (xy 96.677648 -187.835829) (xy 96.711734 -187.791686) (xy 96.751883 -187.752977)
			(xy 96.797241 -187.720526) (xy 96.846841 -187.695025) (xy 96.899625 -187.677018) (xy 96.954468 -187.666888)
			(xy 97.010202 -187.664851) (xy 97.065639 -187.670951) (xy 97.119596 -187.685057) (xy 97.170925 -187.706869)
			(xy 97.218531 -187.735923) (xy 97.261399 -187.771598) (xy 97.298616 -187.813135) (xy 97.329389 -187.859648)
			(xy 97.353061 -187.910145) (xy 97.369129 -187.963552) (xy 97.377249 -188.018728) (xy 97.377758 -188.046614)
			(xy 97.377249 -188.0745) (xy 97.369129 -188.129676) (xy 97.353061 -188.183083) (xy 97.329389 -188.23358)
			(xy 97.298616 -188.280093) (xy 97.28956 -188.2902) (xy 102.792782 -188.2902) (xy 102.796853 -188.234578)
			(xy 102.808979 -188.180141) (xy 102.828902 -188.12805) (xy 102.856198 -188.079415) (xy 102.890284 -188.035272)
			(xy 102.930433 -187.996563) (xy 102.975791 -187.964112) (xy 103.025391 -187.938611) (xy 103.078175 -187.920604)
			(xy 103.133018 -187.910474) (xy 103.188752 -187.908437) (xy 103.244189 -187.914537) (xy 103.298146 -187.928643)
			(xy 103.349475 -187.950455) (xy 103.397081 -187.979509) (xy 103.439949 -188.015184) (xy 103.477166 -188.056721)
			(xy 103.507939 -188.103234) (xy 103.531611 -188.153731) (xy 103.547679 -188.207138) (xy 103.554411 -188.252885)
			(xy 128.656818 -188.252885) (xy 128.656818 -188.192915) (xy 128.664646 -188.133459) (xy 128.680167 -188.075533)
			(xy 128.703116 -188.020128) (xy 128.733101 -187.968193) (xy 128.769608 -187.920615) (xy 128.812012 -187.87821)
			(xy 128.859589 -187.841703) (xy 128.911524 -187.811718) (xy 128.966929 -187.788768) (xy 129.024855 -187.773246)
			(xy 129.084311 -187.765418) (xy 129.114296 -187.764928) (xy 129.977896 -187.764928) (xy 130.007881 -187.765417)
			(xy 130.067339 -187.773244) (xy 130.125266 -187.788765) (xy 130.180671 -187.811714) (xy 130.232607 -187.841699)
			(xy 130.280185 -187.878207) (xy 130.322591 -187.920612) (xy 130.359098 -187.96819) (xy 130.389084 -188.020125)
			(xy 130.412034 -188.075531) (xy 130.427555 -188.133458) (xy 130.435383 -188.192915) (xy 130.435383 -188.252885)
			(xy 130.434185 -188.261981) (xy 131.046262 -188.261981) (xy 131.046262 -188.202019) (xy 131.054088 -188.14257)
			(xy 131.069607 -188.084651) (xy 131.092553 -188.029253) (xy 131.122533 -187.977324) (xy 131.159034 -187.929752)
			(xy 131.201432 -187.887351) (xy 131.249002 -187.850847) (xy 131.30093 -187.820864) (xy 131.356326 -187.797915)
			(xy 131.414244 -187.782393) (xy 131.473693 -187.774564) (xy 131.503674 -187.774072) (xy 132.367274 -187.774072)
			(xy 132.397263 -187.774472) (xy 132.456728 -187.782297) (xy 132.514663 -187.797818) (xy 132.570077 -187.820768)
			(xy 132.62202 -187.850755) (xy 132.669605 -187.887266) (xy 132.712017 -187.929675) (xy 132.74853 -187.977258)
			(xy 132.77852 -188.0292) (xy 132.801474 -188.084612) (xy 132.816998 -188.142546) (xy 132.824827 -188.202011)
			(xy 132.824827 -188.261989) (xy 132.816998 -188.321454) (xy 132.801474 -188.379388) (xy 132.79518 -188.394582)
			(xy 133.54915 -188.394582) (xy 133.54915 -188.334618) (xy 133.556977 -188.275166) (xy 133.572497 -188.217244)
			(xy 133.595444 -188.161844) (xy 133.625426 -188.109912) (xy 133.66193 -188.062339) (xy 133.704331 -188.019937)
			(xy 133.751904 -187.983432) (xy 133.803835 -187.953448) (xy 133.859235 -187.9305) (xy 133.917156 -187.914979)
			(xy 133.976608 -187.907151) (xy 134.00659 -187.90666) (xy 134.87019 -187.90666) (xy 134.900178 -187.907085)
			(xy 134.95964 -187.914912) (xy 135.017571 -187.930433) (xy 135.072981 -187.953384) (xy 135.124922 -187.983371)
			(xy 135.172504 -188.019881) (xy 135.214913 -188.062289) (xy 135.251424 -188.10987) (xy 135.281412 -188.16181)
			(xy 135.304363 -188.217219) (xy 135.319886 -188.275151) (xy 135.327715 -188.334612) (xy 135.327715 -188.394588)
			(xy 135.319886 -188.454049) (xy 135.304363 -188.511981) (xy 135.281412 -188.56739) (xy 135.251424 -188.61933)
			(xy 135.214913 -188.666911) (xy 135.172504 -188.709319) (xy 135.124922 -188.745829) (xy 135.072981 -188.775816)
			(xy 135.017571 -188.798767) (xy 134.95964 -188.814288) (xy 134.900178 -188.822115) (xy 134.87019 -188.822584)
			(xy 134.00659 -188.822584) (xy 133.976608 -188.822049) (xy 133.917156 -188.814221) (xy 133.859235 -188.7987)
			(xy 133.803835 -188.775752) (xy 133.751904 -188.745768) (xy 133.704331 -188.709263) (xy 133.66193 -188.666861)
			(xy 133.625426 -188.619288) (xy 133.595444 -188.567356) (xy 133.572497 -188.511956) (xy 133.556977 -188.454034)
			(xy 133.54915 -188.394582) (xy 132.79518 -188.394582) (xy 132.77852 -188.4348) (xy 132.74853 -188.486742)
			(xy 132.712017 -188.534325) (xy 132.669605 -188.576734) (xy 132.62202 -188.613245) (xy 132.570077 -188.643232)
			(xy 132.514663 -188.666182) (xy 132.456728 -188.681703) (xy 132.397263 -188.689528) (xy 132.367274 -188.689996)
			(xy 131.503674 -188.689996) (xy 131.473693 -188.689436) (xy 131.414244 -188.681607) (xy 131.356326 -188.666085)
			(xy 131.30093 -188.643136) (xy 131.249002 -188.613153) (xy 131.201432 -188.576649) (xy 131.159034 -188.534248)
			(xy 131.122533 -188.486676) (xy 131.092553 -188.434747) (xy 131.069607 -188.379349) (xy 131.054088 -188.32143)
			(xy 131.046262 -188.261981) (xy 130.434185 -188.261981) (xy 130.427555 -188.312342) (xy 130.412034 -188.370269)
			(xy 130.389084 -188.425675) (xy 130.359098 -188.47761) (xy 130.322591 -188.525188) (xy 130.280185 -188.567593)
			(xy 130.232607 -188.604101) (xy 130.180671 -188.634086) (xy 130.125266 -188.657035) (xy 130.067339 -188.672556)
			(xy 130.007881 -188.680383) (xy 129.977896 -188.680852) (xy 129.114296 -188.680852) (xy 129.084311 -188.680382)
			(xy 129.024855 -188.672554) (xy 128.966929 -188.657032) (xy 128.911524 -188.634082) (xy 128.859589 -188.604097)
			(xy 128.812012 -188.56759) (xy 128.769608 -188.525185) (xy 128.733101 -188.477607) (xy 128.703116 -188.425672)
			(xy 128.680167 -188.370267) (xy 128.664646 -188.312341) (xy 128.656818 -188.252885) (xy 103.554411 -188.252885)
			(xy 103.555799 -188.262314) (xy 103.556308 -188.2902) (xy 103.555799 -188.318086) (xy 103.547679 -188.373262)
			(xy 103.531611 -188.426669) (xy 103.507939 -188.477166) (xy 103.477166 -188.523679) (xy 103.439949 -188.565216)
			(xy 103.397081 -188.600891) (xy 103.349475 -188.629945) (xy 103.298146 -188.651757) (xy 103.244189 -188.665863)
			(xy 103.188752 -188.671963) (xy 103.133018 -188.669926) (xy 103.078175 -188.659796) (xy 103.025391 -188.641789)
			(xy 102.975791 -188.616288) (xy 102.930433 -188.583837) (xy 102.890284 -188.545128) (xy 102.856198 -188.500985)
			(xy 102.828902 -188.45235) (xy 102.808979 -188.400259) (xy 102.796853 -188.345822) (xy 102.792782 -188.2902)
			(xy 97.28956 -188.2902) (xy 97.261399 -188.32163) (xy 97.218531 -188.357305) (xy 97.170925 -188.386359)
			(xy 97.119596 -188.408171) (xy 97.065639 -188.422277) (xy 97.010202 -188.428377) (xy 96.954468 -188.42634)
			(xy 96.899625 -188.41621) (xy 96.846841 -188.398203) (xy 96.797241 -188.372702) (xy 96.751883 -188.340251)
			(xy 96.711734 -188.301542) (xy 96.677648 -188.257399) (xy 96.650352 -188.208764) (xy 96.630429 -188.156673)
			(xy 96.618303 -188.102236) (xy 96.614232 -188.046614) (xy 93.984826 -188.046614) (xy 92.47124 -189.5602)
			(xy 94.207582 -189.5602) (xy 94.211653 -189.504578) (xy 94.223779 -189.450141) (xy 94.243702 -189.39805)
			(xy 94.270998 -189.349415) (xy 94.305084 -189.305272) (xy 94.345233 -189.266563) (xy 94.390591 -189.234112)
			(xy 94.440191 -189.208611) (xy 94.492975 -189.190604) (xy 94.547818 -189.180474) (xy 94.603552 -189.178437)
			(xy 94.658989 -189.184537) (xy 94.712946 -189.198643) (xy 94.764275 -189.220455) (xy 94.811881 -189.249509)
			(xy 94.854749 -189.285184) (xy 94.891966 -189.326721) (xy 94.922739 -189.373234) (xy 94.946411 -189.423731)
			(xy 94.962479 -189.477138) (xy 94.970599 -189.532314) (xy 94.971108 -189.5602) (xy 94.970599 -189.588086)
			(xy 94.962479 -189.643262) (xy 94.946411 -189.696669) (xy 94.922739 -189.747166) (xy 94.891966 -189.793679)
			(xy 94.854749 -189.835216) (xy 94.811881 -189.870891) (xy 94.764275 -189.899945) (xy 94.712946 -189.921757)
			(xy 94.658989 -189.935863) (xy 94.603552 -189.941963) (xy 94.547818 -189.939926) (xy 94.492975 -189.929796)
			(xy 94.440191 -189.911789) (xy 94.390591 -189.886288) (xy 94.345233 -189.853837) (xy 94.305084 -189.815128)
			(xy 94.270998 -189.770985) (xy 94.243702 -189.72235) (xy 94.223779 -189.670259) (xy 94.211653 -189.615822)
			(xy 94.207582 -189.5602) (xy 92.47124 -189.5602) (xy 91.99753 -190.03391) (xy 91.990682 -190.041308)
			(xy 91.982946 -190.059906) (xy 91.982544 -190.069978) (xy 91.982544 -190.5) (xy 94.182182 -190.5)
			(xy 94.186253 -190.444378) (xy 94.198379 -190.389941) (xy 94.218302 -190.33785) (xy 94.245598 -190.289215)
			(xy 94.279684 -190.245072) (xy 94.319833 -190.206363) (xy 94.365191 -190.173912) (xy 94.414791 -190.148411)
			(xy 94.467575 -190.130404) (xy 94.522418 -190.120274) (xy 94.578152 -190.118237) (xy 94.633589 -190.124337)
			(xy 94.687546 -190.138443) (xy 94.738875 -190.160255) (xy 94.786481 -190.189309) (xy 94.829349 -190.224984)
			(xy 94.866566 -190.266521) (xy 94.897339 -190.313034) (xy 94.921011 -190.363531) (xy 94.937079 -190.416938)
			(xy 94.945199 -190.472114) (xy 94.945708 -190.5) (xy 94.945199 -190.527886) (xy 94.937079 -190.583062)
			(xy 94.921011 -190.636469) (xy 94.897339 -190.686966) (xy 94.866566 -190.733479) (xy 94.829349 -190.775016)
			(xy 94.786481 -190.810691) (xy 94.738875 -190.839745) (xy 94.687546 -190.861557) (xy 94.633589 -190.875663)
			(xy 94.578152 -190.881763) (xy 94.522418 -190.879726) (xy 94.467575 -190.869596) (xy 94.414791 -190.851589)
			(xy 94.365191 -190.826088) (xy 94.319833 -190.793637) (xy 94.279684 -190.754928) (xy 94.245598 -190.710785)
			(xy 94.218302 -190.66215) (xy 94.198379 -190.610059) (xy 94.186253 -190.555622) (xy 94.182182 -190.5)
			(xy 91.982544 -190.5) (xy 91.982544 -191.280288) (xy 128.928366 -191.280288) (xy 128.932437 -191.224666)
			(xy 128.944563 -191.170229) (xy 128.964486 -191.118138) (xy 128.991782 -191.069503) (xy 129.025868 -191.02536)
			(xy 129.066017 -190.986651) (xy 129.111375 -190.9542) (xy 129.160975 -190.928699) (xy 129.213759 -190.910692)
			(xy 129.268602 -190.900562) (xy 129.324336 -190.898525) (xy 129.379773 -190.904625) (xy 129.43373 -190.918731)
			(xy 129.485059 -190.940543) (xy 129.532665 -190.969597) (xy 129.575533 -191.005272) (xy 129.61275 -191.046809)
			(xy 129.643523 -191.093322) (xy 129.667195 -191.143819) (xy 129.683263 -191.197226) (xy 129.691383 -191.252402)
			(xy 129.691892 -191.280288) (xy 129.691383 -191.308174) (xy 129.683263 -191.36335) (xy 129.667195 -191.416757)
			(xy 129.643523 -191.467254) (xy 129.61275 -191.513767) (xy 129.575533 -191.555304) (xy 129.532665 -191.590979)
			(xy 129.485059 -191.620033) (xy 129.43373 -191.641845) (xy 129.379773 -191.655951) (xy 129.324336 -191.662051)
			(xy 129.268602 -191.660014) (xy 129.213759 -191.649884) (xy 129.160975 -191.631877) (xy 129.111375 -191.606376)
			(xy 129.066017 -191.573925) (xy 129.025868 -191.535216) (xy 128.991782 -191.491073) (xy 128.964486 -191.442438)
			(xy 128.944563 -191.390347) (xy 128.932437 -191.33591) (xy 128.928366 -191.280288) (xy 91.982544 -191.280288)
			(xy 91.982544 -192.001436) (xy 130.04897 -192.001436) (xy 130.048972 -191.946932) (xy 130.056731 -191.892984)
			(xy 130.072089 -191.840689) (xy 130.094733 -191.791112) (xy 130.124201 -191.745262) (xy 130.159895 -191.704072)
			(xy 130.201088 -191.668382) (xy 130.24694 -191.638917) (xy 130.296519 -191.616278) (xy 130.348815 -191.600925)
			(xy 130.402764 -191.59317) (xy 130.430016 -191.592708) (xy 130.443986 -191.592962) (xy 130.4574 -191.593097)
			(xy 130.483522 -191.587017) (xy 130.507163 -191.57435) (xy 130.526692 -191.555966) (xy 130.540766 -191.533135)
			(xy 130.548413 -191.507427) (xy 130.549107 -191.480616) (xy 130.546348 -191.467486) (xy 130.541379 -191.445533)
			(xy 130.536037 -191.400838) (xy 130.53568 -191.378332) (xy 130.53568 -191.37757) (xy 130.53621 -191.350321)
			(xy 130.54397 -191.296379) (xy 130.559328 -191.24409) (xy 130.581971 -191.194519) (xy 130.611438 -191.148675)
			(xy 130.647129 -191.107491) (xy 130.688318 -191.071805) (xy 130.734166 -191.042345) (xy 130.783741 -191.019709)
			(xy 130.836032 -191.004359) (xy 130.889975 -190.996606) (xy 130.944473 -190.99661) (xy 130.998415 -191.004369)
			(xy 131.050704 -191.019726) (xy 131.100276 -191.042368) (xy 131.14612 -191.071834) (xy 131.187305 -191.107525)
			(xy 131.222991 -191.148713) (xy 131.252452 -191.194561) (xy 131.275089 -191.244135) (xy 131.29044 -191.296426)
			(xy 131.298193 -191.350369) (xy 131.298193 -191.360298) (xy 132.865874 -191.360298) (xy 132.869945 -191.304676)
			(xy 132.882071 -191.250239) (xy 132.901994 -191.198148) (xy 132.92929 -191.149513) (xy 132.963376 -191.10537)
			(xy 133.003525 -191.066661) (xy 133.048883 -191.03421) (xy 133.098483 -191.008709) (xy 133.151267 -190.990702)
			(xy 133.20611 -190.980572) (xy 133.261844 -190.978535) (xy 133.317281 -190.984635) (xy 133.371238 -190.998741)
			(xy 133.422567 -191.020553) (xy 133.470173 -191.049607) (xy 133.513041 -191.085282) (xy 133.550258 -191.126819)
			(xy 133.581031 -191.173332) (xy 133.604703 -191.223829) (xy 133.620771 -191.277236) (xy 133.628891 -191.332412)
			(xy 133.6294 -191.360298) (xy 133.628891 -191.388184) (xy 133.620771 -191.44336) (xy 133.604703 -191.496767)
			(xy 133.581031 -191.547264) (xy 133.550258 -191.593777) (xy 133.513041 -191.635314) (xy 133.470173 -191.670989)
			(xy 133.422567 -191.700043) (xy 133.371238 -191.721855) (xy 133.317281 -191.735961) (xy 133.261844 -191.742061)
			(xy 133.20611 -191.740024) (xy 133.151267 -191.729894) (xy 133.098483 -191.711887) (xy 133.048883 -191.686386)
			(xy 133.003525 -191.653935) (xy 132.963376 -191.615226) (xy 132.92929 -191.571083) (xy 132.901994 -191.522448)
			(xy 132.882071 -191.470357) (xy 132.869945 -191.41592) (xy 132.865874 -191.360298) (xy 131.298193 -191.360298)
			(xy 131.298191 -191.404867) (xy 131.290432 -191.458809) (xy 131.275076 -191.511099) (xy 131.252435 -191.56067)
			(xy 131.222969 -191.606516) (xy 131.187279 -191.647701) (xy 131.146092 -191.683387) (xy 131.100244 -191.712849)
			(xy 131.050671 -191.735487) (xy 130.99838 -191.750839) (xy 130.944437 -191.758593) (xy 130.917188 -191.759078)
			(xy 130.903218 -191.758824) (xy 130.889805 -191.75871) (xy 130.863686 -191.764787) (xy 130.840047 -191.777452)
			(xy 130.820518 -191.795832) (xy 130.806445 -191.81866) (xy 130.798796 -191.844363) (xy 130.798099 -191.871172)
			(xy 130.800856 -191.8843) (xy 130.805823 -191.906254) (xy 130.811167 -191.950948) (xy 130.811524 -191.973454)
			(xy 130.811524 -191.974216) (xy 130.811028 -192.001468) (xy 130.803269 -192.055416) (xy 130.787911 -192.107711)
			(xy 130.765267 -192.157288) (xy 130.735799 -192.203138) (xy 130.700105 -192.244328) (xy 130.658912 -192.280018)
			(xy 130.61306 -192.309483) (xy 130.563481 -192.332122) (xy 130.511185 -192.347475) (xy 130.457236 -192.35523)
			(xy 130.402732 -192.355228) (xy 130.348784 -192.347469) (xy 130.296489 -192.332111) (xy 130.246912 -192.309467)
			(xy 130.201062 -192.279999) (xy 130.159872 -192.244305) (xy 130.124182 -192.203112) (xy 130.094717 -192.15726)
			(xy 130.072078 -192.107681) (xy 130.056725 -192.055385) (xy 130.04897 -192.001436) (xy 91.982544 -192.001436)
			(xy 91.982544 -193.001138) (xy 108.648244 -193.001138) (xy 108.652315 -192.945516) (xy 108.664441 -192.891079)
			(xy 108.684364 -192.838988) (xy 108.71166 -192.790353) (xy 108.745746 -192.74621) (xy 108.785895 -192.707501)
			(xy 108.831253 -192.67505) (xy 108.880853 -192.649549) (xy 108.933637 -192.631542) (xy 108.98848 -192.621412)
			(xy 109.044214 -192.619375) (xy 109.099651 -192.625475) (xy 109.153608 -192.639581) (xy 109.204937 -192.661393)
			(xy 109.252543 -192.690447) (xy 109.295411 -192.726122) (xy 109.332628 -192.767659) (xy 109.363401 -192.814172)
			(xy 109.387073 -192.864669) (xy 109.403141 -192.918076) (xy 109.411261 -192.973252) (xy 109.41177 -193.001138)
			(xy 109.411261 -193.029024) (xy 109.403141 -193.0842) (xy 109.387073 -193.137607) (xy 109.363401 -193.188104)
			(xy 109.332628 -193.234617) (xy 109.295411 -193.276154) (xy 109.252543 -193.311829) (xy 109.204937 -193.340883)
			(xy 109.153608 -193.362695) (xy 109.099651 -193.376801) (xy 109.044214 -193.382901) (xy 108.98848 -193.380864)
			(xy 108.933637 -193.370734) (xy 108.880853 -193.352727) (xy 108.831253 -193.327226) (xy 108.785895 -193.294775)
			(xy 108.745746 -193.256066) (xy 108.71166 -193.211923) (xy 108.684364 -193.163288) (xy 108.664441 -193.111197)
			(xy 108.652315 -193.05676) (xy 108.648244 -193.001138) (xy 91.982544 -193.001138) (xy 91.982544 -193.543428)
			(xy 131.837428 -193.543428) (xy 131.841499 -193.487806) (xy 131.853625 -193.433369) (xy 131.873548 -193.381278)
			(xy 131.900844 -193.332643) (xy 131.93493 -193.2885) (xy 131.975079 -193.249791) (xy 132.020437 -193.21734)
			(xy 132.070037 -193.191839) (xy 132.122821 -193.173832) (xy 132.177664 -193.163702) (xy 132.233398 -193.161665)
			(xy 132.288835 -193.167765) (xy 132.342792 -193.181871) (xy 132.394121 -193.203683) (xy 132.441727 -193.232737)
			(xy 132.484595 -193.268412) (xy 132.521812 -193.309949) (xy 132.552585 -193.356462) (xy 132.576257 -193.406959)
			(xy 132.592325 -193.460366) (xy 132.600445 -193.515542) (xy 132.600954 -193.543428) (xy 132.600445 -193.571314)
			(xy 132.592325 -193.62649) (xy 132.576257 -193.679897) (xy 132.552585 -193.730394) (xy 132.521812 -193.776907)
			(xy 132.484595 -193.818444) (xy 132.441727 -193.854119) (xy 132.394121 -193.883173) (xy 132.342792 -193.904985)
			(xy 132.288835 -193.919091) (xy 132.233398 -193.925191) (xy 132.177664 -193.923154) (xy 132.122821 -193.913024)
			(xy 132.070037 -193.895017) (xy 132.020437 -193.869516) (xy 131.975079 -193.837065) (xy 131.93493 -193.798356)
			(xy 131.900844 -193.754213) (xy 131.873548 -193.705578) (xy 131.853625 -193.653487) (xy 131.841499 -193.59905)
			(xy 131.837428 -193.543428) (xy 91.982544 -193.543428) (xy 91.982544 -194.128644) (xy 91.982805 -194.136377)
			(xy 91.987451 -194.151127) (xy 91.991688 -194.1576) (xy 92.011664 -194.187336) (xy 92.045053 -194.250716)
			(xy 92.070527 -194.317671) (xy 92.08771 -194.387217) (xy 92.09635 -194.458331) (xy 92.096844 -194.49415)
			(xy 92.096844 -194.989958) (xy 92.096787 -194.993768) (xy 93.702632 -194.993768) (xy 93.702632 -194.591432)
			(xy 93.70312 -194.56409) (xy 93.710902 -194.509963) (xy 93.726308 -194.457494) (xy 93.749025 -194.407752)
			(xy 93.778589 -194.361749) (xy 93.814399 -194.320421) (xy 93.855727 -194.284611) (xy 93.90173 -194.255047)
			(xy 93.951472 -194.23233) (xy 94.003941 -194.216924) (xy 94.058068 -194.209142) (xy 94.112752 -194.209142)
			(xy 94.166879 -194.216924) (xy 94.219348 -194.23233) (xy 94.26909 -194.255047) (xy 94.315093 -194.284611)
			(xy 94.356421 -194.320421) (xy 94.392231 -194.361749) (xy 94.421795 -194.407752) (xy 94.444512 -194.457494)
			(xy 94.459918 -194.509963) (xy 94.4677 -194.56409) (xy 94.468188 -194.591432) (xy 94.468188 -194.640708)
			(xy 94.468681 -194.650715) (xy 94.476341 -194.669204) (xy 94.490492 -194.683356) (xy 94.508981 -194.691018)
			(xy 94.518988 -194.691508) (xy 94.53118 -194.691508) (xy 94.55277 -194.680332) (xy 94.559882 -194.670426)
			(xy 94.575317 -194.649819) (xy 94.610863 -194.612572) (xy 94.651093 -194.580439) (xy 94.695275 -194.554004)
			(xy 94.742609 -194.533746) (xy 94.792237 -194.520033) (xy 94.843257 -194.513114) (xy 94.869 -194.512692)
			(xy 94.895314 -194.513162) (xy 94.947442 -194.520397) (xy 94.998085 -194.534715) (xy 95.046284 -194.555847)
			(xy 95.091127 -194.583393) (xy 95.131767 -194.616831) (xy 95.149924 -194.635882) (xy 95.157437 -194.643294)
			(xy 95.176724 -194.651813) (xy 95.187262 -194.652392) (xy 95.261938 -194.652392) (xy 95.272486 -194.651845)
			(xy 95.291781 -194.643323) (xy 95.299276 -194.635882) (xy 95.317447 -194.616842) (xy 95.358074 -194.583384)
			(xy 95.402911 -194.555823) (xy 95.451109 -194.534682) (xy 95.501753 -194.520362) (xy 95.553885 -194.513133)
			(xy 95.5802 -194.512692) (xy 95.607451 -194.513178) (xy 95.661399 -194.520934) (xy 95.713694 -194.536289)
			(xy 95.763271 -194.558931) (xy 95.809121 -194.588397) (xy 95.850312 -194.624088) (xy 95.886003 -194.665279)
			(xy 95.915469 -194.711129) (xy 95.938111 -194.760706) (xy 95.953466 -194.813001) (xy 95.961222 -194.866949)
			(xy 95.961222 -194.921451) (xy 95.953466 -194.975399) (xy 95.938111 -195.027694) (xy 95.915469 -195.077271)
			(xy 95.886003 -195.123121) (xy 95.850312 -195.164312) (xy 95.809121 -195.200003) (xy 95.763271 -195.229469)
			(xy 95.713694 -195.252111) (xy 95.661399 -195.267466) (xy 95.607451 -195.275222) (xy 95.5802 -195.275708)
			(xy 95.553886 -195.275238) (xy 95.501758 -195.268003) (xy 95.451115 -195.253685) (xy 95.402916 -195.232553)
			(xy 95.358073 -195.205007) (xy 95.317433 -195.171569) (xy 95.299276 -195.152518) (xy 95.291763 -195.145106)
			(xy 95.272476 -195.136587) (xy 95.261938 -195.136008) (xy 95.187262 -195.136008) (xy 95.176714 -195.136555)
			(xy 95.157419 -195.145077) (xy 95.149924 -195.152518) (xy 95.127682 -195.175712) (xy 95.076865 -195.21504)
			(xy 95.048832 -195.23075) (xy 95.038164 -195.236338) (xy 95.024194 -195.255896) (xy 95.010732 -195.34886)
			(xy 95.009604 -195.360677) (xy 95.017036 -195.383195) (xy 95.024956 -195.39204) (xy 95.145352 -195.51269)
			(xy 95.152776 -195.5195) (xy 95.171357 -195.527238) (xy 95.18142 -195.527676) (xy 95.988632 -195.527676)
			(xy 95.999353 -195.527228) (xy 96.018957 -195.518562) (xy 96.026478 -195.510912) (xy 96.084136 -195.44665)
			(xy 96.09074 -195.42633) (xy 96.089724 -195.415662) (xy 96.087692 -195.3768) (xy 96.088178 -195.349549)
			(xy 96.095934 -195.295601) (xy 96.111289 -195.243306) (xy 96.133931 -195.193729) (xy 96.163397 -195.147879)
			(xy 96.199088 -195.106688) (xy 96.240279 -195.070997) (xy 96.286129 -195.041531) (xy 96.335706 -195.018889)
			(xy 96.388001 -195.003534) (xy 96.441949 -194.995778) (xy 96.496451 -194.995778) (xy 96.550399 -195.003534)
			(xy 96.602694 -195.018889) (xy 96.652271 -195.041531) (xy 96.698121 -195.070997) (xy 96.739312 -195.106688)
			(xy 96.775003 -195.147879) (xy 96.804469 -195.193729) (xy 96.827111 -195.243306) (xy 96.842466 -195.295601)
			(xy 96.850222 -195.349549) (xy 96.850708 -195.3768) (xy 96.848676 -195.415662) (xy 96.84766 -195.42633)
			(xy 96.854264 -195.44665) (xy 96.911922 -195.510912) (xy 96.919528 -195.518447) (xy 96.939078 -195.52711)
			(xy 96.949768 -195.527676) (xy 99.101148 -195.527676) (xy 99.131211 -195.528238) (xy 99.1906 -195.537626)
			(xy 99.247787 -195.556194) (xy 99.301363 -195.583485) (xy 99.350006 -195.618826) (xy 99.371658 -195.63969)
			(xy 99.458056 -195.726088) (xy 126.922185 -195.726088) (xy 126.922185 -195.666112) (xy 126.930014 -195.606648)
			(xy 126.945538 -195.548715) (xy 126.968491 -195.493304) (xy 126.99848 -195.441364) (xy 127.034993 -195.393782)
			(xy 127.077404 -195.351373) (xy 127.124989 -195.314864) (xy 127.176931 -195.284878) (xy 127.232344 -195.261928)
			(xy 127.290278 -195.246408) (xy 127.349742 -195.238583) (xy 127.37973 -195.238116) (xy 128.24333 -195.238116)
			(xy 128.273312 -195.238652) (xy 128.332761 -195.246482) (xy 128.39068 -195.262005) (xy 128.446078 -195.284955)
			(xy 128.498007 -195.314939) (xy 128.545577 -195.351444) (xy 128.587976 -195.393845) (xy 128.624478 -195.441418)
			(xy 128.654459 -195.493349) (xy 128.677405 -195.548748) (xy 128.692924 -195.606668) (xy 128.70075 -195.666118)
			(xy 128.70075 -195.726082) (xy 128.692924 -195.785532) (xy 128.677405 -195.843452) (xy 128.654459 -195.898851)
			(xy 128.624478 -195.950782) (xy 128.587976 -195.998355) (xy 128.545577 -196.040756) (xy 128.498007 -196.077261)
			(xy 128.446078 -196.107245) (xy 128.39068 -196.130195) (xy 128.332761 -196.145718) (xy 128.273312 -196.153548)
			(xy 128.24333 -196.15404) (xy 127.37973 -196.15404) (xy 127.349742 -196.153617) (xy 127.290278 -196.145792)
			(xy 127.232344 -196.130272) (xy 127.176931 -196.107322) (xy 127.124989 -196.077336) (xy 127.077404 -196.040827)
			(xy 127.034993 -195.998418) (xy 126.99848 -195.950836) (xy 126.968491 -195.898896) (xy 126.945538 -195.843485)
			(xy 126.930014 -195.785552) (xy 126.922185 -195.726088) (xy 99.458056 -195.726088) (xy 100.082858 -196.35089)
			(xy 100.09028 -196.357703) (xy 100.108862 -196.365439) (xy 100.118926 -196.365876) (xy 110.236 -196.365876)
			(xy 110.266065 -196.366405) (xy 110.325455 -196.375801) (xy 110.380133 -196.393562) (xy 130.059936 -196.393562)
			(xy 130.064007 -196.33794) (xy 130.076133 -196.283503) (xy 130.096056 -196.231412) (xy 130.123352 -196.182777)
			(xy 130.157438 -196.138634) (xy 130.197587 -196.099925) (xy 130.242945 -196.067474) (xy 130.292545 -196.041973)
			(xy 130.345329 -196.023966) (xy 130.400172 -196.013836) (xy 130.455906 -196.011799) (xy 130.511343 -196.017899)
			(xy 130.5653 -196.032005) (xy 130.616629 -196.053817) (xy 130.664235 -196.082871) (xy 130.707103 -196.118546)
			(xy 130.74432 -196.160083) (xy 130.775093 -196.206596) (xy 130.798765 -196.257093) (xy 130.814833 -196.3105)
			(xy 130.822953 -196.365676) (xy 130.823462 -196.393562) (xy 130.822953 -196.421448) (xy 130.820104 -196.440806)
			(xy 131.909564 -196.440806) (xy 131.913635 -196.385184) (xy 131.925761 -196.330747) (xy 131.945684 -196.278656)
			(xy 131.97298 -196.230021) (xy 132.007066 -196.185878) (xy 132.047215 -196.147169) (xy 132.092573 -196.114718)
			(xy 132.142173 -196.089217) (xy 132.194957 -196.07121) (xy 132.2498 -196.06108) (xy 132.305534 -196.059043)
			(xy 132.360971 -196.065143) (xy 132.414928 -196.079249) (xy 132.466257 -196.101061) (xy 132.513863 -196.130115)
			(xy 132.556731 -196.16579) (xy 132.584437 -196.196712) (xy 136.162794 -196.196712) (xy 136.166865 -196.14109)
			(xy 136.178991 -196.086653) (xy 136.198914 -196.034562) (xy 136.22621 -195.985927) (xy 136.260296 -195.941784)
			(xy 136.300445 -195.903075) (xy 136.345803 -195.870624) (xy 136.395403 -195.845123) (xy 136.448187 -195.827116)
			(xy 136.50303 -195.816986) (xy 136.558764 -195.814949) (xy 136.614201 -195.821049) (xy 136.668158 -195.835155)
			(xy 136.719487 -195.856967) (xy 136.767093 -195.886021) (xy 136.809961 -195.921696) (xy 136.847178 -195.963233)
			(xy 136.877951 -196.009746) (xy 136.901623 -196.060243) (xy 136.917691 -196.11365) (xy 136.925811 -196.168826)
			(xy 136.92632 -196.196712) (xy 136.925811 -196.224598) (xy 136.917691 -196.279774) (xy 136.901623 -196.333181)
			(xy 136.877951 -196.383678) (xy 136.847178 -196.430191) (xy 136.809961 -196.471728) (xy 136.767093 -196.507403)
			(xy 136.719487 -196.536457) (xy 136.668158 -196.558269) (xy 136.614201 -196.572375) (xy 136.558764 -196.578475)
			(xy 136.50303 -196.576438) (xy 136.448187 -196.566308) (xy 136.395403 -196.548301) (xy 136.345803 -196.5228)
			(xy 136.300445 -196.490349) (xy 136.260296 -196.45164) (xy 136.22621 -196.407497) (xy 136.198914 -196.358862)
			(xy 136.178991 -196.306771) (xy 136.166865 -196.252334) (xy 136.162794 -196.196712) (xy 132.584437 -196.196712)
			(xy 132.593948 -196.207327) (xy 132.624721 -196.25384) (xy 132.648393 -196.304337) (xy 132.664461 -196.357744)
			(xy 132.672581 -196.41292) (xy 132.67309 -196.440806) (xy 132.672581 -196.468692) (xy 132.664461 -196.523868)
			(xy 132.648393 -196.577275) (xy 132.624721 -196.627772) (xy 132.593948 -196.674285) (xy 132.556731 -196.715822)
			(xy 132.513863 -196.751497) (xy 132.466257 -196.780551) (xy 132.414928 -196.802363) (xy 132.360971 -196.816469)
			(xy 132.305534 -196.822569) (xy 132.2498 -196.820532) (xy 132.194957 -196.810402) (xy 132.142173 -196.792395)
			(xy 132.092573 -196.766894) (xy 132.047215 -196.734443) (xy 132.007066 -196.695734) (xy 131.97298 -196.651591)
			(xy 131.945684 -196.602956) (xy 131.925761 -196.550865) (xy 131.913635 -196.496428) (xy 131.909564 -196.440806)
			(xy 130.820104 -196.440806) (xy 130.814833 -196.476624) (xy 130.798765 -196.530031) (xy 130.775093 -196.580528)
			(xy 130.74432 -196.627041) (xy 130.707103 -196.668578) (xy 130.664235 -196.704253) (xy 130.616629 -196.733307)
			(xy 130.5653 -196.755119) (xy 130.511343 -196.769225) (xy 130.455906 -196.775325) (xy 130.400172 -196.773288)
			(xy 130.345329 -196.763158) (xy 130.292545 -196.745151) (xy 130.242945 -196.71965) (xy 130.197587 -196.687199)
			(xy 130.157438 -196.64849) (xy 130.123352 -196.604347) (xy 130.096056 -196.555712) (xy 130.076133 -196.503621)
			(xy 130.064007 -196.449184) (xy 130.059936 -196.393562) (xy 110.380133 -196.393562) (xy 110.382642 -196.394377)
			(xy 110.436217 -196.421676) (xy 110.484859 -196.457023) (xy 110.50651 -196.47789) (xy 113.118138 -199.089518)
			(xy 127.763014 -199.089518) (xy 127.767085 -199.033896) (xy 127.779211 -198.979459) (xy 127.799134 -198.927368)
			(xy 127.82643 -198.878733) (xy 127.860516 -198.83459) (xy 127.900665 -198.795881) (xy 127.946023 -198.76343)
			(xy 127.995623 -198.737929) (xy 128.048407 -198.719922) (xy 128.10325 -198.709792) (xy 128.158984 -198.707755)
			(xy 128.214421 -198.713855) (xy 128.268378 -198.727961) (xy 128.319707 -198.749773) (xy 128.367313 -198.778827)
			(xy 128.410181 -198.814502) (xy 128.447398 -198.856039) (xy 128.478171 -198.902552) (xy 128.501843 -198.953049)
			(xy 128.502323 -198.954644) (xy 129.990594 -198.954644) (xy 129.994665 -198.899022) (xy 130.006791 -198.844585)
			(xy 130.026714 -198.792494) (xy 130.05401 -198.743859) (xy 130.088096 -198.699716) (xy 130.128245 -198.661007)
			(xy 130.173603 -198.628556) (xy 130.223203 -198.603055) (xy 130.275987 -198.585048) (xy 130.33083 -198.574918)
			(xy 130.386564 -198.572881) (xy 130.442001 -198.578981) (xy 130.495958 -198.593087) (xy 130.547287 -198.614899)
			(xy 130.594893 -198.643953) (xy 130.637761 -198.679628) (xy 130.674978 -198.721165) (xy 130.67871 -198.726806)
			(xy 136.638028 -198.726806) (xy 136.642099 -198.671184) (xy 136.654225 -198.616747) (xy 136.674148 -198.564656)
			(xy 136.701444 -198.516021) (xy 136.73553 -198.471878) (xy 136.775679 -198.433169) (xy 136.821037 -198.400718)
			(xy 136.870637 -198.375217) (xy 136.923421 -198.35721) (xy 136.978264 -198.34708) (xy 137.033998 -198.345043)
			(xy 137.089435 -198.351143) (xy 137.143392 -198.365249) (xy 137.194721 -198.387061) (xy 137.242327 -198.416115)
			(xy 137.285195 -198.45179) (xy 137.322412 -198.493327) (xy 137.353185 -198.53984) (xy 137.376857 -198.590337)
			(xy 137.392925 -198.643744) (xy 137.401045 -198.69892) (xy 137.401554 -198.726806) (xy 137.401045 -198.754692)
			(xy 137.392925 -198.809868) (xy 137.376857 -198.863275) (xy 137.353185 -198.913772) (xy 137.322412 -198.960285)
			(xy 137.285195 -199.001822) (xy 137.242327 -199.037497) (xy 137.194721 -199.066551) (xy 137.143392 -199.088363)
			(xy 137.089435 -199.102469) (xy 137.033998 -199.108569) (xy 136.978264 -199.106532) (xy 136.923421 -199.096402)
			(xy 136.870637 -199.078395) (xy 136.821037 -199.052894) (xy 136.775679 -199.020443) (xy 136.73553 -198.981734)
			(xy 136.701444 -198.937591) (xy 136.674148 -198.888956) (xy 136.654225 -198.836865) (xy 136.642099 -198.782428)
			(xy 136.638028 -198.726806) (xy 130.67871 -198.726806) (xy 130.705751 -198.767678) (xy 130.729423 -198.818175)
			(xy 130.745491 -198.871582) (xy 130.753611 -198.926758) (xy 130.75412 -198.954644) (xy 130.753611 -198.98253)
			(xy 130.745491 -199.037706) (xy 130.729423 -199.091113) (xy 130.705751 -199.14161) (xy 130.674978 -199.188123)
			(xy 130.637761 -199.22966) (xy 130.595562 -199.264778) (xy 144.901918 -199.264778) (xy 144.905989 -199.209156)
			(xy 144.918115 -199.154719) (xy 144.938038 -199.102628) (xy 144.965334 -199.053993) (xy 144.99942 -199.00985)
			(xy 145.039569 -198.971141) (xy 145.084927 -198.93869) (xy 145.134527 -198.913189) (xy 145.187311 -198.895182)
			(xy 145.242154 -198.885052) (xy 145.297888 -198.883015) (xy 145.353325 -198.889115) (xy 145.407282 -198.903221)
			(xy 145.458611 -198.925033) (xy 145.506217 -198.954087) (xy 145.549085 -198.989762) (xy 145.586302 -199.031299)
			(xy 145.617075 -199.077812) (xy 145.640747 -199.128309) (xy 145.656815 -199.181716) (xy 145.664935 -199.236892)
			(xy 145.665444 -199.264778) (xy 145.664935 -199.292664) (xy 145.656815 -199.34784) (xy 145.640747 -199.401247)
			(xy 145.617075 -199.451744) (xy 145.586302 -199.498257) (xy 145.549085 -199.539794) (xy 145.506217 -199.575469)
			(xy 145.458611 -199.604523) (xy 145.407282 -199.626335) (xy 145.353325 -199.640441) (xy 145.297888 -199.646541)
			(xy 145.242154 -199.644504) (xy 145.187311 -199.634374) (xy 145.134527 -199.616367) (xy 145.084927 -199.590866)
			(xy 145.039569 -199.558415) (xy 144.99942 -199.519706) (xy 144.965334 -199.475563) (xy 144.938038 -199.426928)
			(xy 144.918115 -199.374837) (xy 144.905989 -199.3204) (xy 144.901918 -199.264778) (xy 130.595562 -199.264778)
			(xy 130.594893 -199.265335) (xy 130.547287 -199.294389) (xy 130.495958 -199.316201) (xy 130.442001 -199.330307)
			(xy 130.386564 -199.336407) (xy 130.33083 -199.33437) (xy 130.275987 -199.32424) (xy 130.223203 -199.306233)
			(xy 130.173603 -199.280732) (xy 130.128245 -199.248281) (xy 130.088096 -199.209572) (xy 130.05401 -199.165429)
			(xy 130.026714 -199.116794) (xy 130.006791 -199.064703) (xy 129.994665 -199.010266) (xy 129.990594 -198.954644)
			(xy 128.502323 -198.954644) (xy 128.517911 -199.006456) (xy 128.526031 -199.061632) (xy 128.52654 -199.089518)
			(xy 128.526031 -199.117404) (xy 128.517911 -199.17258) (xy 128.501843 -199.225987) (xy 128.478171 -199.276484)
			(xy 128.447398 -199.322997) (xy 128.410181 -199.364534) (xy 128.367313 -199.400209) (xy 128.319707 -199.429263)
			(xy 128.268378 -199.451075) (xy 128.214421 -199.465181) (xy 128.158984 -199.471281) (xy 128.10325 -199.469244)
			(xy 128.048407 -199.459114) (xy 127.995623 -199.441107) (xy 127.946023 -199.415606) (xy 127.900665 -199.383155)
			(xy 127.860516 -199.344446) (xy 127.82643 -199.300303) (xy 127.799134 -199.251668) (xy 127.779211 -199.199577)
			(xy 127.767085 -199.14514) (xy 127.763014 -199.089518) (xy 113.118138 -199.089518) (xy 114.469926 -200.441306)
			(xy 127.796796 -200.441306) (xy 127.800867 -200.385684) (xy 127.812993 -200.331247) (xy 127.832916 -200.279156)
			(xy 127.860212 -200.230521) (xy 127.894298 -200.186378) (xy 127.934447 -200.147669) (xy 127.979805 -200.115218)
			(xy 128.029405 -200.089717) (xy 128.082189 -200.07171) (xy 128.137032 -200.06158) (xy 128.192766 -200.059543)
			(xy 128.248203 -200.065643) (xy 128.30216 -200.079749) (xy 128.353489 -200.101561) (xy 128.401095 -200.130615)
			(xy 128.443963 -200.16629) (xy 128.48118 -200.207827) (xy 128.511953 -200.25434) (xy 128.535625 -200.304837)
			(xy 128.551693 -200.358244) (xy 128.559813 -200.41342) (xy 128.560322 -200.441306) (xy 128.559813 -200.469192)
			(xy 128.551693 -200.524368) (xy 128.535625 -200.577775) (xy 128.511953 -200.628272) (xy 128.48118 -200.674785)
			(xy 128.443963 -200.716322) (xy 128.401095 -200.751997) (xy 128.353489 -200.781051) (xy 128.30216 -200.802863)
			(xy 128.248203 -200.816969) (xy 128.192766 -200.823069) (xy 128.137032 -200.821032) (xy 128.082189 -200.810902)
			(xy 128.029405 -200.792895) (xy 127.979805 -200.767394) (xy 127.934447 -200.734943) (xy 127.894298 -200.696234)
			(xy 127.860212 -200.652091) (xy 127.832916 -200.603456) (xy 127.812993 -200.551365) (xy 127.800867 -200.496928)
			(xy 127.796796 -200.441306) (xy 114.469926 -200.441306) (xy 115.507516 -201.478896) (xy 128.184146 -201.478896)
			(xy 128.188217 -201.423274) (xy 128.200343 -201.368837) (xy 128.220266 -201.316746) (xy 128.247562 -201.268111)
			(xy 128.281648 -201.223968) (xy 128.321797 -201.185259) (xy 128.367155 -201.152808) (xy 128.416755 -201.127307)
			(xy 128.469539 -201.1093) (xy 128.524382 -201.09917) (xy 128.580116 -201.097133) (xy 128.635553 -201.103233)
			(xy 128.68951 -201.117339) (xy 128.740839 -201.139151) (xy 128.788445 -201.168205) (xy 128.831313 -201.20388)
			(xy 128.86853 -201.245417) (xy 128.899303 -201.29193) (xy 128.922975 -201.342427) (xy 128.939043 -201.395834)
			(xy 128.947163 -201.45101) (xy 128.947672 -201.478896) (xy 128.947163 -201.506782) (xy 128.939043 -201.561958)
			(xy 128.922975 -201.615365) (xy 128.907767 -201.647806) (xy 136.924794 -201.647806) (xy 136.928865 -201.592184)
			(xy 136.940991 -201.537747) (xy 136.960914 -201.485656) (xy 136.98821 -201.437021) (xy 137.022296 -201.392878)
			(xy 137.062445 -201.354169) (xy 137.107803 -201.321718) (xy 137.157403 -201.296217) (xy 137.210187 -201.27821)
			(xy 137.26503 -201.26808) (xy 137.320764 -201.266043) (xy 137.376201 -201.272143) (xy 137.430158 -201.286249)
			(xy 137.481487 -201.308061) (xy 137.529093 -201.337115) (xy 137.571961 -201.37279) (xy 137.609178 -201.414327)
			(xy 137.639951 -201.46084) (xy 137.663623 -201.511337) (xy 137.679691 -201.564744) (xy 137.687811 -201.61992)
			(xy 137.688255 -201.64425) (xy 137.924792 -201.64425) (xy 137.928863 -201.588628) (xy 137.940989 -201.534191)
			(xy 137.960912 -201.4821) (xy 137.988208 -201.433465) (xy 138.022294 -201.389322) (xy 138.062443 -201.350613)
			(xy 138.107801 -201.318162) (xy 138.157401 -201.292661) (xy 138.210185 -201.274654) (xy 138.265028 -201.264524)
			(xy 138.320762 -201.262487) (xy 138.376199 -201.268587) (xy 138.430156 -201.282693) (xy 138.481485 -201.304505)
			(xy 138.529091 -201.333559) (xy 138.571959 -201.369234) (xy 138.609176 -201.410771) (xy 138.639949 -201.457284)
			(xy 138.663621 -201.507781) (xy 138.679689 -201.561188) (xy 138.686979 -201.610722) (xy 139.424662 -201.610722)
			(xy 139.428733 -201.5551) (xy 139.440859 -201.500663) (xy 139.460782 -201.448572) (xy 139.488078 -201.399937)
			(xy 139.522164 -201.355794) (xy 139.562313 -201.317085) (xy 139.607671 -201.284634) (xy 139.657271 -201.259133)
			(xy 139.710055 -201.241126) (xy 139.764898 -201.230996) (xy 139.820632 -201.228959) (xy 139.876069 -201.235059)
			(xy 139.930026 -201.249165) (xy 139.981355 -201.270977) (xy 140.028961 -201.300031) (xy 140.071829 -201.335706)
			(xy 140.109046 -201.377243) (xy 140.139819 -201.423756) (xy 140.163491 -201.474253) (xy 140.179559 -201.52766)
			(xy 140.187679 -201.582836) (xy 140.188188 -201.610722) (xy 140.924786 -201.610722) (xy 140.928857 -201.5551)
			(xy 140.940983 -201.500663) (xy 140.960906 -201.448572) (xy 140.988202 -201.399937) (xy 141.022288 -201.355794)
			(xy 141.062437 -201.317085) (xy 141.107795 -201.284634) (xy 141.157395 -201.259133) (xy 141.210179 -201.241126)
			(xy 141.265022 -201.230996) (xy 141.320756 -201.228959) (xy 141.376193 -201.235059) (xy 141.43015 -201.249165)
			(xy 141.481479 -201.270977) (xy 141.529085 -201.300031) (xy 141.571953 -201.335706) (xy 141.60917 -201.377243)
			(xy 141.639943 -201.423756) (xy 141.663615 -201.474253) (xy 141.679683 -201.52766) (xy 141.687803 -201.582836)
			(xy 141.688312 -201.610722) (xy 141.687803 -201.638608) (xy 141.679683 -201.693784) (xy 141.663615 -201.747191)
			(xy 141.639943 -201.797688) (xy 141.60917 -201.844201) (xy 141.571953 -201.885738) (xy 141.529085 -201.921413)
			(xy 141.481479 -201.950467) (xy 141.43015 -201.972279) (xy 141.376193 -201.986385) (xy 141.320756 -201.992485)
			(xy 141.265022 -201.990448) (xy 141.210179 -201.980318) (xy 141.157395 -201.962311) (xy 141.107795 -201.93681)
			(xy 141.062437 -201.904359) (xy 141.022288 -201.86565) (xy 140.988202 -201.821507) (xy 140.960906 -201.772872)
			(xy 140.940983 -201.720781) (xy 140.928857 -201.666344) (xy 140.924786 -201.610722) (xy 140.188188 -201.610722)
			(xy 140.187679 -201.638608) (xy 140.179559 -201.693784) (xy 140.163491 -201.747191) (xy 140.139819 -201.797688)
			(xy 140.109046 -201.844201) (xy 140.071829 -201.885738) (xy 140.028961 -201.921413) (xy 139.981355 -201.950467)
			(xy 139.930026 -201.972279) (xy 139.876069 -201.986385) (xy 139.820632 -201.992485) (xy 139.764898 -201.990448)
			(xy 139.710055 -201.980318) (xy 139.657271 -201.962311) (xy 139.607671 -201.93681) (xy 139.562313 -201.904359)
			(xy 139.522164 -201.86565) (xy 139.488078 -201.821507) (xy 139.460782 -201.772872) (xy 139.440859 -201.720781)
			(xy 139.428733 -201.666344) (xy 139.424662 -201.610722) (xy 138.686979 -201.610722) (xy 138.687809 -201.616364)
			(xy 138.688318 -201.64425) (xy 138.687809 -201.672136) (xy 138.679689 -201.727312) (xy 138.663621 -201.780719)
			(xy 138.639949 -201.831216) (xy 138.609176 -201.877729) (xy 138.571959 -201.919266) (xy 138.529091 -201.954941)
			(xy 138.481485 -201.983995) (xy 138.430156 -202.005807) (xy 138.376199 -202.019913) (xy 138.320762 -202.026013)
			(xy 138.265028 -202.023976) (xy 138.210185 -202.013846) (xy 138.157401 -201.995839) (xy 138.107801 -201.970338)
			(xy 138.062443 -201.937887) (xy 138.022294 -201.899178) (xy 137.988208 -201.855035) (xy 137.960912 -201.8064)
			(xy 137.940989 -201.754309) (xy 137.928863 -201.699872) (xy 137.924792 -201.64425) (xy 137.688255 -201.64425)
			(xy 137.68832 -201.647806) (xy 137.687811 -201.675692) (xy 137.679691 -201.730868) (xy 137.663623 -201.784275)
			(xy 137.639951 -201.834772) (xy 137.609178 -201.881285) (xy 137.571961 -201.922822) (xy 137.529093 -201.958497)
			(xy 137.481487 -201.987551) (xy 137.430158 -202.009363) (xy 137.376201 -202.023469) (xy 137.320764 -202.029569)
			(xy 137.26503 -202.027532) (xy 137.210187 -202.017402) (xy 137.157403 -201.999395) (xy 137.107803 -201.973894)
			(xy 137.062445 -201.941443) (xy 137.022296 -201.902734) (xy 136.98821 -201.858591) (xy 136.960914 -201.809956)
			(xy 136.940991 -201.757865) (xy 136.928865 -201.703428) (xy 136.924794 -201.647806) (xy 128.907767 -201.647806)
			(xy 128.899303 -201.665862) (xy 128.86853 -201.712375) (xy 128.831313 -201.753912) (xy 128.788445 -201.789587)
			(xy 128.740839 -201.818641) (xy 128.68951 -201.840453) (xy 128.635553 -201.854559) (xy 128.580116 -201.860659)
			(xy 128.524382 -201.858622) (xy 128.469539 -201.848492) (xy 128.416755 -201.830485) (xy 128.367155 -201.804984)
			(xy 128.321797 -201.772533) (xy 128.281648 -201.733824) (xy 128.247562 -201.689681) (xy 128.220266 -201.641046)
			(xy 128.200343 -201.588955) (xy 128.188217 -201.534518) (xy 128.184146 -201.478896) (xy 115.507516 -201.478896)
			(xy 116.201274 -202.172654) (xy 131.671247 -202.172654) (xy 131.671247 -202.118146) (xy 131.679005 -202.064193)
			(xy 131.694362 -202.011893) (xy 131.717006 -201.962311) (xy 131.746476 -201.916456) (xy 131.782172 -201.875262)
			(xy 131.823367 -201.839567) (xy 131.869223 -201.810099) (xy 131.918806 -201.787457) (xy 131.971106 -201.772102)
			(xy 132.02506 -201.764346) (xy 132.052314 -201.763884) (xy 132.081172 -201.764414) (xy 132.138229 -201.773109)
			(xy 132.193325 -201.7903) (xy 132.245204 -201.815594) (xy 132.29268 -201.848413) (xy 132.334672 -201.888009)
			(xy 132.37022 -201.933478) (xy 132.398514 -201.983783) (xy 132.418908 -202.037776) (xy 132.42544 -202.06589)
			(xy 132.428753 -202.079169) (xy 132.441318 -202.103467) (xy 132.459889 -202.123551) (xy 132.483131 -202.137976)
			(xy 132.509372 -202.145704) (xy 132.536722 -202.146178) (xy 132.563215 -202.139365) (xy 132.5753 -202.132946)
			(xy 132.597037 -202.120932) (xy 132.642964 -202.102025) (xy 132.690958 -202.089241) (xy 132.740205 -202.082797)
			(xy 132.765038 -202.0824) (xy 132.792288 -202.082872) (xy 132.846233 -202.090633) (xy 132.898524 -202.105992)
			(xy 132.948098 -202.128636) (xy 132.993944 -202.158104) (xy 133.035131 -202.193796) (xy 133.070819 -202.234986)
			(xy 133.100282 -202.280836) (xy 133.122921 -202.330412) (xy 133.138275 -202.382704) (xy 133.14603 -202.43665)
			(xy 133.14603 -202.49115) (xy 133.138275 -202.545096) (xy 133.122921 -202.597388) (xy 133.100282 -202.646964)
			(xy 133.070819 -202.692814) (xy 133.035131 -202.734004) (xy 132.993944 -202.769696) (xy 132.948098 -202.799164)
			(xy 132.898524 -202.821808) (xy 132.846233 -202.837167) (xy 132.792288 -202.844928) (xy 132.765038 -202.845416)
			(xy 132.736182 -202.844839) (xy 132.679126 -202.836151) (xy 132.624031 -202.818968) (xy 132.572153 -202.793681)
			(xy 132.524676 -202.760867) (xy 132.482684 -202.721277) (xy 132.447135 -202.675812) (xy 132.41884 -202.625511)
			(xy 132.398445 -202.571522) (xy 132.391912 -202.54341) (xy 132.388665 -202.530111) (xy 132.376092 -202.505805)
			(xy 132.357509 -202.485717) (xy 132.334255 -202.471292) (xy 132.308002 -202.463568) (xy 132.28064 -202.463102)
			(xy 132.25414 -202.469927) (xy 132.242052 -202.476354) (xy 132.220304 -202.488348) (xy 132.174381 -202.50726)
			(xy 132.126391 -202.520049) (xy 132.077146 -202.526499) (xy 132.052314 -202.5269) (xy 132.02506 -202.526454)
			(xy 131.971106 -202.518698) (xy 131.918806 -202.503343) (xy 131.869223 -202.480701) (xy 131.823367 -202.451233)
			(xy 131.782172 -202.415538) (xy 131.746476 -202.374344) (xy 131.717006 -202.328489) (xy 131.694362 -202.278907)
			(xy 131.679005 -202.226607) (xy 131.671247 -202.172654) (xy 116.201274 -202.172654) (xy 116.608352 -202.579732)
			(xy 123.927106 -202.579732) (xy 123.931177 -202.52411) (xy 123.943303 -202.469673) (xy 123.963226 -202.417582)
			(xy 123.990522 -202.368947) (xy 124.024608 -202.324804) (xy 124.064757 -202.286095) (xy 124.110115 -202.253644)
			(xy 124.159715 -202.228143) (xy 124.212499 -202.210136) (xy 124.267342 -202.200006) (xy 124.323076 -202.197969)
			(xy 124.378513 -202.204069) (xy 124.43247 -202.218175) (xy 124.483799 -202.239987) (xy 124.531405 -202.269041)
			(xy 124.574273 -202.304716) (xy 124.61149 -202.346253) (xy 124.642263 -202.392766) (xy 124.665935 -202.443263)
			(xy 124.682003 -202.49667) (xy 124.690123 -202.551846) (xy 124.690632 -202.579732) (xy 124.690123 -202.607618)
			(xy 124.682003 -202.662794) (xy 124.665935 -202.716201) (xy 124.642263 -202.766698) (xy 124.61149 -202.813211)
			(xy 124.574273 -202.854748) (xy 124.531405 -202.890423) (xy 124.483799 -202.919477) (xy 124.43247 -202.941289)
			(xy 124.378513 -202.955395) (xy 124.323076 -202.961495) (xy 124.267342 -202.959458) (xy 124.212499 -202.949328)
			(xy 124.159715 -202.931321) (xy 124.110115 -202.90582) (xy 124.064757 -202.873369) (xy 124.024608 -202.83466)
			(xy 123.990522 -202.790517) (xy 123.963226 -202.741882) (xy 123.943303 -202.689791) (xy 123.931177 -202.635354)
			(xy 123.927106 -202.579732) (xy 116.608352 -202.579732) (xy 117.10162 -203.073) (xy 118.820182 -203.073)
			(xy 118.824253 -203.017378) (xy 118.836379 -202.962941) (xy 118.856302 -202.91085) (xy 118.883598 -202.862215)
			(xy 118.917684 -202.818072) (xy 118.957833 -202.779363) (xy 119.003191 -202.746912) (xy 119.052791 -202.721411)
			(xy 119.105575 -202.703404) (xy 119.160418 -202.693274) (xy 119.216152 -202.691237) (xy 119.271589 -202.697337)
			(xy 119.325546 -202.711443) (xy 119.376875 -202.733255) (xy 119.424481 -202.762309) (xy 119.467349 -202.797984)
			(xy 119.504566 -202.839521) (xy 119.535339 -202.886034) (xy 119.559011 -202.936531) (xy 119.575079 -202.989938)
			(xy 119.583199 -203.045114) (xy 119.583708 -203.073) (xy 119.583199 -203.100886) (xy 119.575079 -203.156062)
			(xy 119.559011 -203.209469) (xy 119.535339 -203.259966) (xy 119.504566 -203.306479) (xy 119.467349 -203.348016)
			(xy 119.424481 -203.383691) (xy 119.376875 -203.412745) (xy 119.325546 -203.434557) (xy 119.271589 -203.448663)
			(xy 119.216152 -203.454763) (xy 119.160418 -203.452726) (xy 119.105575 -203.442596) (xy 119.052791 -203.424589)
			(xy 119.003191 -203.399088) (xy 118.957833 -203.366637) (xy 118.917684 -203.327928) (xy 118.883598 -203.283785)
			(xy 118.856302 -203.23515) (xy 118.836379 -203.183059) (xy 118.824253 -203.128622) (xy 118.820182 -203.073)
			(xy 117.10162 -203.073) (xy 118.264967 -204.236347) (xy 131.23092 -204.236347) (xy 131.23092 -204.181853)
			(xy 131.238675 -204.127913) (xy 131.254027 -204.075626) (xy 131.276665 -204.026056) (xy 131.306125 -203.980211)
			(xy 131.341811 -203.939026) (xy 131.382994 -203.903339) (xy 131.428836 -203.873875) (xy 131.478405 -203.851235)
			(xy 131.530691 -203.83588) (xy 131.584631 -203.828122) (xy 131.611878 -203.827634) (xy 131.638791 -203.828041)
			(xy 131.692078 -203.835629) (xy 131.743772 -203.850629) (xy 131.792844 -203.872743) (xy 131.838323 -203.901534)
			(xy 131.879305 -203.936429) (xy 131.914977 -203.976736) (xy 131.944632 -204.021656) (xy 131.967681 -204.070297)
			(xy 131.976114 -204.095858) (xy 131.976114 -204.096112) (xy 131.979894 -204.106129) (xy 131.994055 -204.122148)
			(xy 132.003546 -204.1271) (xy 132.082794 -204.163168) (xy 132.10413 -204.163422) (xy 132.11429 -204.15885)
			(xy 132.138638 -204.148583) (xy 132.189462 -204.134124) (xy 132.241794 -204.126805) (xy 132.268214 -204.126338)
			(xy 132.295468 -204.126733) (xy 132.349421 -204.134492) (xy 132.40172 -204.14985) (xy 132.451301 -204.172495)
			(xy 132.497156 -204.201965) (xy 132.538349 -204.237661) (xy 132.574043 -204.278856) (xy 132.603512 -204.324711)
			(xy 132.626155 -204.374293) (xy 132.641511 -204.426593) (xy 132.649268 -204.480546) (xy 132.649268 -204.535054)
			(xy 132.641511 -204.589007) (xy 132.626155 -204.641307) (xy 132.603512 -204.690889) (xy 132.574043 -204.736744)
			(xy 132.538349 -204.777939) (xy 132.497156 -204.813635) (xy 132.451301 -204.843105) (xy 132.40172 -204.86575)
			(xy 132.349421 -204.881108) (xy 132.295614 -204.888846) (xy 134.823198 -204.888846) (xy 134.827269 -204.833224)
			(xy 134.839395 -204.778787) (xy 134.859318 -204.726696) (xy 134.886614 -204.678061) (xy 134.9207 -204.633918)
			(xy 134.960849 -204.595209) (xy 135.006207 -204.562758) (xy 135.055807 -204.537257) (xy 135.108591 -204.51925)
			(xy 135.163434 -204.50912) (xy 135.219168 -204.507083) (xy 135.274605 -204.513183) (xy 135.328562 -204.527289)
			(xy 135.379891 -204.549101) (xy 135.427497 -204.578155) (xy 135.470365 -204.61383) (xy 135.507582 -204.655367)
			(xy 135.538355 -204.70188) (xy 135.562027 -204.752377) (xy 135.578095 -204.805784) (xy 135.586215 -204.86096)
			(xy 135.586724 -204.888846) (xy 135.586215 -204.916732) (xy 135.581348 -204.949806) (xy 142.112236 -204.949806)
			(xy 142.116307 -204.894184) (xy 142.128433 -204.839747) (xy 142.148356 -204.787656) (xy 142.175652 -204.739021)
			(xy 142.209738 -204.694878) (xy 142.249887 -204.656169) (xy 142.295245 -204.623718) (xy 142.344845 -204.598217)
			(xy 142.397629 -204.58021) (xy 142.452472 -204.57008) (xy 142.508206 -204.568043) (xy 142.563643 -204.574143)
			(xy 142.6176 -204.588249) (xy 142.668929 -204.610061) (xy 142.716535 -204.639115) (xy 142.759403 -204.67479)
			(xy 142.79662 -204.716327) (xy 142.827393 -204.76284) (xy 142.851065 -204.813337) (xy 142.867133 -204.866744)
			(xy 142.875253 -204.92192) (xy 142.875762 -204.949806) (xy 142.875253 -204.977692) (xy 142.867133 -205.032868)
			(xy 142.851065 -205.086275) (xy 142.827393 -205.136772) (xy 142.79662 -205.183285) (xy 142.759403 -205.224822)
			(xy 142.716535 -205.260497) (xy 142.668929 -205.289551) (xy 142.6176 -205.311363) (xy 142.563643 -205.325469)
			(xy 142.508206 -205.331569) (xy 142.452472 -205.329532) (xy 142.397629 -205.319402) (xy 142.344845 -205.301395)
			(xy 142.295245 -205.275894) (xy 142.249887 -205.243443) (xy 142.209738 -205.204734) (xy 142.175652 -205.160591)
			(xy 142.148356 -205.111956) (xy 142.128433 -205.059865) (xy 142.116307 -205.005428) (xy 142.112236 -204.949806)
			(xy 135.581348 -204.949806) (xy 135.578095 -204.971908) (xy 135.562027 -205.025315) (xy 135.538355 -205.075812)
			(xy 135.507582 -205.122325) (xy 135.470365 -205.163862) (xy 135.427497 -205.199537) (xy 135.379891 -205.228591)
			(xy 135.328562 -205.250403) (xy 135.274605 -205.264509) (xy 135.219168 -205.270609) (xy 135.163434 -205.268572)
			(xy 135.108591 -205.258442) (xy 135.055807 -205.240435) (xy 135.006207 -205.214934) (xy 134.960849 -205.182483)
			(xy 134.9207 -205.143774) (xy 134.886614 -205.099631) (xy 134.859318 -205.050996) (xy 134.839395 -204.998905)
			(xy 134.827269 -204.944468) (xy 134.823198 -204.888846) (xy 132.295614 -204.888846) (xy 132.295468 -204.888867)
			(xy 132.268214 -204.889354) (xy 132.241304 -204.888893) (xy 132.188021 -204.881306) (xy 132.136333 -204.866309)
			(xy 132.087263 -204.844199) (xy 132.041787 -204.815415) (xy 132.000805 -204.780528) (xy 131.965131 -204.74023)
			(xy 131.935472 -204.695319) (xy 131.912416 -204.646687) (xy 131.903978 -204.62113) (xy 131.903978 -204.620876)
			(xy 131.900206 -204.610855) (xy 131.886039 -204.594838) (xy 131.876546 -204.589888) (xy 131.797298 -204.55382)
			(xy 131.775962 -204.553566) (xy 131.765802 -204.558138) (xy 131.741455 -204.568407) (xy 131.69063 -204.582866)
			(xy 131.638298 -204.590184) (xy 131.611878 -204.59065) (xy 131.584631 -204.590078) (xy 131.530691 -204.58232)
			(xy 131.478405 -204.566965) (xy 131.428836 -204.544325) (xy 131.382994 -204.514861) (xy 131.341811 -204.479174)
			(xy 131.306125 -204.437989) (xy 131.276665 -204.392144) (xy 131.254027 -204.342574) (xy 131.238675 -204.290287)
			(xy 131.23092 -204.236347) (xy 118.264967 -204.236347) (xy 119.679466 -205.650846) (xy 137.982196 -205.650846)
			(xy 137.986267 -205.595224) (xy 137.998393 -205.540787) (xy 138.018316 -205.488696) (xy 138.045612 -205.440061)
			(xy 138.079698 -205.395918) (xy 138.119847 -205.357209) (xy 138.165205 -205.324758) (xy 138.214805 -205.299257)
			(xy 138.267589 -205.28125) (xy 138.322432 -205.27112) (xy 138.378166 -205.269083) (xy 138.433603 -205.275183)
			(xy 138.48756 -205.289289) (xy 138.538889 -205.311101) (xy 138.586495 -205.340155) (xy 138.629363 -205.37583)
			(xy 138.66658 -205.417367) (xy 138.697353 -205.46388) (xy 138.721025 -205.514377) (xy 138.737093 -205.567784)
			(xy 138.745213 -205.62296) (xy 138.745722 -205.650846) (xy 138.745213 -205.678732) (xy 138.737093 -205.733908)
			(xy 138.721025 -205.787315) (xy 138.697353 -205.837812) (xy 138.66658 -205.884325) (xy 138.629363 -205.925862)
			(xy 138.586495 -205.961537) (xy 138.538889 -205.990591) (xy 138.48756 -206.012403) (xy 138.433603 -206.026509)
			(xy 138.378166 -206.032609) (xy 138.322432 -206.030572) (xy 138.267589 -206.020442) (xy 138.214805 -206.002435)
			(xy 138.165205 -205.976934) (xy 138.119847 -205.944483) (xy 138.079698 -205.905774) (xy 138.045612 -205.861631)
			(xy 138.018316 -205.812996) (xy 137.998393 -205.760905) (xy 137.986267 -205.706468) (xy 137.982196 -205.650846)
			(xy 119.679466 -205.650846) (xy 120.269762 -206.241142) (xy 131.333492 -206.241142) (xy 131.337563 -206.18552)
			(xy 131.349689 -206.131083) (xy 131.369612 -206.078992) (xy 131.396908 -206.030357) (xy 131.430994 -205.986214)
			(xy 131.471143 -205.947505) (xy 131.516501 -205.915054) (xy 131.566101 -205.889553) (xy 131.618885 -205.871546)
			(xy 131.673728 -205.861416) (xy 131.729462 -205.859379) (xy 131.784899 -205.865479) (xy 131.838856 -205.879585)
			(xy 131.890185 -205.901397) (xy 131.937791 -205.930451) (xy 131.980659 -205.966126) (xy 132.017876 -206.007663)
			(xy 132.048649 -206.054176) (xy 132.072321 -206.104673) (xy 132.088389 -206.15808) (xy 132.096509 -206.213256)
			(xy 132.097018 -206.241142) (xy 132.096509 -206.269028) (xy 132.088389 -206.324204) (xy 132.072321 -206.377611)
			(xy 132.048649 -206.428108) (xy 132.024969 -206.4639) (xy 134.571484 -206.4639) (xy 134.575555 -206.408278)
			(xy 134.587681 -206.353841) (xy 134.607604 -206.30175) (xy 134.6349 -206.253115) (xy 134.668986 -206.208972)
			(xy 134.709135 -206.170263) (xy 134.754493 -206.137812) (xy 134.804093 -206.112311) (xy 134.856877 -206.094304)
			(xy 134.91172 -206.084174) (xy 134.967454 -206.082137) (xy 135.022891 -206.088237) (xy 135.076848 -206.102343)
			(xy 135.128177 -206.124155) (xy 135.175783 -206.153209) (xy 135.218651 -206.188884) (xy 135.255868 -206.230421)
			(xy 135.286641 -206.276934) (xy 135.310313 -206.327431) (xy 135.326381 -206.380838) (xy 135.334501 -206.436014)
			(xy 135.33501 -206.4639) (xy 135.334501 -206.491786) (xy 135.326381 -206.546962) (xy 135.310313 -206.600369)
			(xy 135.286641 -206.650866) (xy 135.255868 -206.697379) (xy 135.218651 -206.738916) (xy 135.175783 -206.774591)
			(xy 135.128177 -206.803645) (xy 135.076848 -206.825457) (xy 135.022891 -206.839563) (xy 134.967454 -206.845663)
			(xy 134.91172 -206.843626) (xy 134.856877 -206.833496) (xy 134.804093 -206.815489) (xy 134.754493 -206.789988)
			(xy 134.709135 -206.757537) (xy 134.668986 -206.718828) (xy 134.6349 -206.674685) (xy 134.607604 -206.62605)
			(xy 134.587681 -206.573959) (xy 134.575555 -206.519522) (xy 134.571484 -206.4639) (xy 132.024969 -206.4639)
			(xy 132.017876 -206.474621) (xy 131.980659 -206.516158) (xy 131.937791 -206.551833) (xy 131.890185 -206.580887)
			(xy 131.838856 -206.602699) (xy 131.784899 -206.616805) (xy 131.729462 -206.622905) (xy 131.673728 -206.620868)
			(xy 131.618885 -206.610738) (xy 131.566101 -206.592731) (xy 131.516501 -206.56723) (xy 131.471143 -206.534779)
			(xy 131.430994 -206.49607) (xy 131.396908 -206.451927) (xy 131.369612 -206.403292) (xy 131.349689 -206.351201)
			(xy 131.337563 -206.296764) (xy 131.333492 -206.241142) (xy 120.269762 -206.241142) (xy 120.983756 -206.955136)
			(xy 128.420112 -206.955136) (xy 128.424183 -206.899514) (xy 128.436309 -206.845077) (xy 128.456232 -206.792986)
			(xy 128.483528 -206.744351) (xy 128.517614 -206.700208) (xy 128.557763 -206.661499) (xy 128.603121 -206.629048)
			(xy 128.652721 -206.603547) (xy 128.705505 -206.58554) (xy 128.760348 -206.57541) (xy 128.816082 -206.573373)
			(xy 128.871519 -206.579473) (xy 128.925476 -206.593579) (xy 128.976805 -206.615391) (xy 129.024411 -206.644445)
			(xy 129.067279 -206.68012) (xy 129.104496 -206.721657) (xy 129.135269 -206.76817) (xy 129.158941 -206.818667)
			(xy 129.175009 -206.872074) (xy 129.183129 -206.92725) (xy 129.183638 -206.955136) (xy 129.183129 -206.983022)
			(xy 129.175009 -207.038198) (xy 129.158941 -207.091605) (xy 129.135269 -207.142102) (xy 129.104496 -207.188615)
			(xy 129.067279 -207.230152) (xy 129.024411 -207.265827) (xy 128.976805 -207.294881) (xy 128.925476 -207.316693)
			(xy 128.871519 -207.330799) (xy 128.816082 -207.336899) (xy 128.760348 -207.334862) (xy 128.705505 -207.324732)
			(xy 128.652721 -207.306725) (xy 128.603121 -207.281224) (xy 128.557763 -207.248773) (xy 128.517614 -207.210064)
			(xy 128.483528 -207.165921) (xy 128.456232 -207.117286) (xy 128.436309 -207.065195) (xy 128.424183 -207.010758)
			(xy 128.420112 -206.955136) (xy 120.983756 -206.955136) (xy 121.371106 -207.342486) (xy 138.016994 -207.342486)
			(xy 138.021065 -207.286864) (xy 138.033191 -207.232427) (xy 138.053114 -207.180336) (xy 138.08041 -207.131701)
			(xy 138.114496 -207.087558) (xy 138.154645 -207.048849) (xy 138.200003 -207.016398) (xy 138.249603 -206.990897)
			(xy 138.302387 -206.97289) (xy 138.35723 -206.96276) (xy 138.412964 -206.960723) (xy 138.468401 -206.966823)
			(xy 138.522358 -206.980929) (xy 138.573687 -207.002741) (xy 138.621293 -207.031795) (xy 138.664161 -207.06747)
			(xy 138.701378 -207.109007) (xy 138.732151 -207.15552) (xy 138.755823 -207.206017) (xy 138.771891 -207.259424)
			(xy 138.780011 -207.3146) (xy 138.78052 -207.342486) (xy 138.780011 -207.370372) (xy 138.771891 -207.425548)
			(xy 138.755823 -207.478955) (xy 138.732151 -207.529452) (xy 138.701378 -207.575965) (xy 138.664161 -207.617502)
			(xy 138.621293 -207.653177) (xy 138.573687 -207.682231) (xy 138.522358 -207.704043) (xy 138.468401 -207.718149)
			(xy 138.412964 -207.724249) (xy 138.35723 -207.722212) (xy 138.302387 -207.712082) (xy 138.249603 -207.694075)
			(xy 138.200003 -207.668574) (xy 138.154645 -207.636123) (xy 138.114496 -207.597414) (xy 138.08041 -207.553271)
			(xy 138.053114 -207.504636) (xy 138.033191 -207.452545) (xy 138.021065 -207.398108) (xy 138.016994 -207.342486)
			(xy 121.371106 -207.342486) (xy 122.346466 -208.317846) (xy 141.030196 -208.317846) (xy 141.034267 -208.262224)
			(xy 141.046393 -208.207787) (xy 141.066316 -208.155696) (xy 141.093612 -208.107061) (xy 141.127698 -208.062918)
			(xy 141.167847 -208.024209) (xy 141.213205 -207.991758) (xy 141.262805 -207.966257) (xy 141.315589 -207.94825)
			(xy 141.370432 -207.93812) (xy 141.426166 -207.936083) (xy 141.481603 -207.942183) (xy 141.53556 -207.956289)
			(xy 141.586889 -207.978101) (xy 141.623754 -208.0006) (xy 142.467582 -208.0006) (xy 142.471653 -207.944978)
			(xy 142.483779 -207.890541) (xy 142.503702 -207.83845) (xy 142.530998 -207.789815) (xy 142.565084 -207.745672)
			(xy 142.605233 -207.706963) (xy 142.650591 -207.674512) (xy 142.700191 -207.649011) (xy 142.752975 -207.631004)
			(xy 142.807818 -207.620874) (xy 142.863552 -207.618837) (xy 142.918989 -207.624937) (xy 142.972946 -207.639043)
			(xy 143.024275 -207.660855) (xy 143.071881 -207.689909) (xy 143.114749 -207.725584) (xy 143.151966 -207.767121)
			(xy 143.182739 -207.813634) (xy 143.206411 -207.864131) (xy 143.222479 -207.917538) (xy 143.230599 -207.972714)
			(xy 143.231108 -208.0006) (xy 143.230599 -208.028486) (xy 143.222479 -208.083662) (xy 143.206411 -208.137069)
			(xy 143.182739 -208.187566) (xy 143.151966 -208.234079) (xy 143.114749 -208.275616) (xy 143.071881 -208.311291)
			(xy 143.024275 -208.340345) (xy 142.972946 -208.362157) (xy 142.918989 -208.376263) (xy 142.863552 -208.382363)
			(xy 142.807818 -208.380326) (xy 142.752975 -208.370196) (xy 142.700191 -208.352189) (xy 142.650591 -208.326688)
			(xy 142.605233 -208.294237) (xy 142.565084 -208.255528) (xy 142.530998 -208.211385) (xy 142.503702 -208.16275)
			(xy 142.483779 -208.110659) (xy 142.471653 -208.056222) (xy 142.467582 -208.0006) (xy 141.623754 -208.0006)
			(xy 141.634495 -208.007155) (xy 141.677363 -208.04283) (xy 141.71458 -208.084367) (xy 141.745353 -208.13088)
			(xy 141.769025 -208.181377) (xy 141.785093 -208.234784) (xy 141.793213 -208.28996) (xy 141.793722 -208.317846)
			(xy 141.793213 -208.345732) (xy 141.785093 -208.400908) (xy 141.769025 -208.454315) (xy 141.745353 -208.504812)
			(xy 141.71458 -208.551325) (xy 141.677363 -208.592862) (xy 141.634495 -208.628537) (xy 141.586889 -208.657591)
			(xy 141.53556 -208.679403) (xy 141.481603 -208.693509) (xy 141.426166 -208.699609) (xy 141.370432 -208.697572)
			(xy 141.315589 -208.687442) (xy 141.262805 -208.669435) (xy 141.213205 -208.643934) (xy 141.167847 -208.611483)
			(xy 141.127698 -208.572774) (xy 141.093612 -208.528631) (xy 141.066316 -208.479996) (xy 141.046393 -208.427905)
			(xy 141.034267 -208.373468) (xy 141.030196 -208.317846) (xy 122.346466 -208.317846) (xy 123.02109 -208.99247)
			(xy 123.96927 -208.99247) (xy 123.973341 -208.936848) (xy 123.985467 -208.882411) (xy 124.00539 -208.83032)
			(xy 124.032686 -208.781685) (xy 124.066772 -208.737542) (xy 124.106921 -208.698833) (xy 124.152279 -208.666382)
			(xy 124.201879 -208.640881) (xy 124.254663 -208.622874) (xy 124.309506 -208.612744) (xy 124.36524 -208.610707)
			(xy 124.420677 -208.616807) (xy 124.474634 -208.630913) (xy 124.525963 -208.652725) (xy 124.573569 -208.681779)
			(xy 124.616437 -208.717454) (xy 124.653654 -208.758991) (xy 124.684427 -208.805504) (xy 124.708099 -208.856001)
			(xy 124.724167 -208.909408) (xy 124.732287 -208.964584) (xy 124.732796 -208.99247) (xy 124.732287 -209.020356)
			(xy 124.724167 -209.075532) (xy 124.708099 -209.128939) (xy 124.684427 -209.179436) (xy 124.653654 -209.225949)
			(xy 124.616437 -209.267486) (xy 124.573569 -209.303161) (xy 124.525963 -209.332215) (xy 124.474634 -209.354027)
			(xy 124.420677 -209.368133) (xy 124.36524 -209.374233) (xy 124.309506 -209.372196) (xy 124.254663 -209.362066)
			(xy 124.201879 -209.344059) (xy 124.152279 -209.318558) (xy 124.106921 -209.286107) (xy 124.066772 -209.247398)
			(xy 124.032686 -209.203255) (xy 124.00539 -209.15462) (xy 123.985467 -209.102529) (xy 123.973341 -209.048092)
			(xy 123.96927 -208.99247) (xy 123.02109 -208.99247) (xy 123.63831 -209.60969) (xy 123.645714 -209.616526)
			(xy 123.66431 -209.624248) (xy 123.674378 -209.624676) (xy 128.981708 -209.624676) (xy 128.993026 -209.624029)
			(xy 129.01346 -209.614275) (xy 129.021078 -209.60588) (xy 129.078228 -209.535776) (xy 129.083562 -209.513932)
			(xy 129.081276 -209.502502) (xy 129.077624 -209.483599) (xy 129.073681 -209.445299) (xy 129.073402 -209.426048)
			(xy 129.073888 -209.398797) (xy 129.081644 -209.344849) (xy 129.096999 -209.292554) (xy 129.119641 -209.242977)
			(xy 129.149107 -209.197127) (xy 129.184798 -209.155936) (xy 129.225989 -209.120245) (xy 129.271839 -209.090779)
			(xy 129.321416 -209.068137) (xy 129.373711 -209.052782) (xy 129.427659 -209.045026) (xy 129.482161 -209.045026)
			(xy 129.536109 -209.052782) (xy 129.588404 -209.068137) (xy 129.614042 -209.079846) (xy 137.982196 -209.079846)
			(xy 137.986267 -209.024224) (xy 137.998393 -208.969787) (xy 138.018316 -208.917696) (xy 138.045612 -208.869061)
			(xy 138.079698 -208.824918) (xy 138.119847 -208.786209) (xy 138.165205 -208.753758) (xy 138.214805 -208.728257)
			(xy 138.267589 -208.71025) (xy 138.322432 -208.70012) (xy 138.378166 -208.698083) (xy 138.433603 -208.704183)
			(xy 138.48756 -208.718289) (xy 138.538889 -208.740101) (xy 138.586495 -208.769155) (xy 138.629363 -208.80483)
			(xy 138.66658 -208.846367) (xy 138.697353 -208.89288) (xy 138.721025 -208.943377) (xy 138.737093 -208.996784)
			(xy 138.745213 -209.05196) (xy 138.745722 -209.079846) (xy 138.745213 -209.107732) (xy 138.737093 -209.162908)
			(xy 138.721025 -209.216315) (xy 138.697353 -209.266812) (xy 138.66658 -209.313325) (xy 138.629363 -209.354862)
			(xy 138.586495 -209.390537) (xy 138.538889 -209.419591) (xy 138.48756 -209.441403) (xy 138.433603 -209.455509)
			(xy 138.378166 -209.461609) (xy 138.322432 -209.459572) (xy 138.267589 -209.449442) (xy 138.214805 -209.431435)
			(xy 138.165205 -209.405934) (xy 138.119847 -209.373483) (xy 138.079698 -209.334774) (xy 138.045612 -209.290631)
			(xy 138.018316 -209.241996) (xy 137.998393 -209.189905) (xy 137.986267 -209.135468) (xy 137.982196 -209.079846)
			(xy 129.614042 -209.079846) (xy 129.637981 -209.090779) (xy 129.683831 -209.120245) (xy 129.725022 -209.155936)
			(xy 129.760713 -209.197127) (xy 129.790179 -209.242977) (xy 129.812821 -209.292554) (xy 129.828176 -209.344849)
			(xy 129.835932 -209.398797) (xy 129.836418 -209.426048) (xy 129.836156 -209.4453) (xy 129.834242 -209.463894)
			(xy 132.328156 -209.463894) (xy 132.332227 -209.408272) (xy 132.344353 -209.353835) (xy 132.364276 -209.301744)
			(xy 132.391572 -209.253109) (xy 132.425658 -209.208966) (xy 132.465807 -209.170257) (xy 132.511165 -209.137806)
			(xy 132.560765 -209.112305) (xy 132.613549 -209.094298) (xy 132.668392 -209.084168) (xy 132.724126 -209.082131)
			(xy 132.779563 -209.088231) (xy 132.83352 -209.102337) (xy 132.884849 -209.124149) (xy 132.932455 -209.153203)
			(xy 132.975323 -209.188878) (xy 133.01254 -209.230415) (xy 133.043313 -209.276928) (xy 133.066985 -209.327425)
			(xy 133.083053 -209.380832) (xy 133.091173 -209.436008) (xy 133.091682 -209.463894) (xy 133.091173 -209.49178)
			(xy 133.083053 -209.546956) (xy 133.066985 -209.600363) (xy 133.043313 -209.65086) (xy 133.01254 -209.697373)
			(xy 132.975323 -209.73891) (xy 132.932455 -209.774585) (xy 132.884849 -209.803639) (xy 132.83352 -209.825451)
			(xy 132.779563 -209.839557) (xy 132.724126 -209.845657) (xy 132.668392 -209.84362) (xy 132.613549 -209.83349)
			(xy 132.560765 -209.815483) (xy 132.511165 -209.789982) (xy 132.465807 -209.757531) (xy 132.425658 -209.718822)
			(xy 132.391572 -209.674679) (xy 132.364276 -209.626044) (xy 132.344353 -209.573953) (xy 132.332227 -209.519516)
			(xy 132.328156 -209.463894) (xy 129.834242 -209.463894) (xy 129.832213 -209.483601) (xy 129.828544 -209.502502)
			(xy 129.826928 -209.513667) (xy 129.832323 -209.535543) (xy 129.838958 -209.544666) (xy 129.888742 -209.60588)
			(xy 129.89632 -209.614327) (xy 129.916779 -209.624078) (xy 129.928112 -209.624676) (xy 130.5814 -209.624676)
			(xy 130.611465 -209.625205) (xy 130.670855 -209.634601) (xy 130.728042 -209.653177) (xy 130.781617 -209.680476)
			(xy 130.830259 -209.715823) (xy 130.85191 -209.73669) (xy 130.97256 -209.85734) (xy 130.978792 -209.863123)
			(xy 130.994061 -209.870572) (xy 131.010932 -209.872573) (xy 131.019296 -209.871056) (xy 131.115308 -209.850228)
			(xy 131.134866 -209.833464) (xy 131.139438 -209.821272) (xy 131.150137 -209.794482) (xy 131.178459 -209.744227)
			(xy 131.214023 -209.698808) (xy 131.25602 -209.659262) (xy 131.303493 -209.626489) (xy 131.355358 -209.601237)
			(xy 131.410434 -209.584081) (xy 131.467465 -209.575413) (xy 131.496308 -209.574892) (xy 131.523559 -209.57537)
			(xy 131.577507 -209.583128) (xy 131.629802 -209.598484) (xy 131.67938 -209.621126) (xy 131.72523 -209.650593)
			(xy 131.76642 -209.686286) (xy 131.802112 -209.727476) (xy 131.831578 -209.773327) (xy 131.854219 -209.822905)
			(xy 131.869574 -209.8752) (xy 131.87733 -209.929149) (xy 131.877816 -209.9564) (xy 131.877676 -209.96402)
			(xy 134.571484 -209.96402) (xy 134.575555 -209.908398) (xy 134.587681 -209.853961) (xy 134.607604 -209.80187)
			(xy 134.6349 -209.753235) (xy 134.668986 -209.709092) (xy 134.709135 -209.670383) (xy 134.754493 -209.637932)
			(xy 134.804093 -209.612431) (xy 134.856877 -209.594424) (xy 134.91172 -209.584294) (xy 134.967454 -209.582257)
			(xy 135.022891 -209.588357) (xy 135.076848 -209.602463) (xy 135.128177 -209.624275) (xy 135.175783 -209.653329)
			(xy 135.218651 -209.689004) (xy 135.255868 -209.730541) (xy 135.286641 -209.777054) (xy 135.310313 -209.827551)
			(xy 135.326381 -209.880958) (xy 135.334501 -209.936134) (xy 135.33501 -209.96402) (xy 135.334501 -209.991906)
			(xy 135.326381 -210.047082) (xy 135.310313 -210.100489) (xy 135.286641 -210.150986) (xy 135.255868 -210.197499)
			(xy 135.218651 -210.239036) (xy 135.175783 -210.274711) (xy 135.128177 -210.303765) (xy 135.076848 -210.325577)
			(xy 135.022891 -210.339683) (xy 134.967454 -210.345783) (xy 134.91172 -210.343746) (xy 134.856877 -210.333616)
			(xy 134.804093 -210.315609) (xy 134.754493 -210.290108) (xy 134.709135 -210.257657) (xy 134.668986 -210.218948)
			(xy 134.6349 -210.174805) (xy 134.607604 -210.12617) (xy 134.587681 -210.074079) (xy 134.575555 -210.019642)
			(xy 134.571484 -209.96402) (xy 131.877676 -209.96402) (xy 131.877286 -209.985238) (xy 131.868584 -210.042255)
			(xy 131.851407 -210.097315) (xy 131.826146 -210.149166) (xy 131.793377 -210.196629) (xy 131.753842 -210.238626)
			(xy 131.708443 -210.2742) (xy 131.658211 -210.302544) (xy 131.631436 -210.31327) (xy 131.619244 -210.317842)
			(xy 131.60248 -210.3374) (xy 131.581652 -210.433412) (xy 131.580167 -210.441777) (xy 131.582184 -210.458637)
			(xy 131.589595 -210.473915) (xy 131.595368 -210.480148) (xy 131.949467 -210.834247) (xy 138.520224 -210.834247)
			(xy 138.520224 -210.779753) (xy 138.527979 -210.725815) (xy 138.543331 -210.673529) (xy 138.565967 -210.62396)
			(xy 138.595427 -210.578116) (xy 138.631111 -210.536932) (xy 138.672292 -210.501245) (xy 138.718133 -210.471781)
			(xy 138.767701 -210.449141) (xy 138.819986 -210.433785) (xy 138.873923 -210.426026) (xy 138.90117 -210.425538)
			(xy 138.927933 -210.425945) (xy 138.980932 -210.43343) (xy 139.032366 -210.448244) (xy 139.081227 -210.470097)
			(xy 139.126558 -210.498559) (xy 139.167468 -210.533074) (xy 139.203158 -210.572965) (xy 139.218416 -210.594956)
			(xy 139.227117 -210.606883) (xy 139.249879 -210.625655) (xy 139.277057 -210.637138) (xy 139.306384 -210.640372)
			(xy 139.335411 -210.635089) (xy 139.361717 -210.621729) (xy 139.383107 -210.601407) (xy 139.390882 -210.58886)
			(xy 139.405539 -210.564222) (xy 139.441142 -210.519289) (xy 139.483066 -210.480188) (xy 139.530367 -210.447799)
			(xy 139.581982 -210.422851) (xy 139.636749 -210.405906) (xy 139.693434 -210.397344) (xy 139.722098 -210.396836)
			(xy 139.749354 -210.397211) (xy 139.803312 -210.404968) (xy 139.855616 -210.420326) (xy 139.905202 -210.442971)
			(xy 139.951061 -210.472443) (xy 139.992258 -210.50814) (xy 140.027956 -210.549338) (xy 140.057428 -210.595196)
			(xy 140.080073 -210.644782) (xy 140.095431 -210.697087) (xy 140.103189 -210.751044) (xy 140.103189 -210.805556)
			(xy 140.101514 -210.817206) (xy 140.924786 -210.817206) (xy 140.928857 -210.761584) (xy 140.940983 -210.707147)
			(xy 140.960906 -210.655056) (xy 140.988202 -210.606421) (xy 141.022288 -210.562278) (xy 141.062437 -210.523569)
			(xy 141.107795 -210.491118) (xy 141.157395 -210.465617) (xy 141.210179 -210.44761) (xy 141.265022 -210.43748)
			(xy 141.320756 -210.435443) (xy 141.376193 -210.441543) (xy 141.43015 -210.455649) (xy 141.481479 -210.477461)
			(xy 141.529085 -210.506515) (xy 141.571953 -210.54219) (xy 141.60917 -210.583727) (xy 141.639943 -210.63024)
			(xy 141.663615 -210.680737) (xy 141.679683 -210.734144) (xy 141.687803 -210.78932) (xy 141.688312 -210.817206)
			(xy 141.687803 -210.845092) (xy 141.679683 -210.900268) (xy 141.663615 -210.953675) (xy 141.639943 -211.004172)
			(xy 141.60917 -211.050685) (xy 141.571953 -211.092222) (xy 141.529085 -211.127897) (xy 141.481479 -211.156951)
			(xy 141.43015 -211.178763) (xy 141.376193 -211.192869) (xy 141.320756 -211.198969) (xy 141.265022 -211.196932)
			(xy 141.210179 -211.186802) (xy 141.157395 -211.168795) (xy 141.107795 -211.143294) (xy 141.062437 -211.110843)
			(xy 141.022288 -211.072134) (xy 140.988202 -211.027991) (xy 140.960906 -210.979356) (xy 140.940983 -210.927265)
			(xy 140.928857 -210.872828) (xy 140.924786 -210.817206) (xy 140.101514 -210.817206) (xy 140.095431 -210.859513)
			(xy 140.080073 -210.911818) (xy 140.057428 -210.961404) (xy 140.027956 -211.007262) (xy 139.992258 -211.04846)
			(xy 139.951061 -211.084157) (xy 139.905202 -211.113629) (xy 139.855616 -211.136274) (xy 139.803312 -211.151632)
			(xy 139.749354 -211.159389) (xy 139.722098 -211.159852) (xy 139.695337 -211.159398) (xy 139.64234 -211.151922)
			(xy 139.590906 -211.137116) (xy 139.542045 -211.115271) (xy 139.496714 -211.086816) (xy 139.455802 -211.052308)
			(xy 139.420111 -211.012423) (xy 139.404852 -210.990434) (xy 139.396191 -210.978476) (xy 139.373419 -210.959705)
			(xy 139.346232 -210.948225) (xy 139.316899 -210.944995) (xy 139.287865 -210.950284) (xy 139.261555 -210.963651)
			(xy 139.240162 -210.98398) (xy 139.232386 -210.99653) (xy 139.217678 -211.021136) (xy 139.182084 -211.066069)
			(xy 139.140168 -211.105172) (xy 139.092875 -211.137564) (xy 139.041269 -211.162518) (xy 138.98651 -211.179471)
			(xy 138.929832 -211.188041) (xy 138.90117 -211.188554) (xy 138.873923 -211.187974) (xy 138.819986 -211.180215)
			(xy 138.767701 -211.164859) (xy 138.718133 -211.142219) (xy 138.672292 -211.112755) (xy 138.631111 -211.077068)
			(xy 138.595427 -211.035884) (xy 138.565967 -210.99004) (xy 138.543331 -210.940471) (xy 138.527979 -210.888185)
			(xy 138.520224 -210.834247) (xy 131.949467 -210.834247) (xy 132.862066 -211.746846) (xy 134.826246 -211.746846)
			(xy 134.830317 -211.691224) (xy 134.842443 -211.636787) (xy 134.862366 -211.584696) (xy 134.889662 -211.536061)
			(xy 134.923748 -211.491918) (xy 134.963897 -211.453209) (xy 135.009255 -211.420758) (xy 135.058855 -211.395257)
			(xy 135.111639 -211.37725) (xy 135.166482 -211.36712) (xy 135.222216 -211.365083) (xy 135.277653 -211.371183)
			(xy 135.33161 -211.385289) (xy 135.382939 -211.407101) (xy 135.430545 -211.436155) (xy 135.473413 -211.47183)
			(xy 135.51063 -211.513367) (xy 135.541403 -211.55988) (xy 135.565075 -211.610377) (xy 135.581143 -211.663784)
			(xy 135.589263 -211.71896) (xy 135.589772 -211.746846) (xy 135.589263 -211.774732) (xy 135.581143 -211.829908)
			(xy 135.565075 -211.883315) (xy 135.541403 -211.933812) (xy 135.51063 -211.980325) (xy 135.473413 -212.021862)
			(xy 135.430545 -212.057537) (xy 135.382939 -212.086591) (xy 135.33161 -212.108403) (xy 135.277653 -212.122509)
			(xy 135.222216 -212.128609) (xy 135.166482 -212.126572) (xy 135.111639 -212.116442) (xy 135.058855 -212.098435)
			(xy 135.009255 -212.072934) (xy 134.963897 -212.040483) (xy 134.923748 -212.001774) (xy 134.889662 -211.957631)
			(xy 134.862366 -211.908996) (xy 134.842443 -211.856905) (xy 134.830317 -211.802468) (xy 134.826246 -211.746846)
			(xy 132.862066 -211.746846) (xy 133.67131 -212.55609) (xy 133.678714 -212.562926) (xy 133.69731 -212.570648)
			(xy 133.707378 -212.571076) (xy 135.3312 -212.571076) (xy 135.361265 -212.571605) (xy 135.420655 -212.581001)
			(xy 135.477842 -212.599577) (xy 135.531417 -212.626876) (xy 135.580059 -212.662223) (xy 135.60171 -212.68309)
			(xy 136.424416 -213.505796) (xy 142.064484 -213.505796) (xy 142.068555 -213.450174) (xy 142.080681 -213.395737)
			(xy 142.100604 -213.343646) (xy 142.1279 -213.295011) (xy 142.161986 -213.250868) (xy 142.202135 -213.212159)
			(xy 142.247493 -213.179708) (xy 142.297093 -213.154207) (xy 142.349877 -213.1362) (xy 142.40472 -213.12607)
			(xy 142.460454 -213.124033) (xy 142.515891 -213.130133) (xy 142.569848 -213.144239) (xy 142.621177 -213.166051)
			(xy 142.668783 -213.195105) (xy 142.711651 -213.23078) (xy 142.748868 -213.272317) (xy 142.779641 -213.31883)
			(xy 142.803313 -213.369327) (xy 142.819381 -213.422734) (xy 142.827501 -213.47791) (xy 142.82801 -213.505796)
			(xy 142.827501 -213.533682) (xy 142.819381 -213.588858) (xy 142.803313 -213.642265) (xy 142.779641 -213.692762)
			(xy 142.748868 -213.739275) (xy 142.711651 -213.780812) (xy 142.668783 -213.816487) (xy 142.621177 -213.845541)
			(xy 142.569848 -213.867353) (xy 142.515891 -213.881459) (xy 142.460454 -213.887559) (xy 142.40472 -213.885522)
			(xy 142.349877 -213.875392) (xy 142.297093 -213.857385) (xy 142.247493 -213.831884) (xy 142.202135 -213.799433)
			(xy 142.161986 -213.760724) (xy 142.1279 -213.716581) (xy 142.100604 -213.667946) (xy 142.080681 -213.615855)
			(xy 142.068555 -213.561418) (xy 142.064484 -213.505796) (xy 136.424416 -213.505796) (xy 136.74471 -213.82609)
			(xy 136.765558 -213.847753) (xy 136.800882 -213.896403) (xy 136.828164 -213.949977) (xy 136.846734 -214.007158)
			(xy 136.856135 -214.06654) (xy 136.856724 -214.0966) (xy 136.856237 -214.123924) (xy 136.851072 -214.159846)
			(xy 138.363196 -214.159846) (xy 138.367267 -214.104224) (xy 138.379393 -214.049787) (xy 138.399316 -213.997696)
			(xy 138.426612 -213.949061) (xy 138.460698 -213.904918) (xy 138.500847 -213.866209) (xy 138.546205 -213.833758)
			(xy 138.595805 -213.808257) (xy 138.648589 -213.79025) (xy 138.703432 -213.78012) (xy 138.759166 -213.778083)
			(xy 138.814603 -213.784183) (xy 138.86856 -213.798289) (xy 138.919889 -213.820101) (xy 138.967495 -213.849155)
			(xy 139.010363 -213.88483) (xy 139.04758 -213.926367) (xy 139.078353 -213.97288) (xy 139.102025 -214.023377)
			(xy 139.118093 -214.076784) (xy 139.126213 -214.13196) (xy 139.126722 -214.159846) (xy 139.126213 -214.187732)
			(xy 139.118093 -214.242908) (xy 139.102025 -214.296315) (xy 139.078353 -214.346812) (xy 139.04758 -214.393325)
			(xy 139.010363 -214.434862) (xy 138.967495 -214.470537) (xy 138.919889 -214.499591) (xy 138.86856 -214.521403)
			(xy 138.814603 -214.535509) (xy 138.759166 -214.541609) (xy 138.703432 -214.539572) (xy 138.648589 -214.529442)
			(xy 138.595805 -214.511435) (xy 138.546205 -214.485934) (xy 138.500847 -214.453483) (xy 138.460698 -214.414774)
			(xy 138.426612 -214.370631) (xy 138.399316 -214.321996) (xy 138.379393 -214.269905) (xy 138.367267 -214.215468)
			(xy 138.363196 -214.159846) (xy 136.851072 -214.159846) (xy 136.848459 -214.178015) (xy 136.833063 -214.230449)
			(xy 136.810362 -214.280158) (xy 136.780817 -214.326131) (xy 136.745031 -214.367431) (xy 136.703731 -214.403217)
			(xy 136.657758 -214.432762) (xy 136.608049 -214.455463) (xy 136.555615 -214.470859) (xy 136.501524 -214.478637)
			(xy 136.4742 -214.479124) (xy 136.444135 -214.478595) (xy 136.384745 -214.469199) (xy 136.327558 -214.450623)
			(xy 136.273983 -214.423324) (xy 136.225341 -214.387977) (xy 136.20369 -214.36711) (xy 136.126982 -214.290402)
			(xy 136.118264 -214.28252) (xy 136.096026 -214.274986) (xy 136.08431 -214.275924) (xy 135.992616 -214.288116)
			(xy 135.972804 -214.301324) (xy 135.966962 -214.311738) (xy 135.952251 -214.33631) (xy 135.916671 -214.381183)
			(xy 135.874782 -214.420233) (xy 135.827526 -214.452582) (xy 135.775965 -214.477501) (xy 135.721258 -214.494432)
			(xy 135.664634 -214.502994) (xy 135.636 -214.503508) (xy 135.608749 -214.503022) (xy 135.554801 -214.495266)
			(xy 135.502506 -214.479911) (xy 135.452929 -214.457269) (xy 135.407079 -214.427803) (xy 135.365888 -214.392112)
			(xy 135.330197 -214.350921) (xy 135.300731 -214.305071) (xy 135.278089 -214.255494) (xy 135.262734 -214.203199)
			(xy 135.254978 -214.149251) (xy 135.254492 -214.122) (xy 135.255021 -214.093366) (xy 135.263581 -214.036742)
			(xy 135.280508 -213.982033) (xy 135.305423 -213.930469) (xy 135.337766 -213.883208) (xy 135.376809 -213.841313)
			(xy 135.421676 -213.805724) (xy 135.446262 -213.791038) (xy 135.456676 -213.785196) (xy 135.469884 -213.765384)
			(xy 135.482076 -213.67369) (xy 135.483056 -213.661967) (xy 135.475516 -213.639717) (xy 135.467598 -213.631018)
			(xy 135.18769 -213.35111) (xy 135.180286 -213.344274) (xy 135.16169 -213.336552) (xy 135.151622 -213.336124)
			(xy 133.5278 -213.336124) (xy 133.497735 -213.335595) (xy 133.438345 -213.326199) (xy 133.381158 -213.307623)
			(xy 133.327583 -213.280324) (xy 133.278941 -213.244977) (xy 133.25729 -213.22411) (xy 130.43789 -210.40471)
			(xy 130.430486 -210.397874) (xy 130.41189 -210.390152) (xy 130.401822 -210.389724) (xy 123.4948 -210.389724)
			(xy 123.464735 -210.389195) (xy 123.405345 -210.379799) (xy 123.348158 -210.361223) (xy 123.294583 -210.333924)
			(xy 123.245941 -210.298577) (xy 123.22429 -210.27771) (xy 110.09249 -197.14591) (xy 110.085086 -197.139074)
			(xy 110.06649 -197.131352) (xy 110.056422 -197.130924) (xy 99.939348 -197.130924) (xy 99.909285 -197.130365)
			(xy 99.849896 -197.120976) (xy 99.792709 -197.102407) (xy 99.739133 -197.075115) (xy 99.69049 -197.039774)
			(xy 99.668838 -197.01891) (xy 98.957638 -196.30771) (xy 98.950218 -196.300895) (xy 98.931634 -196.29316)
			(xy 98.92157 -196.292724) (xy 95.001842 -196.292724) (xy 94.971778 -196.292168) (xy 94.912389 -196.282779)
			(xy 94.855202 -196.264209) (xy 94.801627 -196.236917) (xy 94.752984 -196.201574) (xy 94.731332 -196.18071)
			(xy 93.8149 -195.264278) (xy 93.794005 -195.242641) (xy 93.758612 -195.194009) (xy 93.731268 -195.140436)
			(xy 93.712646 -195.083244) (xy 93.703205 -195.023842) (xy 93.702632 -194.993768) (xy 92.096787 -194.993768)
			(xy 92.096308 -195.02569) (xy 92.087653 -195.09663) (xy 92.0705 -195.166006) (xy 92.0451 -195.232805)
			(xy 92.011824 -195.29605) (xy 91.991942 -195.325746) (xy 91.987804 -195.332256) (xy 91.983271 -195.346992)
			(xy 91.983052 -195.354702) (xy 91.983052 -195.364354) (xy 92.004609 -195.394788) (xy 92.040709 -195.460051)
			(xy 92.068294 -195.529344) (xy 92.086927 -195.601561) (xy 92.096309 -195.675551) (xy 92.096844 -195.712842)
			(xy 92.096844 -196.209158) (xy 92.096308 -196.24489) (xy 92.087653 -196.31583) (xy 92.0705 -196.385206)
			(xy 92.0451 -196.452005) (xy 92.011824 -196.51525) (xy 91.991942 -196.544946) (xy 91.987804 -196.551456)
			(xy 91.983271 -196.566192) (xy 91.983052 -196.573902) (xy 91.983052 -196.5833) (xy 92.543882 -196.5833)
			(xy 92.547953 -196.527678) (xy 92.560079 -196.473241) (xy 92.580002 -196.42115) (xy 92.607298 -196.372515)
			(xy 92.641384 -196.328372) (xy 92.681533 -196.289663) (xy 92.726891 -196.257212) (xy 92.776491 -196.231711)
			(xy 92.829275 -196.213704) (xy 92.884118 -196.203574) (xy 92.939852 -196.201537) (xy 92.995289 -196.207637)
			(xy 93.049246 -196.221743) (xy 93.100575 -196.243555) (xy 93.148181 -196.272609) (xy 93.191049 -196.308284)
			(xy 93.228266 -196.349821) (xy 93.259039 -196.396334) (xy 93.282711 -196.446831) (xy 93.298779 -196.500238)
			(xy 93.306899 -196.555414) (xy 93.307408 -196.5833) (xy 93.306899 -196.611186) (xy 93.298779 -196.666362)
			(xy 93.282711 -196.719769) (xy 93.259039 -196.770266) (xy 93.228266 -196.816779) (xy 93.191049 -196.858316)
			(xy 93.148181 -196.893991) (xy 93.100575 -196.923045) (xy 93.049246 -196.944857) (xy 92.995289 -196.958963)
			(xy 92.939852 -196.965063) (xy 92.884118 -196.963026) (xy 92.829275 -196.952896) (xy 92.776491 -196.934889)
			(xy 92.726891 -196.909388) (xy 92.681533 -196.876937) (xy 92.641384 -196.838228) (xy 92.607298 -196.794085)
			(xy 92.580002 -196.74545) (xy 92.560079 -196.693359) (xy 92.547953 -196.638922) (xy 92.543882 -196.5833)
			(xy 91.983052 -196.5833) (xy 91.983052 -196.583554) (xy 92.004609 -196.613988) (xy 92.040709 -196.679251)
			(xy 92.068294 -196.748544) (xy 92.086927 -196.820761) (xy 92.096309 -196.894751) (xy 92.096844 -196.932042)
			(xy 92.096844 -197.428358) (xy 92.096308 -197.46409) (xy 92.087653 -197.53503) (xy 92.0705 -197.604406)
			(xy 92.0451 -197.671205) (xy 92.011824 -197.73445) (xy 91.991942 -197.764146) (xy 91.987804 -197.770656)
			(xy 91.983271 -197.785392) (xy 91.983052 -197.793102) (xy 91.983052 -197.802754) (xy 92.004609 -197.833188)
			(xy 92.040709 -197.898451) (xy 92.068294 -197.967744) (xy 92.086927 -198.039961) (xy 92.096309 -198.113951)
			(xy 92.096844 -198.151242) (xy 92.096844 -198.64705) (xy 92.096319 -198.682867) (xy 92.087661 -198.753975)
			(xy 92.083956 -198.76897) (xy 94.538544 -198.76897) (xy 94.542615 -198.713348) (xy 94.554741 -198.658911)
			(xy 94.574664 -198.60682) (xy 94.60196 -198.558185) (xy 94.636046 -198.514042) (xy 94.676195 -198.475333)
			(xy 94.721553 -198.442882) (xy 94.771153 -198.417381) (xy 94.823937 -198.399374) (xy 94.87878 -198.389244)
			(xy 94.934514 -198.387207) (xy 94.989951 -198.393307) (xy 95.043908 -198.407413) (xy 95.095237 -198.429225)
			(xy 95.142843 -198.458279) (xy 95.185711 -198.493954) (xy 95.222928 -198.535491) (xy 95.253701 -198.582004)
			(xy 95.277373 -198.632501) (xy 95.293441 -198.685908) (xy 95.301561 -198.741084) (xy 95.30207 -198.76897)
			(xy 95.301736 -198.787258) (xy 96.222056 -198.787258) (xy 96.226127 -198.731636) (xy 96.238253 -198.677199)
			(xy 96.258176 -198.625108) (xy 96.285472 -198.576473) (xy 96.319558 -198.53233) (xy 96.359707 -198.493621)
			(xy 96.405065 -198.46117) (xy 96.454665 -198.435669) (xy 96.507449 -198.417662) (xy 96.562292 -198.407532)
			(xy 96.618026 -198.405495) (xy 96.673463 -198.411595) (xy 96.72742 -198.425701) (xy 96.778749 -198.447513)
			(xy 96.826355 -198.476567) (xy 96.869223 -198.512242) (xy 96.90644 -198.553779) (xy 96.937213 -198.600292)
			(xy 96.960885 -198.650789) (xy 96.976953 -198.704196) (xy 96.985073 -198.759372) (xy 96.985582 -198.787258)
			(xy 96.985073 -198.815144) (xy 96.976953 -198.87032) (xy 96.960885 -198.923727) (xy 96.937213 -198.974224)
			(xy 96.90644 -199.020737) (xy 96.869223 -199.062274) (xy 96.826355 -199.097949) (xy 96.778749 -199.127003)
			(xy 96.72742 -199.148815) (xy 96.673463 -199.162921) (xy 96.618026 -199.169021) (xy 96.562292 -199.166984)
			(xy 96.507449 -199.156854) (xy 96.454665 -199.138847) (xy 96.405065 -199.113346) (xy 96.359707 -199.080895)
			(xy 96.319558 -199.042186) (xy 96.285472 -198.998043) (xy 96.258176 -198.949408) (xy 96.238253 -198.897317)
			(xy 96.226127 -198.84288) (xy 96.222056 -198.787258) (xy 95.301736 -198.787258) (xy 95.301561 -198.796856)
			(xy 95.293441 -198.852032) (xy 95.277373 -198.905439) (xy 95.253701 -198.955936) (xy 95.222928 -199.002449)
			(xy 95.185711 -199.043986) (xy 95.142843 -199.079661) (xy 95.095237 -199.108715) (xy 95.043908 -199.130527)
			(xy 94.989951 -199.144633) (xy 94.934514 -199.150733) (xy 94.87878 -199.148696) (xy 94.823937 -199.138566)
			(xy 94.771153 -199.120559) (xy 94.721553 -199.095058) (xy 94.676195 -199.062607) (xy 94.636046 -199.023898)
			(xy 94.60196 -198.979755) (xy 94.574664 -198.93112) (xy 94.554741 -198.879029) (xy 94.542615 -198.824592)
			(xy 94.538544 -198.76897) (xy 92.083956 -198.76897) (xy 92.070478 -198.823517) (xy 92.045021 -198.890475)
			(xy 92.011664 -198.953867) (xy 91.991688 -198.9836) (xy 91.987502 -198.990099) (xy 91.982845 -199.004832)
			(xy 91.982544 -199.012556) (xy 91.982544 -199.3138) (xy 102.995982 -199.3138) (xy 103.000053 -199.258178)
			(xy 103.012179 -199.203741) (xy 103.032102 -199.15165) (xy 103.059398 -199.103015) (xy 103.093484 -199.058872)
			(xy 103.133633 -199.020163) (xy 103.178991 -198.987712) (xy 103.228591 -198.962211) (xy 103.281375 -198.944204)
			(xy 103.336218 -198.934074) (xy 103.391952 -198.932037) (xy 103.447389 -198.938137) (xy 103.501346 -198.952243)
			(xy 103.552675 -198.974055) (xy 103.600281 -199.003109) (xy 103.643149 -199.038784) (xy 103.680366 -199.080321)
			(xy 103.711139 -199.126834) (xy 103.734811 -199.177331) (xy 103.750879 -199.230738) (xy 103.758999 -199.285914)
			(xy 103.759508 -199.3138) (xy 103.758999 -199.341686) (xy 103.750879 -199.396862) (xy 103.734811 -199.450269)
			(xy 103.711139 -199.500766) (xy 103.680366 -199.547279) (xy 103.643149 -199.588816) (xy 103.600281 -199.624491)
			(xy 103.552675 -199.653545) (xy 103.501346 -199.675357) (xy 103.447389 -199.689463) (xy 103.391952 -199.695563)
			(xy 103.336218 -199.693526) (xy 103.281375 -199.683396) (xy 103.228591 -199.665389) (xy 103.178991 -199.639888)
			(xy 103.133633 -199.607437) (xy 103.093484 -199.568728) (xy 103.059398 -199.524585) (xy 103.032102 -199.47595)
			(xy 103.012179 -199.423859) (xy 103.000053 -199.369422) (xy 102.995982 -199.3138) (xy 91.982544 -199.3138)
			(xy 91.982544 -199.880728) (xy 96.29216 -199.880728) (xy 96.296231 -199.825106) (xy 96.308357 -199.770669)
			(xy 96.32828 -199.718578) (xy 96.355576 -199.669943) (xy 96.389662 -199.6258) (xy 96.429811 -199.587091)
			(xy 96.475169 -199.55464) (xy 96.524769 -199.529139) (xy 96.577553 -199.511132) (xy 96.632396 -199.501002)
			(xy 96.68813 -199.498965) (xy 96.743567 -199.505065) (xy 96.797524 -199.519171) (xy 96.848853 -199.540983)
			(xy 96.896459 -199.570037) (xy 96.939327 -199.605712) (xy 96.976544 -199.647249) (xy 97.007317 -199.693762)
			(xy 97.030989 -199.744259) (xy 97.031392 -199.7456) (xy 106.602782 -199.7456) (xy 106.606853 -199.689978)
			(xy 106.618979 -199.635541) (xy 106.638902 -199.58345) (xy 106.666198 -199.534815) (xy 106.700284 -199.490672)
			(xy 106.740433 -199.451963) (xy 106.785791 -199.419512) (xy 106.835391 -199.394011) (xy 106.888175 -199.376004)
			(xy 106.943018 -199.365874) (xy 106.998752 -199.363837) (xy 107.054189 -199.369937) (xy 107.108146 -199.384043)
			(xy 107.159475 -199.405855) (xy 107.161381 -199.407018) (xy 109.422944 -199.407018) (xy 109.427015 -199.351396)
			(xy 109.439141 -199.296959) (xy 109.459064 -199.244868) (xy 109.48636 -199.196233) (xy 109.520446 -199.15209)
			(xy 109.560595 -199.113381) (xy 109.605953 -199.08093) (xy 109.655553 -199.055429) (xy 109.708337 -199.037422)
			(xy 109.76318 -199.027292) (xy 109.818914 -199.025255) (xy 109.874351 -199.031355) (xy 109.928308 -199.045461)
			(xy 109.979637 -199.067273) (xy 110.027243 -199.096327) (xy 110.070111 -199.132002) (xy 110.107328 -199.173539)
			(xy 110.138101 -199.220052) (xy 110.161773 -199.270549) (xy 110.177841 -199.323956) (xy 110.185961 -199.379132)
			(xy 110.18647 -199.407018) (xy 110.185961 -199.434904) (xy 110.177841 -199.49008) (xy 110.161773 -199.543487)
			(xy 110.138101 -199.593984) (xy 110.107328 -199.640497) (xy 110.070111 -199.682034) (xy 110.027243 -199.717709)
			(xy 109.979637 -199.746763) (xy 109.928308 -199.768575) (xy 109.874351 -199.782681) (xy 109.818914 -199.788781)
			(xy 109.76318 -199.786744) (xy 109.708337 -199.776614) (xy 109.655553 -199.758607) (xy 109.605953 -199.733106)
			(xy 109.560595 -199.700655) (xy 109.520446 -199.661946) (xy 109.48636 -199.617803) (xy 109.459064 -199.569168)
			(xy 109.439141 -199.517077) (xy 109.427015 -199.46264) (xy 109.422944 -199.407018) (xy 107.161381 -199.407018)
			(xy 107.207081 -199.434909) (xy 107.249949 -199.470584) (xy 107.287166 -199.512121) (xy 107.317939 -199.558634)
			(xy 107.341611 -199.609131) (xy 107.357679 -199.662538) (xy 107.365799 -199.717714) (xy 107.366308 -199.7456)
			(xy 107.365799 -199.773486) (xy 107.357679 -199.828662) (xy 107.341611 -199.882069) (xy 107.317939 -199.932566)
			(xy 107.287166 -199.979079) (xy 107.249949 -200.020616) (xy 107.207081 -200.056291) (xy 107.159475 -200.085345)
			(xy 107.108146 -200.107157) (xy 107.054189 -200.121263) (xy 106.998752 -200.127363) (xy 106.943018 -200.125326)
			(xy 106.888175 -200.115196) (xy 106.835391 -200.097189) (xy 106.785791 -200.071688) (xy 106.740433 -200.039237)
			(xy 106.700284 -200.000528) (xy 106.666198 -199.956385) (xy 106.638902 -199.90775) (xy 106.618979 -199.855659)
			(xy 106.606853 -199.801222) (xy 106.602782 -199.7456) (xy 97.031392 -199.7456) (xy 97.047057 -199.797666)
			(xy 97.055177 -199.852842) (xy 97.055686 -199.880728) (xy 97.055177 -199.908614) (xy 97.047057 -199.96379)
			(xy 97.030989 -200.017197) (xy 97.007317 -200.067694) (xy 96.976544 -200.114207) (xy 96.939327 -200.155744)
			(xy 96.896459 -200.191419) (xy 96.848853 -200.220473) (xy 96.797524 -200.242285) (xy 96.743567 -200.256391)
			(xy 96.68813 -200.262491) (xy 96.632396 -200.260454) (xy 96.577553 -200.250324) (xy 96.524769 -200.232317)
			(xy 96.475169 -200.206816) (xy 96.429811 -200.174365) (xy 96.389662 -200.135656) (xy 96.355576 -200.091513)
			(xy 96.32828 -200.042878) (xy 96.308357 -199.990787) (xy 96.296231 -199.93635) (xy 96.29216 -199.880728)
			(xy 91.982544 -199.880728) (xy 91.982544 -199.997822) (xy 91.982972 -200.007889) (xy 91.990697 -200.026484)
			(xy 91.99753 -200.03389) (xy 92.36964 -200.406) (xy 100.684582 -200.406) (xy 100.688653 -200.350378)
			(xy 100.700779 -200.295941) (xy 100.720702 -200.24385) (xy 100.747998 -200.195215) (xy 100.782084 -200.151072)
			(xy 100.822233 -200.112363) (xy 100.867591 -200.079912) (xy 100.917191 -200.054411) (xy 100.969975 -200.036404)
			(xy 101.024818 -200.026274) (xy 101.080552 -200.024237) (xy 101.135989 -200.030337) (xy 101.189946 -200.044443)
			(xy 101.241275 -200.066255) (xy 101.288881 -200.095309) (xy 101.331749 -200.130984) (xy 101.368966 -200.172521)
			(xy 101.399739 -200.219034) (xy 101.423411 -200.269531) (xy 101.439479 -200.322938) (xy 101.447599 -200.378114)
			(xy 101.448108 -200.406) (xy 101.447599 -200.433886) (xy 101.439479 -200.489062) (xy 101.423411 -200.542469)
			(xy 101.399739 -200.592966) (xy 101.368966 -200.639479) (xy 101.331749 -200.681016) (xy 101.288881 -200.716691)
			(xy 101.241275 -200.745745) (xy 101.189946 -200.767557) (xy 101.135989 -200.781663) (xy 101.080552 -200.787763)
			(xy 101.024818 -200.785726) (xy 100.969975 -200.775596) (xy 100.917191 -200.757589) (xy 100.867591 -200.732088)
			(xy 100.822233 -200.699637) (xy 100.782084 -200.660928) (xy 100.747998 -200.616785) (xy 100.720702 -200.56815)
			(xy 100.700779 -200.516059) (xy 100.688653 -200.461622) (xy 100.684582 -200.406) (xy 92.36964 -200.406)
			(xy 92.925392 -200.961752) (xy 93.962726 -200.961752) (xy 93.966797 -200.90613) (xy 93.978923 -200.851693)
			(xy 93.998846 -200.799602) (xy 94.026142 -200.750967) (xy 94.060228 -200.706824) (xy 94.100377 -200.668115)
			(xy 94.145735 -200.635664) (xy 94.195335 -200.610163) (xy 94.248119 -200.592156) (xy 94.302962 -200.582026)
			(xy 94.358696 -200.579989) (xy 94.414133 -200.586089) (xy 94.46809 -200.600195) (xy 94.519419 -200.622007)
			(xy 94.567025 -200.651061) (xy 94.609893 -200.686736) (xy 94.64711 -200.728273) (xy 94.677883 -200.774786)
			(xy 94.701555 -200.825283) (xy 94.717623 -200.87869) (xy 94.725743 -200.933866) (xy 94.726252 -200.961752)
			(xy 94.725743 -200.989638) (xy 94.717623 -201.044814) (xy 94.701555 -201.098221) (xy 94.677883 -201.148718)
			(xy 94.64711 -201.195231) (xy 94.609893 -201.236768) (xy 94.567025 -201.272443) (xy 94.519419 -201.301497)
			(xy 94.46809 -201.323309) (xy 94.414133 -201.337415) (xy 94.358696 -201.343515) (xy 94.302962 -201.341478)
			(xy 94.248119 -201.331348) (xy 94.195335 -201.313341) (xy 94.145735 -201.28784) (xy 94.100377 -201.255389)
			(xy 94.060228 -201.21668) (xy 94.026142 -201.172537) (xy 93.998846 -201.123902) (xy 93.978923 -201.071811)
			(xy 93.966797 -201.017374) (xy 93.962726 -200.961752) (xy 92.925392 -200.961752) (xy 93.56471 -201.60107)
			(xy 93.572108 -201.607918) (xy 93.590706 -201.615654) (xy 93.600778 -201.616056) (xy 98.136456 -201.616056)
			(xy 98.147984 -201.6155) (xy 98.16873 -201.605438) (xy 98.176334 -201.596752) (xy 98.232976 -201.524616)
			(xy 98.238056 -201.501756) (xy 98.235262 -201.49058) (xy 98.227564 -201.456491) (xy 98.21929 -201.387094)
			(xy 98.218752 -201.35215) (xy 98.219294 -201.316432) (xy 98.22791 -201.245519) (xy 98.245011 -201.17616)
			(xy 98.270347 -201.109369) (xy 98.303549 -201.046118) (xy 98.344132 -200.98733) (xy 98.391505 -200.933863)
			(xy 98.444978 -200.886495) (xy 98.50377 -200.845918) (xy 98.567024 -200.812722) (xy 98.633818 -200.787393)
			(xy 98.703178 -200.7703) (xy 98.774092 -200.761691) (xy 98.80981 -200.761092) (xy 98.844634 -200.761616)
			(xy 98.913795 -200.769834) (xy 98.981511 -200.78612) (xy 99.046846 -200.810249) (xy 99.108893 -200.841886)
			(xy 99.166794 -200.880594) (xy 99.193604 -200.902824) (xy 99.200692 -200.908406) (xy 99.217609 -200.914644)
			(xy 99.226624 -200.915016) (xy 99.256596 -200.915016) (xy 99.265613 -200.914657) (xy 99.282531 -200.908413)
			(xy 99.289616 -200.902824) (xy 99.316417 -200.880581) (xy 99.374313 -200.841863) (xy 99.436361 -200.810222)
			(xy 99.501699 -200.786096) (xy 99.56942 -200.76982) (xy 99.638585 -200.761619) (xy 99.67341 -200.761092)
			(xy 99.709131 -200.761632) (xy 99.780051 -200.770244) (xy 99.849416 -200.787341) (xy 99.916214 -200.812674)
			(xy 99.979473 -200.845873) (xy 100.038268 -200.886455) (xy 100.091744 -200.933828) (xy 100.13912 -200.9873)
			(xy 100.179706 -201.046093) (xy 100.21291 -201.109349) (xy 100.238247 -201.176146) (xy 100.255349 -201.24551)
			(xy 100.263966 -201.31643) (xy 100.264468 -201.35215) (xy 100.263989 -201.385312) (xy 100.256538 -201.451217)
			(xy 100.241757 -201.515874) (xy 100.219831 -201.57847) (xy 100.191037 -201.638218) (xy 100.155737 -201.694369)
			(xy 100.114374 -201.746215) (xy 100.09124 -201.76998) (xy 99.98837 -201.87285) (xy 99.981524 -201.880248)
			(xy 99.973796 -201.898847) (xy 99.973384 -201.908918) (xy 99.973384 -201.9935) (xy 99.97292 -202.026655)
			(xy 99.9655 -202.092548) (xy 99.950753 -202.157197) (xy 99.928865 -202.21979) (xy 99.90011 -202.279541)
			(xy 99.864849 -202.335699) (xy 99.823526 -202.387558) (xy 99.80041 -202.41133) (xy 99.799283 -202.412457)
			(xy 100.513523 -202.412457) (xy 100.513523 -202.357943) (xy 100.521282 -202.303984) (xy 100.536641 -202.251678)
			(xy 100.559289 -202.202091) (xy 100.588763 -202.156232) (xy 100.624464 -202.115035) (xy 100.665666 -202.079338)
			(xy 100.711528 -202.049869) (xy 100.761117 -202.027227) (xy 100.813425 -202.011873) (xy 100.867385 -202.00412)
			(xy 100.894642 -202.00366) (xy 100.920958 -202.00408) (xy 100.973089 -202.011322) (xy 101.023734 -202.025649)
			(xy 101.071933 -202.04679) (xy 101.116775 -202.074346) (xy 101.157412 -202.107794) (xy 101.175566 -202.12685)
			(xy 101.183105 -202.134231) (xy 101.202372 -202.142769) (xy 101.212904 -202.14336) (xy 101.28758 -202.14336)
			(xy 101.298132 -202.142846) (xy 101.317428 -202.134301) (xy 101.324918 -202.12685) (xy 101.343062 -202.107783)
			(xy 101.383695 -202.074329) (xy 101.428538 -202.046773) (xy 101.476741 -202.025637) (xy 101.52739 -202.011321)
			(xy 101.579525 -202.004098) (xy 101.605842 -202.00366) (xy 101.633089 -202.004213) (xy 101.687028 -202.011974)
			(xy 101.739313 -202.027331) (xy 101.788881 -202.049973) (xy 101.834722 -202.079438) (xy 101.840276 -202.084251)
			(xy 107.238778 -202.084251) (xy 107.238778 -202.029749) (xy 107.246534 -201.975801) (xy 107.261889 -201.923506)
			(xy 107.284531 -201.873929) (xy 107.313997 -201.828079) (xy 107.349688 -201.786888) (xy 107.390879 -201.751197)
			(xy 107.436729 -201.721731) (xy 107.486306 -201.699089) (xy 107.538601 -201.683734) (xy 107.592549 -201.675978)
			(xy 107.647051 -201.675978) (xy 107.700999 -201.683734) (xy 107.753294 -201.699089) (xy 107.802871 -201.721731)
			(xy 107.848721 -201.751197) (xy 107.889912 -201.786888) (xy 107.925603 -201.828079) (xy 107.955069 -201.873929)
			(xy 107.977711 -201.923506) (xy 107.993066 -201.975801) (xy 108.000822 -202.029749) (xy 108.001308 -202.057)
			(xy 108.000292 -202.08367) (xy 108.000292 -202.083924) (xy 107.999786 -202.098586) (xy 108.006225 -202.127196)
			(xy 108.02053 -202.152797) (xy 108.041521 -202.173277) (xy 108.067467 -202.186946) (xy 108.096228 -202.192678)
			(xy 108.125431 -202.19) (xy 108.13923 -202.185016) (xy 108.161697 -202.176484) (xy 108.208237 -202.164495)
			(xy 108.255916 -202.158455) (xy 108.279946 -202.158092) (xy 108.2802 -202.158092) (xy 108.307451 -202.158578)
			(xy 108.361399 -202.166334) (xy 108.413694 -202.181689) (xy 108.463271 -202.204331) (xy 108.509121 -202.233797)
			(xy 108.550312 -202.269488) (xy 108.586003 -202.310679) (xy 108.615469 -202.356529) (xy 108.638111 -202.406106)
			(xy 108.653466 -202.458401) (xy 108.661222 -202.512349) (xy 108.661222 -202.5396) (xy 108.990382 -202.5396)
			(xy 108.994453 -202.483978) (xy 109.006579 -202.429541) (xy 109.026502 -202.37745) (xy 109.053798 -202.328815)
			(xy 109.087884 -202.284672) (xy 109.128033 -202.245963) (xy 109.173391 -202.213512) (xy 109.222991 -202.188011)
			(xy 109.275775 -202.170004) (xy 109.330618 -202.159874) (xy 109.386352 -202.157837) (xy 109.441789 -202.163937)
			(xy 109.495746 -202.178043) (xy 109.547075 -202.199855) (xy 109.594681 -202.228909) (xy 109.637549 -202.264584)
			(xy 109.674766 -202.306121) (xy 109.705539 -202.352634) (xy 109.729211 -202.403131) (xy 109.745279 -202.456538)
			(xy 109.753399 -202.511714) (xy 109.753908 -202.5396) (xy 109.879382 -202.5396) (xy 109.883453 -202.483978)
			(xy 109.895579 -202.429541) (xy 109.915502 -202.37745) (xy 109.942798 -202.328815) (xy 109.976884 -202.284672)
			(xy 110.017033 -202.245963) (xy 110.062391 -202.213512) (xy 110.111991 -202.188011) (xy 110.164775 -202.170004)
			(xy 110.219618 -202.159874) (xy 110.275352 -202.157837) (xy 110.330789 -202.163937) (xy 110.384746 -202.178043)
			(xy 110.436075 -202.199855) (xy 110.483681 -202.228909) (xy 110.526549 -202.264584) (xy 110.563766 -202.306121)
			(xy 110.594539 -202.352634) (xy 110.618211 -202.403131) (xy 110.634279 -202.456538) (xy 110.642399 -202.511714)
			(xy 110.642908 -202.5396) (xy 110.642399 -202.567486) (xy 110.634279 -202.622662) (xy 110.618211 -202.676069)
			(xy 110.594539 -202.726566) (xy 110.563766 -202.773079) (xy 110.526549 -202.814616) (xy 110.483681 -202.850291)
			(xy 110.436075 -202.879345) (xy 110.384746 -202.901157) (xy 110.330789 -202.915263) (xy 110.275352 -202.921363)
			(xy 110.219618 -202.919326) (xy 110.164775 -202.909196) (xy 110.111991 -202.891189) (xy 110.062391 -202.865688)
			(xy 110.017033 -202.833237) (xy 109.976884 -202.794528) (xy 109.942798 -202.750385) (xy 109.915502 -202.70175)
			(xy 109.895579 -202.649659) (xy 109.883453 -202.595222) (xy 109.879382 -202.5396) (xy 109.753908 -202.5396)
			(xy 109.753399 -202.567486) (xy 109.745279 -202.622662) (xy 109.729211 -202.676069) (xy 109.705539 -202.726566)
			(xy 109.674766 -202.773079) (xy 109.637549 -202.814616) (xy 109.594681 -202.850291) (xy 109.547075 -202.879345)
			(xy 109.495746 -202.901157) (xy 109.441789 -202.915263) (xy 109.386352 -202.921363) (xy 109.330618 -202.919326)
			(xy 109.275775 -202.909196) (xy 109.222991 -202.891189) (xy 109.173391 -202.865688) (xy 109.128033 -202.833237)
			(xy 109.087884 -202.794528) (xy 109.053798 -202.750385) (xy 109.026502 -202.70175) (xy 109.006579 -202.649659)
			(xy 108.994453 -202.595222) (xy 108.990382 -202.5396) (xy 108.661222 -202.5396) (xy 108.661222 -202.566851)
			(xy 108.653466 -202.620799) (xy 108.638111 -202.673094) (xy 108.615469 -202.722671) (xy 108.586003 -202.768521)
			(xy 108.550312 -202.809712) (xy 108.509121 -202.845403) (xy 108.463271 -202.874869) (xy 108.413694 -202.897511)
			(xy 108.361399 -202.912866) (xy 108.307451 -202.920622) (xy 108.252949 -202.920622) (xy 108.199001 -202.912866)
			(xy 108.146706 -202.897511) (xy 108.097129 -202.874869) (xy 108.051279 -202.845403) (xy 108.010088 -202.809712)
			(xy 107.974397 -202.768521) (xy 107.944931 -202.722671) (xy 107.922289 -202.673094) (xy 107.906934 -202.620799)
			(xy 107.899178 -202.566851) (xy 107.898692 -202.5396) (xy 107.899708 -202.51293) (xy 107.899708 -202.512676)
			(xy 107.900214 -202.498014) (xy 107.893775 -202.469404) (xy 107.87947 -202.443803) (xy 107.858479 -202.423323)
			(xy 107.832533 -202.409654) (xy 107.803772 -202.403922) (xy 107.774569 -202.4066) (xy 107.76077 -202.411584)
			(xy 107.738303 -202.420116) (xy 107.691763 -202.432105) (xy 107.644084 -202.438145) (xy 107.620054 -202.438508)
			(xy 107.6198 -202.438508) (xy 107.592549 -202.438022) (xy 107.538601 -202.430266) (xy 107.486306 -202.414911)
			(xy 107.436729 -202.392269) (xy 107.390879 -202.362803) (xy 107.349688 -202.327112) (xy 107.313997 -202.285921)
			(xy 107.284531 -202.240071) (xy 107.261889 -202.190494) (xy 107.246534 -202.138199) (xy 107.238778 -202.084251)
			(xy 101.840276 -202.084251) (xy 101.875903 -202.115126) (xy 101.911587 -202.156312) (xy 101.941047 -202.202156)
			(xy 101.963683 -202.251727) (xy 101.979035 -202.304014) (xy 101.98679 -202.357953) (xy 101.98679 -202.412447)
			(xy 101.979035 -202.466386) (xy 101.963683 -202.518673) (xy 101.941047 -202.568244) (xy 101.911587 -202.614088)
			(xy 101.875903 -202.655274) (xy 101.834722 -202.690962) (xy 101.788881 -202.720427) (xy 101.739313 -202.743069)
			(xy 101.687028 -202.758426) (xy 101.633089 -202.766187) (xy 101.605842 -202.766676) (xy 101.579526 -202.766255)
			(xy 101.527396 -202.759012) (xy 101.476752 -202.744684) (xy 101.428553 -202.723543) (xy 101.38371 -202.695988)
			(xy 101.343073 -202.662541) (xy 101.324918 -202.643486) (xy 101.317394 -202.636088) (xy 101.298116 -202.627562)
			(xy 101.28758 -202.626976) (xy 101.212904 -202.626976) (xy 101.202354 -202.627501) (xy 101.183059 -202.63604)
			(xy 101.175566 -202.643486) (xy 101.157417 -202.662548) (xy 101.116786 -202.696005) (xy 101.071945 -202.723564)
			(xy 101.023743 -202.744701) (xy 100.973094 -202.759017) (xy 100.920959 -202.766239) (xy 100.894642 -202.766676)
			(xy 100.867385 -202.76628) (xy 100.813425 -202.758527) (xy 100.761117 -202.743173) (xy 100.711528 -202.720531)
			(xy 100.665666 -202.691062) (xy 100.624464 -202.655365) (xy 100.588763 -202.614168) (xy 100.559289 -202.568309)
			(xy 100.536641 -202.518722) (xy 100.521282 -202.466416) (xy 100.513523 -202.412457) (xy 99.799283 -202.412457)
			(xy 99.30511 -202.90663) (xy 99.281331 -202.929739) (xy 99.229478 -202.971069) (xy 99.173323 -203.006334)
			(xy 99.113573 -203.035091) (xy 99.05098 -203.056977) (xy 98.986329 -203.071718) (xy 98.920435 -203.079129)
			(xy 98.88728 -203.079604) (xy 93.218 -203.079604) (xy 93.184845 -203.07914) (xy 93.118951 -203.07172)
			(xy 93.054302 -203.056974) (xy 92.991708 -203.035086) (xy 92.931957 -203.006331) (xy 92.875799 -202.971072)
			(xy 92.823939 -202.929749) (xy 92.80017 -202.90663) (xy 90.69197 -200.79843) (xy 90.66886 -200.774652)
			(xy 90.627528 -200.722799) (xy 90.592261 -200.666644) (xy 90.563502 -200.606894) (xy 90.541614 -200.544301)
			(xy 90.526871 -200.47965) (xy 90.519458 -200.413755) (xy 90.518996 -200.3806) (xy 90.518996 -190.499238)
			(xy 90.518548 -190.489483) (xy 90.511254 -190.471387) (xy 90.497741 -190.457314) (xy 90.479956 -190.449292)
			(xy 90.470228 -190.448438) (xy 90.460489 -190.448427) (xy 90.44212 -190.454849) (xy 90.427474 -190.46766)
			(xy 90.418664 -190.48501) (xy 90.417396 -190.494666) (xy 89.216889 -204.216) (xy 96.999296 -204.216)
			(xy 97.003367 -204.160378) (xy 97.015493 -204.105941) (xy 97.035416 -204.05385) (xy 97.062712 -204.005215)
			(xy 97.096798 -203.961072) (xy 97.136947 -203.922363) (xy 97.182305 -203.889912) (xy 97.231905 -203.864411)
			(xy 97.284689 -203.846404) (xy 97.339532 -203.836274) (xy 97.395266 -203.834237) (xy 97.450703 -203.840337)
			(xy 97.50466 -203.854443) (xy 97.555989 -203.876255) (xy 97.603595 -203.905309) (xy 97.646463 -203.940984)
			(xy 97.68368 -203.982521) (xy 97.714453 -204.029034) (xy 97.738125 -204.079531) (xy 97.754193 -204.132938)
			(xy 97.762313 -204.188114) (xy 97.762822 -204.216) (xy 97.762313 -204.243886) (xy 97.754193 -204.299062)
			(xy 97.738125 -204.352469) (xy 97.714453 -204.402966) (xy 97.68368 -204.449479) (xy 97.646463 -204.491016)
			(xy 97.603595 -204.526691) (xy 97.555989 -204.555745) (xy 97.50466 -204.577557) (xy 97.450703 -204.591663)
			(xy 97.395266 -204.597763) (xy 97.339532 -204.595726) (xy 97.284689 -204.585596) (xy 97.231905 -204.567589)
			(xy 97.182305 -204.542088) (xy 97.136947 -204.509637) (xy 97.096798 -204.470928) (xy 97.062712 -204.426785)
			(xy 97.035416 -204.37815) (xy 97.015493 -204.326059) (xy 97.003367 -204.271622) (xy 96.999296 -204.216)
			(xy 89.216889 -204.216) (xy 89.146842 -205.016608) (xy 116.266212 -205.016608) (xy 116.270283 -204.960986)
			(xy 116.282409 -204.906549) (xy 116.302332 -204.854458) (xy 116.329628 -204.805823) (xy 116.363714 -204.76168)
			(xy 116.403863 -204.722971) (xy 116.449221 -204.69052) (xy 116.498821 -204.665019) (xy 116.551605 -204.647012)
			(xy 116.606448 -204.636882) (xy 116.662182 -204.634845) (xy 116.717619 -204.640945) (xy 116.771576 -204.655051)
			(xy 116.822905 -204.676863) (xy 116.870511 -204.705917) (xy 116.913379 -204.741592) (xy 116.950596 -204.783129)
			(xy 116.981369 -204.829642) (xy 117.005041 -204.880139) (xy 117.021109 -204.933546) (xy 117.029229 -204.988722)
			(xy 117.029738 -205.016608) (xy 117.029229 -205.044494) (xy 117.021109 -205.09967) (xy 117.005041 -205.153077)
			(xy 116.981369 -205.203574) (xy 116.950596 -205.250087) (xy 116.913379 -205.291624) (xy 116.870511 -205.327299)
			(xy 116.822905 -205.356353) (xy 116.771576 -205.378165) (xy 116.717619 -205.392271) (xy 116.662182 -205.398371)
			(xy 116.606448 -205.396334) (xy 116.551605 -205.386204) (xy 116.498821 -205.368197) (xy 116.449221 -205.342696)
			(xy 116.403863 -205.310245) (xy 116.363714 -205.271536) (xy 116.329628 -205.227393) (xy 116.302332 -205.178758)
			(xy 116.282409 -205.126667) (xy 116.270283 -205.07223) (xy 116.266212 -205.016608) (xy 89.146842 -205.016608)
			(xy 88.977503 -206.952088) (xy 91.57665 -206.952088) (xy 91.580721 -206.896466) (xy 91.592847 -206.842029)
			(xy 91.61277 -206.789938) (xy 91.640066 -206.741303) (xy 91.674152 -206.69716) (xy 91.714301 -206.658451)
			(xy 91.759659 -206.626) (xy 91.809259 -206.600499) (xy 91.862043 -206.582492) (xy 91.916886 -206.572362)
			(xy 91.97262 -206.570325) (xy 92.028057 -206.576425) (xy 92.082014 -206.590531) (xy 92.133343 -206.612343)
			(xy 92.180949 -206.641397) (xy 92.223817 -206.677072) (xy 92.261034 -206.718609) (xy 92.291807 -206.765122)
			(xy 92.315479 -206.815619) (xy 92.331547 -206.869026) (xy 92.339667 -206.924202) (xy 92.340176 -206.952088)
			(xy 92.339667 -206.979974) (xy 92.331547 -207.03515) (xy 92.329408 -207.042258) (xy 92.503496 -207.042258)
			(xy 92.507567 -206.986636) (xy 92.519693 -206.932199) (xy 92.539616 -206.880108) (xy 92.566912 -206.831473)
			(xy 92.600998 -206.78733) (xy 92.641147 -206.748621) (xy 92.686505 -206.71617) (xy 92.736105 -206.690669)
			(xy 92.788889 -206.672662) (xy 92.843732 -206.662532) (xy 92.899466 -206.660495) (xy 92.954903 -206.666595)
			(xy 93.00886 -206.680701) (xy 93.060189 -206.702513) (xy 93.107795 -206.731567) (xy 93.150663 -206.767242)
			(xy 93.18788 -206.808779) (xy 93.218653 -206.855292) (xy 93.242325 -206.905789) (xy 93.258393 -206.959196)
			(xy 93.266513 -207.014372) (xy 93.267022 -207.042258) (xy 93.266513 -207.070144) (xy 93.264038 -207.086962)
			(xy 93.98076 -207.086962) (xy 93.984831 -207.03134) (xy 93.996957 -206.976903) (xy 94.01688 -206.924812)
			(xy 94.044176 -206.876177) (xy 94.078262 -206.832034) (xy 94.118411 -206.793325) (xy 94.163769 -206.760874)
			(xy 94.213369 -206.735373) (xy 94.266153 -206.717366) (xy 94.320996 -206.707236) (xy 94.37673 -206.705199)
			(xy 94.432167 -206.711299) (xy 94.486124 -206.725405) (xy 94.537453 -206.747217) (xy 94.585059 -206.776271)
			(xy 94.627927 -206.811946) (xy 94.635633 -206.820547) (xy 96.553316 -206.820547) (xy 96.553316 -206.766053)
			(xy 96.561071 -206.712113) (xy 96.576423 -206.659825) (xy 96.59906 -206.610255) (xy 96.628521 -206.56441)
			(xy 96.664206 -206.523225) (xy 96.705389 -206.487537) (xy 96.751232 -206.458073) (xy 96.800801 -206.435433)
			(xy 96.853087 -206.420077) (xy 96.907027 -206.412318) (xy 96.934274 -206.41183) (xy 96.963191 -206.412356)
			(xy 97.020362 -206.421082) (xy 97.075561 -206.438337) (xy 97.127523 -206.463727) (xy 97.175057 -206.49667)
			(xy 97.217074 -206.536411) (xy 97.235264 -206.558896) (xy 97.24263 -206.568548) (xy 97.263966 -206.578708)
			(xy 97.369376 -206.577184) (xy 97.390458 -206.566262) (xy 97.397316 -206.55661) (xy 97.415454 -206.53289)
			(xy 97.457838 -206.490833) (xy 97.506252 -206.455885) (xy 97.559515 -206.428899) (xy 97.616329 -206.410533)
			(xy 97.675309 -206.401233) (xy 97.705164 -206.400654) (xy 97.734969 -206.40125) (xy 97.793851 -206.410536)
			(xy 97.85057 -206.42887) (xy 97.903747 -206.455807) (xy 97.952084 -206.49069) (xy 97.994404 -206.53267)
			(xy 98.012504 -206.556356) (xy 98.012758 -206.55661) (xy 98.018331 -206.563579) (xy 98.033234 -206.573372)
			(xy 98.050602 -206.577423) (xy 98.059494 -206.576676) (xy 98.147886 -206.565754) (xy 98.156673 -206.564234)
			(xy 98.172522 -206.556093) (xy 98.184674 -206.543062) (xy 98.188526 -206.53502) (xy 98.188526 -206.534766)
			(xy 98.199728 -206.508917) (xy 98.228558 -206.46052) (xy 98.264194 -206.416892) (xy 98.305861 -206.378981)
			(xy 98.352652 -206.347613) (xy 98.40355 -206.32347) (xy 98.457445 -206.307079) (xy 98.513166 -206.298795)
			(xy 98.541332 -206.298292) (xy 98.568582 -206.29878) (xy 98.622526 -206.30654) (xy 98.674817 -206.321898)
			(xy 98.72439 -206.344541) (xy 98.770237 -206.374008) (xy 98.811423 -206.4097) (xy 98.847111 -206.450889)
			(xy 98.876574 -206.496738) (xy 98.899213 -206.546313) (xy 98.914567 -206.598605) (xy 98.922322 -206.65255)
			(xy 98.922322 -206.70705) (xy 98.914567 -206.760995) (xy 98.899213 -206.813287) (xy 98.876574 -206.862862)
			(xy 98.847111 -206.908711) (xy 98.811423 -206.9499) (xy 98.770237 -206.985592) (xy 98.72439 -207.015059)
			(xy 98.674817 -207.037702) (xy 98.622526 -207.05306) (xy 98.568582 -207.06082) (xy 98.541332 -207.061308)
			(xy 98.511529 -207.060689) (xy 98.452649 -207.051405) (xy 98.395931 -207.033073) (xy 98.342755 -207.006141)
			(xy 98.294417 -206.971263) (xy 98.252094 -206.929289) (xy 98.233992 -206.905606) (xy 98.233738 -206.905352)
			(xy 98.228176 -206.898374) (xy 98.213266 -206.888586) (xy 98.195895 -206.884538) (xy 98.187002 -206.885286)
			(xy 98.09861 -206.896208) (xy 98.089815 -206.897692) (xy 98.073962 -206.905844) (xy 98.061816 -206.918892)
			(xy 98.05797 -206.926942) (xy 98.05797 -206.927196) (xy 98.046802 -206.95306) (xy 98.017965 -207.001455)
			(xy 97.982323 -207.045081) (xy 97.94065 -207.08299) (xy 97.893854 -207.114355) (xy 97.842953 -207.138495)
			(xy 97.789055 -207.154885) (xy 97.733332 -207.163167) (xy 97.705164 -207.16367) (xy 97.676248 -207.163117)
			(xy 97.619078 -207.154397) (xy 97.563879 -207.137147) (xy 97.511917 -207.111762) (xy 97.464383 -207.078824)
			(xy 97.422365 -207.039087) (xy 97.404174 -207.016604) (xy 97.396808 -207.006952) (xy 97.375472 -206.996792)
			(xy 97.270062 -206.998316) (xy 97.24898 -207.009238) (xy 97.242122 -207.01889) (xy 97.22402 -207.04264)
			(xy 97.181629 -207.084695) (xy 97.133208 -207.119639) (xy 97.079938 -207.14662) (xy 97.023117 -207.16498)
			(xy 96.964131 -207.174271) (xy 96.934274 -207.174846) (xy 96.907027 -207.174282) (xy 96.853087 -207.166523)
			(xy 96.800801 -207.151167) (xy 96.751232 -207.128527) (xy 96.705389 -207.099063) (xy 96.664206 -207.063375)
			(xy 96.628521 -207.02219) (xy 96.59906 -206.976345) (xy 96.576423 -206.926775) (xy 96.561071 -206.874487)
			(xy 96.553316 -206.820547) (xy 94.635633 -206.820547) (xy 94.665144 -206.853483) (xy 94.695917 -206.899996)
			(xy 94.719589 -206.950493) (xy 94.735657 -207.0039) (xy 94.743777 -207.059076) (xy 94.744286 -207.086962)
			(xy 94.743777 -207.114848) (xy 94.735657 -207.170024) (xy 94.719589 -207.223431) (xy 94.695917 -207.273928)
			(xy 94.665144 -207.320441) (xy 94.627927 -207.361978) (xy 94.585059 -207.397653) (xy 94.537453 -207.426707)
			(xy 94.486124 -207.448519) (xy 94.432167 -207.462625) (xy 94.37673 -207.468725) (xy 94.320996 -207.466688)
			(xy 94.266153 -207.456558) (xy 94.213369 -207.438551) (xy 94.163769 -207.41305) (xy 94.118411 -207.380599)
			(xy 94.078262 -207.34189) (xy 94.044176 -207.297747) (xy 94.01688 -207.249112) (xy 93.996957 -207.197021)
			(xy 93.984831 -207.142584) (xy 93.98076 -207.086962) (xy 93.264038 -207.086962) (xy 93.258393 -207.12532)
			(xy 93.242325 -207.178727) (xy 93.218653 -207.229224) (xy 93.18788 -207.275737) (xy 93.150663 -207.317274)
			(xy 93.107795 -207.352949) (xy 93.060189 -207.382003) (xy 93.00886 -207.403815) (xy 92.954903 -207.417921)
			(xy 92.899466 -207.424021) (xy 92.843732 -207.421984) (xy 92.788889 -207.411854) (xy 92.736105 -207.393847)
			(xy 92.686505 -207.368346) (xy 92.641147 -207.335895) (xy 92.600998 -207.297186) (xy 92.566912 -207.253043)
			(xy 92.539616 -207.204408) (xy 92.519693 -207.152317) (xy 92.507567 -207.09788) (xy 92.503496 -207.042258)
			(xy 92.329408 -207.042258) (xy 92.315479 -207.088557) (xy 92.291807 -207.139054) (xy 92.261034 -207.185567)
			(xy 92.223817 -207.227104) (xy 92.180949 -207.262779) (xy 92.133343 -207.291833) (xy 92.082014 -207.313645)
			(xy 92.028057 -207.327751) (xy 91.97262 -207.333851) (xy 91.916886 -207.331814) (xy 91.862043 -207.321684)
			(xy 91.809259 -207.303677) (xy 91.759659 -207.278176) (xy 91.714301 -207.245725) (xy 91.674152 -207.207016)
			(xy 91.640066 -207.162873) (xy 91.61277 -207.114238) (xy 91.592847 -207.062147) (xy 91.580721 -207.00771)
			(xy 91.57665 -206.952088) (xy 88.977503 -206.952088) (xy 88.833898 -208.593436) (xy 119.926098 -208.593436)
			(xy 119.930169 -208.537814) (xy 119.942295 -208.483377) (xy 119.962218 -208.431286) (xy 119.989514 -208.382651)
			(xy 120.0236 -208.338508) (xy 120.063749 -208.299799) (xy 120.109107 -208.267348) (xy 120.158707 -208.241847)
			(xy 120.211491 -208.22384) (xy 120.266334 -208.21371) (xy 120.322068 -208.211673) (xy 120.377505 -208.217773)
			(xy 120.431462 -208.231879) (xy 120.482791 -208.253691) (xy 120.530397 -208.282745) (xy 120.573265 -208.31842)
			(xy 120.610482 -208.359957) (xy 120.641255 -208.40647) (xy 120.664927 -208.456967) (xy 120.680995 -208.510374)
			(xy 120.689115 -208.56555) (xy 120.689624 -208.593436) (xy 120.689115 -208.621322) (xy 120.680995 -208.676498)
			(xy 120.664927 -208.729905) (xy 120.641255 -208.780402) (xy 120.610482 -208.826915) (xy 120.573265 -208.868452)
			(xy 120.530397 -208.904127) (xy 120.482791 -208.933181) (xy 120.431462 -208.954993) (xy 120.377505 -208.969099)
			(xy 120.322068 -208.975199) (xy 120.266334 -208.973162) (xy 120.211491 -208.963032) (xy 120.158707 -208.945025)
			(xy 120.109107 -208.919524) (xy 120.063749 -208.887073) (xy 120.0236 -208.848364) (xy 119.989514 -208.804221)
			(xy 119.962218 -208.755586) (xy 119.942295 -208.703495) (xy 119.930169 -208.649058) (xy 119.926098 -208.593436)
			(xy 88.833898 -208.593436) (xy 88.601468 -211.250022) (xy 104.08031 -211.250022) (xy 104.080787 -211.222652)
			(xy 104.088601 -211.168473) (xy 104.104088 -211.11597) (xy 104.126927 -211.066223) (xy 104.15665 -211.020256)
			(xy 104.17429 -210.999324) (xy 104.174544 -210.99907) (xy 104.180113 -210.991971) (xy 104.186369 -210.975064)
			(xy 104.186736 -210.96605) (xy 104.186736 -210.898994) (xy 104.186374 -210.889978) (xy 104.180129 -210.873061)
			(xy 104.174544 -210.865974) (xy 104.17429 -210.865974) (xy 104.17429 -210.86572) (xy 104.156645 -210.844793)
			(xy 104.126935 -210.798818) (xy 104.1041 -210.74907) (xy 104.08861 -210.696568) (xy 104.080783 -210.642391)
			(xy 104.08031 -210.615022) (xy 104.080776 -210.587769) (xy 104.08853 -210.533817) (xy 104.103884 -210.481518)
			(xy 104.126526 -210.431937) (xy 104.155993 -210.386083) (xy 104.191687 -210.344889) (xy 104.23288 -210.309195)
			(xy 104.278733 -210.279728) (xy 104.328314 -210.257086) (xy 104.380613 -210.241731) (xy 104.434565 -210.233976)
			(xy 104.461818 -210.233514) (xy 104.489189 -210.233966) (xy 104.543369 -210.241787) (xy 104.595872 -210.257279)
			(xy 104.645619 -210.280124) (xy 104.691585 -210.309851) (xy 104.712516 -210.327494) (xy 104.71277 -210.327748)
			(xy 104.719857 -210.333334) (xy 104.736774 -210.33958) (xy 104.74579 -210.33994) (xy 104.812846 -210.33994)
			(xy 104.821862 -210.33957) (xy 104.83878 -210.333333) (xy 104.845866 -210.327748) (xy 104.845866 -210.327494)
			(xy 104.84612 -210.327494) (xy 104.867053 -210.309853) (xy 104.913021 -210.280129) (xy 104.962767 -210.257283)
			(xy 105.015269 -210.241787) (xy 105.069447 -210.233958) (xy 105.124189 -210.233958) (xy 105.178367 -210.241787)
			(xy 105.230869 -210.257283) (xy 105.280615 -210.280129) (xy 105.326583 -210.309853) (xy 105.347516 -210.327494)
			(xy 105.34777 -210.327748) (xy 105.354857 -210.333334) (xy 105.371774 -210.33958) (xy 105.38079 -210.33994)
			(xy 105.447846 -210.33994) (xy 105.456862 -210.33957) (xy 105.47378 -210.333333) (xy 105.480866 -210.327748)
			(xy 105.480866 -210.327494) (xy 105.48112 -210.327494) (xy 105.502071 -210.309878) (xy 105.548038 -210.280163)
			(xy 105.597781 -210.257323) (xy 105.650278 -210.241826) (xy 105.70445 -210.233992) (xy 105.731818 -210.233514)
			(xy 105.759072 -210.233938) (xy 105.813026 -210.241698) (xy 105.865326 -210.257058) (xy 105.914908 -210.279704)
			(xy 105.960762 -210.309176) (xy 106.001955 -210.344874) (xy 106.037648 -210.38607) (xy 106.067115 -210.431928)
			(xy 106.081246 -210.462876) (xy 121.397774 -210.462876) (xy 121.401845 -210.407254) (xy 121.413971 -210.352817)
			(xy 121.433894 -210.300726) (xy 121.46119 -210.252091) (xy 121.495276 -210.207948) (xy 121.535425 -210.169239)
			(xy 121.580783 -210.136788) (xy 121.630383 -210.111287) (xy 121.683167 -210.09328) (xy 121.73801 -210.08315)
			(xy 121.793744 -210.081113) (xy 121.849181 -210.087213) (xy 121.903138 -210.101319) (xy 121.954467 -210.123131)
			(xy 122.002073 -210.152185) (xy 122.044941 -210.18786) (xy 122.082158 -210.229397) (xy 122.112931 -210.27591)
			(xy 122.136603 -210.326407) (xy 122.152671 -210.379814) (xy 122.160791 -210.43499) (xy 122.1613 -210.462876)
			(xy 122.160791 -210.490762) (xy 122.152671 -210.545938) (xy 122.136603 -210.599345) (xy 122.112931 -210.649842)
			(xy 122.082158 -210.696355) (xy 122.044941 -210.737892) (xy 122.002073 -210.773567) (xy 121.954467 -210.802621)
			(xy 121.903138 -210.824433) (xy 121.849181 -210.838539) (xy 121.793744 -210.844639) (xy 121.73801 -210.842602)
			(xy 121.683167 -210.832472) (xy 121.630383 -210.814465) (xy 121.580783 -210.788964) (xy 121.535425 -210.756513)
			(xy 121.495276 -210.717804) (xy 121.46119 -210.673661) (xy 121.433894 -210.625026) (xy 121.413971 -210.572935)
			(xy 121.401845 -210.518498) (xy 121.397774 -210.462876) (xy 106.081246 -210.462876) (xy 106.089756 -210.481512)
			(xy 106.10511 -210.533813) (xy 106.112865 -210.587768) (xy 106.113326 -210.615022) (xy 106.112891 -210.642394)
			(xy 106.105068 -210.696575) (xy 106.089573 -210.749079) (xy 106.066724 -210.798825) (xy 106.036991 -210.84479)
			(xy 106.019346 -210.86572) (xy 106.019092 -210.865974) (xy 106.013509 -210.873063) (xy 106.007261 -210.889978)
			(xy 106.0069 -210.898994) (xy 106.0069 -210.938872) (xy 125.26594 -210.938872) (xy 125.270011 -210.88325)
			(xy 125.282137 -210.828813) (xy 125.30206 -210.776722) (xy 125.329356 -210.728087) (xy 125.363442 -210.683944)
			(xy 125.403591 -210.645235) (xy 125.448949 -210.612784) (xy 125.498549 -210.587283) (xy 125.551333 -210.569276)
			(xy 125.606176 -210.559146) (xy 125.66191 -210.557109) (xy 125.717347 -210.563209) (xy 125.771304 -210.577315)
			(xy 125.822633 -210.599127) (xy 125.870239 -210.628181) (xy 125.913107 -210.663856) (xy 125.950324 -210.705393)
			(xy 125.981097 -210.751906) (xy 126.004769 -210.802403) (xy 126.020837 -210.85581) (xy 126.028957 -210.910986)
			(xy 126.029466 -210.938872) (xy 126.028957 -210.966758) (xy 126.020837 -211.021934) (xy 126.004769 -211.075341)
			(xy 125.981097 -211.125838) (xy 125.950324 -211.172351) (xy 125.913107 -211.213888) (xy 125.870239 -211.249563)
			(xy 125.822633 -211.278617) (xy 125.771304 -211.300429) (xy 125.717347 -211.314535) (xy 125.66191 -211.320635)
			(xy 125.606176 -211.318598) (xy 125.551333 -211.308468) (xy 125.498549 -211.290461) (xy 125.448949 -211.26496)
			(xy 125.403591 -211.232509) (xy 125.363442 -211.1938) (xy 125.329356 -211.149657) (xy 125.30206 -211.101022)
			(xy 125.282137 -211.048931) (xy 125.270011 -210.994494) (xy 125.26594 -210.938872) (xy 106.0069 -210.938872)
			(xy 106.0069 -210.96605) (xy 106.007281 -210.975064) (xy 106.013512 -210.991981) (xy 106.019092 -210.99907)
			(xy 106.019346 -210.99907) (xy 106.019346 -210.999324) (xy 106.036955 -211.020281) (xy 106.066673 -211.066246)
			(xy 106.089516 -211.115987) (xy 106.105014 -211.168483) (xy 106.112849 -211.222654) (xy 106.113326 -211.250022)
			(xy 106.112843 -211.277273) (xy 106.105084 -211.33122) (xy 106.089727 -211.383514) (xy 106.067084 -211.43309)
			(xy 106.037617 -211.478939) (xy 106.001926 -211.520129) (xy 105.960736 -211.55582) (xy 105.914886 -211.585286)
			(xy 105.86531 -211.607928) (xy 105.813016 -211.623285) (xy 105.759069 -211.631043) (xy 105.731818 -211.63153)
			(xy 105.704447 -211.63107) (xy 105.650267 -211.623254) (xy 105.597763 -211.607764) (xy 105.548017 -211.58492)
			(xy 105.502051 -211.555193) (xy 105.48112 -211.53755) (xy 105.480866 -211.537296) (xy 105.473765 -211.53173)
			(xy 105.456859 -211.525471) (xy 105.447846 -211.525104) (xy 105.38079 -211.525104) (xy 105.371773 -211.525455)
			(xy 105.354856 -211.531707) (xy 105.34777 -211.537296) (xy 105.34777 -211.53755) (xy 105.347516 -211.53755)
			(xy 105.326583 -211.555191) (xy 105.280615 -211.584915) (xy 105.230869 -211.607761) (xy 105.178367 -211.623257)
			(xy 105.124189 -211.631086) (xy 105.069447 -211.631086) (xy 105.015269 -211.623257) (xy 104.962767 -211.607761)
			(xy 104.913021 -211.584915) (xy 104.867053 -211.555191) (xy 104.84612 -211.53755) (xy 104.845866 -211.537296)
			(xy 104.838765 -211.53173) (xy 104.821859 -211.525471) (xy 104.812846 -211.525104) (xy 104.74579 -211.525104)
			(xy 104.736773 -211.525455) (xy 104.719856 -211.531707) (xy 104.71277 -211.537296) (xy 104.71277 -211.53755)
			(xy 104.712516 -211.53755) (xy 104.691582 -211.555187) (xy 104.645611 -211.584901) (xy 104.595864 -211.607738)
			(xy 104.543363 -211.623229) (xy 104.489187 -211.631057) (xy 104.461818 -211.63153) (xy 104.434568 -211.631005)
			(xy 104.380623 -211.623252) (xy 104.32833 -211.6079) (xy 104.278755 -211.585262) (xy 104.232905 -211.5558)
			(xy 104.191716 -211.520113) (xy 104.156024 -211.478927) (xy 104.126557 -211.43308) (xy 104.103914 -211.383507)
			(xy 104.088557 -211.331216) (xy 104.080798 -211.277272) (xy 104.08031 -211.250022) (xy 88.601468 -211.250022)
			(xy 88.495487 -212.461348) (xy 90.60256 -212.461348) (xy 90.606631 -212.405726) (xy 90.618757 -212.351289)
			(xy 90.63868 -212.299198) (xy 90.665976 -212.250563) (xy 90.700062 -212.20642) (xy 90.740211 -212.167711)
			(xy 90.785569 -212.13526) (xy 90.835169 -212.109759) (xy 90.887953 -212.091752) (xy 90.942796 -212.081622)
			(xy 90.99853 -212.079585) (xy 91.053967 -212.085685) (xy 91.107924 -212.099791) (xy 91.159253 -212.121603)
			(xy 91.206859 -212.150657) (xy 91.249727 -212.186332) (xy 91.286944 -212.227869) (xy 91.294205 -212.238844)
			(xy 125.366524 -212.238844) (xy 125.370595 -212.183222) (xy 125.382721 -212.128785) (xy 125.402644 -212.076694)
			(xy 125.42994 -212.028059) (xy 125.464026 -211.983916) (xy 125.504175 -211.945207) (xy 125.549533 -211.912756)
			(xy 125.599133 -211.887255) (xy 125.651917 -211.869248) (xy 125.70676 -211.859118) (xy 125.762494 -211.857081)
			(xy 125.817931 -211.863181) (xy 125.871888 -211.877287) (xy 125.923217 -211.899099) (xy 125.970823 -211.928153)
			(xy 126.013691 -211.963828) (xy 126.033432 -211.98586) (xy 130.34721 -211.98586) (xy 130.351281 -211.930238)
			(xy 130.363407 -211.875801) (xy 130.38333 -211.82371) (xy 130.410626 -211.775075) (xy 130.444712 -211.730932)
			(xy 130.484861 -211.692223) (xy 130.530219 -211.659772) (xy 130.579819 -211.634271) (xy 130.632603 -211.616264)
			(xy 130.687446 -211.606134) (xy 130.74318 -211.604097) (xy 130.798617 -211.610197) (xy 130.852574 -211.624303)
			(xy 130.903903 -211.646115) (xy 130.951509 -211.675169) (xy 130.994377 -211.710844) (xy 131.031594 -211.752381)
			(xy 131.062367 -211.798894) (xy 131.086039 -211.849391) (xy 131.102107 -211.902798) (xy 131.110227 -211.957974)
			(xy 131.110736 -211.98586) (xy 131.110227 -212.013746) (xy 131.102107 -212.068922) (xy 131.086039 -212.122329)
			(xy 131.062367 -212.172826) (xy 131.031594 -212.219339) (xy 130.994377 -212.260876) (xy 130.951509 -212.296551)
			(xy 130.903903 -212.325605) (xy 130.852574 -212.347417) (xy 130.798617 -212.361523) (xy 130.74318 -212.367623)
			(xy 130.687446 -212.365586) (xy 130.632603 -212.355456) (xy 130.579819 -212.337449) (xy 130.530219 -212.311948)
			(xy 130.484861 -212.279497) (xy 130.444712 -212.240788) (xy 130.410626 -212.196645) (xy 130.38333 -212.14801)
			(xy 130.363407 -212.095919) (xy 130.351281 -212.041482) (xy 130.34721 -211.98586) (xy 126.033432 -211.98586)
			(xy 126.050908 -212.005365) (xy 126.081681 -212.051878) (xy 126.105353 -212.102375) (xy 126.121421 -212.155782)
			(xy 126.129541 -212.210958) (xy 126.13005 -212.238844) (xy 126.129541 -212.26673) (xy 126.121421 -212.321906)
			(xy 126.105353 -212.375313) (xy 126.081681 -212.42581) (xy 126.050908 -212.472323) (xy 126.013691 -212.51386)
			(xy 125.970823 -212.549535) (xy 125.923217 -212.578589) (xy 125.871888 -212.600401) (xy 125.817931 -212.614507)
			(xy 125.762494 -212.620607) (xy 125.70676 -212.61857) (xy 125.651917 -212.60844) (xy 125.599133 -212.590433)
			(xy 125.549533 -212.564932) (xy 125.504175 -212.532481) (xy 125.464026 -212.493772) (xy 125.42994 -212.449629)
			(xy 125.402644 -212.400994) (xy 125.382721 -212.348903) (xy 125.370595 -212.294466) (xy 125.366524 -212.238844)
			(xy 91.294205 -212.238844) (xy 91.317717 -212.274382) (xy 91.341389 -212.324879) (xy 91.357457 -212.378286)
			(xy 91.365577 -212.433462) (xy 91.366086 -212.461348) (xy 91.365577 -212.489234) (xy 91.357457 -212.54441)
			(xy 91.341389 -212.597817) (xy 91.317717 -212.648314) (xy 91.286944 -212.694827) (xy 91.249727 -212.736364)
			(xy 91.206859 -212.772039) (xy 91.159253 -212.801093) (xy 91.107924 -212.822905) (xy 91.053967 -212.837011)
			(xy 90.99853 -212.843111) (xy 90.942796 -212.841074) (xy 90.887953 -212.830944) (xy 90.835169 -212.812937)
			(xy 90.785569 -212.787436) (xy 90.740211 -212.754985) (xy 90.700062 -212.716276) (xy 90.665976 -212.672133)
			(xy 90.63868 -212.623498) (xy 90.618757 -212.571407) (xy 90.606631 -212.51697) (xy 90.60256 -212.461348)
			(xy 88.495487 -212.461348) (xy 88.426507 -213.249764) (xy 119.607328 -213.249764) (xy 119.611399 -213.194142)
			(xy 119.623525 -213.139705) (xy 119.643448 -213.087614) (xy 119.670744 -213.038979) (xy 119.70483 -212.994836)
			(xy 119.744979 -212.956127) (xy 119.790337 -212.923676) (xy 119.839937 -212.898175) (xy 119.892721 -212.880168)
			(xy 119.947564 -212.870038) (xy 120.003298 -212.868001) (xy 120.058735 -212.874101) (xy 120.112692 -212.888207)
			(xy 120.164021 -212.910019) (xy 120.211627 -212.939073) (xy 120.254495 -212.974748) (xy 120.291712 -213.016285)
			(xy 120.322485 -213.062798) (xy 120.346157 -213.113295) (xy 120.362225 -213.166702) (xy 120.370345 -213.221878)
			(xy 120.370854 -213.249764) (xy 120.370345 -213.27765) (xy 120.362225 -213.332826) (xy 120.346157 -213.386233)
			(xy 120.322485 -213.43673) (xy 120.291712 -213.483243) (xy 120.254495 -213.52478) (xy 120.211627 -213.560455)
			(xy 120.164021 -213.589509) (xy 120.112692 -213.611321) (xy 120.058735 -213.625427) (xy 120.003298 -213.631527)
			(xy 119.947564 -213.62949) (xy 119.892721 -213.61936) (xy 119.839937 -213.601353) (xy 119.790337 -213.575852)
			(xy 119.744979 -213.543401) (xy 119.70483 -213.504692) (xy 119.670744 -213.460549) (xy 119.643448 -213.411914)
			(xy 119.623525 -213.359823) (xy 119.611399 -213.305386) (xy 119.607328 -213.249764) (xy 88.426507 -213.249764)
			(xy 88.321948 -214.444834) (xy 125.467362 -214.444834) (xy 125.471433 -214.389212) (xy 125.483559 -214.334775)
			(xy 125.503482 -214.282684) (xy 125.530778 -214.234049) (xy 125.564864 -214.189906) (xy 125.605013 -214.151197)
			(xy 125.650371 -214.118746) (xy 125.699971 -214.093245) (xy 125.752755 -214.075238) (xy 125.807598 -214.065108)
			(xy 125.863332 -214.063071) (xy 125.918769 -214.069171) (xy 125.972726 -214.083277) (xy 126.024055 -214.105089)
			(xy 126.071661 -214.134143) (xy 126.114529 -214.169818) (xy 126.151746 -214.211355) (xy 126.182519 -214.257868)
			(xy 126.206191 -214.308365) (xy 126.222259 -214.361772) (xy 126.230379 -214.416948) (xy 126.230888 -214.444834)
			(xy 126.230379 -214.47272) (xy 126.222259 -214.527896) (xy 126.206191 -214.581303) (xy 126.182519 -214.6318)
			(xy 126.151746 -214.678313) (xy 126.114529 -214.71985) (xy 126.071661 -214.755525) (xy 126.024055 -214.784579)
			(xy 125.972726 -214.806391) (xy 125.918769 -214.820497) (xy 125.863332 -214.826597) (xy 125.807598 -214.82456)
			(xy 125.752755 -214.81443) (xy 125.699971 -214.796423) (xy 125.650371 -214.770922) (xy 125.605013 -214.738471)
			(xy 125.564864 -214.699762) (xy 125.530778 -214.655619) (xy 125.503482 -214.606984) (xy 125.483559 -214.554893)
			(xy 125.471433 -214.500456) (xy 125.467362 -214.444834) (xy 88.321948 -214.444834) (xy 88.264191 -215.10498)
			(xy 117.322598 -215.10498) (xy 117.326669 -215.049358) (xy 117.338795 -214.994921) (xy 117.358718 -214.94283)
			(xy 117.386014 -214.894195) (xy 117.4201 -214.850052) (xy 117.460249 -214.811343) (xy 117.505607 -214.778892)
			(xy 117.555207 -214.753391) (xy 117.607991 -214.735384) (xy 117.662834 -214.725254) (xy 117.718568 -214.723217)
			(xy 117.774005 -214.729317) (xy 117.827962 -214.743423) (xy 117.879291 -214.765235) (xy 117.926897 -214.794289)
			(xy 117.969765 -214.829964) (xy 118.006982 -214.871501) (xy 118.037755 -214.918014) (xy 118.061427 -214.968511)
			(xy 118.077495 -215.021918) (xy 118.085615 -215.077094) (xy 118.086124 -215.10498) (xy 118.085615 -215.132866)
			(xy 118.077495 -215.188042) (xy 118.061427 -215.241449) (xy 118.03848 -215.2904) (xy 121.461782 -215.2904)
			(xy 121.465853 -215.234778) (xy 121.477979 -215.180341) (xy 121.497902 -215.12825) (xy 121.525198 -215.079615)
			(xy 121.559284 -215.035472) (xy 121.599433 -214.996763) (xy 121.644791 -214.964312) (xy 121.694391 -214.938811)
			(xy 121.747175 -214.920804) (xy 121.802018 -214.910674) (xy 121.857752 -214.908637) (xy 121.913189 -214.914737)
			(xy 121.967146 -214.928843) (xy 122.018475 -214.950655) (xy 122.066081 -214.979709) (xy 122.108949 -215.015384)
			(xy 122.138931 -215.048846) (xy 129.600196 -215.048846) (xy 129.604267 -214.993224) (xy 129.616393 -214.938787)
			(xy 129.636316 -214.886696) (xy 129.663612 -214.838061) (xy 129.697698 -214.793918) (xy 129.737847 -214.755209)
			(xy 129.783205 -214.722758) (xy 129.832805 -214.697257) (xy 129.885589 -214.67925) (xy 129.940432 -214.66912)
			(xy 129.996166 -214.667083) (xy 130.0031 -214.667846) (xy 132.902196 -214.667846) (xy 132.906267 -214.612224)
			(xy 132.918393 -214.557787) (xy 132.938316 -214.505696) (xy 132.965612 -214.457061) (xy 132.999698 -214.412918)
			(xy 133.039847 -214.374209) (xy 133.085205 -214.341758) (xy 133.134805 -214.316257) (xy 133.187589 -214.29825)
			(xy 133.242432 -214.28812) (xy 133.298166 -214.286083) (xy 133.353603 -214.292183) (xy 133.40756 -214.306289)
			(xy 133.458889 -214.328101) (xy 133.506495 -214.357155) (xy 133.549363 -214.39283) (xy 133.58658 -214.434367)
			(xy 133.617353 -214.48088) (xy 133.641025 -214.531377) (xy 133.657093 -214.584784) (xy 133.665213 -214.63996)
			(xy 133.665722 -214.667846) (xy 134.426196 -214.667846) (xy 134.430267 -214.612224) (xy 134.442393 -214.557787)
			(xy 134.462316 -214.505696) (xy 134.489612 -214.457061) (xy 134.523698 -214.412918) (xy 134.563847 -214.374209)
			(xy 134.609205 -214.341758) (xy 134.658805 -214.316257) (xy 134.711589 -214.29825) (xy 134.766432 -214.28812)
			(xy 134.822166 -214.286083) (xy 134.877603 -214.292183) (xy 134.93156 -214.306289) (xy 134.982889 -214.328101)
			(xy 135.030495 -214.357155) (xy 135.073363 -214.39283) (xy 135.11058 -214.434367) (xy 135.141353 -214.48088)
			(xy 135.165025 -214.531377) (xy 135.181093 -214.584784) (xy 135.189213 -214.63996) (xy 135.189722 -214.667846)
			(xy 135.189213 -214.695732) (xy 135.181093 -214.750908) (xy 135.165025 -214.804315) (xy 135.141353 -214.854812)
			(xy 135.11058 -214.901325) (xy 135.073363 -214.942862) (xy 135.030495 -214.978537) (xy 134.982889 -215.007591)
			(xy 134.93156 -215.029403) (xy 134.877603 -215.043509) (xy 134.822166 -215.049609) (xy 134.766432 -215.047572)
			(xy 134.711589 -215.037442) (xy 134.658805 -215.019435) (xy 134.609205 -214.993934) (xy 134.563847 -214.961483)
			(xy 134.523698 -214.922774) (xy 134.489612 -214.878631) (xy 134.462316 -214.829996) (xy 134.442393 -214.777905)
			(xy 134.430267 -214.723468) (xy 134.426196 -214.667846) (xy 133.665722 -214.667846) (xy 133.665213 -214.695732)
			(xy 133.657093 -214.750908) (xy 133.641025 -214.804315) (xy 133.617353 -214.854812) (xy 133.58658 -214.901325)
			(xy 133.549363 -214.942862) (xy 133.506495 -214.978537) (xy 133.458889 -215.007591) (xy 133.40756 -215.029403)
			(xy 133.353603 -215.043509) (xy 133.298166 -215.049609) (xy 133.242432 -215.047572) (xy 133.187589 -215.037442)
			(xy 133.134805 -215.019435) (xy 133.085205 -214.993934) (xy 133.039847 -214.961483) (xy 132.999698 -214.922774)
			(xy 132.965612 -214.878631) (xy 132.938316 -214.829996) (xy 132.918393 -214.777905) (xy 132.906267 -214.723468)
			(xy 132.902196 -214.667846) (xy 130.0031 -214.667846) (xy 130.051603 -214.673183) (xy 130.10556 -214.687289)
			(xy 130.156889 -214.709101) (xy 130.204495 -214.738155) (xy 130.247363 -214.77383) (xy 130.28458 -214.815367)
			(xy 130.315353 -214.86188) (xy 130.339025 -214.912377) (xy 130.355093 -214.965784) (xy 130.363213 -215.02096)
			(xy 130.363722 -215.048846) (xy 130.363213 -215.076732) (xy 130.355093 -215.131908) (xy 130.339025 -215.185315)
			(xy 130.315353 -215.235812) (xy 130.28458 -215.282325) (xy 130.247363 -215.323862) (xy 130.204495 -215.359537)
			(xy 130.156889 -215.388591) (xy 130.10556 -215.410403) (xy 130.051603 -215.424509) (xy 129.996166 -215.430609)
			(xy 129.940432 -215.428572) (xy 129.885589 -215.418442) (xy 129.832805 -215.400435) (xy 129.783205 -215.374934)
			(xy 129.737847 -215.342483) (xy 129.697698 -215.303774) (xy 129.663612 -215.259631) (xy 129.636316 -215.210996)
			(xy 129.616393 -215.158905) (xy 129.604267 -215.104468) (xy 129.600196 -215.048846) (xy 122.138931 -215.048846)
			(xy 122.146166 -215.056921) (xy 122.176939 -215.103434) (xy 122.200611 -215.153931) (xy 122.216679 -215.207338)
			(xy 122.224799 -215.262514) (xy 122.225308 -215.2904) (xy 122.224799 -215.318286) (xy 122.216679 -215.373462)
			(xy 122.200611 -215.426869) (xy 122.176939 -215.477366) (xy 122.146166 -215.523879) (xy 122.108949 -215.565416)
			(xy 122.066081 -215.601091) (xy 122.018475 -215.630145) (xy 121.967146 -215.651957) (xy 121.913189 -215.666063)
			(xy 121.857752 -215.672163) (xy 121.802018 -215.670126) (xy 121.747175 -215.659996) (xy 121.694391 -215.641989)
			(xy 121.644791 -215.616488) (xy 121.599433 -215.584037) (xy 121.559284 -215.545328) (xy 121.525198 -215.501185)
			(xy 121.497902 -215.45255) (xy 121.477979 -215.400459) (xy 121.465853 -215.346022) (xy 121.461782 -215.2904)
			(xy 118.03848 -215.2904) (xy 118.037755 -215.291946) (xy 118.006982 -215.338459) (xy 117.969765 -215.379996)
			(xy 117.926897 -215.415671) (xy 117.879291 -215.444725) (xy 117.827962 -215.466537) (xy 117.774005 -215.480643)
			(xy 117.718568 -215.486743) (xy 117.662834 -215.484706) (xy 117.607991 -215.474576) (xy 117.555207 -215.456569)
			(xy 117.505607 -215.431068) (xy 117.460249 -215.398617) (xy 117.4201 -215.359908) (xy 117.386014 -215.315765)
			(xy 117.358718 -215.26713) (xy 117.338795 -215.215039) (xy 117.326669 -215.160602) (xy 117.322598 -215.10498)
			(xy 88.264191 -215.10498) (xy 88.208211 -215.744806) (xy 125.525782 -215.744806) (xy 125.529853 -215.689184)
			(xy 125.541979 -215.634747) (xy 125.561902 -215.582656) (xy 125.589198 -215.534021) (xy 125.623284 -215.489878)
			(xy 125.663433 -215.451169) (xy 125.708791 -215.418718) (xy 125.758391 -215.393217) (xy 125.811175 -215.37521)
			(xy 125.866018 -215.36508) (xy 125.921752 -215.363043) (xy 125.977189 -215.369143) (xy 126.031146 -215.383249)
			(xy 126.082475 -215.405061) (xy 126.130081 -215.434115) (xy 126.172949 -215.46979) (xy 126.210166 -215.511327)
			(xy 126.240939 -215.55784) (xy 126.264611 -215.608337) (xy 126.280679 -215.661744) (xy 126.288799 -215.71692)
			(xy 126.289308 -215.744806) (xy 126.288799 -215.772692) (xy 126.280679 -215.827868) (xy 126.271969 -215.85682)
			(xy 135.41451 -215.85682) (xy 135.418581 -215.801198) (xy 135.430707 -215.746761) (xy 135.45063 -215.69467)
			(xy 135.477926 -215.646035) (xy 135.512012 -215.601892) (xy 135.552161 -215.563183) (xy 135.597519 -215.530732)
			(xy 135.647119 -215.505231) (xy 135.699903 -215.487224) (xy 135.754746 -215.477094) (xy 135.81048 -215.475057)
			(xy 135.865917 -215.481157) (xy 135.919874 -215.495263) (xy 135.971203 -215.517075) (xy 136.018809 -215.546129)
			(xy 136.061677 -215.581804) (xy 136.098894 -215.623341) (xy 136.129667 -215.669854) (xy 136.153339 -215.720351)
			(xy 136.169407 -215.773758) (xy 136.177527 -215.828934) (xy 136.178036 -215.85682) (xy 136.177527 -215.884706)
			(xy 136.169407 -215.939882) (xy 136.153339 -215.993289) (xy 136.149562 -216.001346) (xy 138.978892 -216.001346)
			(xy 138.982963 -215.945724) (xy 138.995089 -215.891287) (xy 139.015012 -215.839196) (xy 139.042308 -215.790561)
			(xy 139.076394 -215.746418) (xy 139.116543 -215.707709) (xy 139.161901 -215.675258) (xy 139.211501 -215.649757)
			(xy 139.264285 -215.63175) (xy 139.319128 -215.62162) (xy 139.374862 -215.619583) (xy 139.430299 -215.625683)
			(xy 139.484256 -215.639789) (xy 139.535585 -215.661601) (xy 139.583191 -215.690655) (xy 139.626059 -215.72633)
			(xy 139.663276 -215.767867) (xy 139.694049 -215.81438) (xy 139.717721 -215.864877) (xy 139.733789 -215.918284)
			(xy 139.741909 -215.97346) (xy 139.742418 -216.001346) (xy 139.741909 -216.029232) (xy 139.733789 -216.084408)
			(xy 139.717721 -216.137815) (xy 139.694049 -216.188312) (xy 139.663276 -216.234825) (xy 139.626059 -216.276362)
			(xy 139.583191 -216.312037) (xy 139.56371 -216.323926) (xy 141.308326 -216.323926) (xy 141.312397 -216.268304)
			(xy 141.324523 -216.213867) (xy 141.344446 -216.161776) (xy 141.371742 -216.113141) (xy 141.405828 -216.068998)
			(xy 141.445977 -216.030289) (xy 141.491335 -215.997838) (xy 141.540935 -215.972337) (xy 141.593719 -215.95433)
			(xy 141.648562 -215.9442) (xy 141.704296 -215.942163) (xy 141.759733 -215.948263) (xy 141.81369 -215.962369)
			(xy 141.865019 -215.984181) (xy 141.912625 -216.013235) (xy 141.955493 -216.04891) (xy 141.99271 -216.090447)
			(xy 142.023483 -216.13696) (xy 142.047155 -216.187457) (xy 142.063223 -216.240864) (xy 142.071343 -216.29604)
			(xy 142.071852 -216.323926) (xy 142.071343 -216.351812) (xy 142.063223 -216.406988) (xy 142.047155 -216.460395)
			(xy 142.023483 -216.510892) (xy 141.99271 -216.557405) (xy 141.955493 -216.598942) (xy 141.912625 -216.634617)
			(xy 141.865019 -216.663671) (xy 141.81369 -216.685483) (xy 141.759733 -216.699589) (xy 141.704296 -216.705689)
			(xy 141.648562 -216.703652) (xy 141.593719 -216.693522) (xy 141.540935 -216.675515) (xy 141.491335 -216.650014)
			(xy 141.445977 -216.617563) (xy 141.405828 -216.578854) (xy 141.371742 -216.534711) (xy 141.344446 -216.486076)
			(xy 141.324523 -216.433985) (xy 141.312397 -216.379548) (xy 141.308326 -216.323926) (xy 139.56371 -216.323926)
			(xy 139.535585 -216.341091) (xy 139.484256 -216.362903) (xy 139.430299 -216.377009) (xy 139.374862 -216.383109)
			(xy 139.319128 -216.381072) (xy 139.264285 -216.370942) (xy 139.211501 -216.352935) (xy 139.161901 -216.327434)
			(xy 139.116543 -216.294983) (xy 139.076394 -216.256274) (xy 139.042308 -216.212131) (xy 139.015012 -216.163496)
			(xy 138.995089 -216.111405) (xy 138.982963 -216.056968) (xy 138.978892 -216.001346) (xy 136.149562 -216.001346)
			(xy 136.129667 -216.043786) (xy 136.098894 -216.090299) (xy 136.061677 -216.131836) (xy 136.018809 -216.167511)
			(xy 135.971203 -216.196565) (xy 135.919874 -216.218377) (xy 135.865917 -216.232483) (xy 135.81048 -216.238583)
			(xy 135.754746 -216.236546) (xy 135.699903 -216.226416) (xy 135.647119 -216.208409) (xy 135.597519 -216.182908)
			(xy 135.552161 -216.150457) (xy 135.512012 -216.111748) (xy 135.477926 -216.067605) (xy 135.45063 -216.01897)
			(xy 135.430707 -215.966879) (xy 135.418581 -215.912442) (xy 135.41451 -215.85682) (xy 126.271969 -215.85682)
			(xy 126.264611 -215.881275) (xy 126.240939 -215.931772) (xy 126.210166 -215.978285) (xy 126.172949 -216.019822)
			(xy 126.130081 -216.055497) (xy 126.082475 -216.084551) (xy 126.031146 -216.106363) (xy 125.977189 -216.120469)
			(xy 125.921752 -216.126569) (xy 125.866018 -216.124532) (xy 125.811175 -216.114402) (xy 125.758391 -216.096395)
			(xy 125.708791 -216.070894) (xy 125.663433 -216.038443) (xy 125.623284 -215.999734) (xy 125.589198 -215.955591)
			(xy 125.561902 -215.906956) (xy 125.541979 -215.854865) (xy 125.529853 -215.800428) (xy 125.525782 -215.744806)
			(xy 88.208211 -215.744806) (xy 87.960514 -218.57589) (xy 97.01733 -218.57589) (xy 97.021401 -218.520268)
			(xy 97.033527 -218.465831) (xy 97.05345 -218.41374) (xy 97.080746 -218.365105) (xy 97.114832 -218.320962)
			(xy 97.154981 -218.282253) (xy 97.200339 -218.249802) (xy 97.249939 -218.224301) (xy 97.302723 -218.206294)
			(xy 97.357566 -218.196164) (xy 97.4133 -218.194127) (xy 97.468737 -218.200227) (xy 97.522694 -218.214333)
			(xy 97.574023 -218.236145) (xy 97.621629 -218.265199) (xy 97.664497 -218.300874) (xy 97.701714 -218.342411)
			(xy 97.732487 -218.388924) (xy 97.756159 -218.439421) (xy 97.772227 -218.492828) (xy 97.780347 -218.548004)
			(xy 97.780856 -218.57589) (xy 97.780347 -218.603776) (xy 97.772227 -218.658952) (xy 97.756159 -218.712359)
			(xy 97.732487 -218.762856) (xy 97.701714 -218.809369) (xy 97.664497 -218.850906) (xy 97.621629 -218.886581)
			(xy 97.574023 -218.915635) (xy 97.522694 -218.937447) (xy 97.511475 -218.94038) (xy 117.85295 -218.94038)
			(xy 117.857021 -218.884758) (xy 117.869147 -218.830321) (xy 117.88907 -218.77823) (xy 117.916366 -218.729595)
			(xy 117.950452 -218.685452) (xy 117.990601 -218.646743) (xy 118.035959 -218.614292) (xy 118.085559 -218.588791)
			(xy 118.138343 -218.570784) (xy 118.193186 -218.560654) (xy 118.24892 -218.558617) (xy 118.304357 -218.564717)
			(xy 118.358314 -218.578823) (xy 118.409643 -218.600635) (xy 118.457249 -218.629689) (xy 118.478062 -218.64701)
			(xy 120.921778 -218.64701) (xy 120.925849 -218.591388) (xy 120.937975 -218.536951) (xy 120.957898 -218.48486)
			(xy 120.985194 -218.436225) (xy 121.01928 -218.392082) (xy 121.059429 -218.353373) (xy 121.104787 -218.320922)
			(xy 121.154387 -218.295421) (xy 121.207171 -218.277414) (xy 121.262014 -218.267284) (xy 121.317748 -218.265247)
			(xy 121.373185 -218.271347) (xy 121.376088 -218.272106) (xy 124.257306 -218.272106) (xy 124.261377 -218.216484)
			(xy 124.273503 -218.162047) (xy 124.293426 -218.109956) (xy 124.320722 -218.061321) (xy 124.354808 -218.017178)
			(xy 124.394957 -217.978469) (xy 124.440315 -217.946018) (xy 124.489915 -217.920517) (xy 124.542699 -217.90251)
			(xy 124.597542 -217.89238) (xy 124.653276 -217.890343) (xy 124.708713 -217.896443) (xy 124.76267 -217.910549)
			(xy 124.813999 -217.932361) (xy 124.861605 -217.961415) (xy 124.904473 -217.99709) (xy 124.94169 -218.038627)
			(xy 124.972463 -218.08514) (xy 124.996135 -218.135637) (xy 125.012203 -218.189044) (xy 125.020323 -218.24422)
			(xy 125.020832 -218.272106) (xy 125.020323 -218.299992) (xy 125.012203 -218.355168) (xy 124.996135 -218.408575)
			(xy 124.972463 -218.459072) (xy 124.94169 -218.505585) (xy 124.904473 -218.547122) (xy 124.861605 -218.582797)
			(xy 124.813999 -218.611851) (xy 124.76267 -218.633663) (xy 124.708713 -218.647769) (xy 124.653276 -218.653869)
			(xy 124.597542 -218.651832) (xy 124.542699 -218.641702) (xy 124.489915 -218.623695) (xy 124.440315 -218.598194)
			(xy 124.394957 -218.565743) (xy 124.354808 -218.527034) (xy 124.320722 -218.482891) (xy 124.293426 -218.434256)
			(xy 124.273503 -218.382165) (xy 124.261377 -218.327728) (xy 124.257306 -218.272106) (xy 121.376088 -218.272106)
			(xy 121.427142 -218.285453) (xy 121.478471 -218.307265) (xy 121.526077 -218.336319) (xy 121.568945 -218.371994)
			(xy 121.606162 -218.413531) (xy 121.636935 -218.460044) (xy 121.660607 -218.510541) (xy 121.676675 -218.563948)
			(xy 121.684795 -218.619124) (xy 121.685304 -218.64701) (xy 121.684795 -218.674896) (xy 121.676675 -218.730072)
			(xy 121.660607 -218.783479) (xy 121.636935 -218.833976) (xy 121.606162 -218.880489) (xy 121.568945 -218.922026)
			(xy 121.526077 -218.957701) (xy 121.478471 -218.986755) (xy 121.427142 -219.008567) (xy 121.373185 -219.022673)
			(xy 121.317748 -219.028773) (xy 121.262014 -219.026736) (xy 121.207171 -219.016606) (xy 121.154387 -218.998599)
			(xy 121.104787 -218.973098) (xy 121.059429 -218.940647) (xy 121.01928 -218.901938) (xy 120.985194 -218.857795)
			(xy 120.957898 -218.80916) (xy 120.937975 -218.757069) (xy 120.925849 -218.702632) (xy 120.921778 -218.64701)
			(xy 118.478062 -218.64701) (xy 118.500117 -218.665364) (xy 118.537334 -218.706901) (xy 118.568107 -218.753414)
			(xy 118.591779 -218.803911) (xy 118.607847 -218.857318) (xy 118.615967 -218.912494) (xy 118.616476 -218.94038)
			(xy 118.615967 -218.968266) (xy 118.607847 -219.023442) (xy 118.591779 -219.076849) (xy 118.568107 -219.127346)
			(xy 118.537334 -219.173859) (xy 118.50643 -219.20835) (xy 127.477264 -219.20835) (xy 127.481335 -219.152728)
			(xy 127.493461 -219.098291) (xy 127.513384 -219.0462) (xy 127.54068 -218.997565) (xy 127.574766 -218.953422)
			(xy 127.614915 -218.914713) (xy 127.660273 -218.882262) (xy 127.709873 -218.856761) (xy 127.762657 -218.838754)
			(xy 127.8175 -218.828624) (xy 127.873234 -218.826587) (xy 127.928671 -218.832687) (xy 127.982628 -218.846793)
			(xy 128.033957 -218.868605) (xy 128.081563 -218.897659) (xy 128.124431 -218.933334) (xy 128.161648 -218.974871)
			(xy 128.192421 -219.021384) (xy 128.216093 -219.071881) (xy 128.232161 -219.125288) (xy 128.240281 -219.180464)
			(xy 128.24079 -219.20835) (xy 128.240281 -219.236236) (xy 128.232161 -219.291412) (xy 128.216093 -219.344819)
			(xy 128.192421 -219.395316) (xy 128.161648 -219.441829) (xy 128.124431 -219.483366) (xy 128.081563 -219.519041)
			(xy 128.033957 -219.548095) (xy 127.982628 -219.569907) (xy 127.928671 -219.584013) (xy 127.873234 -219.590113)
			(xy 127.8175 -219.588076) (xy 127.762657 -219.577946) (xy 127.709873 -219.559939) (xy 127.660273 -219.534438)
			(xy 127.614915 -219.501987) (xy 127.574766 -219.463278) (xy 127.54068 -219.419135) (xy 127.513384 -219.3705)
			(xy 127.493461 -219.318409) (xy 127.481335 -219.263972) (xy 127.477264 -219.20835) (xy 118.50643 -219.20835)
			(xy 118.500117 -219.215396) (xy 118.457249 -219.251071) (xy 118.409643 -219.280125) (xy 118.358314 -219.301937)
			(xy 118.304357 -219.316043) (xy 118.24892 -219.322143) (xy 118.193186 -219.320106) (xy 118.138343 -219.309976)
			(xy 118.085559 -219.291969) (xy 118.035959 -219.266468) (xy 117.990601 -219.234017) (xy 117.950452 -219.195308)
			(xy 117.916366 -219.151165) (xy 117.88907 -219.10253) (xy 117.869147 -219.050439) (xy 117.857021 -218.996002)
			(xy 117.85295 -218.94038) (xy 97.511475 -218.94038) (xy 97.468737 -218.951553) (xy 97.4133 -218.957653)
			(xy 97.357566 -218.955616) (xy 97.302723 -218.945486) (xy 97.249939 -218.927479) (xy 97.200339 -218.901978)
			(xy 97.154981 -218.869527) (xy 97.114832 -218.830818) (xy 97.080746 -218.786675) (xy 97.05345 -218.73804)
			(xy 97.033527 -218.685949) (xy 97.021401 -218.631512) (xy 97.01733 -218.57589) (xy 87.960514 -218.57589)
			(xy 87.874444 -219.559632) (xy 97.811588 -219.559632) (xy 97.815659 -219.50401) (xy 97.827785 -219.449573)
			(xy 97.847708 -219.397482) (xy 97.875004 -219.348847) (xy 97.90909 -219.304704) (xy 97.949239 -219.265995)
			(xy 97.994597 -219.233544) (xy 98.044197 -219.208043) (xy 98.096981 -219.190036) (xy 98.151824 -219.179906)
			(xy 98.207558 -219.177869) (xy 98.262995 -219.183969) (xy 98.316952 -219.198075) (xy 98.368281 -219.219887)
			(xy 98.415887 -219.248941) (xy 98.458755 -219.284616) (xy 98.495972 -219.326153) (xy 98.526745 -219.372666)
			(xy 98.550417 -219.423163) (xy 98.566485 -219.47657) (xy 98.574605 -219.531746) (xy 98.575114 -219.559632)
			(xy 98.575109 -219.559886) (xy 100.279706 -219.559886) (xy 100.283777 -219.504264) (xy 100.295903 -219.449827)
			(xy 100.315826 -219.397736) (xy 100.343122 -219.349101) (xy 100.377208 -219.304958) (xy 100.417357 -219.266249)
			(xy 100.462715 -219.233798) (xy 100.512315 -219.208297) (xy 100.565099 -219.19029) (xy 100.619942 -219.18016)
			(xy 100.675676 -219.178123) (xy 100.731113 -219.184223) (xy 100.78507 -219.198329) (xy 100.836399 -219.220141)
			(xy 100.884005 -219.249195) (xy 100.926873 -219.28487) (xy 100.96409 -219.326407) (xy 100.994863 -219.37292)
			(xy 101.018535 -219.423417) (xy 101.034603 -219.476824) (xy 101.042723 -219.532) (xy 101.043223 -219.559378)
			(xy 102.352854 -219.559378) (xy 102.356925 -219.503756) (xy 102.369051 -219.449319) (xy 102.388974 -219.397228)
			(xy 102.41627 -219.348593) (xy 102.450356 -219.30445) (xy 102.490505 -219.265741) (xy 102.535863 -219.23329)
			(xy 102.585463 -219.207789) (xy 102.638247 -219.189782) (xy 102.69309 -219.179652) (xy 102.748824 -219.177615)
			(xy 102.804261 -219.183715) (xy 102.858218 -219.197821) (xy 102.909547 -219.219633) (xy 102.957153 -219.248687)
			(xy 103.000021 -219.284362) (xy 103.037238 -219.325899) (xy 103.068011 -219.372412) (xy 103.091683 -219.422909)
			(xy 103.107751 -219.476316) (xy 103.115871 -219.531492) (xy 103.11638 -219.559378) (xy 103.115871 -219.587264)
			(xy 103.107751 -219.64244) (xy 103.091683 -219.695847) (xy 103.068011 -219.746344) (xy 103.037238 -219.792857)
			(xy 103.022265 -219.809568) (xy 126.23876 -219.809568) (xy 126.242831 -219.753946) (xy 126.254957 -219.699509)
			(xy 126.27488 -219.647418) (xy 126.302176 -219.598783) (xy 126.336262 -219.55464) (xy 126.376411 -219.515931)
			(xy 126.421769 -219.48348) (xy 126.471369 -219.457979) (xy 126.524153 -219.439972) (xy 126.578996 -219.429842)
			(xy 126.63473 -219.427805) (xy 126.690167 -219.433905) (xy 126.744124 -219.448011) (xy 126.795453 -219.469823)
			(xy 126.843059 -219.498877) (xy 126.885927 -219.534552) (xy 126.923144 -219.576089) (xy 126.953917 -219.622602)
			(xy 126.977589 -219.673099) (xy 126.993657 -219.726506) (xy 127.001777 -219.781682) (xy 127.002286 -219.809568)
			(xy 127.001777 -219.837454) (xy 126.993657 -219.89263) (xy 126.977589 -219.946037) (xy 126.953917 -219.996534)
			(xy 126.923144 -220.043047) (xy 126.885927 -220.084584) (xy 126.843059 -220.120259) (xy 126.795453 -220.149313)
			(xy 126.744124 -220.171125) (xy 126.690167 -220.185231) (xy 126.63473 -220.191331) (xy 126.578996 -220.189294)
			(xy 126.524153 -220.179164) (xy 126.471369 -220.161157) (xy 126.421769 -220.135656) (xy 126.376411 -220.103205)
			(xy 126.336262 -220.064496) (xy 126.302176 -220.020353) (xy 126.27488 -219.971718) (xy 126.254957 -219.919627)
			(xy 126.242831 -219.86519) (xy 126.23876 -219.809568) (xy 103.022265 -219.809568) (xy 103.000021 -219.834394)
			(xy 102.957153 -219.870069) (xy 102.909547 -219.899123) (xy 102.858218 -219.920935) (xy 102.804261 -219.935041)
			(xy 102.748824 -219.941141) (xy 102.69309 -219.939104) (xy 102.638247 -219.928974) (xy 102.585463 -219.910967)
			(xy 102.535863 -219.885466) (xy 102.490505 -219.853015) (xy 102.450356 -219.814306) (xy 102.41627 -219.770163)
			(xy 102.388974 -219.721528) (xy 102.369051 -219.669437) (xy 102.356925 -219.615) (xy 102.352854 -219.559378)
			(xy 101.043223 -219.559378) (xy 101.043232 -219.559886) (xy 101.042723 -219.587772) (xy 101.034603 -219.642948)
			(xy 101.018535 -219.696355) (xy 100.994863 -219.746852) (xy 100.96409 -219.793365) (xy 100.926873 -219.834902)
			(xy 100.884005 -219.870577) (xy 100.836399 -219.899631) (xy 100.78507 -219.921443) (xy 100.731113 -219.935549)
			(xy 100.675676 -219.941649) (xy 100.619942 -219.939612) (xy 100.565099 -219.929482) (xy 100.512315 -219.911475)
			(xy 100.462715 -219.885974) (xy 100.417357 -219.853523) (xy 100.377208 -219.814814) (xy 100.343122 -219.770671)
			(xy 100.315826 -219.722036) (xy 100.295903 -219.669945) (xy 100.283777 -219.615508) (xy 100.279706 -219.559886)
			(xy 98.575109 -219.559886) (xy 98.574605 -219.587518) (xy 98.566485 -219.642694) (xy 98.550417 -219.696101)
			(xy 98.526745 -219.746598) (xy 98.495972 -219.793111) (xy 98.458755 -219.834648) (xy 98.415887 -219.870323)
			(xy 98.368281 -219.899377) (xy 98.316952 -219.921189) (xy 98.262995 -219.935295) (xy 98.207558 -219.941395)
			(xy 98.151824 -219.939358) (xy 98.096981 -219.929228) (xy 98.044197 -219.911221) (xy 97.994597 -219.88572)
			(xy 97.949239 -219.853269) (xy 97.90909 -219.81456) (xy 97.875004 -219.770417) (xy 97.847708 -219.721782)
			(xy 97.827785 -219.669691) (xy 97.815659 -219.615254) (xy 97.811588 -219.559632) (xy 87.874444 -219.559632)
			(xy 87.746818 -221.018354) (xy 96.817432 -221.018354) (xy 96.821503 -220.962732) (xy 96.833629 -220.908295)
			(xy 96.853552 -220.856204) (xy 96.880848 -220.807569) (xy 96.914934 -220.763426) (xy 96.955083 -220.724717)
			(xy 97.000441 -220.692266) (xy 97.050041 -220.666765) (xy 97.102825 -220.648758) (xy 97.157668 -220.638628)
			(xy 97.213402 -220.636591) (xy 97.268839 -220.642691) (xy 97.322796 -220.656797) (xy 97.374125 -220.678609)
			(xy 97.421731 -220.707663) (xy 97.464599 -220.743338) (xy 97.501816 -220.784875) (xy 97.532589 -220.831388)
			(xy 97.556261 -220.881885) (xy 97.572329 -220.935292) (xy 97.580449 -220.990468) (xy 97.580958 -221.018354)
			(xy 97.580449 -221.04624) (xy 97.572329 -221.101416) (xy 97.558881 -221.146116) (xy 100.565456 -221.146116)
			(xy 100.569527 -221.090494) (xy 100.581653 -221.036057) (xy 100.601576 -220.983966) (xy 100.628872 -220.935331)
			(xy 100.662958 -220.891188) (xy 100.703107 -220.852479) (xy 100.748465 -220.820028) (xy 100.798065 -220.794527)
			(xy 100.850849 -220.77652) (xy 100.905692 -220.76639) (xy 100.961426 -220.764353) (xy 101.016863 -220.770453)
			(xy 101.07082 -220.784559) (xy 101.122149 -220.806371) (xy 101.169755 -220.835425) (xy 101.212623 -220.8711)
			(xy 101.24984 -220.912637) (xy 101.255253 -220.920818) (xy 102.937562 -220.920818) (xy 102.941633 -220.865196)
			(xy 102.953759 -220.810759) (xy 102.973682 -220.758668) (xy 103.000978 -220.710033) (xy 103.035064 -220.66589)
			(xy 103.075213 -220.627181) (xy 103.120571 -220.59473) (xy 103.170171 -220.569229) (xy 103.222955 -220.551222)
			(xy 103.277798 -220.541092) (xy 103.333532 -220.539055) (xy 103.388969 -220.545155) (xy 103.442926 -220.559261)
			(xy 103.494255 -220.581073) (xy 103.541861 -220.610127) (xy 103.584729 -220.645802) (xy 103.621946 -220.687339)
			(xy 103.652719 -220.733852) (xy 103.676391 -220.784349) (xy 103.692459 -220.837756) (xy 103.700579 -220.892932)
			(xy 103.701088 -220.920818) (xy 103.700579 -220.948704) (xy 103.692459 -221.00388) (xy 103.676391 -221.057287)
			(xy 103.672852 -221.064836) (xy 116.584474 -221.064836) (xy 116.588545 -221.009214) (xy 116.600671 -220.954777)
			(xy 116.620594 -220.902686) (xy 116.64789 -220.854051) (xy 116.681976 -220.809908) (xy 116.722125 -220.771199)
			(xy 116.767483 -220.738748) (xy 116.817083 -220.713247) (xy 116.869867 -220.69524) (xy 116.92471 -220.68511)
			(xy 116.980444 -220.683073) (xy 117.035881 -220.689173) (xy 117.089838 -220.703279) (xy 117.141167 -220.725091)
			(xy 117.188773 -220.754145) (xy 117.231641 -220.78982) (xy 117.268858 -220.831357) (xy 117.299631 -220.87787)
			(xy 117.323303 -220.928367) (xy 117.339371 -220.981774) (xy 117.347491 -221.03695) (xy 117.348 -221.064836)
			(xy 117.347491 -221.092722) (xy 117.339371 -221.147898) (xy 117.323303 -221.201305) (xy 117.299631 -221.251802)
			(xy 117.268858 -221.298315) (xy 117.231641 -221.339852) (xy 117.188773 -221.375527) (xy 117.141167 -221.404581)
			(xy 117.089838 -221.426393) (xy 117.035881 -221.440499) (xy 116.980444 -221.446599) (xy 116.92471 -221.444562)
			(xy 116.869867 -221.434432) (xy 116.817083 -221.416425) (xy 116.767483 -221.390924) (xy 116.722125 -221.358473)
			(xy 116.681976 -221.319764) (xy 116.64789 -221.275621) (xy 116.620594 -221.226986) (xy 116.600671 -221.174895)
			(xy 116.588545 -221.120458) (xy 116.584474 -221.064836) (xy 103.672852 -221.064836) (xy 103.652719 -221.107784)
			(xy 103.621946 -221.154297) (xy 103.584729 -221.195834) (xy 103.541861 -221.231509) (xy 103.494255 -221.260563)
			(xy 103.442926 -221.282375) (xy 103.388969 -221.296481) (xy 103.333532 -221.302581) (xy 103.277798 -221.300544)
			(xy 103.222955 -221.290414) (xy 103.170171 -221.272407) (xy 103.120571 -221.246906) (xy 103.075213 -221.214455)
			(xy 103.035064 -221.175746) (xy 103.000978 -221.131603) (xy 102.973682 -221.082968) (xy 102.953759 -221.030877)
			(xy 102.941633 -220.97644) (xy 102.937562 -220.920818) (xy 101.255253 -220.920818) (xy 101.280613 -220.95915)
			(xy 101.304285 -221.009647) (xy 101.320353 -221.063054) (xy 101.328473 -221.11823) (xy 101.328982 -221.146116)
			(xy 101.328473 -221.174002) (xy 101.320353 -221.229178) (xy 101.304285 -221.282585) (xy 101.280613 -221.333082)
			(xy 101.24984 -221.379595) (xy 101.212623 -221.421132) (xy 101.169755 -221.456807) (xy 101.122149 -221.485861)
			(xy 101.07082 -221.507673) (xy 101.016863 -221.521779) (xy 100.961426 -221.527879) (xy 100.905692 -221.525842)
			(xy 100.850849 -221.515712) (xy 100.798065 -221.497705) (xy 100.748465 -221.472204) (xy 100.703107 -221.439753)
			(xy 100.662958 -221.401044) (xy 100.628872 -221.356901) (xy 100.601576 -221.308266) (xy 100.581653 -221.256175)
			(xy 100.569527 -221.201738) (xy 100.565456 -221.146116) (xy 97.558881 -221.146116) (xy 97.556261 -221.154823)
			(xy 97.532589 -221.20532) (xy 97.501816 -221.251833) (xy 97.464599 -221.29337) (xy 97.421731 -221.329045)
			(xy 97.374125 -221.358099) (xy 97.322796 -221.379911) (xy 97.268839 -221.394017) (xy 97.213402 -221.400117)
			(xy 97.157668 -221.39808) (xy 97.102825 -221.38795) (xy 97.050041 -221.369943) (xy 97.000441 -221.344442)
			(xy 96.955083 -221.311991) (xy 96.914934 -221.273282) (xy 96.880848 -221.229139) (xy 96.853552 -221.180504)
			(xy 96.833629 -221.128413) (xy 96.821503 -221.073976) (xy 96.817432 -221.018354) (xy 87.746818 -221.018354)
			(xy 87.680038 -221.781624) (xy 87.680038 -221.79026) (xy 87.682897 -221.823026) (xy 128.712974 -221.823026)
			(xy 128.717045 -221.767404) (xy 128.729171 -221.712967) (xy 128.749094 -221.660876) (xy 128.77639 -221.612241)
			(xy 128.810476 -221.568098) (xy 128.850625 -221.529389) (xy 128.895983 -221.496938) (xy 128.945583 -221.471437)
			(xy 128.998367 -221.45343) (xy 129.05321 -221.4433) (xy 129.108944 -221.441263) (xy 129.164381 -221.447363)
			(xy 129.218338 -221.461469) (xy 129.269667 -221.483281) (xy 129.317273 -221.512335) (xy 129.360141 -221.54801)
			(xy 129.397358 -221.589547) (xy 129.428131 -221.63606) (xy 129.451803 -221.686557) (xy 129.467871 -221.739964)
			(xy 129.475991 -221.79514) (xy 129.4765 -221.823026) (xy 129.475991 -221.850912) (xy 129.467871 -221.906088)
			(xy 129.451803 -221.959495) (xy 129.428131 -222.009992) (xy 129.397358 -222.056505) (xy 129.360141 -222.098042)
			(xy 129.317273 -222.133717) (xy 129.269667 -222.162771) (xy 129.247299 -222.172276) (xy 131.918962 -222.172276)
			(xy 131.923033 -222.116654) (xy 131.935159 -222.062217) (xy 131.955082 -222.010126) (xy 131.982378 -221.961491)
			(xy 132.016464 -221.917348) (xy 132.056613 -221.878639) (xy 132.101971 -221.846188) (xy 132.151571 -221.820687)
			(xy 132.204355 -221.80268) (xy 132.259198 -221.79255) (xy 132.314932 -221.790513) (xy 132.370369 -221.796613)
			(xy 132.424326 -221.810719) (xy 132.475655 -221.832531) (xy 132.523261 -221.861585) (xy 132.566129 -221.89726)
			(xy 132.603346 -221.938797) (xy 132.611111 -221.950534) (xy 133.150354 -221.950534) (xy 133.154425 -221.894912)
			(xy 133.166551 -221.840475) (xy 133.186474 -221.788384) (xy 133.21377 -221.739749) (xy 133.247856 -221.695606)
			(xy 133.288005 -221.656897) (xy 133.333363 -221.624446) (xy 133.382963 -221.598945) (xy 133.435747 -221.580938)
			(xy 133.49059 -221.570808) (xy 133.546324 -221.568771) (xy 133.601761 -221.574871) (xy 133.655718 -221.588977)
			(xy 133.707047 -221.610789) (xy 133.754653 -221.639843) (xy 133.797521 -221.675518) (xy 133.834738 -221.717055)
			(xy 133.865511 -221.763568) (xy 133.889183 -221.814065) (xy 133.905251 -221.867472) (xy 133.913371 -221.922648)
			(xy 133.91388 -221.950534) (xy 133.913371 -221.97842) (xy 133.905251 -222.033596) (xy 133.889183 -222.087003)
			(xy 133.865511 -222.1375) (xy 133.834738 -222.184013) (xy 133.797521 -222.22555) (xy 133.754653 -222.261225)
			(xy 133.707047 -222.290279) (xy 133.655718 -222.312091) (xy 133.601761 -222.326197) (xy 133.546324 -222.332297)
			(xy 133.49059 -222.33026) (xy 133.435747 -222.32013) (xy 133.382963 -222.302123) (xy 133.333363 -222.276622)
			(xy 133.288005 -222.244171) (xy 133.247856 -222.205462) (xy 133.21377 -222.161319) (xy 133.186474 -222.112684)
			(xy 133.166551 -222.060593) (xy 133.154425 -222.006156) (xy 133.150354 -221.950534) (xy 132.611111 -221.950534)
			(xy 132.634119 -221.98531) (xy 132.657791 -222.035807) (xy 132.673859 -222.089214) (xy 132.681979 -222.14439)
			(xy 132.682488 -222.172276) (xy 132.681979 -222.200162) (xy 132.673859 -222.255338) (xy 132.657791 -222.308745)
			(xy 132.634119 -222.359242) (xy 132.603346 -222.405755) (xy 132.566129 -222.447292) (xy 132.523261 -222.482967)
			(xy 132.475655 -222.512021) (xy 132.424326 -222.533833) (xy 132.370369 -222.547939) (xy 132.314932 -222.554039)
			(xy 132.259198 -222.552002) (xy 132.204355 -222.541872) (xy 132.151571 -222.523865) (xy 132.101971 -222.498364)
			(xy 132.056613 -222.465913) (xy 132.016464 -222.427204) (xy 131.982378 -222.383061) (xy 131.955082 -222.334426)
			(xy 131.935159 -222.282335) (xy 131.923033 -222.227898) (xy 131.918962 -222.172276) (xy 129.247299 -222.172276)
			(xy 129.218338 -222.184583) (xy 129.164381 -222.198689) (xy 129.108944 -222.204789) (xy 129.05321 -222.202752)
			(xy 128.998367 -222.192622) (xy 128.945583 -222.174615) (xy 128.895983 -222.149114) (xy 128.850625 -222.116663)
			(xy 128.810476 -222.077954) (xy 128.77639 -222.033811) (xy 128.749094 -221.985176) (xy 128.729171 -221.933085)
			(xy 128.717045 -221.878648) (xy 128.712974 -221.823026) (xy 87.682897 -221.823026) (xy 87.738887 -222.46463)
			(xy 99.334318 -222.46463) (xy 99.338389 -222.409008) (xy 99.350515 -222.354571) (xy 99.370438 -222.30248)
			(xy 99.397734 -222.253845) (xy 99.43182 -222.209702) (xy 99.471969 -222.170993) (xy 99.517327 -222.138542)
			(xy 99.566927 -222.113041) (xy 99.619711 -222.095034) (xy 99.674554 -222.084904) (xy 99.730288 -222.082867)
			(xy 99.785725 -222.088967) (xy 99.839682 -222.103073) (xy 99.891011 -222.124885) (xy 99.938617 -222.153939)
			(xy 99.981485 -222.189614) (xy 100.018702 -222.231151) (xy 100.049475 -222.277664) (xy 100.073147 -222.328161)
			(xy 100.089215 -222.381568) (xy 100.097335 -222.436744) (xy 100.097844 -222.46463) (xy 100.097335 -222.492516)
			(xy 100.089215 -222.547692) (xy 100.073147 -222.601099) (xy 100.049475 -222.651596) (xy 100.018702 -222.698109)
			(xy 99.981485 -222.739646) (xy 99.938617 -222.775321) (xy 99.891011 -222.804375) (xy 99.839682 -222.826187)
			(xy 99.785725 -222.840293) (xy 99.730288 -222.846393) (xy 99.674554 -222.844356) (xy 99.619711 -222.834226)
			(xy 99.566927 -222.816219) (xy 99.517327 -222.790718) (xy 99.471969 -222.758267) (xy 99.43182 -222.719558)
			(xy 99.397734 -222.675415) (xy 99.370438 -222.62678) (xy 99.350515 -222.574689) (xy 99.338389 -222.520252)
			(xy 99.334318 -222.46463) (xy 87.738887 -222.46463) (xy 87.797448 -223.135698) (xy 101.499414 -223.135698)
			(xy 101.503485 -223.080076) (xy 101.515611 -223.025639) (xy 101.535534 -222.973548) (xy 101.56283 -222.924913)
			(xy 101.596916 -222.88077) (xy 101.637065 -222.842061) (xy 101.682423 -222.80961) (xy 101.732023 -222.784109)
			(xy 101.784807 -222.766102) (xy 101.83965 -222.755972) (xy 101.895384 -222.753935) (xy 101.950821 -222.760035)
			(xy 102.004778 -222.774141) (xy 102.056107 -222.795953) (xy 102.103713 -222.825007) (xy 102.146581 -222.860682)
			(xy 102.183798 -222.902219) (xy 102.214571 -222.948732) (xy 102.238243 -222.999229) (xy 102.254311 -223.052636)
			(xy 102.262431 -223.107812) (xy 102.26294 -223.135698) (xy 102.262431 -223.163584) (xy 102.254311 -223.21876)
			(xy 102.238243 -223.272167) (xy 102.214571 -223.322664) (xy 102.183798 -223.369177) (xy 102.146581 -223.410714)
			(xy 102.103713 -223.446389) (xy 102.056107 -223.475443) (xy 102.004778 -223.497255) (xy 101.950821 -223.511361)
			(xy 101.895384 -223.517461) (xy 101.83965 -223.515424) (xy 101.784807 -223.505294) (xy 101.732023 -223.487287)
			(xy 101.682423 -223.461786) (xy 101.637065 -223.429335) (xy 101.596916 -223.390626) (xy 101.56283 -223.346483)
			(xy 101.535534 -223.297848) (xy 101.515611 -223.245757) (xy 101.503485 -223.19132) (xy 101.499414 -223.135698)
			(xy 87.797448 -223.135698) (xy 87.859777 -223.849946) (xy 102.606346 -223.849946) (xy 102.610417 -223.794324)
			(xy 102.622543 -223.739887) (xy 102.642466 -223.687796) (xy 102.669762 -223.639161) (xy 102.703848 -223.595018)
			(xy 102.743997 -223.556309) (xy 102.789355 -223.523858) (xy 102.838955 -223.498357) (xy 102.891739 -223.48035)
			(xy 102.946582 -223.47022) (xy 103.002316 -223.468183) (xy 103.057753 -223.474283) (xy 103.11171 -223.488389)
			(xy 103.163039 -223.510201) (xy 103.210645 -223.539255) (xy 103.253513 -223.57493) (xy 103.29073 -223.616467)
			(xy 103.321503 -223.66298) (xy 103.345175 -223.713477) (xy 103.361243 -223.766884) (xy 103.369363 -223.82206)
			(xy 103.369872 -223.849946) (xy 103.369363 -223.877832) (xy 103.361243 -223.933008) (xy 103.345175 -223.986415)
			(xy 103.333778 -224.010728) (xy 129.104896 -224.010728) (xy 129.108967 -223.955106) (xy 129.121093 -223.900669)
			(xy 129.141016 -223.848578) (xy 129.168312 -223.799943) (xy 129.202398 -223.7558) (xy 129.242547 -223.717091)
			(xy 129.287905 -223.68464) (xy 129.337505 -223.659139) (xy 129.390289 -223.641132) (xy 129.445132 -223.631002)
			(xy 129.500866 -223.628965) (xy 129.556303 -223.635065) (xy 129.61026 -223.649171) (xy 129.661589 -223.670983)
			(xy 129.709195 -223.700037) (xy 129.752063 -223.735712) (xy 129.78928 -223.777249) (xy 129.820053 -223.823762)
			(xy 129.843725 -223.874259) (xy 129.859793 -223.927666) (xy 129.867913 -223.982842) (xy 129.868422 -224.010728)
			(xy 129.867913 -224.038614) (xy 129.859793 -224.09379) (xy 129.843725 -224.147197) (xy 129.820053 -224.197694)
			(xy 129.78928 -224.244207) (xy 129.752063 -224.285744) (xy 129.709195 -224.321419) (xy 129.661589 -224.350473)
			(xy 129.61026 -224.372285) (xy 129.556303 -224.386391) (xy 129.500866 -224.392491) (xy 129.445132 -224.390454)
			(xy 129.390289 -224.380324) (xy 129.337505 -224.362317) (xy 129.287905 -224.336816) (xy 129.242547 -224.304365)
			(xy 129.202398 -224.265656) (xy 129.168312 -224.221513) (xy 129.141016 -224.172878) (xy 129.121093 -224.120787)
			(xy 129.108967 -224.06635) (xy 129.104896 -224.010728) (xy 103.333778 -224.010728) (xy 103.321503 -224.036912)
			(xy 103.29073 -224.083425) (xy 103.253513 -224.124962) (xy 103.210645 -224.160637) (xy 103.163039 -224.189691)
			(xy 103.11171 -224.211503) (xy 103.057753 -224.225609) (xy 103.002316 -224.231709) (xy 102.946582 -224.229672)
			(xy 102.891739 -224.219542) (xy 102.838955 -224.201535) (xy 102.789355 -224.176034) (xy 102.743997 -224.143583)
			(xy 102.703848 -224.104874) (xy 102.669762 -224.060731) (xy 102.642466 -224.012096) (xy 102.622543 -223.960005)
			(xy 102.610417 -223.905568) (xy 102.606346 -223.849946) (xy 87.859777 -223.849946) (xy 87.919224 -224.531174)
			(xy 107.58373 -224.531174) (xy 107.587801 -224.475552) (xy 107.599927 -224.421115) (xy 107.61985 -224.369024)
			(xy 107.647146 -224.320389) (xy 107.681232 -224.276246) (xy 107.721381 -224.237537) (xy 107.766739 -224.205086)
			(xy 107.816339 -224.179585) (xy 107.869123 -224.161578) (xy 107.923966 -224.151448) (xy 107.9797 -224.149411)
			(xy 108.035137 -224.155511) (xy 108.089094 -224.169617) (xy 108.140423 -224.191429) (xy 108.188029 -224.220483)
			(xy 108.230897 -224.256158) (xy 108.268114 -224.297695) (xy 108.298887 -224.344208) (xy 108.322559 -224.394705)
			(xy 108.338627 -224.448112) (xy 108.340534 -224.46107) (xy 119.436386 -224.46107) (xy 119.440457 -224.405448)
			(xy 119.452583 -224.351011) (xy 119.472506 -224.29892) (xy 119.499802 -224.250285) (xy 119.533888 -224.206142)
			(xy 119.574037 -224.167433) (xy 119.619395 -224.134982) (xy 119.668995 -224.109481) (xy 119.721779 -224.091474)
			(xy 119.776622 -224.081344) (xy 119.832356 -224.079307) (xy 119.887793 -224.085407) (xy 119.94175 -224.099513)
			(xy 119.993079 -224.121325) (xy 120.040685 -224.150379) (xy 120.083553 -224.186054) (xy 120.12077 -224.227591)
			(xy 120.151543 -224.274104) (xy 120.175215 -224.324601) (xy 120.191283 -224.378008) (xy 120.199403 -224.433184)
			(xy 120.199912 -224.46107) (xy 120.199403 -224.488956) (xy 120.191283 -224.544132) (xy 120.175215 -224.597539)
			(xy 120.151543 -224.648036) (xy 120.12077 -224.694549) (xy 120.083553 -224.736086) (xy 120.040685 -224.771761)
			(xy 119.993079 -224.800815) (xy 119.94175 -224.822627) (xy 119.887793 -224.836733) (xy 119.832356 -224.842833)
			(xy 119.776622 -224.840796) (xy 119.721779 -224.830666) (xy 119.668995 -224.812659) (xy 119.619395 -224.787158)
			(xy 119.574037 -224.754707) (xy 119.533888 -224.715998) (xy 119.499802 -224.671855) (xy 119.472506 -224.62322)
			(xy 119.452583 -224.571129) (xy 119.440457 -224.516692) (xy 119.436386 -224.46107) (xy 108.340534 -224.46107)
			(xy 108.346747 -224.503288) (xy 108.347256 -224.531174) (xy 108.346747 -224.55906) (xy 108.338627 -224.614236)
			(xy 108.322559 -224.667643) (xy 108.298887 -224.71814) (xy 108.268114 -224.764653) (xy 108.230897 -224.80619)
			(xy 108.188029 -224.841865) (xy 108.140423 -224.870919) (xy 108.089094 -224.892731) (xy 108.035137 -224.906837)
			(xy 107.9797 -224.912937) (xy 107.923966 -224.9109) (xy 107.869123 -224.90077) (xy 107.816339 -224.882763)
			(xy 107.766739 -224.857262) (xy 107.721381 -224.824811) (xy 107.681232 -224.786102) (xy 107.647146 -224.741959)
			(xy 107.61985 -224.693324) (xy 107.599927 -224.641233) (xy 107.587801 -224.586796) (xy 107.58373 -224.531174)
			(xy 87.919224 -224.531174) (xy 88.237629 -228.179884) (xy 133.978142 -228.179884) (xy 133.978747 -228.149081)
			(xy 133.988674 -228.08828) (xy 134.00825 -228.029866) (xy 134.022084 -228.002338) (xy 134.022338 -228.00183)
			(xy 134.024822 -227.996513) (xy 134.027511 -227.985091) (xy 134.027672 -227.979224) (xy 134.027672 -226.4664)
			(xy 134.028153 -226.440313) (xy 134.03632 -226.388781) (xy 134.052454 -226.339163) (xy 134.076155 -226.292682)
			(xy 134.106841 -226.250485) (xy 134.124954 -226.231704) (xy 134.251954 -226.104704) (xy 134.270731 -226.086678)
			(xy 134.312846 -226.056097) (xy 134.359221 -226.032469) (xy 134.408717 -226.016372) (xy 134.460119 -226.008204)
			(xy 134.486142 -226.007676) (xy 134.590028 -226.007676) (xy 134.60004 -226.007234) (xy 134.618537 -225.999561)
			(xy 134.63269 -225.985394) (xy 134.640345 -225.966889) (xy 134.640828 -225.956876) (xy 134.640828 -225.945446)
			(xy 134.631176 -225.925126) (xy 134.62254 -225.91776) (xy 134.601327 -225.899529) (xy 134.563926 -225.857941)
			(xy 134.532994 -225.811341) (xy 134.509193 -225.760726) (xy 134.493033 -225.707179) (xy 134.484859 -225.651848)
			(xy 134.484364 -225.623882) (xy 134.48485 -225.596631) (xy 134.492606 -225.542683) (xy 134.507961 -225.490388)
			(xy 134.530603 -225.440811) (xy 134.560069 -225.394961) (xy 134.59576 -225.35377) (xy 134.636951 -225.318079)
			(xy 134.682801 -225.288613) (xy 134.732378 -225.265971) (xy 134.784673 -225.250616) (xy 134.838621 -225.24286)
			(xy 134.893123 -225.24286) (xy 134.947071 -225.250616) (xy 134.999366 -225.265971) (xy 135.048943 -225.288613)
			(xy 135.094793 -225.318079) (xy 135.135984 -225.35377) (xy 135.171675 -225.394961) (xy 135.201141 -225.440811)
			(xy 135.223783 -225.490388) (xy 135.239138 -225.542683) (xy 135.246894 -225.596631) (xy 135.24738 -225.623882)
			(xy 135.246871 -225.651827) (xy 135.238709 -225.707118) (xy 135.222569 -225.760627) (xy 135.198799 -225.81121)
			(xy 135.167905 -225.857786) (xy 135.14959 -225.878898) (xy 135.142137 -225.888167) (xy 135.135893 -225.911079)
			(xy 135.137652 -225.92284) (xy 135.156194 -226.014788) (xy 135.170926 -226.033838) (xy 135.181848 -226.038918)
			(xy 135.207723 -226.051676) (xy 135.254976 -226.084766) (xy 135.275828 -226.104704) (xy 135.402828 -226.231704)
			(xy 135.413242 -226.242626) (xy 135.420838 -226.250171) (xy 135.440395 -226.258828) (xy 135.451088 -226.25939)
			(xy 135.537194 -226.258882) (xy 135.556752 -226.250246) (xy 135.563864 -226.242118) (xy 135.576056 -226.229164)
			(xy 135.725916 -226.079304) (xy 135.744709 -226.061296) (xy 135.78682 -226.030713) (xy 135.833191 -226.007081)
			(xy 135.882683 -225.990981) (xy 135.934082 -225.982807) (xy 135.960104 -225.982276) (xy 136.409176 -225.982276)
			(xy 136.418915 -225.981845) (xy 136.436965 -225.974514) (xy 136.451003 -225.961005) (xy 136.455404 -225.952304)
			(xy 136.493504 -225.867722) (xy 136.49717 -225.858646) (xy 136.497939 -225.839101) (xy 136.491314 -225.820696)
			(xy 136.485122 -225.813112) (xy 136.46719 -225.792074) (xy 136.436913 -225.745826) (xy 136.413632 -225.695691)
			(xy 136.397835 -225.642719) (xy 136.389855 -225.588021) (xy 136.389364 -225.560382) (xy 136.38985 -225.533131)
			(xy 136.397606 -225.479183) (xy 136.412961 -225.426888) (xy 136.435603 -225.377311) (xy 136.465069 -225.331461)
			(xy 136.50076 -225.29027) (xy 136.541951 -225.254579) (xy 136.587801 -225.225113) (xy 136.637378 -225.202471)
			(xy 136.689673 -225.187116) (xy 136.743621 -225.17936) (xy 136.798123 -225.17936) (xy 136.852071 -225.187116)
			(xy 136.904366 -225.202471) (xy 136.953943 -225.225113) (xy 136.999793 -225.254579) (xy 137.040984 -225.29027)
			(xy 137.076675 -225.331461) (xy 137.106141 -225.377311) (xy 137.128783 -225.426888) (xy 137.144138 -225.479183)
			(xy 137.151894 -225.533131) (xy 137.15238 -225.560382) (xy 137.151865 -225.588019) (xy 137.14388 -225.642715)
			(xy 137.128088 -225.695686) (xy 137.104819 -225.745825) (xy 137.074562 -225.792083) (xy 137.056622 -225.813112)
			(xy 137.050466 -225.820711) (xy 137.043876 -225.839106) (xy 137.044639 -225.85863) (xy 137.04824 -225.867722)
			(xy 137.08634 -225.952304) (xy 137.090733 -225.961015) (xy 137.10475 -225.974554) (xy 137.122823 -225.981844)
			(xy 137.132568 -225.982276) (xy 137.157968 -225.982276) (xy 137.168036 -225.98184) (xy 137.186634 -225.974127)
			(xy 137.194036 -225.96729) (xy 139.407392 -223.75368) (xy 139.410799 -223.750041) (xy 139.416304 -223.741731)
			(xy 139.418314 -223.73717) (xy 139.742926 -222.95485) (xy 139.744714 -222.95016) (xy 139.74664 -222.94031)
			(xy 139.746736 -222.935292) (xy 139.746736 -221.032578) (xy 139.74726 -221.006554) (xy 139.755425 -220.95515)
			(xy 139.771519 -220.905652) (xy 139.795147 -220.859276) (xy 139.82573 -220.81716) (xy 139.843764 -220.79839)
			(xy 140.01623 -220.625924) (xy 140.022908 -220.618506) (xy 140.030513 -220.600076) (xy 140.030515 -220.580138)
			(xy 140.022916 -220.561706) (xy 140.01623 -220.554296) (xy 140.007086 -220.545152) (xy 139.982702 -220.537786)
			(xy 139.97051 -220.540326) (xy 139.954673 -220.543281) (xy 139.922611 -220.546462) (xy 139.906502 -220.546676)
			(xy 139.492228 -220.546676) (xy 139.46614 -220.546193) (xy 139.414608 -220.538028) (xy 139.36499 -220.521896)
			(xy 139.318509 -220.498195) (xy 139.276312 -220.467508) (xy 139.257532 -220.449394) (xy 139.079986 -220.271848)
			(xy 139.050014 -220.266006) (xy 139.03579 -220.271848) (xy 139.026761 -220.276169) (xy 139.012671 -220.290358)
			(xy 139.005039 -220.30884) (xy 139.004548 -220.318838) (xy 139.004548 -220.494352) (xy 139.00406 -220.52044)
			(xy 138.995898 -220.571972) (xy 138.979768 -220.621591) (xy 138.956067 -220.668072) (xy 138.92538 -220.710268)
			(xy 138.907266 -220.729048) (xy 138.858498 -220.777816) (xy 138.851769 -220.785179) (xy 138.844125 -220.803586)
			(xy 138.844027 -220.823517) (xy 138.847322 -220.832934) (xy 138.88212 -220.919548) (xy 138.886218 -220.928678)
			(xy 138.900204 -220.94297) (xy 138.918607 -220.950795) (xy 138.928602 -220.951298) (xy 138.95558 -220.952162)
			(xy 139.008893 -220.960594) (xy 139.060485 -220.976455) (xy 139.109328 -220.999429) (xy 139.154445 -221.029056)
			(xy 139.194938 -221.064746) (xy 139.229996 -221.105786) (xy 139.258921 -221.151357) (xy 139.281136 -221.200549)
			(xy 139.296196 -221.252381) (xy 139.303802 -221.305818) (xy 139.304268 -221.332806) (xy 139.303782 -221.360057)
			(xy 139.296026 -221.414005) (xy 139.280671 -221.4663) (xy 139.258029 -221.515877) (xy 139.228563 -221.561727)
			(xy 139.192872 -221.602918) (xy 139.151681 -221.638609) (xy 139.105831 -221.668075) (xy 139.056254 -221.690717)
			(xy 139.003959 -221.706072) (xy 138.950011 -221.713828) (xy 138.895509 -221.713828) (xy 138.841561 -221.706072)
			(xy 138.789266 -221.690717) (xy 138.739689 -221.668075) (xy 138.693839 -221.638609) (xy 138.652648 -221.602918)
			(xy 138.616957 -221.561727) (xy 138.587491 -221.515877) (xy 138.564849 -221.4663) (xy 138.549494 -221.414005)
			(xy 138.541738 -221.360057) (xy 138.541252 -221.332806) (xy 138.541804 -221.303834) (xy 138.55061 -221.246562)
			(xy 138.558778 -221.21876) (xy 138.560998 -221.21061) (xy 138.560518 -221.193735) (xy 138.554543 -221.177947)
			(xy 138.54938 -221.171262) (xy 138.486134 -221.09557) (xy 138.462004 -221.085918) (xy 138.449304 -221.087696)
			(xy 138.439186 -221.08888) (xy 138.418851 -221.090153) (xy 138.408664 -221.090236) (xy 138.218164 -221.090236)
			(xy 138.201654 -221.089728) (xy 138.190986 -221.08922) (xy 138.17092 -221.09684) (xy 138.10234 -221.16542)
			(xy 138.09472 -221.185486) (xy 138.095228 -221.196154) (xy 138.095736 -221.212664) (xy 138.095736 -221.403164)
			(xy 138.095259 -221.429252) (xy 138.087095 -221.480785) (xy 138.070962 -221.530404) (xy 138.047259 -221.576885)
			(xy 138.016569 -221.619081) (xy 137.998454 -221.63786) (xy 137.752582 -221.883478) (xy 137.745757 -221.89089)
			(xy 137.738029 -221.90948) (xy 137.737596 -221.919546) (xy 137.737596 -222.902272) (xy 137.737792 -222.908422)
			(xy 137.740743 -222.920363) (xy 137.743438 -222.925894) (xy 137.757279 -222.953418) (xy 137.776841 -223.011837)
			(xy 137.786771 -223.072637) (xy 137.78738 -223.10344) (xy 137.786894 -223.130691) (xy 137.779138 -223.184639)
			(xy 137.763783 -223.236934) (xy 137.741141 -223.286511) (xy 137.711675 -223.332361) (xy 137.675984 -223.373552)
			(xy 137.634793 -223.409243) (xy 137.588943 -223.438709) (xy 137.539366 -223.461351) (xy 137.487071 -223.476706)
			(xy 137.433123 -223.484462) (xy 137.378621 -223.484462) (xy 137.324673 -223.476706) (xy 137.272378 -223.461351)
			(xy 137.222801 -223.438709) (xy 137.176951 -223.409243) (xy 137.13576 -223.373552) (xy 137.100069 -223.332361)
			(xy 137.070603 -223.286511) (xy 137.047961 -223.236934) (xy 137.032606 -223.184639) (xy 137.02485 -223.130691)
			(xy 137.024364 -223.10344) (xy 137.02496 -223.072637) (xy 137.034892 -223.011835) (xy 137.05447 -222.953422)
			(xy 137.068306 -222.925894) (xy 137.071023 -222.920371) (xy 137.073978 -222.908425) (xy 137.074148 -222.902272)
			(xy 137.074148 -221.760542) (xy 137.074646 -221.734517) (xy 137.082816 -221.683111) (xy 137.098917 -221.633613)
			(xy 137.122551 -221.587237) (xy 137.15314 -221.545123) (xy 137.171176 -221.526354) (xy 137.353802 -221.343728)
			(xy 137.360468 -221.336303) (xy 137.368062 -221.317876) (xy 137.368066 -221.297944) (xy 137.360479 -221.279513)
			(xy 137.353802 -221.2721) (xy 136.116822 -220.03512) (xy 136.098719 -220.01633) (xy 136.068035 -219.974134)
			(xy 136.044333 -219.927656) (xy 136.028198 -219.87804) (xy 136.020028 -219.826511) (xy 136.01954 -219.800424)
			(xy 136.01954 -219.609924) (xy 136.020302 -219.590366) (xy 136.020376 -219.579572) (xy 136.012621 -219.55945)
			(xy 136.005316 -219.551504) (xy 135.997904 -219.54482) (xy 135.979471 -219.537223) (xy 135.959533 -219.537223)
			(xy 135.9411 -219.54482) (xy 135.933688 -219.551504) (xy 135.847582 -219.637356) (xy 135.840766 -219.644775)
			(xy 135.833033 -219.66336) (xy 135.832596 -219.673424) (xy 135.832596 -222.946214) (xy 135.832778 -222.952365)
			(xy 135.835738 -222.964306) (xy 135.838438 -222.969836) (xy 135.852258 -222.99737) (xy 135.871827 -223.055783)
			(xy 135.881767 -223.11658) (xy 135.88238 -223.147382) (xy 135.881894 -223.174633) (xy 135.874138 -223.228581)
			(xy 135.858783 -223.280876) (xy 135.836141 -223.330453) (xy 135.806675 -223.376303) (xy 135.770984 -223.417494)
			(xy 135.729793 -223.453185) (xy 135.683943 -223.482651) (xy 135.634366 -223.505293) (xy 135.582071 -223.520648)
			(xy 135.528123 -223.528404) (xy 135.473621 -223.528404) (xy 135.419673 -223.520648) (xy 135.367378 -223.505293)
			(xy 135.317801 -223.482651) (xy 135.271951 -223.453185) (xy 135.23076 -223.417494) (xy 135.195069 -223.376303)
			(xy 135.165603 -223.330453) (xy 135.142961 -223.280876) (xy 135.127606 -223.228581) (xy 135.11985 -223.174633)
			(xy 135.119364 -223.147382) (xy 135.119976 -223.116579) (xy 135.129901 -223.055778) (xy 135.149474 -222.997365)
			(xy 135.163306 -222.969836) (xy 135.166009 -222.964307) (xy 135.168973 -222.952366) (xy 135.169148 -222.946214)
			(xy 135.169148 -219.51442) (xy 135.169695 -219.488397) (xy 135.177854 -219.436994) (xy 135.193942 -219.387496)
			(xy 135.217566 -219.341119) (xy 135.248145 -219.299003) (xy 135.266176 -219.280232) (xy 137.147046 -217.399362)
			(xy 137.165813 -217.381235) (xy 137.208014 -217.350552) (xy 137.254499 -217.326853) (xy 137.30412 -217.310725)
			(xy 137.355654 -217.302563) (xy 137.381742 -217.30208) (xy 137.774426 -217.30208) (xy 137.800512 -217.302605)
			(xy 137.852042 -217.310761) (xy 137.901659 -217.326884) (xy 137.948141 -217.350576) (xy 137.99034 -217.381253)
			(xy 138.009122 -217.399362) (xy 138.421364 -217.811604) (xy 138.451336 -217.8177) (xy 138.46556 -217.811604)
			(xy 138.474676 -217.807365) (xy 138.488915 -217.793201) (xy 138.496628 -217.774656) (xy 138.497056 -217.764614)
			(xy 138.497056 -217.588592) (xy 138.497583 -217.562568) (xy 138.505746 -217.511164) (xy 138.52184 -217.461666)
			(xy 138.545468 -217.41529) (xy 138.576051 -217.373174) (xy 138.594084 -217.354404) (xy 138.878818 -217.06967)
			(xy 138.897582 -217.05154) (xy 138.939786 -217.020861) (xy 138.986271 -216.997165) (xy 139.035892 -216.981037)
			(xy 139.087426 -216.972873) (xy 139.113514 -216.972388) (xy 139.345162 -216.972388) (xy 139.371249 -216.972888)
			(xy 139.42278 -216.98105) (xy 139.472398 -216.997179) (xy 139.518879 -217.020876) (xy 139.561077 -217.051559)
			(xy 139.579858 -217.06967) (xy 140.60043 -218.090496) (xy 140.607842 -218.09718) (xy 140.626275 -218.104777)
			(xy 140.646213 -218.104777) (xy 140.664646 -218.09718) (xy 140.672058 -218.090496) (xy 142.80261 -215.960198)
			(xy 142.809445 -215.952794) (xy 142.817167 -215.934198) (xy 142.817596 -215.92413) (xy 142.817596 -214.128604)
			(xy 142.818148 -214.102581) (xy 142.826307 -214.051179) (xy 142.842396 -214.001682) (xy 142.866018 -213.955305)
			(xy 142.896594 -213.913187) (xy 142.914624 -213.894416) (xy 143.367506 -213.441788) (xy 143.374345 -213.434387)
			(xy 143.382065 -213.415788) (xy 143.382492 -213.40572) (xy 143.382492 -210.877912) (xy 143.382062 -210.867843)
			(xy 143.374345 -210.849245) (xy 143.367506 -210.841844) (xy 143.097504 -210.572096) (xy 143.079502 -210.553297)
			(xy 143.048918 -210.511188) (xy 143.025285 -210.464819) (xy 143.009183 -210.415328) (xy 143.001008 -210.36393)
			(xy 143.000476 -210.337908) (xy 143.000476 -209.219292) (xy 143.001026 -209.193269) (xy 143.009187 -209.141867)
			(xy 143.025276 -209.09237) (xy 143.048898 -209.045994) (xy 143.079474 -209.003876) (xy 143.097504 -208.985104)
			(xy 144.56029 -207.522572) (xy 144.567133 -207.515175) (xy 144.574852 -207.496573) (xy 144.575276 -207.486504)
			(xy 144.575276 -204.33157) (xy 144.574894 -204.321877) (xy 144.567768 -204.303852) (xy 144.554438 -204.28978)
			(xy 144.545812 -204.285342) (xy 144.448276 -204.240638) (xy 144.419066 -204.244702) (xy 144.407636 -204.254354)
			(xy 144.386847 -204.271482) (xy 144.341333 -204.300291) (xy 144.292226 -204.322425) (xy 144.240497 -204.337446)
			(xy 144.187172 -204.345055) (xy 144.16024 -204.34554) (xy 144.159986 -204.34554) (xy 144.132738 -204.344989)
			(xy 144.078796 -204.337231) (xy 144.026507 -204.321876) (xy 143.976936 -204.299236) (xy 143.931091 -204.269772)
			(xy 143.889906 -204.234084) (xy 143.854219 -204.192897) (xy 143.824757 -204.147051) (xy 143.802119 -204.097479)
			(xy 143.786766 -204.04519) (xy 143.77901 -203.991248) (xy 143.77901 -203.936752) (xy 143.786766 -203.88281)
			(xy 143.802119 -203.830521) (xy 143.824757 -203.780949) (xy 143.854219 -203.735103) (xy 143.889906 -203.693916)
			(xy 143.931091 -203.658228) (xy 143.976936 -203.628764) (xy 144.026507 -203.606124) (xy 144.078796 -203.590769)
			(xy 144.132738 -203.583011) (xy 144.159986 -203.582524) (xy 144.16024 -203.582524) (xy 144.187175 -203.583006)
			(xy 144.24051 -203.590574) (xy 144.292246 -203.605583) (xy 144.341352 -203.627732) (xy 144.386846 -203.656579)
			(xy 144.407636 -203.67371) (xy 144.419066 -203.683362) (xy 144.448276 -203.687426) (xy 144.545812 -203.642722)
			(xy 144.55441 -203.638256) (xy 144.567686 -203.624163) (xy 144.574845 -203.606174) (xy 144.575276 -203.596494)
			(xy 144.575276 -201.675746) (xy 144.575797 -201.649722) (xy 144.583965 -201.598319) (xy 144.600061 -201.548821)
			(xy 144.62369 -201.502445) (xy 144.654271 -201.460329) (xy 144.672304 -201.441558) (xy 145.876518 -200.237598)
			(xy 145.883354 -200.230195) (xy 145.891075 -200.211598) (xy 145.891504 -200.20153) (xy 145.891504 -198.692262)
			(xy 145.891124 -198.682187) (xy 145.883374 -198.663588) (xy 145.876518 -198.656194) (xy 144.936972 -197.716902)
			(xy 144.91892 -197.69815) (xy 144.888343 -197.656027) (xy 144.86472 -197.609646) (xy 144.84863 -197.560145)
			(xy 144.840469 -197.508739) (xy 144.839944 -197.482714) (xy 144.839944 -195.651882) (xy 144.840468 -195.625858)
			(xy 144.848632 -195.574454) (xy 144.864726 -195.524956) (xy 144.888355 -195.47858) (xy 144.918938 -195.436464)
			(xy 144.936972 -195.417694) (xy 146.504152 -193.850514) (xy 146.508251 -193.846106) (xy 146.514547 -193.835852)
			(xy 146.516598 -193.830194) (xy 146.516598 -193.829686) (xy 146.524981 -193.804119) (xy 146.548061 -193.755515)
			(xy 146.57774 -193.710634) (xy 146.61343 -193.670368) (xy 146.654422 -193.635515) (xy 146.699904 -193.606766)
			(xy 146.748974 -193.584691) (xy 146.800657 -193.569728) (xy 146.853931 -193.562174) (xy 146.880834 -193.561716)
			(xy 146.908087 -193.562146) (xy 146.962038 -193.569908) (xy 147.014335 -193.585269) (xy 147.063914 -193.607916)
			(xy 147.109766 -193.637388) (xy 147.150956 -193.673085) (xy 147.186647 -193.714281) (xy 147.216112 -193.760137)
			(xy 147.238752 -193.809719) (xy 147.254104 -193.862019) (xy 147.261858 -193.915971) (xy 147.262342 -193.943224)
			(xy 147.261834 -193.970133) (xy 147.254256 -194.023414) (xy 147.239266 -194.075102) (xy 147.217163 -194.124171)
			(xy 147.188385 -194.169648) (xy 147.153503 -194.210631) (xy 147.113209 -194.246306) (xy 147.068302 -194.275966)
			(xy 147.019674 -194.299022) (xy 146.994118 -194.30746) (xy 146.993864 -194.30746) (xy 146.988171 -194.309439)
			(xy 146.977896 -194.315735) (xy 146.973544 -194.319906) (xy 145.771152 -195.522088) (xy 146.338034 -195.522088)
			(xy 146.342105 -195.466466) (xy 146.354231 -195.412029) (xy 146.374154 -195.359938) (xy 146.40145 -195.311303)
			(xy 146.435536 -195.26716) (xy 146.475685 -195.228451) (xy 146.521043 -195.196) (xy 146.570643 -195.170499)
			(xy 146.623427 -195.152492) (xy 146.67827 -195.142362) (xy 146.734004 -195.140325) (xy 146.789441 -195.146425)
			(xy 146.843398 -195.160531) (xy 146.894727 -195.182343) (xy 146.942333 -195.211397) (xy 146.985201 -195.247072)
			(xy 147.022418 -195.288609) (xy 147.053191 -195.335122) (xy 147.076863 -195.385619) (xy 147.092931 -195.439026)
			(xy 147.101051 -195.494202) (xy 147.10156 -195.522088) (xy 147.101051 -195.549974) (xy 147.092931 -195.60515)
			(xy 147.076863 -195.658557) (xy 147.053191 -195.709054) (xy 147.022418 -195.755567) (xy 146.985201 -195.797104)
			(xy 146.942333 -195.832779) (xy 146.894727 -195.861833) (xy 146.843398 -195.883645) (xy 146.789441 -195.897751)
			(xy 146.734004 -195.903851) (xy 146.67827 -195.901814) (xy 146.623427 -195.891684) (xy 146.570643 -195.873677)
			(xy 146.521043 -195.848176) (xy 146.475685 -195.815725) (xy 146.435536 -195.777016) (xy 146.40145 -195.732873)
			(xy 146.374154 -195.684238) (xy 146.354231 -195.632147) (xy 146.342105 -195.57771) (xy 146.338034 -195.522088)
			(xy 145.771152 -195.522088) (xy 145.518378 -195.774818) (xy 145.511534 -195.782215) (xy 145.503817 -195.800817)
			(xy 145.503392 -195.810886) (xy 145.503392 -196.884798) (xy 146.481798 -196.884798) (xy 146.485869 -196.829176)
			(xy 146.497995 -196.774739) (xy 146.517918 -196.722648) (xy 146.545214 -196.674013) (xy 146.5793 -196.62987)
			(xy 146.619449 -196.591161) (xy 146.664807 -196.55871) (xy 146.714407 -196.533209) (xy 146.767191 -196.515202)
			(xy 146.822034 -196.505072) (xy 146.877768 -196.503035) (xy 146.933205 -196.509135) (xy 146.987162 -196.523241)
			(xy 147.038491 -196.545053) (xy 147.086097 -196.574107) (xy 147.128965 -196.609782) (xy 147.166182 -196.651319)
			(xy 147.196955 -196.697832) (xy 147.220627 -196.748329) (xy 147.236695 -196.801736) (xy 147.244815 -196.856912)
			(xy 147.245324 -196.884798) (xy 147.244815 -196.912684) (xy 147.236695 -196.96786) (xy 147.220627 -197.021267)
			(xy 147.196955 -197.071764) (xy 147.166182 -197.118277) (xy 147.128965 -197.159814) (xy 147.086097 -197.195489)
			(xy 147.038491 -197.224543) (xy 146.987162 -197.246355) (xy 146.933205 -197.260461) (xy 146.877768 -197.266561)
			(xy 146.822034 -197.264524) (xy 146.767191 -197.254394) (xy 146.714407 -197.236387) (xy 146.664807 -197.210886)
			(xy 146.619449 -197.178435) (xy 146.5793 -197.139726) (xy 146.545214 -197.095583) (xy 146.517918 -197.046948)
			(xy 146.497995 -196.994857) (xy 146.485869 -196.94042) (xy 146.481798 -196.884798) (xy 145.503392 -196.884798)
			(xy 145.503392 -197.32371) (xy 145.503788 -197.333783) (xy 145.511527 -197.352382) (xy 145.518378 -197.359778)
			(xy 146.42084 -198.261986) (xy 146.428742 -198.269216) (xy 146.448738 -198.276842) (xy 146.459448 -198.276718)
			(xy 146.490436 -198.275194) (xy 146.500399 -198.274186) (xy 146.518443 -198.265547) (xy 146.525488 -198.25843)
			(xy 146.53641 -198.247) (xy 147.761198 -197.022466) (xy 147.768045 -197.015071) (xy 147.775761 -196.996468)
			(xy 147.776184 -196.986398) (xy 147.776184 -195.053966) (xy 147.776001 -195.047815) (xy 147.77304 -195.035875)
			(xy 147.770342 -195.030344) (xy 147.756521 -195.00281) (xy 147.73695 -194.944397) (xy 147.727012 -194.8836)
			(xy 147.7264 -194.852798) (xy 147.726886 -194.825547) (xy 147.734642 -194.771599) (xy 147.749997 -194.719304)
			(xy 147.772639 -194.669727) (xy 147.802105 -194.623877) (xy 147.837796 -194.582686) (xy 147.878987 -194.546995)
			(xy 147.924837 -194.517529) (xy 147.974414 -194.494887) (xy 148.026709 -194.479532) (xy 148.080657 -194.471776)
			(xy 148.135159 -194.471776) (xy 148.189107 -194.479532) (xy 148.241402 -194.494887) (xy 148.290979 -194.517529)
			(xy 148.336829 -194.546995) (xy 148.37802 -194.582686) (xy 148.413711 -194.623877) (xy 148.443177 -194.669727)
			(xy 148.465819 -194.719304) (xy 148.481174 -194.771599) (xy 148.48893 -194.825547) (xy 148.489416 -194.852798)
			(xy 148.488798 -194.8836) (xy 148.478875 -194.944401) (xy 148.459305 -195.002815) (xy 148.445474 -195.030344)
			(xy 148.442744 -195.035861) (xy 148.439797 -195.047812) (xy 148.439632 -195.053966) (xy 148.439632 -197.145402)
			(xy 148.439076 -197.171424) (xy 148.430916 -197.222826) (xy 148.414828 -197.272323) (xy 148.391207 -197.3187)
			(xy 148.360633 -197.360818) (xy 148.342604 -197.37959) (xy 147.11807 -198.604124) (xy 147.111223 -198.611518)
			(xy 147.103508 -198.630122) (xy 147.103084 -198.640192) (xy 147.103084 -199.392032) (xy 148.762464 -199.392032)
			(xy 148.766535 -199.33641) (xy 148.778661 -199.281973) (xy 148.798584 -199.229882) (xy 148.82588 -199.181247)
			(xy 148.859966 -199.137104) (xy 148.900115 -199.098395) (xy 148.945473 -199.065944) (xy 148.995073 -199.040443)
			(xy 149.047857 -199.022436) (xy 149.1027 -199.012306) (xy 149.158434 -199.010269) (xy 149.213871 -199.016369)
			(xy 149.267828 -199.030475) (xy 149.319157 -199.052287) (xy 149.366763 -199.081341) (xy 149.409631 -199.117016)
			(xy 149.446848 -199.158553) (xy 149.477621 -199.205066) (xy 149.501293 -199.255563) (xy 149.517361 -199.30897)
			(xy 149.525481 -199.364146) (xy 149.52599 -199.392032) (xy 149.525481 -199.419918) (xy 149.517361 -199.475094)
			(xy 149.501293 -199.528501) (xy 149.477621 -199.578998) (xy 149.446848 -199.625511) (xy 149.409631 -199.667048)
			(xy 149.366763 -199.702723) (xy 149.319157 -199.731777) (xy 149.267828 -199.753589) (xy 149.213871 -199.767695)
			(xy 149.158434 -199.773795) (xy 149.1027 -199.771758) (xy 149.047857 -199.761628) (xy 148.995073 -199.743621)
			(xy 148.945473 -199.71812) (xy 148.900115 -199.685669) (xy 148.859966 -199.64696) (xy 148.82588 -199.602817)
			(xy 148.798584 -199.554182) (xy 148.778661 -199.502091) (xy 148.766535 -199.447654) (xy 148.762464 -199.392032)
			(xy 147.103084 -199.392032) (xy 147.103084 -200.0504) (xy 147.471382 -200.0504) (xy 147.475453 -199.994778)
			(xy 147.487579 -199.940341) (xy 147.507502 -199.88825) (xy 147.534798 -199.839615) (xy 147.568884 -199.795472)
			(xy 147.609033 -199.756763) (xy 147.654391 -199.724312) (xy 147.703991 -199.698811) (xy 147.756775 -199.680804)
			(xy 147.811618 -199.670674) (xy 147.867352 -199.668637) (xy 147.922789 -199.674737) (xy 147.976746 -199.688843)
			(xy 148.028075 -199.710655) (xy 148.075681 -199.739709) (xy 148.118549 -199.775384) (xy 148.155766 -199.816921)
			(xy 148.186539 -199.863434) (xy 148.210211 -199.913931) (xy 148.226279 -199.967338) (xy 148.234399 -200.022514)
			(xy 148.234908 -200.0504) (xy 148.234399 -200.078286) (xy 148.226279 -200.133462) (xy 148.210211 -200.186869)
			(xy 148.186539 -200.237366) (xy 148.155766 -200.283879) (xy 148.118549 -200.325416) (xy 148.075681 -200.361091)
			(xy 148.028075 -200.390145) (xy 147.976746 -200.411957) (xy 147.922789 -200.426063) (xy 147.867352 -200.432163)
			(xy 147.811618 -200.430126) (xy 147.756775 -200.419996) (xy 147.703991 -200.401989) (xy 147.654391 -200.376488)
			(xy 147.609033 -200.344037) (xy 147.568884 -200.305328) (xy 147.534798 -200.261185) (xy 147.507502 -200.21255)
			(xy 147.487579 -200.160459) (xy 147.475453 -200.106022) (xy 147.471382 -200.0504) (xy 147.103084 -200.0504)
			(xy 147.103084 -200.674478) (xy 147.102602 -200.700566) (xy 147.094437 -200.752098) (xy 147.078304 -200.801716)
			(xy 147.054603 -200.848197) (xy 147.023916 -200.890394) (xy 147.005802 -200.909174) (xy 145.91411 -202.000612)
			(xy 145.907274 -202.008015) (xy 145.899551 -202.026612) (xy 145.899124 -202.03668) (xy 145.899124 -205.987142)
			(xy 147.192236 -205.987142) (xy 147.196307 -205.93152) (xy 147.208433 -205.877083) (xy 147.228356 -205.824992)
			(xy 147.255652 -205.776357) (xy 147.289738 -205.732214) (xy 147.329887 -205.693505) (xy 147.375245 -205.661054)
			(xy 147.424845 -205.635553) (xy 147.477629 -205.617546) (xy 147.532472 -205.607416) (xy 147.588206 -205.605379)
			(xy 147.643643 -205.611479) (xy 147.6976 -205.625585) (xy 147.748929 -205.647397) (xy 147.796535 -205.676451)
			(xy 147.839403 -205.712126) (xy 147.87662 -205.753663) (xy 147.907393 -205.800176) (xy 147.931065 -205.850673)
			(xy 147.947133 -205.90408) (xy 147.955253 -205.959256) (xy 147.955762 -205.987142) (xy 147.955253 -206.015028)
			(xy 147.947133 -206.070204) (xy 147.931065 -206.123611) (xy 147.907393 -206.174108) (xy 147.87662 -206.220621)
			(xy 147.839403 -206.262158) (xy 147.796535 -206.297833) (xy 147.748929 -206.326887) (xy 147.6976 -206.348699)
			(xy 147.643643 -206.362805) (xy 147.588206 -206.368905) (xy 147.532472 -206.366868) (xy 147.477629 -206.356738)
			(xy 147.424845 -206.338731) (xy 147.375245 -206.31323) (xy 147.329887 -206.280779) (xy 147.289738 -206.24207)
			(xy 147.255652 -206.197927) (xy 147.228356 -206.149292) (xy 147.208433 -206.097201) (xy 147.196307 -206.042764)
			(xy 147.192236 -205.987142) (xy 145.899124 -205.987142) (xy 145.899124 -208.237074) (xy 147.63318 -208.237074)
			(xy 147.637251 -208.181452) (xy 147.649377 -208.127015) (xy 147.6693 -208.074924) (xy 147.696596 -208.026289)
			(xy 147.730682 -207.982146) (xy 147.770831 -207.943437) (xy 147.816189 -207.910986) (xy 147.865789 -207.885485)
			(xy 147.918573 -207.867478) (xy 147.973416 -207.857348) (xy 148.02915 -207.855311) (xy 148.084587 -207.861411)
			(xy 148.138544 -207.875517) (xy 148.189873 -207.897329) (xy 148.237479 -207.926383) (xy 148.280347 -207.962058)
			(xy 148.317564 -208.003595) (xy 148.348337 -208.050108) (xy 148.372009 -208.100605) (xy 148.388077 -208.154012)
			(xy 148.396197 -208.209188) (xy 148.396706 -208.237074) (xy 148.396197 -208.26496) (xy 148.388077 -208.320136)
			(xy 148.372009 -208.373543) (xy 148.348337 -208.42404) (xy 148.317564 -208.470553) (xy 148.280347 -208.51209)
			(xy 148.237479 -208.547765) (xy 148.189873 -208.576819) (xy 148.138544 -208.598631) (xy 148.084587 -208.612737)
			(xy 148.02915 -208.618837) (xy 147.973416 -208.6168) (xy 147.918573 -208.60667) (xy 147.865789 -208.588663)
			(xy 147.816189 -208.563162) (xy 147.770831 -208.530711) (xy 147.730682 -208.492002) (xy 147.696596 -208.447859)
			(xy 147.6693 -208.399224) (xy 147.649377 -208.347133) (xy 147.637251 -208.292696) (xy 147.63318 -208.237074)
			(xy 145.899124 -208.237074) (xy 145.899124 -209.162142) (xy 147.232114 -209.162142) (xy 147.236185 -209.10652)
			(xy 147.248311 -209.052083) (xy 147.268234 -208.999992) (xy 147.29553 -208.951357) (xy 147.329616 -208.907214)
			(xy 147.369765 -208.868505) (xy 147.415123 -208.836054) (xy 147.464723 -208.810553) (xy 147.517507 -208.792546)
			(xy 147.57235 -208.782416) (xy 147.628084 -208.780379) (xy 147.683521 -208.786479) (xy 147.737478 -208.800585)
			(xy 147.788807 -208.822397) (xy 147.836413 -208.851451) (xy 147.879281 -208.887126) (xy 147.916498 -208.928663)
			(xy 147.947271 -208.975176) (xy 147.970943 -209.025673) (xy 147.987011 -209.07908) (xy 147.995131 -209.134256)
			(xy 147.99564 -209.162142) (xy 147.995131 -209.190028) (xy 147.987011 -209.245204) (xy 147.970943 -209.298611)
			(xy 147.947271 -209.349108) (xy 147.916498 -209.395621) (xy 147.879281 -209.437158) (xy 147.836413 -209.472833)
			(xy 147.788807 -209.501887) (xy 147.737478 -209.523699) (xy 147.683521 -209.537805) (xy 147.628084 -209.543905)
			(xy 147.57235 -209.541868) (xy 147.517507 -209.531738) (xy 147.464723 -209.513731) (xy 147.415123 -209.48823)
			(xy 147.369765 -209.455779) (xy 147.329616 -209.41707) (xy 147.29553 -209.372927) (xy 147.268234 -209.324292)
			(xy 147.248311 -209.272201) (xy 147.236185 -209.217764) (xy 147.232114 -209.162142) (xy 145.899124 -209.162142)
			(xy 145.899124 -209.728308) (xy 145.898574 -209.754331) (xy 145.890413 -209.805733) (xy 145.874324 -209.85523)
			(xy 145.850702 -209.901606) (xy 145.820126 -209.943724) (xy 145.802096 -209.962496) (xy 145.598134 -210.166204)
			(xy 145.591625 -210.173225) (xy 145.583994 -210.19077) (xy 145.583358 -210.209891) (xy 145.586196 -210.219036)
			(xy 145.621756 -210.31962) (xy 145.644362 -210.3374) (xy 145.659094 -210.339178) (xy 145.686812 -210.342636)
			(xy 145.740886 -210.356636) (xy 145.792338 -210.378375) (xy 145.840069 -210.407388) (xy 145.883057 -210.443054)
			(xy 145.920381 -210.48461) (xy 145.951243 -210.531166) (xy 145.974983 -210.581727) (xy 145.975525 -210.583526)
			(xy 146.303236 -210.583526) (xy 146.307307 -210.527904) (xy 146.319433 -210.473467) (xy 146.339356 -210.421376)
			(xy 146.366652 -210.372741) (xy 146.400738 -210.328598) (xy 146.440887 -210.289889) (xy 146.486245 -210.257438)
			(xy 146.535845 -210.231937) (xy 146.588629 -210.21393) (xy 146.643472 -210.2038) (xy 146.699206 -210.201763)
			(xy 146.754643 -210.207863) (xy 146.8086 -210.221969) (xy 146.859929 -210.243781) (xy 146.907535 -210.272835)
			(xy 146.950403 -210.30851) (xy 146.98762 -210.350047) (xy 147.018393 -210.39656) (xy 147.042065 -210.447057)
			(xy 147.058133 -210.500464) (xy 147.066253 -210.55564) (xy 147.066762 -210.583526) (xy 147.066253 -210.611412)
			(xy 147.058133 -210.666588) (xy 147.042065 -210.719995) (xy 147.018393 -210.770492) (xy 146.98762 -210.817005)
			(xy 146.950403 -210.858542) (xy 146.907535 -210.894217) (xy 146.859929 -210.923271) (xy 146.8086 -210.945083)
			(xy 146.754643 -210.959189) (xy 146.699206 -210.965289) (xy 146.643472 -210.963252) (xy 146.588629 -210.953122)
			(xy 146.535845 -210.935115) (xy 146.486245 -210.909614) (xy 146.440887 -210.877163) (xy 146.400738 -210.838454)
			(xy 146.366652 -210.794311) (xy 146.339356 -210.745676) (xy 146.319433 -210.693585) (xy 146.307307 -210.639148)
			(xy 146.303236 -210.583526) (xy 145.975525 -210.583526) (xy 145.991093 -210.63521) (xy 145.999227 -210.690471)
			(xy 145.999708 -210.7184) (xy 145.999222 -210.745651) (xy 145.991466 -210.799599) (xy 145.976111 -210.851894)
			(xy 145.953469 -210.901471) (xy 145.924003 -210.947321) (xy 145.888312 -210.988512) (xy 145.847121 -211.024203)
			(xy 145.801271 -211.053669) (xy 145.751694 -211.076311) (xy 145.699399 -211.091666) (xy 145.645451 -211.099422)
			(xy 145.6182 -211.099908) (xy 145.590277 -211.099429) (xy 145.53503 -211.091261) (xy 145.481563 -211.075128)
			(xy 145.431019 -211.051374) (xy 145.384476 -211.020508) (xy 145.342929 -210.983189) (xy 145.307265 -210.940212)
			(xy 145.278244 -210.892497) (xy 145.256489 -210.841061) (xy 145.242461 -210.787004) (xy 145.238978 -210.759294)
			(xy 145.237599 -210.749842) (xy 145.22875 -210.732925) (xy 145.21432 -210.720426) (xy 145.20545 -210.716876)
			(xy 145.118836 -210.686396) (xy 145.109692 -210.683606) (xy 145.0906 -210.684304) (xy 145.073067 -210.691891)
			(xy 145.066004 -210.698334) (xy 144.66951 -211.094828) (xy 144.662667 -211.102225) (xy 144.654948 -211.120827)
			(xy 144.654524 -211.130896) (xy 144.654524 -213.748366) (xy 144.65401 -213.77439) (xy 144.64584 -213.825794)
			(xy 144.629743 -213.875291) (xy 144.606112 -213.921667) (xy 144.575529 -213.963783) (xy 144.557496 -213.982554)
			(xy 144.529556 -214.010494) (xy 144.523196 -214.017346) (xy 144.515561 -214.034394) (xy 144.514598 -214.05305)
			(xy 144.51711 -214.062056) (xy 144.544796 -214.148162) (xy 144.548003 -214.156878) (xy 144.559588 -214.171375)
			(xy 144.57559 -214.180772) (xy 144.584674 -214.182706) (xy 144.584928 -214.182706) (xy 144.611378 -214.18755)
			(xy 144.66271 -214.203554) (xy 144.711284 -214.226611) (xy 144.756137 -214.256263) (xy 144.796379 -214.291924)
			(xy 144.831211 -214.332884) (xy 144.859944 -214.378332) (xy 144.882006 -214.427366) (xy 144.89696 -214.479014)
			(xy 144.90451 -214.53225) (xy 144.904968 -214.559134) (xy 144.904577 -214.58639) (xy 144.896814 -214.640345)
			(xy 144.881452 -214.692647) (xy 144.858802 -214.74223) (xy 144.843594 -214.76589) (xy 145.026886 -214.76589)
			(xy 145.030957 -214.710268) (xy 145.043083 -214.655831) (xy 145.063006 -214.60374) (xy 145.090302 -214.555105)
			(xy 145.124388 -214.510962) (xy 145.164537 -214.472253) (xy 145.209895 -214.439802) (xy 145.259495 -214.414301)
			(xy 145.312279 -214.396294) (xy 145.367122 -214.386164) (xy 145.422856 -214.384127) (xy 145.478293 -214.390227)
			(xy 145.53225 -214.404333) (xy 145.583579 -214.426145) (xy 145.631185 -214.455199) (xy 145.674053 -214.490874)
			(xy 145.71127 -214.532411) (xy 145.742043 -214.578924) (xy 145.765715 -214.629421) (xy 145.781783 -214.682828)
			(xy 145.789903 -214.738004) (xy 145.790412 -214.76589) (xy 145.789903 -214.793776) (xy 145.781783 -214.848952)
			(xy 145.765715 -214.902359) (xy 145.742043 -214.952856) (xy 145.71127 -214.999369) (xy 145.674053 -215.040906)
			(xy 145.631185 -215.076581) (xy 145.583579 -215.105635) (xy 145.53225 -215.127447) (xy 145.478293 -215.141553)
			(xy 145.422856 -215.147653) (xy 145.367122 -215.145616) (xy 145.312279 -215.135486) (xy 145.259495 -215.117479)
			(xy 145.209895 -215.091978) (xy 145.164537 -215.059527) (xy 145.124388 -215.020818) (xy 145.090302 -214.976675)
			(xy 145.063006 -214.92804) (xy 145.043083 -214.875949) (xy 145.030957 -214.821512) (xy 145.026886 -214.76589)
			(xy 144.843594 -214.76589) (xy 144.829327 -214.788085) (xy 144.793626 -214.829278) (xy 144.752425 -214.864971)
			(xy 144.706565 -214.894438) (xy 144.656977 -214.917078) (xy 144.604673 -214.93243) (xy 144.550716 -214.940182)
			(xy 144.52346 -214.940642) (xy 144.494997 -214.940086) (xy 144.438701 -214.93164) (xy 144.384283 -214.914928)
			(xy 144.332951 -214.890319) (xy 144.285843 -214.858359) (xy 144.244004 -214.819758) (xy 144.225772 -214.797894)
			(xy 144.215612 -214.785194) (xy 144.184624 -214.776304) (xy 144.078706 -214.813642) (xy 144.068995 -214.81762)
			(xy 144.053666 -214.831915) (xy 144.045375 -214.851165) (xy 144.044924 -214.861648) (xy 144.044924 -216.408)
			(xy 144.044762 -216.424103) (xy 144.04171 -216.456164) (xy 144.038828 -216.472008) (xy 144.036288 -216.4842)
			(xy 144.043654 -216.508584) (xy 144.052798 -216.517728) (xy 144.06021 -216.524412) (xy 144.078643 -216.532009)
			(xy 144.098581 -216.532009) (xy 144.117014 -216.524412) (xy 144.124426 -216.517728) (xy 144.418304 -216.22385)
			(xy 144.437088 -216.205741) (xy 144.479285 -216.175056) (xy 144.525765 -216.151355) (xy 144.575382 -216.135221)
			(xy 144.626913 -216.127054) (xy 144.653 -216.126568) (xy 144.850104 -216.126568) (xy 144.860175 -216.126153)
			(xy 144.878773 -216.118426) (xy 144.886172 -216.111582) (xy 145.85442 -215.143334) (xy 145.857839 -215.139705)
			(xy 145.863336 -215.131388) (xy 145.865342 -215.126824) (xy 146.436334 -213.749128) (xy 146.4398 -213.739728)
			(xy 146.439807 -213.719707) (xy 146.432148 -213.701208) (xy 146.417991 -213.687051) (xy 146.408902 -213.682834)
			(xy 146.34591 -213.656672) (xy 146.32205 -213.64624) (xy 146.277667 -213.619009) (xy 146.238079 -213.585182)
			(xy 146.204259 -213.545589) (xy 146.177035 -213.501201) (xy 146.166586 -213.477348) (xy 146.093688 -213.301834)
			(xy 146.085633 -213.281598) (xy 146.074322 -213.239538) (xy 146.068626 -213.196357) (xy 146.068288 -213.17458)
			(xy 146.06869 -213.152849) (xy 146.074412 -213.109764) (xy 146.085691 -213.06779) (xy 146.093688 -213.04758)
			(xy 146.236944 -212.70214) (xy 146.247358 -212.678248) (xy 146.274545 -212.633785) (xy 146.308358 -212.594126)
			(xy 146.347964 -212.560251) (xy 146.392384 -212.532994) (xy 146.416268 -212.522562) (xy 146.592036 -212.449664)
			(xy 146.612276 -212.441622) (xy 146.654334 -212.430305) (xy 146.697513 -212.424604) (xy 146.71929 -212.424264)
			(xy 146.741064 -212.424639) (xy 146.784236 -212.430355) (xy 146.826295 -212.44165) (xy 146.846544 -212.449664)
			(xy 146.908774 -212.475572) (xy 146.918192 -212.479087) (xy 146.938284 -212.479112) (xy 146.956855 -212.471446)
			(xy 146.971079 -212.457255) (xy 146.975322 -212.44814) (xy 148.59127 -208.547208) (xy 148.593067 -208.542521)
			(xy 148.594988 -208.532669) (xy 148.59508 -208.52765) (xy 148.59508 -206.274416) (xy 148.594652 -206.264347)
			(xy 148.586934 -206.245749) (xy 148.580094 -206.238348) (xy 147.246086 -204.904594) (xy 147.227965 -204.885822)
			(xy 147.197284 -204.84362) (xy 147.173586 -204.797137) (xy 147.157456 -204.747518) (xy 147.14929 -204.695986)
			(xy 147.148804 -204.669898) (xy 147.148804 -201.591418) (xy 147.149287 -201.56533) (xy 147.157452 -201.513798)
			(xy 147.173585 -201.46418) (xy 147.197286 -201.417699) (xy 147.227973 -201.375502) (xy 147.246086 -201.356722)
			(xy 148.406104 -200.196704) (xy 148.424903 -200.178702) (xy 148.467012 -200.148118) (xy 148.513381 -200.124485)
			(xy 148.562872 -200.108383) (xy 148.61427 -200.100208) (xy 148.640292 -200.099676) (xy 149.20595 -200.099676)
			(xy 149.231974 -200.1002) (xy 149.283377 -200.108367) (xy 149.332874 -200.124462) (xy 149.37925 -200.148091)
			(xy 149.421367 -200.178672) (xy 149.440138 -200.196704) (xy 149.612096 -200.368662) (xy 149.616501 -200.372765)
			(xy 149.626757 -200.379058) (xy 149.632416 -200.381108) (xy 149.632924 -200.381108) (xy 149.658444 -200.389624)
			(xy 149.707046 -200.412686) (xy 149.751926 -200.442347) (xy 149.792195 -200.478019) (xy 149.827052 -200.518994)
			(xy 149.855808 -200.56446) (xy 149.877891 -200.613514) (xy 149.892864 -200.665185) (xy 149.900429 -200.718446)
			(xy 149.900894 -200.745344) (xy 149.900463 -200.772597) (xy 149.8927 -200.826547) (xy 149.877339 -200.878844)
			(xy 149.854692 -200.928422) (xy 149.825219 -200.974273) (xy 149.789522 -201.015463) (xy 149.748327 -201.051154)
			(xy 149.702471 -201.080619) (xy 149.65289 -201.103259) (xy 149.600591 -201.118613) (xy 149.546639 -201.126367)
			(xy 149.519386 -201.126852) (xy 149.492478 -201.126329) (xy 149.439198 -201.118751) (xy 149.387511 -201.103764)
			(xy 149.338442 -201.081663) (xy 149.292965 -201.052887) (xy 149.251982 -201.018007) (xy 149.216307 -200.977714)
			(xy 149.186646 -200.93281) (xy 149.163589 -200.884183) (xy 149.15515 -200.858628) (xy 149.15515 -200.858374)
			(xy 149.153166 -200.852683) (xy 149.146873 -200.842407) (xy 149.142704 -200.838054) (xy 149.083014 -200.77811)
			(xy 149.075602 -200.771285) (xy 149.057012 -200.763556) (xy 149.046946 -200.763124) (xy 148.799296 -200.763124)
			(xy 148.789226 -200.763541) (xy 148.770628 -200.771267) (xy 148.763228 -200.77811) (xy 148.082693 -201.45883)
			(xy 148.477222 -201.45883) (xy 148.481293 -201.403208) (xy 148.493419 -201.348771) (xy 148.513342 -201.29668)
			(xy 148.540638 -201.248045) (xy 148.574724 -201.203902) (xy 148.614873 -201.165193) (xy 148.660231 -201.132742)
			(xy 148.709831 -201.107241) (xy 148.762615 -201.089234) (xy 148.817458 -201.079104) (xy 148.873192 -201.077067)
			(xy 148.928629 -201.083167) (xy 148.982586 -201.097273) (xy 149.033915 -201.119085) (xy 149.081521 -201.148139)
			(xy 149.124389 -201.183814) (xy 149.161606 -201.225351) (xy 149.192379 -201.271864) (xy 149.216051 -201.322361)
			(xy 149.232119 -201.375768) (xy 149.240239 -201.430944) (xy 149.240748 -201.45883) (xy 149.240239 -201.486716)
			(xy 149.232119 -201.541892) (xy 149.216051 -201.595299) (xy 149.192379 -201.645796) (xy 149.161606 -201.692309)
			(xy 149.124389 -201.733846) (xy 149.081521 -201.769521) (xy 149.033915 -201.798575) (xy 148.982586 -201.820387)
			(xy 148.928629 -201.834493) (xy 148.873192 -201.840593) (xy 148.817458 -201.838556) (xy 148.762615 -201.828426)
			(xy 148.709831 -201.810419) (xy 148.660231 -201.784918) (xy 148.614873 -201.752467) (xy 148.574724 -201.713758)
			(xy 148.540638 -201.669615) (xy 148.513342 -201.62098) (xy 148.493419 -201.568889) (xy 148.481293 -201.514452)
			(xy 148.477222 -201.45883) (xy 148.082693 -201.45883) (xy 147.827746 -201.713846) (xy 147.820944 -201.721276)
			(xy 147.8132 -201.739852) (xy 147.81276 -201.749914) (xy 147.81276 -202.69962) (xy 149.057612 -202.69962)
			(xy 149.061683 -202.643998) (xy 149.073809 -202.589561) (xy 149.093732 -202.53747) (xy 149.121028 -202.488835)
			(xy 149.155114 -202.444692) (xy 149.195263 -202.405983) (xy 149.240621 -202.373532) (xy 149.290221 -202.348031)
			(xy 149.343005 -202.330024) (xy 149.397848 -202.319894) (xy 149.453582 -202.317857) (xy 149.509019 -202.323957)
			(xy 149.562976 -202.338063) (xy 149.614305 -202.359875) (xy 149.661911 -202.388929) (xy 149.704779 -202.424604)
			(xy 149.741996 -202.466141) (xy 149.772769 -202.512654) (xy 149.796441 -202.563151) (xy 149.812509 -202.616558)
			(xy 149.820629 -202.671734) (xy 149.821138 -202.69962) (xy 149.820629 -202.727506) (xy 149.812509 -202.782682)
			(xy 149.796441 -202.836089) (xy 149.772769 -202.886586) (xy 149.741996 -202.933099) (xy 149.704779 -202.974636)
			(xy 149.661911 -203.010311) (xy 149.614305 -203.039365) (xy 149.562976 -203.061177) (xy 149.509019 -203.075283)
			(xy 149.453582 -203.081383) (xy 149.397848 -203.079346) (xy 149.343005 -203.069216) (xy 149.290221 -203.051209)
			(xy 149.240621 -203.025708) (xy 149.195263 -202.993257) (xy 149.155114 -202.954548) (xy 149.121028 -202.910405)
			(xy 149.093732 -202.86177) (xy 149.073809 -202.809679) (xy 149.061683 -202.755242) (xy 149.057612 -202.69962)
			(xy 147.81276 -202.69962) (xy 147.81276 -203.58608) (xy 149.029166 -203.58608) (xy 149.029652 -203.558829)
			(xy 149.037408 -203.504881) (xy 149.052763 -203.452586) (xy 149.075405 -203.403009) (xy 149.104871 -203.357159)
			(xy 149.140562 -203.315968) (xy 149.181753 -203.280277) (xy 149.227603 -203.250811) (xy 149.27718 -203.228169)
			(xy 149.329475 -203.212814) (xy 149.383423 -203.205058) (xy 149.437925 -203.205058) (xy 149.491873 -203.212814)
			(xy 149.544168 -203.228169) (xy 149.593745 -203.250811) (xy 149.639595 -203.280277) (xy 149.680786 -203.315968)
			(xy 149.716477 -203.357159) (xy 149.745943 -203.403009) (xy 149.768585 -203.452586) (xy 149.78394 -203.504881)
			(xy 149.791696 -203.558829) (xy 149.792182 -203.58608) (xy 149.791618 -203.615691) (xy 149.78245 -203.674198)
			(xy 149.764363 -203.73059) (xy 149.73779 -203.783515) (xy 149.703367 -203.831705) (xy 149.661919 -203.874005)
			(xy 149.638512 -203.89215) (xy 149.629223 -203.899874) (xy 149.618491 -203.921483) (xy 149.617938 -203.933552)
			(xy 149.619208 -204.015848) (xy 149.620034 -204.027911) (xy 149.6313 -204.049262) (xy 149.640798 -204.056742)
			(xy 149.661873 -204.072134) (xy 149.70004 -204.107725) (xy 149.733001 -204.148185) (xy 149.76014 -204.192759)
			(xy 149.780952 -204.240616) (xy 149.795049 -204.290862) (xy 149.802167 -204.342561) (xy 149.802596 -204.368654)
			(xy 149.80211 -204.395581) (xy 149.794531 -204.448898) (xy 149.77953 -204.50062) (xy 149.757406 -204.549719)
			(xy 149.728599 -204.595219) (xy 149.69368 -204.636217) (xy 149.673818 -204.654404) (xy 149.665436 -204.662024)
			(xy 149.656546 -204.682598) (xy 149.660102 -204.784198) (xy 149.670516 -204.804264) (xy 149.67966 -204.811122)
			(xy 149.702492 -204.829315) (xy 149.742898 -204.871448) (xy 149.776414 -204.919245) (xy 149.802259 -204.971589)
			(xy 149.819829 -205.027259) (xy 149.828714 -205.084956) (xy 149.829266 -205.114144) (xy 149.82878 -205.141395)
			(xy 149.821024 -205.195343) (xy 149.805669 -205.247638) (xy 149.783027 -205.297215) (xy 149.753561 -205.343065)
			(xy 149.71787 -205.384256) (xy 149.676679 -205.419947) (xy 149.630829 -205.449413) (xy 149.581252 -205.472055)
			(xy 149.528957 -205.48741) (xy 149.475009 -205.495166) (xy 149.420507 -205.495166) (xy 149.366559 -205.48741)
			(xy 149.314264 -205.472055) (xy 149.264687 -205.449413) (xy 149.218837 -205.419947) (xy 149.177646 -205.384256)
			(xy 149.141955 -205.343065) (xy 149.112489 -205.297215) (xy 149.089847 -205.247638) (xy 149.074492 -205.195343)
			(xy 149.066736 -205.141395) (xy 149.06625 -205.114144) (xy 149.066752 -205.087218) (xy 149.074331 -205.033903)
			(xy 149.089329 -204.982182) (xy 149.11145 -204.933083) (xy 149.140254 -204.887582) (xy 149.175169 -204.846582)
			(xy 149.195028 -204.828394) (xy 149.20341 -204.820774) (xy 149.2123 -204.8002) (xy 149.208744 -204.6986)
			(xy 149.19833 -204.678534) (xy 149.189186 -204.671676) (xy 149.166342 -204.653498) (xy 149.125939 -204.61136)
			(xy 149.092426 -204.56356) (xy 149.066584 -204.511213) (xy 149.049015 -204.455541) (xy 149.040131 -204.397843)
			(xy 149.03958 -204.368654) (xy 149.040144 -204.339043) (xy 149.049308 -204.280534) (xy 149.067393 -204.224141)
			(xy 149.093967 -204.171215) (xy 149.128391 -204.123026) (xy 149.169842 -204.080727) (xy 149.19325 -204.062584)
			(xy 149.202517 -204.054837) (xy 149.213263 -204.033246) (xy 149.213824 -204.021182) (xy 149.212554 -203.938886)
			(xy 149.211723 -203.926824) (xy 149.200462 -203.905471) (xy 149.190964 -203.897992) (xy 149.169872 -203.882623)
			(xy 149.131703 -203.84703) (xy 149.098741 -203.806567) (xy 149.071603 -203.761989) (xy 149.050793 -203.714128)
			(xy 149.036702 -203.663877) (xy 149.029591 -203.612175) (xy 149.029166 -203.58608) (xy 147.81276 -203.58608)
			(xy 147.81276 -204.511402) (xy 147.813169 -204.521473) (xy 147.820899 -204.540072) (xy 147.827746 -204.54747)
			(xy 149.1615 -205.881224) (xy 149.179512 -205.900013) (xy 149.210095 -205.942125) (xy 149.233726 -205.988497)
			(xy 149.249825 -206.03799) (xy 149.257998 -206.08939) (xy 149.258528 -206.115412) (xy 149.258528 -208.604358)
			(xy 149.258163 -208.625998) (xy 149.252517 -208.668909) (xy 149.241327 -208.710718) (xy 149.233382 -208.73085)
			(xy 148.407619 -210.724496) (xy 148.970236 -210.724496) (xy 148.974307 -210.668874) (xy 148.986433 -210.614437)
			(xy 149.006356 -210.562346) (xy 149.033652 -210.513711) (xy 149.067738 -210.469568) (xy 149.107887 -210.430859)
			(xy 149.153245 -210.398408) (xy 149.202845 -210.372907) (xy 149.255629 -210.3549) (xy 149.310472 -210.34477)
			(xy 149.366206 -210.342733) (xy 149.421643 -210.348833) (xy 149.4756 -210.362939) (xy 149.526929 -210.384751)
			(xy 149.574535 -210.413805) (xy 149.617403 -210.44948) (xy 149.65462 -210.491017) (xy 149.685393 -210.53753)
			(xy 149.709065 -210.588027) (xy 149.725133 -210.641434) (xy 149.733253 -210.69661) (xy 149.733762 -210.724496)
			(xy 149.733253 -210.752382) (xy 149.725133 -210.807558) (xy 149.709065 -210.860965) (xy 149.685393 -210.911462)
			(xy 149.65462 -210.957975) (xy 149.617403 -210.999512) (xy 149.574535 -211.035187) (xy 149.526929 -211.064241)
			(xy 149.4756 -211.086053) (xy 149.421643 -211.100159) (xy 149.366206 -211.106259) (xy 149.310472 -211.104222)
			(xy 149.255629 -211.094092) (xy 149.202845 -211.076085) (xy 149.153245 -211.050584) (xy 149.107887 -211.018133)
			(xy 149.067738 -210.979424) (xy 149.033652 -210.935281) (xy 149.006356 -210.886646) (xy 148.986433 -210.834555)
			(xy 148.974307 -210.780118) (xy 148.970236 -210.724496) (xy 148.407619 -210.724496) (xy 147.493482 -212.931502)
			(xy 147.48312 -212.955418) (xy 147.455921 -212.99988) (xy 147.422095 -213.039535) (xy 147.382478 -213.073404)
			(xy 147.338047 -213.100653) (xy 147.314158 -213.11108) (xy 147.138644 -213.183978) (xy 147.122896 -213.190074)
			(xy 147.112736 -213.19363) (xy 147.096988 -213.208362) (xy 147.064222 -213.288118) (xy 147.06064 -213.298072)
			(xy 147.061034 -213.319199) (xy 147.064984 -213.329012) (xy 147.065238 -213.329012) (xy 147.065238 -213.32952)
			(xy 147.071842 -213.343998) (xy 147.14474 -213.519512) (xy 147.152775 -213.539755) (xy 147.164094 -213.581812)
			(xy 147.169798 -213.624989) (xy 147.17014 -213.646766) (xy 147.169758 -213.668498) (xy 147.164028 -213.711583)
			(xy 147.152741 -213.753557) (xy 147.14474 -213.773766) (xy 146.747738 -214.731854) (xy 146.758152 -214.766398)
			(xy 146.773138 -214.776558) (xy 146.783192 -214.782659) (xy 146.806482 -214.785741) (xy 146.828711 -214.778136)
			(xy 146.8374 -214.770208) (xy 149.372828 -212.23478) (xy 149.376239 -212.231144) (xy 149.381741 -212.222832)
			(xy 149.38375 -212.21827) (xy 150.304246 -209.99704) (xy 150.306037 -209.992351) (xy 150.307961 -209.982501)
			(xy 150.308056 -209.977482) (xy 150.308056 -200.626218) (xy 150.307971 -200.621199) (xy 150.306046 -200.611346)
			(xy 150.304246 -200.60666) (xy 149.654514 -199.039226) (xy 149.652536 -199.034647) (xy 149.647029 -199.026332)
			(xy 149.643592 -199.022716) (xy 148.728938 -198.108062) (xy 148.724554 -198.103935) (xy 148.714283 -198.097657)
			(xy 148.708618 -198.095616) (xy 148.70811 -198.095616) (xy 148.682553 -198.087207) (xy 148.633948 -198.06413)
			(xy 148.589067 -198.034455) (xy 148.548801 -197.998769) (xy 148.513946 -197.95778) (xy 148.485196 -197.912301)
			(xy 148.46312 -197.863235) (xy 148.448155 -197.811553) (xy 148.440599 -197.758282) (xy 148.44014 -197.73138)
			(xy 148.440536 -197.704124) (xy 148.448297 -197.650169) (xy 148.463658 -197.597866) (xy 148.486307 -197.548283)
			(xy 148.515781 -197.502428) (xy 148.551482 -197.461234) (xy 148.592682 -197.42554) (xy 148.638543 -197.396074)
			(xy 148.68813 -197.373435) (xy 148.740435 -197.358083) (xy 148.794392 -197.350332) (xy 148.821648 -197.349872)
			(xy 148.848558 -197.350349) (xy 148.901841 -197.357931) (xy 148.95353 -197.372924) (xy 149.0026 -197.395031)
			(xy 149.048077 -197.423813) (xy 149.089059 -197.458699) (xy 149.124734 -197.498997) (xy 149.154392 -197.543907)
			(xy 149.177447 -197.592539) (xy 149.185884 -197.618096) (xy 149.185884 -197.61835) (xy 149.187855 -197.624047)
			(xy 149.194157 -197.63432) (xy 149.19833 -197.63867) (xy 150.166832 -198.607172) (xy 150.181955 -198.622778)
			(xy 150.208396 -198.657267) (xy 150.2301 -198.694916) (xy 150.238714 -198.714868) (xy 150.946358 -200.423018)
			(xy 150.954301 -200.44315) (xy 150.965481 -200.484962) (xy 150.971137 -200.52787) (xy 150.971504 -200.54951)
			(xy 150.971504 -210.05419) (xy 150.971144 -210.07583) (xy 150.965495 -210.118741) (xy 150.954304 -210.16055)
			(xy 150.946358 -210.180682) (xy 149.96795 -212.542628) (xy 149.959329 -212.562575) (xy 149.937613 -212.600215)
			(xy 149.911173 -212.634702) (xy 149.896068 -212.650324) (xy 147.33651 -215.209628) (xy 147.329667 -215.217025)
			(xy 147.321948 -215.235627) (xy 147.321524 -215.245696) (xy 147.321524 -215.417908) (xy 147.320974 -215.443931)
			(xy 147.312813 -215.495333) (xy 147.296724 -215.54483) (xy 147.273102 -215.591206) (xy 147.242526 -215.633324)
			(xy 147.224496 -215.652096) (xy 145.268696 -217.607896) (xy 145.249897 -217.625898) (xy 145.207788 -217.656482)
			(xy 145.161419 -217.680115) (xy 145.111928 -217.696217) (xy 145.06053 -217.704392) (xy 145.034508 -217.704924)
			(xy 144.862296 -217.704924) (xy 144.852226 -217.705341) (xy 144.833628 -217.713067) (xy 144.826228 -217.71991)
			(xy 141.746224 -220.799914) (xy 142.146018 -220.799914) (xy 142.150089 -220.744292) (xy 142.162215 -220.689855)
			(xy 142.182138 -220.637764) (xy 142.209434 -220.589129) (xy 142.24352 -220.544986) (xy 142.283669 -220.506277)
			(xy 142.329027 -220.473826) (xy 142.378627 -220.448325) (xy 142.431411 -220.430318) (xy 142.486254 -220.420188)
			(xy 142.541988 -220.418151) (xy 142.597425 -220.424251) (xy 142.651382 -220.438357) (xy 142.702711 -220.460169)
			(xy 142.750317 -220.489223) (xy 142.793185 -220.524898) (xy 142.830402 -220.566435) (xy 142.861175 -220.612948)
			(xy 142.884847 -220.663445) (xy 142.900915 -220.716852) (xy 142.909035 -220.772028) (xy 142.909544 -220.799914)
			(xy 142.909035 -220.8278) (xy 142.900915 -220.882976) (xy 142.884847 -220.936383) (xy 142.861175 -220.98688)
			(xy 142.830402 -221.033393) (xy 142.793185 -221.07493) (xy 142.750317 -221.110605) (xy 142.702711 -221.139659)
			(xy 142.651382 -221.161471) (xy 142.597425 -221.175577) (xy 142.541988 -221.181677) (xy 142.486254 -221.17964)
			(xy 142.431411 -221.16951) (xy 142.378627 -221.151503) (xy 142.329027 -221.126002) (xy 142.283669 -221.093551)
			(xy 142.24352 -221.054842) (xy 142.209434 -221.010699) (xy 142.182138 -220.962064) (xy 142.162215 -220.909973)
			(xy 142.150089 -220.855536) (xy 142.146018 -220.799914) (xy 141.746224 -220.799914) (xy 141.094714 -221.451424)
			(xy 141.087873 -221.458823) (xy 141.080153 -221.477423) (xy 141.079728 -221.487492) (xy 141.079728 -222.063818)
			(xy 141.679422 -222.063818) (xy 141.679908 -222.036567) (xy 141.687664 -221.982619) (xy 141.703019 -221.930324)
			(xy 141.725661 -221.880747) (xy 141.755127 -221.834897) (xy 141.790818 -221.793706) (xy 141.832009 -221.758015)
			(xy 141.877859 -221.728549) (xy 141.927436 -221.705907) (xy 141.979731 -221.690552) (xy 142.033679 -221.682796)
			(xy 142.088181 -221.682796) (xy 142.142129 -221.690552) (xy 142.194424 -221.705907) (xy 142.244001 -221.728549)
			(xy 142.289851 -221.758015) (xy 142.331042 -221.793706) (xy 142.366733 -221.834897) (xy 142.396199 -221.880747)
			(xy 142.418841 -221.930324) (xy 142.434196 -221.982619) (xy 142.441952 -222.036567) (xy 142.442438 -222.063818)
			(xy 142.441943 -222.090681) (xy 142.434405 -222.143875) (xy 142.41948 -222.195486) (xy 142.397464 -222.244493)
			(xy 142.368792 -222.289928) (xy 142.35176 -222.310706) (xy 142.34414 -222.319596) (xy 142.338298 -222.342202)
			(xy 142.358872 -222.443548) (xy 142.373096 -222.46209) (xy 142.383256 -222.46717) (xy 142.406567 -222.479398)
			(xy 142.449839 -222.509373) (xy 142.488582 -222.545009) (xy 142.522061 -222.585632) (xy 142.54964 -222.630469)
			(xy 142.570796 -222.678671) (xy 142.585128 -222.729323) (xy 142.592363 -222.781464) (xy 142.592806 -222.807784)
			(xy 142.592507 -222.824548) (xy 150.05507 -222.824548) (xy 150.059141 -222.768926) (xy 150.071267 -222.714489)
			(xy 150.09119 -222.662398) (xy 150.118486 -222.613763) (xy 150.152572 -222.56962) (xy 150.192721 -222.530911)
			(xy 150.238079 -222.49846) (xy 150.287679 -222.472959) (xy 150.340463 -222.454952) (xy 150.395306 -222.444822)
			(xy 150.45104 -222.442785) (xy 150.506477 -222.448885) (xy 150.560434 -222.462991) (xy 150.611763 -222.484803)
			(xy 150.659369 -222.513857) (xy 150.702237 -222.549532) (xy 150.739454 -222.591069) (xy 150.770227 -222.637582)
			(xy 150.793899 -222.688079) (xy 150.809967 -222.741486) (xy 150.818087 -222.796662) (xy 150.818596 -222.824548)
			(xy 150.818087 -222.852434) (xy 150.809967 -222.90761) (xy 150.793899 -222.961017) (xy 150.770227 -223.011514)
			(xy 150.739454 -223.058027) (xy 150.702237 -223.099564) (xy 150.659369 -223.135239) (xy 150.611763 -223.164293)
			(xy 150.560434 -223.186105) (xy 150.506477 -223.200211) (xy 150.45104 -223.206311) (xy 150.395306 -223.204274)
			(xy 150.340463 -223.194144) (xy 150.287679 -223.176137) (xy 150.238079 -223.150636) (xy 150.192721 -223.118185)
			(xy 150.152572 -223.079476) (xy 150.118486 -223.035333) (xy 150.09119 -222.986698) (xy 150.071267 -222.934607)
			(xy 150.059141 -222.88017) (xy 150.05507 -222.824548) (xy 142.592507 -222.824548) (xy 142.59232 -222.835035)
			(xy 142.584564 -222.888983) (xy 142.569209 -222.941278) (xy 142.546567 -222.990855) (xy 142.517101 -223.036705)
			(xy 142.48141 -223.077896) (xy 142.440219 -223.113587) (xy 142.394369 -223.143053) (xy 142.344792 -223.165695)
			(xy 142.292497 -223.18105) (xy 142.238549 -223.188806) (xy 142.184047 -223.188806) (xy 142.130099 -223.18105)
			(xy 142.077804 -223.165695) (xy 142.028227 -223.143053) (xy 141.982377 -223.113587) (xy 141.941186 -223.077896)
			(xy 141.905495 -223.036705) (xy 141.876029 -222.990855) (xy 141.853387 -222.941278) (xy 141.838032 -222.888983)
			(xy 141.830276 -222.835035) (xy 141.82979 -222.807784) (xy 141.830222 -222.780919) (xy 141.837774 -222.727722)
			(xy 141.852713 -222.67611) (xy 141.874744 -222.627104) (xy 141.90343 -222.581672) (xy 141.920468 -222.560896)
			(xy 141.928088 -222.552006) (xy 141.93393 -222.5294) (xy 141.913356 -222.428054) (xy 141.899132 -222.409512)
			(xy 141.888972 -222.404432) (xy 141.865668 -222.392191) (xy 141.822395 -222.362219) (xy 141.783651 -222.326585)
			(xy 141.750171 -222.285964) (xy 141.722591 -222.241129) (xy 141.701434 -222.192928) (xy 141.687101 -222.142277)
			(xy 141.679865 -222.090138) (xy 141.679422 -222.063818) (xy 141.079728 -222.063818) (xy 141.079728 -223.131126)
			(xy 141.079385 -223.152767) (xy 141.07373 -223.195678) (xy 141.062532 -223.237487) (xy 141.054582 -223.257618)
			(xy 140.525073 -224.536) (xy 143.84604 -224.536) (xy 143.850111 -224.480378) (xy 143.862237 -224.425941)
			(xy 143.88216 -224.37385) (xy 143.909456 -224.325215) (xy 143.943542 -224.281072) (xy 143.983691 -224.242363)
			(xy 144.029049 -224.209912) (xy 144.078649 -224.184411) (xy 144.131433 -224.166404) (xy 144.186276 -224.156274)
			(xy 144.24201 -224.154237) (xy 144.297447 -224.160337) (xy 144.351404 -224.174443) (xy 144.402733 -224.196255)
			(xy 144.450339 -224.225309) (xy 144.493207 -224.260984) (xy 144.530424 -224.302521) (xy 144.561197 -224.349034)
			(xy 144.584869 -224.399531) (xy 144.600937 -224.452938) (xy 144.609057 -224.508114) (xy 144.609566 -224.536)
			(xy 144.609057 -224.563886) (xy 144.600937 -224.619062) (xy 144.584869 -224.672469) (xy 144.561197 -224.722966)
			(xy 144.530424 -224.769479) (xy 144.493207 -224.811016) (xy 144.450339 -224.846691) (xy 144.402733 -224.875745)
			(xy 144.351404 -224.897557) (xy 144.297447 -224.911663) (xy 144.24201 -224.917763) (xy 144.186276 -224.915726)
			(xy 144.131433 -224.905596) (xy 144.078649 -224.887589) (xy 144.029049 -224.862088) (xy 143.983691 -224.829637)
			(xy 143.943542 -224.790928) (xy 143.909456 -224.746785) (xy 143.88216 -224.69815) (xy 143.862237 -224.646059)
			(xy 143.850111 -224.591622) (xy 143.84604 -224.536) (xy 140.525073 -224.536) (xy 140.442696 -224.734882)
			(xy 140.434056 -224.75482) (xy 140.412348 -224.792463) (xy 140.385916 -224.826954) (xy 140.370814 -224.842578)
			(xy 139.661392 -225.552) (xy 146.89404 -225.552) (xy 146.898111 -225.496378) (xy 146.910237 -225.441941)
			(xy 146.93016 -225.38985) (xy 146.957456 -225.341215) (xy 146.991542 -225.297072) (xy 147.031691 -225.258363)
			(xy 147.077049 -225.225912) (xy 147.126649 -225.200411) (xy 147.179433 -225.182404) (xy 147.234276 -225.172274)
			(xy 147.29001 -225.170237) (xy 147.345447 -225.176337) (xy 147.399404 -225.190443) (xy 147.450733 -225.212255)
			(xy 147.498339 -225.241309) (xy 147.541207 -225.276984) (xy 147.578424 -225.318521) (xy 147.609197 -225.365034)
			(xy 147.632869 -225.415531) (xy 147.648937 -225.468938) (xy 147.657057 -225.524114) (xy 147.657566 -225.552)
			(xy 147.657057 -225.579886) (xy 147.648937 -225.635062) (xy 147.632869 -225.688469) (xy 147.609197 -225.738966)
			(xy 147.578424 -225.785479) (xy 147.541207 -225.827016) (xy 147.498339 -225.862691) (xy 147.450733 -225.891745)
			(xy 147.399404 -225.913557) (xy 147.345447 -225.927663) (xy 147.29001 -225.933763) (xy 147.234276 -225.931726)
			(xy 147.179433 -225.921596) (xy 147.126649 -225.903589) (xy 147.077049 -225.878088) (xy 147.031691 -225.845637)
			(xy 146.991542 -225.806928) (xy 146.957456 -225.762785) (xy 146.93016 -225.71415) (xy 146.910237 -225.662059)
			(xy 146.898111 -225.607622) (xy 146.89404 -225.552) (xy 139.661392 -225.552) (xy 138.88847 -226.324922)
			(xy 141.670022 -226.324922) (xy 141.674093 -226.2693) (xy 141.686219 -226.214863) (xy 141.706142 -226.162772)
			(xy 141.733438 -226.114137) (xy 141.767524 -226.069994) (xy 141.807673 -226.031285) (xy 141.853031 -225.998834)
			(xy 141.902631 -225.973333) (xy 141.955415 -225.955326) (xy 142.010258 -225.945196) (xy 142.065992 -225.943159)
			(xy 142.121429 -225.949259) (xy 142.175386 -225.963365) (xy 142.226715 -225.985177) (xy 142.274321 -226.014231)
			(xy 142.317189 -226.049906) (xy 142.354406 -226.091443) (xy 142.385179 -226.137956) (xy 142.408851 -226.188453)
			(xy 142.424919 -226.24186) (xy 142.433039 -226.297036) (xy 142.433548 -226.324922) (xy 142.433039 -226.352808)
			(xy 142.424919 -226.407984) (xy 142.408851 -226.461391) (xy 142.385179 -226.511888) (xy 142.354406 -226.558401)
			(xy 142.345805 -226.568) (xy 147.02104 -226.568) (xy 147.025111 -226.512378) (xy 147.037237 -226.457941)
			(xy 147.05716 -226.40585) (xy 147.084456 -226.357215) (xy 147.118542 -226.313072) (xy 147.158691 -226.274363)
			(xy 147.204049 -226.241912) (xy 147.253649 -226.216411) (xy 147.306433 -226.198404) (xy 147.361276 -226.188274)
			(xy 147.41701 -226.186237) (xy 147.472447 -226.192337) (xy 147.526404 -226.206443) (xy 147.577733 -226.228255)
			(xy 147.625339 -226.257309) (xy 147.668207 -226.292984) (xy 147.705424 -226.334521) (xy 147.736197 -226.381034)
			(xy 147.759869 -226.431531) (xy 147.775937 -226.484938) (xy 147.784057 -226.540114) (xy 147.784566 -226.568)
			(xy 147.784057 -226.595886) (xy 147.775937 -226.651062) (xy 147.759869 -226.704469) (xy 147.736197 -226.754966)
			(xy 147.705424 -226.801479) (xy 147.668207 -226.843016) (xy 147.625339 -226.878691) (xy 147.577733 -226.907745)
			(xy 147.526404 -226.929557) (xy 147.472447 -226.943663) (xy 147.41701 -226.949763) (xy 147.361276 -226.947726)
			(xy 147.306433 -226.937596) (xy 147.253649 -226.919589) (xy 147.204049 -226.894088) (xy 147.158691 -226.861637)
			(xy 147.118542 -226.822928) (xy 147.084456 -226.778785) (xy 147.05716 -226.73015) (xy 147.037237 -226.678059)
			(xy 147.025111 -226.623622) (xy 147.02104 -226.568) (xy 142.345805 -226.568) (xy 142.317189 -226.599938)
			(xy 142.274321 -226.635613) (xy 142.226715 -226.664667) (xy 142.175386 -226.686479) (xy 142.121429 -226.700585)
			(xy 142.065992 -226.706685) (xy 142.010258 -226.704648) (xy 141.955415 -226.694518) (xy 141.902631 -226.676511)
			(xy 141.853031 -226.65101) (xy 141.807673 -226.618559) (xy 141.767524 -226.57985) (xy 141.733438 -226.535707)
			(xy 141.706142 -226.487072) (xy 141.686219 -226.434981) (xy 141.674093 -226.380544) (xy 141.670022 -226.324922)
			(xy 138.88847 -226.324922) (xy 138.032998 -227.180394) (xy 142.915892 -227.180394) (xy 142.919963 -227.124772)
			(xy 142.932089 -227.070335) (xy 142.952012 -227.018244) (xy 142.979308 -226.969609) (xy 143.013394 -226.925466)
			(xy 143.053543 -226.886757) (xy 143.098901 -226.854306) (xy 143.148501 -226.828805) (xy 143.201285 -226.810798)
			(xy 143.256128 -226.800668) (xy 143.311862 -226.798631) (xy 143.367299 -226.804731) (xy 143.421256 -226.818837)
			(xy 143.472585 -226.840649) (xy 143.520191 -226.869703) (xy 143.563059 -226.905378) (xy 143.600276 -226.946915)
			(xy 143.631049 -226.993428) (xy 143.654721 -227.043925) (xy 143.670789 -227.097332) (xy 143.678909 -227.152508)
			(xy 143.679418 -227.180394) (xy 143.678909 -227.20828) (xy 143.670789 -227.263456) (xy 143.654721 -227.316863)
			(xy 143.631049 -227.36736) (xy 143.600276 -227.413873) (xy 143.563059 -227.45541) (xy 143.52727 -227.485194)
			(xy 150.013922 -227.485194) (xy 150.017993 -227.429572) (xy 150.030119 -227.375135) (xy 150.050042 -227.323044)
			(xy 150.077338 -227.274409) (xy 150.111424 -227.230266) (xy 150.151573 -227.191557) (xy 150.196931 -227.159106)
			(xy 150.246531 -227.133605) (xy 150.299315 -227.115598) (xy 150.354158 -227.105468) (xy 150.409892 -227.103431)
			(xy 150.465329 -227.109531) (xy 150.519286 -227.123637) (xy 150.570615 -227.145449) (xy 150.618221 -227.174503)
			(xy 150.661089 -227.210178) (xy 150.698306 -227.251715) (xy 150.729079 -227.298228) (xy 150.752751 -227.348725)
			(xy 150.768819 -227.402132) (xy 150.776939 -227.457308) (xy 150.777448 -227.485194) (xy 150.776939 -227.51308)
			(xy 150.768819 -227.568256) (xy 150.752751 -227.621663) (xy 150.729079 -227.67216) (xy 150.698306 -227.718673)
			(xy 150.661089 -227.76021) (xy 150.618221 -227.795885) (xy 150.570615 -227.824939) (xy 150.519286 -227.846751)
			(xy 150.465329 -227.860857) (xy 150.409892 -227.866957) (xy 150.354158 -227.86492) (xy 150.299315 -227.85479)
			(xy 150.246531 -227.836783) (xy 150.196931 -227.811282) (xy 150.151573 -227.778831) (xy 150.111424 -227.740122)
			(xy 150.077338 -227.695979) (xy 150.050042 -227.647344) (xy 150.030119 -227.595253) (xy 150.017993 -227.540816)
			(xy 150.013922 -227.485194) (xy 143.52727 -227.485194) (xy 143.520191 -227.491085) (xy 143.472585 -227.520139)
			(xy 143.421256 -227.541951) (xy 143.367299 -227.556057) (xy 143.311862 -227.562157) (xy 143.256128 -227.56012)
			(xy 143.201285 -227.54999) (xy 143.148501 -227.531983) (xy 143.098901 -227.506482) (xy 143.053543 -227.474031)
			(xy 143.013394 -227.435322) (xy 142.979308 -227.391179) (xy 142.952012 -227.342544) (xy 142.932089 -227.290453)
			(xy 142.919963 -227.236016) (xy 142.915892 -227.180394) (xy 138.032998 -227.180394) (xy 137.267442 -227.94595)
			(xy 141.658338 -227.94595) (xy 141.662409 -227.890328) (xy 141.674535 -227.835891) (xy 141.694458 -227.7838)
			(xy 141.721754 -227.735165) (xy 141.75584 -227.691022) (xy 141.795989 -227.652313) (xy 141.841347 -227.619862)
			(xy 141.890947 -227.594361) (xy 141.943731 -227.576354) (xy 141.998574 -227.566224) (xy 142.054308 -227.564187)
			(xy 142.109745 -227.570287) (xy 142.163702 -227.584393) (xy 142.215031 -227.606205) (xy 142.262637 -227.635259)
			(xy 142.305505 -227.670934) (xy 142.342722 -227.712471) (xy 142.373495 -227.758984) (xy 142.397167 -227.809481)
			(xy 142.413235 -227.862888) (xy 142.421355 -227.918064) (xy 142.421864 -227.94595) (xy 142.421355 -227.973836)
			(xy 142.413235 -228.029012) (xy 142.397167 -228.082419) (xy 142.373495 -228.132916) (xy 142.342722 -228.179429)
			(xy 142.305505 -228.220966) (xy 142.262637 -228.256641) (xy 142.215031 -228.285695) (xy 142.163702 -228.307507)
			(xy 142.109745 -228.321613) (xy 142.054308 -228.327713) (xy 141.998574 -228.325676) (xy 141.943731 -228.315546)
			(xy 141.890947 -228.297539) (xy 141.841347 -228.272038) (xy 141.795989 -228.239587) (xy 141.75584 -228.200878)
			(xy 141.721754 -228.156735) (xy 141.694458 -228.1081) (xy 141.674535 -228.056009) (xy 141.662409 -228.001572)
			(xy 141.658338 -227.94595) (xy 137.267442 -227.94595) (xy 136.901174 -228.312218) (xy 136.882433 -228.330297)
			(xy 136.840324 -228.360927) (xy 136.793947 -228.384603) (xy 136.744441 -228.400744) (xy 136.693021 -228.408953)
			(xy 136.666986 -228.4095) (xy 136.66597 -228.4095) (xy 136.657334 -228.409246) (xy 136.635701 -228.421065)
			(xy 136.590059 -228.439691) (xy 136.542399 -228.452285) (xy 136.493514 -228.45864) (xy 136.468866 -228.45903)
			(xy 136.441618 -228.458497) (xy 136.387677 -228.450737) (xy 136.335389 -228.43538) (xy 136.285819 -228.412739)
			(xy 136.239976 -228.383273) (xy 136.198792 -228.347584) (xy 136.163107 -228.306397) (xy 136.133645 -228.260551)
			(xy 136.111008 -228.210979) (xy 136.095655 -228.15869) (xy 136.0879 -228.104748) (xy 136.0879 -228.050252)
			(xy 136.095655 -227.99631) (xy 136.111008 -227.944021) (xy 136.133645 -227.894449) (xy 136.163107 -227.848603)
			(xy 136.198792 -227.807416) (xy 136.239976 -227.771727) (xy 136.285819 -227.742261) (xy 136.335389 -227.71962)
			(xy 136.387677 -227.704263) (xy 136.441618 -227.696503) (xy 136.468866 -227.696014) (xy 136.486885 -227.696231)
			(xy 136.52276 -227.699668) (xy 136.540494 -227.702872) (xy 136.55294 -227.705158) (xy 136.57707 -227.697792)
			(xy 139.847574 -224.427034) (xy 139.850988 -224.423401) (xy 139.856488 -224.415087) (xy 139.858496 -224.410524)
			(xy 139.88796 -224.340166) (xy 139.877292 -224.305622) (xy 139.862052 -224.295462) (xy 139.851987 -224.289515)
			(xy 139.828836 -224.286488) (xy 139.806723 -224.293982) (xy 139.798044 -224.301812) (xy 137.55116 -226.548696)
			(xy 137.532377 -226.566715) (xy 137.490263 -226.597297) (xy 137.44389 -226.620927) (xy 137.394396 -226.637025)
			(xy 137.342995 -226.645195) (xy 137.316972 -226.645724) (xy 136.193276 -226.645724) (xy 136.183264 -226.646169)
			(xy 136.164767 -226.653841) (xy 136.150614 -226.668007) (xy 136.142959 -226.686511) (xy 136.142476 -226.696524)
			(xy 136.142476 -227.089462) (xy 136.141974 -227.115487) (xy 136.133803 -227.166892) (xy 136.117704 -227.21639)
			(xy 136.09407 -227.262766) (xy 136.063483 -227.304881) (xy 136.045448 -227.32365) (xy 135.910828 -227.45827)
			(xy 135.892034 -227.476368) (xy 135.849839 -227.507053) (xy 135.803362 -227.530756) (xy 135.753747 -227.546892)
			(xy 135.702218 -227.555063) (xy 135.676132 -227.555552) (xy 135.302752 -227.555552) (xy 135.276665 -227.555061)
			(xy 135.225132 -227.546899) (xy 135.175514 -227.530769) (xy 135.129033 -227.507069) (xy 135.086836 -227.476384)
			(xy 135.068056 -227.45827) (xy 134.933436 -227.32365) (xy 134.9154 -227.304883) (xy 134.884823 -227.262763)
			(xy 134.861198 -227.216386) (xy 134.845104 -227.166889) (xy 134.836936 -227.115486) (xy 134.836408 -227.089462)
			(xy 134.836408 -226.721924) (xy 134.835961 -226.711905) (xy 134.8283 -226.69339) (xy 134.814136 -226.679218)
			(xy 134.795626 -226.671546) (xy 134.785608 -226.671124) (xy 134.742428 -226.671124) (xy 134.732406 -226.671543)
			(xy 134.713885 -226.679208) (xy 134.699711 -226.693381) (xy 134.692044 -226.711902) (xy 134.691628 -226.721924)
			(xy 134.691628 -227.98532) (xy 134.694168 -227.996496) (xy 134.696962 -228.00183) (xy 134.69747 -228.002846)
			(xy 134.711176 -228.030329) (xy 134.724143 -228.06914) (xy 135.036304 -228.06914) (xy 135.040375 -228.013518)
			(xy 135.052501 -227.959081) (xy 135.072424 -227.90699) (xy 135.09972 -227.858355) (xy 135.133806 -227.814212)
			(xy 135.173955 -227.775503) (xy 135.219313 -227.743052) (xy 135.268913 -227.717551) (xy 135.321697 -227.699544)
			(xy 135.37654 -227.689414) (xy 135.432274 -227.687377) (xy 135.487711 -227.693477) (xy 135.541668 -227.707583)
			(xy 135.592997 -227.729395) (xy 135.640603 -227.758449) (xy 135.683471 -227.794124) (xy 135.720688 -227.835661)
			(xy 135.751461 -227.882174) (xy 135.775133 -227.932671) (xy 135.791201 -227.986078) (xy 135.799321 -228.041254)
			(xy 135.79983 -228.06914) (xy 135.799321 -228.097026) (xy 135.791201 -228.152202) (xy 135.775133 -228.205609)
			(xy 135.751461 -228.256106) (xy 135.720688 -228.302619) (xy 135.683471 -228.344156) (xy 135.640603 -228.379831)
			(xy 135.592997 -228.408885) (xy 135.541668 -228.430697) (xy 135.487711 -228.444803) (xy 135.432274 -228.450903)
			(xy 135.37654 -228.448866) (xy 135.321697 -228.438736) (xy 135.268913 -228.420729) (xy 135.219313 -228.395228)
			(xy 135.173955 -228.362777) (xy 135.133806 -228.324068) (xy 135.09972 -228.279925) (xy 135.072424 -228.23129)
			(xy 135.052501 -228.179199) (xy 135.040375 -228.124762) (xy 135.036304 -228.06914) (xy 134.724143 -228.06914)
			(xy 134.730636 -228.088572) (xy 134.740519 -228.14918) (xy 134.741158 -228.179884) (xy 134.740672 -228.207135)
			(xy 134.732916 -228.261083) (xy 134.717561 -228.313378) (xy 134.694919 -228.362955) (xy 134.665453 -228.408805)
			(xy 134.629762 -228.449996) (xy 134.588571 -228.485687) (xy 134.542721 -228.515153) (xy 134.493144 -228.537795)
			(xy 134.440849 -228.55315) (xy 134.386901 -228.560906) (xy 134.332399 -228.560906) (xy 134.278451 -228.55315)
			(xy 134.226156 -228.537795) (xy 134.176579 -228.515153) (xy 134.130729 -228.485687) (xy 134.089538 -228.449996)
			(xy 134.053847 -228.408805) (xy 134.024381 -228.362955) (xy 134.001739 -228.313378) (xy 133.986384 -228.261083)
			(xy 133.978628 -228.207135) (xy 133.978142 -228.179884) (xy 88.237629 -228.179884) (xy 88.307538 -228.981)
			(xy 132.09727 -228.981) (xy 132.101341 -228.925378) (xy 132.113467 -228.870941) (xy 132.13339 -228.81885)
			(xy 132.160686 -228.770215) (xy 132.194772 -228.726072) (xy 132.234921 -228.687363) (xy 132.280279 -228.654912)
			(xy 132.329879 -228.629411) (xy 132.382663 -228.611404) (xy 132.437506 -228.601274) (xy 132.49324 -228.599237)
			(xy 132.548677 -228.605337) (xy 132.602634 -228.619443) (xy 132.653963 -228.641255) (xy 132.701569 -228.670309)
			(xy 132.744437 -228.705984) (xy 132.781654 -228.747521) (xy 132.812427 -228.794034) (xy 132.836099 -228.844531)
			(xy 132.852167 -228.897938) (xy 132.860287 -228.953114) (xy 132.860796 -228.981) (xy 132.860287 -229.008886)
			(xy 132.852167 -229.064062) (xy 132.836099 -229.117469) (xy 132.812427 -229.167966) (xy 132.781654 -229.214479)
			(xy 132.744437 -229.256016) (xy 132.701569 -229.291691) (xy 132.653963 -229.320745) (xy 132.602634 -229.342557)
			(xy 132.548677 -229.356663) (xy 132.49324 -229.362763) (xy 132.437506 -229.360726) (xy 132.382663 -229.350596)
			(xy 132.329879 -229.332589) (xy 132.280279 -229.307088) (xy 132.234921 -229.274637) (xy 132.194772 -229.235928)
			(xy 132.160686 -229.191785) (xy 132.13339 -229.14315) (xy 132.113467 -229.091059) (xy 132.101341 -229.036622)
			(xy 132.09727 -228.981) (xy 88.307538 -228.981) (xy 88.347302 -229.436676) (xy 147.716492 -229.436676)
			(xy 147.720563 -229.381054) (xy 147.732689 -229.326617) (xy 147.752612 -229.274526) (xy 147.779908 -229.225891)
			(xy 147.813994 -229.181748) (xy 147.854143 -229.143039) (xy 147.899501 -229.110588) (xy 147.949101 -229.085087)
			(xy 148.001885 -229.06708) (xy 148.056728 -229.05695) (xy 148.112462 -229.054913) (xy 148.167899 -229.061013)
			(xy 148.221856 -229.075119) (xy 148.273185 -229.096931) (xy 148.320791 -229.125985) (xy 148.363659 -229.16166)
			(xy 148.400876 -229.203197) (xy 148.431649 -229.24971) (xy 148.455321 -229.300207) (xy 148.471389 -229.353614)
			(xy 148.479509 -229.40879) (xy 148.480018 -229.436676) (xy 148.479509 -229.464562) (xy 148.471389 -229.519738)
			(xy 148.455321 -229.573145) (xy 148.431649 -229.623642) (xy 148.400876 -229.670155) (xy 148.363659 -229.711692)
			(xy 148.320791 -229.747367) (xy 148.273185 -229.776421) (xy 148.221856 -229.798233) (xy 148.167899 -229.812339)
			(xy 148.112462 -229.818439) (xy 148.056728 -229.816402) (xy 148.001885 -229.806272) (xy 147.949101 -229.788265)
			(xy 147.899501 -229.762764) (xy 147.854143 -229.730313) (xy 147.813994 -229.691604) (xy 147.779908 -229.647461)
			(xy 147.752612 -229.598826) (xy 147.732689 -229.546735) (xy 147.720563 -229.492298) (xy 147.716492 -229.436676)
			(xy 88.347302 -229.436676) (xy 88.391655 -229.94493) (xy 128.9083 -229.94493) (xy 128.912371 -229.889308)
			(xy 128.924497 -229.834871) (xy 128.94442 -229.78278) (xy 128.971716 -229.734145) (xy 129.005802 -229.690002)
			(xy 129.045951 -229.651293) (xy 129.091309 -229.618842) (xy 129.140909 -229.593341) (xy 129.193693 -229.575334)
			(xy 129.248536 -229.565204) (xy 129.30427 -229.563167) (xy 129.359707 -229.569267) (xy 129.413664 -229.583373)
			(xy 129.464993 -229.605185) (xy 129.512599 -229.634239) (xy 129.555467 -229.669914) (xy 129.592684 -229.711451)
			(xy 129.623457 -229.757964) (xy 129.647129 -229.808461) (xy 129.663197 -229.861868) (xy 129.671317 -229.917044)
			(xy 129.671826 -229.94493) (xy 138.89304 -229.94493) (xy 138.897111 -229.889308) (xy 138.909237 -229.834871)
			(xy 138.92916 -229.78278) (xy 138.956456 -229.734145) (xy 138.990542 -229.690002) (xy 139.030691 -229.651293)
			(xy 139.076049 -229.618842) (xy 139.125649 -229.593341) (xy 139.178433 -229.575334) (xy 139.233276 -229.565204)
			(xy 139.28901 -229.563167) (xy 139.344447 -229.569267) (xy 139.398404 -229.583373) (xy 139.449733 -229.605185)
			(xy 139.497339 -229.634239) (xy 139.540207 -229.669914) (xy 139.577424 -229.711451) (xy 139.608197 -229.757964)
			(xy 139.631869 -229.808461) (xy 139.647937 -229.861868) (xy 139.656057 -229.917044) (xy 139.656566 -229.94493)
			(xy 139.656057 -229.972816) (xy 139.647937 -230.027992) (xy 139.631869 -230.081399) (xy 139.608197 -230.131896)
			(xy 139.577424 -230.178409) (xy 139.540207 -230.219946) (xy 139.497339 -230.255621) (xy 139.449733 -230.284675)
			(xy 139.398404 -230.306487) (xy 139.344447 -230.320593) (xy 139.28901 -230.326693) (xy 139.233276 -230.324656)
			(xy 139.178433 -230.314526) (xy 139.125649 -230.296519) (xy 139.076049 -230.271018) (xy 139.030691 -230.238567)
			(xy 138.990542 -230.199858) (xy 138.956456 -230.155715) (xy 138.92916 -230.10708) (xy 138.909237 -230.054989)
			(xy 138.897111 -230.000552) (xy 138.89304 -229.94493) (xy 129.671826 -229.94493) (xy 129.671317 -229.972816)
			(xy 129.663197 -230.027992) (xy 129.647129 -230.081399) (xy 129.623457 -230.131896) (xy 129.592684 -230.178409)
			(xy 129.555467 -230.219946) (xy 129.512599 -230.255621) (xy 129.464993 -230.284675) (xy 129.413664 -230.306487)
			(xy 129.359707 -230.320593) (xy 129.30427 -230.326693) (xy 129.248536 -230.324656) (xy 129.193693 -230.314526)
			(xy 129.140909 -230.296519) (xy 129.091309 -230.271018) (xy 129.045951 -230.238567) (xy 129.005802 -230.199858)
			(xy 128.971716 -230.155715) (xy 128.94442 -230.10708) (xy 128.924497 -230.054989) (xy 128.912371 -230.000552)
			(xy 128.9083 -229.94493) (xy 88.391655 -229.94493) (xy 88.501506 -231.203754) (xy 130.91109 -231.203754)
			(xy 130.915161 -231.148132) (xy 130.927287 -231.093695) (xy 130.94721 -231.041604) (xy 130.974506 -230.992969)
			(xy 131.008592 -230.948826) (xy 131.048741 -230.910117) (xy 131.094099 -230.877666) (xy 131.143699 -230.852165)
			(xy 131.196483 -230.834158) (xy 131.251326 -230.824028) (xy 131.30706 -230.821991) (xy 131.362497 -230.828091)
			(xy 131.416454 -230.842197) (xy 131.467783 -230.864009) (xy 131.476764 -230.86949) (xy 148.496526 -230.86949)
			(xy 148.500597 -230.813868) (xy 148.512723 -230.759431) (xy 148.532646 -230.70734) (xy 148.559942 -230.658705)
			(xy 148.594028 -230.614562) (xy 148.634177 -230.575853) (xy 148.679535 -230.543402) (xy 148.729135 -230.517901)
			(xy 148.781919 -230.499894) (xy 148.836762 -230.489764) (xy 148.892496 -230.487727) (xy 148.947933 -230.493827)
			(xy 149.00189 -230.507933) (xy 149.053219 -230.529745) (xy 149.100825 -230.558799) (xy 149.143693 -230.594474)
			(xy 149.18091 -230.636011) (xy 149.211683 -230.682524) (xy 149.235355 -230.733021) (xy 149.251423 -230.786428)
			(xy 149.259543 -230.841604) (xy 149.260052 -230.86949) (xy 149.259543 -230.897376) (xy 149.251423 -230.952552)
			(xy 149.235355 -231.005959) (xy 149.211683 -231.056456) (xy 149.18091 -231.102969) (xy 149.143693 -231.144506)
			(xy 149.100825 -231.180181) (xy 149.053219 -231.209235) (xy 149.00189 -231.231047) (xy 148.947933 -231.245153)
			(xy 148.892496 -231.251253) (xy 148.836762 -231.249216) (xy 148.781919 -231.239086) (xy 148.729135 -231.221079)
			(xy 148.679535 -231.195578) (xy 148.634177 -231.163127) (xy 148.594028 -231.124418) (xy 148.559942 -231.080275)
			(xy 148.532646 -231.03164) (xy 148.512723 -230.979549) (xy 148.500597 -230.925112) (xy 148.496526 -230.86949)
			(xy 131.476764 -230.86949) (xy 131.515389 -230.893063) (xy 131.558257 -230.928738) (xy 131.595474 -230.970275)
			(xy 131.626247 -231.016788) (xy 131.649919 -231.067285) (xy 131.665987 -231.120692) (xy 131.674107 -231.175868)
			(xy 131.674616 -231.203754) (xy 131.674107 -231.23164) (xy 131.665987 -231.286816) (xy 131.649919 -231.340223)
			(xy 131.626247 -231.39072) (xy 131.595474 -231.437233) (xy 131.558257 -231.47877) (xy 131.515389 -231.514445)
			(xy 131.467783 -231.543499) (xy 131.416454 -231.565311) (xy 131.362497 -231.579417) (xy 131.30706 -231.585517)
			(xy 131.251326 -231.58348) (xy 131.196483 -231.57335) (xy 131.143699 -231.555343) (xy 131.094099 -231.529842)
			(xy 131.048741 -231.497391) (xy 131.008592 -231.458682) (xy 130.974506 -231.414539) (xy 130.94721 -231.365904)
			(xy 130.927287 -231.313813) (xy 130.915161 -231.259376) (xy 130.91109 -231.203754) (xy 88.501506 -231.203754)
			(xy 88.58057 -232.109772) (xy 133.008368 -232.109772) (xy 133.012439 -232.05415) (xy 133.024565 -231.999713)
			(xy 133.044488 -231.947622) (xy 133.071784 -231.898987) (xy 133.10587 -231.854844) (xy 133.146019 -231.816135)
			(xy 133.191377 -231.783684) (xy 133.240977 -231.758183) (xy 133.293761 -231.740176) (xy 133.348604 -231.730046)
			(xy 133.404338 -231.728009) (xy 133.459775 -231.734109) (xy 133.513732 -231.748215) (xy 133.565061 -231.770027)
			(xy 133.612667 -231.799081) (xy 133.655535 -231.834756) (xy 133.692752 -231.876293) (xy 133.723525 -231.922806)
			(xy 133.736395 -231.95026) (xy 134.511286 -231.95026) (xy 134.515357 -231.894638) (xy 134.527483 -231.840201)
			(xy 134.547406 -231.78811) (xy 134.574702 -231.739475) (xy 134.608788 -231.695332) (xy 134.648937 -231.656623)
			(xy 134.694295 -231.624172) (xy 134.743895 -231.598671) (xy 134.796679 -231.580664) (xy 134.851522 -231.570534)
			(xy 134.907256 -231.568497) (xy 134.962693 -231.574597) (xy 135.01665 -231.588703) (xy 135.067979 -231.610515)
			(xy 135.115585 -231.639569) (xy 135.158453 -231.675244) (xy 135.19567 -231.716781) (xy 135.226443 -231.763294)
			(xy 135.250115 -231.813791) (xy 135.266183 -231.867198) (xy 135.274303 -231.922374) (xy 135.274812 -231.95026)
			(xy 135.274303 -231.978146) (xy 135.266183 -232.033322) (xy 135.264121 -232.040176) (xy 152.293318 -232.040176)
			(xy 152.297389 -231.984554) (xy 152.309515 -231.930117) (xy 152.329438 -231.878026) (xy 152.356734 -231.829391)
			(xy 152.39082 -231.785248) (xy 152.430969 -231.746539) (xy 152.476327 -231.714088) (xy 152.525927 -231.688587)
			(xy 152.578711 -231.67058) (xy 152.633554 -231.66045) (xy 152.689288 -231.658413) (xy 152.744725 -231.664513)
			(xy 152.798682 -231.678619) (xy 152.850011 -231.700431) (xy 152.897617 -231.729485) (xy 152.940485 -231.76516)
			(xy 152.977702 -231.806697) (xy 153.008475 -231.85321) (xy 153.032147 -231.903707) (xy 153.048215 -231.957114)
			(xy 153.056335 -232.01229) (xy 153.056844 -232.040176) (xy 153.056335 -232.068062) (xy 153.048215 -232.123238)
			(xy 153.032147 -232.176645) (xy 153.008475 -232.227142) (xy 152.977702 -232.273655) (xy 152.940485 -232.315192)
			(xy 152.936438 -232.31856) (xy 153.215592 -232.31856) (xy 153.219663 -232.262938) (xy 153.231789 -232.208501)
			(xy 153.251712 -232.15641) (xy 153.279008 -232.107775) (xy 153.313094 -232.063632) (xy 153.353243 -232.024923)
			(xy 153.398601 -231.992472) (xy 153.448201 -231.966971) (xy 153.500985 -231.948964) (xy 153.555828 -231.938834)
			(xy 153.611562 -231.936797) (xy 153.666999 -231.942897) (xy 153.720956 -231.957003) (xy 153.772285 -231.978815)
			(xy 153.819891 -232.007869) (xy 153.862759 -232.043544) (xy 153.899976 -232.085081) (xy 153.930749 -232.131594)
			(xy 153.954421 -232.182091) (xy 153.970489 -232.235498) (xy 153.978609 -232.290674) (xy 153.979118 -232.31856)
			(xy 153.978609 -232.346446) (xy 153.970489 -232.401622) (xy 153.954421 -232.455029) (xy 153.930749 -232.505526)
			(xy 153.899976 -232.552039) (xy 153.862759 -232.593576) (xy 153.819891 -232.629251) (xy 153.772285 -232.658305)
			(xy 153.720956 -232.680117) (xy 153.666999 -232.694223) (xy 153.611562 -232.700323) (xy 153.555828 -232.698286)
			(xy 153.500985 -232.688156) (xy 153.448201 -232.670149) (xy 153.398601 -232.644648) (xy 153.353243 -232.612197)
			(xy 153.313094 -232.573488) (xy 153.279008 -232.529345) (xy 153.251712 -232.48071) (xy 153.231789 -232.428619)
			(xy 153.219663 -232.374182) (xy 153.215592 -232.31856) (xy 152.936438 -232.31856) (xy 152.897617 -232.350867)
			(xy 152.850011 -232.379921) (xy 152.798682 -232.401733) (xy 152.744725 -232.415839) (xy 152.689288 -232.421939)
			(xy 152.633554 -232.419902) (xy 152.578711 -232.409772) (xy 152.525927 -232.391765) (xy 152.476327 -232.366264)
			(xy 152.430969 -232.333813) (xy 152.39082 -232.295104) (xy 152.356734 -232.250961) (xy 152.329438 -232.202326)
			(xy 152.309515 -232.150235) (xy 152.297389 -232.095798) (xy 152.293318 -232.040176) (xy 135.264121 -232.040176)
			(xy 135.250115 -232.086729) (xy 135.226443 -232.137226) (xy 135.19567 -232.183739) (xy 135.158453 -232.225276)
			(xy 135.115585 -232.260951) (xy 135.067979 -232.290005) (xy 135.01665 -232.311817) (xy 134.962693 -232.325923)
			(xy 134.907256 -232.332023) (xy 134.851522 -232.329986) (xy 134.796679 -232.319856) (xy 134.743895 -232.301849)
			(xy 134.694295 -232.276348) (xy 134.648937 -232.243897) (xy 134.608788 -232.205188) (xy 134.574702 -232.161045)
			(xy 134.547406 -232.11241) (xy 134.527483 -232.060319) (xy 134.515357 -232.005882) (xy 134.511286 -231.95026)
			(xy 133.736395 -231.95026) (xy 133.747197 -231.973303) (xy 133.763265 -232.02671) (xy 133.771385 -232.081886)
			(xy 133.771894 -232.109772) (xy 133.771385 -232.137658) (xy 133.763265 -232.192834) (xy 133.747197 -232.246241)
			(xy 133.723525 -232.296738) (xy 133.692752 -232.343251) (xy 133.655535 -232.384788) (xy 133.612667 -232.420463)
			(xy 133.565061 -232.449517) (xy 133.513732 -232.471329) (xy 133.459775 -232.485435) (xy 133.404338 -232.491535)
			(xy 133.348604 -232.489498) (xy 133.293761 -232.479368) (xy 133.240977 -232.461361) (xy 133.191377 -232.43586)
			(xy 133.146019 -232.403409) (xy 133.10587 -232.3647) (xy 133.071784 -232.320557) (xy 133.044488 -232.271922)
			(xy 133.024565 -232.219831) (xy 133.012439 -232.165394) (xy 133.008368 -232.109772) (xy 88.58057 -232.109772)
			(xy 88.75255 -234.080558) (xy 119.279922 -234.080558) (xy 119.283993 -234.024936) (xy 119.296119 -233.970499)
			(xy 119.316042 -233.918408) (xy 119.343338 -233.869773) (xy 119.377424 -233.82563) (xy 119.417573 -233.786921)
			(xy 119.462931 -233.75447) (xy 119.512531 -233.728969) (xy 119.565315 -233.710962) (xy 119.620158 -233.700832)
			(xy 119.675892 -233.698795) (xy 119.731329 -233.704895) (xy 119.785286 -233.719001) (xy 119.836615 -233.740813)
			(xy 119.884221 -233.769867) (xy 119.927089 -233.805542) (xy 119.964306 -233.847079) (xy 119.995079 -233.893592)
			(xy 120.018751 -233.944089) (xy 120.034819 -233.997496) (xy 120.042939 -234.052672) (xy 120.043448 -234.080558)
			(xy 120.042939 -234.108444) (xy 120.034819 -234.16362) (xy 120.018751 -234.217027) (xy 119.995079 -234.267524)
			(xy 119.964306 -234.314037) (xy 119.927089 -234.355574) (xy 119.884221 -234.391249) (xy 119.836615 -234.420303)
			(xy 119.785286 -234.442115) (xy 119.731329 -234.456221) (xy 119.675892 -234.462321) (xy 119.620158 -234.460284)
			(xy 119.565315 -234.450154) (xy 119.512531 -234.432147) (xy 119.462931 -234.406646) (xy 119.417573 -234.374195)
			(xy 119.377424 -234.335486) (xy 119.343338 -234.291343) (xy 119.316042 -234.242708) (xy 119.296119 -234.190617)
			(xy 119.283993 -234.13618) (xy 119.279922 -234.080558) (xy 88.75255 -234.080558) (xy 88.831436 -234.984544)
			(xy 93.107 -234.984544) (xy 93.111071 -234.928922) (xy 93.123197 -234.874485) (xy 93.14312 -234.822394)
			(xy 93.170416 -234.773759) (xy 93.204502 -234.729616) (xy 93.244651 -234.690907) (xy 93.290009 -234.658456)
			(xy 93.339609 -234.632955) (xy 93.392393 -234.614948) (xy 93.447236 -234.604818) (xy 93.50297 -234.602781)
			(xy 93.558407 -234.608881) (xy 93.612364 -234.622987) (xy 93.663693 -234.644799) (xy 93.711299 -234.673853)
			(xy 93.754167 -234.709528) (xy 93.791384 -234.751065) (xy 93.822157 -234.797578) (xy 93.845829 -234.848075)
			(xy 93.861897 -234.901482) (xy 93.870017 -234.956658) (xy 93.870526 -234.984544) (xy 93.870017 -235.01243)
			(xy 93.861897 -235.067606) (xy 93.845829 -235.121013) (xy 93.822157 -235.17151) (xy 93.791384 -235.218023)
			(xy 93.754167 -235.25956) (xy 93.711299 -235.295235) (xy 93.663693 -235.324289) (xy 93.612364 -235.346101)
			(xy 93.558407 -235.360207) (xy 93.50297 -235.366307) (xy 93.447236 -235.36427) (xy 93.392393 -235.35414)
			(xy 93.339609 -235.336133) (xy 93.290009 -235.310632) (xy 93.244651 -235.278181) (xy 93.204502 -235.239472)
			(xy 93.170416 -235.195329) (xy 93.14312 -235.146694) (xy 93.123197 -235.094603) (xy 93.111071 -235.040166)
			(xy 93.107 -234.984544) (xy 88.831436 -234.984544) (xy 88.88031 -235.544614) (xy 120.151142 -235.544614)
			(xy 120.155213 -235.488992) (xy 120.167339 -235.434555) (xy 120.187262 -235.382464) (xy 120.214558 -235.333829)
			(xy 120.248644 -235.289686) (xy 120.288793 -235.250977) (xy 120.334151 -235.218526) (xy 120.383751 -235.193025)
			(xy 120.436535 -235.175018) (xy 120.491378 -235.164888) (xy 120.547112 -235.162851) (xy 120.602549 -235.168951)
			(xy 120.656506 -235.183057) (xy 120.707835 -235.204869) (xy 120.755441 -235.233923) (xy 120.798309 -235.269598)
			(xy 120.835526 -235.311135) (xy 120.866299 -235.357648) (xy 120.889971 -235.408145) (xy 120.906039 -235.461552)
			(xy 120.914159 -235.516728) (xy 120.914668 -235.544614) (xy 120.914159 -235.5725) (xy 120.906039 -235.627676)
			(xy 120.889971 -235.681083) (xy 120.866299 -235.73158) (xy 120.835526 -235.778093) (xy 120.798309 -235.81963)
			(xy 120.755441 -235.855305) (xy 120.707835 -235.884359) (xy 120.656506 -235.906171) (xy 120.602549 -235.920277)
			(xy 120.547112 -235.926377) (xy 120.491378 -235.92434) (xy 120.436535 -235.91421) (xy 120.383751 -235.896203)
			(xy 120.334151 -235.870702) (xy 120.288793 -235.838251) (xy 120.248644 -235.799542) (xy 120.214558 -235.755399)
			(xy 120.187262 -235.706764) (xy 120.167339 -235.654673) (xy 120.155213 -235.600236) (xy 120.151142 -235.544614)
			(xy 88.88031 -235.544614) (xy 88.969082 -236.561884) (xy 93.248986 -236.561884) (xy 93.253057 -236.506262)
			(xy 93.265183 -236.451825) (xy 93.285106 -236.399734) (xy 93.312402 -236.351099) (xy 93.346488 -236.306956)
			(xy 93.386637 -236.268247) (xy 93.431995 -236.235796) (xy 93.481595 -236.210295) (xy 93.534379 -236.192288)
			(xy 93.589222 -236.182158) (xy 93.644956 -236.180121) (xy 93.700393 -236.186221) (xy 93.75435 -236.200327)
			(xy 93.805679 -236.222139) (xy 93.853285 -236.251193) (xy 93.896153 -236.286868) (xy 93.93337 -236.328405)
			(xy 93.964143 -236.374918) (xy 93.972012 -236.391704) (xy 99.087938 -236.391704) (xy 99.092009 -236.336082)
			(xy 99.104135 -236.281645) (xy 99.124058 -236.229554) (xy 99.151354 -236.180919) (xy 99.18544 -236.136776)
			(xy 99.225589 -236.098067) (xy 99.270947 -236.065616) (xy 99.320547 -236.040115) (xy 99.373331 -236.022108)
			(xy 99.428174 -236.011978) (xy 99.483908 -236.009941) (xy 99.539345 -236.016041) (xy 99.593302 -236.030147)
			(xy 99.644631 -236.051959) (xy 99.692237 -236.081013) (xy 99.735105 -236.116688) (xy 99.772322 -236.158225)
			(xy 99.803095 -236.204738) (xy 99.826767 -236.255235) (xy 99.842835 -236.308642) (xy 99.850955 -236.363818)
			(xy 99.851464 -236.391704) (xy 99.850955 -236.41959) (xy 99.842835 -236.474766) (xy 99.826767 -236.528173)
			(xy 99.803095 -236.57867) (xy 99.772322 -236.625183) (xy 99.735105 -236.66672) (xy 99.692237 -236.702395)
			(xy 99.644631 -236.731449) (xy 99.593302 -236.753261) (xy 99.539345 -236.767367) (xy 99.483908 -236.773467)
			(xy 99.428174 -236.77143) (xy 99.373331 -236.7613) (xy 99.320547 -236.743293) (xy 99.270947 -236.717792)
			(xy 99.225589 -236.685341) (xy 99.18544 -236.646632) (xy 99.151354 -236.602489) (xy 99.124058 -236.553854)
			(xy 99.104135 -236.501763) (xy 99.092009 -236.447326) (xy 99.087938 -236.391704) (xy 93.972012 -236.391704)
			(xy 93.987815 -236.425415) (xy 94.003883 -236.478822) (xy 94.012003 -236.533998) (xy 94.012512 -236.561884)
			(xy 94.012003 -236.58977) (xy 94.003883 -236.644946) (xy 93.987815 -236.698353) (xy 93.964143 -236.74885)
			(xy 93.946681 -236.775244) (xy 101.503226 -236.775244) (xy 101.503712 -236.747874) (xy 101.511524 -236.693696)
			(xy 101.527008 -236.641193) (xy 101.549845 -236.591446) (xy 101.579566 -236.545478) (xy 101.597206 -236.524546)
			(xy 101.59746 -236.524292) (xy 101.603063 -236.517217) (xy 101.609298 -236.500291) (xy 101.609652 -236.491272)
			(xy 101.609652 -236.424216) (xy 101.609298 -236.415199) (xy 101.603049 -236.398281) (xy 101.59746 -236.391196)
			(xy 101.597206 -236.391196) (xy 101.597206 -236.390942) (xy 101.579574 -236.370004) (xy 101.549861 -236.324033)
			(xy 101.527024 -236.274287) (xy 101.511531 -236.221788) (xy 101.503701 -236.167613) (xy 101.503226 -236.140244)
			(xy 101.503712 -236.112993) (xy 101.511468 -236.059045) (xy 101.526823 -236.00675) (xy 101.549465 -235.957173)
			(xy 101.578931 -235.911323) (xy 101.614622 -235.870132) (xy 101.655813 -235.834441) (xy 101.701663 -235.804975)
			(xy 101.75124 -235.782333) (xy 101.803535 -235.766978) (xy 101.857483 -235.759222) (xy 101.911985 -235.759222)
			(xy 101.965933 -235.766978) (xy 102.018228 -235.782333) (xy 102.067805 -235.804975) (xy 102.113655 -235.834441)
			(xy 102.154846 -235.870132) (xy 102.190537 -235.911323) (xy 102.220003 -235.957173) (xy 102.242645 -236.00675)
			(xy 102.258 -236.059045) (xy 102.265756 -236.112993) (xy 102.266242 -236.140244) (xy 102.265757 -236.167614)
			(xy 102.257946 -236.221793) (xy 102.242462 -236.274296) (xy 102.219624 -236.324043) (xy 102.189902 -236.37001)
			(xy 102.172262 -236.390942) (xy 102.172008 -236.391196) (xy 102.166418 -236.39828) (xy 102.160173 -236.415199)
			(xy 102.159816 -236.424216) (xy 102.159816 -236.491272) (xy 102.160183 -236.500288) (xy 102.166423 -236.517205)
			(xy 102.172008 -236.524292) (xy 102.172262 -236.524292) (xy 102.172262 -236.524546) (xy 102.189883 -236.545492)
			(xy 102.219599 -236.591461) (xy 102.242439 -236.641205) (xy 102.257934 -236.693702) (xy 102.265766 -236.747876)
			(xy 102.266242 -236.775244) (xy 103.535226 -236.775244) (xy 103.535712 -236.747874) (xy 103.543524 -236.693696)
			(xy 103.559008 -236.641193) (xy 103.581845 -236.591446) (xy 103.611566 -236.545478) (xy 103.629206 -236.524546)
			(xy 103.62946 -236.524292) (xy 103.635063 -236.517217) (xy 103.641298 -236.500291) (xy 103.641652 -236.491272)
			(xy 103.641652 -236.424216) (xy 103.641298 -236.415199) (xy 103.635049 -236.398281) (xy 103.62946 -236.391196)
			(xy 103.629206 -236.391196) (xy 103.629206 -236.390942) (xy 103.611574 -236.370004) (xy 103.581861 -236.324033)
			(xy 103.559024 -236.274287) (xy 103.543531 -236.221788) (xy 103.535701 -236.167613) (xy 103.535226 -236.140244)
			(xy 103.535712 -236.112993) (xy 103.543468 -236.059045) (xy 103.558823 -236.00675) (xy 103.581465 -235.957173)
			(xy 103.610931 -235.911323) (xy 103.646622 -235.870132) (xy 103.687813 -235.834441) (xy 103.733663 -235.804975)
			(xy 103.78324 -235.782333) (xy 103.835535 -235.766978) (xy 103.889483 -235.759222) (xy 103.943985 -235.759222)
			(xy 103.997933 -235.766978) (xy 104.050228 -235.782333) (xy 104.099805 -235.804975) (xy 104.145655 -235.834441)
			(xy 104.186846 -235.870132) (xy 104.222537 -235.911323) (xy 104.252003 -235.957173) (xy 104.274645 -236.00675)
			(xy 104.29 -236.059045) (xy 104.297756 -236.112993) (xy 104.298242 -236.140244) (xy 104.297757 -236.167614)
			(xy 104.289946 -236.221793) (xy 104.274462 -236.274296) (xy 104.251624 -236.324043) (xy 104.221902 -236.37001)
			(xy 104.204262 -236.390942) (xy 104.204008 -236.391196) (xy 104.198418 -236.39828) (xy 104.192173 -236.415199)
			(xy 104.191816 -236.424216) (xy 104.191816 -236.491272) (xy 104.192183 -236.500288) (xy 104.198423 -236.517205)
			(xy 104.204008 -236.524292) (xy 104.204262 -236.524292) (xy 104.204262 -236.524546) (xy 104.221883 -236.545492)
			(xy 104.251599 -236.591461) (xy 104.274439 -236.641205) (xy 104.289934 -236.693702) (xy 104.297766 -236.747876)
			(xy 104.298242 -236.775244) (xy 105.567226 -236.775244) (xy 105.567712 -236.747874) (xy 105.575524 -236.693696)
			(xy 105.591008 -236.641193) (xy 105.613845 -236.591446) (xy 105.643566 -236.545478) (xy 105.661206 -236.524546)
			(xy 105.66146 -236.524292) (xy 105.667063 -236.517217) (xy 105.673298 -236.500291) (xy 105.673652 -236.491272)
			(xy 105.673652 -236.424216) (xy 105.673298 -236.415199) (xy 105.667049 -236.398281) (xy 105.66146 -236.391196)
			(xy 105.661206 -236.391196) (xy 105.661206 -236.390942) (xy 105.643574 -236.370004) (xy 105.613861 -236.324033)
			(xy 105.591024 -236.274287) (xy 105.575531 -236.221788) (xy 105.567701 -236.167613) (xy 105.567226 -236.140244)
			(xy 105.567712 -236.112993) (xy 105.575468 -236.059045) (xy 105.590823 -236.00675) (xy 105.613465 -235.957173)
			(xy 105.642931 -235.911323) (xy 105.678622 -235.870132) (xy 105.719813 -235.834441) (xy 105.765663 -235.804975)
			(xy 105.81524 -235.782333) (xy 105.867535 -235.766978) (xy 105.921483 -235.759222) (xy 105.975985 -235.759222)
			(xy 106.029933 -235.766978) (xy 106.082228 -235.782333) (xy 106.131805 -235.804975) (xy 106.177655 -235.834441)
			(xy 106.218846 -235.870132) (xy 106.254537 -235.911323) (xy 106.284003 -235.957173) (xy 106.306645 -236.00675)
			(xy 106.322 -236.059045) (xy 106.329756 -236.112993) (xy 106.330242 -236.140244) (xy 106.329757 -236.167614)
			(xy 106.321946 -236.221793) (xy 106.306462 -236.274296) (xy 106.283624 -236.324043) (xy 106.253902 -236.37001)
			(xy 106.236262 -236.390942) (xy 106.236008 -236.391196) (xy 106.230418 -236.39828) (xy 106.224173 -236.415199)
			(xy 106.223816 -236.424216) (xy 106.223816 -236.491272) (xy 106.224183 -236.500288) (xy 106.230423 -236.517205)
			(xy 106.236008 -236.524292) (xy 106.236262 -236.524292) (xy 106.236262 -236.524546) (xy 106.253883 -236.545492)
			(xy 106.283599 -236.591461) (xy 106.306439 -236.641205) (xy 106.321934 -236.693702) (xy 106.329766 -236.747876)
			(xy 106.330242 -236.775244) (xy 107.599226 -236.775244) (xy 107.599712 -236.747874) (xy 107.607524 -236.693696)
			(xy 107.623008 -236.641193) (xy 107.645845 -236.591446) (xy 107.675566 -236.545478) (xy 107.693206 -236.524546)
			(xy 107.69346 -236.524292) (xy 107.699063 -236.517217) (xy 107.705298 -236.500291) (xy 107.705652 -236.491272)
			(xy 107.705652 -236.424216) (xy 107.705298 -236.415199) (xy 107.699049 -236.398281) (xy 107.69346 -236.391196)
			(xy 107.693206 -236.391196) (xy 107.693206 -236.390942) (xy 107.675574 -236.370004) (xy 107.645861 -236.324033)
			(xy 107.623024 -236.274287) (xy 107.607531 -236.221788) (xy 107.599701 -236.167613) (xy 107.599226 -236.140244)
			(xy 107.599712 -236.112993) (xy 107.607468 -236.059045) (xy 107.622823 -236.00675) (xy 107.645465 -235.957173)
			(xy 107.674931 -235.911323) (xy 107.710622 -235.870132) (xy 107.751813 -235.834441) (xy 107.797663 -235.804975)
			(xy 107.84724 -235.782333) (xy 107.899535 -235.766978) (xy 107.953483 -235.759222) (xy 108.007985 -235.759222)
			(xy 108.061933 -235.766978) (xy 108.114228 -235.782333) (xy 108.163805 -235.804975) (xy 108.209655 -235.834441)
			(xy 108.250846 -235.870132) (xy 108.286537 -235.911323) (xy 108.316003 -235.957173) (xy 108.338645 -236.00675)
			(xy 108.354 -236.059045) (xy 108.361756 -236.112993) (xy 108.362242 -236.140244) (xy 108.361757 -236.167614)
			(xy 108.353946 -236.221793) (xy 108.338462 -236.274296) (xy 108.335986 -236.27969) (xy 119.269254 -236.27969)
			(xy 119.273325 -236.224068) (xy 119.285451 -236.169631) (xy 119.305374 -236.11754) (xy 119.33267 -236.068905)
			(xy 119.366756 -236.024762) (xy 119.406905 -235.986053) (xy 119.452263 -235.953602) (xy 119.501863 -235.928101)
			(xy 119.554647 -235.910094) (xy 119.60949 -235.899964) (xy 119.665224 -235.897927) (xy 119.720661 -235.904027)
			(xy 119.774618 -235.918133) (xy 119.825947 -235.939945) (xy 119.873553 -235.968999) (xy 119.916421 -236.004674)
			(xy 119.953638 -236.046211) (xy 119.984411 -236.092724) (xy 120.008083 -236.143221) (xy 120.024151 -236.196628)
			(xy 120.032271 -236.251804) (xy 120.03278 -236.27969) (xy 120.032271 -236.307576) (xy 120.024151 -236.362752)
			(xy 120.008083 -236.416159) (xy 119.984411 -236.466656) (xy 119.953638 -236.513169) (xy 119.916421 -236.554706)
			(xy 119.873553 -236.590381) (xy 119.825947 -236.619435) (xy 119.774618 -236.641247) (xy 119.720661 -236.655353)
			(xy 119.665224 -236.661453) (xy 119.60949 -236.659416) (xy 119.554647 -236.649286) (xy 119.501863 -236.631279)
			(xy 119.452263 -236.605778) (xy 119.406905 -236.573327) (xy 119.366756 -236.534618) (xy 119.33267 -236.490475)
			(xy 119.305374 -236.44184) (xy 119.285451 -236.389749) (xy 119.273325 -236.335312) (xy 119.269254 -236.27969)
			(xy 108.335986 -236.27969) (xy 108.315624 -236.324043) (xy 108.285902 -236.37001) (xy 108.268262 -236.390942)
			(xy 108.268008 -236.391196) (xy 108.262418 -236.39828) (xy 108.256173 -236.415199) (xy 108.255816 -236.424216)
			(xy 108.255816 -236.491272) (xy 108.256183 -236.500288) (xy 108.262423 -236.517205) (xy 108.268008 -236.524292)
			(xy 108.268262 -236.524292) (xy 108.268262 -236.524546) (xy 108.285883 -236.545492) (xy 108.315599 -236.591461)
			(xy 108.338439 -236.641205) (xy 108.353934 -236.693702) (xy 108.361766 -236.747876) (xy 108.362242 -236.775244)
			(xy 108.361756 -236.802495) (xy 108.354 -236.856443) (xy 108.338645 -236.908738) (xy 108.316003 -236.958315)
			(xy 108.286537 -237.004165) (xy 108.250846 -237.045356) (xy 108.209655 -237.081047) (xy 108.163805 -237.110513)
			(xy 108.114228 -237.133155) (xy 108.061933 -237.14851) (xy 108.007985 -237.156266) (xy 107.953483 -237.156266)
			(xy 107.899535 -237.14851) (xy 107.84724 -237.133155) (xy 107.797663 -237.110513) (xy 107.751813 -237.081047)
			(xy 107.710622 -237.045356) (xy 107.674931 -237.004165) (xy 107.645465 -236.958315) (xy 107.622823 -236.908738)
			(xy 107.607468 -236.856443) (xy 107.599712 -236.802495) (xy 107.599226 -236.775244) (xy 106.330242 -236.775244)
			(xy 106.329756 -236.802495) (xy 106.322 -236.856443) (xy 106.306645 -236.908738) (xy 106.284003 -236.958315)
			(xy 106.254537 -237.004165) (xy 106.218846 -237.045356) (xy 106.177655 -237.081047) (xy 106.131805 -237.110513)
			(xy 106.082228 -237.133155) (xy 106.029933 -237.14851) (xy 105.975985 -237.156266) (xy 105.921483 -237.156266)
			(xy 105.867535 -237.14851) (xy 105.81524 -237.133155) (xy 105.765663 -237.110513) (xy 105.719813 -237.081047)
			(xy 105.678622 -237.045356) (xy 105.642931 -237.004165) (xy 105.613465 -236.958315) (xy 105.590823 -236.908738)
			(xy 105.575468 -236.856443) (xy 105.567712 -236.802495) (xy 105.567226 -236.775244) (xy 104.298242 -236.775244)
			(xy 104.297756 -236.802495) (xy 104.29 -236.856443) (xy 104.274645 -236.908738) (xy 104.252003 -236.958315)
			(xy 104.222537 -237.004165) (xy 104.186846 -237.045356) (xy 104.145655 -237.081047) (xy 104.099805 -237.110513)
			(xy 104.050228 -237.133155) (xy 103.997933 -237.14851) (xy 103.943985 -237.156266) (xy 103.889483 -237.156266)
			(xy 103.835535 -237.14851) (xy 103.78324 -237.133155) (xy 103.733663 -237.110513) (xy 103.687813 -237.081047)
			(xy 103.646622 -237.045356) (xy 103.610931 -237.004165) (xy 103.581465 -236.958315) (xy 103.558823 -236.908738)
			(xy 103.543468 -236.856443) (xy 103.535712 -236.802495) (xy 103.535226 -236.775244) (xy 102.266242 -236.775244)
			(xy 102.265756 -236.802495) (xy 102.258 -236.856443) (xy 102.242645 -236.908738) (xy 102.220003 -236.958315)
			(xy 102.190537 -237.004165) (xy 102.154846 -237.045356) (xy 102.113655 -237.081047) (xy 102.067805 -237.110513)
			(xy 102.018228 -237.133155) (xy 101.965933 -237.14851) (xy 101.911985 -237.156266) (xy 101.857483 -237.156266)
			(xy 101.803535 -237.14851) (xy 101.75124 -237.133155) (xy 101.701663 -237.110513) (xy 101.655813 -237.081047)
			(xy 101.614622 -237.045356) (xy 101.578931 -237.004165) (xy 101.549465 -236.958315) (xy 101.526823 -236.908738)
			(xy 101.511468 -236.856443) (xy 101.503712 -236.802495) (xy 101.503226 -236.775244) (xy 93.946681 -236.775244)
			(xy 93.93337 -236.795363) (xy 93.896153 -236.8369) (xy 93.853285 -236.872575) (xy 93.805679 -236.901629)
			(xy 93.75435 -236.923441) (xy 93.700393 -236.937547) (xy 93.644956 -236.943647) (xy 93.589222 -236.94161)
			(xy 93.534379 -236.93148) (xy 93.481595 -236.913473) (xy 93.431995 -236.887972) (xy 93.386637 -236.855521)
			(xy 93.346488 -236.816812) (xy 93.312402 -236.772669) (xy 93.285106 -236.724034) (xy 93.265183 -236.671943)
			(xy 93.253057 -236.617506) (xy 93.248986 -236.561884) (xy 88.969082 -236.561884) (xy 89.0401 -237.3757)
			(xy 92.775276 -237.3757) (xy 92.779347 -237.320078) (xy 92.791473 -237.265641) (xy 92.811396 -237.21355)
			(xy 92.838692 -237.164915) (xy 92.872778 -237.120772) (xy 92.912927 -237.082063) (xy 92.958285 -237.049612)
			(xy 93.007885 -237.024111) (xy 93.060669 -237.006104) (xy 93.115512 -236.995974) (xy 93.171246 -236.993937)
			(xy 93.226683 -237.000037) (xy 93.28064 -237.014143) (xy 93.331969 -237.035955) (xy 93.379575 -237.065009)
			(xy 93.422443 -237.100684) (xy 93.45966 -237.142221) (xy 93.490433 -237.188734) (xy 93.514105 -237.239231)
			(xy 93.530173 -237.292638) (xy 93.538293 -237.347814) (xy 93.538802 -237.3757) (xy 93.538293 -237.403586)
			(xy 93.530173 -237.458762) (xy 93.514105 -237.512169) (xy 93.508304 -237.524544) (xy 94.323914 -237.524544)
			(xy 94.327985 -237.468922) (xy 94.340111 -237.414485) (xy 94.360034 -237.362394) (xy 94.38733 -237.313759)
			(xy 94.421416 -237.269616) (xy 94.461565 -237.230907) (xy 94.506923 -237.198456) (xy 94.556523 -237.172955)
			(xy 94.609307 -237.154948) (xy 94.66415 -237.144818) (xy 94.719884 -237.142781) (xy 94.775321 -237.148881)
			(xy 94.829278 -237.162987) (xy 94.880607 -237.184799) (xy 94.928213 -237.213853) (xy 94.971081 -237.249528)
			(xy 95.008298 -237.291065) (xy 95.039071 -237.337578) (xy 95.062743 -237.388075) (xy 95.078811 -237.441482)
			(xy 95.086931 -237.496658) (xy 95.08744 -237.524544) (xy 95.086931 -237.55243) (xy 95.078811 -237.607606)
			(xy 95.062743 -237.661013) (xy 95.039071 -237.71151) (xy 95.008298 -237.758023) (xy 94.971081 -237.79956)
			(xy 94.928213 -237.835235) (xy 94.880607 -237.864289) (xy 94.829278 -237.886101) (xy 94.775321 -237.900207)
			(xy 94.719884 -237.906307) (xy 94.66415 -237.90427) (xy 94.609307 -237.89414) (xy 94.556523 -237.876133)
			(xy 94.506923 -237.850632) (xy 94.461565 -237.818181) (xy 94.421416 -237.779472) (xy 94.38733 -237.735329)
			(xy 94.360034 -237.686694) (xy 94.340111 -237.634603) (xy 94.327985 -237.580166) (xy 94.323914 -237.524544)
			(xy 93.508304 -237.524544) (xy 93.490433 -237.562666) (xy 93.45966 -237.609179) (xy 93.422443 -237.650716)
			(xy 93.379575 -237.686391) (xy 93.331969 -237.715445) (xy 93.28064 -237.737257) (xy 93.226683 -237.751363)
			(xy 93.171246 -237.757463) (xy 93.115512 -237.755426) (xy 93.060669 -237.745296) (xy 93.007885 -237.727289)
			(xy 92.958285 -237.701788) (xy 92.912927 -237.669337) (xy 92.872778 -237.630628) (xy 92.838692 -237.586485)
			(xy 92.811396 -237.53785) (xy 92.791473 -237.485759) (xy 92.779347 -237.431322) (xy 92.775276 -237.3757)
			(xy 89.0401 -237.3757) (xy 89.110763 -238.185452) (xy 93.334838 -238.185452) (xy 93.338909 -238.12983)
			(xy 93.351035 -238.075393) (xy 93.370958 -238.023302) (xy 93.398254 -237.974667) (xy 93.43234 -237.930524)
			(xy 93.472489 -237.891815) (xy 93.517847 -237.859364) (xy 93.567447 -237.833863) (xy 93.620231 -237.815856)
			(xy 93.675074 -237.805726) (xy 93.730808 -237.803689) (xy 93.786245 -237.809789) (xy 93.840202 -237.823895)
			(xy 93.891531 -237.845707) (xy 93.939137 -237.874761) (xy 93.982005 -237.910436) (xy 94.019222 -237.951973)
			(xy 94.049995 -237.998486) (xy 94.073667 -238.048983) (xy 94.076363 -238.057944) (xy 119.474486 -238.057944)
			(xy 119.478557 -238.002322) (xy 119.490683 -237.947885) (xy 119.510606 -237.895794) (xy 119.537902 -237.847159)
			(xy 119.571988 -237.803016) (xy 119.612137 -237.764307) (xy 119.657495 -237.731856) (xy 119.707095 -237.706355)
			(xy 119.759879 -237.688348) (xy 119.814722 -237.678218) (xy 119.870456 -237.676181) (xy 119.925893 -237.682281)
			(xy 119.97985 -237.696387) (xy 120.031179 -237.718199) (xy 120.078785 -237.747253) (xy 120.121653 -237.782928)
			(xy 120.15887 -237.824465) (xy 120.189643 -237.870978) (xy 120.213315 -237.921475) (xy 120.229383 -237.974882)
			(xy 120.237503 -238.030058) (xy 120.238012 -238.057944) (xy 120.237503 -238.08583) (xy 120.229383 -238.141006)
			(xy 120.213315 -238.194413) (xy 120.189643 -238.24491) (xy 120.15887 -238.291423) (xy 120.121653 -238.33296)
			(xy 120.078785 -238.368635) (xy 120.031179 -238.397689) (xy 119.97985 -238.419501) (xy 119.925893 -238.433607)
			(xy 119.870456 -238.439707) (xy 119.814722 -238.43767) (xy 119.759879 -238.42754) (xy 119.707095 -238.409533)
			(xy 119.657495 -238.384032) (xy 119.612137 -238.351581) (xy 119.571988 -238.312872) (xy 119.537902 -238.268729)
			(xy 119.510606 -238.220094) (xy 119.490683 -238.168003) (xy 119.478557 -238.113566) (xy 119.474486 -238.057944)
			(xy 94.076363 -238.057944) (xy 94.089735 -238.10239) (xy 94.097855 -238.157566) (xy 94.098364 -238.185452)
			(xy 94.097855 -238.213338) (xy 94.089735 -238.268514) (xy 94.073667 -238.321921) (xy 94.049995 -238.372418)
			(xy 94.019222 -238.418931) (xy 93.993325 -238.447834) (xy 124.488446 -238.447834) (xy 124.492517 -238.392212)
			(xy 124.504643 -238.337775) (xy 124.524566 -238.285684) (xy 124.551862 -238.237049) (xy 124.585948 -238.192906)
			(xy 124.626097 -238.154197) (xy 124.671455 -238.121746) (xy 124.721055 -238.096245) (xy 124.773839 -238.078238)
			(xy 124.828682 -238.068108) (xy 124.884416 -238.066071) (xy 124.939853 -238.072171) (xy 124.99381 -238.086277)
			(xy 125.045139 -238.108089) (xy 125.092745 -238.137143) (xy 125.135613 -238.172818) (xy 125.17283 -238.214355)
			(xy 125.203603 -238.260868) (xy 125.227275 -238.311365) (xy 125.243343 -238.364772) (xy 125.251463 -238.419948)
			(xy 125.251972 -238.447834) (xy 125.251463 -238.47572) (xy 125.243343 -238.530896) (xy 125.227275 -238.584303)
			(xy 125.222519 -238.594449) (xy 131.736092 -238.594449) (xy 131.736092 -238.539951) (xy 131.743848 -238.486006)
			(xy 131.759202 -238.433715) (xy 131.781841 -238.38414) (xy 131.811305 -238.338293) (xy 131.846993 -238.297104)
			(xy 131.88818 -238.261414) (xy 131.934026 -238.231949) (xy 131.9836 -238.209307) (xy 132.035891 -238.193951)
			(xy 132.089835 -238.186193) (xy 132.117084 -238.185706) (xy 132.143203 -238.186155) (xy 132.194952 -238.193287)
			(xy 132.245247 -238.207406) (xy 132.293147 -238.228249) (xy 132.337759 -238.255426) (xy 132.37825 -238.288431)
			(xy 132.413865 -238.326647) (xy 132.42925 -238.347758) (xy 132.437721 -238.359102) (xy 132.459727 -238.376902)
			(xy 132.485776 -238.387974) (xy 132.513863 -238.391469) (xy 132.54183 -238.387116) (xy 132.567527 -238.375251)
			(xy 132.588978 -238.356786) (xy 132.597144 -238.345218) (xy 132.612371 -238.323033) (xy 132.648039 -238.282748)
			(xy 132.689016 -238.247876) (xy 132.734487 -238.21911) (xy 132.78355 -238.19702) (xy 132.83523 -238.182045)
			(xy 132.888503 -238.174483) (xy 132.915406 -238.174022) (xy 132.942659 -238.174448) (xy 132.99661 -238.182206)
			(xy 133.048909 -238.197563) (xy 133.098489 -238.220206) (xy 133.144342 -238.249675) (xy 133.185535 -238.285369)
			(xy 133.221229 -238.326563) (xy 133.250697 -238.372416) (xy 133.273339 -238.421997) (xy 133.28361 -238.456978)
			(xy 149.834854 -238.456978) (xy 149.835289 -238.430663) (xy 149.842528 -238.378532) (xy 149.856853 -238.327888)
			(xy 149.877991 -238.279689) (xy 149.905544 -238.234846) (xy 149.938989 -238.194209) (xy 149.958044 -238.176054)
			(xy 149.96546 -238.168544) (xy 149.973978 -238.149255) (xy 149.974554 -238.138716) (xy 149.974554 -238.06404)
			(xy 149.97403 -238.053489) (xy 149.965493 -238.034193) (xy 149.958044 -238.026702) (xy 149.938986 -238.008549)
			(xy 149.905531 -237.967918) (xy 149.877974 -237.923077) (xy 149.856836 -237.874875) (xy 149.842519 -237.824228)
			(xy 149.835293 -237.772094) (xy 149.834854 -237.745778) (xy 149.83534 -237.718527) (xy 149.843096 -237.664579)
			(xy 149.858451 -237.612284) (xy 149.881093 -237.562707) (xy 149.910559 -237.516857) (xy 149.94625 -237.475666)
			(xy 149.987441 -237.439975) (xy 150.033291 -237.410509) (xy 150.082868 -237.387867) (xy 150.135163 -237.372512)
			(xy 150.189111 -237.364756) (xy 150.243613 -237.364756) (xy 150.297561 -237.372512) (xy 150.349856 -237.387867)
			(xy 150.399433 -237.410509) (xy 150.445283 -237.439975) (xy 150.486474 -237.475666) (xy 150.522165 -237.516857)
			(xy 150.551631 -237.562707) (xy 150.574273 -237.612284) (xy 150.589628 -237.664579) (xy 150.597384 -237.718527)
			(xy 150.59787 -237.745778) (xy 150.597398 -237.772092) (xy 150.590165 -237.824221) (xy 150.575848 -237.874864)
			(xy 150.554716 -237.923063) (xy 150.52717 -237.967906) (xy 150.493732 -238.008546) (xy 150.47468 -238.026702)
			(xy 150.467272 -238.034218) (xy 150.458752 -238.053502) (xy 150.45817 -238.06404) (xy 150.45817 -238.138716)
			(xy 150.458686 -238.149267) (xy 150.467231 -238.168562) (xy 150.47468 -238.176054) (xy 150.493751 -238.194194)
			(xy 150.527207 -238.234827) (xy 150.554765 -238.27967) (xy 150.575901 -238.327874) (xy 150.590214 -238.378524)
			(xy 150.597434 -238.430661) (xy 150.59787 -238.456978) (xy 150.597384 -238.484229) (xy 150.589628 -238.538177)
			(xy 150.574273 -238.590472) (xy 150.551631 -238.640049) (xy 150.522165 -238.685899) (xy 150.486474 -238.72709)
			(xy 150.445283 -238.762781) (xy 150.399433 -238.792247) (xy 150.349856 -238.814889) (xy 150.297561 -238.830244)
			(xy 150.243613 -238.838) (xy 150.189111 -238.838) (xy 150.135163 -238.830244) (xy 150.082868 -238.814889)
			(xy 150.033291 -238.792247) (xy 149.987441 -238.762781) (xy 149.94625 -238.72709) (xy 149.910559 -238.685899)
			(xy 149.881093 -238.640049) (xy 149.858451 -238.590472) (xy 149.843096 -238.538177) (xy 149.83534 -238.484229)
			(xy 149.834854 -238.456978) (xy 133.28361 -238.456978) (xy 133.288695 -238.474295) (xy 133.296452 -238.528247)
			(xy 133.296452 -238.582753) (xy 133.288695 -238.636705) (xy 133.273339 -238.689003) (xy 133.250697 -238.738584)
			(xy 133.221229 -238.784437) (xy 133.185535 -238.825631) (xy 133.144342 -238.861325) (xy 133.098489 -238.890794)
			(xy 133.048909 -238.913437) (xy 132.99661 -238.928794) (xy 132.942659 -238.936552) (xy 132.915406 -238.937038)
			(xy 132.889286 -238.93662) (xy 132.837534 -238.929485) (xy 132.787238 -238.915363) (xy 132.739337 -238.894515)
			(xy 132.694725 -238.867333) (xy 132.654235 -238.834322) (xy 132.618624 -238.7961) (xy 132.60324 -238.774986)
			(xy 132.594777 -238.763638) (xy 132.572766 -238.745848) (xy 132.546717 -238.734783) (xy 132.518631 -238.731292)
			(xy 132.490666 -238.735644) (xy 132.464969 -238.747504) (xy 132.443515 -238.765962) (xy 132.435346 -238.777526)
			(xy 132.420108 -238.799703) (xy 132.384443 -238.839991) (xy 132.34347 -238.874865) (xy 132.298001 -238.903634)
			(xy 132.248939 -238.925725) (xy 132.197259 -238.9407) (xy 132.143987 -238.948261) (xy 132.117084 -238.948722)
			(xy 132.089835 -238.948207) (xy 132.035891 -238.940449) (xy 131.9836 -238.925093) (xy 131.934026 -238.902451)
			(xy 131.88818 -238.872986) (xy 131.846993 -238.837296) (xy 131.811305 -238.796107) (xy 131.781841 -238.75026)
			(xy 131.759202 -238.700685) (xy 131.743848 -238.648394) (xy 131.736092 -238.594449) (xy 125.222519 -238.594449)
			(xy 125.203603 -238.6348) (xy 125.17283 -238.681313) (xy 125.135613 -238.72285) (xy 125.092745 -238.758525)
			(xy 125.045139 -238.787579) (xy 124.99381 -238.809391) (xy 124.939853 -238.823497) (xy 124.884416 -238.829597)
			(xy 124.828682 -238.82756) (xy 124.773839 -238.81743) (xy 124.721055 -238.799423) (xy 124.671455 -238.773922)
			(xy 124.626097 -238.741471) (xy 124.585948 -238.702762) (xy 124.551862 -238.658619) (xy 124.524566 -238.609984)
			(xy 124.504643 -238.557893) (xy 124.492517 -238.503456) (xy 124.488446 -238.447834) (xy 93.993325 -238.447834)
			(xy 93.982005 -238.460468) (xy 93.939137 -238.496143) (xy 93.891531 -238.525197) (xy 93.840202 -238.547009)
			(xy 93.786245 -238.561115) (xy 93.730808 -238.567215) (xy 93.675074 -238.565178) (xy 93.620231 -238.555048)
			(xy 93.567447 -238.537041) (xy 93.517847 -238.51154) (xy 93.472489 -238.479089) (xy 93.43234 -238.44038)
			(xy 93.398254 -238.396237) (xy 93.370958 -238.347602) (xy 93.351035 -238.295511) (xy 93.338909 -238.241074)
			(xy 93.334838 -238.185452) (xy 89.110763 -238.185452) (xy 89.187765 -239.067848) (xy 125.173992 -239.067848)
			(xy 125.178063 -239.012226) (xy 125.190189 -238.957789) (xy 125.210112 -238.905698) (xy 125.237408 -238.857063)
			(xy 125.271494 -238.81292) (xy 125.311643 -238.774211) (xy 125.357001 -238.74176) (xy 125.406601 -238.716259)
			(xy 125.459385 -238.698252) (xy 125.514228 -238.688122) (xy 125.569962 -238.686085) (xy 125.625399 -238.692185)
			(xy 125.679356 -238.706291) (xy 125.730685 -238.728103) (xy 125.778291 -238.757157) (xy 125.821159 -238.792832)
			(xy 125.858376 -238.834369) (xy 125.889149 -238.880882) (xy 125.912821 -238.931379) (xy 125.928889 -238.984786)
			(xy 125.937009 -239.039962) (xy 125.937518 -239.067848) (xy 125.937078 -239.091978) (xy 145.186144 -239.091978)
			(xy 145.190215 -239.036356) (xy 145.202341 -238.981919) (xy 145.222264 -238.929828) (xy 145.24956 -238.881193)
			(xy 145.283646 -238.83705) (xy 145.323795 -238.798341) (xy 145.369153 -238.76589) (xy 145.418753 -238.740389)
			(xy 145.471537 -238.722382) (xy 145.52638 -238.712252) (xy 145.582114 -238.710215) (xy 145.637551 -238.716315)
			(xy 145.691508 -238.730421) (xy 145.742837 -238.752233) (xy 145.790443 -238.781287) (xy 145.833311 -238.816962)
			(xy 145.870528 -238.858499) (xy 145.901301 -238.905012) (xy 145.924973 -238.955509) (xy 145.941041 -239.008916)
			(xy 145.949161 -239.064092) (xy 145.94967 -239.091978) (xy 148.386544 -239.091978) (xy 148.390615 -239.036356)
			(xy 148.402741 -238.981919) (xy 148.422664 -238.929828) (xy 148.44996 -238.881193) (xy 148.484046 -238.83705)
			(xy 148.524195 -238.798341) (xy 148.569553 -238.76589) (xy 148.619153 -238.740389) (xy 148.671937 -238.722382)
			(xy 148.72678 -238.712252) (xy 148.782514 -238.710215) (xy 148.837951 -238.716315) (xy 148.891908 -238.730421)
			(xy 148.943237 -238.752233) (xy 148.990843 -238.781287) (xy 149.033711 -238.816962) (xy 149.070928 -238.858499)
			(xy 149.101701 -238.905012) (xy 149.125373 -238.955509) (xy 149.141441 -239.008916) (xy 149.149561 -239.064092)
			(xy 149.15007 -239.091978) (xy 149.149606 -239.117378) (xy 149.275544 -239.117378) (xy 149.279615 -239.061756)
			(xy 149.291741 -239.007319) (xy 149.311664 -238.955228) (xy 149.33896 -238.906593) (xy 149.373046 -238.86245)
			(xy 149.413195 -238.823741) (xy 149.458553 -238.79129) (xy 149.508153 -238.765789) (xy 149.560937 -238.747782)
			(xy 149.61578 -238.737652) (xy 149.671514 -238.735615) (xy 149.726951 -238.741715) (xy 149.780908 -238.755821)
			(xy 149.832237 -238.777633) (xy 149.879843 -238.806687) (xy 149.922711 -238.842362) (xy 149.959928 -238.883899)
			(xy 149.990701 -238.930412) (xy 150.014373 -238.980909) (xy 150.030441 -239.034316) (xy 150.037027 -239.07907)
			(xy 153.398934 -239.07907) (xy 153.398934 -239.01913) (xy 153.406758 -238.959703) (xy 153.422271 -238.901805)
			(xy 153.445208 -238.846427) (xy 153.475178 -238.794517) (xy 153.511666 -238.746963) (xy 153.554049 -238.704578)
			(xy 153.601602 -238.668088) (xy 153.653511 -238.638116) (xy 153.708888 -238.615177) (xy 153.766785 -238.599661)
			(xy 153.826212 -238.591835) (xy 153.856182 -238.591344) (xy 154.719782 -238.591344) (xy 154.749749 -238.591908)
			(xy 154.809169 -238.599729) (xy 154.867061 -238.615239) (xy 154.922433 -238.638172) (xy 154.974337 -238.668138)
			(xy 155.021886 -238.704622) (xy 155.064267 -238.747) (xy 155.100752 -238.794548) (xy 155.13072 -238.846451)
			(xy 155.153656 -238.901822) (xy 155.169168 -238.959713) (xy 155.176991 -239.019133) (xy 155.176991 -239.079067)
			(xy 155.169168 -239.138487) (xy 155.153656 -239.196378) (xy 155.13072 -239.251749) (xy 155.100752 -239.303652)
			(xy 155.064267 -239.3512) (xy 155.021886 -239.393578) (xy 154.974337 -239.430062) (xy 154.922433 -239.460028)
			(xy 154.867061 -239.482961) (xy 154.809169 -239.498471) (xy 154.749749 -239.506292) (xy 154.719782 -239.50676)
			(xy 153.856182 -239.50676) (xy 153.826212 -239.506365) (xy 153.766785 -239.498539) (xy 153.708888 -239.483023)
			(xy 153.653511 -239.460084) (xy 153.601602 -239.430112) (xy 153.554049 -239.393622) (xy 153.511666 -239.351237)
			(xy 153.475178 -239.303683) (xy 153.445208 -239.251773) (xy 153.422271 -239.196395) (xy 153.406758 -239.138497)
			(xy 153.398934 -239.07907) (xy 150.037027 -239.07907) (xy 150.038561 -239.089492) (xy 150.03907 -239.117378)
			(xy 150.038561 -239.145264) (xy 150.030441 -239.20044) (xy 150.014373 -239.253847) (xy 149.990701 -239.304344)
			(xy 149.959928 -239.350857) (xy 149.922711 -239.392394) (xy 149.879843 -239.428069) (xy 149.832237 -239.457123)
			(xy 149.780908 -239.478935) (xy 149.726951 -239.493041) (xy 149.671514 -239.499141) (xy 149.61578 -239.497104)
			(xy 149.560937 -239.486974) (xy 149.508153 -239.468967) (xy 149.458553 -239.443466) (xy 149.413195 -239.411015)
			(xy 149.373046 -239.372306) (xy 149.33896 -239.328163) (xy 149.311664 -239.279528) (xy 149.291741 -239.227437)
			(xy 149.279615 -239.173) (xy 149.275544 -239.117378) (xy 149.149606 -239.117378) (xy 149.149561 -239.119864)
			(xy 149.141441 -239.17504) (xy 149.125373 -239.228447) (xy 149.101701 -239.278944) (xy 149.070928 -239.325457)
			(xy 149.033711 -239.366994) (xy 148.990843 -239.402669) (xy 148.943237 -239.431723) (xy 148.891908 -239.453535)
			(xy 148.837951 -239.467641) (xy 148.782514 -239.473741) (xy 148.72678 -239.471704) (xy 148.671937 -239.461574)
			(xy 148.619153 -239.443567) (xy 148.569553 -239.418066) (xy 148.524195 -239.385615) (xy 148.484046 -239.346906)
			(xy 148.44996 -239.302763) (xy 148.422664 -239.254128) (xy 148.402741 -239.202037) (xy 148.390615 -239.1476)
			(xy 148.386544 -239.091978) (xy 145.94967 -239.091978) (xy 145.949161 -239.119864) (xy 145.941041 -239.17504)
			(xy 145.924973 -239.228447) (xy 145.901301 -239.278944) (xy 145.870528 -239.325457) (xy 145.833311 -239.366994)
			(xy 145.790443 -239.402669) (xy 145.742837 -239.431723) (xy 145.691508 -239.453535) (xy 145.637551 -239.467641)
			(xy 145.582114 -239.473741) (xy 145.52638 -239.471704) (xy 145.471537 -239.461574) (xy 145.418753 -239.443567)
			(xy 145.369153 -239.418066) (xy 145.323795 -239.385615) (xy 145.283646 -239.346906) (xy 145.24956 -239.302763)
			(xy 145.222264 -239.254128) (xy 145.202341 -239.202037) (xy 145.190215 -239.1476) (xy 145.186144 -239.091978)
			(xy 125.937078 -239.091978) (xy 125.937009 -239.095734) (xy 125.928889 -239.15091) (xy 125.912821 -239.204317)
			(xy 125.889149 -239.254814) (xy 125.858376 -239.301327) (xy 125.821159 -239.342864) (xy 125.778291 -239.378539)
			(xy 125.730685 -239.407593) (xy 125.679356 -239.429405) (xy 125.625399 -239.443511) (xy 125.569962 -239.449611)
			(xy 125.514228 -239.447574) (xy 125.459385 -239.437444) (xy 125.406601 -239.419437) (xy 125.357001 -239.393936)
			(xy 125.311643 -239.361485) (xy 125.271494 -239.322776) (xy 125.237408 -239.278633) (xy 125.210112 -239.229998)
			(xy 125.190189 -239.177907) (xy 125.178063 -239.12347) (xy 125.173992 -239.067848) (xy 89.187765 -239.067848)
			(xy 89.245395 -239.728248) (xy 93.652338 -239.728248) (xy 93.656409 -239.672626) (xy 93.668535 -239.618189)
			(xy 93.688458 -239.566098) (xy 93.715754 -239.517463) (xy 93.74984 -239.47332) (xy 93.789989 -239.434611)
			(xy 93.835347 -239.40216) (xy 93.884947 -239.376659) (xy 93.937731 -239.358652) (xy 93.992574 -239.348522)
			(xy 94.048308 -239.346485) (xy 94.103745 -239.352585) (xy 94.157702 -239.366691) (xy 94.209031 -239.388503)
			(xy 94.256637 -239.417557) (xy 94.299505 -239.453232) (xy 94.336722 -239.494769) (xy 94.367495 -239.541282)
			(xy 94.391167 -239.591779) (xy 94.407235 -239.645186) (xy 94.415355 -239.700362) (xy 94.415864 -239.728248)
			(xy 94.415355 -239.756134) (xy 94.407235 -239.81131) (xy 94.391167 -239.864717) (xy 94.367495 -239.915214)
			(xy 94.336722 -239.961727) (xy 94.299505 -240.003264) (xy 94.256637 -240.038939) (xy 94.209031 -240.067993)
			(xy 94.157702 -240.089805) (xy 94.103745 -240.103911) (xy 94.048308 -240.110011) (xy 93.992574 -240.107974)
			(xy 93.937731 -240.097844) (xy 93.884947 -240.079837) (xy 93.835347 -240.054336) (xy 93.789989 -240.021885)
			(xy 93.74984 -239.983176) (xy 93.715754 -239.939033) (xy 93.688458 -239.890398) (xy 93.668535 -239.838307)
			(xy 93.656409 -239.78387) (xy 93.652338 -239.728248) (xy 89.245395 -239.728248) (xy 89.313021 -240.503202)
			(xy 92.046804 -240.503202) (xy 92.050875 -240.44758) (xy 92.063001 -240.393143) (xy 92.082924 -240.341052)
			(xy 92.11022 -240.292417) (xy 92.144306 -240.248274) (xy 92.184455 -240.209565) (xy 92.229813 -240.177114)
			(xy 92.279413 -240.151613) (xy 92.332197 -240.133606) (xy 92.38704 -240.123476) (xy 92.442774 -240.121439)
			(xy 92.498211 -240.127539) (xy 92.552168 -240.141645) (xy 92.603497 -240.163457) (xy 92.651103 -240.192511)
			(xy 92.693971 -240.228186) (xy 92.731188 -240.269723) (xy 92.761961 -240.316236) (xy 92.785633 -240.366733)
			(xy 92.801701 -240.42014) (xy 92.809821 -240.475316) (xy 92.81033 -240.503202) (xy 92.809821 -240.531088)
			(xy 92.801701 -240.586264) (xy 92.785633 -240.639671) (xy 92.761961 -240.690168) (xy 92.731188 -240.736681)
			(xy 92.724408 -240.744248) (xy 93.652338 -240.744248) (xy 93.656409 -240.688626) (xy 93.668535 -240.634189)
			(xy 93.688458 -240.582098) (xy 93.715754 -240.533463) (xy 93.74984 -240.48932) (xy 93.789989 -240.450611)
			(xy 93.835347 -240.41816) (xy 93.884947 -240.392659) (xy 93.937731 -240.374652) (xy 93.992574 -240.364522)
			(xy 94.048308 -240.362485) (xy 94.103745 -240.368585) (xy 94.157702 -240.382691) (xy 94.209031 -240.404503)
			(xy 94.256637 -240.433557) (xy 94.299505 -240.469232) (xy 94.336722 -240.510769) (xy 94.367495 -240.557282)
			(xy 94.391167 -240.607779) (xy 94.407235 -240.661186) (xy 94.415355 -240.716362) (xy 94.415864 -240.744248)
			(xy 94.415355 -240.772134) (xy 94.412917 -240.788698) (xy 97.371406 -240.788698) (xy 97.375477 -240.733076)
			(xy 97.387603 -240.678639) (xy 97.407526 -240.626548) (xy 97.434822 -240.577913) (xy 97.468908 -240.53377)
			(xy 97.509057 -240.495061) (xy 97.554415 -240.46261) (xy 97.604015 -240.437109) (xy 97.656799 -240.419102)
			(xy 97.711642 -240.408972) (xy 97.767376 -240.406935) (xy 97.822813 -240.413035) (xy 97.87677 -240.427141)
			(xy 97.928099 -240.448953) (xy 97.975705 -240.478007) (xy 98.018573 -240.513682) (xy 98.05579 -240.555219)
			(xy 98.086563 -240.601732) (xy 98.110235 -240.652229) (xy 98.126303 -240.705636) (xy 98.134423 -240.760812)
			(xy 98.134932 -240.788698) (xy 98.134423 -240.816584) (xy 98.126303 -240.87176) (xy 98.110235 -240.925167)
			(xy 98.108839 -240.928144) (xy 99.417122 -240.928144) (xy 99.421193 -240.872522) (xy 99.433319 -240.818085)
			(xy 99.453242 -240.765994) (xy 99.480538 -240.717359) (xy 99.514624 -240.673216) (xy 99.554773 -240.634507)
			(xy 99.600131 -240.602056) (xy 99.649731 -240.576555) (xy 99.702515 -240.558548) (xy 99.757358 -240.548418)
			(xy 99.813092 -240.546381) (xy 99.868529 -240.552481) (xy 99.922486 -240.566587) (xy 99.973815 -240.588399)
			(xy 100.021421 -240.617453) (xy 100.064289 -240.653128) (xy 100.101506 -240.694665) (xy 100.132279 -240.741178)
			(xy 100.155951 -240.791675) (xy 100.172019 -240.845082) (xy 100.180139 -240.900258) (xy 100.180648 -240.928144)
			(xy 100.180139 -240.95603) (xy 100.172019 -241.011206) (xy 100.155951 -241.064613) (xy 100.132279 -241.11511)
			(xy 100.101506 -241.161623) (xy 100.064289 -241.20316) (xy 100.021421 -241.238835) (xy 99.973815 -241.267889)
			(xy 99.922486 -241.289701) (xy 99.868529 -241.303807) (xy 99.813092 -241.309907) (xy 99.757358 -241.30787)
			(xy 99.702515 -241.29774) (xy 99.649731 -241.279733) (xy 99.600131 -241.254232) (xy 99.554773 -241.221781)
			(xy 99.514624 -241.183072) (xy 99.480538 -241.138929) (xy 99.453242 -241.090294) (xy 99.433319 -241.038203)
			(xy 99.421193 -240.983766) (xy 99.417122 -240.928144) (xy 98.108839 -240.928144) (xy 98.086563 -240.975664)
			(xy 98.05579 -241.022177) (xy 98.018573 -241.063714) (xy 97.975705 -241.099389) (xy 97.928099 -241.128443)
			(xy 97.87677 -241.150255) (xy 97.822813 -241.164361) (xy 97.767376 -241.170461) (xy 97.711642 -241.168424)
			(xy 97.656799 -241.158294) (xy 97.604015 -241.140287) (xy 97.554415 -241.114786) (xy 97.509057 -241.082335)
			(xy 97.468908 -241.043626) (xy 97.434822 -240.999483) (xy 97.407526 -240.950848) (xy 97.387603 -240.898757)
			(xy 97.375477 -240.84432) (xy 97.371406 -240.788698) (xy 94.412917 -240.788698) (xy 94.407235 -240.82731)
			(xy 94.391167 -240.880717) (xy 94.367495 -240.931214) (xy 94.336722 -240.977727) (xy 94.299505 -241.019264)
			(xy 94.256637 -241.054939) (xy 94.209031 -241.083993) (xy 94.157702 -241.105805) (xy 94.103745 -241.119911)
			(xy 94.048308 -241.126011) (xy 93.992574 -241.123974) (xy 93.937731 -241.113844) (xy 93.884947 -241.095837)
			(xy 93.835347 -241.070336) (xy 93.789989 -241.037885) (xy 93.74984 -240.999176) (xy 93.715754 -240.955033)
			(xy 93.688458 -240.906398) (xy 93.668535 -240.854307) (xy 93.656409 -240.79987) (xy 93.652338 -240.744248)
			(xy 92.724408 -240.744248) (xy 92.693971 -240.778218) (xy 92.651103 -240.813893) (xy 92.603497 -240.842947)
			(xy 92.552168 -240.864759) (xy 92.498211 -240.878865) (xy 92.442774 -240.884965) (xy 92.38704 -240.882928)
			(xy 92.332197 -240.872798) (xy 92.279413 -240.854791) (xy 92.229813 -240.82929) (xy 92.184455 -240.796839)
			(xy 92.144306 -240.75813) (xy 92.11022 -240.713987) (xy 92.082924 -240.665352) (xy 92.063001 -240.613261)
			(xy 92.050875 -240.558824) (xy 92.046804 -240.503202) (xy 89.313021 -240.503202) (xy 89.377544 -241.242596)
			(xy 96.119694 -241.242596) (xy 96.123765 -241.186974) (xy 96.135891 -241.132537) (xy 96.155814 -241.080446)
			(xy 96.18311 -241.031811) (xy 96.217196 -240.987668) (xy 96.257345 -240.948959) (xy 96.302703 -240.916508)
			(xy 96.352303 -240.891007) (xy 96.405087 -240.873) (xy 96.45993 -240.86287) (xy 96.515664 -240.860833)
			(xy 96.571101 -240.866933) (xy 96.625058 -240.881039) (xy 96.676387 -240.902851) (xy 96.723993 -240.931905)
			(xy 96.766861 -240.96758) (xy 96.804078 -241.009117) (xy 96.834851 -241.05563) (xy 96.858523 -241.106127)
			(xy 96.874591 -241.159534) (xy 96.882711 -241.21471) (xy 96.88322 -241.242596) (xy 96.882711 -241.270482)
			(xy 96.874591 -241.325658) (xy 96.858523 -241.379065) (xy 96.834851 -241.429562) (xy 96.804078 -241.476075)
			(xy 96.766861 -241.517612) (xy 96.723993 -241.553287) (xy 96.676387 -241.582341) (xy 96.625058 -241.604153)
			(xy 96.571101 -241.618259) (xy 96.515664 -241.624359) (xy 96.45993 -241.622322) (xy 96.405087 -241.612192)
			(xy 96.352303 -241.594185) (xy 96.302703 -241.568684) (xy 96.257345 -241.536233) (xy 96.217196 -241.497524)
			(xy 96.18311 -241.453381) (xy 96.155814 -241.404746) (xy 96.135891 -241.352655) (xy 96.123765 -241.298218)
			(xy 96.119694 -241.242596) (xy 89.377544 -241.242596) (xy 89.464543 -242.239546) (xy 93.623636 -242.239546)
			(xy 93.627707 -242.183924) (xy 93.639833 -242.129487) (xy 93.659756 -242.077396) (xy 93.687052 -242.028761)
			(xy 93.721138 -241.984618) (xy 93.761287 -241.945909) (xy 93.806645 -241.913458) (xy 93.856245 -241.887957)
			(xy 93.909029 -241.86995) (xy 93.963872 -241.85982) (xy 94.019606 -241.857783) (xy 94.075043 -241.863883)
			(xy 94.129 -241.877989) (xy 94.180329 -241.899801) (xy 94.227935 -241.928855) (xy 94.270803 -241.96453)
			(xy 94.30802 -242.006067) (xy 94.338793 -242.05258) (xy 94.362465 -242.103077) (xy 94.378533 -242.156484)
			(xy 94.386653 -242.21166) (xy 94.387148 -242.238784) (xy 95.660718 -242.238784) (xy 95.661204 -242.211533)
			(xy 95.66896 -242.157585) (xy 95.684315 -242.10529) (xy 95.706957 -242.055713) (xy 95.736423 -242.009863)
			(xy 95.772114 -241.968672) (xy 95.813305 -241.932981) (xy 95.859155 -241.903515) (xy 95.908732 -241.880873)
			(xy 95.961027 -241.865518) (xy 96.014975 -241.857762) (xy 96.069477 -241.857762) (xy 96.123425 -241.865518)
			(xy 96.17572 -241.880873) (xy 96.225297 -241.903515) (xy 96.271147 -241.932981) (xy 96.312338 -241.968672)
			(xy 96.316912 -241.973951) (xy 120.012962 -241.973951) (xy 120.012962 -241.919449) (xy 120.020718 -241.865502)
			(xy 120.036072 -241.813207) (xy 120.058712 -241.76363) (xy 120.088176 -241.71778) (xy 120.123866 -241.676588)
			(xy 120.165054 -241.640895) (xy 120.210902 -241.611427) (xy 120.260477 -241.588783) (xy 120.312771 -241.573425)
			(xy 120.366717 -241.565664) (xy 120.393968 -241.565176) (xy 120.422514 -241.56573) (xy 120.478967 -241.574244)
			(xy 120.533522 -241.59107) (xy 120.584963 -241.615835) (xy 120.608852 -241.63147) (xy 120.616605 -241.636267)
			(xy 120.634307 -241.640571) (xy 120.643396 -241.639852) (xy 120.718834 -241.630962) (xy 120.735344 -241.622326)
			(xy 120.74144 -241.615468) (xy 120.759642 -241.596066) (xy 120.800453 -241.561942) (xy 120.845605 -241.533814)
			(xy 120.894224 -241.512224) (xy 120.94537 -241.497593) (xy 120.998051 -241.490202) (xy 121.02465 -241.489738)
			(xy 121.050587 -241.490183) (xy 121.101982 -241.497206) (xy 121.151952 -241.511129) (xy 121.199574 -241.531696)
			(xy 121.24397 -241.558526) (xy 121.28432 -241.591126) (xy 121.31988 -241.628893) (xy 121.335292 -241.649758)
			(xy 121.342658 -241.659918) (xy 121.36501 -241.671348) (xy 121.46153 -241.669316) (xy 121.473906 -241.668441)
			(xy 121.495605 -241.656468) (xy 121.502932 -241.646456) (xy 121.518144 -241.624182) (xy 121.553818 -241.583727)
			(xy 121.594835 -241.548701) (xy 121.640378 -241.519803) (xy 121.689538 -241.497609) (xy 121.741334 -241.482563)
			(xy 121.794733 -241.474964) (xy 121.821702 -241.474498) (xy 121.848954 -241.474972) (xy 121.902902 -241.482729)
			(xy 121.955197 -241.498084) (xy 122.004775 -241.520726) (xy 122.050626 -241.550193) (xy 122.091817 -241.585885)
			(xy 122.127508 -241.627076) (xy 122.156975 -241.672927) (xy 122.179616 -241.722505) (xy 122.194972 -241.7748)
			(xy 122.202728 -241.828748) (xy 122.202728 -241.875564) (xy 132.041644 -241.875564) (xy 132.045715 -241.819942)
			(xy 132.057841 -241.765505) (xy 132.077764 -241.713414) (xy 132.10506 -241.664779) (xy 132.139146 -241.620636)
			(xy 132.179295 -241.581927) (xy 132.224653 -241.549476) (xy 132.274253 -241.523975) (xy 132.327037 -241.505968)
			(xy 132.38188 -241.495838) (xy 132.437614 -241.493801) (xy 132.493051 -241.499901) (xy 132.547008 -241.514007)
			(xy 132.598337 -241.535819) (xy 132.645943 -241.564873) (xy 132.688811 -241.600548) (xy 132.726028 -241.642085)
			(xy 132.756801 -241.688598) (xy 132.780473 -241.739095) (xy 132.796541 -241.792502) (xy 132.804661 -241.847678)
			(xy 132.804813 -241.856006) (xy 133.699248 -241.856006) (xy 133.703319 -241.800384) (xy 133.715445 -241.745947)
			(xy 133.735368 -241.693856) (xy 133.762664 -241.645221) (xy 133.79675 -241.601078) (xy 133.836899 -241.562369)
			(xy 133.882257 -241.529918) (xy 133.931857 -241.504417) (xy 133.984641 -241.48641) (xy 134.039484 -241.47628)
			(xy 134.095218 -241.474243) (xy 134.150655 -241.480343) (xy 134.204612 -241.494449) (xy 134.255941 -241.516261)
			(xy 134.303547 -241.545315) (xy 134.346415 -241.58099) (xy 134.383632 -241.622527) (xy 134.414405 -241.66904)
			(xy 134.438077 -241.719537) (xy 134.454145 -241.772944) (xy 134.456103 -241.786251) (xy 142.647156 -241.786251)
			(xy 142.647156 -241.731749) (xy 142.654912 -241.677801) (xy 142.670266 -241.625507) (xy 142.692905 -241.575929)
			(xy 142.72237 -241.530078) (xy 142.758059 -241.488886) (xy 142.799247 -241.453193) (xy 142.845096 -241.423724)
			(xy 142.894671 -241.401079) (xy 142.946964 -241.38572) (xy 143.000911 -241.377958) (xy 143.028162 -241.37747)
			(xy 143.055409 -241.377884) (xy 143.109346 -241.385651) (xy 143.161627 -241.401017) (xy 143.211189 -241.42367)
			(xy 143.257021 -241.453148) (xy 143.298189 -241.488851) (xy 143.333855 -241.530051) (xy 143.348964 -241.55273)
			(xy 143.35385 -241.559725) (xy 143.36724 -241.570279) (xy 143.383364 -241.575817) (xy 143.39189 -241.576098)
			(xy 143.477234 -241.576098) (xy 143.485755 -241.575787) (xy 143.501866 -241.570235) (xy 143.515276 -241.559719)
			(xy 143.52016 -241.55273) (xy 143.535296 -241.530073) (xy 143.57096 -241.488878) (xy 143.612125 -241.453181)
			(xy 143.657953 -241.423709) (xy 143.70751 -241.401061) (xy 143.759787 -241.385699) (xy 143.813718 -241.377936)
			(xy 143.840962 -241.37747) (xy 143.866939 -241.377857) (xy 143.918413 -241.384909) (xy 143.968452 -241.398887)
			(xy 144.016129 -241.419531) (xy 144.06056 -241.44646) (xy 144.100921 -241.479174) (xy 144.136465 -241.517068)
			(xy 144.151858 -241.537998) (xy 144.159499 -241.547481) (xy 144.181104 -241.558632) (xy 144.19326 -241.559334)
			(xy 144.276064 -241.559334) (xy 144.288229 -241.558659) (xy 144.309851 -241.547509) (xy 144.317466 -241.537998)
			(xy 144.332855 -241.517069) (xy 144.368412 -241.479195) (xy 144.40878 -241.446497) (xy 144.453212 -241.41958)
			(xy 144.500886 -241.398943) (xy 144.55092 -241.384967) (xy 144.602387 -241.377911) (xy 144.628362 -241.37747)
			(xy 144.655615 -241.377975) (xy 144.709567 -241.385727) (xy 144.761866 -241.401079) (xy 144.811448 -241.423718)
			(xy 144.857304 -241.453183) (xy 144.898499 -241.488875) (xy 144.934194 -241.530066) (xy 144.963664 -241.575918)
			(xy 144.986308 -241.625498) (xy 145.001665 -241.677796) (xy 145.009423 -241.731747) (xy 145.009423 -241.786253)
			(xy 145.001665 -241.840204) (xy 144.986308 -241.892502) (xy 144.963664 -241.942082) (xy 144.934194 -241.987934)
			(xy 144.898499 -242.029125) (xy 144.857304 -242.064817) (xy 144.811448 -242.094282) (xy 144.761866 -242.116921)
			(xy 144.709567 -242.132273) (xy 144.655615 -242.140025) (xy 144.628362 -242.140486) (xy 144.602386 -242.140057)
			(xy 144.550915 -242.13301) (xy 144.500878 -242.119038) (xy 144.453202 -242.098399) (xy 144.408771 -242.071477)
			(xy 144.368408 -242.03877) (xy 144.332861 -242.000885) (xy 144.317466 -241.979958) (xy 144.309822 -241.970478)
			(xy 144.288219 -241.959327) (xy 144.276064 -241.958622) (xy 144.19326 -241.958622) (xy 144.1811 -241.959327)
			(xy 144.159478 -241.970458) (xy 144.151858 -241.979958) (xy 144.136441 -242.000866) (xy 144.100891 -242.038743)
			(xy 144.060528 -242.071444) (xy 144.016101 -242.098364) (xy 143.968431 -242.119004) (xy 143.9184 -242.132984)
			(xy 143.866935 -242.140043) (xy 143.840962 -242.140486) (xy 143.813717 -242.140028) (xy 143.759783 -242.132266)
			(xy 143.707504 -242.116905) (xy 143.657943 -242.094259) (xy 143.612111 -242.064788) (xy 143.570941 -242.029093)
			(xy 143.535271 -241.987901) (xy 143.52016 -241.965226) (xy 143.515331 -241.958187) (xy 143.501914 -241.947645)
			(xy 143.485768 -241.942126) (xy 143.477234 -241.941858) (xy 143.39189 -241.941858) (xy 143.383372 -241.942204)
			(xy 143.367265 -241.947744) (xy 143.353852 -241.958244) (xy 143.348964 -241.965226) (xy 143.333863 -241.987908)
			(xy 143.298195 -242.029104) (xy 143.257025 -242.064801) (xy 143.211191 -242.094272) (xy 143.161627 -242.116916)
			(xy 143.109344 -242.132271) (xy 143.055408 -242.140025) (xy 143.028162 -242.140486) (xy 143.000911 -242.140042)
			(xy 142.946964 -242.13228) (xy 142.894671 -242.116921) (xy 142.845096 -242.094276) (xy 142.799247 -242.064807)
			(xy 142.758059 -242.029114) (xy 142.72237 -241.987922) (xy 142.692905 -241.942071) (xy 142.670266 -241.892493)
			(xy 142.654912 -241.840199) (xy 142.647156 -241.786251) (xy 134.456103 -241.786251) (xy 134.462265 -241.82812)
			(xy 134.462774 -241.856006) (xy 134.462265 -241.883892) (xy 134.454145 -241.939068) (xy 134.438077 -241.992475)
			(xy 134.414405 -242.042972) (xy 134.383632 -242.089485) (xy 134.346415 -242.131022) (xy 134.303547 -242.166697)
			(xy 134.255941 -242.195751) (xy 134.204612 -242.217563) (xy 134.150655 -242.231669) (xy 134.095218 -242.237769)
			(xy 134.039484 -242.235732) (xy 133.984641 -242.225602) (xy 133.931857 -242.207595) (xy 133.882257 -242.182094)
			(xy 133.836899 -242.149643) (xy 133.79675 -242.110934) (xy 133.762664 -242.066791) (xy 133.735368 -242.018156)
			(xy 133.715445 -241.966065) (xy 133.703319 -241.911628) (xy 133.699248 -241.856006) (xy 132.804813 -241.856006)
			(xy 132.80517 -241.875564) (xy 132.804661 -241.90345) (xy 132.796541 -241.958626) (xy 132.780473 -242.012033)
			(xy 132.756801 -242.06253) (xy 132.726028 -242.109043) (xy 132.688811 -242.15058) (xy 132.645943 -242.186255)
			(xy 132.598337 -242.215309) (xy 132.547008 -242.237121) (xy 132.493051 -242.251227) (xy 132.437614 -242.257327)
			(xy 132.38188 -242.25529) (xy 132.327037 -242.24516) (xy 132.274253 -242.227153) (xy 132.224653 -242.201652)
			(xy 132.179295 -242.169201) (xy 132.139146 -242.130492) (xy 132.10506 -242.086349) (xy 132.077764 -242.037714)
			(xy 132.057841 -241.985623) (xy 132.045715 -241.931186) (xy 132.041644 -241.875564) (xy 122.202728 -241.875564)
			(xy 122.202728 -241.883252) (xy 122.194972 -241.9372) (xy 122.179616 -241.989495) (xy 122.156975 -242.039073)
			(xy 122.127508 -242.084924) (xy 122.091817 -242.126115) (xy 122.050626 -242.161807) (xy 122.004775 -242.191274)
			(xy 121.955197 -242.213916) (xy 121.902902 -242.229271) (xy 121.848954 -242.237028) (xy 121.821702 -242.237514)
			(xy 121.795765 -242.237083) (xy 121.74437 -242.230055) (xy 121.6944 -242.216127) (xy 121.646779 -242.195558)
			(xy 121.602384 -242.168726) (xy 121.562034 -242.136126) (xy 121.526473 -242.098359) (xy 121.51106 -242.077494)
			(xy 121.503694 -242.067334) (xy 121.481342 -242.055904) (xy 121.384822 -242.057936) (xy 121.372445 -242.058801)
			(xy 121.350748 -242.070784) (xy 121.34342 -242.080796) (xy 121.328223 -242.103081) (xy 121.292549 -242.143539)
			(xy 121.25153 -242.178566) (xy 121.205984 -242.207463) (xy 121.156821 -242.229655) (xy 121.105022 -242.244697)
			(xy 121.05162 -242.252291) (xy 121.02465 -242.252754) (xy 120.996104 -242.252203) (xy 120.93965 -242.243691)
			(xy 120.885095 -242.226863) (xy 120.833654 -242.202097) (xy 120.809766 -242.18646) (xy 120.802007 -242.181673)
			(xy 120.784309 -242.177362) (xy 120.775222 -242.178078) (xy 120.699784 -242.186968) (xy 120.683274 -242.195604)
			(xy 120.677178 -242.202462) (xy 120.658974 -242.221861) (xy 120.618163 -242.255984) (xy 120.573011 -242.284113)
			(xy 120.524392 -242.305702) (xy 120.473247 -242.320335) (xy 120.420566 -242.327727) (xy 120.393968 -242.328192)
			(xy 120.366717 -242.327736) (xy 120.312771 -242.319975) (xy 120.260477 -242.304617) (xy 120.210902 -242.281973)
			(xy 120.165054 -242.252505) (xy 120.123866 -242.216812) (xy 120.088176 -242.17562) (xy 120.058712 -242.12977)
			(xy 120.036072 -242.080193) (xy 120.020718 -242.027898) (xy 120.012962 -241.973951) (xy 96.316912 -241.973951)
			(xy 96.348029 -242.009863) (xy 96.377495 -242.055713) (xy 96.400137 -242.10529) (xy 96.415492 -242.157585)
			(xy 96.423248 -242.211533) (xy 96.423734 -242.238784) (xy 96.423734 -242.239038) (xy 96.423195 -242.268248)
			(xy 96.414295 -242.325986) (xy 96.39668 -242.381687) (xy 96.370762 -242.434043) (xy 96.354392 -242.45824)
			(xy 96.346586 -242.470125) (xy 96.33728 -242.496984) (xy 96.335729 -242.525366) (xy 96.342052 -242.553079)
			(xy 96.355761 -242.57798) (xy 96.375796 -242.598144) (xy 96.400608 -242.612012) (xy 96.414336 -242.61572)
			(xy 96.441951 -242.622701) (xy 96.494916 -242.643645) (xy 96.544177 -242.672233) (xy 96.588637 -242.707831)
			(xy 96.627309 -242.749645) (xy 96.659331 -242.796745) (xy 96.683992 -242.848085) (xy 96.700743 -242.902522)
			(xy 96.709211 -242.958844) (xy 96.709738 -242.987322) (xy 96.709252 -243.014573) (xy 96.701496 -243.068521)
			(xy 96.686141 -243.120816) (xy 96.663499 -243.170393) (xy 96.634033 -243.216243) (xy 96.598342 -243.257434)
			(xy 96.557151 -243.293125) (xy 96.511301 -243.322591) (xy 96.461724 -243.345233) (xy 96.409429 -243.360588)
			(xy 96.355481 -243.368344) (xy 96.300979 -243.368344) (xy 96.247031 -243.360588) (xy 96.194736 -243.345233)
			(xy 96.145159 -243.322591) (xy 96.099309 -243.293125) (xy 96.058118 -243.257434) (xy 96.022427 -243.216243)
			(xy 95.992961 -243.170393) (xy 95.970319 -243.120816) (xy 95.954964 -243.068521) (xy 95.947208 -243.014573)
			(xy 95.946722 -242.987322) (xy 95.946722 -242.987068) (xy 95.947272 -242.957858) (xy 95.95617 -242.900121)
			(xy 95.973782 -242.844421) (xy 95.999696 -242.792064) (xy 96.016064 -242.767866) (xy 96.02383 -242.755959)
			(xy 96.033129 -242.729108) (xy 96.034678 -242.700736) (xy 96.02836 -242.673032) (xy 96.014661 -242.648137)
			(xy 95.994639 -242.627974) (xy 95.969842 -242.614099) (xy 95.95612 -242.610386) (xy 95.928499 -242.60343)
			(xy 95.875535 -242.58248) (xy 95.826275 -242.553887) (xy 95.781816 -242.518286) (xy 95.743146 -242.476469)
			(xy 95.711124 -242.429366) (xy 95.686464 -242.378024) (xy 95.669714 -242.323586) (xy 95.661246 -242.267262)
			(xy 95.660718 -242.238784) (xy 94.387148 -242.238784) (xy 94.387162 -242.239546) (xy 94.386653 -242.267432)
			(xy 94.378533 -242.322608) (xy 94.362465 -242.376015) (xy 94.338793 -242.426512) (xy 94.30802 -242.473025)
			(xy 94.270803 -242.514562) (xy 94.227935 -242.550237) (xy 94.180329 -242.579291) (xy 94.129 -242.601103)
			(xy 94.075043 -242.615209) (xy 94.019606 -242.621309) (xy 93.963872 -242.619272) (xy 93.909029 -242.609142)
			(xy 93.856245 -242.591135) (xy 93.806645 -242.565634) (xy 93.761287 -242.533183) (xy 93.721138 -242.494474)
			(xy 93.687052 -242.450331) (xy 93.659756 -242.401696) (xy 93.639833 -242.349605) (xy 93.627707 -242.295168)
			(xy 93.623636 -242.239546) (xy 89.464543 -242.239546) (xy 89.594795 -243.732157) (xy 101.008827 -243.732157)
			(xy 101.008827 -243.677643) (xy 101.016586 -243.623685) (xy 101.031945 -243.571379) (xy 101.054592 -243.521793)
			(xy 101.084066 -243.475934) (xy 101.119767 -243.434737) (xy 101.160968 -243.399041) (xy 101.20683 -243.369572)
			(xy 101.256419 -243.34693) (xy 101.308726 -243.331577) (xy 101.362685 -243.323824) (xy 101.389942 -243.323364)
			(xy 101.416936 -243.323799) (xy 101.470386 -243.331411) (xy 101.522229 -243.346477) (xy 101.571434 -243.368697)
			(xy 101.617017 -243.397627) (xy 101.637846 -243.414804) (xy 101.645974 -243.421916) (xy 101.666548 -243.428012)
			(xy 101.751892 -243.41709) (xy 101.762437 -243.415319) (xy 101.78072 -243.404262) (xy 101.787198 -243.395754)
			(xy 101.804809 -243.371452) (xy 101.846406 -243.328193) (xy 101.870002 -243.309648) (xy 101.877876 -243.303806)
			(xy 101.88829 -243.28628) (xy 101.901498 -243.195856) (xy 101.896672 -243.176552) (xy 101.89083 -243.168678)
			(xy 101.89083 -243.168424) (xy 101.873309 -243.143692) (xy 101.84551 -243.089835) (xy 101.826579 -243.032259)
			(xy 101.816992 -242.972414) (xy 101.816408 -242.94211) (xy 101.816865 -242.914857) (xy 101.824621 -242.860905)
			(xy 101.839976 -242.808606) (xy 101.862619 -242.759025) (xy 101.892087 -242.713171) (xy 101.927782 -242.671977)
			(xy 101.968975 -242.636284) (xy 102.01483 -242.606816) (xy 102.064411 -242.584174) (xy 102.116711 -242.568819)
			(xy 102.170663 -242.561064) (xy 102.197916 -242.560602) (xy 102.223949 -242.561056) (xy 102.275531 -242.568144)
			(xy 102.325672 -242.582173) (xy 102.373443 -242.602882) (xy 102.417959 -242.629887) (xy 102.438454 -242.645946)
			(xy 102.446214 -242.651683) (xy 102.464622 -242.657425) (xy 102.474268 -242.657122) (xy 102.554024 -242.650772)
			(xy 102.571804 -242.642136) (xy 102.578154 -242.63477) (xy 102.596347 -242.615136) (xy 102.637251 -242.58061)
			(xy 102.682577 -242.552138) (xy 102.731436 -242.530278) (xy 102.78287 -242.515459) (xy 102.835871 -242.507971)
			(xy 102.862634 -242.507516) (xy 102.889887 -242.507946) (xy 102.943838 -242.515708) (xy 102.996135 -242.531069)
			(xy 103.045714 -242.553716) (xy 103.091566 -242.583188) (xy 103.132756 -242.618885) (xy 103.168447 -242.660081)
			(xy 103.197912 -242.705937) (xy 103.220552 -242.755519) (xy 103.235904 -242.807819) (xy 103.243658 -242.861771)
			(xy 103.244142 -242.889024) (xy 103.243581 -242.917797) (xy 103.234937 -242.974689) (xy 103.217849 -243.029638)
			(xy 103.192704 -243.081399) (xy 103.160072 -243.128797) (xy 103.140764 -243.150136) (xy 103.133398 -243.15801)
			(xy 103.126286 -243.177822) (xy 103.133652 -243.274088) (xy 103.143558 -243.292884) (xy 103.15194 -243.299488)
			(xy 103.17115 -243.315236) (xy 127.416558 -243.315236) (xy 127.420629 -243.259614) (xy 127.432755 -243.205177)
			(xy 127.452678 -243.153086) (xy 127.479974 -243.104451) (xy 127.51406 -243.060308) (xy 127.554209 -243.021599)
			(xy 127.599567 -242.989148) (xy 127.649167 -242.963647) (xy 127.701951 -242.94564) (xy 127.756794 -242.93551)
			(xy 127.812528 -242.933473) (xy 127.867965 -242.939573) (xy 127.921922 -242.953679) (xy 127.973251 -242.975491)
			(xy 128.020857 -243.004545) (xy 128.063725 -243.04022) (xy 128.100942 -243.081757) (xy 128.131715 -243.12827)
			(xy 128.155387 -243.178767) (xy 128.171455 -243.232174) (xy 128.179575 -243.28735) (xy 128.180084 -243.315236)
			(xy 128.179575 -243.343122) (xy 128.171455 -243.398298) (xy 128.155387 -243.451705) (xy 128.131715 -243.502202)
			(xy 128.100942 -243.548715) (xy 128.063725 -243.590252) (xy 128.020857 -243.625927) (xy 127.973251 -243.654981)
			(xy 127.921922 -243.676793) (xy 127.867965 -243.690899) (xy 127.812528 -243.696999) (xy 127.756794 -243.694962)
			(xy 127.701951 -243.684832) (xy 127.649167 -243.666825) (xy 127.599567 -243.641324) (xy 127.554209 -243.608873)
			(xy 127.51406 -243.570164) (xy 127.479974 -243.526021) (xy 127.452678 -243.477386) (xy 127.432755 -243.425295)
			(xy 127.420629 -243.370858) (xy 127.416558 -243.315236) (xy 103.17115 -243.315236) (xy 103.174144 -243.31769)
			(xy 103.213355 -243.359629) (xy 103.245839 -243.406969) (xy 103.270865 -243.458642) (xy 103.287866 -243.51348)
			(xy 103.29646 -243.570247) (xy 103.296974 -243.598954) (xy 103.296502 -243.626207) (xy 103.28875 -243.68016)
			(xy 103.273398 -243.732459) (xy 103.250759 -243.782042) (xy 103.221292 -243.827897) (xy 103.185599 -243.869091)
			(xy 103.144406 -243.904785) (xy 103.098552 -243.934253) (xy 103.048971 -243.956894) (xy 102.996671 -243.972248)
			(xy 102.942719 -243.980001) (xy 102.915466 -243.980462) (xy 102.888564 -243.98) (xy 102.835295 -243.972425)
			(xy 102.783618 -243.957443) (xy 102.734557 -243.935353) (xy 102.689085 -243.906591) (xy 102.648103 -243.871728)
			(xy 102.612423 -243.831455) (xy 102.597204 -243.809266) (xy 102.590092 -243.798344) (xy 102.567232 -243.786406)
			(xy 102.454964 -243.788438) (xy 102.432612 -243.801392) (xy 102.425754 -243.812568) (xy 102.410835 -243.836172)
			(xy 102.375158 -243.879126) (xy 102.3336 -243.91642) (xy 102.287049 -243.947258) (xy 102.236501 -243.970981)
			(xy 102.183034 -243.987082) (xy 102.127791 -243.995218) (xy 102.099872 -243.995702) (xy 102.072879 -243.995243)
			(xy 102.019431 -243.987635) (xy 101.967588 -243.972573) (xy 101.918384 -243.950359) (xy 101.872799 -243.921435)
			(xy 101.851968 -243.904262) (xy 101.84384 -243.89715) (xy 101.823266 -243.891054) (xy 101.737922 -243.901976)
			(xy 101.727382 -243.903766) (xy 101.709098 -243.91481) (xy 101.702616 -243.923312) (xy 101.687264 -243.944543)
			(xy 101.651674 -243.982993) (xy 101.611156 -244.01621) (xy 101.566473 -244.043567) (xy 101.518466 -244.064551)
			(xy 101.468038 -244.078765) (xy 101.416138 -244.085943) (xy 101.389942 -244.08638) (xy 101.362685 -244.085976)
			(xy 101.308726 -244.078223) (xy 101.256419 -244.06287) (xy 101.20683 -244.040228) (xy 101.160968 -244.010759)
			(xy 101.119767 -243.975063) (xy 101.084066 -243.933866) (xy 101.054592 -243.888007) (xy 101.031945 -243.838421)
			(xy 101.016586 -243.786115) (xy 101.008827 -243.732157) (xy 89.594795 -243.732157) (xy 89.645478 -244.312948)
			(xy 95.852232 -244.312948) (xy 95.856303 -244.257326) (xy 95.868429 -244.202889) (xy 95.888352 -244.150798)
			(xy 95.915648 -244.102163) (xy 95.949734 -244.05802) (xy 95.989883 -244.019311) (xy 96.035241 -243.98686)
			(xy 96.084841 -243.961359) (xy 96.137625 -243.943352) (xy 96.192468 -243.933222) (xy 96.248202 -243.931185)
			(xy 96.303639 -243.937285) (xy 96.357596 -243.951391) (xy 96.408925 -243.973203) (xy 96.456531 -244.002257)
			(xy 96.499399 -244.037932) (xy 96.536616 -244.079469) (xy 96.567389 -244.125982) (xy 96.591061 -244.176479)
			(xy 96.607129 -244.229886) (xy 96.615249 -244.285062) (xy 96.615758 -244.312948) (xy 96.615249 -244.340834)
			(xy 96.607129 -244.39601) (xy 96.591061 -244.449417) (xy 96.567389 -244.499914) (xy 96.536616 -244.546427)
			(xy 96.518457 -244.566694) (xy 100.51999 -244.566694) (xy 100.524061 -244.511072) (xy 100.536187 -244.456635)
			(xy 100.55611 -244.404544) (xy 100.583406 -244.355909) (xy 100.617492 -244.311766) (xy 100.657641 -244.273057)
			(xy 100.702999 -244.240606) (xy 100.752599 -244.215105) (xy 100.805383 -244.197098) (xy 100.860226 -244.186968)
			(xy 100.91596 -244.184931) (xy 100.971397 -244.191031) (xy 101.025354 -244.205137) (xy 101.076683 -244.226949)
			(xy 101.124289 -244.256003) (xy 101.167157 -244.291678) (xy 101.204374 -244.333215) (xy 101.235147 -244.379728)
			(xy 101.258819 -244.430225) (xy 101.262228 -244.441555) (xy 104.256749 -244.441555) (xy 104.256749 -244.387045)
			(xy 104.264508 -244.33309) (xy 104.279866 -244.280788) (xy 104.302512 -244.231204) (xy 104.331984 -244.185348)
			(xy 104.367682 -244.144154) (xy 104.40888 -244.10846) (xy 104.454739 -244.078992) (xy 104.504325 -244.056352)
			(xy 104.556629 -244.040999) (xy 104.610585 -244.033247) (xy 104.63784 -244.032786) (xy 104.66658 -244.033289)
			(xy 104.723408 -244.041917) (xy 104.778299 -244.058972) (xy 104.83001 -244.084068) (xy 104.877372 -244.116638)
			(xy 104.898698 -244.13591) (xy 104.905556 -244.142514) (xy 104.92359 -244.149626) (xy 105.01249 -244.149626)
			(xy 105.030524 -244.142514) (xy 105.037382 -244.13591) (xy 105.058709 -244.11664) (xy 105.106072 -244.084075)
			(xy 105.157783 -244.058984) (xy 105.212674 -244.041934) (xy 105.269501 -244.033312) (xy 105.326979 -244.033312)
			(xy 105.383806 -244.041934) (xy 105.438697 -244.058984) (xy 105.490408 -244.084075) (xy 105.537771 -244.11664)
			(xy 105.559098 -244.13591) (xy 105.565956 -244.142514) (xy 105.58399 -244.149626) (xy 105.67289 -244.149626)
			(xy 105.690924 -244.142514) (xy 105.697782 -244.13591) (xy 105.719089 -244.116616) (xy 105.766457 -244.084054)
			(xy 105.818174 -244.058966) (xy 105.873069 -244.041921) (xy 105.9299 -244.033304) (xy 105.95864 -244.032786)
			(xy 105.985889 -244.033286) (xy 106.039832 -244.041048) (xy 106.092121 -244.056406) (xy 106.141692 -244.079049)
			(xy 106.187537 -244.108516) (xy 106.228722 -244.144207) (xy 106.264408 -244.185395) (xy 106.29387 -244.231243)
			(xy 106.315638 -244.278912) (xy 134.358124 -244.278912) (xy 134.362195 -244.22329) (xy 134.374321 -244.168853)
			(xy 134.394244 -244.116762) (xy 134.42154 -244.068127) (xy 134.455626 -244.023984) (xy 134.495775 -243.985275)
			(xy 134.541133 -243.952824) (xy 134.590733 -243.927323) (xy 134.643517 -243.909316) (xy 134.69836 -243.899186)
			(xy 134.754094 -243.897149) (xy 134.809531 -243.903249) (xy 134.863488 -243.917355) (xy 134.914817 -243.939167)
			(xy 134.962423 -243.968221) (xy 135.005291 -244.003896) (xy 135.042508 -244.045433) (xy 135.073281 -244.091946)
			(xy 135.096953 -244.142443) (xy 135.113021 -244.19585) (xy 135.121141 -244.251026) (xy 135.12165 -244.278912)
			(xy 135.121141 -244.306798) (xy 135.113021 -244.361974) (xy 135.096953 -244.415381) (xy 135.073281 -244.465878)
			(xy 135.042508 -244.512391) (xy 135.005291 -244.553928) (xy 134.962423 -244.589603) (xy 134.914817 -244.618657)
			(xy 134.863488 -244.640469) (xy 134.809531 -244.654575) (xy 134.754094 -244.660675) (xy 134.69836 -244.658638)
			(xy 134.643517 -244.648508) (xy 134.590733 -244.630501) (xy 134.541133 -244.605) (xy 134.495775 -244.572549)
			(xy 134.455626 -244.53384) (xy 134.42154 -244.489697) (xy 134.394244 -244.441062) (xy 134.374321 -244.388971)
			(xy 134.362195 -244.334534) (xy 134.358124 -244.278912) (xy 106.315638 -244.278912) (xy 106.316508 -244.280817)
			(xy 106.331861 -244.333108) (xy 106.339616 -244.387051) (xy 106.339616 -244.441549) (xy 106.331861 -244.495492)
			(xy 106.316508 -244.547783) (xy 106.29387 -244.597357) (xy 106.264408 -244.643205) (xy 106.228722 -244.684393)
			(xy 106.187537 -244.720084) (xy 106.141692 -244.749551) (xy 106.092121 -244.772194) (xy 106.039832 -244.787552)
			(xy 105.985889 -244.795314) (xy 105.95864 -244.795802) (xy 105.9299 -244.795314) (xy 105.873071 -244.786683)
			(xy 105.81818 -244.769624) (xy 105.766469 -244.744525) (xy 105.719108 -244.711952) (xy 105.697782 -244.692678)
			(xy 105.690924 -244.686074) (xy 105.67289 -244.678962) (xy 105.58399 -244.678962) (xy 105.565956 -244.686074)
			(xy 105.559098 -244.692678) (xy 105.537771 -244.711948) (xy 105.490408 -244.744513) (xy 105.438697 -244.769604)
			(xy 105.383806 -244.786654) (xy 105.326979 -244.795276) (xy 105.269501 -244.795276) (xy 105.212674 -244.786654)
			(xy 105.157783 -244.769604) (xy 105.106072 -244.744513) (xy 105.058709 -244.711948) (xy 105.037382 -244.692678)
			(xy 105.030524 -244.686074) (xy 105.01249 -244.678962) (xy 104.92359 -244.678962) (xy 104.905556 -244.686074)
			(xy 104.898698 -244.692678) (xy 104.877357 -244.711932) (xy 104.829998 -244.7445) (xy 104.77829 -244.769596)
			(xy 104.723403 -244.78665) (xy 104.666578 -244.795278) (xy 104.63784 -244.795802) (xy 104.610585 -244.795353)
			(xy 104.556629 -244.787601) (xy 104.504325 -244.772248) (xy 104.454739 -244.749608) (xy 104.40888 -244.72014)
			(xy 104.367682 -244.684446) (xy 104.331984 -244.643252) (xy 104.302512 -244.597396) (xy 104.279866 -244.547812)
			(xy 104.264508 -244.49551) (xy 104.256749 -244.441555) (xy 101.262228 -244.441555) (xy 101.274887 -244.483632)
			(xy 101.283007 -244.538808) (xy 101.283516 -244.566694) (xy 101.283007 -244.59458) (xy 101.274887 -244.649756)
			(xy 101.258819 -244.703163) (xy 101.235147 -244.75366) (xy 101.204374 -244.800173) (xy 101.167157 -244.84171)
			(xy 101.124289 -244.877385) (xy 101.076683 -244.906439) (xy 101.025354 -244.928251) (xy 100.971397 -244.942357)
			(xy 100.91596 -244.948457) (xy 100.860226 -244.94642) (xy 100.805383 -244.93629) (xy 100.752599 -244.918283)
			(xy 100.702999 -244.892782) (xy 100.657641 -244.860331) (xy 100.617492 -244.821622) (xy 100.583406 -244.777479)
			(xy 100.55611 -244.728844) (xy 100.536187 -244.676753) (xy 100.524061 -244.622316) (xy 100.51999 -244.566694)
			(xy 96.518457 -244.566694) (xy 96.499399 -244.587964) (xy 96.456531 -244.623639) (xy 96.408925 -244.652693)
			(xy 96.357596 -244.674505) (xy 96.303639 -244.688611) (xy 96.248202 -244.694711) (xy 96.192468 -244.692674)
			(xy 96.137625 -244.682544) (xy 96.084841 -244.664537) (xy 96.035241 -244.639036) (xy 95.989883 -244.606585)
			(xy 95.949734 -244.567876) (xy 95.915648 -244.523733) (xy 95.888352 -244.475098) (xy 95.868429 -244.423007)
			(xy 95.856303 -244.36857) (xy 95.852232 -244.312948) (xy 89.645478 -244.312948) (xy 89.6887 -244.808248)
			(xy 93.652338 -244.808248) (xy 93.656409 -244.752626) (xy 93.668535 -244.698189) (xy 93.688458 -244.646098)
			(xy 93.715754 -244.597463) (xy 93.74984 -244.55332) (xy 93.789989 -244.514611) (xy 93.835347 -244.48216)
			(xy 93.884947 -244.456659) (xy 93.937731 -244.438652) (xy 93.992574 -244.428522) (xy 94.048308 -244.426485)
			(xy 94.103745 -244.432585) (xy 94.157702 -244.446691) (xy 94.209031 -244.468503) (xy 94.256637 -244.497557)
			(xy 94.299505 -244.533232) (xy 94.336722 -244.574769) (xy 94.367495 -244.621282) (xy 94.391167 -244.671779)
			(xy 94.407235 -244.725186) (xy 94.415355 -244.780362) (xy 94.415864 -244.808248) (xy 94.415355 -244.836134)
			(xy 94.407235 -244.89131) (xy 94.391167 -244.944717) (xy 94.367495 -244.995214) (xy 94.336722 -245.041727)
			(xy 94.299505 -245.083264) (xy 94.256637 -245.118939) (xy 94.209031 -245.147993) (xy 94.157702 -245.169805)
			(xy 94.103745 -245.183911) (xy 94.048308 -245.190011) (xy 93.992574 -245.187974) (xy 93.937731 -245.177844)
			(xy 93.884947 -245.159837) (xy 93.835347 -245.134336) (xy 93.789989 -245.101885) (xy 93.74984 -245.063176)
			(xy 93.715754 -245.019033) (xy 93.688458 -244.970398) (xy 93.668535 -244.918307) (xy 93.656409 -244.86387)
			(xy 93.652338 -244.808248) (xy 89.6887 -244.808248) (xy 89.777361 -245.824248) (xy 95.865694 -245.824248)
			(xy 95.869765 -245.768626) (xy 95.881891 -245.714189) (xy 95.901814 -245.662098) (xy 95.92911 -245.613463)
			(xy 95.963196 -245.56932) (xy 96.003345 -245.530611) (xy 96.048703 -245.49816) (xy 96.098303 -245.472659)
			(xy 96.151087 -245.454652) (xy 96.20593 -245.444522) (xy 96.261664 -245.442485) (xy 96.317101 -245.448585)
			(xy 96.371058 -245.462691) (xy 96.422387 -245.484503) (xy 96.469993 -245.513557) (xy 96.512861 -245.549232)
			(xy 96.550078 -245.590769) (xy 96.580851 -245.637282) (xy 96.604523 -245.687779) (xy 96.620591 -245.741186)
			(xy 96.628711 -245.796362) (xy 96.62922 -245.824248) (xy 96.628711 -245.852134) (xy 96.620591 -245.90731)
			(xy 96.609282 -245.944898) (xy 100.372416 -245.944898) (xy 100.376487 -245.889276) (xy 100.388613 -245.834839)
			(xy 100.408536 -245.782748) (xy 100.435832 -245.734113) (xy 100.469918 -245.68997) (xy 100.510067 -245.651261)
			(xy 100.555425 -245.61881) (xy 100.605025 -245.593309) (xy 100.657809 -245.575302) (xy 100.712652 -245.565172)
			(xy 100.768386 -245.563135) (xy 100.823823 -245.569235) (xy 100.87778 -245.583341) (xy 100.929109 -245.605153)
			(xy 100.976715 -245.634207) (xy 101.019583 -245.669882) (xy 101.0568 -245.711419) (xy 101.087573 -245.757932)
			(xy 101.111245 -245.808429) (xy 101.127313 -245.861836) (xy 101.135433 -245.917012) (xy 101.135942 -245.944898)
			(xy 101.135433 -245.972784) (xy 101.127313 -246.02796) (xy 101.111245 -246.081367) (xy 101.087573 -246.131864)
			(xy 101.0568 -246.178377) (xy 101.019583 -246.219914) (xy 100.976715 -246.255589) (xy 100.929109 -246.284643)
			(xy 100.87778 -246.306455) (xy 100.823823 -246.320561) (xy 100.768386 -246.326661) (xy 100.712652 -246.324624)
			(xy 100.657809 -246.314494) (xy 100.605025 -246.296487) (xy 100.555425 -246.270986) (xy 100.510067 -246.238535)
			(xy 100.469918 -246.199826) (xy 100.435832 -246.155683) (xy 100.408536 -246.107048) (xy 100.388613 -246.054957)
			(xy 100.376487 -246.00052) (xy 100.372416 -245.944898) (xy 96.609282 -245.944898) (xy 96.604523 -245.960717)
			(xy 96.580851 -246.011214) (xy 96.550078 -246.057727) (xy 96.512861 -246.099264) (xy 96.469993 -246.134939)
			(xy 96.422387 -246.163993) (xy 96.371058 -246.185805) (xy 96.317101 -246.199911) (xy 96.261664 -246.206011)
			(xy 96.20593 -246.203974) (xy 96.151087 -246.193844) (xy 96.098303 -246.175837) (xy 96.048703 -246.150336)
			(xy 96.003345 -246.117885) (xy 95.963196 -246.079176) (xy 95.92911 -246.035033) (xy 95.901814 -245.986398)
			(xy 95.881891 -245.934307) (xy 95.869765 -245.87987) (xy 95.865694 -245.824248) (xy 89.777361 -245.824248)
			(xy 89.866022 -246.840248) (xy 93.652338 -246.840248) (xy 93.656409 -246.784626) (xy 93.668535 -246.730189)
			(xy 93.688458 -246.678098) (xy 93.715754 -246.629463) (xy 93.74984 -246.58532) (xy 93.789989 -246.546611)
			(xy 93.835347 -246.51416) (xy 93.884947 -246.488659) (xy 93.937731 -246.470652) (xy 93.992574 -246.460522)
			(xy 94.048308 -246.458485) (xy 94.103745 -246.464585) (xy 94.157702 -246.478691) (xy 94.209031 -246.500503)
			(xy 94.256637 -246.529557) (xy 94.299505 -246.565232) (xy 94.336722 -246.606769) (xy 94.367495 -246.653282)
			(xy 94.391167 -246.703779) (xy 94.407235 -246.757186) (xy 94.415355 -246.812362) (xy 94.415716 -246.83212)
			(xy 99.693474 -246.83212) (xy 99.697545 -246.776498) (xy 99.709671 -246.722061) (xy 99.729594 -246.66997)
			(xy 99.75689 -246.621335) (xy 99.790976 -246.577192) (xy 99.831125 -246.538483) (xy 99.876483 -246.506032)
			(xy 99.926083 -246.480531) (xy 99.978867 -246.462524) (xy 100.03371 -246.452394) (xy 100.089444 -246.450357)
			(xy 100.144881 -246.456457) (xy 100.198838 -246.470563) (xy 100.250167 -246.492375) (xy 100.297773 -246.521429)
			(xy 100.340641 -246.557104) (xy 100.377858 -246.598641) (xy 100.408631 -246.645154) (xy 100.432303 -246.695651)
			(xy 100.448371 -246.749058) (xy 100.456491 -246.804234) (xy 100.457 -246.83212) (xy 100.456491 -246.860006)
			(xy 100.448371 -246.915182) (xy 100.432303 -246.968589) (xy 100.408631 -247.019086) (xy 100.377858 -247.065599)
			(xy 100.340641 -247.107136) (xy 100.297773 -247.142811) (xy 100.250167 -247.171865) (xy 100.198838 -247.193677)
			(xy 100.144881 -247.207783) (xy 100.089444 -247.213883) (xy 100.03371 -247.211846) (xy 99.978867 -247.201716)
			(xy 99.926083 -247.183709) (xy 99.876483 -247.158208) (xy 99.831125 -247.125757) (xy 99.790976 -247.087048)
			(xy 99.75689 -247.042905) (xy 99.729594 -246.99427) (xy 99.709671 -246.942179) (xy 99.697545 -246.887742)
			(xy 99.693474 -246.83212) (xy 94.415716 -246.83212) (xy 94.415864 -246.840248) (xy 94.415355 -246.868134)
			(xy 94.407235 -246.92331) (xy 94.391167 -246.976717) (xy 94.367495 -247.027214) (xy 94.336722 -247.073727)
			(xy 94.299505 -247.115264) (xy 94.256637 -247.150939) (xy 94.209031 -247.179993) (xy 94.157702 -247.201805)
			(xy 94.103745 -247.215911) (xy 94.048308 -247.222011) (xy 93.992574 -247.219974) (xy 93.937731 -247.209844)
			(xy 93.884947 -247.191837) (xy 93.835347 -247.166336) (xy 93.789989 -247.133885) (xy 93.74984 -247.095176)
			(xy 93.715754 -247.051033) (xy 93.688458 -247.002398) (xy 93.668535 -246.950307) (xy 93.656409 -246.89587)
			(xy 93.652338 -246.840248) (xy 89.866022 -246.840248) (xy 89.996177 -248.331736) (xy 102.279196 -248.331736)
			(xy 102.279682 -248.302996) (xy 102.288314 -248.246167) (xy 102.305373 -248.191276) (xy 102.330473 -248.139564)
			(xy 102.363046 -248.092204) (xy 102.38232 -248.070878) (xy 102.388924 -248.06402) (xy 102.396036 -248.045986)
			(xy 102.396036 -247.957086) (xy 102.388924 -247.939052) (xy 102.38232 -247.932194) (xy 102.363085 -247.910836)
			(xy 102.330519 -247.863479) (xy 102.305426 -247.811772) (xy 102.288373 -247.756886) (xy 102.279747 -247.700063)
			(xy 102.279743 -247.642589) (xy 102.288361 -247.585765) (xy 102.305406 -247.530877) (xy 102.330493 -247.479167)
			(xy 102.363052 -247.431805) (xy 102.38232 -247.410478) (xy 102.388924 -247.40362) (xy 102.396036 -247.385586)
			(xy 102.396036 -247.296686) (xy 102.388924 -247.278652) (xy 102.38232 -247.271794) (xy 102.363063 -247.250455)
			(xy 102.330496 -247.203096) (xy 102.305401 -247.151387) (xy 102.288347 -247.096499) (xy 102.27972 -247.039674)
			(xy 102.279196 -247.010936) (xy 102.279684 -246.983567) (xy 102.287497 -246.929388) (xy 102.302981 -246.876886)
			(xy 102.325818 -246.827138) (xy 102.355537 -246.781171) (xy 102.373176 -246.760238) (xy 102.37343 -246.759984)
			(xy 102.379033 -246.752909) (xy 102.385269 -246.735983) (xy 102.385622 -246.726964) (xy 102.385622 -246.659908)
			(xy 102.385256 -246.650892) (xy 102.379014 -246.633975) (xy 102.37343 -246.626888) (xy 102.373176 -246.626888)
			(xy 102.373176 -246.626634) (xy 102.355536 -246.605703) (xy 102.325825 -246.55973) (xy 102.30299 -246.509982)
			(xy 102.287499 -246.457481) (xy 102.27967 -246.403305) (xy 102.279196 -246.375936) (xy 102.279682 -246.348685)
			(xy 102.287438 -246.294737) (xy 102.302793 -246.242442) (xy 102.325435 -246.192865) (xy 102.354901 -246.147015)
			(xy 102.390592 -246.105824) (xy 102.431783 -246.070133) (xy 102.477633 -246.040667) (xy 102.52721 -246.018025)
			(xy 102.579505 -246.00267) (xy 102.633453 -245.994914) (xy 102.687955 -245.994914) (xy 102.741903 -246.00267)
			(xy 102.794198 -246.018025) (xy 102.843775 -246.040667) (xy 102.889625 -246.070133) (xy 102.930816 -246.105824)
			(xy 102.966507 -246.147015) (xy 102.995973 -246.192865) (xy 103.018615 -246.242442) (xy 103.03397 -246.294737)
			(xy 103.041726 -246.348685) (xy 103.042212 -246.375936) (xy 103.041764 -246.403307) (xy 103.033941 -246.457487)
			(xy 103.018448 -246.50999) (xy 102.995602 -246.559736) (xy 102.965875 -246.605703) (xy 102.948232 -246.626634)
			(xy 102.947978 -246.626888) (xy 102.942388 -246.633972) (xy 102.936144 -246.650891) (xy 102.935786 -246.659908)
			(xy 102.935786 -246.726964) (xy 102.936163 -246.735979) (xy 102.942397 -246.752896) (xy 102.947978 -246.759984)
			(xy 102.948232 -246.759984) (xy 102.948232 -246.760238) (xy 102.96586 -246.781179) (xy 102.995573 -246.82715)
			(xy 103.01841 -246.876895) (xy 103.033904 -246.929394) (xy 103.041736 -246.983567) (xy 103.042212 -247.010936)
			(xy 103.041707 -247.039676) (xy 103.033079 -247.096504) (xy 103.016025 -247.151394) (xy 102.990929 -247.203106)
			(xy 102.95836 -247.250468) (xy 102.939088 -247.271794) (xy 102.932484 -247.278652) (xy 102.925372 -247.296686)
			(xy 102.925372 -247.385586) (xy 102.932484 -247.40362) (xy 102.939088 -247.410478) (xy 102.958394 -247.431774)
			(xy 102.990957 -247.479142) (xy 103.016046 -247.530859) (xy 103.028986 -247.57253) (xy 114.288822 -247.57253)
			(xy 114.292893 -247.516908) (xy 114.305019 -247.462471) (xy 114.324942 -247.41038) (xy 114.352238 -247.361745)
			(xy 114.386324 -247.317602) (xy 114.426473 -247.278893) (xy 114.471831 -247.246442) (xy 114.521431 -247.220941)
			(xy 114.574215 -247.202934) (xy 114.629058 -247.192804) (xy 114.684792 -247.190767) (xy 114.740229 -247.196867)
			(xy 114.794186 -247.210973) (xy 114.845515 -247.232785) (xy 114.893121 -247.261839) (xy 114.935989 -247.297514)
			(xy 114.973206 -247.339051) (xy 115.003979 -247.385564) (xy 115.027651 -247.436061) (xy 115.043719 -247.489468)
			(xy 115.051839 -247.544644) (xy 115.052348 -247.57253) (xy 115.05232 -247.574054) (xy 115.980462 -247.574054)
			(xy 115.984533 -247.518432) (xy 115.996659 -247.463995) (xy 116.016582 -247.411904) (xy 116.043878 -247.363269)
			(xy 116.077964 -247.319126) (xy 116.118113 -247.280417) (xy 116.163471 -247.247966) (xy 116.213071 -247.222465)
			(xy 116.265855 -247.204458) (xy 116.320698 -247.194328) (xy 116.376432 -247.192291) (xy 116.431869 -247.198391)
			(xy 116.485826 -247.212497) (xy 116.537155 -247.234309) (xy 116.584761 -247.263363) (xy 116.627629 -247.299038)
			(xy 116.664846 -247.340575) (xy 116.695619 -247.387088) (xy 116.719291 -247.437585) (xy 116.735359 -247.490992)
			(xy 116.743479 -247.546168) (xy 116.743988 -247.574054) (xy 116.743479 -247.60194) (xy 116.735359 -247.657116)
			(xy 116.719291 -247.710523) (xy 116.695619 -247.76102) (xy 116.664846 -247.807533) (xy 116.627629 -247.84907)
			(xy 116.584761 -247.884745) (xy 116.537155 -247.913799) (xy 116.485826 -247.935611) (xy 116.431869 -247.949717)
			(xy 116.376432 -247.955817) (xy 116.320698 -247.95378) (xy 116.265855 -247.94365) (xy 116.213071 -247.925643)
			(xy 116.163471 -247.900142) (xy 116.118113 -247.867691) (xy 116.077964 -247.828982) (xy 116.043878 -247.784839)
			(xy 116.016582 -247.736204) (xy 115.996659 -247.684113) (xy 115.984533 -247.629676) (xy 115.980462 -247.574054)
			(xy 115.05232 -247.574054) (xy 115.051839 -247.600416) (xy 115.043719 -247.655592) (xy 115.027651 -247.708999)
			(xy 115.003979 -247.759496) (xy 114.973206 -247.806009) (xy 114.935989 -247.847546) (xy 114.893121 -247.883221)
			(xy 114.845515 -247.912275) (xy 114.794186 -247.934087) (xy 114.740229 -247.948193) (xy 114.684792 -247.954293)
			(xy 114.629058 -247.952256) (xy 114.574215 -247.942126) (xy 114.521431 -247.924119) (xy 114.471831 -247.898618)
			(xy 114.426473 -247.866167) (xy 114.386324 -247.827458) (xy 114.352238 -247.783315) (xy 114.324942 -247.73468)
			(xy 114.305019 -247.682589) (xy 114.292893 -247.628152) (xy 114.288822 -247.57253) (xy 103.028986 -247.57253)
			(xy 103.033093 -247.585754) (xy 103.041712 -247.642586) (xy 103.041708 -247.700067) (xy 103.033081 -247.756897)
			(xy 103.016026 -247.81179) (xy 102.990931 -247.863503) (xy 102.958361 -247.910867) (xy 102.939088 -247.932194)
			(xy 102.932484 -247.939052) (xy 102.925372 -247.957086) (xy 102.925372 -248.045986) (xy 102.932484 -248.06402)
			(xy 102.939088 -248.070878) (xy 102.95838 -248.092186) (xy 102.990942 -248.139554) (xy 103.01603 -248.19127)
			(xy 103.033076 -248.246165) (xy 103.041694 -248.302996) (xy 103.042212 -248.331736) (xy 103.041726 -248.358987)
			(xy 103.03397 -248.412935) (xy 103.018615 -248.46523) (xy 103.017828 -248.466954) (xy 104.083041 -248.466954)
			(xy 104.083041 -248.412446) (xy 104.090798 -248.358493) (xy 104.106155 -248.306192) (xy 104.128799 -248.25661)
			(xy 104.158268 -248.210755) (xy 104.193964 -248.169561) (xy 104.235158 -248.133866) (xy 104.281014 -248.104397)
			(xy 104.330596 -248.081754) (xy 104.382897 -248.066397) (xy 104.43685 -248.058641) (xy 104.464104 -248.058178)
			(xy 104.492843 -248.058705) (xy 104.54967 -248.067328) (xy 104.60456 -248.084377) (xy 104.656272 -248.109468)
			(xy 104.703635 -248.142032) (xy 104.724962 -248.161302) (xy 104.73182 -248.167906) (xy 104.749854 -248.175018)
			(xy 104.838754 -248.175018) (xy 104.856788 -248.167906) (xy 104.863646 -248.161302) (xy 104.884973 -248.142032)
			(xy 104.932336 -248.109467) (xy 104.984047 -248.084376) (xy 105.038938 -248.067326) (xy 105.095765 -248.058704)
			(xy 105.153243 -248.058704) (xy 105.21007 -248.067326) (xy 105.264961 -248.084376) (xy 105.316672 -248.109467)
			(xy 105.364035 -248.142032) (xy 105.385362 -248.161302) (xy 105.39222 -248.167906) (xy 105.410254 -248.175018)
			(xy 105.499154 -248.175018) (xy 105.517188 -248.167906) (xy 105.524046 -248.161302) (xy 105.545381 -248.14204)
			(xy 105.59274 -248.109471) (xy 105.644449 -248.084375) (xy 105.699339 -248.067323) (xy 105.756165 -248.058699)
			(xy 105.784904 -248.058178) (xy 105.812154 -248.058693) (xy 105.866099 -248.066449) (xy 105.918392 -248.081804)
			(xy 105.967966 -248.104445) (xy 106.013815 -248.13391) (xy 106.055003 -248.1696) (xy 106.080826 -248.199402)
			(xy 123.865384 -248.199402) (xy 123.869455 -248.14378) (xy 123.881581 -248.089343) (xy 123.901504 -248.037252)
			(xy 123.9288 -247.988617) (xy 123.962886 -247.944474) (xy 124.003035 -247.905765) (xy 124.048393 -247.873314)
			(xy 124.097993 -247.847813) (xy 124.150777 -247.829806) (xy 124.20562 -247.819676) (xy 124.261354 -247.817639)
			(xy 124.316791 -247.823739) (xy 124.370748 -247.837845) (xy 124.422077 -247.859657) (xy 124.469683 -247.888711)
			(xy 124.512551 -247.924386) (xy 124.549768 -247.965923) (xy 124.580541 -248.012436) (xy 124.604213 -248.062933)
			(xy 124.620281 -248.11634) (xy 124.628401 -248.171516) (xy 124.62891 -248.199402) (xy 124.628401 -248.227288)
			(xy 124.620281 -248.282464) (xy 124.604213 -248.335871) (xy 124.580541 -248.386368) (xy 124.549768 -248.432881)
			(xy 124.512551 -248.474418) (xy 124.469683 -248.510093) (xy 124.422077 -248.539147) (xy 124.370748 -248.560959)
			(xy 124.316791 -248.575065) (xy 124.261354 -248.581165) (xy 124.20562 -248.579128) (xy 124.150777 -248.568998)
			(xy 124.097993 -248.550991) (xy 124.048393 -248.52549) (xy 124.003035 -248.493039) (xy 123.962886 -248.45433)
			(xy 123.9288 -248.410187) (xy 123.901504 -248.361552) (xy 123.881581 -248.309461) (xy 123.869455 -248.255024)
			(xy 123.865384 -248.199402) (xy 106.080826 -248.199402) (xy 106.090693 -248.210789) (xy 106.120157 -248.256637)
			(xy 106.142797 -248.306212) (xy 106.158152 -248.358505) (xy 106.165908 -248.41245) (xy 106.165908 -248.46695)
			(xy 106.158152 -248.520895) (xy 106.142797 -248.573188) (xy 106.120157 -248.622763) (xy 106.101022 -248.652538)
			(xy 128.32029 -248.652538) (xy 128.324361 -248.596916) (xy 128.336487 -248.542479) (xy 128.35641 -248.490388)
			(xy 128.383706 -248.441753) (xy 128.417792 -248.39761) (xy 128.457941 -248.358901) (xy 128.503299 -248.32645)
			(xy 128.552899 -248.300949) (xy 128.605683 -248.282942) (xy 128.660526 -248.272812) (xy 128.71626 -248.270775)
			(xy 128.771697 -248.276875) (xy 128.825654 -248.290981) (xy 128.876983 -248.312793) (xy 128.924589 -248.341847)
			(xy 128.967457 -248.377522) (xy 129.004674 -248.419059) (xy 129.035447 -248.465572) (xy 129.059119 -248.516069)
			(xy 129.075187 -248.569476) (xy 129.083307 -248.624652) (xy 129.083816 -248.652538) (xy 129.083307 -248.680424)
			(xy 129.075187 -248.7356) (xy 129.059119 -248.789007) (xy 129.035447 -248.839504) (xy 129.004674 -248.886017)
			(xy 128.967457 -248.927554) (xy 128.924589 -248.963229) (xy 128.876983 -248.992283) (xy 128.825654 -249.014095)
			(xy 128.771697 -249.028201) (xy 128.71626 -249.034301) (xy 128.660526 -249.032264) (xy 128.605683 -249.022134)
			(xy 128.552899 -249.004127) (xy 128.503299 -248.978626) (xy 128.457941 -248.946175) (xy 128.417792 -248.907466)
			(xy 128.383706 -248.863323) (xy 128.35641 -248.814688) (xy 128.336487 -248.762597) (xy 128.324361 -248.70816)
			(xy 128.32029 -248.652538) (xy 106.101022 -248.652538) (xy 106.090693 -248.668611) (xy 106.055003 -248.7098)
			(xy 106.013815 -248.74549) (xy 105.967966 -248.774955) (xy 105.918392 -248.797596) (xy 105.866099 -248.812951)
			(xy 105.812154 -248.820707) (xy 105.784904 -248.821194) (xy 105.756165 -248.820669) (xy 105.699338 -248.812047)
			(xy 105.644447 -248.794998) (xy 105.592735 -248.769906) (xy 105.545373 -248.737341) (xy 105.524046 -248.71807)
			(xy 105.517188 -248.711466) (xy 105.499154 -248.704354) (xy 105.410254 -248.704354) (xy 105.39222 -248.711466)
			(xy 105.385362 -248.71807) (xy 105.364035 -248.73734) (xy 105.316672 -248.769905) (xy 105.264961 -248.794996)
			(xy 105.21007 -248.812046) (xy 105.153243 -248.820668) (xy 105.095765 -248.820668) (xy 105.038938 -248.812046)
			(xy 104.984047 -248.794996) (xy 104.932336 -248.769905) (xy 104.884973 -248.73734) (xy 104.863646 -248.71807)
			(xy 104.856788 -248.711466) (xy 104.838754 -248.704354) (xy 104.749854 -248.704354) (xy 104.73182 -248.711466)
			(xy 104.724962 -248.71807) (xy 104.703634 -248.73734) (xy 104.656272 -248.769906) (xy 104.604561 -248.794999)
			(xy 104.54967 -248.812049) (xy 104.492843 -248.820673) (xy 104.464104 -248.821194) (xy 104.43685 -248.820759)
			(xy 104.382897 -248.813003) (xy 104.330596 -248.797646) (xy 104.281014 -248.775003) (xy 104.235158 -248.745534)
			(xy 104.193964 -248.709839) (xy 104.158268 -248.668645) (xy 104.128799 -248.62279) (xy 104.106155 -248.573208)
			(xy 104.090798 -248.520907) (xy 104.083041 -248.466954) (xy 103.017828 -248.466954) (xy 102.995973 -248.514807)
			(xy 102.966507 -248.560657) (xy 102.930816 -248.601848) (xy 102.889625 -248.637539) (xy 102.843775 -248.667005)
			(xy 102.794198 -248.689647) (xy 102.741903 -248.705002) (xy 102.687955 -248.712758) (xy 102.633453 -248.712758)
			(xy 102.579505 -248.705002) (xy 102.52721 -248.689647) (xy 102.477633 -248.667005) (xy 102.431783 -248.637539)
			(xy 102.390592 -248.601848) (xy 102.354901 -248.560657) (xy 102.325435 -248.514807) (xy 102.302793 -248.46523)
			(xy 102.287438 -248.412935) (xy 102.279682 -248.358987) (xy 102.279196 -248.331736) (xy 89.996177 -248.331736)
			(xy 90.042746 -248.86539) (xy 90.043491 -248.871605) (xy 90.047594 -248.883427) (xy 90.050874 -248.888758)
			(xy 90.56751 -249.672856) (xy 90.571574 -249.676666) (xy 90.631264 -249.736356) (xy 90.637013 -249.741554)
			(xy 90.650846 -249.748531) (xy 90.658442 -249.750072) (xy 90.666824 -249.750834) (xy 94.984062 -249.750834)
			(xy 94.998032 -249.748802) (xy 95.004382 -249.747024) (xy 95.010478 -249.743214) (xy 95.016474 -249.739805)
			(xy 95.029746 -249.736068) (xy 95.03664 -249.735848) (xy 102.224586 -249.735848) (xy 102.234027 -249.735351)
			(xy 102.251605 -249.728432) (xy 102.258876 -249.722386) (xy 102.280974 -249.702066) (xy 102.309422 -249.675904)
			(xy 102.312882 -249.672656) (xy 102.318642 -249.665117) (xy 102.320852 -249.660918) (xy 102.324916 -249.652536)
			(xy 102.325678 -249.642884) (xy 102.328544 -249.614622) (xy 102.341578 -249.559334) (xy 102.362665 -249.50659)
			(xy 102.391339 -249.457555) (xy 102.426966 -249.413313) (xy 102.468759 -249.374842) (xy 102.515794 -249.342993)
			(xy 102.567031 -249.31847) (xy 102.621338 -249.301815) (xy 102.677514 -249.293395) (xy 102.705916 -249.292872)
			(xy 102.734654 -249.293395) (xy 102.791479 -249.302021) (xy 102.846367 -249.319075) (xy 102.898075 -249.344172)
			(xy 102.945432 -249.376743) (xy 102.966774 -249.395996) (xy 102.967028 -249.39625) (xy 102.97095 -249.399707)
			(xy 102.979911 -249.405087) (xy 102.984808 -249.406918) (xy 102.988877 -249.408215) (xy 102.997302 -249.409615)
			(xy 103.001572 -249.409712) (xy 103.079042 -249.409712) (xy 103.092758 -249.407934) (xy 103.105458 -249.395996)
			(xy 103.126785 -249.376726) (xy 103.174148 -249.344161) (xy 103.225859 -249.31907) (xy 103.28075 -249.30202)
			(xy 103.337577 -249.293398) (xy 103.395055 -249.293398) (xy 103.451882 -249.30202) (xy 103.506773 -249.31907)
			(xy 103.558484 -249.344161) (xy 103.605847 -249.376726) (xy 103.627174 -249.395996) (xy 103.627428 -249.39625)
			(xy 103.63135 -249.399707) (xy 103.640311 -249.405087) (xy 103.645208 -249.406918) (xy 103.649277 -249.408215)
			(xy 103.657702 -249.409615) (xy 103.661972 -249.409712) (xy 103.739442 -249.409712) (xy 103.753158 -249.407934)
			(xy 103.765858 -249.395996) (xy 103.787186 -249.376727) (xy 103.834549 -249.344166) (xy 103.886261 -249.319079)
			(xy 103.941152 -249.302033) (xy 103.997978 -249.293413) (xy 104.026716 -249.292872) (xy 104.039454 -249.292951)
			(xy 104.064875 -249.294605) (xy 104.077516 -249.296174) (xy 104.105894 -249.30051) (xy 104.161 -249.316594)
			(xy 104.213075 -249.340751) (xy 104.260943 -249.372438) (xy 104.303523 -249.410939) (xy 104.339855 -249.455384)
			(xy 104.369118 -249.50477) (xy 104.390652 -249.557984) (xy 104.40397 -249.613823) (xy 104.406954 -249.642376)
			(xy 104.40797 -249.652282) (xy 104.41178 -249.66041) (xy 104.413983 -249.66467) (xy 104.419735 -249.672345)
			(xy 104.42321 -249.67565) (xy 104.454706 -249.704606) (xy 104.455214 -249.705114) (xy 104.473502 -249.722132)
			(xy 104.480737 -249.728385) (xy 104.498493 -249.735441) (xy 104.508046 -249.735848) (xy 127.677672 -249.735848)
			(xy 127.687949 -249.735384) (xy 127.706865 -249.727344) (xy 127.72112 -249.712537) (xy 127.72517 -249.703082)
			(xy 127.758952 -249.614436) (xy 127.762146 -249.604656) (xy 127.761329 -249.584115) (xy 127.752573 -249.565516)
			(xy 127.745236 -249.558302) (xy 127.725523 -249.540135) (xy 127.690878 -249.499225) (xy 127.662304 -249.453867)
			(xy 127.640363 -249.404954) (xy 127.625487 -249.353451) (xy 127.617971 -249.300372) (xy 127.617474 -249.273568)
			(xy 127.61796 -249.246317) (xy 127.625716 -249.192369) (xy 127.641071 -249.140074) (xy 127.663713 -249.090497)
			(xy 127.693179 -249.044647) (xy 127.72887 -249.003456) (xy 127.770061 -248.967765) (xy 127.815911 -248.938299)
			(xy 127.865488 -248.915657) (xy 127.917783 -248.900302) (xy 127.971731 -248.892546) (xy 128.026233 -248.892546)
			(xy 128.080181 -248.900302) (xy 128.132476 -248.915657) (xy 128.182053 -248.938299) (xy 128.227903 -248.967765)
			(xy 128.269094 -249.003456) (xy 128.304785 -249.044647) (xy 128.334251 -249.090497) (xy 128.356893 -249.140074)
			(xy 128.372248 -249.192369) (xy 128.380004 -249.246317) (xy 128.38049 -249.273568) (xy 128.380036 -249.300375)
			(xy 128.372526 -249.35346) (xy 128.35765 -249.404968) (xy 128.335701 -249.453883) (xy 128.307113 -249.499239)
			(xy 128.272451 -249.540141) (xy 128.252728 -249.558302) (xy 128.245333 -249.565476) (xy 128.236529 -249.584082)
			(xy 128.235775 -249.604653) (xy 128.239012 -249.614436) (xy 128.272794 -249.703082) (xy 128.276873 -249.712527)
			(xy 128.291106 -249.727359) (xy 128.310014 -249.735422) (xy 128.320292 -249.735848) (xy 132.278882 -249.735848)
			(xy 132.288944 -249.736288) (xy 132.307523 -249.744028) (xy 132.31495 -249.750834) (xy 136.16051 -253.596394)
			(xy 136.167367 -253.603788) (xy 136.174447 -253.620778) (xy 137.487404 -253.620778) (xy 137.491475 -253.565156)
			(xy 137.503601 -253.510719) (xy 137.523524 -253.458628) (xy 137.55082 -253.409993) (xy 137.584906 -253.36585)
			(xy 137.625055 -253.327141) (xy 137.670413 -253.29469) (xy 137.720013 -253.269189) (xy 137.772797 -253.251182)
			(xy 137.82764 -253.241052) (xy 137.883374 -253.239015) (xy 137.938811 -253.245115) (xy 137.992768 -253.259221)
			(xy 138.044097 -253.281033) (xy 138.091703 -253.310087) (xy 138.134571 -253.345762) (xy 138.171788 -253.387299)
			(xy 138.202561 -253.433812) (xy 138.226233 -253.484309) (xy 138.232368 -253.5047) (xy 138.850624 -253.5047)
			(xy 138.850624 -247.540526) (xy 138.851167 -247.507241) (xy 138.859911 -247.441245) (xy 138.877187 -247.376954)
			(xy 138.9027 -247.315465) (xy 138.936015 -247.257829) (xy 138.976562 -247.20503) (xy 138.999722 -247.181116)
			(xy 139.744958 -246.435626) (xy 139.751773 -246.428206) (xy 139.759509 -246.409622) (xy 139.759944 -246.399558)
			(xy 139.759944 -243.611908) (xy 139.760446 -243.579947) (xy 139.768457 -243.516529) (xy 139.784354 -243.454615)
			(xy 139.807886 -243.395182) (xy 139.83868 -243.339167) (xy 139.876253 -243.287452) (xy 139.92001 -243.240855)
			(xy 139.969263 -243.20011) (xy 140.023234 -243.165859) (xy 140.081073 -243.138642) (xy 140.141866 -243.118889)
			(xy 140.204656 -243.106911) (xy 140.268452 -243.102898) (xy 140.332248 -243.106911) (xy 140.395038 -243.118889)
			(xy 140.455831 -243.138642) (xy 140.492672 -243.155978) (xy 142.449294 -243.155978) (xy 142.453365 -243.100356)
			(xy 142.465491 -243.045919) (xy 142.485414 -242.993828) (xy 142.51271 -242.945193) (xy 142.546796 -242.90105)
			(xy 142.586945 -242.862341) (xy 142.632303 -242.82989) (xy 142.681903 -242.804389) (xy 142.734687 -242.786382)
			(xy 142.78953 -242.776252) (xy 142.845264 -242.774215) (xy 142.900701 -242.780315) (xy 142.954658 -242.794421)
			(xy 143.005987 -242.816233) (xy 143.053593 -242.845287) (xy 143.096461 -242.880962) (xy 143.133678 -242.922499)
			(xy 143.164451 -242.969012) (xy 143.188123 -243.019509) (xy 143.204191 -243.072916) (xy 143.212311 -243.128092)
			(xy 143.212356 -243.130578) (xy 144.551144 -243.130578) (xy 144.555215 -243.074956) (xy 144.567341 -243.020519)
			(xy 144.587264 -242.968428) (xy 144.61456 -242.919793) (xy 144.648646 -242.87565) (xy 144.688795 -242.836941)
			(xy 144.734153 -242.80449) (xy 144.783753 -242.778989) (xy 144.836537 -242.760982) (xy 144.89138 -242.750852)
			(xy 144.947114 -242.748815) (xy 145.002551 -242.754915) (xy 145.056508 -242.769021) (xy 145.107837 -242.790833)
			(xy 145.155443 -242.819887) (xy 145.198311 -242.855562) (xy 145.235528 -242.897099) (xy 145.266301 -242.943612)
			(xy 145.289973 -242.994109) (xy 145.306041 -243.047516) (xy 145.309742 -243.072666) (xy 149.923498 -243.072666)
			(xy 149.927569 -243.017044) (xy 149.939695 -242.962607) (xy 149.959618 -242.910516) (xy 149.986914 -242.861881)
			(xy 150.021 -242.817738) (xy 150.061149 -242.779029) (xy 150.106507 -242.746578) (xy 150.156107 -242.721077)
			(xy 150.208891 -242.70307) (xy 150.263734 -242.69294) (xy 150.319468 -242.690903) (xy 150.374905 -242.697003)
			(xy 150.428862 -242.711109) (xy 150.480191 -242.732921) (xy 150.527797 -242.761975) (xy 150.570665 -242.79765)
			(xy 150.607882 -242.839187) (xy 150.638655 -242.8857) (xy 150.662327 -242.936197) (xy 150.678395 -242.989604)
			(xy 150.686515 -243.04478) (xy 150.687024 -243.072666) (xy 150.686515 -243.100552) (xy 150.678395 -243.155728)
			(xy 150.662327 -243.209135) (xy 150.638655 -243.259632) (xy 150.607882 -243.306145) (xy 150.570665 -243.347682)
			(xy 150.527797 -243.383357) (xy 150.480191 -243.412411) (xy 150.428862 -243.434223) (xy 150.374905 -243.448329)
			(xy 150.319468 -243.454429) (xy 150.263734 -243.452392) (xy 150.208891 -243.442262) (xy 150.156107 -243.424255)
			(xy 150.106507 -243.398754) (xy 150.061149 -243.366303) (xy 150.021 -243.327594) (xy 149.986914 -243.283451)
			(xy 149.959618 -243.234816) (xy 149.939695 -243.182725) (xy 149.927569 -243.128288) (xy 149.923498 -243.072666)
			(xy 145.309742 -243.072666) (xy 145.314161 -243.102692) (xy 145.31467 -243.130578) (xy 145.314161 -243.158464)
			(xy 145.306041 -243.21364) (xy 145.289973 -243.267047) (xy 145.266301 -243.317544) (xy 145.235528 -243.364057)
			(xy 145.198311 -243.405594) (xy 145.155443 -243.441269) (xy 145.107837 -243.470323) (xy 145.056508 -243.492135)
			(xy 145.002551 -243.506241) (xy 144.947114 -243.512341) (xy 144.89138 -243.510304) (xy 144.836537 -243.500174)
			(xy 144.783753 -243.482167) (xy 144.734153 -243.456666) (xy 144.688795 -243.424215) (xy 144.648646 -243.385506)
			(xy 144.61456 -243.341363) (xy 144.587264 -243.292728) (xy 144.567341 -243.240637) (xy 144.555215 -243.1862)
			(xy 144.551144 -243.130578) (xy 143.212356 -243.130578) (xy 143.21282 -243.155978) (xy 143.212311 -243.183864)
			(xy 143.204191 -243.23904) (xy 143.188123 -243.292447) (xy 143.164451 -243.342944) (xy 143.133678 -243.389457)
			(xy 143.096461 -243.430994) (xy 143.053593 -243.466669) (xy 143.005987 -243.495723) (xy 142.954658 -243.517535)
			(xy 142.900701 -243.531641) (xy 142.845264 -243.537741) (xy 142.78953 -243.535704) (xy 142.734687 -243.525574)
			(xy 142.681903 -243.507567) (xy 142.632303 -243.482066) (xy 142.586945 -243.449615) (xy 142.546796 -243.410906)
			(xy 142.51271 -243.366763) (xy 142.485414 -243.318128) (xy 142.465491 -243.266037) (xy 142.453365 -243.2116)
			(xy 142.449294 -243.155978) (xy 140.492672 -243.155978) (xy 140.51367 -243.165859) (xy 140.567641 -243.20011)
			(xy 140.616894 -243.240855) (xy 140.660651 -243.287452) (xy 140.698224 -243.339167) (xy 140.729018 -243.395182)
			(xy 140.75255 -243.454615) (xy 140.768447 -243.516529) (xy 140.776458 -243.579947) (xy 140.77696 -243.611908)
			(xy 140.77696 -244.298978) (xy 148.488144 -244.298978) (xy 148.492215 -244.243356) (xy 148.504341 -244.188919)
			(xy 148.524264 -244.136828) (xy 148.55156 -244.088193) (xy 148.585646 -244.04405) (xy 148.625795 -244.005341)
			(xy 148.671153 -243.97289) (xy 148.720753 -243.947389) (xy 148.773537 -243.929382) (xy 148.82838 -243.919252)
			(xy 148.884114 -243.917215) (xy 148.939551 -243.923315) (xy 148.993508 -243.937421) (xy 149.044837 -243.959233)
			(xy 149.092443 -243.988287) (xy 149.135311 -244.023962) (xy 149.172528 -244.065499) (xy 149.203301 -244.112012)
			(xy 149.226973 -244.162509) (xy 149.243041 -244.215916) (xy 149.251161 -244.271092) (xy 149.25167 -244.298978)
			(xy 149.251161 -244.326864) (xy 149.243041 -244.38204) (xy 149.226973 -244.435447) (xy 149.203301 -244.485944)
			(xy 149.172528 -244.532457) (xy 149.135311 -244.573994) (xy 149.092443 -244.609669) (xy 149.044837 -244.638723)
			(xy 148.993508 -244.660535) (xy 148.939551 -244.674641) (xy 148.884114 -244.680741) (xy 148.82838 -244.678704)
			(xy 148.773537 -244.668574) (xy 148.720753 -244.650567) (xy 148.671153 -244.625066) (xy 148.625795 -244.592615)
			(xy 148.585646 -244.553906) (xy 148.55156 -244.509763) (xy 148.524264 -244.461128) (xy 148.504341 -244.409037)
			(xy 148.492215 -244.3546) (xy 148.488144 -244.298978) (xy 140.77696 -244.298978) (xy 140.77696 -245.191026)
			(xy 145.387312 -245.191026) (xy 145.391383 -245.135404) (xy 145.403509 -245.080967) (xy 145.423432 -245.028876)
			(xy 145.450728 -244.980241) (xy 145.484814 -244.936098) (xy 145.524963 -244.897389) (xy 145.570321 -244.864938)
			(xy 145.619921 -244.839437) (xy 145.672705 -244.82143) (xy 145.727548 -244.8113) (xy 145.783282 -244.809263)
			(xy 145.838719 -244.815363) (xy 145.892676 -244.829469) (xy 145.944005 -244.851281) (xy 145.991611 -244.880335)
			(xy 146.034479 -244.91601) (xy 146.071696 -244.957547) (xy 146.102469 -245.00406) (xy 146.126141 -245.054557)
			(xy 146.142209 -245.107964) (xy 146.150329 -245.16314) (xy 146.150838 -245.191026) (xy 146.150329 -245.218912)
			(xy 146.142209 -245.274088) (xy 146.128226 -245.320566) (xy 151.397206 -245.320566) (xy 151.401277 -245.264944)
			(xy 151.413403 -245.210507) (xy 151.433326 -245.158416) (xy 151.460622 -245.109781) (xy 151.494708 -245.065638)
			(xy 151.534857 -245.026929) (xy 151.580215 -244.994478) (xy 151.629815 -244.968977) (xy 151.682599 -244.95097)
			(xy 151.737442 -244.94084) (xy 151.793176 -244.938803) (xy 151.848613 -244.944903) (xy 151.90257 -244.959009)
			(xy 151.953899 -244.980821) (xy 152.001505 -245.009875) (xy 152.044373 -245.04555) (xy 152.08159 -245.087087)
			(xy 152.112363 -245.1336) (xy 152.136035 -245.184097) (xy 152.152103 -245.237504) (xy 152.160223 -245.29268)
			(xy 152.160431 -245.304056) (xy 152.648918 -245.304056) (xy 152.652989 -245.248434) (xy 152.665115 -245.193997)
			(xy 152.685038 -245.141906) (xy 152.712334 -245.093271) (xy 152.74642 -245.049128) (xy 152.786569 -245.010419)
			(xy 152.831927 -244.977968) (xy 152.881527 -244.952467) (xy 152.934311 -244.93446) (xy 152.989154 -244.92433)
			(xy 153.044888 -244.922293) (xy 153.100325 -244.928393) (xy 153.154282 -244.942499) (xy 153.205611 -244.964311)
			(xy 153.253217 -244.993365) (xy 153.296085 -245.02904) (xy 153.333302 -245.070577) (xy 153.364075 -245.11709)
			(xy 153.387747 -245.167587) (xy 153.403815 -245.220994) (xy 153.411935 -245.27617) (xy 153.412444 -245.304056)
			(xy 153.411935 -245.331942) (xy 153.403815 -245.387118) (xy 153.387747 -245.440525) (xy 153.374325 -245.469156)
			(xy 154.295092 -245.469156) (xy 154.299163 -245.413534) (xy 154.311289 -245.359097) (xy 154.331212 -245.307006)
			(xy 154.358508 -245.258371) (xy 154.392594 -245.214228) (xy 154.432743 -245.175519) (xy 154.478101 -245.143068)
			(xy 154.527701 -245.117567) (xy 154.580485 -245.09956) (xy 154.635328 -245.08943) (xy 154.691062 -245.087393)
			(xy 154.746499 -245.093493) (xy 154.800456 -245.107599) (xy 154.851785 -245.129411) (xy 154.899391 -245.158465)
			(xy 154.942259 -245.19414) (xy 154.979476 -245.235677) (xy 155.010249 -245.28219) (xy 155.033921 -245.332687)
			(xy 155.049989 -245.386094) (xy 155.058109 -245.44127) (xy 155.058618 -245.469156) (xy 155.058109 -245.497042)
			(xy 155.049989 -245.552218) (xy 155.033921 -245.605625) (xy 155.010249 -245.656122) (xy 154.979476 -245.702635)
			(xy 154.942259 -245.744172) (xy 154.899391 -245.779847) (xy 154.851785 -245.808901) (xy 154.800456 -245.830713)
			(xy 154.746499 -245.844819) (xy 154.691062 -245.850919) (xy 154.635328 -245.848882) (xy 154.580485 -245.838752)
			(xy 154.527701 -245.820745) (xy 154.478101 -245.795244) (xy 154.432743 -245.762793) (xy 154.392594 -245.724084)
			(xy 154.358508 -245.679941) (xy 154.331212 -245.631306) (xy 154.311289 -245.579215) (xy 154.299163 -245.524778)
			(xy 154.295092 -245.469156) (xy 153.374325 -245.469156) (xy 153.364075 -245.491022) (xy 153.333302 -245.537535)
			(xy 153.296085 -245.579072) (xy 153.253217 -245.614747) (xy 153.205611 -245.643801) (xy 153.154282 -245.665613)
			(xy 153.100325 -245.679719) (xy 153.044888 -245.685819) (xy 152.989154 -245.683782) (xy 152.934311 -245.673652)
			(xy 152.881527 -245.655645) (xy 152.831927 -245.630144) (xy 152.786569 -245.597693) (xy 152.74642 -245.558984)
			(xy 152.712334 -245.514841) (xy 152.685038 -245.466206) (xy 152.665115 -245.414115) (xy 152.652989 -245.359678)
			(xy 152.648918 -245.304056) (xy 152.160431 -245.304056) (xy 152.160732 -245.320566) (xy 152.160223 -245.348452)
			(xy 152.152103 -245.403628) (xy 152.136035 -245.457035) (xy 152.112363 -245.507532) (xy 152.08159 -245.554045)
			(xy 152.044373 -245.595582) (xy 152.001505 -245.631257) (xy 151.953899 -245.660311) (xy 151.90257 -245.682123)
			(xy 151.848613 -245.696229) (xy 151.793176 -245.702329) (xy 151.737442 -245.700292) (xy 151.682599 -245.690162)
			(xy 151.629815 -245.672155) (xy 151.580215 -245.646654) (xy 151.534857 -245.614203) (xy 151.494708 -245.575494)
			(xy 151.460622 -245.531351) (xy 151.433326 -245.482716) (xy 151.413403 -245.430625) (xy 151.401277 -245.376188)
			(xy 151.397206 -245.320566) (xy 146.128226 -245.320566) (xy 146.126141 -245.327495) (xy 146.102469 -245.377992)
			(xy 146.071696 -245.424505) (xy 146.034479 -245.466042) (xy 145.991611 -245.501717) (xy 145.944005 -245.530771)
			(xy 145.892676 -245.552583) (xy 145.838719 -245.566689) (xy 145.783282 -245.572789) (xy 145.727548 -245.570752)
			(xy 145.672705 -245.560622) (xy 145.619921 -245.542615) (xy 145.570321 -245.517114) (xy 145.524963 -245.484663)
			(xy 145.484814 -245.445954) (xy 145.450728 -245.401811) (xy 145.423432 -245.353176) (xy 145.403509 -245.301085)
			(xy 145.391383 -245.246648) (xy 145.387312 -245.191026) (xy 140.77696 -245.191026) (xy 140.77696 -246.631206)
			(xy 140.776378 -246.66449) (xy 140.767643 -246.730484) (xy 140.750375 -246.794775) (xy 140.724869 -246.856264)
			(xy 140.69156 -246.913901) (xy 140.651019 -246.966701) (xy 140.627862 -246.990616) (xy 139.882626 -247.736106)
			(xy 139.875795 -247.743513) (xy 139.868069 -247.762107) (xy 139.86764 -247.772174) (xy 139.86764 -249.052842)
			(xy 141.076424 -249.052842) (xy 141.080495 -248.99722) (xy 141.092621 -248.942783) (xy 141.112544 -248.890692)
			(xy 141.13984 -248.842057) (xy 141.173926 -248.797914) (xy 141.214075 -248.759205) (xy 141.259433 -248.726754)
			(xy 141.309033 -248.701253) (xy 141.361817 -248.683246) (xy 141.41666 -248.673116) (xy 141.472394 -248.671079)
			(xy 141.527831 -248.677179) (xy 141.581788 -248.691285) (xy 141.633117 -248.713097) (xy 141.680723 -248.742151)
			(xy 141.723591 -248.777826) (xy 141.760808 -248.819363) (xy 141.791581 -248.865876) (xy 141.815253 -248.916373)
			(xy 141.831321 -248.96978) (xy 141.839441 -249.024956) (xy 141.839579 -249.032522) (xy 142.092424 -249.032522)
			(xy 142.096495 -248.9769) (xy 142.108621 -248.922463) (xy 142.128544 -248.870372) (xy 142.15584 -248.821737)
			(xy 142.189926 -248.777594) (xy 142.230075 -248.738885) (xy 142.275433 -248.706434) (xy 142.325033 -248.680933)
			(xy 142.377817 -248.662926) (xy 142.43266 -248.652796) (xy 142.488394 -248.650759) (xy 142.543831 -248.656859)
			(xy 142.597788 -248.670965) (xy 142.649117 -248.692777) (xy 142.696723 -248.721831) (xy 142.739591 -248.757506)
			(xy 142.776808 -248.799043) (xy 142.807581 -248.845556) (xy 142.831253 -248.896053) (xy 142.847321 -248.94946)
			(xy 142.855441 -249.004636) (xy 142.85595 -249.032522) (xy 142.855441 -249.060408) (xy 142.847321 -249.115584)
			(xy 142.831253 -249.168991) (xy 142.807581 -249.219488) (xy 142.776808 -249.266001) (xy 142.739591 -249.307538)
			(xy 142.696723 -249.343213) (xy 142.649117 -249.372267) (xy 142.597788 -249.394079) (xy 142.543831 -249.408185)
			(xy 142.488394 -249.414285) (xy 142.43266 -249.412248) (xy 142.377817 -249.402118) (xy 142.325033 -249.384111)
			(xy 142.275433 -249.35861) (xy 142.230075 -249.326159) (xy 142.189926 -249.28745) (xy 142.15584 -249.243307)
			(xy 142.128544 -249.194672) (xy 142.108621 -249.142581) (xy 142.096495 -249.088144) (xy 142.092424 -249.032522)
			(xy 141.839579 -249.032522) (xy 141.83995 -249.052842) (xy 141.839441 -249.080728) (xy 141.831321 -249.135904)
			(xy 141.815253 -249.189311) (xy 141.791581 -249.239808) (xy 141.760808 -249.286321) (xy 141.723591 -249.327858)
			(xy 141.680723 -249.363533) (xy 141.633117 -249.392587) (xy 141.581788 -249.414399) (xy 141.527831 -249.428505)
			(xy 141.472394 -249.434605) (xy 141.41666 -249.432568) (xy 141.361817 -249.422438) (xy 141.309033 -249.404431)
			(xy 141.259433 -249.37893) (xy 141.214075 -249.346479) (xy 141.173926 -249.30777) (xy 141.13984 -249.263627)
			(xy 141.112544 -249.214992) (xy 141.092621 -249.162901) (xy 141.080495 -249.108464) (xy 141.076424 -249.052842)
			(xy 139.86764 -249.052842) (xy 139.86764 -251.158502) (xy 140.060424 -251.158502) (xy 140.064495 -251.10288)
			(xy 140.076621 -251.048443) (xy 140.096544 -250.996352) (xy 140.12384 -250.947717) (xy 140.157926 -250.903574)
			(xy 140.198075 -250.864865) (xy 140.243433 -250.832414) (xy 140.293033 -250.806913) (xy 140.345817 -250.788906)
			(xy 140.40066 -250.778776) (xy 140.456394 -250.776739) (xy 140.511831 -250.782839) (xy 140.565788 -250.796945)
			(xy 140.617117 -250.818757) (xy 140.664723 -250.847811) (xy 140.707591 -250.883486) (xy 140.744808 -250.925023)
			(xy 140.775581 -250.971536) (xy 140.799253 -251.022033) (xy 140.815321 -251.07544) (xy 140.823441 -251.130616)
			(xy 140.82395 -251.158502) (xy 141.076424 -251.158502) (xy 141.080495 -251.10288) (xy 141.092621 -251.048443)
			(xy 141.112544 -250.996352) (xy 141.13984 -250.947717) (xy 141.173926 -250.903574) (xy 141.214075 -250.864865)
			(xy 141.259433 -250.832414) (xy 141.309033 -250.806913) (xy 141.361817 -250.788906) (xy 141.41666 -250.778776)
			(xy 141.472394 -250.776739) (xy 141.527831 -250.782839) (xy 141.581788 -250.796945) (xy 141.633117 -250.818757)
			(xy 141.680723 -250.847811) (xy 141.723591 -250.883486) (xy 141.760808 -250.925023) (xy 141.791581 -250.971536)
			(xy 141.815253 -251.022033) (xy 141.831321 -251.07544) (xy 141.839441 -251.130616) (xy 141.83995 -251.158502)
			(xy 142.092424 -251.158502) (xy 142.096495 -251.10288) (xy 142.108621 -251.048443) (xy 142.128544 -250.996352)
			(xy 142.15584 -250.947717) (xy 142.189926 -250.903574) (xy 142.230075 -250.864865) (xy 142.275433 -250.832414)
			(xy 142.325033 -250.806913) (xy 142.377817 -250.788906) (xy 142.43266 -250.778776) (xy 142.488394 -250.776739)
			(xy 142.543831 -250.782839) (xy 142.597788 -250.796945) (xy 142.649117 -250.818757) (xy 142.696723 -250.847811)
			(xy 142.739591 -250.883486) (xy 142.776808 -250.925023) (xy 142.807581 -250.971536) (xy 142.831253 -251.022033)
			(xy 142.847321 -251.07544) (xy 142.855441 -251.130616) (xy 142.85595 -251.158502) (xy 143.108424 -251.158502)
			(xy 143.112495 -251.10288) (xy 143.124621 -251.048443) (xy 143.144544 -250.996352) (xy 143.17184 -250.947717)
			(xy 143.205926 -250.903574) (xy 143.246075 -250.864865) (xy 143.291433 -250.832414) (xy 143.341033 -250.806913)
			(xy 143.393817 -250.788906) (xy 143.44866 -250.778776) (xy 143.504394 -250.776739) (xy 143.559831 -250.782839)
			(xy 143.613788 -250.796945) (xy 143.665117 -250.818757) (xy 143.712723 -250.847811) (xy 143.755591 -250.883486)
			(xy 143.792808 -250.925023) (xy 143.823581 -250.971536) (xy 143.847253 -251.022033) (xy 143.863321 -251.07544)
			(xy 143.871441 -251.130616) (xy 143.87195 -251.158502) (xy 144.124424 -251.158502) (xy 144.128495 -251.10288)
			(xy 144.140621 -251.048443) (xy 144.160544 -250.996352) (xy 144.18784 -250.947717) (xy 144.221926 -250.903574)
			(xy 144.262075 -250.864865) (xy 144.307433 -250.832414) (xy 144.357033 -250.806913) (xy 144.409817 -250.788906)
			(xy 144.46466 -250.778776) (xy 144.520394 -250.776739) (xy 144.575831 -250.782839) (xy 144.629788 -250.796945)
			(xy 144.681117 -250.818757) (xy 144.728723 -250.847811) (xy 144.771591 -250.883486) (xy 144.808808 -250.925023)
			(xy 144.839581 -250.971536) (xy 144.863253 -251.022033) (xy 144.879321 -251.07544) (xy 144.887441 -251.130616)
			(xy 144.88795 -251.158502) (xy 145.140424 -251.158502) (xy 145.144495 -251.10288) (xy 145.156621 -251.048443)
			(xy 145.176544 -250.996352) (xy 145.20384 -250.947717) (xy 145.237926 -250.903574) (xy 145.278075 -250.864865)
			(xy 145.323433 -250.832414) (xy 145.373033 -250.806913) (xy 145.425817 -250.788906) (xy 145.48066 -250.778776)
			(xy 145.536394 -250.776739) (xy 145.591831 -250.782839) (xy 145.645788 -250.796945) (xy 145.697117 -250.818757)
			(xy 145.744723 -250.847811) (xy 145.787591 -250.883486) (xy 145.824808 -250.925023) (xy 145.855581 -250.971536)
			(xy 145.879253 -251.022033) (xy 145.895321 -251.07544) (xy 145.903441 -251.130616) (xy 145.90395 -251.158502)
			(xy 146.156424 -251.158502) (xy 146.160495 -251.10288) (xy 146.172621 -251.048443) (xy 146.192544 -250.996352)
			(xy 146.21984 -250.947717) (xy 146.253926 -250.903574) (xy 146.294075 -250.864865) (xy 146.339433 -250.832414)
			(xy 146.389033 -250.806913) (xy 146.441817 -250.788906) (xy 146.49666 -250.778776) (xy 146.552394 -250.776739)
			(xy 146.607831 -250.782839) (xy 146.661788 -250.796945) (xy 146.713117 -250.818757) (xy 146.760723 -250.847811)
			(xy 146.803591 -250.883486) (xy 146.840808 -250.925023) (xy 146.871581 -250.971536) (xy 146.895253 -251.022033)
			(xy 146.911321 -251.07544) (xy 146.919441 -251.130616) (xy 146.91995 -251.158502) (xy 147.172424 -251.158502)
			(xy 147.176495 -251.10288) (xy 147.188621 -251.048443) (xy 147.208544 -250.996352) (xy 147.23584 -250.947717)
			(xy 147.269926 -250.903574) (xy 147.310075 -250.864865) (xy 147.355433 -250.832414) (xy 147.405033 -250.806913)
			(xy 147.457817 -250.788906) (xy 147.51266 -250.778776) (xy 147.568394 -250.776739) (xy 147.623831 -250.782839)
			(xy 147.677788 -250.796945) (xy 147.729117 -250.818757) (xy 147.776723 -250.847811) (xy 147.819591 -250.883486)
			(xy 147.856808 -250.925023) (xy 147.887581 -250.971536) (xy 147.911253 -251.022033) (xy 147.927321 -251.07544)
			(xy 147.935441 -251.130616) (xy 147.93595 -251.158502) (xy 148.188424 -251.158502) (xy 148.192495 -251.10288)
			(xy 148.204621 -251.048443) (xy 148.224544 -250.996352) (xy 148.25184 -250.947717) (xy 148.285926 -250.903574)
			(xy 148.326075 -250.864865) (xy 148.371433 -250.832414) (xy 148.421033 -250.806913) (xy 148.473817 -250.788906)
			(xy 148.52866 -250.778776) (xy 148.584394 -250.776739) (xy 148.639831 -250.782839) (xy 148.693788 -250.796945)
			(xy 148.745117 -250.818757) (xy 148.792723 -250.847811) (xy 148.835591 -250.883486) (xy 148.872808 -250.925023)
			(xy 148.903581 -250.971536) (xy 148.927253 -251.022033) (xy 148.943321 -251.07544) (xy 148.951441 -251.130616)
			(xy 148.95195 -251.158502) (xy 149.204424 -251.158502) (xy 149.208495 -251.10288) (xy 149.220621 -251.048443)
			(xy 149.240544 -250.996352) (xy 149.26784 -250.947717) (xy 149.301926 -250.903574) (xy 149.342075 -250.864865)
			(xy 149.387433 -250.832414) (xy 149.437033 -250.806913) (xy 149.489817 -250.788906) (xy 149.54466 -250.778776)
			(xy 149.600394 -250.776739) (xy 149.655831 -250.782839) (xy 149.709788 -250.796945) (xy 149.761117 -250.818757)
			(xy 149.808723 -250.847811) (xy 149.851591 -250.883486) (xy 149.888808 -250.925023) (xy 149.919581 -250.971536)
			(xy 149.943253 -251.022033) (xy 149.959321 -251.07544) (xy 149.967441 -251.130616) (xy 149.96795 -251.158502)
			(xy 150.220424 -251.158502) (xy 150.224495 -251.10288) (xy 150.236621 -251.048443) (xy 150.256544 -250.996352)
			(xy 150.28384 -250.947717) (xy 150.317926 -250.903574) (xy 150.358075 -250.864865) (xy 150.403433 -250.832414)
			(xy 150.453033 -250.806913) (xy 150.505817 -250.788906) (xy 150.56066 -250.778776) (xy 150.616394 -250.776739)
			(xy 150.671831 -250.782839) (xy 150.725788 -250.796945) (xy 150.777117 -250.818757) (xy 150.824723 -250.847811)
			(xy 150.867591 -250.883486) (xy 150.904808 -250.925023) (xy 150.935581 -250.971536) (xy 150.959253 -251.022033)
			(xy 150.975321 -251.07544) (xy 150.983441 -251.130616) (xy 150.98395 -251.158502) (xy 151.236424 -251.158502)
			(xy 151.240495 -251.10288) (xy 151.252621 -251.048443) (xy 151.272544 -250.996352) (xy 151.29984 -250.947717)
			(xy 151.333926 -250.903574) (xy 151.374075 -250.864865) (xy 151.419433 -250.832414) (xy 151.469033 -250.806913)
			(xy 151.521817 -250.788906) (xy 151.57666 -250.778776) (xy 151.632394 -250.776739) (xy 151.687831 -250.782839)
			(xy 151.741788 -250.796945) (xy 151.793117 -250.818757) (xy 151.840723 -250.847811) (xy 151.883591 -250.883486)
			(xy 151.920808 -250.925023) (xy 151.951581 -250.971536) (xy 151.975253 -251.022033) (xy 151.991321 -251.07544)
			(xy 151.999441 -251.130616) (xy 151.99995 -251.158502) (xy 152.252424 -251.158502) (xy 152.256495 -251.10288)
			(xy 152.268621 -251.048443) (xy 152.288544 -250.996352) (xy 152.31584 -250.947717) (xy 152.349926 -250.903574)
			(xy 152.390075 -250.864865) (xy 152.435433 -250.832414) (xy 152.485033 -250.806913) (xy 152.537817 -250.788906)
			(xy 152.59266 -250.778776) (xy 152.648394 -250.776739) (xy 152.703831 -250.782839) (xy 152.757788 -250.796945)
			(xy 152.809117 -250.818757) (xy 152.856723 -250.847811) (xy 152.899591 -250.883486) (xy 152.936808 -250.925023)
			(xy 152.967581 -250.971536) (xy 152.991253 -251.022033) (xy 153.007321 -251.07544) (xy 153.015441 -251.130616)
			(xy 153.01595 -251.158502) (xy 153.268424 -251.158502) (xy 153.272495 -251.10288) (xy 153.284621 -251.048443)
			(xy 153.304544 -250.996352) (xy 153.33184 -250.947717) (xy 153.365926 -250.903574) (xy 153.406075 -250.864865)
			(xy 153.451433 -250.832414) (xy 153.501033 -250.806913) (xy 153.553817 -250.788906) (xy 153.60866 -250.778776)
			(xy 153.664394 -250.776739) (xy 153.719831 -250.782839) (xy 153.773788 -250.796945) (xy 153.825117 -250.818757)
			(xy 153.872723 -250.847811) (xy 153.915591 -250.883486) (xy 153.952808 -250.925023) (xy 153.983581 -250.971536)
			(xy 154.007253 -251.022033) (xy 154.023321 -251.07544) (xy 154.031441 -251.130616) (xy 154.03195 -251.158502)
			(xy 154.284424 -251.158502) (xy 154.288495 -251.10288) (xy 154.300621 -251.048443) (xy 154.320544 -250.996352)
			(xy 154.34784 -250.947717) (xy 154.381926 -250.903574) (xy 154.422075 -250.864865) (xy 154.467433 -250.832414)
			(xy 154.517033 -250.806913) (xy 154.569817 -250.788906) (xy 154.62466 -250.778776) (xy 154.680394 -250.776739)
			(xy 154.735831 -250.782839) (xy 154.789788 -250.796945) (xy 154.841117 -250.818757) (xy 154.888723 -250.847811)
			(xy 154.931591 -250.883486) (xy 154.968808 -250.925023) (xy 154.999581 -250.971536) (xy 155.023253 -251.022033)
			(xy 155.039321 -251.07544) (xy 155.047441 -251.130616) (xy 155.04795 -251.158502) (xy 156.316424 -251.158502)
			(xy 156.320495 -251.10288) (xy 156.332621 -251.048443) (xy 156.352544 -250.996352) (xy 156.37984 -250.947717)
			(xy 156.413926 -250.903574) (xy 156.454075 -250.864865) (xy 156.499433 -250.832414) (xy 156.549033 -250.806913)
			(xy 156.601817 -250.788906) (xy 156.65666 -250.778776) (xy 156.712394 -250.776739) (xy 156.767831 -250.782839)
			(xy 156.821788 -250.796945) (xy 156.873117 -250.818757) (xy 156.920723 -250.847811) (xy 156.963591 -250.883486)
			(xy 157.000808 -250.925023) (xy 157.031581 -250.971536) (xy 157.055253 -251.022033) (xy 157.071321 -251.07544)
			(xy 157.079441 -251.130616) (xy 157.07995 -251.158502) (xy 157.079441 -251.186388) (xy 157.071321 -251.241564)
			(xy 157.055253 -251.294971) (xy 157.031581 -251.345468) (xy 157.000808 -251.391981) (xy 156.963591 -251.433518)
			(xy 156.920723 -251.469193) (xy 156.873117 -251.498247) (xy 156.821788 -251.520059) (xy 156.767831 -251.534165)
			(xy 156.712394 -251.540265) (xy 156.65666 -251.538228) (xy 156.601817 -251.528098) (xy 156.549033 -251.510091)
			(xy 156.499433 -251.48459) (xy 156.454075 -251.452139) (xy 156.413926 -251.41343) (xy 156.37984 -251.369287)
			(xy 156.352544 -251.320652) (xy 156.332621 -251.268561) (xy 156.320495 -251.214124) (xy 156.316424 -251.158502)
			(xy 155.04795 -251.158502) (xy 155.047441 -251.186388) (xy 155.039321 -251.241564) (xy 155.023253 -251.294971)
			(xy 154.999581 -251.345468) (xy 154.968808 -251.391981) (xy 154.931591 -251.433518) (xy 154.888723 -251.469193)
			(xy 154.841117 -251.498247) (xy 154.789788 -251.520059) (xy 154.735831 -251.534165) (xy 154.680394 -251.540265)
			(xy 154.62466 -251.538228) (xy 154.569817 -251.528098) (xy 154.517033 -251.510091) (xy 154.467433 -251.48459)
			(xy 154.422075 -251.452139) (xy 154.381926 -251.41343) (xy 154.34784 -251.369287) (xy 154.320544 -251.320652)
			(xy 154.300621 -251.268561) (xy 154.288495 -251.214124) (xy 154.284424 -251.158502) (xy 154.03195 -251.158502)
			(xy 154.031441 -251.186388) (xy 154.023321 -251.241564) (xy 154.007253 -251.294971) (xy 153.983581 -251.345468)
			(xy 153.952808 -251.391981) (xy 153.915591 -251.433518) (xy 153.872723 -251.469193) (xy 153.825117 -251.498247)
			(xy 153.773788 -251.520059) (xy 153.719831 -251.534165) (xy 153.664394 -251.540265) (xy 153.60866 -251.538228)
			(xy 153.553817 -251.528098) (xy 153.501033 -251.510091) (xy 153.451433 -251.48459) (xy 153.406075 -251.452139)
			(xy 153.365926 -251.41343) (xy 153.33184 -251.369287) (xy 153.304544 -251.320652) (xy 153.284621 -251.268561)
			(xy 153.272495 -251.214124) (xy 153.268424 -251.158502) (xy 153.01595 -251.158502) (xy 153.015441 -251.186388)
			(xy 153.007321 -251.241564) (xy 152.991253 -251.294971) (xy 152.967581 -251.345468) (xy 152.936808 -251.391981)
			(xy 152.899591 -251.433518) (xy 152.856723 -251.469193) (xy 152.809117 -251.498247) (xy 152.757788 -251.520059)
			(xy 152.703831 -251.534165) (xy 152.648394 -251.540265) (xy 152.59266 -251.538228) (xy 152.537817 -251.528098)
			(xy 152.485033 -251.510091) (xy 152.435433 -251.48459) (xy 152.390075 -251.452139) (xy 152.349926 -251.41343)
			(xy 152.31584 -251.369287) (xy 152.288544 -251.320652) (xy 152.268621 -251.268561) (xy 152.256495 -251.214124)
			(xy 152.252424 -251.158502) (xy 151.99995 -251.158502) (xy 151.999441 -251.186388) (xy 151.991321 -251.241564)
			(xy 151.975253 -251.294971) (xy 151.951581 -251.345468) (xy 151.920808 -251.391981) (xy 151.883591 -251.433518)
			(xy 151.840723 -251.469193) (xy 151.793117 -251.498247) (xy 151.741788 -251.520059) (xy 151.687831 -251.534165)
			(xy 151.632394 -251.540265) (xy 151.57666 -251.538228) (xy 151.521817 -251.528098) (xy 151.469033 -251.510091)
			(xy 151.419433 -251.48459) (xy 151.374075 -251.452139) (xy 151.333926 -251.41343) (xy 151.29984 -251.369287)
			(xy 151.272544 -251.320652) (xy 151.252621 -251.268561) (xy 151.240495 -251.214124) (xy 151.236424 -251.158502)
			(xy 150.98395 -251.158502) (xy 150.983441 -251.186388) (xy 150.975321 -251.241564) (xy 150.959253 -251.294971)
			(xy 150.935581 -251.345468) (xy 150.904808 -251.391981) (xy 150.867591 -251.433518) (xy 150.824723 -251.469193)
			(xy 150.777117 -251.498247) (xy 150.725788 -251.520059) (xy 150.671831 -251.534165) (xy 150.616394 -251.540265)
			(xy 150.56066 -251.538228) (xy 150.505817 -251.528098) (xy 150.453033 -251.510091) (xy 150.403433 -251.48459)
			(xy 150.358075 -251.452139) (xy 150.317926 -251.41343) (xy 150.28384 -251.369287) (xy 150.256544 -251.320652)
			(xy 150.236621 -251.268561) (xy 150.224495 -251.214124) (xy 150.220424 -251.158502) (xy 149.96795 -251.158502)
			(xy 149.967441 -251.186388) (xy 149.959321 -251.241564) (xy 149.943253 -251.294971) (xy 149.919581 -251.345468)
			(xy 149.888808 -251.391981) (xy 149.851591 -251.433518) (xy 149.808723 -251.469193) (xy 149.761117 -251.498247)
			(xy 149.709788 -251.520059) (xy 149.655831 -251.534165) (xy 149.600394 -251.540265) (xy 149.54466 -251.538228)
			(xy 149.489817 -251.528098) (xy 149.437033 -251.510091) (xy 149.387433 -251.48459) (xy 149.342075 -251.452139)
			(xy 149.301926 -251.41343) (xy 149.26784 -251.369287) (xy 149.240544 -251.320652) (xy 149.220621 -251.268561)
			(xy 149.208495 -251.214124) (xy 149.204424 -251.158502) (xy 148.95195 -251.158502) (xy 148.951441 -251.186388)
			(xy 148.943321 -251.241564) (xy 148.927253 -251.294971) (xy 148.903581 -251.345468) (xy 148.872808 -251.391981)
			(xy 148.835591 -251.433518) (xy 148.792723 -251.469193) (xy 148.745117 -251.498247) (xy 148.693788 -251.520059)
			(xy 148.639831 -251.534165) (xy 148.584394 -251.540265) (xy 148.52866 -251.538228) (xy 148.473817 -251.528098)
			(xy 148.421033 -251.510091) (xy 148.371433 -251.48459) (xy 148.326075 -251.452139) (xy 148.285926 -251.41343)
			(xy 148.25184 -251.369287) (xy 148.224544 -251.320652) (xy 148.204621 -251.268561) (xy 148.192495 -251.214124)
			(xy 148.188424 -251.158502) (xy 147.93595 -251.158502) (xy 147.935441 -251.186388) (xy 147.927321 -251.241564)
			(xy 147.911253 -251.294971) (xy 147.887581 -251.345468) (xy 147.856808 -251.391981) (xy 147.819591 -251.433518)
			(xy 147.776723 -251.469193) (xy 147.729117 -251.498247) (xy 147.677788 -251.520059) (xy 147.623831 -251.534165)
			(xy 147.568394 -251.540265) (xy 147.51266 -251.538228) (xy 147.457817 -251.528098) (xy 147.405033 -251.510091)
			(xy 147.355433 -251.48459) (xy 147.310075 -251.452139) (xy 147.269926 -251.41343) (xy 147.23584 -251.369287)
			(xy 147.208544 -251.320652) (xy 147.188621 -251.268561) (xy 147.176495 -251.214124) (xy 147.172424 -251.158502)
			(xy 146.91995 -251.158502) (xy 146.919441 -251.186388) (xy 146.911321 -251.241564) (xy 146.895253 -251.294971)
			(xy 146.871581 -251.345468) (xy 146.840808 -251.391981) (xy 146.803591 -251.433518) (xy 146.760723 -251.469193)
			(xy 146.713117 -251.498247) (xy 146.661788 -251.520059) (xy 146.607831 -251.534165) (xy 146.552394 -251.540265)
			(xy 146.49666 -251.538228) (xy 146.441817 -251.528098) (xy 146.389033 -251.510091) (xy 146.339433 -251.48459)
			(xy 146.294075 -251.452139) (xy 146.253926 -251.41343) (xy 146.21984 -251.369287) (xy 146.192544 -251.320652)
			(xy 146.172621 -251.268561) (xy 146.160495 -251.214124) (xy 146.156424 -251.158502) (xy 145.90395 -251.158502)
			(xy 145.903441 -251.186388) (xy 145.895321 -251.241564) (xy 145.879253 -251.294971) (xy 145.855581 -251.345468)
			(xy 145.824808 -251.391981) (xy 145.787591 -251.433518) (xy 145.744723 -251.469193) (xy 145.697117 -251.498247)
			(xy 145.645788 -251.520059) (xy 145.591831 -251.534165) (xy 145.536394 -251.540265) (xy 145.48066 -251.538228)
			(xy 145.425817 -251.528098) (xy 145.373033 -251.510091) (xy 145.323433 -251.48459) (xy 145.278075 -251.452139)
			(xy 145.237926 -251.41343) (xy 145.20384 -251.369287) (xy 145.176544 -251.320652) (xy 145.156621 -251.268561)
			(xy 145.144495 -251.214124) (xy 145.140424 -251.158502) (xy 144.88795 -251.158502) (xy 144.887441 -251.186388)
			(xy 144.879321 -251.241564) (xy 144.863253 -251.294971) (xy 144.839581 -251.345468) (xy 144.808808 -251.391981)
			(xy 144.771591 -251.433518) (xy 144.728723 -251.469193) (xy 144.681117 -251.498247) (xy 144.629788 -251.520059)
			(xy 144.575831 -251.534165) (xy 144.520394 -251.540265) (xy 144.46466 -251.538228) (xy 144.409817 -251.528098)
			(xy 144.357033 -251.510091) (xy 144.307433 -251.48459) (xy 144.262075 -251.452139) (xy 144.221926 -251.41343)
			(xy 144.18784 -251.369287) (xy 144.160544 -251.320652) (xy 144.140621 -251.268561) (xy 144.128495 -251.214124)
			(xy 144.124424 -251.158502) (xy 143.87195 -251.158502) (xy 143.871441 -251.186388) (xy 143.863321 -251.241564)
			(xy 143.847253 -251.294971) (xy 143.823581 -251.345468) (xy 143.792808 -251.391981) (xy 143.755591 -251.433518)
			(xy 143.712723 -251.469193) (xy 143.665117 -251.498247) (xy 143.613788 -251.520059) (xy 143.559831 -251.534165)
			(xy 143.504394 -251.540265) (xy 143.44866 -251.538228) (xy 143.393817 -251.528098) (xy 143.341033 -251.510091)
			(xy 143.291433 -251.48459) (xy 143.246075 -251.452139) (xy 143.205926 -251.41343) (xy 143.17184 -251.369287)
			(xy 143.144544 -251.320652) (xy 143.124621 -251.268561) (xy 143.112495 -251.214124) (xy 143.108424 -251.158502)
			(xy 142.85595 -251.158502) (xy 142.855441 -251.186388) (xy 142.847321 -251.241564) (xy 142.831253 -251.294971)
			(xy 142.807581 -251.345468) (xy 142.776808 -251.391981) (xy 142.739591 -251.433518) (xy 142.696723 -251.469193)
			(xy 142.649117 -251.498247) (xy 142.597788 -251.520059) (xy 142.543831 -251.534165) (xy 142.488394 -251.540265)
			(xy 142.43266 -251.538228) (xy 142.377817 -251.528098) (xy 142.325033 -251.510091) (xy 142.275433 -251.48459)
			(xy 142.230075 -251.452139) (xy 142.189926 -251.41343) (xy 142.15584 -251.369287) (xy 142.128544 -251.320652)
			(xy 142.108621 -251.268561) (xy 142.096495 -251.214124) (xy 142.092424 -251.158502) (xy 141.83995 -251.158502)
			(xy 141.839441 -251.186388) (xy 141.831321 -251.241564) (xy 141.815253 -251.294971) (xy 141.791581 -251.345468)
			(xy 141.760808 -251.391981) (xy 141.723591 -251.433518) (xy 141.680723 -251.469193) (xy 141.633117 -251.498247)
			(xy 141.581788 -251.520059) (xy 141.527831 -251.534165) (xy 141.472394 -251.540265) (xy 141.41666 -251.538228)
			(xy 141.361817 -251.528098) (xy 141.309033 -251.510091) (xy 141.259433 -251.48459) (xy 141.214075 -251.452139)
			(xy 141.173926 -251.41343) (xy 141.13984 -251.369287) (xy 141.112544 -251.320652) (xy 141.092621 -251.268561)
			(xy 141.080495 -251.214124) (xy 141.076424 -251.158502) (xy 140.82395 -251.158502) (xy 140.823441 -251.186388)
			(xy 140.815321 -251.241564) (xy 140.799253 -251.294971) (xy 140.775581 -251.345468) (xy 140.744808 -251.391981)
			(xy 140.707591 -251.433518) (xy 140.664723 -251.469193) (xy 140.617117 -251.498247) (xy 140.565788 -251.520059)
			(xy 140.511831 -251.534165) (xy 140.456394 -251.540265) (xy 140.40066 -251.538228) (xy 140.345817 -251.528098)
			(xy 140.293033 -251.510091) (xy 140.243433 -251.48459) (xy 140.198075 -251.452139) (xy 140.157926 -251.41343)
			(xy 140.12384 -251.369287) (xy 140.096544 -251.320652) (xy 140.076621 -251.268561) (xy 140.064495 -251.214124)
			(xy 140.060424 -251.158502) (xy 139.86764 -251.158502) (xy 139.86764 -253.273052) (xy 139.86808 -253.28312)
			(xy 139.875789 -253.301718) (xy 139.882626 -253.30912) (xy 140.029922 -253.45644) (xy 155.300424 -253.45644)
			(xy 155.304495 -253.400818) (xy 155.316621 -253.346381) (xy 155.336544 -253.29429) (xy 155.36384 -253.245655)
			(xy 155.397926 -253.201512) (xy 155.438075 -253.162803) (xy 155.483433 -253.130352) (xy 155.533033 -253.104851)
			(xy 155.585817 -253.086844) (xy 155.64066 -253.076714) (xy 155.696394 -253.074677) (xy 155.751831 -253.080777)
			(xy 155.805788 -253.094883) (xy 155.857117 -253.116695) (xy 155.904723 -253.145749) (xy 155.947591 -253.181424)
			(xy 155.984808 -253.222961) (xy 156.015581 -253.269474) (xy 156.039253 -253.319971) (xy 156.055321 -253.373378)
			(xy 156.063441 -253.428554) (xy 156.06395 -253.45644) (xy 156.063441 -253.484326) (xy 156.055321 -253.539502)
			(xy 156.039253 -253.592909) (xy 156.015581 -253.643406) (xy 155.984808 -253.689919) (xy 155.947591 -253.731456)
			(xy 155.904723 -253.767131) (xy 155.857117 -253.796185) (xy 155.805788 -253.817997) (xy 155.751831 -253.832103)
			(xy 155.696394 -253.838203) (xy 155.64066 -253.836166) (xy 155.585817 -253.826036) (xy 155.533033 -253.808029)
			(xy 155.483433 -253.782528) (xy 155.438075 -253.750077) (xy 155.397926 -253.711368) (xy 155.36384 -253.667225)
			(xy 155.336544 -253.61859) (xy 155.316621 -253.566499) (xy 155.304495 -253.512062) (xy 155.300424 -253.45644)
			(xy 140.029922 -253.45644) (xy 141.410436 -254.837184) (xy 141.433599 -254.861083) (xy 141.474103 -254.913896)
			(xy 141.50737 -254.971543) (xy 141.532831 -255.033037) (xy 141.550051 -255.097328) (xy 141.558736 -255.163316)
			(xy 141.55928 -255.196594) (xy 141.55928 -255.979676) (xy 141.559926 -255.990995) (xy 141.569678 -256.01143)
			(xy 141.578076 -256.019046) (xy 141.648434 -256.076196) (xy 141.670786 -256.081276) (xy 141.681962 -256.07899)
			(xy 141.701295 -256.075182) (xy 141.740491 -256.071108) (xy 141.760194 -256.070862) (xy 141.760448 -256.070862)
			(xy 141.786764 -256.071278) (xy 141.838896 -256.07852) (xy 141.88954 -256.092848) (xy 141.937739 -256.11399)
			(xy 141.982581 -256.141546) (xy 142.023218 -256.174995) (xy 142.041372 -256.194052) (xy 142.048909 -256.201436)
			(xy 142.068177 -256.209972) (xy 142.07871 -256.210562) (xy 142.153386 -256.210562) (xy 142.163938 -256.21005)
			(xy 142.183234 -256.201504) (xy 142.190724 -256.194052) (xy 142.208865 -256.174983) (xy 142.249499 -256.141529)
			(xy 142.294343 -256.113973) (xy 142.342546 -256.092837) (xy 142.393196 -256.078522) (xy 142.445331 -256.0713)
			(xy 142.471648 -256.070862) (xy 142.498895 -256.071411) (xy 142.552833 -256.079173) (xy 142.605118 -256.094531)
			(xy 142.654685 -256.117173) (xy 142.700526 -256.146638) (xy 142.741707 -256.182327) (xy 142.777391 -256.223513)
			(xy 142.80685 -256.269357) (xy 142.829486 -256.318927) (xy 142.844837 -256.371214) (xy 142.852592 -256.425153)
			(xy 142.852592 -256.479647) (xy 142.844837 -256.533586) (xy 142.829486 -256.585873) (xy 142.80685 -256.635443)
			(xy 142.777391 -256.681287) (xy 142.741707 -256.722473) (xy 142.700526 -256.758162) (xy 142.654685 -256.787627)
			(xy 142.605118 -256.810269) (xy 142.552833 -256.825627) (xy 142.498895 -256.833389) (xy 142.471648 -256.833878)
			(xy 142.445333 -256.833452) (xy 142.393202 -256.82621) (xy 142.342558 -256.811883) (xy 142.294359 -256.790743)
			(xy 142.249517 -256.763189) (xy 142.208879 -256.729743) (xy 142.190724 -256.710688) (xy 142.183197 -256.703293)
			(xy 142.163921 -256.694765) (xy 142.153386 -256.694178) (xy 142.07871 -256.694178) (xy 142.06816 -256.694705)
			(xy 142.048865 -256.703242) (xy 142.041372 -256.710688) (xy 142.023221 -256.729748) (xy 141.98259 -256.763205)
			(xy 141.937749 -256.790764) (xy 141.889548 -256.811902) (xy 141.838899 -256.826218) (xy 141.786764 -256.833441)
			(xy 141.760448 -256.833878) (xy 141.760194 -256.833878) (xy 141.740492 -256.833611) (xy 141.701298 -256.829539)
			(xy 141.681962 -256.82575) (xy 141.670786 -256.823464) (xy 141.648434 -256.828544) (xy 141.578076 -256.885694)
			(xy 141.569644 -256.893285) (xy 141.559886 -256.913734) (xy 141.55928 -256.925064) (xy 141.55928 -257.137916)
			(xy 150.396194 -257.137916) (xy 150.396746 -257.108534) (xy 150.405774 -257.050468) (xy 150.423604 -256.994474)
			(xy 150.449813 -256.941879) (xy 150.483782 -256.893927) (xy 150.524705 -256.851754) (xy 150.547832 -256.833624)
			(xy 150.556753 -256.82614) (xy 150.567214 -256.805369) (xy 150.567898 -256.793746) (xy 150.569168 -256.701798)
			(xy 150.559262 -256.680716) (xy 150.550118 -256.67335) (xy 150.528267 -256.655147) (xy 150.489727 -256.613328)
			(xy 150.45782 -256.566252) (xy 150.433253 -256.514962) (xy 150.41657 -256.460593) (xy 150.408142 -256.404351)
			(xy 150.407624 -256.375916) (xy 150.40811 -256.348665) (xy 150.415866 -256.294717) (xy 150.431221 -256.242422)
			(xy 150.453863 -256.192845) (xy 150.483329 -256.146995) (xy 150.51902 -256.105804) (xy 150.560211 -256.070113)
			(xy 150.606061 -256.040647) (xy 150.655638 -256.018005) (xy 150.707933 -256.00265) (xy 150.761881 -255.994894)
			(xy 150.816383 -255.994894) (xy 150.870331 -256.00265) (xy 150.922626 -256.018005) (xy 150.972203 -256.040647)
			(xy 151.018053 -256.070113) (xy 151.059244 -256.105804) (xy 151.094935 -256.146995) (xy 151.124401 -256.192845)
			(xy 151.147043 -256.242422) (xy 151.162398 -256.294717) (xy 151.170154 -256.348665) (xy 151.17064 -256.375916)
			(xy 151.170098 -256.405298) (xy 151.161066 -256.463364) (xy 151.143233 -256.519357) (xy 151.117022 -256.571952)
			(xy 151.083052 -256.619904) (xy 151.042129 -256.662077) (xy 151.019002 -256.680208) (xy 151.010056 -256.687665)
			(xy 150.999611 -256.708457) (xy 150.998936 -256.720086) (xy 150.997666 -256.812034) (xy 151.007572 -256.833116)
			(xy 151.016716 -256.840482) (xy 151.038541 -256.858714) (xy 151.077082 -256.900528) (xy 151.108991 -256.947598)
			(xy 151.133562 -256.998883) (xy 151.15025 -257.053245) (xy 151.158687 -257.109483) (xy 151.15921 -257.137916)
			(xy 151.792684 -257.137916) (xy 151.796755 -257.082294) (xy 151.808881 -257.027857) (xy 151.828804 -256.975766)
			(xy 151.8561 -256.927131) (xy 151.890186 -256.882988) (xy 151.930335 -256.844279) (xy 151.975693 -256.811828)
			(xy 152.025293 -256.786327) (xy 152.078077 -256.76832) (xy 152.13292 -256.75819) (xy 152.188654 -256.756153)
			(xy 152.244091 -256.762253) (xy 152.298048 -256.776359) (xy 152.349377 -256.798171) (xy 152.396983 -256.827225)
			(xy 152.439851 -256.8629) (xy 152.477068 -256.904437) (xy 152.507841 -256.95095) (xy 152.531513 -257.001447)
			(xy 152.538947 -257.026156) (xy 156.812994 -257.026156) (xy 156.817065 -256.970534) (xy 156.829191 -256.916097)
			(xy 156.849114 -256.864006) (xy 156.87641 -256.815371) (xy 156.910496 -256.771228) (xy 156.950645 -256.732519)
			(xy 156.996003 -256.700068) (xy 157.045603 -256.674567) (xy 157.098387 -256.65656) (xy 157.15323 -256.64643)
			(xy 157.208964 -256.644393) (xy 157.264401 -256.650493) (xy 157.318358 -256.664599) (xy 157.369687 -256.686411)
			(xy 157.417293 -256.715465) (xy 157.460161 -256.75114) (xy 157.497378 -256.792677) (xy 157.528151 -256.83919)
			(xy 157.551823 -256.889687) (xy 157.567891 -256.943094) (xy 157.576011 -256.99827) (xy 157.57652 -257.026156)
			(xy 157.576011 -257.054042) (xy 157.567891 -257.109218) (xy 157.551823 -257.162625) (xy 157.528151 -257.213122)
			(xy 157.497378 -257.259635) (xy 157.460161 -257.301172) (xy 157.417293 -257.336847) (xy 157.369687 -257.365901)
			(xy 157.318358 -257.387713) (xy 157.264401 -257.401819) (xy 157.208964 -257.407919) (xy 157.15323 -257.405882)
			(xy 157.098387 -257.395752) (xy 157.045603 -257.377745) (xy 156.996003 -257.352244) (xy 156.950645 -257.319793)
			(xy 156.910496 -257.281084) (xy 156.87641 -257.236941) (xy 156.849114 -257.188306) (xy 156.829191 -257.136215)
			(xy 156.817065 -257.081778) (xy 156.812994 -257.026156) (xy 152.538947 -257.026156) (xy 152.547581 -257.054854)
			(xy 152.555701 -257.11003) (xy 152.55621 -257.137916) (xy 152.555701 -257.165802) (xy 152.547581 -257.220978)
			(xy 152.531513 -257.274385) (xy 152.507841 -257.324882) (xy 152.477068 -257.371395) (xy 152.439851 -257.412932)
			(xy 152.396983 -257.448607) (xy 152.349377 -257.477661) (xy 152.298048 -257.499473) (xy 152.244091 -257.513579)
			(xy 152.188654 -257.519679) (xy 152.13292 -257.517642) (xy 152.078077 -257.507512) (xy 152.025293 -257.489505)
			(xy 151.975693 -257.464004) (xy 151.930335 -257.431553) (xy 151.890186 -257.392844) (xy 151.8561 -257.348701)
			(xy 151.828804 -257.300066) (xy 151.808881 -257.247975) (xy 151.796755 -257.193538) (xy 151.792684 -257.137916)
			(xy 151.15921 -257.137916) (xy 151.158724 -257.165167) (xy 151.150968 -257.219115) (xy 151.135613 -257.27141)
			(xy 151.112971 -257.320987) (xy 151.083505 -257.366837) (xy 151.047814 -257.408028) (xy 151.006623 -257.443719)
			(xy 150.960773 -257.473185) (xy 150.911196 -257.495827) (xy 150.858901 -257.511182) (xy 150.804953 -257.518938)
			(xy 150.750451 -257.518938) (xy 150.696503 -257.511182) (xy 150.644208 -257.495827) (xy 150.594631 -257.473185)
			(xy 150.548781 -257.443719) (xy 150.50759 -257.408028) (xy 150.471899 -257.366837) (xy 150.442433 -257.320987)
			(xy 150.419791 -257.27141) (xy 150.404436 -257.219115) (xy 150.39668 -257.165167) (xy 150.396194 -257.137916)
			(xy 141.55928 -257.137916) (xy 141.55928 -258.274058) (xy 144.86966 -258.274058) (xy 144.873731 -258.218436)
			(xy 144.885857 -258.163999) (xy 144.90578 -258.111908) (xy 144.933076 -258.063273) (xy 144.967162 -258.01913)
			(xy 145.007311 -257.980421) (xy 145.052669 -257.94797) (xy 145.102269 -257.922469) (xy 145.155053 -257.904462)
			(xy 145.209896 -257.894332) (xy 145.26563 -257.892295) (xy 145.321067 -257.898395) (xy 145.375024 -257.912501)
			(xy 145.426353 -257.934313) (xy 145.473959 -257.963367) (xy 145.516827 -257.999042) (xy 145.554044 -258.040579)
			(xy 145.584817 -258.087092) (xy 145.608489 -258.137589) (xy 145.624557 -258.190996) (xy 145.632677 -258.246172)
			(xy 145.633186 -258.274058) (xy 146.354798 -258.274058) (xy 146.358869 -258.218436) (xy 146.370995 -258.163999)
			(xy 146.390918 -258.111908) (xy 146.418214 -258.063273) (xy 146.4523 -258.01913) (xy 146.492449 -257.980421)
			(xy 146.537807 -257.94797) (xy 146.587407 -257.922469) (xy 146.640191 -257.904462) (xy 146.695034 -257.894332)
			(xy 146.750768 -257.892295) (xy 146.806205 -257.898395) (xy 146.860162 -257.912501) (xy 146.911491 -257.934313)
			(xy 146.959097 -257.963367) (xy 147.001965 -257.999042) (xy 147.039182 -258.040579) (xy 147.069955 -258.087092)
			(xy 147.093627 -258.137589) (xy 147.109695 -258.190996) (xy 147.117815 -258.246172) (xy 147.118324 -258.274058)
			(xy 147.117815 -258.301944) (xy 147.109695 -258.35712) (xy 147.093627 -258.410527) (xy 147.069955 -258.461024)
			(xy 147.039182 -258.507537) (xy 147.001965 -258.549074) (xy 146.959097 -258.584749) (xy 146.911491 -258.613803)
			(xy 146.860162 -258.635615) (xy 146.806205 -258.649721) (xy 146.750768 -258.655821) (xy 146.695034 -258.653784)
			(xy 146.640191 -258.643654) (xy 146.587407 -258.625647) (xy 146.537807 -258.600146) (xy 146.492449 -258.567695)
			(xy 146.4523 -258.528986) (xy 146.418214 -258.484843) (xy 146.390918 -258.436208) (xy 146.370995 -258.384117)
			(xy 146.358869 -258.32968) (xy 146.354798 -258.274058) (xy 145.633186 -258.274058) (xy 145.632677 -258.301944)
			(xy 145.624557 -258.35712) (xy 145.608489 -258.410527) (xy 145.584817 -258.461024) (xy 145.554044 -258.507537)
			(xy 145.516827 -258.549074) (xy 145.473959 -258.584749) (xy 145.426353 -258.613803) (xy 145.375024 -258.635615)
			(xy 145.321067 -258.649721) (xy 145.26563 -258.655821) (xy 145.209896 -258.653784) (xy 145.155053 -258.643654)
			(xy 145.102269 -258.625647) (xy 145.052669 -258.600146) (xy 145.007311 -258.567695) (xy 144.967162 -258.528986)
			(xy 144.933076 -258.484843) (xy 144.90578 -258.436208) (xy 144.885857 -258.384117) (xy 144.873731 -258.32968)
			(xy 144.86966 -258.274058) (xy 141.55928 -258.274058) (xy 141.55928 -258.532884) (xy 141.558764 -258.566164)
			(xy 141.550087 -258.632157) (xy 141.532868 -258.696451) (xy 141.507401 -258.757946) (xy 141.474123 -258.81559)
			(xy 141.433602 -258.868395) (xy 141.410436 -258.892294) (xy 141.252194 -259.050536) (xy 141.22826 -259.073662)
			(xy 141.175454 -259.114169) (xy 141.117815 -259.147442) (xy 141.056328 -259.172909) (xy 140.992043 -259.190137)
			(xy 140.92606 -259.198831) (xy 140.892784 -259.19938) (xy 140.862061 -259.19896) (xy 140.801064 -259.191553)
			(xy 140.741404 -259.176851) (xy 140.683949 -259.155067) (xy 140.629539 -259.126518) (xy 140.578965 -259.091621)
			(xy 140.532965 -259.050884) (xy 140.492209 -259.0049) (xy 140.457291 -258.954341) (xy 140.42872 -258.899942)
			(xy 140.406911 -258.842497) (xy 140.392185 -258.782843) (xy 140.384753 -258.721848) (xy 140.384276 -258.691126)
			(xy 140.384787 -258.658436) (xy 140.393201 -258.593601) (xy 140.409855 -258.530378) (xy 140.434475 -258.469811)
			(xy 140.466654 -258.412898) (xy 140.505861 -258.360579) (xy 140.528294 -258.336796) (xy 140.534857 -258.329403)
			(xy 140.542308 -258.311111) (xy 140.542772 -258.301236) (xy 140.542772 -256.0066) (xy 140.542263 -255.996265)
			(xy 140.534172 -255.977245) (xy 140.519254 -255.962939) (xy 140.509752 -255.958848) (xy 140.405358 -255.919732)
			(xy 140.375132 -255.927352) (xy 140.364464 -255.939544) (xy 140.346287 -255.95968) (xy 140.305177 -255.995072)
			(xy 140.259468 -256.024283) (xy 140.21008 -256.046723) (xy 140.158012 -256.061939) (xy 140.104313 -256.069623)
			(xy 140.07719 -256.0701) (xy 140.049939 -256.06963) (xy 139.995991 -256.061872) (xy 139.943696 -256.046515)
			(xy 139.894119 -256.023873) (xy 139.848269 -255.994406) (xy 139.807079 -255.958714) (xy 139.771388 -255.917523)
			(xy 139.741922 -255.871672) (xy 139.719281 -255.822094) (xy 139.703926 -255.769799) (xy 139.69617 -255.715851)
			(xy 139.69617 -255.661349) (xy 139.703926 -255.607401) (xy 139.719281 -255.555106) (xy 139.741922 -255.505528)
			(xy 139.771388 -255.459677) (xy 139.807079 -255.418486) (xy 139.848269 -255.382794) (xy 139.894119 -255.353327)
			(xy 139.943696 -255.330685) (xy 139.995991 -255.315328) (xy 140.049939 -255.30757) (xy 140.07719 -255.307084)
			(xy 140.104414 -255.307597) (xy 140.158307 -255.315357) (xy 140.210552 -255.330693) (xy 140.260088 -255.353294)
			(xy 140.305913 -255.382701) (xy 140.347096 -255.418319) (xy 140.382802 -255.459425) (xy 140.412309 -255.505186)
			(xy 140.435017 -255.554673) (xy 140.443204 -255.580642) (xy 140.446655 -255.590474) (xy 140.459937 -255.606495)
			(xy 140.478486 -255.615928) (xy 140.499256 -255.617224) (xy 140.518834 -255.610168) (xy 140.534003 -255.595921)
			(xy 140.54227 -255.576823) (xy 140.542772 -255.566418) (xy 140.542772 -255.428242) (xy 140.542332 -255.418174)
			(xy 140.534622 -255.399576) (xy 140.527786 -255.392174) (xy 138.999722 -253.86411) (xy 138.976544 -253.840211)
			(xy 138.935979 -253.78742) (xy 138.902655 -253.729784) (xy 138.877143 -253.66829) (xy 138.859879 -253.603991)
			(xy 138.851159 -253.537988) (xy 138.850624 -253.5047) (xy 138.232368 -253.5047) (xy 138.242301 -253.537716)
			(xy 138.250421 -253.592892) (xy 138.25093 -253.620778) (xy 138.250421 -253.648664) (xy 138.242301 -253.70384)
			(xy 138.226233 -253.757247) (xy 138.202561 -253.807744) (xy 138.171788 -253.854257) (xy 138.134571 -253.895794)
			(xy 138.091703 -253.931469) (xy 138.044097 -253.960523) (xy 137.992768 -253.982335) (xy 137.938811 -253.996441)
			(xy 137.883374 -254.002541) (xy 137.82764 -254.000504) (xy 137.772797 -253.990374) (xy 137.720013 -253.972367)
			(xy 137.670413 -253.946866) (xy 137.625055 -253.914415) (xy 137.584906 -253.875706) (xy 137.55082 -253.831563)
			(xy 137.523524 -253.782928) (xy 137.503601 -253.730837) (xy 137.491475 -253.6764) (xy 137.487404 -253.620778)
			(xy 136.174447 -253.620778) (xy 136.175118 -253.622387) (xy 136.175496 -253.632462) (xy 136.175496 -254.44958)
			(xy 136.175496 -254.450088) (xy 136.175242 -254.46863) (xy 136.175236 -254.472692) (xy 136.176387 -254.480733)
			(xy 136.177528 -254.484632) (xy 136.179814 -254.490474) (xy 136.184386 -254.500634) (xy 136.190482 -254.505968)
			(xy 136.190482 -255.910588) (xy 137.976608 -255.910588) (xy 137.980679 -255.854966) (xy 137.992805 -255.800529)
			(xy 138.012728 -255.748438) (xy 138.040024 -255.699803) (xy 138.07411 -255.65566) (xy 138.114259 -255.616951)
			(xy 138.159617 -255.5845) (xy 138.209217 -255.558999) (xy 138.262001 -255.540992) (xy 138.316844 -255.530862)
			(xy 138.372578 -255.528825) (xy 138.428015 -255.534925) (xy 138.481972 -255.549031) (xy 138.533301 -255.570843)
			(xy 138.580907 -255.599897) (xy 138.623775 -255.635572) (xy 138.660992 -255.677109) (xy 138.691765 -255.723622)
			(xy 138.715437 -255.774119) (xy 138.731505 -255.827526) (xy 138.739625 -255.882702) (xy 138.740134 -255.910588)
			(xy 138.739625 -255.938474) (xy 138.731505 -255.99365) (xy 138.715437 -256.047057) (xy 138.691765 -256.097554)
			(xy 138.660992 -256.144067) (xy 138.623775 -256.185604) (xy 138.580907 -256.221279) (xy 138.533301 -256.250333)
			(xy 138.481972 -256.272145) (xy 138.428015 -256.286251) (xy 138.372578 -256.292351) (xy 138.316844 -256.290314)
			(xy 138.262001 -256.280184) (xy 138.209217 -256.262177) (xy 138.159617 -256.236676) (xy 138.114259 -256.204225)
			(xy 138.07411 -256.165516) (xy 138.040024 -256.121373) (xy 138.012728 -256.072738) (xy 137.992805 -256.020647)
			(xy 137.980679 -255.96621) (xy 137.976608 -255.910588) (xy 136.190482 -255.910588) (xy 136.190482 -257.474212)
			(xy 138.071858 -257.474212) (xy 138.075929 -257.41859) (xy 138.088055 -257.364153) (xy 138.107978 -257.312062)
			(xy 138.135274 -257.263427) (xy 138.16936 -257.219284) (xy 138.209509 -257.180575) (xy 138.254867 -257.148124)
			(xy 138.304467 -257.122623) (xy 138.357251 -257.104616) (xy 138.412094 -257.094486) (xy 138.467828 -257.092449)
			(xy 138.523265 -257.098549) (xy 138.577222 -257.112655) (xy 138.628551 -257.134467) (xy 138.676157 -257.163521)
			(xy 138.719025 -257.199196) (xy 138.756242 -257.240733) (xy 138.787015 -257.287246) (xy 138.810687 -257.337743)
			(xy 138.826755 -257.39115) (xy 138.834875 -257.446326) (xy 138.835384 -257.474212) (xy 138.834875 -257.502098)
			(xy 138.826755 -257.557274) (xy 138.810687 -257.610681) (xy 138.787015 -257.661178) (xy 138.756242 -257.707691)
			(xy 138.719025 -257.749228) (xy 138.676157 -257.784903) (xy 138.628551 -257.813957) (xy 138.577222 -257.835769)
			(xy 138.523265 -257.849875) (xy 138.467828 -257.855975) (xy 138.412094 -257.853938) (xy 138.357251 -257.843808)
			(xy 138.304467 -257.825801) (xy 138.254867 -257.8003) (xy 138.209509 -257.767849) (xy 138.16936 -257.72914)
			(xy 138.135274 -257.684997) (xy 138.107978 -257.636362) (xy 138.088055 -257.584271) (xy 138.075929 -257.529834)
			(xy 138.071858 -257.474212) (xy 136.190482 -257.474212) (xy 136.190482 -258.649978) (xy 139.02639 -258.649978)
			(xy 139.030461 -258.594356) (xy 139.042587 -258.539919) (xy 139.06251 -258.487828) (xy 139.089806 -258.439193)
			(xy 139.123892 -258.39505) (xy 139.164041 -258.356341) (xy 139.209399 -258.32389) (xy 139.258999 -258.298389)
			(xy 139.311783 -258.280382) (xy 139.366626 -258.270252) (xy 139.42236 -258.268215) (xy 139.477797 -258.274315)
			(xy 139.531754 -258.288421) (xy 139.583083 -258.310233) (xy 139.630689 -258.339287) (xy 139.673557 -258.374962)
			(xy 139.710774 -258.416499) (xy 139.741547 -258.463012) (xy 139.765219 -258.513509) (xy 139.781287 -258.566916)
			(xy 139.789407 -258.622092) (xy 139.789916 -258.649978) (xy 139.789407 -258.677864) (xy 139.781287 -258.73304)
			(xy 139.765219 -258.786447) (xy 139.741547 -258.836944) (xy 139.710774 -258.883457) (xy 139.673557 -258.924994)
			(xy 139.630689 -258.960669) (xy 139.583083 -258.989723) (xy 139.531754 -259.011535) (xy 139.477797 -259.025641)
			(xy 139.42236 -259.031741) (xy 139.366626 -259.029704) (xy 139.311783 -259.019574) (xy 139.258999 -259.001567)
			(xy 139.209399 -258.976066) (xy 139.164041 -258.943615) (xy 139.123892 -258.904906) (xy 139.089806 -258.860763)
			(xy 139.06251 -258.812128) (xy 139.042587 -258.760037) (xy 139.030461 -258.7056) (xy 139.02639 -258.649978)
			(xy 136.190482 -258.649978) (xy 136.190482 -259.888228) (xy 136.191244 -259.89661) (xy 136.192758 -259.904216)
			(xy 136.199741 -259.918052) (xy 136.20496 -259.923788) (xy 136.308846 -260.027674) (xy 138.191746 -260.027674)
			(xy 138.195817 -259.972052) (xy 138.207943 -259.917615) (xy 138.227866 -259.865524) (xy 138.255162 -259.816889)
			(xy 138.289248 -259.772746) (xy 138.329397 -259.734037) (xy 138.374755 -259.701586) (xy 138.424355 -259.676085)
			(xy 138.477139 -259.658078) (xy 138.531982 -259.647948) (xy 138.587716 -259.645911) (xy 138.643153 -259.652011)
			(xy 138.69711 -259.666117) (xy 138.748439 -259.687929) (xy 138.796045 -259.716983) (xy 138.838913 -259.752658)
			(xy 138.87613 -259.794195) (xy 138.906903 -259.840708) (xy 138.930575 -259.891205) (xy 138.946643 -259.944612)
			(xy 138.954763 -259.999788) (xy 138.955272 -260.027674) (xy 138.954763 -260.05556) (xy 138.95255 -260.0706)
			(xy 139.742924 -260.0706) (xy 139.746995 -260.014978) (xy 139.759121 -259.960541) (xy 139.779044 -259.90845)
			(xy 139.80634 -259.859815) (xy 139.840426 -259.815672) (xy 139.880575 -259.776963) (xy 139.925933 -259.744512)
			(xy 139.975533 -259.719011) (xy 140.028317 -259.701004) (xy 140.08316 -259.690874) (xy 140.138894 -259.688837)
			(xy 140.194331 -259.694937) (xy 140.248288 -259.709043) (xy 140.299617 -259.730855) (xy 140.347223 -259.759909)
			(xy 140.390091 -259.795584) (xy 140.427308 -259.837121) (xy 140.458081 -259.883634) (xy 140.481753 -259.934131)
			(xy 140.497821 -259.987538) (xy 140.505941 -260.042714) (xy 140.50645 -260.0706) (xy 140.505972 -260.096762)
			(xy 143.758918 -260.096762) (xy 143.762989 -260.04114) (xy 143.775115 -259.986703) (xy 143.795038 -259.934612)
			(xy 143.822334 -259.885977) (xy 143.85642 -259.841834) (xy 143.896569 -259.803125) (xy 143.941927 -259.770674)
			(xy 143.991527 -259.745173) (xy 144.044311 -259.727166) (xy 144.099154 -259.717036) (xy 144.154888 -259.714999)
			(xy 144.210325 -259.721099) (xy 144.264282 -259.735205) (xy 144.315611 -259.757017) (xy 144.363217 -259.786071)
			(xy 144.406085 -259.821746) (xy 144.443302 -259.863283) (xy 144.474075 -259.909796) (xy 144.497747 -259.960293)
			(xy 144.513815 -260.0137) (xy 144.521935 -260.068876) (xy 144.522444 -260.096762) (xy 144.521935 -260.124648)
			(xy 144.513815 -260.179824) (xy 144.497747 -260.233231) (xy 144.474075 -260.283728) (xy 144.443302 -260.330241)
			(xy 144.436067 -260.338316) (xy 150.396194 -260.338316) (xy 150.396746 -260.308934) (xy 150.405774 -260.250868)
			(xy 150.423604 -260.194874) (xy 150.449813 -260.142279) (xy 150.483782 -260.094327) (xy 150.524705 -260.052154)
			(xy 150.547832 -260.034024) (xy 150.556753 -260.02654) (xy 150.567214 -260.005769) (xy 150.567898 -259.994146)
			(xy 150.569168 -259.902198) (xy 150.559262 -259.881116) (xy 150.550118 -259.87375) (xy 150.528267 -259.855547)
			(xy 150.489727 -259.813728) (xy 150.45782 -259.766652) (xy 150.433253 -259.715362) (xy 150.41657 -259.660993)
			(xy 150.408142 -259.604751) (xy 150.407624 -259.576316) (xy 150.40811 -259.549065) (xy 150.415866 -259.495117)
			(xy 150.431221 -259.442822) (xy 150.453863 -259.393245) (xy 150.483329 -259.347395) (xy 150.51902 -259.306204)
			(xy 150.560211 -259.270513) (xy 150.606061 -259.241047) (xy 150.655638 -259.218405) (xy 150.707933 -259.20305)
			(xy 150.761881 -259.195294) (xy 150.816383 -259.195294) (xy 150.870331 -259.20305) (xy 150.922626 -259.218405)
			(xy 150.972203 -259.241047) (xy 151.018053 -259.270513) (xy 151.059244 -259.306204) (xy 151.094935 -259.347395)
			(xy 151.124401 -259.393245) (xy 151.147043 -259.442822) (xy 151.162398 -259.495117) (xy 151.170154 -259.549065)
			(xy 151.17064 -259.576316) (xy 151.170098 -259.605698) (xy 151.161066 -259.663764) (xy 151.143233 -259.719757)
			(xy 151.117022 -259.772352) (xy 151.083052 -259.820304) (xy 151.042129 -259.862477) (xy 151.019002 -259.880608)
			(xy 151.010056 -259.888065) (xy 150.999611 -259.908857) (xy 150.998936 -259.920486) (xy 150.997666 -260.012434)
			(xy 151.007572 -260.033516) (xy 151.016716 -260.040882) (xy 151.038541 -260.059114) (xy 151.077082 -260.100928)
			(xy 151.108991 -260.147998) (xy 151.133562 -260.199283) (xy 151.15025 -260.253645) (xy 151.158687 -260.309883)
			(xy 151.15921 -260.338316) (xy 151.792684 -260.338316) (xy 151.796755 -260.282694) (xy 151.808881 -260.228257)
			(xy 151.828804 -260.176166) (xy 151.8561 -260.127531) (xy 151.890186 -260.083388) (xy 151.930335 -260.044679)
			(xy 151.975693 -260.012228) (xy 152.025293 -259.986727) (xy 152.078077 -259.96872) (xy 152.13292 -259.95859)
			(xy 152.188654 -259.956553) (xy 152.244091 -259.962653) (xy 152.298048 -259.976759) (xy 152.349377 -259.998571)
			(xy 152.396983 -260.027625) (xy 152.439851 -260.0633) (xy 152.477068 -260.104837) (xy 152.507841 -260.15135)
			(xy 152.531513 -260.201847) (xy 152.547581 -260.255254) (xy 152.555701 -260.31043) (xy 152.55621 -260.338316)
			(xy 152.555701 -260.366202) (xy 152.547581 -260.421378) (xy 152.531513 -260.474785) (xy 152.507841 -260.525282)
			(xy 152.477068 -260.571795) (xy 152.439851 -260.613332) (xy 152.396983 -260.649007) (xy 152.349377 -260.678061)
			(xy 152.298048 -260.699873) (xy 152.244091 -260.713979) (xy 152.188654 -260.720079) (xy 152.13292 -260.718042)
			(xy 152.078077 -260.707912) (xy 152.025293 -260.689905) (xy 151.975693 -260.664404) (xy 151.930335 -260.631953)
			(xy 151.890186 -260.593244) (xy 151.8561 -260.549101) (xy 151.828804 -260.500466) (xy 151.808881 -260.448375)
			(xy 151.796755 -260.393938) (xy 151.792684 -260.338316) (xy 151.15921 -260.338316) (xy 151.158724 -260.365567)
			(xy 151.150968 -260.419515) (xy 151.135613 -260.47181) (xy 151.112971 -260.521387) (xy 151.083505 -260.567237)
			(xy 151.047814 -260.608428) (xy 151.006623 -260.644119) (xy 150.960773 -260.673585) (xy 150.911196 -260.696227)
			(xy 150.858901 -260.711582) (xy 150.804953 -260.719338) (xy 150.750451 -260.719338) (xy 150.696503 -260.711582)
			(xy 150.644208 -260.696227) (xy 150.594631 -260.673585) (xy 150.548781 -260.644119) (xy 150.50759 -260.608428)
			(xy 150.471899 -260.567237) (xy 150.442433 -260.521387) (xy 150.419791 -260.47181) (xy 150.404436 -260.419515)
			(xy 150.39668 -260.365567) (xy 150.396194 -260.338316) (xy 144.436067 -260.338316) (xy 144.406085 -260.371778)
			(xy 144.363217 -260.407453) (xy 144.315611 -260.436507) (xy 144.264282 -260.458319) (xy 144.210325 -260.472425)
			(xy 144.154888 -260.478525) (xy 144.099154 -260.476488) (xy 144.044311 -260.466358) (xy 143.991527 -260.448351)
			(xy 143.941927 -260.42285) (xy 143.896569 -260.390399) (xy 143.85642 -260.35169) (xy 143.822334 -260.307547)
			(xy 143.795038 -260.258912) (xy 143.775115 -260.206821) (xy 143.762989 -260.152384) (xy 143.758918 -260.096762)
			(xy 140.505972 -260.096762) (xy 140.505941 -260.098486) (xy 140.497821 -260.153662) (xy 140.481753 -260.207069)
			(xy 140.458081 -260.257566) (xy 140.427308 -260.304079) (xy 140.390091 -260.345616) (xy 140.347223 -260.381291)
			(xy 140.299617 -260.410345) (xy 140.248288 -260.432157) (xy 140.194331 -260.446263) (xy 140.138894 -260.452363)
			(xy 140.08316 -260.450326) (xy 140.028317 -260.440196) (xy 139.975533 -260.422189) (xy 139.925933 -260.396688)
			(xy 139.880575 -260.364237) (xy 139.840426 -260.325528) (xy 139.80634 -260.281385) (xy 139.779044 -260.23275)
			(xy 139.759121 -260.180659) (xy 139.746995 -260.126222) (xy 139.742924 -260.0706) (xy 138.95255 -260.0706)
			(xy 138.946643 -260.110736) (xy 138.930575 -260.164143) (xy 138.906903 -260.21464) (xy 138.87613 -260.261153)
			(xy 138.838913 -260.30269) (xy 138.796045 -260.338365) (xy 138.748439 -260.367419) (xy 138.69711 -260.389231)
			(xy 138.643153 -260.403337) (xy 138.587716 -260.409437) (xy 138.531982 -260.4074) (xy 138.477139 -260.39727)
			(xy 138.424355 -260.379263) (xy 138.374755 -260.353762) (xy 138.329397 -260.321311) (xy 138.289248 -260.282602)
			(xy 138.255162 -260.238459) (xy 138.227866 -260.189824) (xy 138.207943 -260.137733) (xy 138.195817 -260.083296)
			(xy 138.191746 -260.027674) (xy 136.308846 -260.027674) (xy 138.071422 -261.79025) (xy 141.61948 -261.79025)
			(xy 141.61948 -261.73575) (xy 141.627236 -261.681804) (xy 141.64259 -261.629512) (xy 141.665229 -261.579936)
			(xy 141.694693 -261.534087) (xy 141.730382 -261.492898) (xy 141.771569 -261.457206) (xy 141.817417 -261.42774)
			(xy 141.866991 -261.405097) (xy 141.919283 -261.38974) (xy 141.973228 -261.381981) (xy 142.000478 -261.381494)
			(xy 142.029396 -261.381992) (xy 142.08657 -261.39072) (xy 142.141771 -261.40798) (xy 142.193733 -261.433375)
			(xy 142.241266 -261.466324) (xy 142.28328 -261.506071) (xy 142.301468 -261.52856) (xy 142.309089 -261.537353)
			(xy 142.329979 -261.547542) (xy 142.3416 -261.548118) (xy 142.421356 -261.548118) (xy 142.432989 -261.54759)
			(xy 142.453898 -261.537393) (xy 142.461488 -261.52856) (xy 142.479676 -261.506074) (xy 142.521697 -261.466341)
			(xy 142.569233 -261.433403) (xy 142.621195 -261.408016) (xy 142.676393 -261.390759) (xy 142.733562 -261.38203)
			(xy 142.762478 -261.381494) (xy 142.788259 -261.381921) (xy 142.839351 -261.388863) (xy 142.889043 -261.402624)
			(xy 142.936429 -261.422951) (xy 142.980645 -261.449476) (xy 143.020886 -261.481715) (xy 143.056417 -261.51908)
			(xy 143.07185 -261.539736) (xy 143.078708 -261.549388) (xy 143.099282 -261.56031) (xy 143.19123 -261.563612)
			(xy 143.202886 -261.563532) (xy 143.224189 -261.554119) (xy 143.232124 -261.545578) (xy 143.250359 -261.524629)
			(xy 143.291834 -261.487692) (xy 143.338226 -261.457159) (xy 143.388556 -261.433676) (xy 143.441758 -261.417737)
			(xy 143.496709 -261.409682) (xy 143.524478 -261.40918) (xy 143.553396 -261.409684) (xy 143.610569 -261.418411)
			(xy 143.66577 -261.43567) (xy 143.717732 -261.461064) (xy 143.765265 -261.494012) (xy 143.80728 -261.533758)
			(xy 143.825468 -261.556246) (xy 143.833091 -261.565036) (xy 143.85398 -261.575227) (xy 143.8656 -261.575804)
			(xy 143.945356 -261.575804) (xy 143.95699 -261.575281) (xy 143.977899 -261.565081) (xy 143.985488 -261.556246)
			(xy 144.003672 -261.533757) (xy 144.045695 -261.494025) (xy 144.093232 -261.461088) (xy 144.145194 -261.435701)
			(xy 144.200392 -261.418445) (xy 144.257562 -261.409716) (xy 144.286478 -261.40918) (xy 144.313731 -261.409666)
			(xy 144.367683 -261.41742) (xy 144.419981 -261.432774) (xy 144.469563 -261.455414) (xy 144.499198 -261.474458)
			(xy 144.86966 -261.474458) (xy 144.873731 -261.418836) (xy 144.885857 -261.364399) (xy 144.90578 -261.312308)
			(xy 144.933076 -261.263673) (xy 144.967162 -261.21953) (xy 145.007311 -261.180821) (xy 145.052669 -261.14837)
			(xy 145.102269 -261.122869) (xy 145.155053 -261.104862) (xy 145.209896 -261.094732) (xy 145.26563 -261.092695)
			(xy 145.321067 -261.098795) (xy 145.375024 -261.112901) (xy 145.426353 -261.134713) (xy 145.473959 -261.163767)
			(xy 145.516827 -261.199442) (xy 145.554044 -261.240979) (xy 145.584817 -261.287492) (xy 145.608489 -261.337989)
			(xy 145.624557 -261.391396) (xy 145.632677 -261.446572) (xy 145.633186 -261.474458) (xy 146.354798 -261.474458)
			(xy 146.358869 -261.418836) (xy 146.370995 -261.364399) (xy 146.390918 -261.312308) (xy 146.418214 -261.263673)
			(xy 146.4523 -261.21953) (xy 146.492449 -261.180821) (xy 146.537807 -261.14837) (xy 146.587407 -261.122869)
			(xy 146.640191 -261.104862) (xy 146.695034 -261.094732) (xy 146.750768 -261.092695) (xy 146.806205 -261.098795)
			(xy 146.860162 -261.112901) (xy 146.911491 -261.134713) (xy 146.959097 -261.163767) (xy 147.001965 -261.199442)
			(xy 147.039182 -261.240979) (xy 147.069955 -261.287492) (xy 147.093627 -261.337989) (xy 147.109695 -261.391396)
			(xy 147.117815 -261.446572) (xy 147.118324 -261.474458) (xy 147.117815 -261.502344) (xy 147.109695 -261.55752)
			(xy 147.093627 -261.610927) (xy 147.069955 -261.661424) (xy 147.039182 -261.707937) (xy 147.008278 -261.742428)
			(xy 157.474158 -261.742428) (xy 157.474644 -261.715177) (xy 157.4824 -261.661229) (xy 157.497755 -261.608934)
			(xy 157.520397 -261.559357) (xy 157.549863 -261.513507) (xy 157.585554 -261.472316) (xy 157.626745 -261.436625)
			(xy 157.672595 -261.407159) (xy 157.722172 -261.384517) (xy 157.774467 -261.369162) (xy 157.828415 -261.361406)
			(xy 157.882917 -261.361406) (xy 157.936865 -261.369162) (xy 157.98916 -261.384517) (xy 158.038737 -261.407159)
			(xy 158.084587 -261.436625) (xy 158.125778 -261.472316) (xy 158.161469 -261.513507) (xy 158.190935 -261.559357)
			(xy 158.213577 -261.608934) (xy 158.228932 -261.661229) (xy 158.236688 -261.715177) (xy 158.237174 -261.742428)
			(xy 158.236651 -261.771382) (xy 158.22789 -261.828623) (xy 158.210586 -261.883885) (xy 158.185138 -261.935901)
			(xy 158.152129 -261.983479) (xy 158.112314 -262.025528) (xy 158.066608 -262.061084) (xy 158.041594 -262.075676)
			(xy 158.029689 -262.08289) (xy 158.009983 -262.102534) (xy 157.996317 -262.126771) (xy 157.989707 -262.153798)
			(xy 157.990643 -262.181606) (xy 157.999057 -262.208128) (xy 158.014323 -262.23139) (xy 158.035305 -262.249664)
			(xy 158.04769 -262.256016) (xy 158.071847 -262.267919) (xy 158.11678 -262.297609) (xy 158.157094 -262.333319)
			(xy 158.191989 -262.374339) (xy 158.220773 -262.419857) (xy 158.242875 -262.468968) (xy 158.257855 -262.520698)
			(xy 158.265417 -262.57402) (xy 158.265876 -262.600948) (xy 158.26539 -262.628199) (xy 158.257634 -262.682147)
			(xy 158.242279 -262.734442) (xy 158.219637 -262.784019) (xy 158.190171 -262.829869) (xy 158.15448 -262.87106)
			(xy 158.113289 -262.906751) (xy 158.067439 -262.936217) (xy 158.017862 -262.958859) (xy 157.965567 -262.974214)
			(xy 157.911619 -262.98197) (xy 157.857117 -262.98197) (xy 157.803169 -262.974214) (xy 157.750874 -262.958859)
			(xy 157.701297 -262.936217) (xy 157.655447 -262.906751) (xy 157.614256 -262.87106) (xy 157.578565 -262.829869)
			(xy 157.549099 -262.784019) (xy 157.526457 -262.734442) (xy 157.511102 -262.682147) (xy 157.503346 -262.628199)
			(xy 157.50286 -262.600948) (xy 157.503426 -262.571996) (xy 157.512177 -262.514756) (xy 157.529472 -262.459494)
			(xy 157.554912 -262.407477) (xy 157.587916 -262.359898) (xy 157.627725 -262.317848) (xy 157.673428 -262.282291)
			(xy 157.69844 -262.2677) (xy 157.710363 -262.260516) (xy 157.730064 -262.240864) (xy 157.743725 -262.216622)
			(xy 157.750331 -262.189591) (xy 157.749391 -262.161781) (xy 157.740976 -262.135258) (xy 157.72571 -262.111993)
			(xy 157.704729 -262.093715) (xy 157.692344 -262.08736) (xy 157.668225 -262.075383) (xy 157.623293 -262.045704)
			(xy 157.582978 -262.010006) (xy 157.548079 -261.968996) (xy 157.51929 -261.923489) (xy 157.497182 -261.874387)
			(xy 157.482193 -261.822667) (xy 157.474622 -261.769352) (xy 157.474158 -261.742428) (xy 147.008278 -261.742428)
			(xy 147.001965 -261.749474) (xy 146.959097 -261.785149) (xy 146.911491 -261.814203) (xy 146.860162 -261.836015)
			(xy 146.806205 -261.850121) (xy 146.750768 -261.856221) (xy 146.695034 -261.854184) (xy 146.640191 -261.844054)
			(xy 146.587407 -261.826047) (xy 146.537807 -261.800546) (xy 146.492449 -261.768095) (xy 146.4523 -261.729386)
			(xy 146.418214 -261.685243) (xy 146.390918 -261.636608) (xy 146.370995 -261.584517) (xy 146.358869 -261.53008)
			(xy 146.354798 -261.474458) (xy 145.633186 -261.474458) (xy 145.632677 -261.502344) (xy 145.624557 -261.55752)
			(xy 145.608489 -261.610927) (xy 145.584817 -261.661424) (xy 145.554044 -261.707937) (xy 145.516827 -261.749474)
			(xy 145.473959 -261.785149) (xy 145.426353 -261.814203) (xy 145.375024 -261.836015) (xy 145.321067 -261.850121)
			(xy 145.26563 -261.856221) (xy 145.209896 -261.854184) (xy 145.155053 -261.844054) (xy 145.102269 -261.826047)
			(xy 145.052669 -261.800546) (xy 145.007311 -261.768095) (xy 144.967162 -261.729386) (xy 144.933076 -261.685243)
			(xy 144.90578 -261.636608) (xy 144.885857 -261.584517) (xy 144.873731 -261.53008) (xy 144.86966 -261.474458)
			(xy 144.499198 -261.474458) (xy 144.515417 -261.484881) (xy 144.556611 -261.520573) (xy 144.592306 -261.561765)
			(xy 144.621775 -261.607618) (xy 144.644419 -261.657198) (xy 144.659775 -261.709496) (xy 144.667533 -261.763447)
			(xy 144.667533 -261.817953) (xy 144.659775 -261.871904) (xy 144.644419 -261.924202) (xy 144.621775 -261.973782)
			(xy 144.592306 -262.019635) (xy 144.556611 -262.060827) (xy 144.515417 -262.096519) (xy 144.469563 -262.125986)
			(xy 144.419981 -262.148626) (xy 144.367683 -262.16398) (xy 144.313731 -262.171734) (xy 144.286478 -262.172196)
			(xy 144.257563 -262.171623) (xy 144.200394 -262.162906) (xy 144.145197 -262.145659) (xy 144.093235 -262.120277)
			(xy 144.045699 -262.087343) (xy 144.00368 -262.047611) (xy 143.985488 -262.02513) (xy 143.977888 -262.016316)
			(xy 143.956981 -262.006139) (xy 143.945356 -262.005572) (xy 143.8656 -262.005572) (xy 143.853966 -262.0061)
			(xy 143.833055 -262.016294) (xy 143.825468 -262.02513) (xy 143.807303 -262.047635) (xy 143.765277 -262.087368)
			(xy 143.717736 -262.120303) (xy 143.66577 -262.145688) (xy 143.610568 -262.162939) (xy 143.553395 -262.171664)
			(xy 143.524478 -262.172196) (xy 143.498698 -262.171731) (xy 143.447607 -262.164796) (xy 143.397916 -262.151043)
			(xy 143.35053 -262.130721) (xy 143.306314 -262.104202) (xy 143.266072 -262.071968) (xy 143.230539 -262.034608)
			(xy 143.215106 -262.013954) (xy 143.208248 -262.004302) (xy 143.187674 -261.99338) (xy 143.095726 -261.990078)
			(xy 143.084073 -261.990194) (xy 143.062771 -261.999582) (xy 143.054832 -262.008112) (xy 143.036618 -262.02908)
			(xy 142.995138 -262.066016) (xy 142.948742 -262.096546) (xy 142.898409 -262.120027) (xy 142.845203 -262.135961)
			(xy 142.790248 -262.144011) (xy 142.762478 -262.14451) (xy 142.733561 -262.14397) (xy 142.67639 -262.13525)
			(xy 142.62119 -262.117999) (xy 142.569227 -262.092611) (xy 142.521693 -262.05967) (xy 142.479677 -262.019929)
			(xy 142.461488 -261.997444) (xy 142.453886 -261.988632) (xy 142.432981 -261.978453) (xy 142.421356 -261.977886)
			(xy 142.3416 -261.977886) (xy 142.329971 -261.978444) (xy 142.309061 -261.98862) (xy 142.301468 -261.997444)
			(xy 142.283306 -262.019952) (xy 142.241279 -262.059684) (xy 142.193738 -262.092618) (xy 142.141771 -262.118002)
			(xy 142.086569 -262.135254) (xy 142.029396 -262.143978) (xy 142.000478 -262.14451) (xy 141.973228 -262.144019)
			(xy 141.919283 -262.13626) (xy 141.866991 -262.120903) (xy 141.817417 -262.09826) (xy 141.771569 -262.068794)
			(xy 141.730382 -262.033102) (xy 141.694693 -261.991913) (xy 141.665229 -261.946064) (xy 141.64259 -261.896488)
			(xy 141.627236 -261.844196) (xy 141.61948 -261.79025) (xy 138.071422 -261.79025) (xy 138.381232 -262.10006)
			(xy 138.388077 -262.107458) (xy 138.3958 -262.126057) (xy 138.396218 -262.136128) (xy 138.396218 -262.847836)
			(xy 148.939502 -262.847836) (xy 148.943573 -262.792214) (xy 148.955699 -262.737777) (xy 148.975622 -262.685686)
			(xy 149.002918 -262.637051) (xy 149.037004 -262.592908) (xy 149.077153 -262.554199) (xy 149.122511 -262.521748)
			(xy 149.172111 -262.496247) (xy 149.224895 -262.47824) (xy 149.279738 -262.46811) (xy 149.335472 -262.466073)
			(xy 149.390909 -262.472173) (xy 149.444866 -262.486279) (xy 149.496195 -262.508091) (xy 149.543801 -262.537145)
			(xy 149.586669 -262.57282) (xy 149.623886 -262.614357) (xy 149.654659 -262.66087) (xy 149.678331 -262.711367)
			(xy 149.694399 -262.764774) (xy 149.702519 -262.81995) (xy 149.703028 -262.847836) (xy 149.702519 -262.875722)
			(xy 149.694399 -262.930898) (xy 149.678331 -262.984305) (xy 149.654659 -263.034802) (xy 149.623886 -263.081315)
			(xy 149.586669 -263.122852) (xy 149.543801 -263.158527) (xy 149.496195 -263.187581) (xy 149.444866 -263.209393)
			(xy 149.390909 -263.223499) (xy 149.335472 -263.229599) (xy 149.279738 -263.227562) (xy 149.224895 -263.217432)
			(xy 149.172111 -263.199425) (xy 149.122511 -263.173924) (xy 149.077153 -263.141473) (xy 149.037004 -263.102764)
			(xy 149.002918 -263.058621) (xy 148.975622 -263.009986) (xy 148.955699 -262.957895) (xy 148.943573 -262.903458)
			(xy 148.939502 -262.847836) (xy 138.396218 -262.847836) (xy 138.396218 -263.37768) (xy 154.048204 -263.37768)
			(xy 154.052275 -263.322058) (xy 154.064401 -263.267621) (xy 154.084324 -263.21553) (xy 154.11162 -263.166895)
			(xy 154.145706 -263.122752) (xy 154.185855 -263.084043) (xy 154.231213 -263.051592) (xy 154.280813 -263.026091)
			(xy 154.333597 -263.008084) (xy 154.38844 -262.997954) (xy 154.444174 -262.995917) (xy 154.499611 -263.002017)
			(xy 154.553568 -263.016123) (xy 154.604897 -263.037935) (xy 154.652503 -263.066989) (xy 154.695371 -263.102664)
			(xy 154.732588 -263.144201) (xy 154.763361 -263.190714) (xy 154.787033 -263.241211) (xy 154.803101 -263.294618)
			(xy 154.811221 -263.349794) (xy 154.81173 -263.37768) (xy 154.811221 -263.405566) (xy 154.803101 -263.460742)
			(xy 154.787033 -263.514149) (xy 154.763361 -263.564646) (xy 154.732588 -263.611159) (xy 154.695371 -263.652696)
			(xy 154.652503 -263.688371) (xy 154.604897 -263.717425) (xy 154.553568 -263.739237) (xy 154.499611 -263.753343)
			(xy 154.444174 -263.759443) (xy 154.38844 -263.757406) (xy 154.333597 -263.747276) (xy 154.280813 -263.729269)
			(xy 154.231213 -263.703768) (xy 154.185855 -263.671317) (xy 154.145706 -263.632608) (xy 154.11162 -263.588465)
			(xy 154.084324 -263.53983) (xy 154.064401 -263.487739) (xy 154.052275 -263.433302) (xy 154.048204 -263.37768)
			(xy 138.396218 -263.37768) (xy 138.396218 -264.643616) (xy 153.652218 -264.643616) (xy 153.656289 -264.587994)
			(xy 153.668415 -264.533557) (xy 153.688338 -264.481466) (xy 153.715634 -264.432831) (xy 153.74972 -264.388688)
			(xy 153.789869 -264.349979) (xy 153.835227 -264.317528) (xy 153.884827 -264.292027) (xy 153.937611 -264.27402)
			(xy 153.992454 -264.26389) (xy 154.048188 -264.261853) (xy 154.103625 -264.267953) (xy 154.157582 -264.282059)
			(xy 154.208911 -264.303871) (xy 154.256517 -264.332925) (xy 154.299385 -264.3686) (xy 154.336602 -264.410137)
			(xy 154.367375 -264.45665) (xy 154.391047 -264.507147) (xy 154.407115 -264.560554) (xy 154.415235 -264.61573)
			(xy 154.415744 -264.643616) (xy 154.415235 -264.671502) (xy 154.407115 -264.726678) (xy 154.391047 -264.780085)
			(xy 154.367375 -264.830582) (xy 154.336602 -264.877095) (xy 154.299385 -264.918632) (xy 154.256517 -264.954307)
			(xy 154.208911 -264.983361) (xy 154.157582 -265.005173) (xy 154.103625 -265.019279) (xy 154.048188 -265.025379)
			(xy 153.992454 -265.023342) (xy 153.937611 -265.013212) (xy 153.884827 -264.995205) (xy 153.835227 -264.969704)
			(xy 153.789869 -264.937253) (xy 153.74972 -264.898544) (xy 153.715634 -264.854401) (xy 153.688338 -264.805766)
			(xy 153.668415 -264.753675) (xy 153.656289 -264.699238) (xy 153.652218 -264.643616) (xy 138.396218 -264.643616)
			(xy 138.396218 -265.16457) (xy 156.563058 -265.16457) (xy 156.567129 -265.108948) (xy 156.579255 -265.054511)
			(xy 156.599178 -265.00242) (xy 156.626474 -264.953785) (xy 156.66056 -264.909642) (xy 156.700709 -264.870933)
			(xy 156.746067 -264.838482) (xy 156.795667 -264.812981) (xy 156.848451 -264.794974) (xy 156.903294 -264.784844)
			(xy 156.959028 -264.782807) (xy 157.014465 -264.788907) (xy 157.068422 -264.803013) (xy 157.119751 -264.824825)
			(xy 157.167357 -264.853879) (xy 157.210225 -264.889554) (xy 157.247442 -264.931091) (xy 157.278215 -264.977604)
			(xy 157.301887 -265.028101) (xy 157.317955 -265.081508) (xy 157.326075 -265.136684) (xy 157.326584 -265.16457)
			(xy 157.326075 -265.192456) (xy 157.317955 -265.247632) (xy 157.301887 -265.301039) (xy 157.278215 -265.351536)
			(xy 157.247442 -265.398049) (xy 157.210225 -265.439586) (xy 157.167357 -265.475261) (xy 157.119751 -265.504315)
			(xy 157.068422 -265.526127) (xy 157.014465 -265.540233) (xy 156.959028 -265.546333) (xy 156.903294 -265.544296)
			(xy 156.848451 -265.534166) (xy 156.795667 -265.516159) (xy 156.746067 -265.490658) (xy 156.700709 -265.458207)
			(xy 156.66056 -265.419498) (xy 156.626474 -265.375355) (xy 156.599178 -265.32672) (xy 156.579255 -265.274629)
			(xy 156.567129 -265.220192) (xy 156.563058 -265.16457) (xy 138.396218 -265.16457) (xy 138.396218 -266.517882)
			(xy 156.497018 -266.517882) (xy 156.501089 -266.46226) (xy 156.513215 -266.407823) (xy 156.533138 -266.355732)
			(xy 156.560434 -266.307097) (xy 156.59452 -266.262954) (xy 156.634669 -266.224245) (xy 156.680027 -266.191794)
			(xy 156.729627 -266.166293) (xy 156.782411 -266.148286) (xy 156.837254 -266.138156) (xy 156.892988 -266.136119)
			(xy 156.948425 -266.142219) (xy 157.002382 -266.156325) (xy 157.053711 -266.178137) (xy 157.101317 -266.207191)
			(xy 157.144185 -266.242866) (xy 157.181402 -266.284403) (xy 157.212175 -266.330916) (xy 157.235847 -266.381413)
			(xy 157.251915 -266.43482) (xy 157.260035 -266.489996) (xy 157.260544 -266.517882) (xy 157.260035 -266.545768)
			(xy 157.251915 -266.600944) (xy 157.235847 -266.654351) (xy 157.212175 -266.704848) (xy 157.181402 -266.751361)
			(xy 157.144185 -266.792898) (xy 157.101317 -266.828573) (xy 157.053711 -266.857627) (xy 157.002382 -266.879439)
			(xy 156.948425 -266.893545) (xy 156.892988 -266.899645) (xy 156.837254 -266.897608) (xy 156.782411 -266.887478)
			(xy 156.729627 -266.869471) (xy 156.680027 -266.84397) (xy 156.634669 -266.811519) (xy 156.59452 -266.77281)
			(xy 156.560434 -266.728667) (xy 156.533138 -266.680032) (xy 156.513215 -266.627941) (xy 156.501089 -266.573504)
			(xy 156.497018 -266.517882) (xy 138.396218 -266.517882) (xy 138.396218 -266.963398) (xy 154.756102 -266.963398)
			(xy 154.760173 -266.907776) (xy 154.772299 -266.853339) (xy 154.792222 -266.801248) (xy 154.819518 -266.752613)
			(xy 154.853604 -266.70847) (xy 154.893753 -266.669761) (xy 154.939111 -266.63731) (xy 154.988711 -266.611809)
			(xy 155.041495 -266.593802) (xy 155.096338 -266.583672) (xy 155.152072 -266.581635) (xy 155.207509 -266.587735)
			(xy 155.261466 -266.601841) (xy 155.312795 -266.623653) (xy 155.360401 -266.652707) (xy 155.403269 -266.688382)
			(xy 155.440486 -266.729919) (xy 155.471259 -266.776432) (xy 155.494931 -266.826929) (xy 155.510999 -266.880336)
			(xy 155.519119 -266.935512) (xy 155.519628 -266.963398) (xy 155.519119 -266.991284) (xy 155.510999 -267.04646)
			(xy 155.494931 -267.099867) (xy 155.471259 -267.150364) (xy 155.440486 -267.196877) (xy 155.403269 -267.238414)
			(xy 155.360401 -267.274089) (xy 155.312795 -267.303143) (xy 155.261466 -267.324955) (xy 155.207509 -267.339061)
			(xy 155.152072 -267.345161) (xy 155.096338 -267.343124) (xy 155.041495 -267.332994) (xy 154.988711 -267.314987)
			(xy 154.939111 -267.289486) (xy 154.893753 -267.257035) (xy 154.853604 -267.218326) (xy 154.819518 -267.174183)
			(xy 154.792222 -267.125548) (xy 154.772299 -267.073457) (xy 154.760173 -267.01902) (xy 154.756102 -266.963398)
			(xy 138.396218 -266.963398) (xy 138.396218 -267.578078) (xy 152.95321 -267.578078) (xy 152.957281 -267.522456)
			(xy 152.969407 -267.468019) (xy 152.98933 -267.415928) (xy 153.016626 -267.367293) (xy 153.050712 -267.32315)
			(xy 153.090861 -267.284441) (xy 153.136219 -267.25199) (xy 153.185819 -267.226489) (xy 153.238603 -267.208482)
			(xy 153.293446 -267.198352) (xy 153.34918 -267.196315) (xy 153.404617 -267.202415) (xy 153.458574 -267.216521)
			(xy 153.509903 -267.238333) (xy 153.557509 -267.267387) (xy 153.600377 -267.303062) (xy 153.637594 -267.344599)
			(xy 153.668367 -267.391112) (xy 153.692039 -267.441609) (xy 153.708107 -267.495016) (xy 153.716227 -267.550192)
			(xy 153.716736 -267.578078) (xy 153.716227 -267.605964) (xy 153.708107 -267.66114) (xy 153.692039 -267.714547)
			(xy 153.668367 -267.765044) (xy 153.637594 -267.811557) (xy 153.600377 -267.853094) (xy 153.557509 -267.888769)
			(xy 153.509903 -267.917823) (xy 153.458574 -267.939635) (xy 153.404617 -267.953741) (xy 153.34918 -267.959841)
			(xy 153.293446 -267.957804) (xy 153.238603 -267.947674) (xy 153.185819 -267.929667) (xy 153.136219 -267.904166)
			(xy 153.090861 -267.871715) (xy 153.050712 -267.833006) (xy 153.016626 -267.788863) (xy 152.98933 -267.740228)
			(xy 152.969407 -267.688137) (xy 152.957281 -267.6337) (xy 152.95321 -267.578078) (xy 138.396218 -267.578078)
			(xy 138.396218 -268.061694) (xy 138.39698 -268.070076) (xy 138.398491 -268.077683) (xy 138.405471 -268.091523)
			(xy 138.410696 -268.097254) (xy 141.213332 -270.89989) (xy 142.982451 -270.89989) (xy 142.98644 -270.75135)
			(xy 142.998397 -270.603237) (xy 143.018287 -270.45598) (xy 143.046052 -270.310004) (xy 143.081613 -270.165727)
			(xy 143.124867 -270.023568) (xy 143.175689 -269.883935) (xy 143.233933 -269.747232) (xy 143.299431 -269.613852)
			(xy 143.371994 -269.48418) (xy 143.451412 -269.35859) (xy 143.537457 -269.237443) (xy 143.629881 -269.12109)
			(xy 143.728417 -269.009866) (xy 143.832781 -268.904091) (xy 143.942673 -268.804071) (xy 144.057774 -268.710093)
			(xy 144.177754 -268.622429) (xy 144.302267 -268.541332) (xy 144.430953 -268.467035) (xy 144.563442 -268.399753)
			(xy 144.699351 -268.339679) (xy 144.838289 -268.286987) (xy 144.979855 -268.241828) (xy 145.123641 -268.204333)
			(xy 145.269232 -268.174611) (xy 145.416208 -268.152746) (xy 145.564147 -268.138802) (xy 145.71262 -268.132818)
			(xy 145.861201 -268.134813) (xy 146.00946 -268.144781) (xy 146.156971 -268.162692) (xy 146.303307 -268.188495)
			(xy 146.448048 -268.222115) (xy 146.590775 -268.263457) (xy 146.731078 -268.3124) (xy 146.868551 -268.368803)
			(xy 147.002798 -268.432504) (xy 147.133433 -268.50332) (xy 147.260078 -268.581045) (xy 147.382368 -268.665456)
			(xy 147.499951 -268.756309) (xy 147.612488 -268.853343) (xy 147.719655 -268.956278) (xy 147.821142 -269.064817)
			(xy 147.916656 -269.178646) (xy 148.005923 -269.297439) (xy 148.088684 -269.420851) (xy 148.164702 -269.548529)
			(xy 148.233757 -269.680102) (xy 148.29565 -269.815193) (xy 148.350203 -269.95341) (xy 148.361422 -269.987014)
			(xy 155.308552 -269.987014) (xy 155.312623 -269.931392) (xy 155.324749 -269.876955) (xy 155.344672 -269.824864)
			(xy 155.371968 -269.776229) (xy 155.406054 -269.732086) (xy 155.446203 -269.693377) (xy 155.491561 -269.660926)
			(xy 155.541161 -269.635425) (xy 155.593945 -269.617418) (xy 155.648788 -269.607288) (xy 155.704522 -269.605251)
			(xy 155.759959 -269.611351) (xy 155.813916 -269.625457) (xy 155.865245 -269.647269) (xy 155.912851 -269.676323)
			(xy 155.955719 -269.711998) (xy 155.992936 -269.753535) (xy 156.023709 -269.800048) (xy 156.047381 -269.850545)
			(xy 156.063449 -269.903952) (xy 156.071569 -269.959128) (xy 156.072078 -269.987014) (xy 156.071569 -270.0149)
			(xy 156.063449 -270.070076) (xy 156.047381 -270.123483) (xy 156.023709 -270.17398) (xy 155.992936 -270.220493)
			(xy 155.955719 -270.26203) (xy 155.912851 -270.297705) (xy 155.865245 -270.326759) (xy 155.813916 -270.348571)
			(xy 155.759959 -270.362677) (xy 155.704522 -270.368777) (xy 155.648788 -270.36674) (xy 155.593945 -270.35661)
			(xy 155.541161 -270.338603) (xy 155.491561 -270.313102) (xy 155.446203 -270.280651) (xy 155.406054 -270.241942)
			(xy 155.371968 -270.197799) (xy 155.344672 -270.149164) (xy 155.324749 -270.097073) (xy 155.312623 -270.042636)
			(xy 155.308552 -269.987014) (xy 148.361422 -269.987014) (xy 148.397258 -270.094357) (xy 148.43668 -270.237627)
			(xy 148.468354 -270.382806) (xy 148.49219 -270.529475) (xy 148.508119 -270.677213) (xy 148.516095 -270.825593)
			(xy 148.516594 -270.89989) (xy 148.516095 -270.974187) (xy 148.508119 -271.122567) (xy 148.49219 -271.270305)
			(xy 148.468354 -271.416974) (xy 148.43668 -271.562153) (xy 148.397258 -271.705423) (xy 148.350203 -271.84637)
			(xy 148.29565 -271.984587) (xy 148.233757 -272.119678) (xy 148.164702 -272.251251) (xy 148.088684 -272.378929)
			(xy 148.005923 -272.502341) (xy 147.916656 -272.621134) (xy 147.913577 -272.624804) (xy 154.0693 -272.624804)
			(xy 154.07326 -272.57575) (xy 154.085037 -272.527966) (xy 154.104328 -272.48269) (xy 154.130631 -272.441094)
			(xy 154.163266 -272.404257) (xy 154.201387 -272.373132) (xy 154.244008 -272.348525) (xy 154.290024 -272.331073)
			(xy 154.338243 -272.321229) (xy 154.387418 -272.319248) (xy 154.436273 -272.32518) (xy 154.483544 -272.338872)
			(xy 154.528006 -272.35997) (xy 154.568509 -272.387926) (xy 154.604002 -272.422018) (xy 154.633567 -272.461362)
			(xy 154.656438 -272.504939) (xy 154.672022 -272.55162) (xy 154.679917 -272.600197) (xy 154.680412 -272.624804)
			(xy 155.96922 -272.624804) (xy 155.97318 -272.57575) (xy 155.984957 -272.527966) (xy 156.004248 -272.48269)
			(xy 156.030551 -272.441094) (xy 156.063186 -272.404257) (xy 156.101307 -272.373132) (xy 156.143928 -272.348525)
			(xy 156.189944 -272.331073) (xy 156.238163 -272.321229) (xy 156.287338 -272.319248) (xy 156.336193 -272.32518)
			(xy 156.383464 -272.338872) (xy 156.427926 -272.35997) (xy 156.468429 -272.387926) (xy 156.503922 -272.422018)
			(xy 156.533487 -272.461362) (xy 156.556358 -272.504939) (xy 156.571942 -272.55162) (xy 156.579837 -272.600197)
			(xy 156.580332 -272.624804) (xy 157.86914 -272.624804) (xy 157.8731 -272.57575) (xy 157.884877 -272.527966)
			(xy 157.904168 -272.48269) (xy 157.930471 -272.441094) (xy 157.963106 -272.404257) (xy 158.001227 -272.373132)
			(xy 158.043848 -272.348525) (xy 158.089864 -272.331073) (xy 158.138083 -272.321229) (xy 158.187258 -272.319248)
			(xy 158.236113 -272.32518) (xy 158.283384 -272.338872) (xy 158.327846 -272.35997) (xy 158.368349 -272.387926)
			(xy 158.403842 -272.422018) (xy 158.433407 -272.461362) (xy 158.456278 -272.504939) (xy 158.471862 -272.55162)
			(xy 158.479757 -272.600197) (xy 158.480252 -272.624804) (xy 158.479757 -272.649411) (xy 158.471862 -272.697988)
			(xy 158.456278 -272.744669) (xy 158.433407 -272.788246) (xy 158.403842 -272.82759) (xy 158.368349 -272.861682)
			(xy 158.327846 -272.889638) (xy 158.283384 -272.910736) (xy 158.236113 -272.924428) (xy 158.187258 -272.93036)
			(xy 158.138083 -272.928379) (xy 158.089864 -272.918535) (xy 158.043848 -272.901083) (xy 158.001227 -272.876476)
			(xy 157.963106 -272.845351) (xy 157.930471 -272.808514) (xy 157.904168 -272.766918) (xy 157.884877 -272.721642)
			(xy 157.8731 -272.673858) (xy 157.86914 -272.624804) (xy 156.580332 -272.624804) (xy 156.579837 -272.649411)
			(xy 156.571942 -272.697988) (xy 156.556358 -272.744669) (xy 156.533487 -272.788246) (xy 156.503922 -272.82759)
			(xy 156.468429 -272.861682) (xy 156.427926 -272.889638) (xy 156.383464 -272.910736) (xy 156.336193 -272.924428)
			(xy 156.287338 -272.93036) (xy 156.238163 -272.928379) (xy 156.189944 -272.918535) (xy 156.143928 -272.901083)
			(xy 156.101307 -272.876476) (xy 156.063186 -272.845351) (xy 156.030551 -272.808514) (xy 156.004248 -272.766918)
			(xy 155.984957 -272.721642) (xy 155.97318 -272.673858) (xy 155.96922 -272.624804) (xy 154.680412 -272.624804)
			(xy 154.679917 -272.649411) (xy 154.672022 -272.697988) (xy 154.656438 -272.744669) (xy 154.633567 -272.788246)
			(xy 154.604002 -272.82759) (xy 154.568509 -272.861682) (xy 154.528006 -272.889638) (xy 154.483544 -272.910736)
			(xy 154.436273 -272.924428) (xy 154.387418 -272.93036) (xy 154.338243 -272.928379) (xy 154.290024 -272.918535)
			(xy 154.244008 -272.901083) (xy 154.201387 -272.876476) (xy 154.163266 -272.845351) (xy 154.130631 -272.808514)
			(xy 154.104328 -272.766918) (xy 154.085037 -272.721642) (xy 154.07326 -272.673858) (xy 154.0693 -272.624804)
			(xy 147.913577 -272.624804) (xy 147.821142 -272.734963) (xy 147.719655 -272.843502) (xy 147.612488 -272.946437)
			(xy 147.499951 -273.043471) (xy 147.393798 -273.125492) (xy 160.223196 -273.125492) (xy 160.223196 -273.074076)
			(xy 160.231239 -273.023294) (xy 160.247127 -272.974395) (xy 160.27047 -272.928583) (xy 160.300691 -272.886987)
			(xy 160.337047 -272.850631) (xy 160.378643 -272.82041) (xy 160.424455 -272.797067) (xy 160.473354 -272.781179)
			(xy 160.524136 -272.773136) (xy 160.575552 -272.773136) (xy 160.626334 -272.781179) (xy 160.675233 -272.797067)
			(xy 160.721045 -272.82041) (xy 160.762641 -272.850631) (xy 160.798997 -272.886987) (xy 160.829218 -272.928583)
			(xy 160.852561 -272.974395) (xy 160.868449 -273.023294) (xy 160.876492 -273.074076) (xy 160.876996 -273.099784)
			(xy 160.876492 -273.125492) (xy 162.12337 -273.125492) (xy 162.12337 -273.074076) (xy 162.131413 -273.023294)
			(xy 162.147301 -272.974395) (xy 162.170644 -272.928583) (xy 162.200865 -272.886987) (xy 162.237221 -272.850631)
			(xy 162.278817 -272.82041) (xy 162.324629 -272.797067) (xy 162.373528 -272.781179) (xy 162.42431 -272.773136)
			(xy 162.475726 -272.773136) (xy 162.526508 -272.781179) (xy 162.575407 -272.797067) (xy 162.621219 -272.82041)
			(xy 162.662815 -272.850631) (xy 162.699171 -272.886987) (xy 162.729392 -272.928583) (xy 162.752735 -272.974395)
			(xy 162.768623 -273.023294) (xy 162.776666 -273.074076) (xy 162.77717 -273.099784) (xy 162.776666 -273.125492)
			(xy 164.02329 -273.125492) (xy 164.02329 -273.074076) (xy 164.031333 -273.023294) (xy 164.047221 -272.974395)
			(xy 164.070564 -272.928583) (xy 164.100785 -272.886987) (xy 164.137141 -272.850631) (xy 164.178737 -272.82041)
			(xy 164.224549 -272.797067) (xy 164.273448 -272.781179) (xy 164.32423 -272.773136) (xy 164.375646 -272.773136)
			(xy 164.426428 -272.781179) (xy 164.475327 -272.797067) (xy 164.521139 -272.82041) (xy 164.562735 -272.850631)
			(xy 164.599091 -272.886987) (xy 164.629312 -272.928583) (xy 164.652655 -272.974395) (xy 164.668543 -273.023294)
			(xy 164.676586 -273.074076) (xy 164.67709 -273.099784) (xy 164.676586 -273.125492) (xy 165.92321 -273.125492)
			(xy 165.92321 -273.074076) (xy 165.931253 -273.023294) (xy 165.947141 -272.974395) (xy 165.970484 -272.928583)
			(xy 166.000705 -272.886987) (xy 166.037061 -272.850631) (xy 166.078657 -272.82041) (xy 166.124469 -272.797067)
			(xy 166.173368 -272.781179) (xy 166.22415 -272.773136) (xy 166.275566 -272.773136) (xy 166.326348 -272.781179)
			(xy 166.375247 -272.797067) (xy 166.421059 -272.82041) (xy 166.462655 -272.850631) (xy 166.499011 -272.886987)
			(xy 166.529232 -272.928583) (xy 166.552575 -272.974395) (xy 166.568463 -273.023294) (xy 166.576506 -273.074076)
			(xy 166.57701 -273.099784) (xy 166.576506 -273.125492) (xy 167.823384 -273.125492) (xy 167.823384 -273.074076)
			(xy 167.831427 -273.023294) (xy 167.847315 -272.974395) (xy 167.870658 -272.928583) (xy 167.900879 -272.886987)
			(xy 167.937235 -272.850631) (xy 167.978831 -272.82041) (xy 168.024643 -272.797067) (xy 168.073542 -272.781179)
			(xy 168.124324 -272.773136) (xy 168.17574 -272.773136) (xy 168.226522 -272.781179) (xy 168.275421 -272.797067)
			(xy 168.321233 -272.82041) (xy 168.362829 -272.850631) (xy 168.399185 -272.886987) (xy 168.429406 -272.928583)
			(xy 168.452749 -272.974395) (xy 168.468637 -273.023294) (xy 168.47668 -273.074076) (xy 168.477184 -273.099784)
			(xy 168.47668 -273.125492) (xy 169.723304 -273.125492) (xy 169.723304 -273.074076) (xy 169.731347 -273.023294)
			(xy 169.747235 -272.974395) (xy 169.770578 -272.928583) (xy 169.800799 -272.886987) (xy 169.837155 -272.850631)
			(xy 169.878751 -272.82041) (xy 169.924563 -272.797067) (xy 169.973462 -272.781179) (xy 170.024244 -272.773136)
			(xy 170.07566 -272.773136) (xy 170.126442 -272.781179) (xy 170.175341 -272.797067) (xy 170.221153 -272.82041)
			(xy 170.262749 -272.850631) (xy 170.299105 -272.886987) (xy 170.329326 -272.928583) (xy 170.352669 -272.974395)
			(xy 170.368557 -273.023294) (xy 170.3766 -273.074076) (xy 170.377104 -273.099784) (xy 170.3766 -273.125492)
			(xy 171.623224 -273.125492) (xy 171.623224 -273.074076) (xy 171.631267 -273.023294) (xy 171.647155 -272.974395)
			(xy 171.670498 -272.928583) (xy 171.700719 -272.886987) (xy 171.737075 -272.850631) (xy 171.778671 -272.82041)
			(xy 171.824483 -272.797067) (xy 171.873382 -272.781179) (xy 171.924164 -272.773136) (xy 171.97558 -272.773136)
			(xy 172.026362 -272.781179) (xy 172.075261 -272.797067) (xy 172.121073 -272.82041) (xy 172.162669 -272.850631)
			(xy 172.199025 -272.886987) (xy 172.229246 -272.928583) (xy 172.252589 -272.974395) (xy 172.268477 -273.023294)
			(xy 172.27652 -273.074076) (xy 172.277024 -273.099784) (xy 172.27652 -273.125492) (xy 172.268477 -273.176274)
			(xy 172.252589 -273.225173) (xy 172.229246 -273.270985) (xy 172.199025 -273.312581) (xy 172.162669 -273.348937)
			(xy 172.121073 -273.379158) (xy 172.075261 -273.402501) (xy 172.026362 -273.418389) (xy 171.97558 -273.426432)
			(xy 171.924164 -273.426432) (xy 171.873382 -273.418389) (xy 171.824483 -273.402501) (xy 171.778671 -273.379158)
			(xy 171.737075 -273.348937) (xy 171.700719 -273.312581) (xy 171.670498 -273.270985) (xy 171.647155 -273.225173)
			(xy 171.631267 -273.176274) (xy 171.623224 -273.125492) (xy 170.3766 -273.125492) (xy 170.368557 -273.176274)
			(xy 170.352669 -273.225173) (xy 170.329326 -273.270985) (xy 170.299105 -273.312581) (xy 170.262749 -273.348937)
			(xy 170.221153 -273.379158) (xy 170.175341 -273.402501) (xy 170.126442 -273.418389) (xy 170.07566 -273.426432)
			(xy 170.024244 -273.426432) (xy 169.973462 -273.418389) (xy 169.924563 -273.402501) (xy 169.878751 -273.379158)
			(xy 169.837155 -273.348937) (xy 169.800799 -273.312581) (xy 169.770578 -273.270985) (xy 169.747235 -273.225173)
			(xy 169.731347 -273.176274) (xy 169.723304 -273.125492) (xy 168.47668 -273.125492) (xy 168.468637 -273.176274)
			(xy 168.452749 -273.225173) (xy 168.429406 -273.270985) (xy 168.399185 -273.312581) (xy 168.362829 -273.348937)
			(xy 168.321233 -273.379158) (xy 168.275421 -273.402501) (xy 168.226522 -273.418389) (xy 168.17574 -273.426432)
			(xy 168.124324 -273.426432) (xy 168.073542 -273.418389) (xy 168.024643 -273.402501) (xy 167.978831 -273.379158)
			(xy 167.937235 -273.348937) (xy 167.900879 -273.312581) (xy 167.870658 -273.270985) (xy 167.847315 -273.225173)
			(xy 167.831427 -273.176274) (xy 167.823384 -273.125492) (xy 166.576506 -273.125492) (xy 166.568463 -273.176274)
			(xy 166.552575 -273.225173) (xy 166.529232 -273.270985) (xy 166.499011 -273.312581) (xy 166.462655 -273.348937)
			(xy 166.421059 -273.379158) (xy 166.375247 -273.402501) (xy 166.326348 -273.418389) (xy 166.275566 -273.426432)
			(xy 166.22415 -273.426432) (xy 166.173368 -273.418389) (xy 166.124469 -273.402501) (xy 166.078657 -273.379158)
			(xy 166.037061 -273.348937) (xy 166.000705 -273.312581) (xy 165.970484 -273.270985) (xy 165.947141 -273.225173)
			(xy 165.931253 -273.176274) (xy 165.92321 -273.125492) (xy 164.676586 -273.125492) (xy 164.668543 -273.176274)
			(xy 164.652655 -273.225173) (xy 164.629312 -273.270985) (xy 164.599091 -273.312581) (xy 164.562735 -273.348937)
			(xy 164.521139 -273.379158) (xy 164.475327 -273.402501) (xy 164.426428 -273.418389) (xy 164.375646 -273.426432)
			(xy 164.32423 -273.426432) (xy 164.273448 -273.418389) (xy 164.224549 -273.402501) (xy 164.178737 -273.379158)
			(xy 164.137141 -273.348937) (xy 164.100785 -273.312581) (xy 164.070564 -273.270985) (xy 164.047221 -273.225173)
			(xy 164.031333 -273.176274) (xy 164.02329 -273.125492) (xy 162.776666 -273.125492) (xy 162.768623 -273.176274)
			(xy 162.752735 -273.225173) (xy 162.729392 -273.270985) (xy 162.699171 -273.312581) (xy 162.662815 -273.348937)
			(xy 162.621219 -273.379158) (xy 162.575407 -273.402501) (xy 162.526508 -273.418389) (xy 162.475726 -273.426432)
			(xy 162.42431 -273.426432) (xy 162.373528 -273.418389) (xy 162.324629 -273.402501) (xy 162.278817 -273.379158)
			(xy 162.237221 -273.348937) (xy 162.200865 -273.312581) (xy 162.170644 -273.270985) (xy 162.147301 -273.225173)
			(xy 162.131413 -273.176274) (xy 162.12337 -273.125492) (xy 160.876492 -273.125492) (xy 160.868449 -273.176274)
			(xy 160.852561 -273.225173) (xy 160.829218 -273.270985) (xy 160.798997 -273.312581) (xy 160.762641 -273.348937)
			(xy 160.721045 -273.379158) (xy 160.675233 -273.402501) (xy 160.626334 -273.418389) (xy 160.575552 -273.426432)
			(xy 160.524136 -273.426432) (xy 160.473354 -273.418389) (xy 160.424455 -273.402501) (xy 160.378643 -273.379158)
			(xy 160.337047 -273.348937) (xy 160.300691 -273.312581) (xy 160.27047 -273.270985) (xy 160.247127 -273.225173)
			(xy 160.231239 -273.176274) (xy 160.223196 -273.125492) (xy 147.393798 -273.125492) (xy 147.382368 -273.134324)
			(xy 147.260078 -273.218735) (xy 147.133433 -273.29646) (xy 147.002798 -273.367276) (xy 146.868551 -273.430977)
			(xy 146.731078 -273.48738) (xy 146.590775 -273.536323) (xy 146.458063 -273.574764) (xy 155.96922 -273.574764)
			(xy 155.97318 -273.52571) (xy 155.984957 -273.477926) (xy 156.004248 -273.43265) (xy 156.030551 -273.391054)
			(xy 156.063186 -273.354217) (xy 156.101307 -273.323092) (xy 156.143928 -273.298485) (xy 156.189944 -273.281033)
			(xy 156.238163 -273.271189) (xy 156.287338 -273.269208) (xy 156.336193 -273.27514) (xy 156.383464 -273.288832)
			(xy 156.427926 -273.30993) (xy 156.468429 -273.337886) (xy 156.503922 -273.371978) (xy 156.533487 -273.411322)
			(xy 156.556358 -273.454899) (xy 156.571942 -273.50158) (xy 156.579837 -273.550157) (xy 156.580332 -273.574764)
			(xy 157.86914 -273.574764) (xy 157.8731 -273.52571) (xy 157.884877 -273.477926) (xy 157.904168 -273.43265)
			(xy 157.930471 -273.391054) (xy 157.963106 -273.354217) (xy 158.001227 -273.323092) (xy 158.043848 -273.298485)
			(xy 158.089864 -273.281033) (xy 158.138083 -273.271189) (xy 158.187258 -273.269208) (xy 158.236113 -273.27514)
			(xy 158.283384 -273.288832) (xy 158.327846 -273.30993) (xy 158.368349 -273.337886) (xy 158.403842 -273.371978)
			(xy 158.433407 -273.411322) (xy 158.456278 -273.454899) (xy 158.471862 -273.50158) (xy 158.479757 -273.550157)
			(xy 158.480252 -273.574764) (xy 158.479757 -273.599371) (xy 158.471862 -273.647948) (xy 158.456278 -273.694629)
			(xy 158.433407 -273.738206) (xy 158.403842 -273.77755) (xy 158.368349 -273.811642) (xy 158.327846 -273.839598)
			(xy 158.283384 -273.860696) (xy 158.236113 -273.874388) (xy 158.187258 -273.88032) (xy 158.138083 -273.878339)
			(xy 158.089864 -273.868495) (xy 158.043848 -273.851043) (xy 158.001227 -273.826436) (xy 157.963106 -273.795311)
			(xy 157.930471 -273.758474) (xy 157.904168 -273.716878) (xy 157.884877 -273.671602) (xy 157.8731 -273.623818)
			(xy 157.86914 -273.574764) (xy 156.580332 -273.574764) (xy 156.579837 -273.599371) (xy 156.571942 -273.647948)
			(xy 156.556358 -273.694629) (xy 156.533487 -273.738206) (xy 156.503922 -273.77755) (xy 156.468429 -273.811642)
			(xy 156.427926 -273.839598) (xy 156.383464 -273.860696) (xy 156.336193 -273.874388) (xy 156.287338 -273.88032)
			(xy 156.238163 -273.878339) (xy 156.189944 -273.868495) (xy 156.143928 -273.851043) (xy 156.101307 -273.826436)
			(xy 156.063186 -273.795311) (xy 156.030551 -273.758474) (xy 156.004248 -273.716878) (xy 155.984957 -273.671602)
			(xy 155.97318 -273.623818) (xy 155.96922 -273.574764) (xy 146.458063 -273.574764) (xy 146.448048 -273.577665)
			(xy 146.303307 -273.611285) (xy 146.156971 -273.637088) (xy 146.00946 -273.654999) (xy 145.861201 -273.664967)
			(xy 145.71262 -273.666962) (xy 145.564147 -273.660978) (xy 145.416208 -273.647034) (xy 145.269232 -273.625169)
			(xy 145.123641 -273.595447) (xy 144.979855 -273.557952) (xy 144.838289 -273.512793) (xy 144.699351 -273.460101)
			(xy 144.563442 -273.400027) (xy 144.430953 -273.332745) (xy 144.302267 -273.258448) (xy 144.177754 -273.177351)
			(xy 144.057774 -273.089687) (xy 143.942673 -272.995709) (xy 143.832781 -272.895689) (xy 143.728417 -272.789914)
			(xy 143.629881 -272.67869) (xy 143.537457 -272.562337) (xy 143.451412 -272.44119) (xy 143.371994 -272.3156)
			(xy 143.299431 -272.185928) (xy 143.233933 -272.052548) (xy 143.175689 -271.915845) (xy 143.124867 -271.776212)
			(xy 143.081613 -271.634053) (xy 143.046052 -271.489776) (xy 143.018287 -271.3438) (xy 142.998397 -271.196543)
			(xy 142.98644 -271.04843) (xy 142.982451 -270.89989) (xy 141.213332 -270.89989) (xy 142.160498 -271.847056)
			(xy 142.167336 -271.854457) (xy 142.17505 -271.873056) (xy 142.175484 -271.883124) (xy 142.175484 -274.075452)
			(xy 160.223196 -274.075452) (xy 160.223196 -274.024036) (xy 160.231239 -273.973254) (xy 160.247127 -273.924355)
			(xy 160.27047 -273.878543) (xy 160.300691 -273.836947) (xy 160.337047 -273.800591) (xy 160.378643 -273.77037)
			(xy 160.424455 -273.747027) (xy 160.473354 -273.731139) (xy 160.524136 -273.723096) (xy 160.575552 -273.723096)
			(xy 160.626334 -273.731139) (xy 160.675233 -273.747027) (xy 160.721045 -273.77037) (xy 160.762641 -273.800591)
			(xy 160.798997 -273.836947) (xy 160.829218 -273.878543) (xy 160.852561 -273.924355) (xy 160.868449 -273.973254)
			(xy 160.876492 -274.024036) (xy 160.876996 -274.049744) (xy 160.876492 -274.075452) (xy 162.12337 -274.075452)
			(xy 162.12337 -274.024036) (xy 162.131413 -273.973254) (xy 162.147301 -273.924355) (xy 162.170644 -273.878543)
			(xy 162.200865 -273.836947) (xy 162.237221 -273.800591) (xy 162.278817 -273.77037) (xy 162.324629 -273.747027)
			(xy 162.373528 -273.731139) (xy 162.42431 -273.723096) (xy 162.475726 -273.723096) (xy 162.526508 -273.731139)
			(xy 162.575407 -273.747027) (xy 162.621219 -273.77037) (xy 162.662815 -273.800591) (xy 162.699171 -273.836947)
			(xy 162.729392 -273.878543) (xy 162.752735 -273.924355) (xy 162.768623 -273.973254) (xy 162.776666 -274.024036)
			(xy 162.77717 -274.049744) (xy 162.776666 -274.075452) (xy 164.02329 -274.075452) (xy 164.02329 -274.024036)
			(xy 164.031333 -273.973254) (xy 164.047221 -273.924355) (xy 164.070564 -273.878543) (xy 164.100785 -273.836947)
			(xy 164.137141 -273.800591) (xy 164.178737 -273.77037) (xy 164.224549 -273.747027) (xy 164.273448 -273.731139)
			(xy 164.32423 -273.723096) (xy 164.375646 -273.723096) (xy 164.426428 -273.731139) (xy 164.475327 -273.747027)
			(xy 164.521139 -273.77037) (xy 164.562735 -273.800591) (xy 164.599091 -273.836947) (xy 164.629312 -273.878543)
			(xy 164.652655 -273.924355) (xy 164.668543 -273.973254) (xy 164.676586 -274.024036) (xy 164.67709 -274.049744)
			(xy 164.676586 -274.075452) (xy 165.92321 -274.075452) (xy 165.92321 -274.024036) (xy 165.931253 -273.973254)
			(xy 165.947141 -273.924355) (xy 165.970484 -273.878543) (xy 166.000705 -273.836947) (xy 166.037061 -273.800591)
			(xy 166.078657 -273.77037) (xy 166.124469 -273.747027) (xy 166.173368 -273.731139) (xy 166.22415 -273.723096)
			(xy 166.275566 -273.723096) (xy 166.326348 -273.731139) (xy 166.375247 -273.747027) (xy 166.421059 -273.77037)
			(xy 166.462655 -273.800591) (xy 166.499011 -273.836947) (xy 166.529232 -273.878543) (xy 166.552575 -273.924355)
			(xy 166.568463 -273.973254) (xy 166.576506 -274.024036) (xy 166.57701 -274.049744) (xy 166.576506 -274.075452)
			(xy 167.823384 -274.075452) (xy 167.823384 -274.024036) (xy 167.831427 -273.973254) (xy 167.847315 -273.924355)
			(xy 167.870658 -273.878543) (xy 167.900879 -273.836947) (xy 167.937235 -273.800591) (xy 167.978831 -273.77037)
			(xy 168.024643 -273.747027) (xy 168.073542 -273.731139) (xy 168.124324 -273.723096) (xy 168.17574 -273.723096)
			(xy 168.226522 -273.731139) (xy 168.275421 -273.747027) (xy 168.321233 -273.77037) (xy 168.362829 -273.800591)
			(xy 168.399185 -273.836947) (xy 168.429406 -273.878543) (xy 168.452749 -273.924355) (xy 168.468637 -273.973254)
			(xy 168.47668 -274.024036) (xy 168.477184 -274.049744) (xy 168.47668 -274.075452) (xy 169.723304 -274.075452)
			(xy 169.723304 -274.024036) (xy 169.731347 -273.973254) (xy 169.747235 -273.924355) (xy 169.770578 -273.878543)
			(xy 169.800799 -273.836947) (xy 169.837155 -273.800591) (xy 169.878751 -273.77037) (xy 169.924563 -273.747027)
			(xy 169.973462 -273.731139) (xy 170.024244 -273.723096) (xy 170.07566 -273.723096) (xy 170.126442 -273.731139)
			(xy 170.175341 -273.747027) (xy 170.221153 -273.77037) (xy 170.262749 -273.800591) (xy 170.299105 -273.836947)
			(xy 170.329326 -273.878543) (xy 170.352669 -273.924355) (xy 170.368557 -273.973254) (xy 170.3766 -274.024036)
			(xy 170.377104 -274.049744) (xy 170.3766 -274.075452) (xy 171.623224 -274.075452) (xy 171.623224 -274.024036)
			(xy 171.631267 -273.973254) (xy 171.647155 -273.924355) (xy 171.670498 -273.878543) (xy 171.700719 -273.836947)
			(xy 171.737075 -273.800591) (xy 171.778671 -273.77037) (xy 171.824483 -273.747027) (xy 171.873382 -273.731139)
			(xy 171.924164 -273.723096) (xy 171.97558 -273.723096) (xy 172.026362 -273.731139) (xy 172.075261 -273.747027)
			(xy 172.121073 -273.77037) (xy 172.162669 -273.800591) (xy 172.199025 -273.836947) (xy 172.229246 -273.878543)
			(xy 172.252589 -273.924355) (xy 172.268477 -273.973254) (xy 172.27652 -274.024036) (xy 172.277024 -274.049744)
			(xy 172.27652 -274.075452) (xy 172.268477 -274.126234) (xy 172.252589 -274.175133) (xy 172.229246 -274.220945)
			(xy 172.199025 -274.262541) (xy 172.162669 -274.298897) (xy 172.121073 -274.329118) (xy 172.075261 -274.352461)
			(xy 172.026362 -274.368349) (xy 171.97558 -274.376392) (xy 171.924164 -274.376392) (xy 171.873382 -274.368349)
			(xy 171.824483 -274.352461) (xy 171.778671 -274.329118) (xy 171.737075 -274.298897) (xy 171.700719 -274.262541)
			(xy 171.670498 -274.220945) (xy 171.647155 -274.175133) (xy 171.631267 -274.126234) (xy 171.623224 -274.075452)
			(xy 170.3766 -274.075452) (xy 170.368557 -274.126234) (xy 170.352669 -274.175133) (xy 170.329326 -274.220945)
			(xy 170.299105 -274.262541) (xy 170.262749 -274.298897) (xy 170.221153 -274.329118) (xy 170.175341 -274.352461)
			(xy 170.126442 -274.368349) (xy 170.07566 -274.376392) (xy 170.024244 -274.376392) (xy 169.973462 -274.368349)
			(xy 169.924563 -274.352461) (xy 169.878751 -274.329118) (xy 169.837155 -274.298897) (xy 169.800799 -274.262541)
			(xy 169.770578 -274.220945) (xy 169.747235 -274.175133) (xy 169.731347 -274.126234) (xy 169.723304 -274.075452)
			(xy 168.47668 -274.075452) (xy 168.468637 -274.126234) (xy 168.452749 -274.175133) (xy 168.429406 -274.220945)
			(xy 168.399185 -274.262541) (xy 168.362829 -274.298897) (xy 168.321233 -274.329118) (xy 168.275421 -274.352461)
			(xy 168.226522 -274.368349) (xy 168.17574 -274.376392) (xy 168.124324 -274.376392) (xy 168.073542 -274.368349)
			(xy 168.024643 -274.352461) (xy 167.978831 -274.329118) (xy 167.937235 -274.298897) (xy 167.900879 -274.262541)
			(xy 167.870658 -274.220945) (xy 167.847315 -274.175133) (xy 167.831427 -274.126234) (xy 167.823384 -274.075452)
			(xy 166.576506 -274.075452) (xy 166.568463 -274.126234) (xy 166.552575 -274.175133) (xy 166.529232 -274.220945)
			(xy 166.499011 -274.262541) (xy 166.462655 -274.298897) (xy 166.421059 -274.329118) (xy 166.375247 -274.352461)
			(xy 166.326348 -274.368349) (xy 166.275566 -274.376392) (xy 166.22415 -274.376392) (xy 166.173368 -274.368349)
			(xy 166.124469 -274.352461) (xy 166.078657 -274.329118) (xy 166.037061 -274.298897) (xy 166.000705 -274.262541)
			(xy 165.970484 -274.220945) (xy 165.947141 -274.175133) (xy 165.931253 -274.126234) (xy 165.92321 -274.075452)
			(xy 164.676586 -274.075452) (xy 164.668543 -274.126234) (xy 164.652655 -274.175133) (xy 164.629312 -274.220945)
			(xy 164.599091 -274.262541) (xy 164.562735 -274.298897) (xy 164.521139 -274.329118) (xy 164.475327 -274.352461)
			(xy 164.426428 -274.368349) (xy 164.375646 -274.376392) (xy 164.32423 -274.376392) (xy 164.273448 -274.368349)
			(xy 164.224549 -274.352461) (xy 164.178737 -274.329118) (xy 164.137141 -274.298897) (xy 164.100785 -274.262541)
			(xy 164.070564 -274.220945) (xy 164.047221 -274.175133) (xy 164.031333 -274.126234) (xy 164.02329 -274.075452)
			(xy 162.776666 -274.075452) (xy 162.768623 -274.126234) (xy 162.752735 -274.175133) (xy 162.729392 -274.220945)
			(xy 162.699171 -274.262541) (xy 162.662815 -274.298897) (xy 162.621219 -274.329118) (xy 162.575407 -274.352461)
			(xy 162.526508 -274.368349) (xy 162.475726 -274.376392) (xy 162.42431 -274.376392) (xy 162.373528 -274.368349)
			(xy 162.324629 -274.352461) (xy 162.278817 -274.329118) (xy 162.237221 -274.298897) (xy 162.200865 -274.262541)
			(xy 162.170644 -274.220945) (xy 162.147301 -274.175133) (xy 162.131413 -274.126234) (xy 162.12337 -274.075452)
			(xy 160.876492 -274.075452) (xy 160.868449 -274.126234) (xy 160.852561 -274.175133) (xy 160.829218 -274.220945)
			(xy 160.798997 -274.262541) (xy 160.762641 -274.298897) (xy 160.721045 -274.329118) (xy 160.675233 -274.352461)
			(xy 160.626334 -274.368349) (xy 160.575552 -274.376392) (xy 160.524136 -274.376392) (xy 160.473354 -274.368349)
			(xy 160.424455 -274.352461) (xy 160.378643 -274.329118) (xy 160.337047 -274.298897) (xy 160.300691 -274.262541)
			(xy 160.27047 -274.220945) (xy 160.247127 -274.175133) (xy 160.231239 -274.126234) (xy 160.223196 -274.075452)
			(xy 142.175484 -274.075452) (xy 142.175484 -274.524978) (xy 155.01926 -274.524978) (xy 155.02322 -274.475924)
			(xy 155.034997 -274.42814) (xy 155.054288 -274.382864) (xy 155.080591 -274.341268) (xy 155.113226 -274.304431)
			(xy 155.151347 -274.273306) (xy 155.193968 -274.248699) (xy 155.239984 -274.231247) (xy 155.288203 -274.221403)
			(xy 155.337378 -274.219422) (xy 155.386233 -274.225354) (xy 155.433504 -274.239046) (xy 155.477966 -274.260144)
			(xy 155.518469 -274.2881) (xy 155.553962 -274.322192) (xy 155.583527 -274.361536) (xy 155.606398 -274.405113)
			(xy 155.621982 -274.451794) (xy 155.629877 -274.500371) (xy 155.630372 -274.524978) (xy 156.91918 -274.524978)
			(xy 156.92314 -274.475924) (xy 156.934917 -274.42814) (xy 156.954208 -274.382864) (xy 156.980511 -274.341268)
			(xy 157.013146 -274.304431) (xy 157.051267 -274.273306) (xy 157.093888 -274.248699) (xy 157.139904 -274.231247)
			(xy 157.188123 -274.221403) (xy 157.237298 -274.219422) (xy 157.286153 -274.225354) (xy 157.333424 -274.239046)
			(xy 157.377886 -274.260144) (xy 157.418389 -274.2881) (xy 157.453882 -274.322192) (xy 157.483447 -274.361536)
			(xy 157.506318 -274.405113) (xy 157.521902 -274.451794) (xy 157.529797 -274.500371) (xy 157.530292 -274.524978)
			(xy 158.8191 -274.524978) (xy 158.82306 -274.475924) (xy 158.834837 -274.42814) (xy 158.854128 -274.382864)
			(xy 158.880431 -274.341268) (xy 158.913066 -274.304431) (xy 158.951187 -274.273306) (xy 158.993808 -274.248699)
			(xy 159.039824 -274.231247) (xy 159.088043 -274.221403) (xy 159.137218 -274.219422) (xy 159.186073 -274.225354)
			(xy 159.233344 -274.239046) (xy 159.277806 -274.260144) (xy 159.318309 -274.2881) (xy 159.353802 -274.322192)
			(xy 159.383367 -274.361536) (xy 159.406238 -274.405113) (xy 159.421822 -274.451794) (xy 159.429717 -274.500371)
			(xy 159.430212 -274.524978) (xy 159.429717 -274.549585) (xy 159.421822 -274.598162) (xy 159.406238 -274.644843)
			(xy 159.383367 -274.68842) (xy 159.353802 -274.727764) (xy 159.318309 -274.761856) (xy 159.277806 -274.789812)
			(xy 159.233344 -274.81091) (xy 159.186073 -274.824602) (xy 159.137218 -274.830534) (xy 159.088043 -274.828553)
			(xy 159.039824 -274.818709) (xy 158.993808 -274.801257) (xy 158.951187 -274.77665) (xy 158.913066 -274.745525)
			(xy 158.880431 -274.708688) (xy 158.854128 -274.667092) (xy 158.834837 -274.621816) (xy 158.82306 -274.574032)
			(xy 158.8191 -274.524978) (xy 157.530292 -274.524978) (xy 157.529797 -274.549585) (xy 157.521902 -274.598162)
			(xy 157.506318 -274.644843) (xy 157.483447 -274.68842) (xy 157.453882 -274.727764) (xy 157.418389 -274.761856)
			(xy 157.377886 -274.789812) (xy 157.333424 -274.81091) (xy 157.286153 -274.824602) (xy 157.237298 -274.830534)
			(xy 157.188123 -274.828553) (xy 157.139904 -274.818709) (xy 157.093888 -274.801257) (xy 157.051267 -274.77665)
			(xy 157.013146 -274.745525) (xy 156.980511 -274.708688) (xy 156.954208 -274.667092) (xy 156.934917 -274.621816)
			(xy 156.92314 -274.574032) (xy 156.91918 -274.524978) (xy 155.630372 -274.524978) (xy 155.629877 -274.549585)
			(xy 155.621982 -274.598162) (xy 155.606398 -274.644843) (xy 155.583527 -274.68842) (xy 155.553962 -274.727764)
			(xy 155.518469 -274.761856) (xy 155.477966 -274.789812) (xy 155.433504 -274.81091) (xy 155.386233 -274.824602)
			(xy 155.337378 -274.830534) (xy 155.288203 -274.828553) (xy 155.239984 -274.818709) (xy 155.193968 -274.801257)
			(xy 155.151347 -274.77665) (xy 155.113226 -274.745525) (xy 155.080591 -274.708688) (xy 155.054288 -274.667092)
			(xy 155.034997 -274.621816) (xy 155.02322 -274.574032) (xy 155.01926 -274.524978) (xy 142.175484 -274.524978)
			(xy 142.175484 -275.025666) (xy 161.17341 -275.025666) (xy 161.17341 -274.97425) (xy 161.181453 -274.923468)
			(xy 161.197341 -274.874569) (xy 161.220684 -274.828757) (xy 161.250905 -274.787161) (xy 161.287261 -274.750805)
			(xy 161.328857 -274.720584) (xy 161.374669 -274.697241) (xy 161.423568 -274.681353) (xy 161.47435 -274.67331)
			(xy 161.525766 -274.67331) (xy 161.576548 -274.681353) (xy 161.625447 -274.697241) (xy 161.671259 -274.720584)
			(xy 161.712855 -274.750805) (xy 161.749211 -274.787161) (xy 161.779432 -274.828757) (xy 161.802775 -274.874569)
			(xy 161.818663 -274.923468) (xy 161.826706 -274.97425) (xy 161.82721 -274.999958) (xy 161.826706 -275.025666)
			(xy 163.07333 -275.025666) (xy 163.07333 -274.97425) (xy 163.081373 -274.923468) (xy 163.097261 -274.874569)
			(xy 163.120604 -274.828757) (xy 163.150825 -274.787161) (xy 163.187181 -274.750805) (xy 163.228777 -274.720584)
			(xy 163.274589 -274.697241) (xy 163.323488 -274.681353) (xy 163.37427 -274.67331) (xy 163.425686 -274.67331)
			(xy 163.476468 -274.681353) (xy 163.525367 -274.697241) (xy 163.571179 -274.720584) (xy 163.612775 -274.750805)
			(xy 163.649131 -274.787161) (xy 163.679352 -274.828757) (xy 163.702695 -274.874569) (xy 163.718583 -274.923468)
			(xy 163.726626 -274.97425) (xy 163.72713 -274.999958) (xy 163.726626 -275.025666) (xy 164.97325 -275.025666)
			(xy 164.97325 -274.97425) (xy 164.981293 -274.923468) (xy 164.997181 -274.874569) (xy 165.020524 -274.828757)
			(xy 165.050745 -274.787161) (xy 165.087101 -274.750805) (xy 165.128697 -274.720584) (xy 165.174509 -274.697241)
			(xy 165.223408 -274.681353) (xy 165.27419 -274.67331) (xy 165.325606 -274.67331) (xy 165.376388 -274.681353)
			(xy 165.425287 -274.697241) (xy 165.471099 -274.720584) (xy 165.512695 -274.750805) (xy 165.549051 -274.787161)
			(xy 165.579272 -274.828757) (xy 165.602615 -274.874569) (xy 165.618503 -274.923468) (xy 165.626546 -274.97425)
			(xy 165.62705 -274.999958) (xy 165.626546 -275.025666) (xy 166.873424 -275.025666) (xy 166.873424 -274.97425)
			(xy 166.881467 -274.923468) (xy 166.897355 -274.874569) (xy 166.920698 -274.828757) (xy 166.950919 -274.787161)
			(xy 166.987275 -274.750805) (xy 167.028871 -274.720584) (xy 167.074683 -274.697241) (xy 167.123582 -274.681353)
			(xy 167.174364 -274.67331) (xy 167.22578 -274.67331) (xy 167.276562 -274.681353) (xy 167.325461 -274.697241)
			(xy 167.371273 -274.720584) (xy 167.412869 -274.750805) (xy 167.449225 -274.787161) (xy 167.479446 -274.828757)
			(xy 167.502789 -274.874569) (xy 167.518677 -274.923468) (xy 167.52672 -274.97425) (xy 167.527224 -274.999958)
			(xy 167.52672 -275.025666) (xy 168.773344 -275.025666) (xy 168.773344 -274.97425) (xy 168.781387 -274.923468)
			(xy 168.797275 -274.874569) (xy 168.820618 -274.828757) (xy 168.850839 -274.787161) (xy 168.887195 -274.750805)
			(xy 168.928791 -274.720584) (xy 168.974603 -274.697241) (xy 169.023502 -274.681353) (xy 169.074284 -274.67331)
			(xy 169.1257 -274.67331) (xy 169.176482 -274.681353) (xy 169.225381 -274.697241) (xy 169.271193 -274.720584)
			(xy 169.312789 -274.750805) (xy 169.349145 -274.787161) (xy 169.379366 -274.828757) (xy 169.402709 -274.874569)
			(xy 169.418597 -274.923468) (xy 169.42664 -274.97425) (xy 169.427144 -274.999958) (xy 169.42664 -275.025666)
			(xy 170.673264 -275.025666) (xy 170.673264 -274.97425) (xy 170.681307 -274.923468) (xy 170.697195 -274.874569)
			(xy 170.720538 -274.828757) (xy 170.750759 -274.787161) (xy 170.787115 -274.750805) (xy 170.828711 -274.720584)
			(xy 170.874523 -274.697241) (xy 170.923422 -274.681353) (xy 170.974204 -274.67331) (xy 171.02562 -274.67331)
			(xy 171.076402 -274.681353) (xy 171.125301 -274.697241) (xy 171.171113 -274.720584) (xy 171.212709 -274.750805)
			(xy 171.249065 -274.787161) (xy 171.279286 -274.828757) (xy 171.302629 -274.874569) (xy 171.318517 -274.923468)
			(xy 171.32656 -274.97425) (xy 171.327064 -274.999958) (xy 171.32656 -275.025666) (xy 172.573438 -275.025666)
			(xy 172.573438 -274.97425) (xy 172.581481 -274.923468) (xy 172.597369 -274.874569) (xy 172.620712 -274.828757)
			(xy 172.650933 -274.787161) (xy 172.687289 -274.750805) (xy 172.728885 -274.720584) (xy 172.774697 -274.697241)
			(xy 172.823596 -274.681353) (xy 172.874378 -274.67331) (xy 172.925794 -274.67331) (xy 172.976576 -274.681353)
			(xy 173.025475 -274.697241) (xy 173.071287 -274.720584) (xy 173.112883 -274.750805) (xy 173.149239 -274.787161)
			(xy 173.17946 -274.828757) (xy 173.202803 -274.874569) (xy 173.218691 -274.923468) (xy 173.226734 -274.97425)
			(xy 173.227238 -274.999958) (xy 173.226734 -275.025666) (xy 173.218691 -275.076448) (xy 173.202803 -275.125347)
			(xy 173.17946 -275.171159) (xy 173.149239 -275.212755) (xy 173.112883 -275.249111) (xy 173.071287 -275.279332)
			(xy 173.025475 -275.302675) (xy 172.976576 -275.318563) (xy 172.925794 -275.326606) (xy 172.874378 -275.326606)
			(xy 172.823596 -275.318563) (xy 172.774697 -275.302675) (xy 172.728885 -275.279332) (xy 172.687289 -275.249111)
			(xy 172.650933 -275.212755) (xy 172.620712 -275.171159) (xy 172.597369 -275.125347) (xy 172.581481 -275.076448)
			(xy 172.573438 -275.025666) (xy 171.32656 -275.025666) (xy 171.318517 -275.076448) (xy 171.302629 -275.125347)
			(xy 171.279286 -275.171159) (xy 171.249065 -275.212755) (xy 171.212709 -275.249111) (xy 171.171113 -275.279332)
			(xy 171.125301 -275.302675) (xy 171.076402 -275.318563) (xy 171.02562 -275.326606) (xy 170.974204 -275.326606)
			(xy 170.923422 -275.318563) (xy 170.874523 -275.302675) (xy 170.828711 -275.279332) (xy 170.787115 -275.249111)
			(xy 170.750759 -275.212755) (xy 170.720538 -275.171159) (xy 170.697195 -275.125347) (xy 170.681307 -275.076448)
			(xy 170.673264 -275.025666) (xy 169.42664 -275.025666) (xy 169.418597 -275.076448) (xy 169.402709 -275.125347)
			(xy 169.379366 -275.171159) (xy 169.349145 -275.212755) (xy 169.312789 -275.249111) (xy 169.271193 -275.279332)
			(xy 169.225381 -275.302675) (xy 169.176482 -275.318563) (xy 169.1257 -275.326606) (xy 169.074284 -275.326606)
			(xy 169.023502 -275.318563) (xy 168.974603 -275.302675) (xy 168.928791 -275.279332) (xy 168.887195 -275.249111)
			(xy 168.850839 -275.212755) (xy 168.820618 -275.171159) (xy 168.797275 -275.125347) (xy 168.781387 -275.076448)
			(xy 168.773344 -275.025666) (xy 167.52672 -275.025666) (xy 167.518677 -275.076448) (xy 167.502789 -275.125347)
			(xy 167.479446 -275.171159) (xy 167.449225 -275.212755) (xy 167.412869 -275.249111) (xy 167.371273 -275.279332)
			(xy 167.325461 -275.302675) (xy 167.276562 -275.318563) (xy 167.22578 -275.326606) (xy 167.174364 -275.326606)
			(xy 167.123582 -275.318563) (xy 167.074683 -275.302675) (xy 167.028871 -275.279332) (xy 166.987275 -275.249111)
			(xy 166.950919 -275.212755) (xy 166.920698 -275.171159) (xy 166.897355 -275.125347) (xy 166.881467 -275.076448)
			(xy 166.873424 -275.025666) (xy 165.626546 -275.025666) (xy 165.618503 -275.076448) (xy 165.602615 -275.125347)
			(xy 165.579272 -275.171159) (xy 165.549051 -275.212755) (xy 165.512695 -275.249111) (xy 165.471099 -275.279332)
			(xy 165.425287 -275.302675) (xy 165.376388 -275.318563) (xy 165.325606 -275.326606) (xy 165.27419 -275.326606)
			(xy 165.223408 -275.318563) (xy 165.174509 -275.302675) (xy 165.128697 -275.279332) (xy 165.087101 -275.249111)
			(xy 165.050745 -275.212755) (xy 165.020524 -275.171159) (xy 164.997181 -275.125347) (xy 164.981293 -275.076448)
			(xy 164.97325 -275.025666) (xy 163.726626 -275.025666) (xy 163.718583 -275.076448) (xy 163.702695 -275.125347)
			(xy 163.679352 -275.171159) (xy 163.649131 -275.212755) (xy 163.612775 -275.249111) (xy 163.571179 -275.279332)
			(xy 163.525367 -275.302675) (xy 163.476468 -275.318563) (xy 163.425686 -275.326606) (xy 163.37427 -275.326606)
			(xy 163.323488 -275.318563) (xy 163.274589 -275.302675) (xy 163.228777 -275.279332) (xy 163.187181 -275.249111)
			(xy 163.150825 -275.212755) (xy 163.120604 -275.171159) (xy 163.097261 -275.125347) (xy 163.081373 -275.076448)
			(xy 163.07333 -275.025666) (xy 161.826706 -275.025666) (xy 161.818663 -275.076448) (xy 161.802775 -275.125347)
			(xy 161.779432 -275.171159) (xy 161.749211 -275.212755) (xy 161.712855 -275.249111) (xy 161.671259 -275.279332)
			(xy 161.625447 -275.302675) (xy 161.576548 -275.318563) (xy 161.525766 -275.326606) (xy 161.47435 -275.326606)
			(xy 161.423568 -275.318563) (xy 161.374669 -275.302675) (xy 161.328857 -275.279332) (xy 161.287261 -275.249111)
			(xy 161.250905 -275.212755) (xy 161.220684 -275.171159) (xy 161.197341 -275.125347) (xy 161.181453 -275.076448)
			(xy 161.17341 -275.025666) (xy 142.175484 -275.025666) (xy 142.175484 -275.474938) (xy 155.01926 -275.474938)
			(xy 155.02322 -275.425884) (xy 155.034997 -275.3781) (xy 155.054288 -275.332824) (xy 155.080591 -275.291228)
			(xy 155.113226 -275.254391) (xy 155.151347 -275.223266) (xy 155.193968 -275.198659) (xy 155.239984 -275.181207)
			(xy 155.288203 -275.171363) (xy 155.337378 -275.169382) (xy 155.386233 -275.175314) (xy 155.433504 -275.189006)
			(xy 155.477966 -275.210104) (xy 155.518469 -275.23806) (xy 155.553962 -275.272152) (xy 155.583527 -275.311496)
			(xy 155.606398 -275.355073) (xy 155.621982 -275.401754) (xy 155.629877 -275.450331) (xy 155.630372 -275.474938)
			(xy 156.91918 -275.474938) (xy 156.92314 -275.425884) (xy 156.934917 -275.3781) (xy 156.954208 -275.332824)
			(xy 156.980511 -275.291228) (xy 157.013146 -275.254391) (xy 157.051267 -275.223266) (xy 157.093888 -275.198659)
			(xy 157.139904 -275.181207) (xy 157.188123 -275.171363) (xy 157.237298 -275.169382) (xy 157.286153 -275.175314)
			(xy 157.333424 -275.189006) (xy 157.377886 -275.210104) (xy 157.418389 -275.23806) (xy 157.453882 -275.272152)
			(xy 157.483447 -275.311496) (xy 157.506318 -275.355073) (xy 157.521902 -275.401754) (xy 157.529797 -275.450331)
			(xy 157.530292 -275.474938) (xy 158.8191 -275.474938) (xy 158.82306 -275.425884) (xy 158.834837 -275.3781)
			(xy 158.854128 -275.332824) (xy 158.880431 -275.291228) (xy 158.913066 -275.254391) (xy 158.951187 -275.223266)
			(xy 158.993808 -275.198659) (xy 159.039824 -275.181207) (xy 159.088043 -275.171363) (xy 159.137218 -275.169382)
			(xy 159.186073 -275.175314) (xy 159.233344 -275.189006) (xy 159.277806 -275.210104) (xy 159.318309 -275.23806)
			(xy 159.353802 -275.272152) (xy 159.383367 -275.311496) (xy 159.406238 -275.355073) (xy 159.421822 -275.401754)
			(xy 159.429717 -275.450331) (xy 159.430212 -275.474938) (xy 159.429717 -275.499545) (xy 159.421822 -275.548122)
			(xy 159.406238 -275.594803) (xy 159.383367 -275.63838) (xy 159.353802 -275.677724) (xy 159.318309 -275.711816)
			(xy 159.277806 -275.739772) (xy 159.233344 -275.76087) (xy 159.186073 -275.774562) (xy 159.137218 -275.780494)
			(xy 159.088043 -275.778513) (xy 159.039824 -275.768669) (xy 158.993808 -275.751217) (xy 158.951187 -275.72661)
			(xy 158.913066 -275.695485) (xy 158.880431 -275.658648) (xy 158.854128 -275.617052) (xy 158.834837 -275.571776)
			(xy 158.82306 -275.523992) (xy 158.8191 -275.474938) (xy 157.530292 -275.474938) (xy 157.529797 -275.499545)
			(xy 157.521902 -275.548122) (xy 157.506318 -275.594803) (xy 157.483447 -275.63838) (xy 157.453882 -275.677724)
			(xy 157.418389 -275.711816) (xy 157.377886 -275.739772) (xy 157.333424 -275.76087) (xy 157.286153 -275.774562)
			(xy 157.237298 -275.780494) (xy 157.188123 -275.778513) (xy 157.139904 -275.768669) (xy 157.093888 -275.751217)
			(xy 157.051267 -275.72661) (xy 157.013146 -275.695485) (xy 156.980511 -275.658648) (xy 156.954208 -275.617052)
			(xy 156.934917 -275.571776) (xy 156.92314 -275.523992) (xy 156.91918 -275.474938) (xy 155.630372 -275.474938)
			(xy 155.629877 -275.499545) (xy 155.621982 -275.548122) (xy 155.606398 -275.594803) (xy 155.583527 -275.63838)
			(xy 155.553962 -275.677724) (xy 155.518469 -275.711816) (xy 155.477966 -275.739772) (xy 155.433504 -275.76087)
			(xy 155.386233 -275.774562) (xy 155.337378 -275.780494) (xy 155.288203 -275.778513) (xy 155.239984 -275.768669)
			(xy 155.193968 -275.751217) (xy 155.151347 -275.72661) (xy 155.113226 -275.695485) (xy 155.080591 -275.658648)
			(xy 155.054288 -275.617052) (xy 155.034997 -275.571776) (xy 155.02322 -275.523992) (xy 155.01926 -275.474938)
			(xy 142.175484 -275.474938) (xy 142.175484 -275.975626) (xy 161.17341 -275.975626) (xy 161.17341 -275.92421)
			(xy 161.181453 -275.873428) (xy 161.197341 -275.824529) (xy 161.220684 -275.778717) (xy 161.250905 -275.737121)
			(xy 161.287261 -275.700765) (xy 161.328857 -275.670544) (xy 161.374669 -275.647201) (xy 161.423568 -275.631313)
			(xy 161.47435 -275.62327) (xy 161.525766 -275.62327) (xy 161.576548 -275.631313) (xy 161.625447 -275.647201)
			(xy 161.671259 -275.670544) (xy 161.712855 -275.700765) (xy 161.749211 -275.737121) (xy 161.779432 -275.778717)
			(xy 161.802775 -275.824529) (xy 161.818663 -275.873428) (xy 161.826706 -275.92421) (xy 161.82721 -275.949918)
			(xy 161.826706 -275.975626) (xy 163.07333 -275.975626) (xy 163.07333 -275.92421) (xy 163.081373 -275.873428)
			(xy 163.097261 -275.824529) (xy 163.120604 -275.778717) (xy 163.150825 -275.737121) (xy 163.187181 -275.700765)
			(xy 163.228777 -275.670544) (xy 163.274589 -275.647201) (xy 163.323488 -275.631313) (xy 163.37427 -275.62327)
			(xy 163.425686 -275.62327) (xy 163.476468 -275.631313) (xy 163.525367 -275.647201) (xy 163.571179 -275.670544)
			(xy 163.612775 -275.700765) (xy 163.649131 -275.737121) (xy 163.679352 -275.778717) (xy 163.702695 -275.824529)
			(xy 163.718583 -275.873428) (xy 163.726626 -275.92421) (xy 163.72713 -275.949918) (xy 163.726626 -275.975626)
			(xy 164.97325 -275.975626) (xy 164.97325 -275.92421) (xy 164.981293 -275.873428) (xy 164.997181 -275.824529)
			(xy 165.020524 -275.778717) (xy 165.050745 -275.737121) (xy 165.087101 -275.700765) (xy 165.128697 -275.670544)
			(xy 165.174509 -275.647201) (xy 165.223408 -275.631313) (xy 165.27419 -275.62327) (xy 165.325606 -275.62327)
			(xy 165.376388 -275.631313) (xy 165.425287 -275.647201) (xy 165.471099 -275.670544) (xy 165.512695 -275.700765)
			(xy 165.549051 -275.737121) (xy 165.579272 -275.778717) (xy 165.602615 -275.824529) (xy 165.618503 -275.873428)
			(xy 165.626546 -275.92421) (xy 165.62705 -275.949918) (xy 165.626546 -275.975626) (xy 166.873424 -275.975626)
			(xy 166.873424 -275.92421) (xy 166.881467 -275.873428) (xy 166.897355 -275.824529) (xy 166.920698 -275.778717)
			(xy 166.950919 -275.737121) (xy 166.987275 -275.700765) (xy 167.028871 -275.670544) (xy 167.074683 -275.647201)
			(xy 167.123582 -275.631313) (xy 167.174364 -275.62327) (xy 167.22578 -275.62327) (xy 167.276562 -275.631313)
			(xy 167.325461 -275.647201) (xy 167.371273 -275.670544) (xy 167.412869 -275.700765) (xy 167.449225 -275.737121)
			(xy 167.479446 -275.778717) (xy 167.502789 -275.824529) (xy 167.518677 -275.873428) (xy 167.52672 -275.92421)
			(xy 167.527224 -275.949918) (xy 167.52672 -275.975626) (xy 168.773344 -275.975626) (xy 168.773344 -275.92421)
			(xy 168.781387 -275.873428) (xy 168.797275 -275.824529) (xy 168.820618 -275.778717) (xy 168.850839 -275.737121)
			(xy 168.887195 -275.700765) (xy 168.928791 -275.670544) (xy 168.974603 -275.647201) (xy 169.023502 -275.631313)
			(xy 169.074284 -275.62327) (xy 169.1257 -275.62327) (xy 169.176482 -275.631313) (xy 169.225381 -275.647201)
			(xy 169.271193 -275.670544) (xy 169.312789 -275.700765) (xy 169.349145 -275.737121) (xy 169.379366 -275.778717)
			(xy 169.402709 -275.824529) (xy 169.418597 -275.873428) (xy 169.42664 -275.92421) (xy 169.427144 -275.949918)
			(xy 169.42664 -275.975626) (xy 170.673264 -275.975626) (xy 170.673264 -275.92421) (xy 170.681307 -275.873428)
			(xy 170.697195 -275.824529) (xy 170.720538 -275.778717) (xy 170.750759 -275.737121) (xy 170.787115 -275.700765)
			(xy 170.828711 -275.670544) (xy 170.874523 -275.647201) (xy 170.923422 -275.631313) (xy 170.974204 -275.62327)
			(xy 171.02562 -275.62327) (xy 171.076402 -275.631313) (xy 171.125301 -275.647201) (xy 171.171113 -275.670544)
			(xy 171.212709 -275.700765) (xy 171.249065 -275.737121) (xy 171.279286 -275.778717) (xy 171.302629 -275.824529)
			(xy 171.318517 -275.873428) (xy 171.32656 -275.92421) (xy 171.327064 -275.949918) (xy 171.32656 -275.975626)
			(xy 172.573438 -275.975626) (xy 172.573438 -275.92421) (xy 172.581481 -275.873428) (xy 172.597369 -275.824529)
			(xy 172.620712 -275.778717) (xy 172.650933 -275.737121) (xy 172.687289 -275.700765) (xy 172.728885 -275.670544)
			(xy 172.774697 -275.647201) (xy 172.823596 -275.631313) (xy 172.874378 -275.62327) (xy 172.925794 -275.62327)
			(xy 172.976576 -275.631313) (xy 173.025475 -275.647201) (xy 173.071287 -275.670544) (xy 173.112883 -275.700765)
			(xy 173.149239 -275.737121) (xy 173.17946 -275.778717) (xy 173.202803 -275.824529) (xy 173.218691 -275.873428)
			(xy 173.226734 -275.92421) (xy 173.227238 -275.949918) (xy 173.226734 -275.975626) (xy 173.218691 -276.026408)
			(xy 173.202803 -276.075307) (xy 173.17946 -276.121119) (xy 173.149239 -276.162715) (xy 173.112883 -276.199071)
			(xy 173.071287 -276.229292) (xy 173.025475 -276.252635) (xy 172.976576 -276.268523) (xy 172.925794 -276.276566)
			(xy 172.874378 -276.276566) (xy 172.823596 -276.268523) (xy 172.774697 -276.252635) (xy 172.728885 -276.229292)
			(xy 172.687289 -276.199071) (xy 172.650933 -276.162715) (xy 172.620712 -276.121119) (xy 172.597369 -276.075307)
			(xy 172.581481 -276.026408) (xy 172.573438 -275.975626) (xy 171.32656 -275.975626) (xy 171.318517 -276.026408)
			(xy 171.302629 -276.075307) (xy 171.279286 -276.121119) (xy 171.249065 -276.162715) (xy 171.212709 -276.199071)
			(xy 171.171113 -276.229292) (xy 171.125301 -276.252635) (xy 171.076402 -276.268523) (xy 171.02562 -276.276566)
			(xy 170.974204 -276.276566) (xy 170.923422 -276.268523) (xy 170.874523 -276.252635) (xy 170.828711 -276.229292)
			(xy 170.787115 -276.199071) (xy 170.750759 -276.162715) (xy 170.720538 -276.121119) (xy 170.697195 -276.075307)
			(xy 170.681307 -276.026408) (xy 170.673264 -275.975626) (xy 169.42664 -275.975626) (xy 169.418597 -276.026408)
			(xy 169.402709 -276.075307) (xy 169.379366 -276.121119) (xy 169.349145 -276.162715) (xy 169.312789 -276.199071)
			(xy 169.271193 -276.229292) (xy 169.225381 -276.252635) (xy 169.176482 -276.268523) (xy 169.1257 -276.276566)
			(xy 169.074284 -276.276566) (xy 169.023502 -276.268523) (xy 168.974603 -276.252635) (xy 168.928791 -276.229292)
			(xy 168.887195 -276.199071) (xy 168.850839 -276.162715) (xy 168.820618 -276.121119) (xy 168.797275 -276.075307)
			(xy 168.781387 -276.026408) (xy 168.773344 -275.975626) (xy 167.52672 -275.975626) (xy 167.518677 -276.026408)
			(xy 167.502789 -276.075307) (xy 167.479446 -276.121119) (xy 167.449225 -276.162715) (xy 167.412869 -276.199071)
			(xy 167.371273 -276.229292) (xy 167.325461 -276.252635) (xy 167.276562 -276.268523) (xy 167.22578 -276.276566)
			(xy 167.174364 -276.276566) (xy 167.123582 -276.268523) (xy 167.074683 -276.252635) (xy 167.028871 -276.229292)
			(xy 166.987275 -276.199071) (xy 166.950919 -276.162715) (xy 166.920698 -276.121119) (xy 166.897355 -276.075307)
			(xy 166.881467 -276.026408) (xy 166.873424 -275.975626) (xy 165.626546 -275.975626) (xy 165.618503 -276.026408)
			(xy 165.602615 -276.075307) (xy 165.579272 -276.121119) (xy 165.549051 -276.162715) (xy 165.512695 -276.199071)
			(xy 165.471099 -276.229292) (xy 165.425287 -276.252635) (xy 165.376388 -276.268523) (xy 165.325606 -276.276566)
			(xy 165.27419 -276.276566) (xy 165.223408 -276.268523) (xy 165.174509 -276.252635) (xy 165.128697 -276.229292)
			(xy 165.087101 -276.199071) (xy 165.050745 -276.162715) (xy 165.020524 -276.121119) (xy 164.997181 -276.075307)
			(xy 164.981293 -276.026408) (xy 164.97325 -275.975626) (xy 163.726626 -275.975626) (xy 163.718583 -276.026408)
			(xy 163.702695 -276.075307) (xy 163.679352 -276.121119) (xy 163.649131 -276.162715) (xy 163.612775 -276.199071)
			(xy 163.571179 -276.229292) (xy 163.525367 -276.252635) (xy 163.476468 -276.268523) (xy 163.425686 -276.276566)
			(xy 163.37427 -276.276566) (xy 163.323488 -276.268523) (xy 163.274589 -276.252635) (xy 163.228777 -276.229292)
			(xy 163.187181 -276.199071) (xy 163.150825 -276.162715) (xy 163.120604 -276.121119) (xy 163.097261 -276.075307)
			(xy 163.081373 -276.026408) (xy 163.07333 -275.975626) (xy 161.826706 -275.975626) (xy 161.818663 -276.026408)
			(xy 161.802775 -276.075307) (xy 161.779432 -276.121119) (xy 161.749211 -276.162715) (xy 161.712855 -276.199071)
			(xy 161.671259 -276.229292) (xy 161.625447 -276.252635) (xy 161.576548 -276.268523) (xy 161.525766 -276.276566)
			(xy 161.47435 -276.276566) (xy 161.423568 -276.268523) (xy 161.374669 -276.252635) (xy 161.328857 -276.229292)
			(xy 161.287261 -276.199071) (xy 161.250905 -276.162715) (xy 161.220684 -276.121119) (xy 161.197341 -276.075307)
			(xy 161.181453 -276.026408) (xy 161.17341 -275.975626) (xy 142.175484 -275.975626) (xy 142.175484 -276.424898)
			(xy 152.169126 -276.424898) (xy 152.173086 -276.375844) (xy 152.184863 -276.32806) (xy 152.204154 -276.282784)
			(xy 152.230457 -276.241188) (xy 152.263092 -276.204351) (xy 152.301213 -276.173226) (xy 152.343834 -276.148619)
			(xy 152.38985 -276.131167) (xy 152.438069 -276.121323) (xy 152.487244 -276.119342) (xy 152.536099 -276.125274)
			(xy 152.58337 -276.138966) (xy 152.627832 -276.160064) (xy 152.668335 -276.18802) (xy 152.703828 -276.222112)
			(xy 152.733393 -276.261456) (xy 152.756264 -276.305033) (xy 152.771848 -276.351714) (xy 152.779743 -276.400291)
			(xy 152.780238 -276.424898) (xy 153.119086 -276.424898) (xy 153.123046 -276.375844) (xy 153.134823 -276.32806)
			(xy 153.154114 -276.282784) (xy 153.180417 -276.241188) (xy 153.213052 -276.204351) (xy 153.251173 -276.173226)
			(xy 153.293794 -276.148619) (xy 153.33981 -276.131167) (xy 153.388029 -276.121323) (xy 153.437204 -276.119342)
			(xy 153.486059 -276.125274) (xy 153.53333 -276.138966) (xy 153.577792 -276.160064) (xy 153.618295 -276.18802)
			(xy 153.653788 -276.222112) (xy 153.683353 -276.261456) (xy 153.706224 -276.305033) (xy 153.721808 -276.351714)
			(xy 153.729703 -276.400291) (xy 153.730198 -276.424898) (xy 153.729703 -276.449505) (xy 153.721808 -276.498082)
			(xy 153.706224 -276.544763) (xy 153.683353 -276.58834) (xy 153.653788 -276.627684) (xy 153.618295 -276.661776)
			(xy 153.577792 -276.689732) (xy 153.53333 -276.71083) (xy 153.486059 -276.724522) (xy 153.437204 -276.730454)
			(xy 153.388029 -276.728473) (xy 153.33981 -276.718629) (xy 153.293794 -276.701177) (xy 153.251173 -276.67657)
			(xy 153.213052 -276.645445) (xy 153.180417 -276.608608) (xy 153.154114 -276.567012) (xy 153.134823 -276.521736)
			(xy 153.123046 -276.473952) (xy 153.119086 -276.424898) (xy 152.780238 -276.424898) (xy 152.779743 -276.449505)
			(xy 152.771848 -276.498082) (xy 152.756264 -276.544763) (xy 152.733393 -276.58834) (xy 152.703828 -276.627684)
			(xy 152.668335 -276.661776) (xy 152.627832 -276.689732) (xy 152.58337 -276.71083) (xy 152.536099 -276.724522)
			(xy 152.487244 -276.730454) (xy 152.438069 -276.728473) (xy 152.38985 -276.718629) (xy 152.343834 -276.701177)
			(xy 152.301213 -276.67657) (xy 152.263092 -276.645445) (xy 152.230457 -276.608608) (xy 152.204154 -276.567012)
			(xy 152.184863 -276.521736) (xy 152.173086 -276.473952) (xy 152.169126 -276.424898) (xy 142.175484 -276.424898)
			(xy 142.175484 -277.374858) (xy 154.0693 -277.374858) (xy 154.07326 -277.325804) (xy 154.085037 -277.27802)
			(xy 154.104328 -277.232744) (xy 154.130631 -277.191148) (xy 154.163266 -277.154311) (xy 154.201387 -277.123186)
			(xy 154.244008 -277.098579) (xy 154.290024 -277.081127) (xy 154.338243 -277.071283) (xy 154.387418 -277.069302)
			(xy 154.436273 -277.075234) (xy 154.483544 -277.088926) (xy 154.528006 -277.110024) (xy 154.568509 -277.13798)
			(xy 154.604002 -277.172072) (xy 154.633567 -277.211416) (xy 154.656438 -277.254993) (xy 154.672022 -277.301674)
			(xy 154.679917 -277.350251) (xy 154.680412 -277.374858) (xy 155.96922 -277.374858) (xy 155.97318 -277.325804)
			(xy 155.984957 -277.27802) (xy 156.004248 -277.232744) (xy 156.030551 -277.191148) (xy 156.063186 -277.154311)
			(xy 156.101307 -277.123186) (xy 156.143928 -277.098579) (xy 156.189944 -277.081127) (xy 156.238163 -277.071283)
			(xy 156.287338 -277.069302) (xy 156.336193 -277.075234) (xy 156.383464 -277.088926) (xy 156.427926 -277.110024)
			(xy 156.468429 -277.13798) (xy 156.503922 -277.172072) (xy 156.533487 -277.211416) (xy 156.556358 -277.254993)
			(xy 156.571942 -277.301674) (xy 156.579837 -277.350251) (xy 156.580332 -277.374858) (xy 157.86914 -277.374858)
			(xy 157.8731 -277.325804) (xy 157.884877 -277.27802) (xy 157.904168 -277.232744) (xy 157.930471 -277.191148)
			(xy 157.963106 -277.154311) (xy 158.001227 -277.123186) (xy 158.043848 -277.098579) (xy 158.089864 -277.081127)
			(xy 158.138083 -277.071283) (xy 158.187258 -277.069302) (xy 158.236113 -277.075234) (xy 158.283384 -277.088926)
			(xy 158.327846 -277.110024) (xy 158.368349 -277.13798) (xy 158.403842 -277.172072) (xy 158.433407 -277.211416)
			(xy 158.456278 -277.254993) (xy 158.471862 -277.301674) (xy 158.479757 -277.350251) (xy 158.480252 -277.374858)
			(xy 158.479757 -277.399465) (xy 158.471862 -277.448042) (xy 158.456278 -277.494723) (xy 158.433407 -277.5383)
			(xy 158.403842 -277.577644) (xy 158.368349 -277.611736) (xy 158.327846 -277.639692) (xy 158.283384 -277.66079)
			(xy 158.236113 -277.674482) (xy 158.187258 -277.680414) (xy 158.138083 -277.678433) (xy 158.089864 -277.668589)
			(xy 158.043848 -277.651137) (xy 158.001227 -277.62653) (xy 157.963106 -277.595405) (xy 157.930471 -277.558568)
			(xy 157.904168 -277.516972) (xy 157.884877 -277.471696) (xy 157.8731 -277.423912) (xy 157.86914 -277.374858)
			(xy 156.580332 -277.374858) (xy 156.579837 -277.399465) (xy 156.571942 -277.448042) (xy 156.556358 -277.494723)
			(xy 156.533487 -277.5383) (xy 156.503922 -277.577644) (xy 156.468429 -277.611736) (xy 156.427926 -277.639692)
			(xy 156.383464 -277.66079) (xy 156.336193 -277.674482) (xy 156.287338 -277.680414) (xy 156.238163 -277.678433)
			(xy 156.189944 -277.668589) (xy 156.143928 -277.651137) (xy 156.101307 -277.62653) (xy 156.063186 -277.595405)
			(xy 156.030551 -277.558568) (xy 156.004248 -277.516972) (xy 155.984957 -277.471696) (xy 155.97318 -277.423912)
			(xy 155.96922 -277.374858) (xy 154.680412 -277.374858) (xy 154.679917 -277.399465) (xy 154.672022 -277.448042)
			(xy 154.656438 -277.494723) (xy 154.633567 -277.5383) (xy 154.604002 -277.577644) (xy 154.568509 -277.611736)
			(xy 154.528006 -277.639692) (xy 154.483544 -277.66079) (xy 154.436273 -277.674482) (xy 154.387418 -277.680414)
			(xy 154.338243 -277.678433) (xy 154.290024 -277.668589) (xy 154.244008 -277.651137) (xy 154.201387 -277.62653)
			(xy 154.163266 -277.595405) (xy 154.130631 -277.558568) (xy 154.104328 -277.516972) (xy 154.085037 -277.471696)
			(xy 154.07326 -277.423912) (xy 154.0693 -277.374858) (xy 142.175484 -277.374858) (xy 142.175484 -277.849838)
			(xy 160.24404 -277.849838) (xy 160.248 -277.800784) (xy 160.259777 -277.753) (xy 160.279068 -277.707724)
			(xy 160.305371 -277.666128) (xy 160.338006 -277.629291) (xy 160.376127 -277.598166) (xy 160.418748 -277.573559)
			(xy 160.464764 -277.556107) (xy 160.512983 -277.546263) (xy 160.562158 -277.544282) (xy 160.611013 -277.550214)
			(xy 160.658284 -277.563906) (xy 160.702746 -277.585004) (xy 160.743249 -277.61296) (xy 160.778742 -277.647052)
			(xy 160.808307 -277.686396) (xy 160.831178 -277.729973) (xy 160.846762 -277.776654) (xy 160.854657 -277.825231)
			(xy 160.855152 -277.849838) (xy 162.144214 -277.849838) (xy 162.148174 -277.800784) (xy 162.159951 -277.753)
			(xy 162.179242 -277.707724) (xy 162.205545 -277.666128) (xy 162.23818 -277.629291) (xy 162.276301 -277.598166)
			(xy 162.318922 -277.573559) (xy 162.364938 -277.556107) (xy 162.413157 -277.546263) (xy 162.462332 -277.544282)
			(xy 162.511187 -277.550214) (xy 162.558458 -277.563906) (xy 162.60292 -277.585004) (xy 162.643423 -277.61296)
			(xy 162.678916 -277.647052) (xy 162.708481 -277.686396) (xy 162.731352 -277.729973) (xy 162.746936 -277.776654)
			(xy 162.754831 -277.825231) (xy 162.755326 -277.849838) (xy 164.044134 -277.849838) (xy 164.048094 -277.800784)
			(xy 164.059871 -277.753) (xy 164.079162 -277.707724) (xy 164.105465 -277.666128) (xy 164.1381 -277.629291)
			(xy 164.176221 -277.598166) (xy 164.218842 -277.573559) (xy 164.264858 -277.556107) (xy 164.313077 -277.546263)
			(xy 164.362252 -277.544282) (xy 164.411107 -277.550214) (xy 164.458378 -277.563906) (xy 164.50284 -277.585004)
			(xy 164.543343 -277.61296) (xy 164.578836 -277.647052) (xy 164.608401 -277.686396) (xy 164.631272 -277.729973)
			(xy 164.646856 -277.776654) (xy 164.654751 -277.825231) (xy 164.655246 -277.849838) (xy 165.944054 -277.849838)
			(xy 165.948014 -277.800784) (xy 165.959791 -277.753) (xy 165.979082 -277.707724) (xy 166.005385 -277.666128)
			(xy 166.03802 -277.629291) (xy 166.076141 -277.598166) (xy 166.118762 -277.573559) (xy 166.164778 -277.556107)
			(xy 166.212997 -277.546263) (xy 166.262172 -277.544282) (xy 166.311027 -277.550214) (xy 166.358298 -277.563906)
			(xy 166.40276 -277.585004) (xy 166.443263 -277.61296) (xy 166.478756 -277.647052) (xy 166.508321 -277.686396)
			(xy 166.531192 -277.729973) (xy 166.546776 -277.776654) (xy 166.554671 -277.825231) (xy 166.555166 -277.849838)
			(xy 167.844228 -277.849838) (xy 167.848188 -277.800784) (xy 167.859965 -277.753) (xy 167.879256 -277.707724)
			(xy 167.905559 -277.666128) (xy 167.938194 -277.629291) (xy 167.976315 -277.598166) (xy 168.018936 -277.573559)
			(xy 168.064952 -277.556107) (xy 168.113171 -277.546263) (xy 168.162346 -277.544282) (xy 168.211201 -277.550214)
			(xy 168.258472 -277.563906) (xy 168.302934 -277.585004) (xy 168.343437 -277.61296) (xy 168.37893 -277.647052)
			(xy 168.408495 -277.686396) (xy 168.431366 -277.729973) (xy 168.44695 -277.776654) (xy 168.454845 -277.825231)
			(xy 168.45534 -277.849838) (xy 169.744148 -277.849838) (xy 169.748108 -277.800784) (xy 169.759885 -277.753)
			(xy 169.779176 -277.707724) (xy 169.805479 -277.666128) (xy 169.838114 -277.629291) (xy 169.876235 -277.598166)
			(xy 169.918856 -277.573559) (xy 169.964872 -277.556107) (xy 170.013091 -277.546263) (xy 170.062266 -277.544282)
			(xy 170.111121 -277.550214) (xy 170.158392 -277.563906) (xy 170.202854 -277.585004) (xy 170.243357 -277.61296)
			(xy 170.27885 -277.647052) (xy 170.308415 -277.686396) (xy 170.331286 -277.729973) (xy 170.34687 -277.776654)
			(xy 170.354765 -277.825231) (xy 170.35526 -277.849838) (xy 171.644068 -277.849838) (xy 171.648028 -277.800784)
			(xy 171.659805 -277.753) (xy 171.679096 -277.707724) (xy 171.705399 -277.666128) (xy 171.738034 -277.629291)
			(xy 171.776155 -277.598166) (xy 171.818776 -277.573559) (xy 171.864792 -277.556107) (xy 171.913011 -277.546263)
			(xy 171.962186 -277.544282) (xy 172.011041 -277.550214) (xy 172.058312 -277.563906) (xy 172.102774 -277.585004)
			(xy 172.143277 -277.61296) (xy 172.17877 -277.647052) (xy 172.208335 -277.686396) (xy 172.231206 -277.729973)
			(xy 172.24679 -277.776654) (xy 172.254685 -277.825231) (xy 172.25518 -277.849838) (xy 172.254685 -277.874445)
			(xy 172.24679 -277.923022) (xy 172.231206 -277.969703) (xy 172.208335 -278.01328) (xy 172.17877 -278.052624)
			(xy 172.143277 -278.086716) (xy 172.102774 -278.114672) (xy 172.058312 -278.13577) (xy 172.011041 -278.149462)
			(xy 171.962186 -278.155394) (xy 171.913011 -278.153413) (xy 171.864792 -278.143569) (xy 171.818776 -278.126117)
			(xy 171.776155 -278.10151) (xy 171.738034 -278.070385) (xy 171.705399 -278.033548) (xy 171.679096 -277.991952)
			(xy 171.659805 -277.946676) (xy 171.648028 -277.898892) (xy 171.644068 -277.849838) (xy 170.35526 -277.849838)
			(xy 170.354765 -277.874445) (xy 170.34687 -277.923022) (xy 170.331286 -277.969703) (xy 170.308415 -278.01328)
			(xy 170.27885 -278.052624) (xy 170.243357 -278.086716) (xy 170.202854 -278.114672) (xy 170.158392 -278.13577)
			(xy 170.111121 -278.149462) (xy 170.062266 -278.155394) (xy 170.013091 -278.153413) (xy 169.964872 -278.143569)
			(xy 169.918856 -278.126117) (xy 169.876235 -278.10151) (xy 169.838114 -278.070385) (xy 169.805479 -278.033548)
			(xy 169.779176 -277.991952) (xy 169.759885 -277.946676) (xy 169.748108 -277.898892) (xy 169.744148 -277.849838)
			(xy 168.45534 -277.849838) (xy 168.454845 -277.874445) (xy 168.44695 -277.923022) (xy 168.431366 -277.969703)
			(xy 168.408495 -278.01328) (xy 168.37893 -278.052624) (xy 168.343437 -278.086716) (xy 168.302934 -278.114672)
			(xy 168.258472 -278.13577) (xy 168.211201 -278.149462) (xy 168.162346 -278.155394) (xy 168.113171 -278.153413)
			(xy 168.064952 -278.143569) (xy 168.018936 -278.126117) (xy 167.976315 -278.10151) (xy 167.938194 -278.070385)
			(xy 167.905559 -278.033548) (xy 167.879256 -277.991952) (xy 167.859965 -277.946676) (xy 167.848188 -277.898892)
			(xy 167.844228 -277.849838) (xy 166.555166 -277.849838) (xy 166.554671 -277.874445) (xy 166.546776 -277.923022)
			(xy 166.531192 -277.969703) (xy 166.508321 -278.01328) (xy 166.478756 -278.052624) (xy 166.443263 -278.086716)
			(xy 166.40276 -278.114672) (xy 166.358298 -278.13577) (xy 166.311027 -278.149462) (xy 166.262172 -278.155394)
			(xy 166.212997 -278.153413) (xy 166.164778 -278.143569) (xy 166.118762 -278.126117) (xy 166.076141 -278.10151)
			(xy 166.03802 -278.070385) (xy 166.005385 -278.033548) (xy 165.979082 -277.991952) (xy 165.959791 -277.946676)
			(xy 165.948014 -277.898892) (xy 165.944054 -277.849838) (xy 164.655246 -277.849838) (xy 164.654751 -277.874445)
			(xy 164.646856 -277.923022) (xy 164.631272 -277.969703) (xy 164.608401 -278.01328) (xy 164.578836 -278.052624)
			(xy 164.543343 -278.086716) (xy 164.50284 -278.114672) (xy 164.458378 -278.13577) (xy 164.411107 -278.149462)
			(xy 164.362252 -278.155394) (xy 164.313077 -278.153413) (xy 164.264858 -278.143569) (xy 164.218842 -278.126117)
			(xy 164.176221 -278.10151) (xy 164.1381 -278.070385) (xy 164.105465 -278.033548) (xy 164.079162 -277.991952)
			(xy 164.059871 -277.946676) (xy 164.048094 -277.898892) (xy 164.044134 -277.849838) (xy 162.755326 -277.849838)
			(xy 162.754831 -277.874445) (xy 162.746936 -277.923022) (xy 162.731352 -277.969703) (xy 162.708481 -278.01328)
			(xy 162.678916 -278.052624) (xy 162.643423 -278.086716) (xy 162.60292 -278.114672) (xy 162.558458 -278.13577)
			(xy 162.511187 -278.149462) (xy 162.462332 -278.155394) (xy 162.413157 -278.153413) (xy 162.364938 -278.143569)
			(xy 162.318922 -278.126117) (xy 162.276301 -278.10151) (xy 162.23818 -278.070385) (xy 162.205545 -278.033548)
			(xy 162.179242 -277.991952) (xy 162.159951 -277.946676) (xy 162.148174 -277.898892) (xy 162.144214 -277.849838)
			(xy 160.855152 -277.849838) (xy 160.854657 -277.874445) (xy 160.846762 -277.923022) (xy 160.831178 -277.969703)
			(xy 160.808307 -278.01328) (xy 160.778742 -278.052624) (xy 160.743249 -278.086716) (xy 160.702746 -278.114672)
			(xy 160.658284 -278.13577) (xy 160.611013 -278.149462) (xy 160.562158 -278.155394) (xy 160.512983 -278.153413)
			(xy 160.464764 -278.143569) (xy 160.418748 -278.126117) (xy 160.376127 -278.10151) (xy 160.338006 -278.070385)
			(xy 160.305371 -278.033548) (xy 160.279068 -277.991952) (xy 160.259777 -277.946676) (xy 160.248 -277.898892)
			(xy 160.24404 -277.849838) (xy 142.175484 -277.849838) (xy 142.175484 -278.324818) (xy 154.0693 -278.324818)
			(xy 154.07326 -278.275764) (xy 154.085037 -278.22798) (xy 154.104328 -278.182704) (xy 154.130631 -278.141108)
			(xy 154.163266 -278.104271) (xy 154.201387 -278.073146) (xy 154.244008 -278.048539) (xy 154.290024 -278.031087)
			(xy 154.338243 -278.021243) (xy 154.387418 -278.019262) (xy 154.436273 -278.025194) (xy 154.483544 -278.038886)
			(xy 154.528006 -278.059984) (xy 154.568509 -278.08794) (xy 154.604002 -278.122032) (xy 154.633567 -278.161376)
			(xy 154.656438 -278.204953) (xy 154.672022 -278.251634) (xy 154.679917 -278.300211) (xy 154.680412 -278.324818)
			(xy 155.96922 -278.324818) (xy 155.97318 -278.275764) (xy 155.984957 -278.22798) (xy 156.004248 -278.182704)
			(xy 156.030551 -278.141108) (xy 156.063186 -278.104271) (xy 156.101307 -278.073146) (xy 156.143928 -278.048539)
			(xy 156.189944 -278.031087) (xy 156.238163 -278.021243) (xy 156.287338 -278.019262) (xy 156.336193 -278.025194)
			(xy 156.383464 -278.038886) (xy 156.427926 -278.059984) (xy 156.468429 -278.08794) (xy 156.503922 -278.122032)
			(xy 156.533487 -278.161376) (xy 156.556358 -278.204953) (xy 156.571942 -278.251634) (xy 156.579837 -278.300211)
			(xy 156.580332 -278.324818) (xy 157.86914 -278.324818) (xy 157.8731 -278.275764) (xy 157.884877 -278.22798)
			(xy 157.904168 -278.182704) (xy 157.930471 -278.141108) (xy 157.963106 -278.104271) (xy 158.001227 -278.073146)
			(xy 158.043848 -278.048539) (xy 158.089864 -278.031087) (xy 158.138083 -278.021243) (xy 158.187258 -278.019262)
			(xy 158.236113 -278.025194) (xy 158.283384 -278.038886) (xy 158.327846 -278.059984) (xy 158.368349 -278.08794)
			(xy 158.403842 -278.122032) (xy 158.433407 -278.161376) (xy 158.456278 -278.204953) (xy 158.471862 -278.251634)
			(xy 158.479757 -278.300211) (xy 158.480252 -278.324818) (xy 158.479757 -278.349425) (xy 158.471862 -278.398002)
			(xy 158.456278 -278.444683) (xy 158.433407 -278.48826) (xy 158.403842 -278.527604) (xy 158.368349 -278.561696)
			(xy 158.327846 -278.589652) (xy 158.283384 -278.61075) (xy 158.236113 -278.624442) (xy 158.187258 -278.630374)
			(xy 158.138083 -278.628393) (xy 158.089864 -278.618549) (xy 158.043848 -278.601097) (xy 158.001227 -278.57649)
			(xy 157.963106 -278.545365) (xy 157.930471 -278.508528) (xy 157.904168 -278.466932) (xy 157.884877 -278.421656)
			(xy 157.8731 -278.373872) (xy 157.86914 -278.324818) (xy 156.580332 -278.324818) (xy 156.579837 -278.349425)
			(xy 156.571942 -278.398002) (xy 156.556358 -278.444683) (xy 156.533487 -278.48826) (xy 156.503922 -278.527604)
			(xy 156.468429 -278.561696) (xy 156.427926 -278.589652) (xy 156.383464 -278.61075) (xy 156.336193 -278.624442)
			(xy 156.287338 -278.630374) (xy 156.238163 -278.628393) (xy 156.189944 -278.618549) (xy 156.143928 -278.601097)
			(xy 156.101307 -278.57649) (xy 156.063186 -278.545365) (xy 156.030551 -278.508528) (xy 156.004248 -278.466932)
			(xy 155.984957 -278.421656) (xy 155.97318 -278.373872) (xy 155.96922 -278.324818) (xy 154.680412 -278.324818)
			(xy 154.679917 -278.349425) (xy 154.672022 -278.398002) (xy 154.656438 -278.444683) (xy 154.633567 -278.48826)
			(xy 154.604002 -278.527604) (xy 154.568509 -278.561696) (xy 154.528006 -278.589652) (xy 154.483544 -278.61075)
			(xy 154.436273 -278.624442) (xy 154.387418 -278.630374) (xy 154.338243 -278.628393) (xy 154.290024 -278.618549)
			(xy 154.244008 -278.601097) (xy 154.201387 -278.57649) (xy 154.163266 -278.545365) (xy 154.130631 -278.508528)
			(xy 154.104328 -278.466932) (xy 154.085037 -278.421656) (xy 154.07326 -278.373872) (xy 154.0693 -278.324818)
			(xy 142.175484 -278.324818) (xy 142.175484 -278.799798) (xy 160.24404 -278.799798) (xy 160.248 -278.750744)
			(xy 160.259777 -278.70296) (xy 160.279068 -278.657684) (xy 160.305371 -278.616088) (xy 160.338006 -278.579251)
			(xy 160.376127 -278.548126) (xy 160.418748 -278.523519) (xy 160.464764 -278.506067) (xy 160.512983 -278.496223)
			(xy 160.562158 -278.494242) (xy 160.611013 -278.500174) (xy 160.658284 -278.513866) (xy 160.702746 -278.534964)
			(xy 160.743249 -278.56292) (xy 160.778742 -278.597012) (xy 160.808307 -278.636356) (xy 160.831178 -278.679933)
			(xy 160.846762 -278.726614) (xy 160.854657 -278.775191) (xy 160.855152 -278.799798) (xy 162.144214 -278.799798)
			(xy 162.148174 -278.750744) (xy 162.159951 -278.70296) (xy 162.179242 -278.657684) (xy 162.205545 -278.616088)
			(xy 162.23818 -278.579251) (xy 162.276301 -278.548126) (xy 162.318922 -278.523519) (xy 162.364938 -278.506067)
			(xy 162.413157 -278.496223) (xy 162.462332 -278.494242) (xy 162.511187 -278.500174) (xy 162.558458 -278.513866)
			(xy 162.60292 -278.534964) (xy 162.643423 -278.56292) (xy 162.678916 -278.597012) (xy 162.708481 -278.636356)
			(xy 162.731352 -278.679933) (xy 162.746936 -278.726614) (xy 162.754831 -278.775191) (xy 162.755326 -278.799798)
			(xy 164.044134 -278.799798) (xy 164.048094 -278.750744) (xy 164.059871 -278.70296) (xy 164.079162 -278.657684)
			(xy 164.105465 -278.616088) (xy 164.1381 -278.579251) (xy 164.176221 -278.548126) (xy 164.218842 -278.523519)
			(xy 164.264858 -278.506067) (xy 164.313077 -278.496223) (xy 164.362252 -278.494242) (xy 164.411107 -278.500174)
			(xy 164.458378 -278.513866) (xy 164.50284 -278.534964) (xy 164.543343 -278.56292) (xy 164.578836 -278.597012)
			(xy 164.608401 -278.636356) (xy 164.631272 -278.679933) (xy 164.646856 -278.726614) (xy 164.654751 -278.775191)
			(xy 164.655246 -278.799798) (xy 165.944054 -278.799798) (xy 165.948014 -278.750744) (xy 165.959791 -278.70296)
			(xy 165.979082 -278.657684) (xy 166.005385 -278.616088) (xy 166.03802 -278.579251) (xy 166.076141 -278.548126)
			(xy 166.118762 -278.523519) (xy 166.164778 -278.506067) (xy 166.212997 -278.496223) (xy 166.262172 -278.494242)
			(xy 166.311027 -278.500174) (xy 166.358298 -278.513866) (xy 166.40276 -278.534964) (xy 166.443263 -278.56292)
			(xy 166.478756 -278.597012) (xy 166.508321 -278.636356) (xy 166.531192 -278.679933) (xy 166.546776 -278.726614)
			(xy 166.554671 -278.775191) (xy 166.555166 -278.799798) (xy 167.844228 -278.799798) (xy 167.848188 -278.750744)
			(xy 167.859965 -278.70296) (xy 167.879256 -278.657684) (xy 167.905559 -278.616088) (xy 167.938194 -278.579251)
			(xy 167.976315 -278.548126) (xy 168.018936 -278.523519) (xy 168.064952 -278.506067) (xy 168.113171 -278.496223)
			(xy 168.162346 -278.494242) (xy 168.211201 -278.500174) (xy 168.258472 -278.513866) (xy 168.302934 -278.534964)
			(xy 168.343437 -278.56292) (xy 168.37893 -278.597012) (xy 168.408495 -278.636356) (xy 168.431366 -278.679933)
			(xy 168.44695 -278.726614) (xy 168.454845 -278.775191) (xy 168.45534 -278.799798) (xy 169.744148 -278.799798)
			(xy 169.748108 -278.750744) (xy 169.759885 -278.70296) (xy 169.779176 -278.657684) (xy 169.805479 -278.616088)
			(xy 169.838114 -278.579251) (xy 169.876235 -278.548126) (xy 169.918856 -278.523519) (xy 169.964872 -278.506067)
			(xy 170.013091 -278.496223) (xy 170.062266 -278.494242) (xy 170.111121 -278.500174) (xy 170.158392 -278.513866)
			(xy 170.202854 -278.534964) (xy 170.243357 -278.56292) (xy 170.27885 -278.597012) (xy 170.308415 -278.636356)
			(xy 170.331286 -278.679933) (xy 170.34687 -278.726614) (xy 170.354765 -278.775191) (xy 170.35526 -278.799798)
			(xy 171.644068 -278.799798) (xy 171.648028 -278.750744) (xy 171.659805 -278.70296) (xy 171.679096 -278.657684)
			(xy 171.705399 -278.616088) (xy 171.738034 -278.579251) (xy 171.776155 -278.548126) (xy 171.818776 -278.523519)
			(xy 171.864792 -278.506067) (xy 171.913011 -278.496223) (xy 171.962186 -278.494242) (xy 172.011041 -278.500174)
			(xy 172.058312 -278.513866) (xy 172.102774 -278.534964) (xy 172.143277 -278.56292) (xy 172.17877 -278.597012)
			(xy 172.208335 -278.636356) (xy 172.231206 -278.679933) (xy 172.24679 -278.726614) (xy 172.254685 -278.775191)
			(xy 172.25518 -278.799798) (xy 173.544242 -278.799798) (xy 173.548202 -278.750744) (xy 173.559979 -278.70296)
			(xy 173.57927 -278.657684) (xy 173.605573 -278.616088) (xy 173.638208 -278.579251) (xy 173.676329 -278.548126)
			(xy 173.71895 -278.523519) (xy 173.764966 -278.506067) (xy 173.813185 -278.496223) (xy 173.86236 -278.494242)
			(xy 173.911215 -278.500174) (xy 173.958486 -278.513866) (xy 174.002948 -278.534964) (xy 174.043451 -278.56292)
			(xy 174.078944 -278.597012) (xy 174.108509 -278.636356) (xy 174.13138 -278.679933) (xy 174.146964 -278.726614)
			(xy 174.154859 -278.775191) (xy 174.155354 -278.799798) (xy 174.154859 -278.824405) (xy 174.146964 -278.872982)
			(xy 174.13138 -278.919663) (xy 174.108509 -278.96324) (xy 174.078944 -279.002584) (xy 174.043451 -279.036676)
			(xy 174.002948 -279.064632) (xy 173.958486 -279.08573) (xy 173.911215 -279.099422) (xy 173.86236 -279.105354)
			(xy 173.813185 -279.103373) (xy 173.764966 -279.093529) (xy 173.71895 -279.076077) (xy 173.676329 -279.05147)
			(xy 173.638208 -279.020345) (xy 173.605573 -278.983508) (xy 173.57927 -278.941912) (xy 173.559979 -278.896636)
			(xy 173.548202 -278.848852) (xy 173.544242 -278.799798) (xy 172.25518 -278.799798) (xy 172.254685 -278.824405)
			(xy 172.24679 -278.872982) (xy 172.231206 -278.919663) (xy 172.208335 -278.96324) (xy 172.17877 -279.002584)
			(xy 172.143277 -279.036676) (xy 172.102774 -279.064632) (xy 172.058312 -279.08573) (xy 172.011041 -279.099422)
			(xy 171.962186 -279.105354) (xy 171.913011 -279.103373) (xy 171.864792 -279.093529) (xy 171.818776 -279.076077)
			(xy 171.776155 -279.05147) (xy 171.738034 -279.020345) (xy 171.705399 -278.983508) (xy 171.679096 -278.941912)
			(xy 171.659805 -278.896636) (xy 171.648028 -278.848852) (xy 171.644068 -278.799798) (xy 170.35526 -278.799798)
			(xy 170.354765 -278.824405) (xy 170.34687 -278.872982) (xy 170.331286 -278.919663) (xy 170.308415 -278.96324)
			(xy 170.27885 -279.002584) (xy 170.243357 -279.036676) (xy 170.202854 -279.064632) (xy 170.158392 -279.08573)
			(xy 170.111121 -279.099422) (xy 170.062266 -279.105354) (xy 170.013091 -279.103373) (xy 169.964872 -279.093529)
			(xy 169.918856 -279.076077) (xy 169.876235 -279.05147) (xy 169.838114 -279.020345) (xy 169.805479 -278.983508)
			(xy 169.779176 -278.941912) (xy 169.759885 -278.896636) (xy 169.748108 -278.848852) (xy 169.744148 -278.799798)
			(xy 168.45534 -278.799798) (xy 168.454845 -278.824405) (xy 168.44695 -278.872982) (xy 168.431366 -278.919663)
			(xy 168.408495 -278.96324) (xy 168.37893 -279.002584) (xy 168.343437 -279.036676) (xy 168.302934 -279.064632)
			(xy 168.258472 -279.08573) (xy 168.211201 -279.099422) (xy 168.162346 -279.105354) (xy 168.113171 -279.103373)
			(xy 168.064952 -279.093529) (xy 168.018936 -279.076077) (xy 167.976315 -279.05147) (xy 167.938194 -279.020345)
			(xy 167.905559 -278.983508) (xy 167.879256 -278.941912) (xy 167.859965 -278.896636) (xy 167.848188 -278.848852)
			(xy 167.844228 -278.799798) (xy 166.555166 -278.799798) (xy 166.554671 -278.824405) (xy 166.546776 -278.872982)
			(xy 166.531192 -278.919663) (xy 166.508321 -278.96324) (xy 166.478756 -279.002584) (xy 166.443263 -279.036676)
			(xy 166.40276 -279.064632) (xy 166.358298 -279.08573) (xy 166.311027 -279.099422) (xy 166.262172 -279.105354)
			(xy 166.212997 -279.103373) (xy 166.164778 -279.093529) (xy 166.118762 -279.076077) (xy 166.076141 -279.05147)
			(xy 166.03802 -279.020345) (xy 166.005385 -278.983508) (xy 165.979082 -278.941912) (xy 165.959791 -278.896636)
			(xy 165.948014 -278.848852) (xy 165.944054 -278.799798) (xy 164.655246 -278.799798) (xy 164.654751 -278.824405)
			(xy 164.646856 -278.872982) (xy 164.631272 -278.919663) (xy 164.608401 -278.96324) (xy 164.578836 -279.002584)
			(xy 164.543343 -279.036676) (xy 164.50284 -279.064632) (xy 164.458378 -279.08573) (xy 164.411107 -279.099422)
			(xy 164.362252 -279.105354) (xy 164.313077 -279.103373) (xy 164.264858 -279.093529) (xy 164.218842 -279.076077)
			(xy 164.176221 -279.05147) (xy 164.1381 -279.020345) (xy 164.105465 -278.983508) (xy 164.079162 -278.941912)
			(xy 164.059871 -278.896636) (xy 164.048094 -278.848852) (xy 164.044134 -278.799798) (xy 162.755326 -278.799798)
			(xy 162.754831 -278.824405) (xy 162.746936 -278.872982) (xy 162.731352 -278.919663) (xy 162.708481 -278.96324)
			(xy 162.678916 -279.002584) (xy 162.643423 -279.036676) (xy 162.60292 -279.064632) (xy 162.558458 -279.08573)
			(xy 162.511187 -279.099422) (xy 162.462332 -279.105354) (xy 162.413157 -279.103373) (xy 162.364938 -279.093529)
			(xy 162.318922 -279.076077) (xy 162.276301 -279.05147) (xy 162.23818 -279.020345) (xy 162.205545 -278.983508)
			(xy 162.179242 -278.941912) (xy 162.159951 -278.896636) (xy 162.148174 -278.848852) (xy 162.144214 -278.799798)
			(xy 160.855152 -278.799798) (xy 160.854657 -278.824405) (xy 160.846762 -278.872982) (xy 160.831178 -278.919663)
			(xy 160.808307 -278.96324) (xy 160.778742 -279.002584) (xy 160.743249 -279.036676) (xy 160.702746 -279.064632)
			(xy 160.658284 -279.08573) (xy 160.611013 -279.099422) (xy 160.562158 -279.105354) (xy 160.512983 -279.103373)
			(xy 160.464764 -279.093529) (xy 160.418748 -279.076077) (xy 160.376127 -279.05147) (xy 160.338006 -279.020345)
			(xy 160.305371 -278.983508) (xy 160.279068 -278.941912) (xy 160.259777 -278.896636) (xy 160.248 -278.848852)
			(xy 160.24404 -278.799798) (xy 142.175484 -278.799798) (xy 142.175484 -279.274778) (xy 152.169126 -279.274778)
			(xy 152.173086 -279.225724) (xy 152.184863 -279.17794) (xy 152.204154 -279.132664) (xy 152.230457 -279.091068)
			(xy 152.263092 -279.054231) (xy 152.301213 -279.023106) (xy 152.343834 -278.998499) (xy 152.38985 -278.981047)
			(xy 152.438069 -278.971203) (xy 152.487244 -278.969222) (xy 152.536099 -278.975154) (xy 152.58337 -278.988846)
			(xy 152.627832 -279.009944) (xy 152.668335 -279.0379) (xy 152.703828 -279.071992) (xy 152.733393 -279.111336)
			(xy 152.756264 -279.154913) (xy 152.771848 -279.201594) (xy 152.779743 -279.250171) (xy 152.780238 -279.274778)
			(xy 153.119086 -279.274778) (xy 153.123046 -279.225724) (xy 153.134823 -279.17794) (xy 153.154114 -279.132664)
			(xy 153.180417 -279.091068) (xy 153.213052 -279.054231) (xy 153.251173 -279.023106) (xy 153.293794 -278.998499)
			(xy 153.33981 -278.981047) (xy 153.388029 -278.971203) (xy 153.437204 -278.969222) (xy 153.486059 -278.975154)
			(xy 153.53333 -278.988846) (xy 153.577792 -279.009944) (xy 153.618295 -279.0379) (xy 153.653788 -279.071992)
			(xy 153.683353 -279.111336) (xy 153.706224 -279.154913) (xy 153.721808 -279.201594) (xy 153.729703 -279.250171)
			(xy 153.730198 -279.274778) (xy 155.01926 -279.274778) (xy 155.02322 -279.225724) (xy 155.034997 -279.17794)
			(xy 155.054288 -279.132664) (xy 155.080591 -279.091068) (xy 155.113226 -279.054231) (xy 155.151347 -279.023106)
			(xy 155.193968 -278.998499) (xy 155.239984 -278.981047) (xy 155.288203 -278.971203) (xy 155.337378 -278.969222)
			(xy 155.386233 -278.975154) (xy 155.433504 -278.988846) (xy 155.477966 -279.009944) (xy 155.518469 -279.0379)
			(xy 155.553962 -279.071992) (xy 155.583527 -279.111336) (xy 155.606398 -279.154913) (xy 155.621982 -279.201594)
			(xy 155.629877 -279.250171) (xy 155.630372 -279.274778) (xy 156.91918 -279.274778) (xy 156.92314 -279.225724)
			(xy 156.934917 -279.17794) (xy 156.954208 -279.132664) (xy 156.980511 -279.091068) (xy 157.013146 -279.054231)
			(xy 157.051267 -279.023106) (xy 157.093888 -278.998499) (xy 157.139904 -278.981047) (xy 157.188123 -278.971203)
			(xy 157.237298 -278.969222) (xy 157.286153 -278.975154) (xy 157.333424 -278.988846) (xy 157.377886 -279.009944)
			(xy 157.418389 -279.0379) (xy 157.453882 -279.071992) (xy 157.483447 -279.111336) (xy 157.506318 -279.154913)
			(xy 157.521902 -279.201594) (xy 157.529797 -279.250171) (xy 157.530292 -279.274778) (xy 157.529797 -279.299385)
			(xy 157.521902 -279.347962) (xy 157.506318 -279.394643) (xy 157.483447 -279.43822) (xy 157.453882 -279.477564)
			(xy 157.418389 -279.511656) (xy 157.377886 -279.539612) (xy 157.333424 -279.56071) (xy 157.286153 -279.574402)
			(xy 157.237298 -279.580334) (xy 157.188123 -279.578353) (xy 157.139904 -279.568509) (xy 157.093888 -279.551057)
			(xy 157.051267 -279.52645) (xy 157.013146 -279.495325) (xy 156.980511 -279.458488) (xy 156.954208 -279.416892)
			(xy 156.934917 -279.371616) (xy 156.92314 -279.323832) (xy 156.91918 -279.274778) (xy 155.630372 -279.274778)
			(xy 155.629877 -279.299385) (xy 155.621982 -279.347962) (xy 155.606398 -279.394643) (xy 155.583527 -279.43822)
			(xy 155.553962 -279.477564) (xy 155.518469 -279.511656) (xy 155.477966 -279.539612) (xy 155.433504 -279.56071)
			(xy 155.386233 -279.574402) (xy 155.337378 -279.580334) (xy 155.288203 -279.578353) (xy 155.239984 -279.568509)
			(xy 155.193968 -279.551057) (xy 155.151347 -279.52645) (xy 155.113226 -279.495325) (xy 155.080591 -279.458488)
			(xy 155.054288 -279.416892) (xy 155.034997 -279.371616) (xy 155.02322 -279.323832) (xy 155.01926 -279.274778)
			(xy 153.730198 -279.274778) (xy 153.729703 -279.299385) (xy 153.721808 -279.347962) (xy 153.706224 -279.394643)
			(xy 153.683353 -279.43822) (xy 153.653788 -279.477564) (xy 153.618295 -279.511656) (xy 153.577792 -279.539612)
			(xy 153.53333 -279.56071) (xy 153.486059 -279.574402) (xy 153.437204 -279.580334) (xy 153.388029 -279.578353)
			(xy 153.33981 -279.568509) (xy 153.293794 -279.551057) (xy 153.251173 -279.52645) (xy 153.213052 -279.495325)
			(xy 153.180417 -279.458488) (xy 153.154114 -279.416892) (xy 153.134823 -279.371616) (xy 153.123046 -279.323832)
			(xy 153.119086 -279.274778) (xy 152.780238 -279.274778) (xy 152.779743 -279.299385) (xy 152.771848 -279.347962)
			(xy 152.756264 -279.394643) (xy 152.733393 -279.43822) (xy 152.703828 -279.477564) (xy 152.668335 -279.511656)
			(xy 152.627832 -279.539612) (xy 152.58337 -279.56071) (xy 152.536099 -279.574402) (xy 152.487244 -279.580334)
			(xy 152.438069 -279.578353) (xy 152.38985 -279.568509) (xy 152.343834 -279.551057) (xy 152.301213 -279.52645)
			(xy 152.263092 -279.495325) (xy 152.230457 -279.458488) (xy 152.204154 -279.416892) (xy 152.184863 -279.371616)
			(xy 152.173086 -279.323832) (xy 152.169126 -279.274778) (xy 142.175484 -279.274778) (xy 142.175484 -280.139394)
			(xy 142.176246 -280.147776) (xy 142.177755 -280.155384) (xy 142.184732 -280.169227) (xy 142.189962 -280.174954)
			(xy 142.571978 -280.55697) (xy 142.577728 -280.562166) (xy 142.591562 -280.569137) (xy 142.599156 -280.570686)
			(xy 142.607538 -280.571448) (xy 146.79295 -280.571448) (xy 146.803015 -280.571882) (xy 146.821602 -280.579614)
			(xy 146.829018 -280.586434) (xy 146.935698 -280.693114) (xy 147.43811 -280.693114) (xy 147.438654 -280.663732)
			(xy 147.447683 -280.605665) (xy 147.465514 -280.549671) (xy 147.491725 -280.497075) (xy 147.525695 -280.449124)
			(xy 147.56662 -280.406952) (xy 147.589748 -280.388822) (xy 147.598672 -280.381342) (xy 147.609132 -280.360568)
			(xy 147.609814 -280.348944) (xy 147.611084 -280.256996) (xy 147.601178 -280.235914) (xy 147.592034 -280.228548)
			(xy 147.570186 -280.210342) (xy 147.531644 -280.168524) (xy 147.499736 -280.121449) (xy 147.475169 -280.070159)
			(xy 147.458486 -280.015791) (xy 147.450058 -279.959549) (xy 147.44954 -279.931114) (xy 147.450026 -279.903863)
			(xy 147.457782 -279.849915) (xy 147.473137 -279.79762) (xy 147.495779 -279.748043) (xy 147.525245 -279.702193)
			(xy 147.560936 -279.661002) (xy 147.602127 -279.625311) (xy 147.647977 -279.595845) (xy 147.697554 -279.573203)
			(xy 147.749849 -279.557848) (xy 147.803797 -279.550092) (xy 147.858299 -279.550092) (xy 147.912247 -279.557848)
			(xy 147.964542 -279.573203) (xy 148.014119 -279.595845) (xy 148.059969 -279.625311) (xy 148.10116 -279.661002)
			(xy 148.136851 -279.702193) (xy 148.166317 -279.748043) (xy 148.188959 -279.79762) (xy 148.204314 -279.849915)
			(xy 148.21207 -279.903863) (xy 148.212556 -279.931114) (xy 148.212006 -279.960496) (xy 148.202975 -280.018561)
			(xy 148.185143 -280.074554) (xy 148.158933 -280.127149) (xy 148.124966 -280.175101) (xy 148.084044 -280.217274)
			(xy 148.074524 -280.224738) (xy 155.01926 -280.224738) (xy 155.02322 -280.175684) (xy 155.034997 -280.1279)
			(xy 155.054288 -280.082624) (xy 155.080591 -280.041028) (xy 155.113226 -280.004191) (xy 155.151347 -279.973066)
			(xy 155.193968 -279.948459) (xy 155.239984 -279.931007) (xy 155.288203 -279.921163) (xy 155.337378 -279.919182)
			(xy 155.386233 -279.925114) (xy 155.433504 -279.938806) (xy 155.477966 -279.959904) (xy 155.518469 -279.98786)
			(xy 155.553962 -280.021952) (xy 155.583527 -280.061296) (xy 155.606398 -280.104873) (xy 155.621982 -280.151554)
			(xy 155.629877 -280.200131) (xy 155.630372 -280.224738) (xy 156.91918 -280.224738) (xy 156.92314 -280.175684)
			(xy 156.934917 -280.1279) (xy 156.954208 -280.082624) (xy 156.980511 -280.041028) (xy 157.013146 -280.004191)
			(xy 157.051267 -279.973066) (xy 157.093888 -279.948459) (xy 157.139904 -279.931007) (xy 157.188123 -279.921163)
			(xy 157.237298 -279.919182) (xy 157.286153 -279.925114) (xy 157.333424 -279.938806) (xy 157.377886 -279.959904)
			(xy 157.418389 -279.98786) (xy 157.453882 -280.021952) (xy 157.483447 -280.061296) (xy 157.506318 -280.104873)
			(xy 157.521902 -280.151554) (xy 157.529797 -280.200131) (xy 157.530292 -280.224738) (xy 158.8191 -280.224738)
			(xy 158.82306 -280.175684) (xy 158.834837 -280.1279) (xy 158.854128 -280.082624) (xy 158.880431 -280.041028)
			(xy 158.913066 -280.004191) (xy 158.951187 -279.973066) (xy 158.993808 -279.948459) (xy 159.039824 -279.931007)
			(xy 159.088043 -279.921163) (xy 159.137218 -279.919182) (xy 159.186073 -279.925114) (xy 159.233344 -279.938806)
			(xy 159.277806 -279.959904) (xy 159.318309 -279.98786) (xy 159.353802 -280.021952) (xy 159.383367 -280.061296)
			(xy 159.406238 -280.104873) (xy 159.421822 -280.151554) (xy 159.429717 -280.200131) (xy 159.430212 -280.224738)
			(xy 159.429717 -280.249345) (xy 159.421822 -280.297922) (xy 159.406238 -280.344603) (xy 159.383367 -280.38818)
			(xy 159.353802 -280.427524) (xy 159.318309 -280.461616) (xy 159.277806 -280.489572) (xy 159.233344 -280.51067)
			(xy 159.186073 -280.524362) (xy 159.137218 -280.530294) (xy 159.088043 -280.528313) (xy 159.039824 -280.518469)
			(xy 158.993808 -280.501017) (xy 158.951187 -280.47641) (xy 158.913066 -280.445285) (xy 158.880431 -280.408448)
			(xy 158.854128 -280.366852) (xy 158.834837 -280.321576) (xy 158.82306 -280.273792) (xy 158.8191 -280.224738)
			(xy 157.530292 -280.224738) (xy 157.529797 -280.249345) (xy 157.521902 -280.297922) (xy 157.506318 -280.344603)
			(xy 157.483447 -280.38818) (xy 157.453882 -280.427524) (xy 157.418389 -280.461616) (xy 157.377886 -280.489572)
			(xy 157.333424 -280.51067) (xy 157.286153 -280.524362) (xy 157.237298 -280.530294) (xy 157.188123 -280.528313)
			(xy 157.139904 -280.518469) (xy 157.093888 -280.501017) (xy 157.051267 -280.47641) (xy 157.013146 -280.445285)
			(xy 156.980511 -280.408448) (xy 156.954208 -280.366852) (xy 156.934917 -280.321576) (xy 156.92314 -280.273792)
			(xy 156.91918 -280.224738) (xy 155.630372 -280.224738) (xy 155.629877 -280.249345) (xy 155.621982 -280.297922)
			(xy 155.606398 -280.344603) (xy 155.583527 -280.38818) (xy 155.553962 -280.427524) (xy 155.518469 -280.461616)
			(xy 155.477966 -280.489572) (xy 155.433504 -280.51067) (xy 155.386233 -280.524362) (xy 155.337378 -280.530294)
			(xy 155.288203 -280.528313) (xy 155.239984 -280.518469) (xy 155.193968 -280.501017) (xy 155.151347 -280.47641)
			(xy 155.113226 -280.445285) (xy 155.080591 -280.408448) (xy 155.054288 -280.366852) (xy 155.034997 -280.321576)
			(xy 155.02322 -280.273792) (xy 155.01926 -280.224738) (xy 148.074524 -280.224738) (xy 148.060918 -280.235406)
			(xy 148.051975 -280.242867) (xy 148.041527 -280.263656) (xy 148.040852 -280.275284) (xy 148.039582 -280.367232)
			(xy 148.049488 -280.388314) (xy 148.058632 -280.39568) (xy 148.080459 -280.413909) (xy 148.118999 -280.455724)
			(xy 148.150908 -280.502795) (xy 148.175478 -280.55408) (xy 148.192166 -280.608443) (xy 148.200603 -280.664681)
			(xy 148.201126 -280.693114) (xy 148.8346 -280.693114) (xy 148.838671 -280.637492) (xy 148.850797 -280.583055)
			(xy 148.87072 -280.530964) (xy 148.898016 -280.482329) (xy 148.932102 -280.438186) (xy 148.972251 -280.399477)
			(xy 149.017609 -280.367026) (xy 149.067209 -280.341525) (xy 149.119993 -280.323518) (xy 149.174836 -280.313388)
			(xy 149.23057 -280.311351) (xy 149.286007 -280.317451) (xy 149.339964 -280.331557) (xy 149.391293 -280.353369)
			(xy 149.438899 -280.382423) (xy 149.481767 -280.418098) (xy 149.518984 -280.459635) (xy 149.549757 -280.506148)
			(xy 149.573429 -280.556645) (xy 149.589497 -280.610052) (xy 149.597617 -280.665228) (xy 149.598126 -280.693114)
			(xy 149.597617 -280.721) (xy 149.589497 -280.776176) (xy 149.573429 -280.829583) (xy 149.549757 -280.88008)
			(xy 149.518984 -280.926593) (xy 149.481767 -280.96813) (xy 149.438899 -281.003805) (xy 149.391293 -281.032859)
			(xy 149.339964 -281.054671) (xy 149.286007 -281.068777) (xy 149.23057 -281.074877) (xy 149.174836 -281.07284)
			(xy 149.119993 -281.06271) (xy 149.067209 -281.044703) (xy 149.017609 -281.019202) (xy 148.972251 -280.986751)
			(xy 148.932102 -280.948042) (xy 148.898016 -280.903899) (xy 148.87072 -280.855264) (xy 148.850797 -280.803173)
			(xy 148.838671 -280.748736) (xy 148.8346 -280.693114) (xy 148.201126 -280.693114) (xy 148.20064 -280.720365)
			(xy 148.192884 -280.774313) (xy 148.177529 -280.826608) (xy 148.154887 -280.876185) (xy 148.125421 -280.922035)
			(xy 148.08973 -280.963226) (xy 148.048539 -280.998917) (xy 148.002689 -281.028383) (xy 147.953112 -281.051025)
			(xy 147.900817 -281.06638) (xy 147.846869 -281.074136) (xy 147.792367 -281.074136) (xy 147.738419 -281.06638)
			(xy 147.686124 -281.051025) (xy 147.636547 -281.028383) (xy 147.590697 -280.998917) (xy 147.549506 -280.963226)
			(xy 147.513815 -280.922035) (xy 147.484349 -280.876185) (xy 147.461707 -280.826608) (xy 147.446352 -280.774313)
			(xy 147.438596 -280.720365) (xy 147.43811 -280.693114) (xy 146.935698 -280.693114) (xy 147.417536 -281.174952)
			(xy 152.169126 -281.174952) (xy 152.173086 -281.125898) (xy 152.184863 -281.078114) (xy 152.204154 -281.032838)
			(xy 152.230457 -280.991242) (xy 152.263092 -280.954405) (xy 152.301213 -280.92328) (xy 152.343834 -280.898673)
			(xy 152.38985 -280.881221) (xy 152.438069 -280.871377) (xy 152.487244 -280.869396) (xy 152.536099 -280.875328)
			(xy 152.58337 -280.88902) (xy 152.627832 -280.910118) (xy 152.668335 -280.938074) (xy 152.703828 -280.972166)
			(xy 152.733393 -281.01151) (xy 152.756264 -281.055087) (xy 152.771848 -281.101768) (xy 152.779743 -281.150345)
			(xy 152.780238 -281.174952) (xy 153.119086 -281.174952) (xy 153.123046 -281.125898) (xy 153.134823 -281.078114)
			(xy 153.154114 -281.032838) (xy 153.180417 -280.991242) (xy 153.213052 -280.954405) (xy 153.251173 -280.92328)
			(xy 153.293794 -280.898673) (xy 153.33981 -280.881221) (xy 153.388029 -280.871377) (xy 153.437204 -280.869396)
			(xy 153.486059 -280.875328) (xy 153.53333 -280.88902) (xy 153.577792 -280.910118) (xy 153.618295 -280.938074)
			(xy 153.653788 -280.972166) (xy 153.683353 -281.01151) (xy 153.706224 -281.055087) (xy 153.721808 -281.101768)
			(xy 153.729703 -281.150345) (xy 153.730198 -281.174952) (xy 153.729703 -281.199559) (xy 153.721808 -281.248136)
			(xy 153.706224 -281.294817) (xy 153.683353 -281.338394) (xy 153.653788 -281.377738) (xy 153.618295 -281.41183)
			(xy 153.577792 -281.439786) (xy 153.53333 -281.460884) (xy 153.486059 -281.474576) (xy 153.437204 -281.480508)
			(xy 153.388029 -281.478527) (xy 153.33981 -281.468683) (xy 153.293794 -281.451231) (xy 153.251173 -281.426624)
			(xy 153.213052 -281.395499) (xy 153.180417 -281.358662) (xy 153.154114 -281.317066) (xy 153.134823 -281.27179)
			(xy 153.123046 -281.224006) (xy 153.119086 -281.174952) (xy 152.780238 -281.174952) (xy 152.779743 -281.199559)
			(xy 152.771848 -281.248136) (xy 152.756264 -281.294817) (xy 152.733393 -281.338394) (xy 152.703828 -281.377738)
			(xy 152.668335 -281.41183) (xy 152.627832 -281.439786) (xy 152.58337 -281.460884) (xy 152.536099 -281.474576)
			(xy 152.487244 -281.480508) (xy 152.438069 -281.478527) (xy 152.38985 -281.468683) (xy 152.343834 -281.451231)
			(xy 152.301213 -281.426624) (xy 152.263092 -281.395499) (xy 152.230457 -281.358662) (xy 152.204154 -281.317066)
			(xy 152.184863 -281.27179) (xy 152.173086 -281.224006) (xy 152.169126 -281.174952) (xy 147.417536 -281.174952)
			(xy 147.534376 -281.291792) (xy 147.541226 -281.299189) (xy 147.548967 -281.317787) (xy 147.549362 -281.32786)
			(xy 147.549362 -282.682696) (xy 147.550124 -282.687014) (xy 147.550378 -282.689808) (xy 147.551338 -282.69579)
			(xy 147.555697 -282.707091) (xy 147.559014 -282.71216) (xy 147.569174 -282.72232) (xy 147.57654 -282.728416)
			(xy 147.594574 -282.740608) (xy 147.595082 -282.740608) (xy 147.642072 -282.77312) (xy 147.649407 -282.77713)
			(xy 147.665742 -282.780633) (xy 147.674076 -282.779978) (xy 147.675092 -282.779978) (xy 147.685506 -282.778708)
			(xy 147.691602 -282.776422) (xy 147.713809 -282.768089) (xy 147.759767 -282.756355) (xy 147.806824 -282.750401)
			(xy 147.83054 -282.750006) (xy 147.854162 -282.750006) (xy 147.861274 -282.750514) (xy 147.875244 -282.752546)
			(xy 147.876006 -282.752546) (xy 147.903475 -282.756328) (xy 147.956999 -282.7708) (xy 148.007868 -282.792861)
			(xy 148.055011 -282.822047) (xy 148.097438 -282.857745) (xy 148.134255 -282.899203) (xy 148.164689 -282.94555)
			(xy 148.1881 -282.995812) (xy 148.203996 -283.048931) (xy 148.207801 -283.074872) (xy 152.169126 -283.074872)
			(xy 152.173086 -283.025818) (xy 152.184863 -282.978034) (xy 152.204154 -282.932758) (xy 152.230457 -282.891162)
			(xy 152.263092 -282.854325) (xy 152.301213 -282.8232) (xy 152.343834 -282.798593) (xy 152.38985 -282.781141)
			(xy 152.438069 -282.771297) (xy 152.487244 -282.769316) (xy 152.536099 -282.775248) (xy 152.58337 -282.78894)
			(xy 152.627832 -282.810038) (xy 152.668335 -282.837994) (xy 152.703828 -282.872086) (xy 152.733393 -282.91143)
			(xy 152.756264 -282.955007) (xy 152.771848 -283.001688) (xy 152.779743 -283.050265) (xy 152.780238 -283.074872)
			(xy 152.779743 -283.099479) (xy 152.771848 -283.148056) (xy 152.756264 -283.194737) (xy 152.733393 -283.238314)
			(xy 152.703828 -283.277658) (xy 152.668335 -283.31175) (xy 152.627832 -283.339706) (xy 152.58337 -283.360804)
			(xy 152.536099 -283.374496) (xy 152.487244 -283.380428) (xy 152.438069 -283.378447) (xy 152.38985 -283.368603)
			(xy 152.343834 -283.351151) (xy 152.301213 -283.326544) (xy 152.263092 -283.295419) (xy 152.230457 -283.258582)
			(xy 152.204154 -283.216986) (xy 152.184863 -283.17171) (xy 152.173086 -283.123926) (xy 152.169126 -283.074872)
			(xy 148.207801 -283.074872) (xy 148.212042 -283.103791) (xy 148.212556 -283.131514) (xy 148.212008 -283.160596)
			(xy 148.203181 -283.218086) (xy 148.185733 -283.27357) (xy 148.160068 -283.325765) (xy 148.12678 -283.373461)
			(xy 148.086641 -283.415554) (xy 148.063966 -283.433774) (xy 148.061172 -283.435806) (xy 148.054314 -283.442664)
			(xy 148.05152 -283.445966) (xy 148.046804 -283.45244) (xy 148.041235 -283.467447) (xy 148.040598 -283.47543)
			(xy 148.04009 -283.516832) (xy 148.039582 -283.554932) (xy 148.039582 -283.556456) (xy 148.0401 -283.567385)
			(xy 148.049186 -283.587263) (xy 148.057108 -283.59481) (xy 148.060664 -283.597858) (xy 148.061426 -283.598366)
			(xy 148.06168 -283.59862) (xy 148.083088 -283.616834) (xy 148.120835 -283.65848) (xy 148.152063 -283.705214)
			(xy 148.176095 -283.756024) (xy 148.192411 -283.809811) (xy 148.200657 -283.86541) (xy 148.201126 -283.893514)
			(xy 148.8346 -283.893514) (xy 148.838671 -283.837892) (xy 148.850797 -283.783455) (xy 148.87072 -283.731364)
			(xy 148.898016 -283.682729) (xy 148.932102 -283.638586) (xy 148.972251 -283.599877) (xy 149.017609 -283.567426)
			(xy 149.067209 -283.541925) (xy 149.119993 -283.523918) (xy 149.174836 -283.513788) (xy 149.23057 -283.511751)
			(xy 149.286007 -283.517851) (xy 149.339964 -283.531957) (xy 149.391293 -283.553769) (xy 149.438899 -283.582823)
			(xy 149.481767 -283.618498) (xy 149.518984 -283.660035) (xy 149.549757 -283.706548) (xy 149.573429 -283.757045)
			(xy 149.589497 -283.810452) (xy 149.597617 -283.865628) (xy 149.598126 -283.893514) (xy 149.597617 -283.9214)
			(xy 149.589497 -283.976576) (xy 149.573429 -284.029983) (xy 149.549757 -284.08048) (xy 149.518984 -284.126993)
			(xy 149.481767 -284.16853) (xy 149.438899 -284.204205) (xy 149.391293 -284.233259) (xy 149.339964 -284.255071)
			(xy 149.286007 -284.269177) (xy 149.23057 -284.275277) (xy 149.174836 -284.27324) (xy 149.119993 -284.26311)
			(xy 149.067209 -284.245103) (xy 149.017609 -284.219602) (xy 148.972251 -284.187151) (xy 148.932102 -284.148442)
			(xy 148.898016 -284.104299) (xy 148.87072 -284.055664) (xy 148.850797 -284.003573) (xy 148.838671 -283.949136)
			(xy 148.8346 -283.893514) (xy 148.201126 -283.893514) (xy 148.200639 -283.920765) (xy 148.192881 -283.974712)
			(xy 148.177525 -284.027006) (xy 148.154883 -284.076583) (xy 148.125417 -284.122433) (xy 148.089726 -284.163623)
			(xy 148.048536 -284.199315) (xy 148.002686 -284.228781) (xy 147.95311 -284.251424) (xy 147.900816 -284.26678)
			(xy 147.846869 -284.274539) (xy 147.819618 -284.275022) (xy 147.818856 -284.275022) (xy 147.784912 -284.274279)
			(xy 147.718096 -284.26226) (xy 147.686014 -284.251146) (xy 147.680264 -284.249169) (xy 147.66819 -284.247764)
			(xy 147.662138 -284.248352) (xy 147.649692 -284.249876) (xy 147.570952 -284.30474) (xy 147.563071 -284.310898)
			(xy 147.55234 -284.327754) (xy 147.550124 -284.337506) (xy 147.549362 -284.341062) (xy 147.549362 -285.883096)
			(xy 147.550124 -285.887414) (xy 147.550378 -285.890208) (xy 147.551338 -285.89619) (xy 147.555697 -285.907491)
			(xy 147.559014 -285.91256) (xy 147.569174 -285.92272) (xy 147.57654 -285.928816) (xy 147.594574 -285.941008)
			(xy 147.595082 -285.941008) (xy 147.642072 -285.97352) (xy 147.649407 -285.97753) (xy 147.665742 -285.981033)
			(xy 147.674076 -285.980378) (xy 147.675092 -285.980378) (xy 147.685506 -285.979108) (xy 147.691602 -285.976822)
			(xy 147.713809 -285.968489) (xy 147.759767 -285.956755) (xy 147.806824 -285.950801) (xy 147.83054 -285.950406)
			(xy 147.854162 -285.950406) (xy 147.861274 -285.950914) (xy 147.875244 -285.952946) (xy 147.876006 -285.952946)
			(xy 147.903475 -285.956728) (xy 147.956999 -285.9712) (xy 148.007868 -285.993261) (xy 148.055011 -286.022447)
			(xy 148.097438 -286.058145) (xy 148.134255 -286.099603) (xy 148.164689 -286.14595) (xy 148.1881 -286.196212)
			(xy 148.203996 -286.249331) (xy 148.212042 -286.304191) (xy 148.212556 -286.331914) (xy 148.212008 -286.360996)
			(xy 148.203181 -286.418486) (xy 148.185733 -286.47397) (xy 148.160068 -286.526165) (xy 148.12678 -286.573861)
			(xy 148.086641 -286.615954) (xy 148.063966 -286.634174) (xy 148.061172 -286.636206) (xy 148.054314 -286.643064)
			(xy 148.05152 -286.646366) (xy 148.046804 -286.65284) (xy 148.041235 -286.667847) (xy 148.040598 -286.67583)
			(xy 148.04009 -286.717232) (xy 148.039582 -286.755332) (xy 148.039582 -286.756856) (xy 148.0401 -286.767785)
			(xy 148.049186 -286.787663) (xy 148.057108 -286.79521) (xy 148.060664 -286.798258) (xy 148.061426 -286.798766)
			(xy 148.06168 -286.79902) (xy 148.083088 -286.817234) (xy 148.120835 -286.85888) (xy 148.152063 -286.905614)
			(xy 148.176095 -286.956424) (xy 148.192411 -287.010211) (xy 148.200657 -287.06581) (xy 148.201126 -287.093914)
			(xy 148.8346 -287.093914) (xy 148.838671 -287.038292) (xy 148.850797 -286.983855) (xy 148.87072 -286.931764)
			(xy 148.898016 -286.883129) (xy 148.932102 -286.838986) (xy 148.972251 -286.800277) (xy 149.017609 -286.767826)
			(xy 149.067209 -286.742325) (xy 149.119993 -286.724318) (xy 149.174836 -286.714188) (xy 149.23057 -286.712151)
			(xy 149.286007 -286.718251) (xy 149.339964 -286.732357) (xy 149.391293 -286.754169) (xy 149.438899 -286.783223)
			(xy 149.481767 -286.818898) (xy 149.518984 -286.860435) (xy 149.549757 -286.906948) (xy 149.573429 -286.957445)
			(xy 149.589497 -287.010852) (xy 149.597617 -287.066028) (xy 149.598126 -287.093914) (xy 149.597617 -287.1218)
			(xy 149.589497 -287.176976) (xy 149.573429 -287.230383) (xy 149.549757 -287.28088) (xy 149.518984 -287.327393)
			(xy 149.481767 -287.36893) (xy 149.438899 -287.404605) (xy 149.391293 -287.433659) (xy 149.339964 -287.455471)
			(xy 149.286007 -287.469577) (xy 149.23057 -287.475677) (xy 149.174836 -287.47364) (xy 149.119993 -287.46351)
			(xy 149.067209 -287.445503) (xy 149.017609 -287.420002) (xy 148.972251 -287.387551) (xy 148.932102 -287.348842)
			(xy 148.898016 -287.304699) (xy 148.87072 -287.256064) (xy 148.850797 -287.203973) (xy 148.838671 -287.149536)
			(xy 148.8346 -287.093914) (xy 148.201126 -287.093914) (xy 148.200639 -287.121165) (xy 148.192881 -287.175112)
			(xy 148.177525 -287.227406) (xy 148.154883 -287.276983) (xy 148.125417 -287.322833) (xy 148.089726 -287.364023)
			(xy 148.048536 -287.399715) (xy 148.002686 -287.429181) (xy 147.95311 -287.451824) (xy 147.900816 -287.46718)
			(xy 147.846869 -287.474939) (xy 147.819618 -287.475422) (xy 147.818856 -287.475422) (xy 147.784912 -287.474679)
			(xy 147.718096 -287.46266) (xy 147.686014 -287.451546) (xy 147.680264 -287.449569) (xy 147.66819 -287.448164)
			(xy 147.662138 -287.448752) (xy 147.649692 -287.450276) (xy 147.570952 -287.50514) (xy 147.563071 -287.511298)
			(xy 147.55234 -287.528154) (xy 147.550124 -287.537906) (xy 147.549362 -287.541462) (xy 147.549362 -289.083496)
			(xy 147.550124 -289.087814) (xy 147.550378 -289.090608) (xy 147.551338 -289.09659) (xy 147.555697 -289.107891)
			(xy 147.559014 -289.11296) (xy 147.569174 -289.12312) (xy 147.57654 -289.129216) (xy 147.594574 -289.141408)
			(xy 147.595082 -289.141408) (xy 147.642072 -289.17392) (xy 147.649407 -289.17793) (xy 147.665742 -289.181433)
			(xy 147.674076 -289.180778) (xy 147.675092 -289.180778) (xy 147.685506 -289.179508) (xy 147.691602 -289.177222)
			(xy 147.713809 -289.168889) (xy 147.759767 -289.157155) (xy 147.806824 -289.151201) (xy 147.83054 -289.150806)
			(xy 147.854162 -289.150806) (xy 147.861274 -289.151314) (xy 147.875244 -289.153346) (xy 147.876006 -289.153346)
			(xy 147.903475 -289.157128) (xy 147.956999 -289.1716) (xy 148.007868 -289.193661) (xy 148.055011 -289.222847)
			(xy 148.097438 -289.258545) (xy 148.134255 -289.300003) (xy 148.164689 -289.34635) (xy 148.1881 -289.396612)
			(xy 148.203996 -289.449731) (xy 148.212042 -289.504591) (xy 148.212556 -289.532314) (xy 148.212008 -289.561396)
			(xy 148.203181 -289.618886) (xy 148.185733 -289.67437) (xy 148.160068 -289.726565) (xy 148.12678 -289.774261)
			(xy 148.086641 -289.816354) (xy 148.063966 -289.834574) (xy 148.061172 -289.836606) (xy 148.054314 -289.843464)
			(xy 148.05152 -289.846766) (xy 148.046804 -289.85324) (xy 148.041235 -289.868247) (xy 148.040598 -289.87623)
			(xy 148.04009 -289.917632) (xy 148.039582 -289.955732) (xy 148.039582 -289.957256) (xy 148.0401 -289.968185)
			(xy 148.049186 -289.988063) (xy 148.057108 -289.99561) (xy 148.060664 -289.998658) (xy 148.061426 -289.999166)
			(xy 148.06168 -289.99942) (xy 148.083088 -290.017634) (xy 148.120835 -290.05928) (xy 148.152063 -290.106014)
			(xy 148.176095 -290.156824) (xy 148.192411 -290.210611) (xy 148.200657 -290.26621) (xy 148.201126 -290.294314)
			(xy 148.8346 -290.294314) (xy 148.838671 -290.238692) (xy 148.850797 -290.184255) (xy 148.87072 -290.132164)
			(xy 148.898016 -290.083529) (xy 148.932102 -290.039386) (xy 148.972251 -290.000677) (xy 149.017609 -289.968226)
			(xy 149.067209 -289.942725) (xy 149.119993 -289.924718) (xy 149.174836 -289.914588) (xy 149.23057 -289.912551)
			(xy 149.286007 -289.918651) (xy 149.339964 -289.932757) (xy 149.391293 -289.954569) (xy 149.438899 -289.983623)
			(xy 149.481767 -290.019298) (xy 149.518984 -290.060835) (xy 149.549757 -290.107348) (xy 149.573429 -290.157845)
			(xy 149.589497 -290.211252) (xy 149.597617 -290.266428) (xy 149.598126 -290.294314) (xy 149.597617 -290.3222)
			(xy 149.589497 -290.377376) (xy 149.573429 -290.430783) (xy 149.549757 -290.48128) (xy 149.518984 -290.527793)
			(xy 149.481767 -290.56933) (xy 149.438899 -290.605005) (xy 149.391293 -290.634059) (xy 149.339964 -290.655871)
			(xy 149.286007 -290.669977) (xy 149.23057 -290.676077) (xy 149.174836 -290.67404) (xy 149.119993 -290.66391)
			(xy 149.067209 -290.645903) (xy 149.017609 -290.620402) (xy 148.972251 -290.587951) (xy 148.932102 -290.549242)
			(xy 148.898016 -290.505099) (xy 148.87072 -290.456464) (xy 148.850797 -290.404373) (xy 148.838671 -290.349936)
			(xy 148.8346 -290.294314) (xy 148.201126 -290.294314) (xy 148.200639 -290.321565) (xy 148.192881 -290.375512)
			(xy 148.177525 -290.427806) (xy 148.154883 -290.477383) (xy 148.125417 -290.523233) (xy 148.089726 -290.564423)
			(xy 148.048536 -290.600115) (xy 148.002686 -290.629581) (xy 147.95311 -290.652224) (xy 147.900816 -290.66758)
			(xy 147.846869 -290.675339) (xy 147.819618 -290.675822) (xy 147.818856 -290.675822) (xy 147.784912 -290.675079)
			(xy 147.718096 -290.66306) (xy 147.686014 -290.651946) (xy 147.680264 -290.649969) (xy 147.66819 -290.648564)
			(xy 147.662138 -290.649152) (xy 147.649692 -290.650676) (xy 147.570952 -290.70554) (xy 147.563071 -290.711698)
			(xy 147.55234 -290.728554) (xy 147.550124 -290.738306) (xy 147.549362 -290.741862) (xy 147.549362 -292.283896)
			(xy 147.550124 -292.288214) (xy 147.550378 -292.291008) (xy 147.551338 -292.29699) (xy 147.555697 -292.308291)
			(xy 147.559014 -292.31336) (xy 147.569174 -292.32352) (xy 147.57654 -292.329616) (xy 147.594574 -292.341808)
			(xy 147.595082 -292.341808) (xy 147.642072 -292.37432) (xy 147.649407 -292.37833) (xy 147.665742 -292.381833)
			(xy 147.674076 -292.381178) (xy 147.675092 -292.381178) (xy 147.685506 -292.379908) (xy 147.691602 -292.377622)
			(xy 147.713809 -292.369289) (xy 147.759767 -292.357555) (xy 147.806824 -292.351601) (xy 147.83054 -292.351206)
			(xy 147.854162 -292.351206) (xy 147.861274 -292.351714) (xy 147.875244 -292.353746) (xy 147.876006 -292.353746)
			(xy 147.903475 -292.357528) (xy 147.956999 -292.372) (xy 148.007868 -292.394061) (xy 148.055011 -292.423247)
			(xy 148.097438 -292.458945) (xy 148.134255 -292.500403) (xy 148.164689 -292.54675) (xy 148.1881 -292.597012)
			(xy 148.203996 -292.650131) (xy 148.212042 -292.704991) (xy 148.212556 -292.732714) (xy 148.212008 -292.761796)
			(xy 148.203181 -292.819286) (xy 148.185733 -292.87477) (xy 148.160068 -292.926965) (xy 148.12678 -292.974661)
			(xy 148.086641 -293.016754) (xy 148.063966 -293.034974) (xy 148.061172 -293.037006) (xy 148.054314 -293.043864)
			(xy 148.05152 -293.047166) (xy 148.046804 -293.05364) (xy 148.041235 -293.068647) (xy 148.040598 -293.07663)
			(xy 148.04009 -293.118032) (xy 148.039582 -293.156132) (xy 148.039582 -293.157656) (xy 148.0401 -293.168585)
			(xy 148.049186 -293.188463) (xy 148.057108 -293.19601) (xy 148.060664 -293.199058) (xy 148.061426 -293.199566)
			(xy 148.06168 -293.19982) (xy 148.083088 -293.218034) (xy 148.120835 -293.25968) (xy 148.152063 -293.306414)
			(xy 148.176095 -293.357224) (xy 148.192411 -293.411011) (xy 148.200657 -293.46661) (xy 148.201126 -293.494714)
			(xy 148.8346 -293.494714) (xy 148.838671 -293.439092) (xy 148.850797 -293.384655) (xy 148.87072 -293.332564)
			(xy 148.898016 -293.283929) (xy 148.932102 -293.239786) (xy 148.972251 -293.201077) (xy 149.017609 -293.168626)
			(xy 149.067209 -293.143125) (xy 149.119993 -293.125118) (xy 149.174836 -293.114988) (xy 149.23057 -293.112951)
			(xy 149.286007 -293.119051) (xy 149.339964 -293.133157) (xy 149.391293 -293.154969) (xy 149.438899 -293.184023)
			(xy 149.481767 -293.219698) (xy 149.518984 -293.261235) (xy 149.549757 -293.307748) (xy 149.573429 -293.358245)
			(xy 149.589497 -293.411652) (xy 149.597617 -293.466828) (xy 149.598126 -293.494714) (xy 149.597617 -293.5226)
			(xy 149.589497 -293.577776) (xy 149.573429 -293.631183) (xy 149.549757 -293.68168) (xy 149.518984 -293.728193)
			(xy 149.481767 -293.76973) (xy 149.438899 -293.805405) (xy 149.391293 -293.834459) (xy 149.339964 -293.856271)
			(xy 149.286007 -293.870377) (xy 149.23057 -293.876477) (xy 149.174836 -293.87444) (xy 149.119993 -293.86431)
			(xy 149.067209 -293.846303) (xy 149.017609 -293.820802) (xy 148.972251 -293.788351) (xy 148.932102 -293.749642)
			(xy 148.898016 -293.705499) (xy 148.87072 -293.656864) (xy 148.850797 -293.604773) (xy 148.838671 -293.550336)
			(xy 148.8346 -293.494714) (xy 148.201126 -293.494714) (xy 148.200639 -293.521965) (xy 148.192881 -293.575912)
			(xy 148.177525 -293.628206) (xy 148.154883 -293.677783) (xy 148.125417 -293.723633) (xy 148.089726 -293.764823)
			(xy 148.048536 -293.800515) (xy 148.002686 -293.829981) (xy 147.95311 -293.852624) (xy 147.900816 -293.86798)
			(xy 147.846869 -293.875739) (xy 147.819618 -293.876222) (xy 147.818856 -293.876222) (xy 147.784912 -293.875479)
			(xy 147.718096 -293.86346) (xy 147.686014 -293.852346) (xy 147.680264 -293.850369) (xy 147.66819 -293.848964)
			(xy 147.662138 -293.849552) (xy 147.649692 -293.851076) (xy 147.570952 -293.90594) (xy 147.563071 -293.912098)
			(xy 147.55234 -293.928954) (xy 147.550124 -293.938706) (xy 147.549362 -293.942262) (xy 147.549362 -295.484296)
			(xy 147.550124 -295.488614) (xy 147.550378 -295.491408) (xy 147.551338 -295.49739) (xy 147.555697 -295.508691)
			(xy 147.559014 -295.51376) (xy 147.569174 -295.52392) (xy 147.57654 -295.530016) (xy 147.594574 -295.542208)
			(xy 147.595082 -295.542208) (xy 147.642072 -295.57472) (xy 147.649407 -295.57873) (xy 147.665742 -295.582233)
			(xy 147.674076 -295.581578) (xy 147.675092 -295.581578) (xy 147.685506 -295.580308) (xy 147.691602 -295.578022)
			(xy 147.713809 -295.569689) (xy 147.759767 -295.557955) (xy 147.806824 -295.552001) (xy 147.83054 -295.551606)
			(xy 147.854162 -295.551606) (xy 147.861274 -295.552114) (xy 147.875244 -295.554146) (xy 147.876006 -295.554146)
			(xy 147.903475 -295.557928) (xy 147.956999 -295.5724) (xy 148.007868 -295.594461) (xy 148.055011 -295.623647)
			(xy 148.097438 -295.659345) (xy 148.134255 -295.700803) (xy 148.164689 -295.74715) (xy 148.1881 -295.797412)
			(xy 148.203996 -295.850531) (xy 148.212042 -295.905391) (xy 148.212556 -295.933114) (xy 148.212008 -295.962196)
			(xy 148.203181 -296.019686) (xy 148.185733 -296.07517) (xy 148.160068 -296.127365) (xy 148.12678 -296.175061)
			(xy 148.086641 -296.217154) (xy 148.063966 -296.235374) (xy 148.061172 -296.237406) (xy 148.054314 -296.244264)
			(xy 148.05152 -296.247566) (xy 148.046804 -296.25404) (xy 148.041235 -296.269047) (xy 148.040598 -296.27703)
			(xy 148.04009 -296.318432) (xy 148.039582 -296.356532) (xy 148.039582 -296.358056) (xy 148.0401 -296.368985)
			(xy 148.049186 -296.388863) (xy 148.057108 -296.39641) (xy 148.060664 -296.399458) (xy 148.061426 -296.399966)
			(xy 148.06168 -296.40022) (xy 148.083088 -296.418434) (xy 148.120835 -296.46008) (xy 148.152063 -296.506814)
			(xy 148.176095 -296.557624) (xy 148.192411 -296.611411) (xy 148.200657 -296.66701) (xy 148.201126 -296.695114)
			(xy 148.8346 -296.695114) (xy 148.838671 -296.639492) (xy 148.850797 -296.585055) (xy 148.87072 -296.532964)
			(xy 148.898016 -296.484329) (xy 148.932102 -296.440186) (xy 148.972251 -296.401477) (xy 149.017609 -296.369026)
			(xy 149.067209 -296.343525) (xy 149.119993 -296.325518) (xy 149.174836 -296.315388) (xy 149.23057 -296.313351)
			(xy 149.286007 -296.319451) (xy 149.339964 -296.333557) (xy 149.391293 -296.355369) (xy 149.438899 -296.384423)
			(xy 149.481767 -296.420098) (xy 149.518984 -296.461635) (xy 149.549757 -296.508148) (xy 149.573429 -296.558645)
			(xy 149.589497 -296.612052) (xy 149.597617 -296.667228) (xy 149.598126 -296.695114) (xy 149.597617 -296.723)
			(xy 149.589497 -296.778176) (xy 149.573429 -296.831583) (xy 149.549757 -296.88208) (xy 149.518984 -296.928593)
			(xy 149.481767 -296.97013) (xy 149.438899 -297.005805) (xy 149.391293 -297.034859) (xy 149.339964 -297.056671)
			(xy 149.286007 -297.070777) (xy 149.23057 -297.076877) (xy 149.174836 -297.07484) (xy 149.119993 -297.06471)
			(xy 149.067209 -297.046703) (xy 149.017609 -297.021202) (xy 148.972251 -296.988751) (xy 148.932102 -296.950042)
			(xy 148.898016 -296.905899) (xy 148.87072 -296.857264) (xy 148.850797 -296.805173) (xy 148.838671 -296.750736)
			(xy 148.8346 -296.695114) (xy 148.201126 -296.695114) (xy 148.200639 -296.722365) (xy 148.192881 -296.776312)
			(xy 148.177525 -296.828606) (xy 148.154883 -296.878183) (xy 148.125417 -296.924033) (xy 148.089726 -296.965223)
			(xy 148.048536 -297.000915) (xy 148.002686 -297.030381) (xy 147.95311 -297.053024) (xy 147.900816 -297.06838)
			(xy 147.846869 -297.076139) (xy 147.819618 -297.076622) (xy 147.818856 -297.076622) (xy 147.784912 -297.075879)
			(xy 147.718096 -297.06386) (xy 147.686014 -297.052746) (xy 147.680264 -297.050769) (xy 147.66819 -297.049364)
			(xy 147.662138 -297.049952) (xy 147.649692 -297.051476) (xy 147.570952 -297.10634) (xy 147.563071 -297.112498)
			(xy 147.55234 -297.129354) (xy 147.550124 -297.139106) (xy 147.549362 -297.142662) (xy 147.549362 -298.684696)
			(xy 147.550124 -298.689014) (xy 147.550378 -298.691808) (xy 147.551338 -298.69779) (xy 147.555697 -298.709091)
			(xy 147.559014 -298.71416) (xy 147.569174 -298.72432) (xy 147.57654 -298.730416) (xy 147.594574 -298.742608)
			(xy 147.595082 -298.742608) (xy 147.642072 -298.77512) (xy 147.649407 -298.77913) (xy 147.665742 -298.782633)
			(xy 147.674076 -298.781978) (xy 147.675092 -298.781978) (xy 147.685506 -298.780708) (xy 147.691602 -298.778422)
			(xy 147.713809 -298.770089) (xy 147.759767 -298.758355) (xy 147.806824 -298.752401) (xy 147.83054 -298.752006)
			(xy 147.854162 -298.752006) (xy 147.861274 -298.752514) (xy 147.875244 -298.754546) (xy 147.876006 -298.754546)
			(xy 147.903475 -298.758328) (xy 147.956999 -298.7728) (xy 148.007868 -298.794861) (xy 148.055011 -298.824047)
			(xy 148.097438 -298.859745) (xy 148.134255 -298.901203) (xy 148.164689 -298.94755) (xy 148.1881 -298.997812)
			(xy 148.203996 -299.050931) (xy 148.212042 -299.105791) (xy 148.212556 -299.133514) (xy 148.212008 -299.162596)
			(xy 148.203181 -299.220086) (xy 148.185733 -299.27557) (xy 148.160068 -299.327765) (xy 148.12678 -299.375461)
			(xy 148.086641 -299.417554) (xy 148.063966 -299.435774) (xy 148.061172 -299.437806) (xy 148.054314 -299.444664)
			(xy 148.05152 -299.447966) (xy 148.046804 -299.45444) (xy 148.041235 -299.469447) (xy 148.040598 -299.47743)
			(xy 148.04009 -299.518832) (xy 148.039582 -299.556932) (xy 148.039582 -299.558456) (xy 148.0401 -299.569385)
			(xy 148.049186 -299.589263) (xy 148.057108 -299.59681) (xy 148.060664 -299.599858) (xy 148.06168 -299.60062)
			(xy 148.081961 -299.617861) (xy 148.118015 -299.657021) (xy 148.148271 -299.700816) (xy 148.172143 -299.748393)
			(xy 148.189165 -299.798828) (xy 148.194522 -299.824902) (xy 148.1963 -299.834554) (xy 148.212556 -299.859954)
			(xy 148.21552 -299.864347) (xy 148.222944 -299.871906) (xy 148.227288 -299.87494) (xy 148.29028 -299.916596)
			(xy 148.302218 -299.91812) (xy 148.31187 -299.91939)
		)
		(stroke
			(width 0)
			(type solid)
		)
		(fill yes)
		(layer "In9.Cu")
		(net "GND")
	)
	(gr_line
		(start 26.027888 -151.935942)
		(end 26.027888 -151.935688)
		(stroke
			(width 0.08255)
			(type default)
		)
		(layer "In9.Cu")
	)
	(gr_line
		(start 27.046174 -109.719618)
		(end 27.194256 -109.658404)
		(stroke
			(width 0.08255)
			(type default)
		)
		(layer "In9.Cu")
	)
	(gr_line
		(start 27.11069 -111.674148)
		(end 27.378152 -111.02848)
		(stroke
			(width 0.08255)
			(type default)
		)
		(layer "In9.Cu")
	)
	(gr_line
		(start 27.194256 -109.658404)
		(end 27.38374 -109.200442)
		(stroke
			(width 0.08255)
			(type default)
		)
		(layer "In9.Cu")
	)
	(gr_line
		(start 27.372818 -111.78159)
		(end 27.503882 -111.72698)
		(stroke
			(width 0.08255)
			(type default)
		)
		(layer "In9.Cu")
	)
	(gr_line
		(start 27.38374 -109.200442)
		(end 27.322272 -109.052614)
		(stroke
			(width 0.08255)
			(type default)
		)
		(layer "In9.Cu")
	)
	(gr_line
		(start 27.503882 -111.72698)
		(end 27.693874 -111.269272)
		(stroke
			(width 0.08255)
			(type default)
		)
		(layer "In9.Cu")
	)
	(gr_line
		(start 27.512772 -108.593128)
		(end 27.660854 -108.53166)
		(stroke
			(width 0.08255)
			(type default)
		)
		(layer "In9.Cu")
	)
	(gr_line
		(start 27.567636 -110.571026)
		(end 27.835098 -109.925358)
		(stroke
			(width 0.08255)
			(type default)
		)
		(layer "In9.Cu")
	)
	(gr_line
		(start 27.660854 -108.53166)
		(end 27.850338 -108.073952)
		(stroke
			(width 0.08255)
			(type default)
		)
		(layer "In9.Cu")
	)
	(gr_line
		(start 27.693874 -111.269272)
		(end 27.639264 -111.137954)
		(stroke
			(width 0.08255)
			(type default)
		)
		(layer "In9.Cu")
	)
	(gr_line
		(start 27.829764 -110.678468)
		(end 27.960828 -110.623858)
		(stroke
			(width 0.08255)
			(type default)
		)
		(layer "In9.Cu")
	)
	(gr_line
		(start 27.850338 -108.073952)
		(end 27.789124 -107.926124)
		(stroke
			(width 0.08255)
			(type default)
		)
		(layer "In9.Cu")
	)
	(gr_line
		(start 27.960828 -110.623858)
		(end 28.15082 -110.16615)
		(stroke
			(width 0.08255)
			(type default)
		)
		(layer "In9.Cu")
	)
	(gr_line
		(start 28.024582 -109.467904)
		(end 28.292044 -108.822236)
		(stroke
			(width 0.08255)
			(type default)
		)
		(layer "In9.Cu")
	)
	(gr_line
		(start 28.15082 -110.16615)
		(end 28.09621 -110.034832)
		(stroke
			(width 0.08255)
			(type default)
		)
		(layer "In9.Cu")
	)
	(gr_line
		(start 28.28671 -109.575346)
		(end 28.417774 -109.520736)
		(stroke
			(width 0.08255)
			(type default)
		)
		(layer "In9.Cu")
	)
	(gr_line
		(start 28.417774 -109.520736)
		(end 28.607766 -109.063028)
		(stroke
			(width 0.08255)
			(type default)
		)
		(layer "In9.Cu")
	)
	(gr_line
		(start 28.441396 -114.302794)
		(end 28.718256 -113.633758)
		(stroke
			(width 0.08255)
			(type default)
		)
		(layer "In9.Cu")
	)
	(gr_line
		(start 28.481528 -108.364782)
		(end 28.74899 -107.719114)
		(stroke
			(width 0.08255)
			(type default)
		)
		(layer "In9.Cu")
	)
	(gr_line
		(start 28.607766 -109.063028)
		(end 28.553156 -108.93171)
		(stroke
			(width 0.08255)
			(type default)
		)
		(layer "In9.Cu")
	)
	(gr_line
		(start 28.701746 -114.410744)
		(end 28.702 -114.410744)
		(stroke
			(width 0.08255)
			(type default)
		)
		(layer "In9.Cu")
	)
	(gr_line
		(start 28.703524 -114.409982)
		(end 28.851352 -114.349022)
		(stroke
			(width 0.08255)
			(type default)
		)
		(layer "In9.Cu")
	)
	(gr_line
		(start 28.742132 -108.472732)
		(end 28.742132 -108.472478)
		(stroke
			(width 0.08255)
			(type default)
		)
		(layer "In9.Cu")
	)
	(gr_line
		(start 28.74391 -108.471716)
		(end 28.874974 -108.417614)
		(stroke
			(width 0.08255)
			(type default)
		)
		(layer "In9.Cu")
	)
	(gr_line
		(start 28.851352 -114.349022)
		(end 29.040836 -113.89106)
		(stroke
			(width 0.08255)
			(type default)
		)
		(layer "In9.Cu")
	)
	(gr_line
		(start 28.874974 -108.417614)
		(end 29.064712 -107.959652)
		(stroke
			(width 0.08255)
			(type default)
		)
		(layer "In9.Cu")
	)
	(gr_line
		(start 28.90774 -113.176304)
		(end 29.184854 -112.507268)
		(stroke
			(width 0.08255)
			(type default)
		)
		(layer "In9.Cu")
	)
	(gr_line
		(start 28.928314 -130.237484)
		(end 29.059632 -130.183382)
		(stroke
			(width 0.08255)
			(type default)
		)
		(layer "In9.Cu")
	)
	(gr_line
		(start 29.040836 -113.89106)
		(end 28.979622 -113.743232)
		(stroke
			(width 0.08255)
			(type default)
		)
		(layer "In9.Cu")
	)
	(gr_line
		(start 29.059632 -130.183382)
		(end 29.244544 -129.737104)
		(stroke
			(width 0.08255)
			(type default)
		)
		(layer "In9.Cu")
	)
	(gr_line
		(start 29.064712 -107.959652)
		(end 29.010356 -107.828588)
		(stroke
			(width 0.08255)
			(type default)
		)
		(layer "In9.Cu")
	)
	(gr_line
		(start 29.169868 -113.283492)
		(end 29.31795 -113.222532)
		(stroke
			(width 0.08255)
			(type default)
		)
		(layer "In9.Cu")
	)
	(gr_line
		(start 29.244544 -129.737104)
		(end 29.189934 -129.605786)
		(stroke
			(width 0.08255)
			(type default)
		)
		(layer "In9.Cu")
	)
	(gr_line
		(start 29.249116 -117.968268)
		(end 29.516578 -117.3226)
		(stroke
			(width 0.08255)
			(type default)
		)
		(layer "In9.Cu")
	)
	(gr_line
		(start 29.31795 -113.222532)
		(end 29.507434 -112.76457)
		(stroke
			(width 0.08255)
			(type default)
		)
		(layer "In9.Cu")
	)
	(gr_line
		(start 29.374338 -112.049814)
		(end 29.651452 -111.380778)
		(stroke
			(width 0.08255)
			(type default)
		)
		(layer "In9.Cu")
	)
	(gr_line
		(start 29.396944 -129.103374)
		(end 29.39669 -129.103374)
		(stroke
			(width 0.08255)
			(type default)
		)
		(layer "In9.Cu")
	)
	(gr_line
		(start 29.398468 -129.102612)
		(end 29.529786 -129.04851)
		(stroke
			(width 0.08255)
			(type default)
		)
		(layer "In9.Cu")
	)
	(gr_line
		(start 29.492194 -105.317544)
		(end 29.65196 -105.317544)
		(stroke
			(width 0.08255)
			(type default)
		)
		(layer "In9.Cu")
	)
	(gr_line
		(start 29.507434 -112.76457)
		(end 29.445966 -112.616742)
		(stroke
			(width 0.08255)
			(type default)
		)
		(layer "In9.Cu")
	)
	(gr_line
		(start 29.511244 -118.07571)
		(end 29.642308 -118.0211)
		(stroke
			(width 0.08255)
			(type default)
		)
		(layer "In9.Cu")
	)
	(gr_line
		(start 29.529786 -129.04851)
		(end 29.714444 -128.602232)
		(stroke
			(width 0.08255)
			(type default)
		)
		(layer "In9.Cu")
	)
	(gr_line
		(start 29.547312 -130.798824)
		(end 29.805122 -130.176524)
		(stroke
			(width 0.08255)
			(type default)
		)
		(layer "In9.Cu")
	)
	(gr_line
		(start 29.634688 -112.157764)
		(end 29.634942 -112.157764)
		(stroke
			(width 0.08255)
			(type default)
		)
		(layer "In9.Cu")
	)
	(gr_line
		(start 29.636466 -112.157002)
		(end 29.784294 -112.096042)
		(stroke
			(width 0.08255)
			(type default)
		)
		(layer "In9.Cu")
	)
	(gr_line
		(start 29.642308 -118.0211)
		(end 29.8323 -117.563392)
		(stroke
			(width 0.08255)
			(type default)
		)
		(layer "In9.Cu")
	)
	(gr_line
		(start 29.65196 -105.317544)
		(end 29.99359 -104.975914)
		(stroke
			(width 0.08255)
			(type default)
		)
		(layer "In9.Cu")
	)
	(gr_line
		(start 29.706062 -116.865146)
		(end 29.973524 -116.219478)
		(stroke
			(width 0.08255)
			(type default)
		)
		(layer "In9.Cu")
	)
	(gr_line
		(start 29.714444 -128.602232)
		(end 29.660088 -128.471168)
		(stroke
			(width 0.08255)
			(type default)
		)
		(layer "In9.Cu")
	)
	(gr_line
		(start 29.784294 -112.096042)
		(end 29.973778 -111.63808)
		(stroke
			(width 0.08255)
			(type default)
		)
		(layer "In9.Cu")
	)
	(gr_line
		(start 29.807916 -130.906774)
		(end 29.807916 -130.90652)
		(stroke
			(width 0.08255)
			(type default)
		)
		(layer "In9.Cu")
	)
	(gr_line
		(start 29.809694 -130.905758)
		(end 29.923994 -130.858514)
		(stroke
			(width 0.08255)
			(type default)
		)
		(layer "In9.Cu")
	)
	(gr_line
		(start 29.8323 -117.563392)
		(end 29.77769 -117.432074)
		(stroke
			(width 0.08255)
			(type default)
		)
		(layer "In9.Cu")
	)
	(gr_line
		(start 29.840936 -110.923324)
		(end 30.117796 -110.254288)
		(stroke
			(width 0.08255)
			(type default)
		)
		(layer "In9.Cu")
	)
	(gr_line
		(start 29.843984 -128.023874)
		(end 29.843984 -128.02362)
		(stroke
			(width 0.08255)
			(type default)
		)
		(layer "In9.Cu")
	)
	(gr_line
		(start 29.845762 -128.022858)
		(end 29.97708 -127.968756)
		(stroke
			(width 0.08255)
			(type default)
		)
		(layer "In9.Cu")
	)
	(gr_line
		(start 29.878274 -106.054906)
		(end 30.372558 -105.560622)
		(stroke
			(width 0.08255)
			(type default)
		)
		(layer "In9.Cu")
	)
	(gr_line
		(start 29.904944 -151.234902)
		(end 29.904944 -151.235156)
		(stroke
			(width 0.08255)
			(type default)
		)
		(layer "In9.Cu")
	)
	(gr_line
		(start 29.912056 -111.488728)
		(end 29.911802 -111.488728)
		(stroke
			(width 0.08255)
			(type default)
		)
		(layer "In9.Cu")
	)
	(gr_line
		(start 29.923994 -130.858514)
		(end 30.113986 -130.400552)
		(stroke
			(width 0.08255)
			(type default)
		)
		(layer "In9.Cu")
	)
	(gr_line
		(start 29.96819 -116.972588)
		(end 30.099254 -116.917978)
		(stroke
			(width 0.08255)
			(type default)
		)
		(layer "In9.Cu")
	)
	(gr_line
		(start 29.973778 -111.63808)
		(end 29.912564 -111.490506)
		(stroke
			(width 0.08255)
			(type default)
		)
		(layer "In9.Cu")
	)
	(gr_line
		(start 29.97708 -127.968756)
		(end 30.161738 -127.522478)
		(stroke
			(width 0.08255)
			(type default)
		)
		(layer "In9.Cu")
	)
	(gr_line
		(start 29.99359 -104.975914)
		(end 29.99359 -104.816148)
		(stroke
			(width 0.08255)
			(type default)
		)
		(layer "In9.Cu")
	)
	(gr_line
		(start 29.994606 -129.71907)
		(end 30.252162 -129.097024)
		(stroke
			(width 0.08255)
			(type default)
		)
		(layer "In9.Cu")
	)
	(gr_line
		(start 30.05963 -121.681494)
		(end 30.336744 -121.012458)
		(stroke
			(width 0.08255)
			(type default)
		)
		(layer "In9.Cu")
	)
	(gr_line
		(start 30.079442 -106.254296)
		(end 30.221428 -106.254296)
		(stroke
			(width 0.08255)
			(type default)
		)
		(layer "In9.Cu")
	)
	(gr_line
		(start 30.099254 -116.917978)
		(end 30.289246 -116.46027)
		(stroke
			(width 0.08255)
			(type default)
		)
		(layer "In9.Cu")
	)
	(gr_line
		(start 30.101286 -111.031274)
		(end 30.10154 -111.031274)
		(stroke
			(width 0.08255)
			(type default)
		)
		(layer "In9.Cu")
	)
	(gr_line
		(start 30.10281 -111.030512)
		(end 30.250892 -110.969552)
		(stroke
			(width 0.08255)
			(type default)
		)
		(layer "In9.Cu")
	)
	(gr_line
		(start 30.113986 -130.400552)
		(end 30.066234 -130.285998)
		(stroke
			(width 0.08255)
			(type default)
		)
		(layer "In9.Cu")
	)
	(gr_line
		(start 30.161738 -127.522478)
		(end 30.107382 -127.391414)
		(stroke
			(width 0.08255)
			(type default)
		)
		(layer "In9.Cu")
	)
	(gr_line
		(start 30.163008 -115.762024)
		(end 30.43047 -115.116356)
		(stroke
			(width 0.08255)
			(type default)
		)
		(layer "In9.Cu")
	)
	(gr_line
		(start 30.221428 -106.254296)
		(end 30.571948 -105.903776)
		(stroke
			(width 0.08255)
			(type default)
		)
		(layer "In9.Cu")
	)
	(gr_line
		(start 30.250892 -110.969552)
		(end 30.440376 -110.51159)
		(stroke
			(width 0.08255)
			(type default)
		)
		(layer "In9.Cu")
	)
	(gr_line
		(start 30.25521 -129.82702)
		(end 30.254956 -129.82702)
		(stroke
			(width 0.08255)
			(type default)
		)
		(layer "In9.Cu")
	)
	(gr_line
		(start 30.256734 -129.826258)
		(end 30.371034 -129.779014)
		(stroke
			(width 0.08255)
			(type default)
		)
		(layer "In9.Cu")
	)
	(gr_line
		(start 30.289246 -116.46027)
		(end 30.234636 -116.328952)
		(stroke
			(width 0.08255)
			(type default)
		)
		(layer "In9.Cu")
	)
	(gr_line
		(start 30.291278 -126.94412)
		(end 30.291278 -126.943866)
		(stroke
			(width 0.08255)
			(type default)
		)
		(layer "In9.Cu")
	)
	(gr_line
		(start 30.293056 -126.943104)
		(end 30.424374 -126.889002)
		(stroke
			(width 0.08255)
			(type default)
		)
		(layer "In9.Cu")
	)
	(gr_line
		(start 30.30728 -109.796834)
		(end 30.584394 -109.127798)
		(stroke
			(width 0.08255)
			(type default)
		)
		(layer "In9.Cu")
	)
	(gr_line
		(start 30.321504 -121.788936)
		(end 30.46984 -121.727722)
		(stroke
			(width 0.08255)
			(type default)
		)
		(layer "In9.Cu")
	)
	(gr_line
		(start 30.33649 -104.473248)
		(end 30.496256 -104.473248)
		(stroke
			(width 0.08255)
			(type default)
		)
		(layer "In9.Cu")
	)
	(gr_line
		(start 30.371034 -129.779014)
		(end 30.561026 -129.321052)
		(stroke
			(width 0.08255)
			(type default)
		)
		(layer "In9.Cu")
	)
	(gr_line
		(start 30.424374 -126.889002)
		(end 30.609032 -126.442724)
		(stroke
			(width 0.08255)
			(type default)
		)
		(layer "In9.Cu")
	)
	(gr_line
		(start 30.425136 -115.869212)
		(end 30.5562 -115.814856)
		(stroke
			(width 0.08255)
			(type default)
		)
		(layer "In9.Cu")
	)
	(gr_line
		(start 30.440376 -110.51159)
		(end 30.379162 -110.363762)
		(stroke
			(width 0.08255)
			(type default)
		)
		(layer "In9.Cu")
	)
	(gr_line
		(start 30.441646 -128.63957)
		(end 30.699456 -128.01727)
		(stroke
			(width 0.08255)
			(type default)
		)
		(layer "In9.Cu")
	)
	(gr_line
		(start 30.46984 -121.727722)
		(end 30.659324 -121.26976)
		(stroke
			(width 0.08255)
			(type default)
		)
		(layer "In9.Cu")
	)
	(gr_line
		(start 30.496256 -104.473248)
		(end 30.837886 -104.131618)
		(stroke
			(width 0.08255)
			(type default)
		)
		(layer "In9.Cu")
	)
	(gr_line
		(start 30.526228 -120.555004)
		(end 30.803342 -119.885968)
		(stroke
			(width 0.08255)
			(type default)
		)
		(layer "In9.Cu")
	)
	(gr_line
		(start 30.5562 -115.814856)
		(end 30.746192 -115.357148)
		(stroke
			(width 0.08255)
			(type default)
		)
		(layer "In9.Cu")
	)
	(gr_line
		(start 30.561026 -129.321052)
		(end 30.513528 -129.206498)
		(stroke
			(width 0.08255)
			(type default)
		)
		(layer "In9.Cu")
	)
	(gr_line
		(start 30.569408 -109.904276)
		(end 30.71749 -109.843062)
		(stroke
			(width 0.08255)
			(type default)
		)
		(layer "In9.Cu")
	)
	(gr_line
		(start 30.571948 -105.903776)
		(end 30.571948 -105.76179)
		(stroke
			(width 0.08255)
			(type default)
		)
		(layer "In9.Cu")
	)
	(gr_line
		(start 30.609032 -126.442724)
		(end 30.554422 -126.31166)
		(stroke
			(width 0.08255)
			(type default)
		)
		(layer "In9.Cu")
	)
	(gr_line
		(start 30.619954 -114.658902)
		(end 30.887416 -114.013234)
		(stroke
			(width 0.08255)
			(type default)
		)
		(layer "In9.Cu")
	)
	(gr_line
		(start 30.659324 -121.26976)
		(end 30.597856 -121.121932)
		(stroke
			(width 0.08255)
			(type default)
		)
		(layer "In9.Cu")
	)
	(gr_line
		(start 30.70225 -128.74752)
		(end 30.70225 -128.747266)
		(stroke
			(width 0.08255)
			(type default)
		)
		(layer "In9.Cu")
	)
	(gr_line
		(start 30.704028 -128.746504)
		(end 30.818328 -128.69926)
		(stroke
			(width 0.08255)
			(type default)
		)
		(layer "In9.Cu")
	)
	(gr_line
		(start 30.71749 -109.843062)
		(end 30.906974 -109.3851)
		(stroke
			(width 0.08255)
			(type default)
		)
		(layer "In9.Cu")
	)
	(gr_line
		(start 30.72257 -105.21061)
		(end 31.216854 -104.716326)
		(stroke
			(width 0.08255)
			(type default)
		)
		(layer "In9.Cu")
	)
	(gr_line
		(start 30.738572 -125.864366)
		(end 30.738318 -125.864366)
		(stroke
			(width 0.08255)
			(type default)
		)
		(layer "In9.Cu")
	)
	(gr_line
		(start 30.740096 -125.863604)
		(end 30.871414 -125.809502)
		(stroke
			(width 0.08255)
			(type default)
		)
		(layer "In9.Cu")
	)
	(gr_line
		(start 30.746192 -115.357148)
		(end 30.691582 -115.22583)
		(stroke
			(width 0.08255)
			(type default)
		)
		(layer "In9.Cu")
	)
	(gr_line
		(start 30.788356 -120.662446)
		(end 30.936438 -120.601232)
		(stroke
			(width 0.08255)
			(type default)
		)
		(layer "In9.Cu")
	)
	(gr_line
		(start 30.818328 -128.69926)
		(end 31.00832 -128.241298)
		(stroke
			(width 0.08255)
			(type default)
		)
		(layer "In9.Cu")
	)
	(gr_line
		(start 30.837886 -104.131618)
		(end 30.837886 -103.971852)
		(stroke
			(width 0.08255)
			(type default)
		)
		(layer "In9.Cu")
	)
	(gr_line
		(start 30.871414 -125.809502)
		(end 31.056072 -125.363224)
		(stroke
			(width 0.08255)
			(type default)
		)
		(layer "In9.Cu")
	)
	(gr_line
		(start 30.882082 -114.76609)
		(end 31.013146 -114.711734)
		(stroke
			(width 0.08255)
			(type default)
		)
		(layer "In9.Cu")
	)
	(gr_line
		(start 30.88894 -127.559816)
		(end 31.14675 -126.937516)
		(stroke
			(width 0.08255)
			(type default)
		)
		(layer "In9.Cu")
	)
	(gr_line
		(start 30.906974 -109.3851)
		(end 30.845506 -109.237272)
		(stroke
			(width 0.08255)
			(type default)
		)
		(layer "In9.Cu")
	)
	(gr_line
		(start 30.923738 -105.41)
		(end 31.065724 -105.41)
		(stroke
			(width 0.08255)
			(type default)
		)
		(layer "In9.Cu")
	)
	(gr_line
		(start 30.936438 -120.601232)
		(end 31.125922 -120.14327)
		(stroke
			(width 0.08255)
			(type default)
		)
		(layer "In9.Cu")
	)
	(gr_line
		(start 30.936438 -108.277914)
		(end 30.957774 -108.226098)
		(stroke
			(width 0.08255)
			(type default)
		)
		(layer "In9.Cu")
	)
	(gr_line
		(start 30.957774 -108.226098)
		(end 30.958282 -108.226098)
		(stroke
			(width 0.08255)
			(type default)
		)
		(layer "In9.Cu")
	)
	(gr_line
		(start 30.958282 -108.226098)
		(end 30.997906 -108.186474)
		(stroke
			(width 0.08255)
			(type default)
		)
		(layer "In9.Cu")
	)
	(gr_line
		(start 30.992826 -119.428514)
		(end 31.26994 -118.759478)
		(stroke
			(width 0.08255)
			(type default)
		)
		(layer "In9.Cu")
	)
	(gr_line
		(start 31.00832 -128.241298)
		(end 30.960822 -128.126744)
		(stroke
			(width 0.08255)
			(type default)
		)
		(layer "In9.Cu")
	)
	(gr_line
		(start 31.013146 -114.711734)
		(end 31.203138 -114.254026)
		(stroke
			(width 0.08255)
			(type default)
		)
		(layer "In9.Cu")
	)
	(gr_line
		(start 31.056072 -125.363224)
		(end 31.001716 -125.232414)
		(stroke
			(width 0.08255)
			(type default)
		)
		(layer "In9.Cu")
	)
	(gr_line
		(start 31.065724 -105.41)
		(end 31.416244 -105.05948)
		(stroke
			(width 0.08255)
			(type default)
		)
		(layer "In9.Cu")
	)
	(gr_line
		(start 31.0769 -113.55578)
		(end 31.344362 -112.910112)
		(stroke
			(width 0.08255)
			(type default)
		)
		(layer "In9.Cu")
	)
	(gr_line
		(start 31.125922 -120.14327)
		(end 31.064454 -119.995442)
		(stroke
			(width 0.08255)
			(type default)
		)
		(layer "In9.Cu")
	)
	(gr_line
		(start 31.149544 -127.667766)
		(end 31.149544 -127.667512)
		(stroke
			(width 0.08255)
			(type default)
		)
		(layer "In9.Cu")
	)
	(gr_line
		(start 31.151322 -127.66675)
		(end 31.265622 -127.619506)
		(stroke
			(width 0.08255)
			(type default)
		)
		(layer "In9.Cu")
	)
	(gr_line
		(start 31.180786 -103.628952)
		(end 31.340552 -103.628952)
		(stroke
			(width 0.08255)
			(type default)
		)
		(layer "In9.Cu")
	)
	(gr_line
		(start 31.187136 -124.784104)
		(end 31.318708 -124.730002)
		(stroke
			(width 0.08255)
			(type default)
		)
		(layer "In9.Cu")
	)
	(gr_line
		(start 31.197296 -108.385864)
		(end 31.197042 -108.385864)
		(stroke
			(width 0.08255)
			(type default)
		)
		(layer "In9.Cu")
	)
	(gr_line
		(start 31.203138 -114.254026)
		(end 31.148782 -114.122708)
		(stroke
			(width 0.08255)
			(type default)
		)
		(layer "In9.Cu")
	)
	(gr_line
		(start 31.254954 -119.535956)
		(end 31.403036 -119.474742)
		(stroke
			(width 0.08255)
			(type default)
		)
		(layer "In9.Cu")
	)
	(gr_line
		(start 31.265622 -127.619506)
		(end 31.455614 -127.161544)
		(stroke
			(width 0.08255)
			(type default)
		)
		(layer "In9.Cu")
	)
	(gr_line
		(start 31.318708 -124.730002)
		(end 31.503366 -124.283724)
		(stroke
			(width 0.08255)
			(type default)
		)
		(layer "In9.Cu")
	)
	(gr_line
		(start 31.336234 -126.480062)
		(end 31.59379 -125.858016)
		(stroke
			(width 0.08255)
			(type default)
		)
		(layer "In9.Cu")
	)
	(gr_line
		(start 31.339028 -113.662968)
		(end 31.470092 -113.608612)
		(stroke
			(width 0.08255)
			(type default)
		)
		(layer "In9.Cu")
	)
	(gr_line
		(start 31.340552 -103.628952)
		(end 31.682182 -103.287322)
		(stroke
			(width 0.08255)
			(type default)
		)
		(layer "In9.Cu")
	)
	(gr_line
		(start 31.403036 -119.474742)
		(end 31.59252 -119.01678)
		(stroke
			(width 0.08255)
			(type default)
		)
		(layer "In9.Cu")
	)
	(gr_line
		(start 31.416244 -105.05948)
		(end 31.416244 -104.917494)
		(stroke
			(width 0.08255)
			(type default)
		)
		(layer "In9.Cu")
	)
	(gr_line
		(start 31.455614 -127.161544)
		(end 31.407862 -127.04699)
		(stroke
			(width 0.08255)
			(type default)
		)
		(layer "In9.Cu")
	)
	(gr_line
		(start 31.459424 -118.302024)
		(end 31.736538 -117.632988)
		(stroke
			(width 0.08255)
			(type default)
		)
		(layer "In9.Cu")
	)
	(gr_line
		(start 31.470092 -113.608612)
		(end 31.660084 -113.150904)
		(stroke
			(width 0.08255)
			(type default)
		)
		(layer "In9.Cu")
	)
	(gr_line
		(start 31.503366 -124.283724)
		(end 31.448756 -124.15266)
		(stroke
			(width 0.08255)
			(type default)
		)
		(layer "In9.Cu")
	)
	(gr_line
		(start 31.506668 -138.41476)
		(end 31.2293 -137.745724)
		(stroke
			(width 0.08255)
			(type default)
		)
		(layer "In9.Cu")
	)
	(gr_line
		(start 31.521146 -107.663234)
		(end 32.01543 -107.16895)
		(stroke
			(width 0.08255)
			(type default)
		)
		(layer "In9.Cu")
	)
	(gr_line
		(start 31.533846 -112.452658)
		(end 31.801308 -111.80699)
		(stroke
			(width 0.08255)
			(type default)
		)
		(layer "In9.Cu")
	)
	(gr_line
		(start 31.566866 -104.366314)
		(end 32.06115 -103.87203)
		(stroke
			(width 0.08255)
			(type default)
		)
		(layer "In9.Cu")
	)
	(gr_line
		(start 31.59252 -119.01678)
		(end 31.531052 -118.868952)
		(stroke
			(width 0.08255)
			(type default)
		)
		(layer "In9.Cu")
	)
	(gr_line
		(start 31.596838 -126.588012)
		(end 31.596584 -126.588012)
		(stroke
			(width 0.08255)
			(type default)
		)
		(layer "In9.Cu")
	)
	(gr_line
		(start 31.598362 -126.58725)
		(end 31.712662 -126.540006)
		(stroke
			(width 0.08255)
			(type default)
		)
		(layer "In9.Cu")
	)
	(gr_line
		(start 31.632906 -123.705366)
		(end 31.632652 -123.705366)
		(stroke
			(width 0.08255)
			(type default)
		)
		(layer "In9.Cu")
	)
	(gr_line
		(start 31.63443 -123.704604)
		(end 31.765748 -123.650502)
		(stroke
			(width 0.08255)
			(type default)
		)
		(layer "In9.Cu")
	)
	(gr_line
		(start 31.63951 -137.69975)
		(end 31.491428 -137.638536)
		(stroke
			(width 0.08255)
			(type default)
		)
		(layer "In9.Cu")
	)
	(gr_line
		(start 31.660084 -113.150904)
		(end 31.605728 -113.019586)
		(stroke
			(width 0.08255)
			(type default)
		)
		(layer "In9.Cu")
	)
	(gr_line
		(start 31.682182 -103.287322)
		(end 31.682182 -103.127556)
		(stroke
			(width 0.08255)
			(type default)
		)
		(layer "In9.Cu")
	)
	(gr_line
		(start 31.712662 -126.540006)
		(end 31.902654 -126.082044)
		(stroke
			(width 0.08255)
			(type default)
		)
		(layer "In9.Cu")
	)
	(gr_line
		(start 31.721552 -118.409466)
		(end 31.869634 -118.348252)
		(stroke
			(width 0.08255)
			(type default)
		)
		(layer "In9.Cu")
	)
	(gr_line
		(start 31.722314 -107.862624)
		(end 31.8643 -107.862624)
		(stroke
			(width 0.08255)
			(type default)
		)
		(layer "In9.Cu")
	)
	(gr_line
		(start 31.765748 -123.650502)
		(end 31.950406 -123.204224)
		(stroke
			(width 0.08255)
			(type default)
		)
		(layer "In9.Cu")
	)
	(gr_line
		(start 31.76778 -138.30554)
		(end 31.828994 -138.157458)
		(stroke
			(width 0.08255)
			(type default)
		)
		(layer "In9.Cu")
	)
	(gr_line
		(start 31.768034 -104.565704)
		(end 31.91002 -104.565704)
		(stroke
			(width 0.08255)
			(type default)
		)
		(layer "In9.Cu")
	)
	(gr_line
		(start 31.783274 -125.400562)
		(end 32.041084 -124.778262)
		(stroke
			(width 0.08255)
			(type default)
		)
		(layer "In9.Cu")
	)
	(gr_line
		(start 31.795974 -112.559846)
		(end 31.927038 -112.50549)
		(stroke
			(width 0.08255)
			(type default)
		)
		(layer "In9.Cu")
	)
	(gr_line
		(start 31.828994 -138.157458)
		(end 31.63951 -137.69975)
		(stroke
			(width 0.08255)
			(type default)
		)
		(layer "In9.Cu")
	)
	(gr_line
		(start 31.8643 -107.862624)
		(end 32.21482 -107.512104)
		(stroke
			(width 0.08255)
			(type default)
		)
		(layer "In9.Cu")
	)
	(gr_line
		(start 31.869634 -118.348252)
		(end 32.059118 -117.89029)
		(stroke
			(width 0.08255)
			(type default)
		)
		(layer "In9.Cu")
	)
	(gr_line
		(start 31.902654 -126.082044)
		(end 31.855156 -125.96749)
		(stroke
			(width 0.08255)
			(type default)
		)
		(layer "In9.Cu")
	)
	(gr_line
		(start 31.91002 -104.565704)
		(end 32.26054 -104.215184)
		(stroke
			(width 0.08255)
			(type default)
		)
		(layer "In9.Cu")
	)
	(gr_line
		(start 31.926022 -117.175534)
		(end 32.203136 -116.506498)
		(stroke
			(width 0.08255)
			(type default)
		)
		(layer "In9.Cu")
	)
	(gr_line
		(start 31.927038 -112.50549)
		(end 32.11703 -112.047782)
		(stroke
			(width 0.08255)
			(type default)
		)
		(layer "In9.Cu")
	)
	(gr_line
		(start 31.950406 -123.204224)
		(end 31.89605 -123.07316)
		(stroke
			(width 0.08255)
			(type default)
		)
		(layer "In9.Cu")
	)
	(gr_line
		(start 31.973266 -139.54125)
		(end 31.696152 -138.872214)
		(stroke
			(width 0.08255)
			(type default)
		)
		(layer "In9.Cu")
	)
	(gr_line
		(start 31.990792 -111.349536)
		(end 32.258254 -110.703868)
		(stroke
			(width 0.08255)
			(type default)
		)
		(layer "In9.Cu")
	)
	(gr_line
		(start 32.025082 -102.784656)
		(end 32.184848 -102.784656)
		(stroke
			(width 0.08255)
			(type default)
		)
		(layer "In9.Cu")
	)
	(gr_line
		(start 32.043878 -125.508512)
		(end 32.043878 -125.508258)
		(stroke
			(width 0.08255)
			(type default)
		)
		(layer "In9.Cu")
	)
	(gr_line
		(start 32.045656 -125.507496)
		(end 32.159956 -125.460252)
		(stroke
			(width 0.08255)
			(type default)
		)
		(layer "In9.Cu")
	)
	(gr_line
		(start 32.059118 -117.89029)
		(end 31.99765 -117.742462)
		(stroke
			(width 0.08255)
			(type default)
		)
		(layer "In9.Cu")
	)
	(gr_line
		(start 32.067754 -131.484624)
		(end 32.47009 -130.882644)
		(stroke
			(width 0.08255)
			(type default)
		)
		(layer "In9.Cu")
	)
	(gr_line
		(start 32.08147 -122.625104)
		(end 32.212788 -122.571002)
		(stroke
			(width 0.08255)
			(type default)
		)
		(layer "In9.Cu")
	)
	(gr_line
		(start 32.106362 -138.82624)
		(end 31.958026 -138.764772)
		(stroke
			(width 0.08255)
			(type default)
		)
		(layer "In9.Cu")
	)
	(gr_line
		(start 32.11703 -112.047782)
		(end 32.062674 -111.916464)
		(stroke
			(width 0.08255)
			(type default)
		)
		(layer "In9.Cu")
	)
	(gr_line
		(start 32.159956 -125.460252)
		(end 32.349948 -125.00229)
		(stroke
			(width 0.08255)
			(type default)
		)
		(layer "In9.Cu")
	)
	(gr_line
		(start 32.184848 -102.784656)
		(end 32.526478 -102.443026)
		(stroke
			(width 0.08255)
			(type default)
		)
		(layer "In9.Cu")
	)
	(gr_line
		(start 32.18815 -117.282976)
		(end 32.336232 -117.221762)
		(stroke
			(width 0.08255)
			(type default)
		)
		(layer "In9.Cu")
	)
	(gr_line
		(start 32.212788 -122.571002)
		(end 32.397446 -122.124724)
		(stroke
			(width 0.08255)
			(type default)
		)
		(layer "In9.Cu")
	)
	(gr_line
		(start 32.21482 -107.512104)
		(end 32.21482 -107.370118)
		(stroke
			(width 0.08255)
			(type default)
		)
		(layer "In9.Cu")
	)
	(gr_line
		(start 32.230568 -124.320808)
		(end 32.488378 -123.698508)
		(stroke
			(width 0.08255)
			(type default)
		)
		(layer "In9.Cu")
	)
	(gr_line
		(start 32.234378 -139.43203)
		(end 32.295846 -139.283948)
		(stroke
			(width 0.08255)
			(type default)
		)
		(layer "In9.Cu")
	)
	(gr_line
		(start 32.25292 -111.456724)
		(end 32.383984 -111.402368)
		(stroke
			(width 0.08255)
			(type default)
		)
		(layer "In9.Cu")
	)
	(gr_line
		(start 32.26054 -104.215184)
		(end 32.26054 -104.073198)
		(stroke
			(width 0.08255)
			(type default)
		)
		(layer "In9.Cu")
	)
	(gr_line
		(start 32.295846 -139.283948)
		(end 32.106362 -138.82624)
		(stroke
			(width 0.08255)
			(type default)
		)
		(layer "In9.Cu")
	)
	(gr_line
		(start 32.30372 -131.641088)
		(end 32.460692 -131.609846)
		(stroke
			(width 0.08255)
			(type default)
		)
		(layer "In9.Cu")
	)
	(gr_line
		(start 32.336232 -117.221762)
		(end 32.525716 -116.7638)
		(stroke
			(width 0.08255)
			(type default)
		)
		(layer "In9.Cu")
	)
	(gr_line
		(start 32.349948 -125.00229)
		(end 32.30245 -124.887736)
		(stroke
			(width 0.08255)
			(type default)
		)
		(layer "In9.Cu")
	)
	(gr_line
		(start 32.365442 -106.818938)
		(end 32.87776 -106.30662)
		(stroke
			(width 0.08255)
			(type default)
		)
		(layer "In9.Cu")
	)
	(gr_line
		(start 32.383984 -111.402368)
		(end 32.573976 -110.94466)
		(stroke
			(width 0.08255)
			(type default)
		)
		(layer "In9.Cu")
	)
	(gr_line
		(start 32.39262 -116.049044)
		(end 32.669734 -115.380008)
		(stroke
			(width 0.08255)
			(type default)
		)
		(layer "In9.Cu")
	)
	(gr_line
		(start 32.397446 -122.124724)
		(end 32.34309 -121.99366)
		(stroke
			(width 0.08255)
			(type default)
		)
		(layer "In9.Cu")
	)
	(gr_line
		(start 32.411162 -103.522018)
		(end 32.878268 -103.054912)
		(stroke
			(width 0.08255)
			(type default)
		)
		(layer "In9.Cu")
	)
	(gr_line
		(start 32.439864 -140.66774)
		(end 32.16275 -139.998704)
		(stroke
			(width 0.08255)
			(type default)
		)
		(layer "In9.Cu")
	)
	(gr_line
		(start 32.460692 -131.609846)
		(end 32.736028 -131.197858)
		(stroke
			(width 0.08255)
			(type default)
		)
		(layer "In9.Cu")
	)
	(gr_line
		(start 32.491172 -124.428758)
		(end 32.491172 -124.428504)
		(stroke
			(width 0.08255)
			(type default)
		)
		(layer "In9.Cu")
	)
	(gr_line
		(start 32.49295 -124.427742)
		(end 32.60725 -124.380498)
		(stroke
			(width 0.08255)
			(type default)
		)
		(layer "In9.Cu")
	)
	(gr_line
		(start 32.525716 -116.7638)
		(end 32.464248 -116.615972)
		(stroke
			(width 0.08255)
			(type default)
		)
		(layer "In9.Cu")
	)
	(gr_line
		(start 32.526478 -102.443026)
		(end 32.526478 -102.28326)
		(stroke
			(width 0.08255)
			(type default)
		)
		(layer "In9.Cu")
	)
	(gr_line
		(start 32.56661 -107.018328)
		(end 32.72663 -107.018328)
		(stroke
			(width 0.08255)
			(type default)
		)
		(layer "In9.Cu")
	)
	(gr_line
		(start 32.57296 -139.95273)
		(end 32.424624 -139.891262)
		(stroke
			(width 0.08255)
			(type default)
		)
		(layer "In9.Cu")
	)
	(gr_line
		(start 32.573976 -110.94466)
		(end 32.51962 -110.813342)
		(stroke
			(width 0.08255)
			(type default)
		)
		(layer "In9.Cu")
	)
	(gr_line
		(start 32.60725 -124.380498)
		(end 32.796988 -123.92279)
		(stroke
			(width 0.08255)
			(type default)
		)
		(layer "In9.Cu")
	)
	(gr_line
		(start 32.61233 -103.721408)
		(end 32.736028 -103.721408)
		(stroke
			(width 0.08255)
			(type default)
		)
		(layer "In9.Cu")
	)
	(gr_line
		(start 32.654748 -116.156486)
		(end 32.80283 -116.095272)
		(stroke
			(width 0.08255)
			(type default)
		)
		(layer "In9.Cu")
	)
	(gr_line
		(start 32.700976 -140.558266)
		(end 32.762444 -140.410438)
		(stroke
			(width 0.08255)
			(type default)
		)
		(layer "In9.Cu")
	)
	(gr_line
		(start 32.72663 -107.018328)
		(end 33.07715 -106.667808)
		(stroke
			(width 0.08255)
			(type default)
		)
		(layer "In9.Cu")
	)
	(gr_line
		(start 32.736028 -131.197858)
		(end 32.704786 -131.040886)
		(stroke
			(width 0.08255)
			(type default)
		)
		(layer "In9.Cu")
	)
	(gr_line
		(start 32.736028 -103.721408)
		(end 33.077658 -103.380032)
		(stroke
			(width 0.08255)
			(type default)
		)
		(layer "In9.Cu")
	)
	(gr_line
		(start 32.745172 -130.47091)
		(end 33.147254 -129.86893)
		(stroke
			(width 0.08255)
			(type default)
		)
		(layer "In9.Cu")
	)
	(gr_line
		(start 32.762444 -140.410438)
		(end 32.57296 -139.95273)
		(stroke
			(width 0.08255)
			(type default)
		)
		(layer "In9.Cu")
	)
	(gr_line
		(start 32.796988 -123.92279)
		(end 32.74949 -123.807982)
		(stroke
			(width 0.08255)
			(type default)
		)
		(layer "In9.Cu")
	)
	(gr_line
		(start 32.80283 -116.095272)
		(end 32.992314 -115.63731)
		(stroke
			(width 0.08255)
			(type default)
		)
		(layer "In9.Cu")
	)
	(gr_line
		(start 32.859218 -114.922554)
		(end 33.136332 -114.253518)
		(stroke
			(width 0.08255)
			(type default)
		)
		(layer "In9.Cu")
	)
	(gr_line
		(start 32.869378 -101.94036)
		(end 33.029144 -101.94036)
		(stroke
			(width 0.08255)
			(type default)
		)
		(layer "In9.Cu")
	)
	(gr_line
		(start 32.886904 -141.74724)
		(end 32.629348 -141.125194)
		(stroke
			(width 0.08255)
			(type default)
		)
		(layer "In9.Cu")
	)
	(gr_line
		(start 32.981138 -130.627374)
		(end 33.13811 -130.596132)
		(stroke
			(width 0.08255)
			(type default)
		)
		(layer "In9.Cu")
	)
	(gr_line
		(start 32.992314 -115.63731)
		(end 32.9311 -115.489482)
		(stroke
			(width 0.08255)
			(type default)
		)
		(layer "In9.Cu")
	)
	(gr_line
		(start 33.00603 -141.06525)
		(end 32.891476 -141.017752)
		(stroke
			(width 0.08255)
			(type default)
		)
		(layer "In9.Cu")
	)
	(gr_line
		(start 33.029144 -101.94036)
		(end 33.37052 -101.598984)
		(stroke
			(width 0.08255)
			(type default)
		)
		(layer "In9.Cu")
	)
	(gr_line
		(start 33.07715 -106.667808)
		(end 33.07715 -106.507788)
		(stroke
			(width 0.08255)
			(type default)
		)
		(layer "In9.Cu")
	)
	(gr_line
		(start 33.077658 -103.380032)
		(end 33.077658 -103.25608)
		(stroke
			(width 0.08255)
			(type default)
		)
		(layer "In9.Cu")
	)
	(gr_line
		(start 33.121346 -115.029742)
		(end 33.269428 -114.968782)
		(stroke
			(width 0.08255)
			(type default)
		)
		(layer "In9.Cu")
	)
	(gr_line
		(start 33.128712 -120.868694)
		(end 33.288478 -120.868694)
		(stroke
			(width 0.08255)
			(type default)
		)
		(layer "In9.Cu")
	)
	(gr_line
		(start 33.13811 -130.596132)
		(end 33.413446 -130.184144)
		(stroke
			(width 0.08255)
			(type default)
		)
		(layer "In9.Cu")
	)
	(gr_line
		(start 33.14827 -141.63802)
		(end 33.195768 -141.523212)
		(stroke
			(width 0.08255)
			(type default)
		)
		(layer "In9.Cu")
	)
	(gr_line
		(start 33.16859 -109.495336)
		(end 33.628584 -109.035342)
		(stroke
			(width 0.08255)
			(type default)
		)
		(layer "In9.Cu")
	)
	(gr_line
		(start 33.195768 -141.523212)
		(end 33.00603 -141.06525)
		(stroke
			(width 0.08255)
			(type default)
		)
		(layer "In9.Cu")
	)
	(gr_line
		(start 33.21939 -102.71379)
		(end 33.68675 -102.24643)
		(stroke
			(width 0.08255)
			(type default)
		)
		(layer "In9.Cu")
	)
	(gr_line
		(start 33.227772 -105.956608)
		(end 33.74009 -105.44429)
		(stroke
			(width 0.08255)
			(type default)
		)
		(layer "In9.Cu")
	)
	(gr_line
		(start 33.269428 -114.968782)
		(end 33.458912 -114.51082)
		(stroke
			(width 0.08255)
			(type default)
		)
		(layer "In9.Cu")
	)
	(gr_line
		(start 33.271968 -122.386852)
		(end 33.766252 -121.892568)
		(stroke
			(width 0.08255)
			(type default)
		)
		(layer "In9.Cu")
	)
	(gr_line
		(start 33.288478 -120.868694)
		(end 33.629854 -120.527318)
		(stroke
			(width 0.08255)
			(type default)
		)
		(layer "In9.Cu")
	)
	(gr_line
		(start 33.325816 -113.796064)
		(end 33.60293 -113.127028)
		(stroke
			(width 0.08255)
			(type default)
		)
		(layer "In9.Cu")
	)
	(gr_line
		(start 33.369758 -109.694726)
		(end 33.486344 -109.694726)
		(stroke
			(width 0.08255)
			(type default)
		)
		(layer "In9.Cu")
	)
	(gr_line
		(start 33.37052 -101.598984)
		(end 33.37052 -101.439218)
		(stroke
			(width 0.08255)
			(type default)
		)
		(layer "In9.Cu")
	)
	(gr_line
		(start 33.413446 -130.184144)
		(end 33.382204 -130.027172)
		(stroke
			(width 0.08255)
			(type default)
		)
		(layer "In9.Cu")
	)
	(gr_line
		(start 33.420558 -102.91318)
		(end 33.54451 -102.91318)
		(stroke
			(width 0.08255)
			(type default)
		)
		(layer "In9.Cu")
	)
	(gr_line
		(start 33.42259 -129.457196)
		(end 33.824926 -128.854962)
		(stroke
			(width 0.08255)
			(type default)
		)
		(layer "In9.Cu")
	)
	(gr_line
		(start 33.42894 -106.155998)
		(end 33.58896 -106.155998)
		(stroke
			(width 0.08255)
			(type default)
		)
		(layer "In9.Cu")
	)
	(gr_line
		(start 33.458912 -114.51082)
		(end 33.397698 -114.362992)
		(stroke
			(width 0.08255)
			(type default)
		)
		(layer "In9.Cu")
	)
	(gr_line
		(start 33.473136 -122.586242)
		(end 33.615122 -122.586242)
		(stroke
			(width 0.08255)
			(type default)
		)
		(layer "In9.Cu")
	)
	(gr_line
		(start 33.486344 -109.694726)
		(end 33.827974 -109.35335)
		(stroke
			(width 0.08255)
			(type default)
		)
		(layer "In9.Cu")
	)
	(gr_line
		(start 33.54451 -102.91318)
		(end 33.88614 -102.57155)
		(stroke
			(width 0.08255)
			(type default)
		)
		(layer "In9.Cu")
	)
	(gr_line
		(start 33.587944 -113.903252)
		(end 33.736026 -113.842292)
		(stroke
			(width 0.08255)
			(type default)
		)
		(layer "In9.Cu")
	)
	(gr_line
		(start 33.58896 -106.155998)
		(end 33.93948 -105.805478)
		(stroke
			(width 0.08255)
			(type default)
		)
		(layer "In9.Cu")
	)
	(gr_line
		(start 33.615122 -122.586242)
		(end 33.965642 -122.235722)
		(stroke
			(width 0.08255)
			(type default)
		)
		(layer "In9.Cu")
	)
	(gr_line
		(start 33.629854 -120.527318)
		(end 33.629854 -120.367552)
		(stroke
			(width 0.08255)
			(type default)
		)
		(layer "In9.Cu")
	)
	(gr_line
		(start 33.658556 -129.61366)
		(end 33.815528 -129.582164)
		(stroke
			(width 0.08255)
			(type default)
		)
		(layer "In9.Cu")
	)
	(gr_line
		(start 33.736026 -113.842292)
		(end 33.92551 -113.38433)
		(stroke
			(width 0.08255)
			(type default)
		)
		(layer "In9.Cu")
	)
	(gr_line
		(start 33.815528 -129.582164)
		(end 34.090864 -129.170176)
		(stroke
			(width 0.08255)
			(type default)
		)
		(layer "In9.Cu")
	)
	(gr_line
		(start 33.827974 -109.35335)
		(end 33.827974 -109.23651)
		(stroke
			(width 0.08255)
			(type default)
		)
		(layer "In9.Cu")
	)
	(gr_line
		(start 33.88614 -102.57155)
		(end 33.88614 -102.447598)
		(stroke
			(width 0.08255)
			(type default)
		)
		(layer "In9.Cu")
	)
	(gr_line
		(start 33.92551 -113.38433)
		(end 33.864296 -113.236502)
		(stroke
			(width 0.08255)
			(type default)
		)
		(layer "In9.Cu")
	)
	(gr_line
		(start 33.93948 -105.805478)
		(end 33.93948 -105.645458)
		(stroke
			(width 0.08255)
			(type default)
		)
		(layer "In9.Cu")
	)
	(gr_line
		(start 33.965642 -122.235722)
		(end 33.965642 -122.093736)
		(stroke
			(width 0.08255)
			(type default)
		)
		(layer "In9.Cu")
	)
	(gr_line
		(start 34.090864 -129.170176)
		(end 34.059622 -129.013458)
		(stroke
			(width 0.08255)
			(type default)
		)
		(layer "In9.Cu")
	)
	(gr_line
		(start 34.100008 -128.443228)
		(end 34.438844 -127.936244)
		(stroke
			(width 0.08255)
			(type default)
		)
		(layer "In9.Cu")
	)
	(gr_line
		(start 34.29 -139.189968)
		(end 34.012886 -138.520932)
		(stroke
			(width 0.08255)
			(type default)
		)
		(layer "In9.Cu")
	)
	(gr_line
		(start 34.336228 -128.599692)
		(end 34.45764 -128.575562)
		(stroke
			(width 0.08255)
			(type default)
		)
		(layer "In9.Cu")
	)
	(gr_line
		(start 34.422842 -138.474704)
		(end 34.275014 -138.413744)
		(stroke
			(width 0.08255)
			(type default)
		)
		(layer "In9.Cu")
	)
	(gr_line
		(start 34.45764 -128.575562)
		(end 34.697924 -128.216152)
		(stroke
			(width 0.08255)
			(type default)
		)
		(layer "In9.Cu")
	)
	(gr_line
		(start 34.551112 -139.080494)
		(end 34.612326 -138.932666)
		(stroke
			(width 0.08255)
			(type default)
		)
		(layer "In9.Cu")
	)
	(gr_line
		(start 34.612326 -138.932666)
		(end 34.422842 -138.474704)
		(stroke
			(width 0.08255)
			(type default)
		)
		(layer "In9.Cu")
	)
	(gr_line
		(start 34.697924 -128.216152)
		(end 34.67354 -128.094486)
		(stroke
			(width 0.08255)
			(type default)
		)
		(layer "In9.Cu")
	)
	(gr_line
		(start 34.699956 -127.545338)
		(end 34.70656 -127.535432)
		(stroke
			(width 0.08255)
			(type default)
		)
		(layer "In9.Cu")
	)
	(gr_line
		(start 34.70656 -127.535432)
		(end 35.04565 -127.028194)
		(stroke
			(width 0.08255)
			(type default)
		)
		(layer "In9.Cu")
	)
	(gr_line
		(start 34.756598 -140.316458)
		(end 34.479484 -139.647422)
		(stroke
			(width 0.08255)
			(type default)
		)
		(layer "In9.Cu")
	)
	(gr_line
		(start 34.83483 -119.797068)
		(end 35.12566 -120.087898)
		(stroke
			(width 0.08255)
			(type default)
		)
		(layer "In9.Cu")
	)
	(gr_line
		(start 34.83483 -112.493552)
		(end 35.12566 -112.784382)
		(stroke
			(width 0.08255)
			(type default)
		)
		(layer "In9.Cu")
	)
	(gr_line
		(start 34.83483 -112.211612)
		(end 35.12566 -111.920782)
		(stroke
			(width 0.08255)
			(type default)
		)
		(layer "In9.Cu")
	)
	(gr_line
		(start 34.83483 -108.89361)
		(end 35.12566 -109.18444)
		(stroke
			(width 0.08255)
			(type default)
		)
		(layer "In9.Cu")
	)
	(gr_line
		(start 34.83483 -108.61167)
		(end 35.12566 -108.32084)
		(stroke
			(width 0.08255)
			(type default)
		)
		(layer "In9.Cu")
	)
	(gr_line
		(start 34.83483 -105.293668)
		(end 35.12566 -105.584498)
		(stroke
			(width 0.08255)
			(type default)
		)
		(layer "In9.Cu")
	)
	(gr_line
		(start 34.83483 -105.011728)
		(end 35.12566 -104.720898)
		(stroke
			(width 0.08255)
			(type default)
		)
		(layer "In9.Cu")
	)
	(gr_line
		(start 34.889694 -139.601448)
		(end 34.741612 -139.53998)
		(stroke
			(width 0.08255)
			(type default)
		)
		(layer "In9.Cu")
	)
	(gr_line
		(start 34.94278 -127.691896)
		(end 35.064446 -127.667512)
		(stroke
			(width 0.08255)
			(type default)
		)
		(layer "In9.Cu")
	)
	(gr_line
		(start 35.017964 -140.207238)
		(end 35.079178 -140.059156)
		(stroke
			(width 0.08255)
			(type default)
		)
		(layer "In9.Cu")
	)
	(gr_line
		(start 35.064446 -127.667512)
		(end 35.304476 -127.308356)
		(stroke
			(width 0.08255)
			(type default)
		)
		(layer "In9.Cu")
	)
	(gr_line
		(start 35.079178 -140.059156)
		(end 34.889694 -139.601448)
		(stroke
			(width 0.08255)
			(type default)
		)
		(layer "In9.Cu")
	)
	(gr_line
		(start 35.12566 -121.321576)
		(end 35.70986 -121.321576)
		(stroke
			(width 0.08255)
			(type default)
		)
		(layer "In9.Cu")
	)
	(gr_line
		(start 35.12693 -121.604786)
		(end 35.21456 -121.692416)
		(stroke
			(width 0.08255)
			(type default)
		)
		(layer "In9.Cu")
	)
	(gr_line
		(start 35.211004 -100.344732)
		(end 35.359086 -100.4062)
		(stroke
			(width 0.08255)
			(type default)
		)
		(layer "In9.Cu")
	)
	(gr_line
		(start 35.21456 -121.692416)
		(end 35.62096 -121.692416)
		(stroke
			(width 0.08255)
			(type default)
		)
		(layer "In9.Cu")
	)
	(gr_line
		(start 35.304476 -127.308356)
		(end 35.280346 -127.186436)
		(stroke
			(width 0.08255)
			(type default)
		)
		(layer "In9.Cu")
	)
	(gr_line
		(start 35.359086 -100.4062)
		(end 35.805364 -100.221542)
		(stroke
			(width 0.08255)
			(type default)
		)
		(layer "In9.Cu")
	)
	(gr_line
		(start 35.44443 -101.693472)
		(end 35.73526 -101.984302)
		(stroke
			(width 0.08255)
			(type default)
		)
		(layer "In9.Cu")
	)
	(gr_line
		(start 35.44443 -101.411532)
		(end 35.73526 -101.120702)
		(stroke
			(width 0.08255)
			(type default)
		)
		(layer "In9.Cu")
	)
	(gr_line
		(start 35.475672 -143.914368)
		(end 35.440112 -143.19123)
		(stroke
			(width 0.08255)
			(type default)
		)
		(layer "In9.Cu")
	)
	(gr_line
		(start 35.536886 -145.15846)
		(end 35.501326 -144.435322)
		(stroke
			(width 0.08255)
			(type default)
		)
		(layer "In9.Cu")
	)
	(gr_line
		(start 35.59683 -146.37639)
		(end 35.56127 -145.652998)
		(stroke
			(width 0.08255)
			(type default)
		)
		(layer "In9.Cu")
	)
	(gr_line
		(start 35.62096 -121.692416)
		(end 35.70859 -121.604786)
		(stroke
			(width 0.08255)
			(type default)
		)
		(layer "In9.Cu")
	)
	(gr_line
		(start 35.656774 -147.59432)
		(end 35.621214 -146.870928)
		(stroke
			(width 0.08255)
			(type default)
		)
		(layer "In9.Cu")
	)
	(gr_line
		(start 35.716718 -148.812504)
		(end 35.681158 -148.088858)
		(stroke
			(width 0.08255)
			(type default)
		)
		(layer "In9.Cu")
	)
	(gr_line
		(start 35.758628 -143.899636)
		(end 35.866324 -143.781018)
		(stroke
			(width 0.08255)
			(type default)
		)
		(layer "In9.Cu")
	)
	(gr_line
		(start 35.805364 -100.221542)
		(end 35.866578 -100.073206)
		(stroke
			(width 0.08255)
			(type default)
		)
		(layer "In9.Cu")
	)
	(gr_line
		(start 35.819842 -145.143728)
		(end 35.927538 -145.02511)
		(stroke
			(width 0.08255)
			(type default)
		)
		(layer "In9.Cu")
	)
	(gr_line
		(start 35.84194 -143.285972)
		(end 35.723068 -143.178784)
		(stroke
			(width 0.08255)
			(type default)
		)
		(layer "In9.Cu")
	)
	(gr_line
		(start 35.84956 -132.531612)
		(end 36.56076 -132.531612)
		(stroke
			(width 0.08255)
			(type default)
		)
		(layer "In9.Cu")
	)
	(gr_line
		(start 35.85083 -132.814822)
		(end 35.96386 -132.927852)
		(stroke
			(width 0.08255)
			(type default)
		)
		(layer "In9.Cu")
	)
	(gr_line
		(start 35.866324 -143.781018)
		(end 35.84194 -143.285972)
		(stroke
			(width 0.08255)
			(type default)
		)
		(layer "In9.Cu")
	)
	(gr_line
		(start 35.879786 -146.361658)
		(end 35.987482 -146.242786)
		(stroke
			(width 0.08255)
			(type default)
		)
		(layer "In9.Cu")
	)
	(gr_line
		(start 35.903154 -144.530064)
		(end 35.784282 -144.422876)
		(stroke
			(width 0.08255)
			(type default)
		)
		(layer "In9.Cu")
	)
	(gr_line
		(start 35.927538 -145.02511)
		(end 35.903154 -144.530064)
		(stroke
			(width 0.08255)
			(type default)
		)
		(layer "In9.Cu")
	)
	(gr_line
		(start 35.93973 -147.579588)
		(end 36.047426 -147.460716)
		(stroke
			(width 0.08255)
			(type default)
		)
		(layer "In9.Cu")
	)
	(gr_line
		(start 35.963098 -145.74774)
		(end 35.844226 -145.640298)
		(stroke
			(width 0.08255)
			(type default)
		)
		(layer "In9.Cu")
	)
	(gr_line
		(start 35.96386 -132.927852)
		(end 36.44646 -132.927852)
		(stroke
			(width 0.08255)
			(type default)
		)
		(layer "In9.Cu")
	)
	(gr_line
		(start 35.987482 -146.242786)
		(end 35.963098 -145.74774)
		(stroke
			(width 0.08255)
			(type default)
		)
		(layer "In9.Cu")
	)
	(gr_line
		(start 35.99942 -148.797518)
		(end 36.10737 -148.678646)
		(stroke
			(width 0.08255)
			(type default)
		)
		(layer "In9.Cu")
	)
	(gr_line
		(start 36.023042 -146.965924)
		(end 35.90417 -146.858228)
		(stroke
			(width 0.08255)
			(type default)
		)
		(layer "In9.Cu")
	)
	(gr_line
		(start 36.047426 -147.460716)
		(end 36.023042 -146.965924)
		(stroke
			(width 0.08255)
			(type default)
		)
		(layer "In9.Cu")
	)
	(gr_line
		(start 36.082986 -148.183854)
		(end 35.964114 -148.076158)
		(stroke
			(width 0.08255)
			(type default)
		)
		(layer "In9.Cu")
	)
	(gr_line
		(start 36.10737 -148.678646)
		(end 36.082986 -148.183854)
		(stroke
			(width 0.08255)
			(type default)
		)
		(layer "In9.Cu")
	)
	(gr_line
		(start 36.11626 -121.321576)
		(end 36.70046 -121.321576)
		(stroke
			(width 0.08255)
			(type default)
		)
		(layer "In9.Cu")
	)
	(gr_line
		(start 36.11753 -121.604786)
		(end 36.20516 -121.692416)
		(stroke
			(width 0.08255)
			(type default)
		)
		(layer "In9.Cu")
	)
	(gr_line
		(start 36.20516 -121.692416)
		(end 36.61156 -121.692416)
		(stroke
			(width 0.08255)
			(type default)
		)
		(layer "In9.Cu")
	)
	(gr_line
		(start 36.44646 -132.927852)
		(end 36.55949 -132.814822)
		(stroke
			(width 0.08255)
			(type default)
		)
		(layer "In9.Cu")
	)
	(gr_line
		(start 36.61156 -121.692416)
		(end 36.69919 -121.604786)
		(stroke
			(width 0.08255)
			(type default)
		)
		(layer "In9.Cu")
	)
	(gr_line
		(start 37.152072 -137.480802)
		(end 37.01034 -137.480802)
		(stroke
			(width 0.08255)
			(type default)
		)
		(layer "In9.Cu")
	)
	(gr_line
		(start 37.294312 -138.165332)
		(end 36.809172 -137.680192)
		(stroke
			(width 0.08255)
			(type default)
		)
		(layer "In9.Cu")
	)
	(gr_line
		(start 37.476938 -136.413494)
		(end 37.767768 -136.704324)
		(stroke
			(width 0.08255)
			(type default)
		)
		(layer "In9.Cu")
	)
	(gr_line
		(start 37.476938 -136.131554)
		(end 37.767768 -135.840724)
		(stroke
			(width 0.08255)
			(type default)
		)
		(layer "In9.Cu")
	)
	(gr_line
		(start 37.476938 -132.813552)
		(end 37.767768 -133.104382)
		(stroke
			(width 0.08255)
			(type default)
		)
		(layer "In9.Cu")
	)
	(gr_line
		(start 37.476938 -132.531612)
		(end 37.767768 -132.240782)
		(stroke
			(width 0.08255)
			(type default)
		)
		(layer "In9.Cu")
	)
	(gr_line
		(start 37.476938 -125.203712)
		(end 37.767768 -125.494542)
		(stroke
			(width 0.08255)
			(type default)
		)
		(layer "In9.Cu")
	)
	(gr_line
		(start 37.476938 -124.921772)
		(end 37.767768 -124.630942)
		(stroke
			(width 0.08255)
			(type default)
		)
		(layer "In9.Cu")
	)
	(gr_line
		(start 37.476938 -121.603516)
		(end 37.767768 -121.894346)
		(stroke
			(width 0.08255)
			(type default)
		)
		(layer "In9.Cu")
	)
	(gr_line
		(start 37.476938 -121.321576)
		(end 37.767768 -121.030746)
		(stroke
			(width 0.08255)
			(type default)
		)
		(layer "In9.Cu")
	)
	(gr_line
		(start 37.476938 -99.887024)
		(end 37.767768 -100.177854)
		(stroke
			(width 0.08255)
			(type default)
		)
		(layer "In9.Cu")
	)
	(gr_line
		(start 37.493702 -137.964164)
		(end 37.493702 -137.822178)
		(stroke
			(width 0.08255)
			(type default)
		)
		(layer "In9.Cu")
	)
	(gr_line
		(start 37.493702 -137.822178)
		(end 37.152072 -137.480802)
		(stroke
			(width 0.08255)
			(type default)
		)
		(layer "In9.Cu")
	)
	(gr_line
		(start 38.25113 -140.656056)
		(end 38.117526 -139.98321)
		(stroke
			(width 0.08255)
			(type default)
		)
		(layer "In9.Cu")
	)
	(gr_line
		(start 38.483794 -141.826996)
		(end 38.34765 -141.141704)
		(stroke
			(width 0.08255)
			(type default)
		)
		(layer "In9.Cu")
	)
	(gr_line
		(start 38.513766 -140.008102)
		(end 38.395656 -139.929362)
		(stroke
			(width 0.08255)
			(type default)
		)
		(layer "In9.Cu")
	)
	(gr_line
		(start 38.528752 -140.600176)
		(end 38.607746 -140.481812)
		(stroke
			(width 0.08255)
			(type default)
		)
		(layer "In9.Cu")
	)
	(gr_line
		(start 38.607746 -140.481812)
		(end 38.513766 -140.008102)
		(stroke
			(width 0.08255)
			(type default)
		)
		(layer "In9.Cu")
	)
	(gr_line
		(start 38.716204 -142.997936)
		(end 38.58006 -142.312644)
		(stroke
			(width 0.08255)
			(type default)
		)
		(layer "In9.Cu")
	)
	(gr_line
		(start 38.744144 -141.16685)
		(end 38.625526 -141.087856)
		(stroke
			(width 0.08255)
			(type default)
		)
		(layer "In9.Cu")
	)
	(gr_line
		(start 38.761416 -141.771116)
		(end 38.84041 -141.652752)
		(stroke
			(width 0.08255)
			(type default)
		)
		(layer "In9.Cu")
	)
	(gr_line
		(start 38.84041 -141.652752)
		(end 38.744144 -141.16685)
		(stroke
			(width 0.08255)
			(type default)
		)
		(layer "In9.Cu")
	)
	(gr_line
		(start 38.948868 -144.168876)
		(end 38.812724 -143.483584)
		(stroke
			(width 0.08255)
			(type default)
		)
		(layer "In9.Cu")
	)
	(gr_line
		(start 38.976808 -142.33779)
		(end 38.85819 -142.258542)
		(stroke
			(width 0.08255)
			(type default)
		)
		(layer "In9.Cu")
	)
	(gr_line
		(start 38.993826 -142.942056)
		(end 39.073074 -142.823692)
		(stroke
			(width 0.08255)
			(type default)
		)
		(layer "In9.Cu")
	)
	(gr_line
		(start 39.073074 -142.823692)
		(end 38.976808 -142.33779)
		(stroke
			(width 0.08255)
			(type default)
		)
		(layer "In9.Cu")
	)
	(gr_line
		(start 39.181278 -145.339816)
		(end 39.045388 -144.654524)
		(stroke
			(width 0.08255)
			(type default)
		)
		(layer "In9.Cu")
	)
	(gr_line
		(start 39.209472 -143.50873)
		(end 39.0906 -143.429482)
		(stroke
			(width 0.08255)
			(type default)
		)
		(layer "In9.Cu")
	)
	(gr_line
		(start 39.22649 -144.11325)
		(end 39.305738 -143.994632)
		(stroke
			(width 0.08255)
			(type default)
		)
		(layer "In9.Cu")
	)
	(gr_line
		(start 39.305738 -143.994632)
		(end 39.209472 -143.50873)
		(stroke
			(width 0.08255)
			(type default)
		)
		(layer "In9.Cu")
	)
	(gr_line
		(start 39.413942 -146.510756)
		(end 39.277798 -145.825464)
		(stroke
			(width 0.08255)
			(type default)
		)
		(layer "In9.Cu")
	)
	(gr_line
		(start 39.442136 -144.67967)
		(end 39.323264 -144.600422)
		(stroke
			(width 0.08255)
			(type default)
		)
		(layer "In9.Cu")
	)
	(gr_line
		(start 39.459154 -145.28419)
		(end 39.538402 -145.165572)
		(stroke
			(width 0.08255)
			(type default)
		)
		(layer "In9.Cu")
	)
	(gr_line
		(start 39.538402 -145.165572)
		(end 39.442136 -144.67967)
		(stroke
			(width 0.08255)
			(type default)
		)
		(layer "In9.Cu")
	)
	(gr_line
		(start 39.646606 -147.68195)
		(end 39.510462 -146.996404)
		(stroke
			(width 0.08255)
			(type default)
		)
		(layer "In9.Cu")
	)
	(gr_line
		(start 39.6748 -145.85061)
		(end 39.555674 -145.771108)
		(stroke
			(width 0.08255)
			(type default)
		)
		(layer "In9.Cu")
	)
	(gr_line
		(start 39.691564 -146.455384)
		(end 39.771066 -146.336512)
		(stroke
			(width 0.08255)
			(type default)
		)
		(layer "In9.Cu")
	)
	(gr_line
		(start 39.771066 -146.336512)
		(end 39.6748 -145.85061)
		(stroke
			(width 0.08255)
			(type default)
		)
		(layer "In9.Cu")
	)
	(gr_line
		(start 39.884096 -148.878036)
		(end 39.742872 -148.167344)
		(stroke
			(width 0.08255)
			(type default)
		)
		(layer "In9.Cu")
	)
	(gr_line
		(start 39.907464 -147.02155)
		(end 39.788338 -146.942048)
		(stroke
			(width 0.08255)
			(type default)
		)
		(layer "In9.Cu")
	)
	(gr_line
		(start 39.924228 -147.626324)
		(end 40.00373 -147.507452)
		(stroke
			(width 0.08255)
			(type default)
		)
		(layer "In9.Cu")
	)
	(gr_line
		(start 40.00373 -147.507452)
		(end 39.907464 -147.02155)
		(stroke
			(width 0.08255)
			(type default)
		)
		(layer "In9.Cu")
	)
	(gr_line
		(start 40.15486 -148.202396)
		(end 40.020748 -148.112988)
		(stroke
			(width 0.08255)
			(type default)
		)
		(layer "In9.Cu")
	)
	(gr_line
		(start 40.161718 -148.82241)
		(end 40.25138 -148.688552)
		(stroke
			(width 0.08255)
			(type default)
		)
		(layer "In9.Cu")
	)
	(gr_line
		(start 40.25138 -148.688552)
		(end 40.15486 -148.202396)
		(stroke
			(width 0.08255)
			(type default)
		)
		(layer "In9.Cu")
	)
	(gr_line
		(start 58.083958 -319.944496)
		(end 58.083958 -319.916048)
		(stroke
			(width 0.05715)
			(type default)
		)
		(layer "In9.Cu")
	)
	(gr_line
		(start 58.083958 -319.916048)
		(end 58.129678 -319.870328)
		(stroke
			(width 0.05715)
			(type default)
		)
		(layer "In9.Cu")
	)
	(gr_line
		(start 58.611008 -316.229492)
		(end 58.699908 -316.140592)
		(stroke
			(width 0.05715)
			(type default)
		)
		(layer "In9.Cu")
	)
	(gr_line
		(start 58.699908 -316.140592)
		(end 58.699908 -315.849762)
		(stroke
			(width 0.05715)
			(type default)
		)
		(layer "In9.Cu")
	)
	(gr_line
		(start 59.270138 -271.546066)
		(end 59.315858 -271.500346)
		(stroke
			(width 0.05715)
			(type default)
		)
		(layer "In9.Cu")
	)
	(gr_line
		(start 59.315858 -271.500346)
		(end 59.315858 -271.471898)
		(stroke
			(width 0.05715)
			(type default)
		)
		(layer "In9.Cu")
	)
	(gr_line
		(start 59.649614 -278.115268)
		(end 59.535314 -278.229568)
		(stroke
			(width 0.05715)
			(type default)
		)
		(layer "In9.Cu")
	)
	(gr_line
		(start 59.649614 -277.849838)
		(end 59.649614 -278.115268)
		(stroke
			(width 0.05715)
			(type default)
		)
		(layer "In9.Cu")
	)
	(gr_line
		(start 59.983878 -271.554448)
		(end 59.983878 -271.526)
		(stroke
			(width 0.05715)
			(type default)
		)
		(layer "In9.Cu")
	)
	(gr_line
		(start 60.029598 -271.600168)
		(end 59.983878 -271.554448)
		(stroke
			(width 0.05715)
			(type default)
		)
		(layer "In9.Cu")
	)
	(gr_line
		(start 60.220098 -271.600168)
		(end 60.265818 -271.554448)
		(stroke
			(width 0.05715)
			(type default)
		)
		(layer "In9.Cu")
	)
	(gr_line
		(start 60.265818 -271.554448)
		(end 60.265818 -271.526)
		(stroke
			(width 0.05715)
			(type default)
		)
		(layer "In9.Cu")
	)
	(gr_line
		(start 60.599828 -280.699718)
		(end 60.599828 -280.434288)
		(stroke
			(width 0.05715)
			(type default)
		)
		(layer "In9.Cu")
	)
	(gr_line
		(start 60.599828 -280.434288)
		(end 60.485528 -280.319988)
		(stroke
			(width 0.05715)
			(type default)
		)
		(layer "In9.Cu")
	)
	(gr_line
		(start 60.599828 -280.015188)
		(end 60.485528 -280.129488)
		(stroke
			(width 0.05715)
			(type default)
		)
		(layer "In9.Cu")
	)
	(gr_line
		(start 60.599828 -279.749504)
		(end 60.599828 -280.015188)
		(stroke
			(width 0.05715)
			(type default)
		)
		(layer "In9.Cu")
	)
	(gr_line
		(start 61.883798 -271.554448)
		(end 61.883798 -271.526)
		(stroke
			(width 0.05715)
			(type default)
		)
		(layer "In9.Cu")
	)
	(gr_line
		(start 61.929518 -271.600168)
		(end 61.883798 -271.554448)
		(stroke
			(width 0.05715)
			(type default)
		)
		(layer "In9.Cu")
	)
	(gr_line
		(start 62.120018 -271.600168)
		(end 62.165738 -271.554448)
		(stroke
			(width 0.05715)
			(type default)
		)
		(layer "In9.Cu")
	)
	(gr_line
		(start 62.165738 -271.554448)
		(end 62.165738 -271.526)
		(stroke
			(width 0.05715)
			(type default)
		)
		(layer "In9.Cu")
	)
	(gr_line
		(start 62.499748 -280.699718)
		(end 62.499748 -280.434288)
		(stroke
			(width 0.05715)
			(type default)
		)
		(layer "In9.Cu")
	)
	(gr_line
		(start 62.499748 -280.434288)
		(end 62.385448 -280.319988)
		(stroke
			(width 0.05715)
			(type default)
		)
		(layer "In9.Cu")
	)
	(gr_line
		(start 62.499748 -280.015188)
		(end 62.385448 -280.129488)
		(stroke
			(width 0.05715)
			(type default)
		)
		(layer "In9.Cu")
	)
	(gr_line
		(start 62.499748 -279.749504)
		(end 62.499748 -280.015188)
		(stroke
			(width 0.05715)
			(type default)
		)
		(layer "In9.Cu")
	)
	(gr_line
		(start 63.783972 -271.554448)
		(end 63.783972 -271.526)
		(stroke
			(width 0.05715)
			(type default)
		)
		(layer "In9.Cu")
	)
	(gr_line
		(start 63.783972 -269.36065)
		(end 63.783972 -268.66215)
		(stroke
			(width 0.08255)
			(type default)
		)
		(layer "In9.Cu")
	)
	(gr_line
		(start 63.829692 -271.600168)
		(end 63.783972 -271.554448)
		(stroke
			(width 0.05715)
			(type default)
		)
		(layer "In9.Cu")
	)
	(gr_line
		(start 64.020192 -271.600168)
		(end 64.065912 -271.554448)
		(stroke
			(width 0.05715)
			(type default)
		)
		(layer "In9.Cu")
	)
	(gr_line
		(start 64.065912 -271.554448)
		(end 64.065912 -271.526)
		(stroke
			(width 0.05715)
			(type default)
		)
		(layer "In9.Cu")
	)
	(gr_line
		(start 64.067182 -269.35938)
		(end 64.167512 -269.25905)
		(stroke
			(width 0.08255)
			(type default)
		)
		(layer "In9.Cu")
	)
	(gr_line
		(start 64.167512 -269.25905)
		(end 64.167512 -268.76375)
		(stroke
			(width 0.08255)
			(type default)
		)
		(layer "In9.Cu")
	)
	(gr_line
		(start 64.167512 -268.76375)
		(end 64.067182 -268.66342)
		(stroke
			(width 0.08255)
			(type default)
		)
		(layer "In9.Cu")
	)
	(gr_line
		(start 64.399922 -280.699718)
		(end 64.399922 -280.434288)
		(stroke
			(width 0.05715)
			(type default)
		)
		(layer "In9.Cu")
	)
	(gr_line
		(start 64.399922 -280.434288)
		(end 64.285622 -280.319988)
		(stroke
			(width 0.05715)
			(type default)
		)
		(layer "In9.Cu")
	)
	(gr_line
		(start 64.399922 -280.015188)
		(end 64.285622 -280.129488)
		(stroke
			(width 0.05715)
			(type default)
		)
		(layer "In9.Cu")
	)
	(gr_line
		(start 64.399922 -279.749504)
		(end 64.399922 -280.015188)
		(stroke
			(width 0.05715)
			(type default)
		)
		(layer "In9.Cu")
	)
	(gr_line
		(start 65.683892 -271.554448)
		(end 65.683892 -271.526)
		(stroke
			(width 0.05715)
			(type default)
		)
		(layer "In9.Cu")
	)
	(gr_line
		(start 65.729612 -271.600168)
		(end 65.683892 -271.554448)
		(stroke
			(width 0.05715)
			(type default)
		)
		(layer "In9.Cu")
	)
	(gr_line
		(start 65.920112 -271.600168)
		(end 65.965832 -271.554448)
		(stroke
			(width 0.05715)
			(type default)
		)
		(layer "In9.Cu")
	)
	(gr_line
		(start 65.965832 -271.554448)
		(end 65.965832 -271.526)
		(stroke
			(width 0.05715)
			(type default)
		)
		(layer "In9.Cu")
	)
	(gr_line
		(start 66.299842 -280.699718)
		(end 66.299842 -280.434288)
		(stroke
			(width 0.05715)
			(type default)
		)
		(layer "In9.Cu")
	)
	(gr_line
		(start 66.299842 -280.434288)
		(end 66.185542 -280.319988)
		(stroke
			(width 0.05715)
			(type default)
		)
		(layer "In9.Cu")
	)
	(gr_line
		(start 66.299842 -280.015188)
		(end 66.185542 -280.129488)
		(stroke
			(width 0.05715)
			(type default)
		)
		(layer "In9.Cu")
	)
	(gr_line
		(start 66.299842 -279.749504)
		(end 66.299842 -280.015188)
		(stroke
			(width 0.05715)
			(type default)
		)
		(layer "In9.Cu")
	)
	(gr_line
		(start 66.870072 -271.546066)
		(end 66.915792 -271.500346)
		(stroke
			(width 0.05715)
			(type default)
		)
		(layer "In9.Cu")
	)
	(gr_line
		(start 66.915792 -271.500346)
		(end 66.915792 -271.471898)
		(stroke
			(width 0.05715)
			(type default)
		)
		(layer "In9.Cu")
	)
	(gr_line
		(start 67.249548 -278.115268)
		(end 67.135248 -278.229568)
		(stroke
			(width 0.05715)
			(type default)
		)
		(layer "In9.Cu")
	)
	(gr_line
		(start 67.249548 -277.849838)
		(end 67.249548 -278.115268)
		(stroke
			(width 0.05715)
			(type default)
		)
		(layer "In9.Cu")
	)
	(gr_line
		(start 67.583812 -271.554448)
		(end 67.583812 -271.526)
		(stroke
			(width 0.05715)
			(type default)
		)
		(layer "In9.Cu")
	)
	(gr_line
		(start 67.629532 -271.600168)
		(end 67.583812 -271.554448)
		(stroke
			(width 0.05715)
			(type default)
		)
		(layer "In9.Cu")
	)
	(gr_line
		(start 67.820032 -271.600168)
		(end 67.865752 -271.554448)
		(stroke
			(width 0.05715)
			(type default)
		)
		(layer "In9.Cu")
	)
	(gr_line
		(start 67.865752 -271.554448)
		(end 67.865752 -271.526)
		(stroke
			(width 0.05715)
			(type default)
		)
		(layer "In9.Cu")
	)
	(gr_line
		(start 68.199762 -280.699718)
		(end 68.199762 -280.434288)
		(stroke
			(width 0.05715)
			(type default)
		)
		(layer "In9.Cu")
	)
	(gr_line
		(start 68.199762 -280.434288)
		(end 68.085462 -280.319988)
		(stroke
			(width 0.05715)
			(type default)
		)
		(layer "In9.Cu")
	)
	(gr_line
		(start 68.199762 -280.015188)
		(end 68.085462 -280.129488)
		(stroke
			(width 0.05715)
			(type default)
		)
		(layer "In9.Cu")
	)
	(gr_line
		(start 68.199762 -279.749504)
		(end 68.199762 -280.015188)
		(stroke
			(width 0.05715)
			(type default)
		)
		(layer "In9.Cu")
	)
	(gr_line
		(start 69.483986 -271.554448)
		(end 69.483986 -271.526)
		(stroke
			(width 0.05715)
			(type default)
		)
		(layer "In9.Cu")
	)
	(gr_line
		(start 69.529706 -271.600168)
		(end 69.483986 -271.554448)
		(stroke
			(width 0.05715)
			(type default)
		)
		(layer "In9.Cu")
	)
	(gr_line
		(start 69.720206 -271.600168)
		(end 69.765926 -271.554448)
		(stroke
			(width 0.05715)
			(type default)
		)
		(layer "In9.Cu")
	)
	(gr_line
		(start 69.765926 -271.554448)
		(end 69.765926 -271.526)
		(stroke
			(width 0.05715)
			(type default)
		)
		(layer "In9.Cu")
	)
	(gr_line
		(start 70.099936 -280.699718)
		(end 70.099936 -280.434288)
		(stroke
			(width 0.05715)
			(type default)
		)
		(layer "In9.Cu")
	)
	(gr_line
		(start 70.099936 -280.434288)
		(end 69.985636 -280.319988)
		(stroke
			(width 0.05715)
			(type default)
		)
		(layer "In9.Cu")
	)
	(gr_line
		(start 70.099936 -280.015188)
		(end 69.985636 -280.129488)
		(stroke
			(width 0.05715)
			(type default)
		)
		(layer "In9.Cu")
	)
	(gr_line
		(start 70.099936 -279.749504)
		(end 70.099936 -280.015188)
		(stroke
			(width 0.05715)
			(type default)
		)
		(layer "In9.Cu")
	)
	(gr_line
		(start 71.383906 -271.554448)
		(end 71.383906 -271.526)
		(stroke
			(width 0.05715)
			(type default)
		)
		(layer "In9.Cu")
	)
	(gr_line
		(start 71.429626 -271.600168)
		(end 71.383906 -271.554448)
		(stroke
			(width 0.05715)
			(type default)
		)
		(layer "In9.Cu")
	)
	(gr_line
		(start 71.620126 -271.600168)
		(end 71.665846 -271.554448)
		(stroke
			(width 0.05715)
			(type default)
		)
		(layer "In9.Cu")
	)
	(gr_line
		(start 71.665846 -271.554448)
		(end 71.665846 -271.526)
		(stroke
			(width 0.05715)
			(type default)
		)
		(layer "In9.Cu")
	)
	(gr_line
		(start 71.90994 -396.872206)
		(end 72.03694 -396.999206)
		(stroke
			(width 0.08255)
			(type default)
		)
		(layer "In9.Cu")
	)
	(gr_line
		(start 71.90994 -396.49019)
		(end 71.90994 -396.872206)
		(stroke
			(width 0.08255)
			(type default)
		)
		(layer "In9.Cu")
	)
	(gr_line
		(start 71.999856 -280.699718)
		(end 71.999856 -280.434288)
		(stroke
			(width 0.05715)
			(type default)
		)
		(layer "In9.Cu")
	)
	(gr_line
		(start 71.999856 -280.434288)
		(end 71.885556 -280.319988)
		(stroke
			(width 0.05715)
			(type default)
		)
		(layer "In9.Cu")
	)
	(gr_line
		(start 71.999856 -280.015188)
		(end 71.885556 -280.129488)
		(stroke
			(width 0.05715)
			(type default)
		)
		(layer "In9.Cu")
	)
	(gr_line
		(start 71.999856 -279.749504)
		(end 71.999856 -280.015188)
		(stroke
			(width 0.05715)
			(type default)
		)
		(layer "In9.Cu")
	)
	(gr_line
		(start 73.283826 -271.554448)
		(end 73.283826 -271.526)
		(stroke
			(width 0.05715)
			(type default)
		)
		(layer "In9.Cu")
	)
	(gr_line
		(start 73.329546 -271.600168)
		(end 73.283826 -271.554448)
		(stroke
			(width 0.05715)
			(type default)
		)
		(layer "In9.Cu")
	)
	(gr_line
		(start 73.520046 -271.600168)
		(end 73.565766 -271.554448)
		(stroke
			(width 0.05715)
			(type default)
		)
		(layer "In9.Cu")
	)
	(gr_line
		(start 73.565766 -271.554448)
		(end 73.565766 -271.526)
		(stroke
			(width 0.05715)
			(type default)
		)
		(layer "In9.Cu")
	)
	(gr_line
		(start 73.870312 -393.41933)
		(end 73.870312 -393.295378)
		(stroke
			(width 0.08255)
			(type default)
		)
		(layer "In9.Cu")
	)
	(gr_line
		(start 73.870312 -393.295378)
		(end 74.220578 -392.945112)
		(stroke
			(width 0.08255)
			(type default)
		)
		(layer "In9.Cu")
	)
	(gr_line
		(start 73.899776 -280.699718)
		(end 73.899776 -280.434288)
		(stroke
			(width 0.05715)
			(type default)
		)
		(layer "In9.Cu")
	)
	(gr_line
		(start 73.899776 -280.434288)
		(end 73.785476 -280.319988)
		(stroke
			(width 0.05715)
			(type default)
		)
		(layer "In9.Cu")
	)
	(gr_line
		(start 73.899776 -280.015188)
		(end 73.785476 -280.129488)
		(stroke
			(width 0.05715)
			(type default)
		)
		(layer "In9.Cu")
	)
	(gr_line
		(start 73.899776 -279.749504)
		(end 73.899776 -280.015188)
		(stroke
			(width 0.05715)
			(type default)
		)
		(layer "In9.Cu")
	)
	(gr_line
		(start 74.220578 -392.945112)
		(end 74.34453 -392.945112)
		(stroke
			(width 0.08255)
			(type default)
		)
		(layer "In9.Cu")
	)
	(gr_line
		(start 74.69632 -392.593322)
		(end 74.69632 -392.46937)
		(stroke
			(width 0.08255)
			(type default)
		)
		(layer "In9.Cu")
	)
	(gr_line
		(start 74.69632 -392.46937)
		(end 75.04684 -392.11885)
		(stroke
			(width 0.08255)
			(type default)
		)
		(layer "In9.Cu")
	)
	(gr_line
		(start 75.04684 -392.11885)
		(end 75.170792 -392.11885)
		(stroke
			(width 0.08255)
			(type default)
		)
		(layer "In9.Cu")
	)
	(gr_line
		(start 80.4799 -199.893174)
		(end 80.480154 -199.893174)
		(stroke
			(width 0.08255)
			(type default)
		)
		(layer "In9.Cu")
	)
	(gr_line
		(start 81.499964 -276.899878)
		(end 81.765394 -276.899878)
		(stroke
			(width 0.05715)
			(type default)
		)
		(layer "In9.Cu")
	)
	(gr_line
		(start 81.765394 -276.899878)
		(end 81.879694 -276.785578)
		(stroke
			(width 0.05715)
			(type default)
		)
		(layer "In9.Cu")
	)
	(gr_line
		(start 81.823052 -143.188436)
		(end 81.532222 -143.479266)
		(stroke
			(width 0.08255)
			(type default)
		)
		(layer "In9.Cu")
	)
	(gr_line
		(start 82.784188 -271.8054)
		(end 82.784188 -271.776952)
		(stroke
			(width 0.05715)
			(type default)
		)
		(layer "In9.Cu")
	)
	(gr_line
		(start 82.829908 -271.85112)
		(end 82.784188 -271.8054)
		(stroke
			(width 0.05715)
			(type default)
		)
		(layer "In9.Cu")
	)
	(gr_line
		(start 84.092288 -143.282162)
		(end 84.045044 -143.167608)
		(stroke
			(width 0.08255)
			(type default)
		)
		(layer "In9.Cu")
	)
	(gr_line
		(start 84.55025 -143.4719)
		(end 84.092288 -143.282162)
		(stroke
			(width 0.08255)
			(type default)
		)
		(layer "In9.Cu")
	)
	(gr_line
		(start 84.664804 -143.424402)
		(end 84.55025 -143.4719)
		(stroke
			(width 0.08255)
			(type default)
		)
		(layer "In9.Cu")
	)
	(gr_line
		(start 86.36635 -144.90192)
		(end 86.36635 -144.777968)
		(stroke
			(width 0.08255)
			(type default)
		)
		(layer "In9.Cu")
	)
	(gr_line
		(start 86.71687 -145.25244)
		(end 86.36635 -144.90192)
		(stroke
			(width 0.08255)
			(type default)
		)
		(layer "In9.Cu")
	)
	(gr_line
		(start 86.840822 -145.25244)
		(end 86.71687 -145.25244)
		(stroke
			(width 0.08255)
			(type default)
		)
		(layer "In9.Cu")
	)
	(gr_line
		(start 87.192612 -145.728182)
		(end 87.192612 -145.60423)
		(stroke
			(width 0.08255)
			(type default)
		)
		(layer "In9.Cu")
	)
	(gr_line
		(start 87.543132 -146.078702)
		(end 87.192612 -145.728182)
		(stroke
			(width 0.08255)
			(type default)
		)
		(layer "In9.Cu")
	)
	(gr_line
		(start 87.667084 -146.078702)
		(end 87.543132 -146.078702)
		(stroke
			(width 0.08255)
			(type default)
		)
		(layer "In9.Cu")
	)
	(gr_line
		(start 88.070182 -146.605752)
		(end 88.070182 -146.4818)
		(stroke
			(width 0.08255)
			(type default)
		)
		(layer "In9.Cu")
	)
	(gr_line
		(start 88.420448 -146.956018)
		(end 88.070182 -146.605752)
		(stroke
			(width 0.08255)
			(type default)
		)
		(layer "In9.Cu")
	)
	(gr_line
		(start 88.5444 -146.956018)
		(end 88.420448 -146.956018)
		(stroke
			(width 0.08255)
			(type default)
		)
		(layer "In9.Cu")
	)
	(gr_line
		(start 89.024206 -147.718272)
		(end 89.048336 -147.596606)
		(stroke
			(width 0.08255)
			(type default)
		)
		(layer "In9.Cu")
	)
	(gr_line
		(start 89.299542 -148.13026)
		(end 89.024206 -147.718272)
		(stroke
			(width 0.08255)
			(type default)
		)
		(layer "In9.Cu")
	)
	(gr_line
		(start 89.421208 -148.154644)
		(end 89.299542 -148.13026)
		(stroke
			(width 0.08255)
			(type default)
		)
		(layer "In9.Cu")
	)
	(gr_line
		(start 89.422986 -148.154898)
		(end 89.422732 -148.154898)
		(stroke
			(width 0.08255)
			(type default)
		)
		(layer "In9.Cu")
	)
	(gr_line
		(start 90.000328 -149.38121)
		(end 90.047826 -149.266656)
		(stroke
			(width 0.08255)
			(type default)
		)
		(layer "In9.Cu")
	)
	(gr_line
		(start 90.19032 -149.839172)
		(end 90.000328 -149.38121)
		(stroke
			(width 0.08255)
			(type default)
		)
		(layer "In9.Cu")
	)
	(gr_line
		(start 90.30462 -149.886416)
		(end 90.19032 -149.839172)
		(stroke
			(width 0.08255)
			(type default)
		)
		(layer "In9.Cu")
	)
	(gr_line
		(start 90.306398 -149.887178)
		(end 90.306144 -149.887178)
		(stroke
			(width 0.08255)
			(type default)
		)
		(layer "In9.Cu")
	)
	(gr_line
		(start 91.1098 -198.76135)
		(end 91.1098 -198.03745)
		(stroke
			(width 0.08255)
			(type default)
		)
		(layer "In9.Cu")
	)
	(gr_line
		(start 91.1098 -197.54215)
		(end 91.1098 -196.81825)
		(stroke
			(width 0.08255)
			(type default)
		)
		(layer "In9.Cu")
	)
	(gr_line
		(start 91.1098 -196.32295)
		(end 91.1098 -195.59905)
		(stroke
			(width 0.08255)
			(type default)
		)
		(layer "In9.Cu")
	)
	(gr_line
		(start 91.1098 -195.10375)
		(end 91.1098 -194.37985)
		(stroke
			(width 0.08255)
			(type default)
		)
		(layer "In9.Cu")
	)
	(gr_line
		(start 91.39301 -198.76008)
		(end 91.50604 -198.64705)
		(stroke
			(width 0.08255)
			(type default)
		)
		(layer "In9.Cu")
	)
	(gr_line
		(start 91.39301 -197.54088)
		(end 91.50604 -197.42785)
		(stroke
			(width 0.08255)
			(type default)
		)
		(layer "In9.Cu")
	)
	(gr_line
		(start 91.39301 -196.32168)
		(end 91.50604 -196.20865)
		(stroke
			(width 0.08255)
			(type default)
		)
		(layer "In9.Cu")
	)
	(gr_line
		(start 91.39301 -195.10248)
		(end 91.50604 -194.98945)
		(stroke
			(width 0.08255)
			(type default)
		)
		(layer "In9.Cu")
	)
	(gr_line
		(start 91.50604 -198.64705)
		(end 91.50604 -198.15175)
		(stroke
			(width 0.08255)
			(type default)
		)
		(layer "In9.Cu")
	)
	(gr_line
		(start 91.50604 -198.15175)
		(end 91.39301 -198.03872)
		(stroke
			(width 0.08255)
			(type default)
		)
		(layer "In9.Cu")
	)
	(gr_line
		(start 91.50604 -197.42785)
		(end 91.50604 -196.93255)
		(stroke
			(width 0.08255)
			(type default)
		)
		(layer "In9.Cu")
	)
	(gr_line
		(start 91.50604 -196.93255)
		(end 91.39301 -196.81952)
		(stroke
			(width 0.08255)
			(type default)
		)
		(layer "In9.Cu")
	)
	(gr_line
		(start 91.50604 -196.20865)
		(end 91.50604 -195.71335)
		(stroke
			(width 0.08255)
			(type default)
		)
		(layer "In9.Cu")
	)
	(gr_line
		(start 91.50604 -195.71335)
		(end 91.39301 -195.60032)
		(stroke
			(width 0.08255)
			(type default)
		)
		(layer "In9.Cu")
	)
	(gr_line
		(start 91.50604 -194.98945)
		(end 91.50604 -194.49415)
		(stroke
			(width 0.08255)
			(type default)
		)
		(layer "In9.Cu")
	)
	(gr_line
		(start 91.50604 -194.49415)
		(end 91.39301 -194.38112)
		(stroke
			(width 0.08255)
			(type default)
		)
		(layer "In9.Cu")
	)
	(gr_line
		(start 98.80981 -201.35215)
		(end 99.10064 -201.64298)
		(stroke
			(width 0.08255)
			(type default)
		)
		(layer "In9.Cu")
	)
	(gr_line
		(start 99.67341 -201.35215)
		(end 99.38258 -201.64298)
		(stroke
			(width 0.08255)
			(type default)
		)
		(layer "In9.Cu")
	)
	(gr_line
		(start 108.570268 -121.401332)
		(end 109.082332 -120.889268)
		(stroke
			(width 0.08255)
			(type default)
		)
		(layer "In9.Cu")
	)
	(gr_line
		(start 108.771436 -121.600722)
		(end 108.931202 -121.600722)
		(stroke
			(width 0.08255)
			(type default)
		)
		(layer "In9.Cu")
	)
	(gr_line
		(start 108.931202 -121.600722)
		(end 109.281722 -121.250202)
		(stroke
			(width 0.08255)
			(type default)
		)
		(layer "In9.Cu")
	)
	(gr_line
		(start 109.281722 -121.250202)
		(end 109.281722 -121.090436)
		(stroke
			(width 0.08255)
			(type default)
		)
		(layer "In9.Cu")
	)
	(gr_line
		(start 109.432344 -120.539256)
		(end 109.944662 -120.026938)
		(stroke
			(width 0.08255)
			(type default)
		)
		(layer "In9.Cu")
	)
	(gr_line
		(start 109.633512 -120.738646)
		(end 109.793532 -120.738646)
		(stroke
			(width 0.08255)
			(type default)
		)
		(layer "In9.Cu")
	)
	(gr_line
		(start 109.793532 -120.738646)
		(end 110.144052 -120.388126)
		(stroke
			(width 0.08255)
			(type default)
		)
		(layer "In9.Cu")
	)
	(gr_line
		(start 110.144052 -120.388126)
		(end 110.144052 -120.228106)
		(stroke
			(width 0.08255)
			(type default)
		)
		(layer "In9.Cu")
	)
	(gr_line
		(start 110.294674 -119.676926)
		(end 110.806992 -119.164608)
		(stroke
			(width 0.08255)
			(type default)
		)
		(layer "In9.Cu")
	)
	(gr_line
		(start 110.495842 -119.876316)
		(end 110.655862 -119.876316)
		(stroke
			(width 0.08255)
			(type default)
		)
		(layer "In9.Cu")
	)
	(gr_line
		(start 110.655862 -119.876316)
		(end 111.006382 -119.525796)
		(stroke
			(width 0.08255)
			(type default)
		)
		(layer "In9.Cu")
	)
	(gr_line
		(start 111.006382 -119.525796)
		(end 111.006382 -119.365776)
		(stroke
			(width 0.08255)
			(type default)
		)
		(layer "In9.Cu")
	)
	(gr_line
		(start 111.157004 -118.814596)
		(end 111.669322 -118.302278)
		(stroke
			(width 0.08255)
			(type default)
		)
		(layer "In9.Cu")
	)
	(gr_line
		(start 111.358172 -119.013986)
		(end 111.518192 -119.013986)
		(stroke
			(width 0.08255)
			(type default)
		)
		(layer "In9.Cu")
	)
	(gr_line
		(start 111.518192 -119.013986)
		(end 111.868712 -118.663466)
		(stroke
			(width 0.08255)
			(type default)
		)
		(layer "In9.Cu")
	)
	(gr_line
		(start 111.868712 -118.663466)
		(end 111.868712 -118.503446)
		(stroke
			(width 0.08255)
			(type default)
		)
		(layer "In9.Cu")
	)
	(gr_line
		(start 137.60704 -311.177432)
		(end 137.890504 -310.538622)
		(stroke
			(width 0.08255)
			(type default)
		)
		(layer "In9.Cu")
	)
	(gr_line
		(start 137.866374 -311.291224)
		(end 137.998962 -311.239916)
		(stroke
			(width 0.08255)
			(type default)
		)
		(layer "In9.Cu")
	)
	(gr_line
		(start 137.998962 -311.239916)
		(end 138.199876 -310.787034)
		(stroke
			(width 0.08255)
			(type default)
		)
		(layer "In9.Cu")
	)
	(gr_line
		(start 138.091164 -310.085994)
		(end 138.374628 -309.447184)
		(stroke
			(width 0.08255)
			(type default)
		)
		(layer "In9.Cu")
	)
	(gr_line
		(start 138.199876 -310.787034)
		(end 138.148822 -310.654446)
		(stroke
			(width 0.08255)
			(type default)
		)
		(layer "In9.Cu")
	)
	(gr_line
		(start 138.350498 -310.199786)
		(end 138.483086 -310.148478)
		(stroke
			(width 0.08255)
			(type default)
		)
		(layer "In9.Cu")
	)
	(gr_line
		(start 138.47445 -86.4362)
		(end 139.19835 -86.4362)
		(stroke
			(width 0.08255)
			(type default)
		)
		(layer "In9.Cu")
	)
	(gr_line
		(start 138.47572 -86.71941)
		(end 138.58875 -86.83244)
		(stroke
			(width 0.08255)
			(type default)
		)
		(layer "In9.Cu")
	)
	(gr_line
		(start 138.483086 -310.148478)
		(end 138.684 -309.695596)
		(stroke
			(width 0.08255)
			(type default)
		)
		(layer "In9.Cu")
	)
	(gr_line
		(start 138.575288 -308.994556)
		(end 138.858752 -308.355746)
		(stroke
			(width 0.08255)
			(type default)
		)
		(layer "In9.Cu")
	)
	(gr_line
		(start 138.58875 -86.83244)
		(end 139.08405 -86.83244)
		(stroke
			(width 0.08255)
			(type default)
		)
		(layer "In9.Cu")
	)
	(gr_line
		(start 138.684 -309.695596)
		(end 138.632946 -309.563008)
		(stroke
			(width 0.08255)
			(type default)
		)
		(layer "In9.Cu")
	)
	(gr_line
		(start 138.834622 -309.108348)
		(end 138.96721 -309.05704)
		(stroke
			(width 0.08255)
			(type default)
		)
		(layer "In9.Cu")
	)
	(gr_line
		(start 138.915902 -198.23557)
		(end 138.625072 -198.5264)
		(stroke
			(width 0.08255)
			(type default)
		)
		(layer "In9.Cu")
	)
	(gr_line
		(start 138.96721 -309.05704)
		(end 139.168124 -308.604158)
		(stroke
			(width 0.08255)
			(type default)
		)
		(layer "In9.Cu")
	)
	(gr_line
		(start 139.059412 -307.903118)
		(end 139.342876 -307.264308)
		(stroke
			(width 0.08255)
			(type default)
		)
		(layer "In9.Cu")
	)
	(gr_line
		(start 139.08405 -86.83244)
		(end 139.19708 -86.71941)
		(stroke
			(width 0.08255)
			(type default)
		)
		(layer "In9.Cu")
	)
	(gr_line
		(start 139.168124 -308.604158)
		(end 139.11707 -308.47157)
		(stroke
			(width 0.08255)
			(type default)
		)
		(layer "In9.Cu")
	)
	(gr_line
		(start 139.197842 -198.23557)
		(end 139.488672 -198.5264)
		(stroke
			(width 0.08255)
			(type default)
		)
		(layer "In9.Cu")
	)
	(gr_line
		(start 139.318746 -308.01691)
		(end 139.451334 -307.965602)
		(stroke
			(width 0.08255)
			(type default)
		)
		(layer "In9.Cu")
	)
	(gr_line
		(start 139.451334 -307.965602)
		(end 139.652248 -307.51272)
		(stroke
			(width 0.08255)
			(type default)
		)
		(layer "In9.Cu")
	)
	(gr_line
		(start 139.652248 -307.51272)
		(end 139.601194 -307.380132)
		(stroke
			(width 0.08255)
			(type default)
		)
		(layer "In9.Cu")
	)
	(gr_line
		(start 139.92225 -86.4362)
		(end 140.64615 -86.4362)
		(stroke
			(width 0.08255)
			(type default)
		)
		(layer "In9.Cu")
	)
	(gr_line
		(start 139.92352 -86.71941)
		(end 140.03655 -86.83244)
		(stroke
			(width 0.08255)
			(type default)
		)
		(layer "In9.Cu")
	)
	(gr_line
		(start 140.03655 -86.83244)
		(end 140.53185 -86.83244)
		(stroke
			(width 0.08255)
			(type default)
		)
		(layer "In9.Cu")
	)
	(gr_line
		(start 140.329158 -305.999388)
		(end 140.823188 -305.505358)
		(stroke
			(width 0.08255)
			(type default)
		)
		(layer "In9.Cu")
	)
	(gr_line
		(start 140.530326 -306.198778)
		(end 140.672058 -306.198778)
		(stroke
			(width 0.08255)
			(type default)
		)
		(layer "In9.Cu")
	)
	(gr_line
		(start 140.53185 -86.83244)
		(end 140.64488 -86.71941)
		(stroke
			(width 0.08255)
			(type default)
		)
		(layer "In9.Cu")
	)
	(gr_line
		(start 140.672058 -306.198778)
		(end 141.022578 -305.848258)
		(stroke
			(width 0.08255)
			(type default)
		)
		(layer "In9.Cu")
	)
	(gr_line
		(start 141.022578 -305.848258)
		(end 141.022578 -305.706526)
		(stroke
			(width 0.08255)
			(type default)
		)
		(layer "In9.Cu")
	)
	(gr_line
		(start 141.14145 -86.4362)
		(end 141.86535 -86.4362)
		(stroke
			(width 0.08255)
			(type default)
		)
		(layer "In9.Cu")
	)
	(gr_line
		(start 141.14272 -86.71941)
		(end 141.25575 -86.83244)
		(stroke
			(width 0.08255)
			(type default)
		)
		(layer "In9.Cu")
	)
	(gr_line
		(start 141.199362 -305.129184)
		(end 141.693646 -304.6349)
		(stroke
			(width 0.08255)
			(type default)
		)
		(layer "In9.Cu")
	)
	(gr_line
		(start 141.25575 -86.83244)
		(end 141.75105 -86.83244)
		(stroke
			(width 0.08255)
			(type default)
		)
		(layer "In9.Cu")
	)
	(gr_line
		(start 141.40053 -305.328574)
		(end 141.542516 -305.328574)
		(stroke
			(width 0.08255)
			(type default)
		)
		(layer "In9.Cu")
	)
	(gr_line
		(start 141.542516 -305.328574)
		(end 141.893036 -304.978054)
		(stroke
			(width 0.08255)
			(type default)
		)
		(layer "In9.Cu")
	)
	(gr_line
		(start 141.75105 -86.83244)
		(end 141.86408 -86.71941)
		(stroke
			(width 0.08255)
			(type default)
		)
		(layer "In9.Cu")
	)
	(gr_line
		(start 141.893036 -304.978054)
		(end 141.893036 -304.836068)
		(stroke
			(width 0.08255)
			(type default)
		)
		(layer "In9.Cu")
	)
	(gr_line
		(start 142.043658 -304.284888)
		(end 142.537688 -303.790858)
		(stroke
			(width 0.08255)
			(type default)
		)
		(layer "In9.Cu")
	)
	(gr_line
		(start 142.127986 -151.935942)
		(end 142.127986 -151.935688)
		(stroke
			(width 0.08255)
			(type default)
		)
		(layer "In9.Cu")
	)
	(gr_line
		(start 142.244826 -304.484278)
		(end 142.386558 -304.484278)
		(stroke
			(width 0.08255)
			(type default)
		)
		(layer "In9.Cu")
	)
	(gr_line
		(start 142.36065 -86.4362)
		(end 143.08455 -86.4362)
		(stroke
			(width 0.08255)
			(type default)
		)
		(layer "In9.Cu")
	)
	(gr_line
		(start 142.36192 -86.71941)
		(end 142.47495 -86.83244)
		(stroke
			(width 0.08255)
			(type default)
		)
		(layer "In9.Cu")
	)
	(gr_line
		(start 142.386558 -304.484278)
		(end 142.737078 -304.133758)
		(stroke
			(width 0.08255)
			(type default)
		)
		(layer "In9.Cu")
	)
	(gr_line
		(start 142.47495 -86.83244)
		(end 142.97025 -86.83244)
		(stroke
			(width 0.08255)
			(type default)
		)
		(layer "In9.Cu")
	)
	(gr_line
		(start 142.737078 -304.133758)
		(end 142.737078 -303.992026)
		(stroke
			(width 0.08255)
			(type default)
		)
		(layer "In9.Cu")
	)
	(gr_line
		(start 142.97025 -86.83244)
		(end 143.08328 -86.71941)
		(stroke
			(width 0.08255)
			(type default)
		)
		(layer "In9.Cu")
	)
	(gr_line
		(start 143.027146 -112.095534)
		(end 143.30426 -111.426498)
		(stroke
			(width 0.08255)
			(type default)
		)
		(layer "In9.Cu")
	)
	(gr_line
		(start 143.289274 -112.202976)
		(end 143.409416 -112.153192)
		(stroke
			(width 0.08255)
			(type default)
		)
		(layer "In9.Cu")
	)
	(gr_line
		(start 143.409416 -112.153192)
		(end 143.615156 -111.65586)
		(stroke
			(width 0.08255)
			(type default)
		)
		(layer "In9.Cu")
	)
	(gr_line
		(start 143.493744 -110.969044)
		(end 143.770858 -110.300008)
		(stroke
			(width 0.08255)
			(type default)
		)
		(layer "In9.Cu")
	)
	(gr_line
		(start 143.615156 -111.65586)
		(end 143.565372 -111.535972)
		(stroke
			(width 0.08255)
			(type default)
		)
		(layer "In9.Cu")
	)
	(gr_line
		(start 143.755872 -111.076486)
		(end 143.88211 -111.024162)
		(stroke
			(width 0.08255)
			(type default)
		)
		(layer "In9.Cu")
	)
	(gr_line
		(start 143.88211 -111.024162)
		(end 144.084294 -110.535466)
		(stroke
			(width 0.08255)
			(type default)
		)
		(layer "In9.Cu")
	)
	(gr_line
		(start 143.960342 -109.842554)
		(end 144.237456 -109.173518)
		(stroke
			(width 0.08255)
			(type default)
		)
		(layer "In9.Cu")
	)
	(gr_line
		(start 144.084294 -110.535466)
		(end 144.03197 -110.409482)
		(stroke
			(width 0.08255)
			(type default)
		)
		(layer "In9.Cu")
	)
	(gr_line
		(start 144.163542 -115.023392)
		(end 144.440656 -114.354102)
		(stroke
			(width 0.08255)
			(type default)
		)
		(layer "In9.Cu")
	)
	(gr_line
		(start 144.22247 -109.949996)
		(end 144.370552 -109.888782)
		(stroke
			(width 0.08255)
			(type default)
		)
		(layer "In9.Cu")
	)
	(gr_line
		(start 144.370552 -109.888782)
		(end 144.560036 -109.43082)
		(stroke
			(width 0.08255)
			(type default)
		)
		(layer "In9.Cu")
	)
	(gr_line
		(start 144.423892 -115.131088)
		(end 144.424146 -115.131342)
		(stroke
			(width 0.08255)
			(type default)
		)
		(layer "In9.Cu")
	)
	(gr_line
		(start 144.42567 -115.130326)
		(end 144.51457 -115.09375)
		(stroke
			(width 0.08255)
			(type default)
		)
		(layer "In9.Cu")
	)
	(gr_line
		(start 144.42694 -108.716064)
		(end 144.704054 -108.047028)
		(stroke
			(width 0.08255)
			(type default)
		)
		(layer "In9.Cu")
	)
	(gr_line
		(start 144.51457 -115.09375)
		(end 144.738598 -114.552476)
		(stroke
			(width 0.08255)
			(type default)
		)
		(layer "In9.Cu")
	)
	(gr_line
		(start 144.560036 -109.43082)
		(end 144.498568 -109.282992)
		(stroke
			(width 0.08255)
			(type default)
		)
		(layer "In9.Cu")
	)
	(gr_line
		(start 144.63014 -113.896648)
		(end 144.907 -113.227612)
		(stroke
			(width 0.08255)
			(type default)
		)
		(layer "In9.Cu")
	)
	(gr_line
		(start 144.689068 -108.823252)
		(end 144.83715 -108.762292)
		(stroke
			(width 0.08255)
			(type default)
		)
		(layer "In9.Cu")
	)
	(gr_line
		(start 144.70126 -114.462052)
		(end 144.701006 -114.462052)
		(stroke
			(width 0.08255)
			(type default)
		)
		(layer "In9.Cu")
	)
	(gr_line
		(start 144.738598 -114.552476)
		(end 144.701768 -114.46383)
		(stroke
			(width 0.08255)
			(type default)
		)
		(layer "In9.Cu")
	)
	(gr_line
		(start 144.83715 -108.762292)
		(end 145.026634 -108.30433)
		(stroke
			(width 0.08255)
			(type default)
		)
		(layer "In9.Cu")
	)
	(gr_line
		(start 144.89049 -114.004598)
		(end 144.890744 -114.004598)
		(stroke
			(width 0.08255)
			(type default)
		)
		(layer "In9.Cu")
	)
	(gr_line
		(start 144.892268 -114.003836)
		(end 145.040096 -113.942876)
		(stroke
			(width 0.08255)
			(type default)
		)
		(layer "In9.Cu")
	)
	(gr_line
		(start 144.907 -113.227612)
		(end 144.914874 -113.209324)
		(stroke
			(width 0.08255)
			(type default)
		)
		(layer "In9.Cu")
	)
	(gr_line
		(start 145.003012 -130.237484)
		(end 145.13433 -130.183382)
		(stroke
			(width 0.08255)
			(type default)
		)
		(layer "In9.Cu")
	)
	(gr_line
		(start 145.026634 -108.30433)
		(end 144.96542 -108.156502)
		(stroke
			(width 0.08255)
			(type default)
		)
		(layer "In9.Cu")
	)
	(gr_line
		(start 145.040096 -113.942876)
		(end 145.22958 -113.484914)
		(stroke
			(width 0.08255)
			(type default)
		)
		(layer "In9.Cu")
	)
	(gr_line
		(start 145.096484 -112.770158)
		(end 145.373598 -112.101122)
		(stroke
			(width 0.08255)
			(type default)
		)
		(layer "In9.Cu")
	)
	(gr_line
		(start 145.13433 -130.183382)
		(end 145.319242 -129.737104)
		(stroke
			(width 0.08255)
			(type default)
		)
		(layer "In9.Cu")
	)
	(gr_line
		(start 145.149316 -118.331234)
		(end 145.42643 -117.662198)
		(stroke
			(width 0.08255)
			(type default)
		)
		(layer "In9.Cu")
	)
	(gr_line
		(start 145.167604 -113.335562)
		(end 145.175224 -113.31702)
		(stroke
			(width 0.08255)
			(type default)
		)
		(layer "In9.Cu")
	)
	(gr_line
		(start 145.22958 -113.484914)
		(end 145.168366 -113.33734)
		(stroke
			(width 0.08255)
			(type default)
		)
		(layer "In9.Cu")
	)
	(gr_line
		(start 145.319242 -129.737104)
		(end 145.264632 -129.60604)
		(stroke
			(width 0.08255)
			(type default)
		)
		(layer "In9.Cu")
	)
	(gr_line
		(start 145.358612 -112.877346)
		(end 145.506694 -112.816386)
		(stroke
			(width 0.08255)
			(type default)
		)
		(layer "In9.Cu")
	)
	(gr_line
		(start 145.411444 -118.438676)
		(end 145.590006 -118.365016)
		(stroke
			(width 0.08255)
			(type default)
		)
		(layer "In9.Cu")
	)
	(gr_line
		(start 145.471388 -129.103374)
		(end 145.471642 -129.103374)
		(stroke
			(width 0.08255)
			(type default)
		)
		(layer "In9.Cu")
	)
	(gr_line
		(start 145.473166 -129.102612)
		(end 145.604484 -129.04851)
		(stroke
			(width 0.08255)
			(type default)
		)
		(layer "In9.Cu")
	)
	(gr_line
		(start 145.506694 -112.816386)
		(end 145.696178 -112.358424)
		(stroke
			(width 0.08255)
			(type default)
		)
		(layer "In9.Cu")
	)
	(gr_line
		(start 145.545048 -130.9751)
		(end 145.822162 -130.306064)
		(stroke
			(width 0.08255)
			(type default)
		)
		(layer "In9.Cu")
	)
	(gr_line
		(start 145.563082 -111.643668)
		(end 145.840196 -110.974632)
		(stroke
			(width 0.08255)
			(type default)
		)
		(layer "In9.Cu")
	)
	(gr_line
		(start 145.590006 -118.365016)
		(end 145.76171 -117.94998)
		(stroke
			(width 0.08255)
			(type default)
		)
		(layer "In9.Cu")
	)
	(gr_line
		(start 145.604484 -129.04851)
		(end 145.789142 -128.602232)
		(stroke
			(width 0.08255)
			(type default)
		)
		(layer "In9.Cu")
	)
	(gr_line
		(start 145.615914 -117.204744)
		(end 145.893028 -116.535708)
		(stroke
			(width 0.08255)
			(type default)
		)
		(layer "In9.Cu")
	)
	(gr_line
		(start 145.696178 -112.358424)
		(end 145.634964 -112.210596)
		(stroke
			(width 0.08255)
			(type default)
		)
		(layer "In9.Cu")
	)
	(gr_line
		(start 145.76171 -117.94998)
		(end 145.687542 -117.771672)
		(stroke
			(width 0.08255)
			(type default)
		)
		(layer "In9.Cu")
	)
	(gr_line
		(start 145.789142 -128.602232)
		(end 145.734786 -128.471168)
		(stroke
			(width 0.08255)
			(type default)
		)
		(layer "In9.Cu")
	)
	(gr_line
		(start 145.807176 -131.082288)
		(end 145.92046 -131.035552)
		(stroke
			(width 0.08255)
			(type default)
		)
		(layer "In9.Cu")
	)
	(gr_line
		(start 145.82521 -111.750856)
		(end 145.973292 -111.689896)
		(stroke
			(width 0.08255)
			(type default)
		)
		(layer "In9.Cu")
	)
	(gr_line
		(start 145.878042 -117.311932)
		(end 146.056604 -117.238526)
		(stroke
			(width 0.08255)
			(type default)
		)
		(layer "In9.Cu")
	)
	(gr_line
		(start 145.918682 -128.02362)
		(end 145.918682 -128.023874)
		(stroke
			(width 0.08255)
			(type default)
		)
		(layer "In9.Cu")
	)
	(gr_line
		(start 145.92046 -131.035552)
		(end 146.130518 -130.528822)
		(stroke
			(width 0.08255)
			(type default)
		)
		(layer "In9.Cu")
	)
	(gr_line
		(start 145.92046 -128.022858)
		(end 146.051778 -127.968756)
		(stroke
			(width 0.08255)
			(type default)
		)
		(layer "In9.Cu")
	)
	(gr_line
		(start 145.92427 -106.109008)
		(end 146.436588 -105.59669)
		(stroke
			(width 0.08255)
			(type default)
		)
		(layer "In9.Cu")
	)
	(gr_line
		(start 145.973292 -111.689896)
		(end 146.162776 -111.231934)
		(stroke
			(width 0.08255)
			(type default)
		)
		(layer "In9.Cu")
	)
	(gr_line
		(start 146.005042 -151.235156)
		(end 146.005042 -151.234902)
		(stroke
			(width 0.08255)
			(type default)
		)
		(layer "In9.Cu")
	)
	(gr_line
		(start 146.011646 -129.84861)
		(end 146.28876 -129.179574)
		(stroke
			(width 0.08255)
			(type default)
		)
		(layer "In9.Cu")
	)
	(gr_line
		(start 146.02968 -110.517178)
		(end 146.306794 -109.847888)
		(stroke
			(width 0.08255)
			(type default)
		)
		(layer "In9.Cu")
	)
	(gr_line
		(start 146.051778 -127.968756)
		(end 146.236436 -127.522478)
		(stroke
			(width 0.08255)
			(type default)
		)
		(layer "In9.Cu")
	)
	(gr_line
		(start 146.056604 -117.238526)
		(end 146.228308 -116.82349)
		(stroke
			(width 0.08255)
			(type default)
		)
		(layer "In9.Cu")
	)
	(gr_line
		(start 146.082512 -116.078254)
		(end 146.35988 -115.409218)
		(stroke
			(width 0.08255)
			(type default)
		)
		(layer "In9.Cu")
	)
	(gr_line
		(start 146.125438 -106.308398)
		(end 146.285458 -106.308398)
		(stroke
			(width 0.08255)
			(type default)
		)
		(layer "In9.Cu")
	)
	(gr_line
		(start 146.130518 -130.528822)
		(end 146.083528 -130.415538)
		(stroke
			(width 0.08255)
			(type default)
		)
		(layer "In9.Cu")
	)
	(gr_line
		(start 146.162776 -111.231934)
		(end 146.101562 -111.084106)
		(stroke
			(width 0.08255)
			(type default)
		)
		(layer "In9.Cu")
	)
	(gr_line
		(start 146.209258 -121.56186)
		(end 146.486372 -120.892824)
		(stroke
			(width 0.08255)
			(type default)
		)
		(layer "In9.Cu")
	)
	(gr_line
		(start 146.228308 -116.82349)
		(end 146.154394 -116.645182)
		(stroke
			(width 0.08255)
			(type default)
		)
		(layer "In9.Cu")
	)
	(gr_line
		(start 146.236436 -127.522478)
		(end 146.18208 -127.391414)
		(stroke
			(width 0.08255)
			(type default)
		)
		(layer "In9.Cu")
	)
	(gr_line
		(start 146.273774 -129.955798)
		(end 146.421856 -129.894838)
		(stroke
			(width 0.08255)
			(type default)
		)
		(layer "In9.Cu")
	)
	(gr_line
		(start 146.285458 -106.308398)
		(end 146.635978 -105.957878)
		(stroke
			(width 0.08255)
			(type default)
		)
		(layer "In9.Cu")
	)
	(gr_line
		(start 146.290284 -110.624874)
		(end 146.290284 -110.625128)
		(stroke
			(width 0.08255)
			(type default)
		)
		(layer "In9.Cu")
	)
	(gr_line
		(start 146.292062 -110.624112)
		(end 146.43989 -110.563152)
		(stroke
			(width 0.08255)
			(type default)
		)
		(layer "In9.Cu")
	)
	(gr_line
		(start 146.34464 -116.185442)
		(end 146.492722 -116.124482)
		(stroke
			(width 0.08255)
			(type default)
		)
		(layer "In9.Cu")
	)
	(gr_line
		(start 146.365976 -126.943866)
		(end 146.365976 -126.94412)
		(stroke
			(width 0.08255)
			(type default)
		)
		(layer "In9.Cu")
	)
	(gr_line
		(start 146.367754 -126.943104)
		(end 146.499072 -126.889002)
		(stroke
			(width 0.08255)
			(type default)
		)
		(layer "In9.Cu")
	)
	(gr_line
		(start 146.421856 -129.894838)
		(end 146.61134 -129.436876)
		(stroke
			(width 0.08255)
			(type default)
		)
		(layer "In9.Cu")
	)
	(gr_line
		(start 146.43989 -110.563152)
		(end 146.629374 -110.10519)
		(stroke
			(width 0.08255)
			(type default)
		)
		(layer "In9.Cu")
	)
	(gr_line
		(start 146.471386 -121.669302)
		(end 146.649948 -121.595642)
		(stroke
			(width 0.08255)
			(type default)
		)
		(layer "In9.Cu")
	)
	(gr_line
		(start 146.478244 -128.72212)
		(end 146.755358 -128.053084)
		(stroke
			(width 0.08255)
			(type default)
		)
		(layer "In9.Cu")
	)
	(gr_line
		(start 146.492722 -116.124482)
		(end 146.682206 -115.66652)
		(stroke
			(width 0.08255)
			(type default)
		)
		(layer "In9.Cu")
	)
	(gr_line
		(start 146.496278 -109.390434)
		(end 146.773646 -108.721144)
		(stroke
			(width 0.08255)
			(type default)
		)
		(layer "In9.Cu")
	)
	(gr_line
		(start 146.499072 -126.889002)
		(end 146.68373 -126.442724)
		(stroke
			(width 0.08255)
			(type default)
		)
		(layer "In9.Cu")
	)
	(gr_line
		(start 146.549364 -114.952018)
		(end 146.826478 -114.282728)
		(stroke
			(width 0.08255)
			(type default)
		)
		(layer "In9.Cu")
	)
	(gr_line
		(start 146.61134 -129.436876)
		(end 146.550126 -129.289048)
		(stroke
			(width 0.08255)
			(type default)
		)
		(layer "In9.Cu")
	)
	(gr_line
		(start 146.620484 -115.517168)
		(end 146.62023 -115.517168)
		(stroke
			(width 0.08255)
			(type default)
		)
		(layer "In9.Cu")
	)
	(gr_line
		(start 146.629374 -110.10519)
		(end 146.56816 -109.957362)
		(stroke
			(width 0.08255)
			(type default)
		)
		(layer "In9.Cu")
	)
	(gr_line
		(start 146.635978 -105.957878)
		(end 146.635978 -105.797858)
		(stroke
			(width 0.08255)
			(type default)
		)
		(layer "In9.Cu")
	)
	(gr_line
		(start 146.649948 -121.595642)
		(end 146.821652 -121.180606)
		(stroke
			(width 0.08255)
			(type default)
		)
		(layer "In9.Cu")
	)
	(gr_line
		(start 146.675856 -120.43537)
		(end 146.95297 -119.766334)
		(stroke
			(width 0.08255)
			(type default)
		)
		(layer "In9.Cu")
	)
	(gr_line
		(start 146.682206 -115.66652)
		(end 146.620992 -115.518946)
		(stroke
			(width 0.08255)
			(type default)
		)
		(layer "In9.Cu")
	)
	(gr_line
		(start 146.68373 -126.442724)
		(end 146.62912 -126.31166)
		(stroke
			(width 0.08255)
			(type default)
		)
		(layer "In9.Cu")
	)
	(gr_line
		(start 146.740372 -128.829308)
		(end 146.888454 -128.768348)
		(stroke
			(width 0.08255)
			(type default)
		)
		(layer "In9.Cu")
	)
	(gr_line
		(start 146.758406 -109.497622)
		(end 146.906488 -109.436662)
		(stroke
			(width 0.08255)
			(type default)
		)
		(layer "In9.Cu")
	)
	(gr_line
		(start 146.7866 -105.246678)
		(end 147.298918 -104.73436)
		(stroke
			(width 0.08255)
			(type default)
		)
		(layer "In9.Cu")
	)
	(gr_line
		(start 146.809714 -115.059714)
		(end 146.809968 -115.059968)
		(stroke
			(width 0.08255)
			(type default)
		)
		(layer "In9.Cu")
	)
	(gr_line
		(start 146.811492 -115.058952)
		(end 146.95932 -114.997992)
		(stroke
			(width 0.08255)
			(type default)
		)
		(layer "In9.Cu")
	)
	(gr_line
		(start 146.813016 -125.864366)
		(end 146.81327 -125.864366)
		(stroke
			(width 0.08255)
			(type default)
		)
		(layer "In9.Cu")
	)
	(gr_line
		(start 146.814794 -125.863604)
		(end 146.946112 -125.809502)
		(stroke
			(width 0.08255)
			(type default)
		)
		(layer "In9.Cu")
	)
	(gr_line
		(start 146.821652 -121.180606)
		(end 146.747484 -121.002298)
		(stroke
			(width 0.08255)
			(type default)
		)
		(layer "In9.Cu")
	)
	(gr_line
		(start 146.888454 -128.768348)
		(end 147.077938 -128.310386)
		(stroke
			(width 0.08255)
			(type default)
		)
		(layer "In9.Cu")
	)
	(gr_line
		(start 146.906488 -109.436662)
		(end 147.095972 -108.9787)
		(stroke
			(width 0.08255)
			(type default)
		)
		(layer "In9.Cu")
	)
	(gr_line
		(start 146.937984 -120.542812)
		(end 147.116546 -120.469152)
		(stroke
			(width 0.08255)
			(type default)
		)
		(layer "In9.Cu")
	)
	(gr_line
		(start 146.944842 -127.59563)
		(end 147.221956 -126.926594)
		(stroke
			(width 0.08255)
			(type default)
		)
		(layer "In9.Cu")
	)
	(gr_line
		(start 146.946112 -125.809502)
		(end 147.13077 -125.363224)
		(stroke
			(width 0.08255)
			(type default)
		)
		(layer "In9.Cu")
	)
	(gr_line
		(start 146.95932 -114.997992)
		(end 147.149058 -114.54003)
		(stroke
			(width 0.08255)
			(type default)
		)
		(layer "In9.Cu")
	)
	(gr_line
		(start 146.987768 -105.446068)
		(end 147.147788 -105.446068)
		(stroke
			(width 0.08255)
			(type default)
		)
		(layer "In9.Cu")
	)
	(gr_line
		(start 147.015962 -113.825274)
		(end 147.293076 -113.156238)
		(stroke
			(width 0.08255)
			(type default)
		)
		(layer "In9.Cu")
	)
	(gr_line
		(start 147.066 -108.752132)
		(end 147.066 -108.752386)
		(stroke
			(width 0.08255)
			(type default)
		)
		(layer "In9.Cu")
	)
	(gr_line
		(start 147.077938 -128.310386)
		(end 147.016724 -128.162558)
		(stroke
			(width 0.08255)
			(type default)
		)
		(layer "In9.Cu")
	)
	(gr_line
		(start 147.095972 -108.9787)
		(end 147.034758 -108.830872)
		(stroke
			(width 0.08255)
			(type default)
		)
		(layer "In9.Cu")
	)
	(gr_line
		(start 147.116546 -120.469152)
		(end 147.28825 -120.054116)
		(stroke
			(width 0.08255)
			(type default)
		)
		(layer "In9.Cu")
	)
	(gr_line
		(start 147.13077 -125.363224)
		(end 147.076414 -125.23216)
		(stroke
			(width 0.08255)
			(type default)
		)
		(layer "In9.Cu")
	)
	(gr_line
		(start 147.142454 -119.30888)
		(end 147.419568 -118.639844)
		(stroke
			(width 0.08255)
			(type default)
		)
		(layer "In9.Cu")
	)
	(gr_line
		(start 147.147788 -105.446068)
		(end 147.498308 -105.095548)
		(stroke
			(width 0.08255)
			(type default)
		)
		(layer "In9.Cu")
	)
	(gr_line
		(start 147.149058 -114.54003)
		(end 147.08759 -114.392202)
		(stroke
			(width 0.08255)
			(type default)
		)
		(layer "In9.Cu")
	)
	(gr_line
		(start 147.20697 -127.702818)
		(end 147.355052 -127.641858)
		(stroke
			(width 0.08255)
			(type default)
		)
		(layer "In9.Cu")
	)
	(gr_line
		(start 147.261834 -124.784104)
		(end 147.393406 -124.730002)
		(stroke
			(width 0.08255)
			(type default)
		)
		(layer "In9.Cu")
	)
	(gr_line
		(start 147.276312 -113.933224)
		(end 147.276566 -113.933224)
		(stroke
			(width 0.08255)
			(type default)
		)
		(layer "In9.Cu")
	)
	(gr_line
		(start 147.27809 -113.932462)
		(end 147.425918 -113.871502)
		(stroke
			(width 0.08255)
			(type default)
		)
		(layer "In9.Cu")
	)
	(gr_line
		(start 147.28825 -120.054116)
		(end 147.214082 -119.875808)
		(stroke
			(width 0.08255)
			(type default)
		)
		(layer "In9.Cu")
	)
	(gr_line
		(start 147.355052 -127.641858)
		(end 147.544536 -127.183896)
		(stroke
			(width 0.08255)
			(type default)
		)
		(layer "In9.Cu")
	)
	(gr_line
		(start 147.393406 -124.730002)
		(end 147.578064 -124.283724)
		(stroke
			(width 0.08255)
			(type default)
		)
		(layer "In9.Cu")
	)
	(gr_line
		(start 147.404582 -119.416322)
		(end 147.552664 -119.355108)
		(stroke
			(width 0.08255)
			(type default)
		)
		(layer "In9.Cu")
	)
	(gr_line
		(start 147.41144 -126.46914)
		(end 147.688554 -125.800104)
		(stroke
			(width 0.08255)
			(type default)
		)
		(layer "In9.Cu")
	)
	(gr_line
		(start 147.425918 -113.871502)
		(end 147.615656 -113.41354)
		(stroke
			(width 0.08255)
			(type default)
		)
		(layer "In9.Cu")
	)
	(gr_line
		(start 147.48256 -112.698784)
		(end 147.759928 -112.029748)
		(stroke
			(width 0.08255)
			(type default)
		)
		(layer "In9.Cu")
	)
	(gr_line
		(start 147.498308 -105.095548)
		(end 147.498308 -104.935528)
		(stroke
			(width 0.08255)
			(type default)
		)
		(layer "In9.Cu")
	)
	(gr_line
		(start 147.544536 -127.183896)
		(end 147.483322 -127.036068)
		(stroke
			(width 0.08255)
			(type default)
		)
		(layer "In9.Cu")
	)
	(gr_line
		(start 147.552664 -119.355108)
		(end 147.742148 -118.897146)
		(stroke
			(width 0.08255)
			(type default)
		)
		(layer "In9.Cu")
	)
	(gr_line
		(start 147.578064 -124.283724)
		(end 147.523454 -124.15266)
		(stroke
			(width 0.08255)
			(type default)
		)
		(layer "In9.Cu")
	)
	(gr_line
		(start 147.609052 -118.18239)
		(end 147.886166 -117.513354)
		(stroke
			(width 0.08255)
			(type default)
		)
		(layer "In9.Cu")
	)
	(gr_line
		(start 147.615656 -113.41354)
		(end 147.554442 -113.265712)
		(stroke
			(width 0.08255)
			(type default)
		)
		(layer "In9.Cu")
	)
	(gr_line
		(start 147.64893 -104.384348)
		(end 148.161248 -103.87203)
		(stroke
			(width 0.08255)
			(type default)
		)
		(layer "In9.Cu")
	)
	(gr_line
		(start 147.673568 -126.576328)
		(end 147.82165 -126.515368)
		(stroke
			(width 0.08255)
			(type default)
		)
		(layer "In9.Cu")
	)
	(gr_line
		(start 147.68703 -107.597448)
		(end 148.199348 -107.08513)
		(stroke
			(width 0.08255)
			(type default)
		)
		(layer "In9.Cu")
	)
	(gr_line
		(start 147.70735 -123.705366)
		(end 147.707604 -123.705366)
		(stroke
			(width 0.08255)
			(type default)
		)
		(layer "In9.Cu")
	)
	(gr_line
		(start 147.709128 -123.704604)
		(end 147.840446 -123.650502)
		(stroke
			(width 0.08255)
			(type default)
		)
		(layer "In9.Cu")
	)
	(gr_line
		(start 147.742148 -118.897146)
		(end 147.68068 -118.749318)
		(stroke
			(width 0.08255)
			(type default)
		)
		(layer "In9.Cu")
	)
	(gr_line
		(start 147.74291 -112.806734)
		(end 147.743164 -112.806734)
		(stroke
			(width 0.08255)
			(type default)
		)
		(layer "In9.Cu")
	)
	(gr_line
		(start 147.744942 -112.805972)
		(end 147.892516 -112.745012)
		(stroke
			(width 0.08255)
			(type default)
		)
		(layer "In9.Cu")
	)
	(gr_line
		(start 147.759928 -112.029748)
		(end 147.77085 -112.002824)
		(stroke
			(width 0.08255)
			(type default)
		)
		(layer "In9.Cu")
	)
	(gr_line
		(start 147.82165 -126.515368)
		(end 148.011134 -126.057406)
		(stroke
			(width 0.08255)
			(type default)
		)
		(layer "In9.Cu")
	)
	(gr_line
		(start 147.840446 -123.650502)
		(end 148.025104 -123.204224)
		(stroke
			(width 0.08255)
			(type default)
		)
		(layer "In9.Cu")
	)
	(gr_line
		(start 147.850098 -104.583738)
		(end 148.010118 -104.583738)
		(stroke
			(width 0.08255)
			(type default)
		)
		(layer "In9.Cu")
	)
	(gr_line
		(start 147.87118 -118.289832)
		(end 148.019262 -118.228618)
		(stroke
			(width 0.08255)
			(type default)
		)
		(layer "In9.Cu")
	)
	(gr_line
		(start 147.878038 -125.34265)
		(end 148.155152 -124.673614)
		(stroke
			(width 0.08255)
			(type default)
		)
		(layer "In9.Cu")
	)
	(gr_line
		(start 147.888198 -107.796838)
		(end 148.048218 -107.796838)
		(stroke
			(width 0.08255)
			(type default)
		)
		(layer "In9.Cu")
	)
	(gr_line
		(start 147.892516 -112.745012)
		(end 148.082254 -112.28705)
		(stroke
			(width 0.08255)
			(type default)
		)
		(layer "In9.Cu")
	)
	(gr_line
		(start 147.949158 -111.572548)
		(end 148.198332 -110.971076)
		(stroke
			(width 0.08255)
			(type default)
		)
		(layer "In9.Cu")
	)
	(gr_line
		(start 148.010118 -104.583738)
		(end 148.360638 -104.233218)
		(stroke
			(width 0.08255)
			(type default)
		)
		(layer "In9.Cu")
	)
	(gr_line
		(start 148.011134 -126.057406)
		(end 147.94992 -125.909578)
		(stroke
			(width 0.08255)
			(type default)
		)
		(layer "In9.Cu")
	)
	(gr_line
		(start 148.019262 -118.228618)
		(end 148.208746 -117.770656)
		(stroke
			(width 0.08255)
			(type default)
		)
		(layer "In9.Cu")
	)
	(gr_line
		(start 148.020278 -112.137698)
		(end 148.031454 -112.110774)
		(stroke
			(width 0.08255)
			(type default)
		)
		(layer "In9.Cu")
	)
	(gr_line
		(start 148.025104 -123.204224)
		(end 147.970748 -123.07316)
		(stroke
			(width 0.08255)
			(type default)
		)
		(layer "In9.Cu")
	)
	(gr_line
		(start 148.048218 -107.796838)
		(end 148.398738 -107.446318)
		(stroke
			(width 0.08255)
			(type default)
		)
		(layer "In9.Cu")
	)
	(gr_line
		(start 148.07565 -117.0559)
		(end 148.352764 -116.386864)
		(stroke
			(width 0.08255)
			(type default)
		)
		(layer "In9.Cu")
	)
	(gr_line
		(start 148.082254 -112.28705)
		(end 148.02104 -112.139476)
		(stroke
			(width 0.08255)
			(type default)
		)
		(layer "In9.Cu")
	)
	(gr_line
		(start 148.140166 -125.449838)
		(end 148.288248 -125.388878)
		(stroke
			(width 0.08255)
			(type default)
		)
		(layer "In9.Cu")
	)
	(gr_line
		(start 148.156168 -122.625104)
		(end 148.287486 -122.571002)
		(stroke
			(width 0.08255)
			(type default)
		)
		(layer "In9.Cu")
	)
	(gr_line
		(start 148.167852 -131.484624)
		(end 148.570188 -130.882644)
		(stroke
			(width 0.08255)
			(type default)
		)
		(layer "In9.Cu")
	)
	(gr_line
		(start 148.208746 -117.770656)
		(end 148.147278 -117.622828)
		(stroke
			(width 0.08255)
			(type default)
		)
		(layer "In9.Cu")
	)
	(gr_line
		(start 148.209762 -111.680498)
		(end 148.209762 -111.67999)
		(stroke
			(width 0.08255)
			(type default)
		)
		(layer "In9.Cu")
	)
	(gr_line
		(start 148.21154 -111.679228)
		(end 148.319236 -111.634524)
		(stroke
			(width 0.08255)
			(type default)
		)
		(layer "In9.Cu")
	)
	(gr_line
		(start 148.287486 -122.571002)
		(end 148.472144 -122.124724)
		(stroke
			(width 0.08255)
			(type default)
		)
		(layer "In9.Cu")
	)
	(gr_line
		(start 148.288248 -125.388878)
		(end 148.477732 -124.930916)
		(stroke
			(width 0.08255)
			(type default)
		)
		(layer "In9.Cu")
	)
	(gr_line
		(start 148.319236 -111.634524)
		(end 148.504148 -111.1885)
		(stroke
			(width 0.08255)
			(type default)
		)
		(layer "In9.Cu")
	)
	(gr_line
		(start 148.337778 -117.163342)
		(end 148.48586 -117.102128)
		(stroke
			(width 0.08255)
			(type default)
		)
		(layer "In9.Cu")
	)
	(gr_line
		(start 148.344636 -124.21616)
		(end 148.62175 -123.547124)
		(stroke
			(width 0.08255)
			(type default)
		)
		(layer "In9.Cu")
	)
	(gr_line
		(start 148.360638 -104.233218)
		(end 148.360638 -104.073198)
		(stroke
			(width 0.08255)
			(type default)
		)
		(layer "In9.Cu")
	)
	(gr_line
		(start 148.398738 -107.446318)
		(end 148.398738 -107.286298)
		(stroke
			(width 0.08255)
			(type default)
		)
		(layer "In9.Cu")
	)
	(gr_line
		(start 148.403818 -131.641088)
		(end 148.56079 -131.609846)
		(stroke
			(width 0.08255)
			(type default)
		)
		(layer "In9.Cu")
	)
	(gr_line
		(start 148.472144 -122.124724)
		(end 148.417788 -121.99366)
		(stroke
			(width 0.08255)
			(type default)
		)
		(layer "In9.Cu")
	)
	(gr_line
		(start 148.477732 -124.930916)
		(end 148.416518 -124.783088)
		(stroke
			(width 0.08255)
			(type default)
		)
		(layer "In9.Cu")
	)
	(gr_line
		(start 148.48586 -117.102128)
		(end 148.675344 -116.644166)
		(stroke
			(width 0.08255)
			(type default)
		)
		(layer "In9.Cu")
	)
	(gr_line
		(start 148.504148 -111.1885)
		(end 148.459698 -111.08055)
		(stroke
			(width 0.08255)
			(type default)
		)
		(layer "In9.Cu")
	)
	(gr_line
		(start 148.51126 -103.522018)
		(end 148.978366 -103.054912)
		(stroke
			(width 0.08255)
			(type default)
		)
		(layer "In9.Cu")
	)
	(gr_line
		(start 148.542248 -115.92941)
		(end 148.819362 -115.260374)
		(stroke
			(width 0.08255)
			(type default)
		)
		(layer "In9.Cu")
	)
	(gr_line
		(start 148.54936 -106.735118)
		(end 149.016466 -106.268012)
		(stroke
			(width 0.08255)
			(type default)
		)
		(layer "In9.Cu")
	)
	(gr_line
		(start 148.56079 -131.609846)
		(end 148.836126 -131.197858)
		(stroke
			(width 0.08255)
			(type default)
		)
		(layer "In9.Cu")
	)
	(gr_line
		(start 148.606764 -124.323348)
		(end 148.754846 -124.262388)
		(stroke
			(width 0.08255)
			(type default)
		)
		(layer "In9.Cu")
	)
	(gr_line
		(start 148.675344 -116.644166)
		(end 148.61413 -116.496338)
		(stroke
			(width 0.08255)
			(type default)
		)
		(layer "In9.Cu")
	)
	(gr_line
		(start 148.712428 -103.721408)
		(end 148.836126 -103.721408)
		(stroke
			(width 0.08255)
			(type default)
		)
		(layer "In9.Cu")
	)
	(gr_line
		(start 148.750528 -106.934508)
		(end 148.874226 -106.934508)
		(stroke
			(width 0.08255)
			(type default)
		)
		(layer "In9.Cu")
	)
	(gr_line
		(start 148.754846 -124.262388)
		(end 148.94433 -123.804426)
		(stroke
			(width 0.08255)
			(type default)
		)
		(layer "In9.Cu")
	)
	(gr_line
		(start 148.804376 -116.036598)
		(end 148.952458 -115.975638)
		(stroke
			(width 0.08255)
			(type default)
		)
		(layer "In9.Cu")
	)
	(gr_line
		(start 148.836126 -131.197858)
		(end 148.804884 -131.040886)
		(stroke
			(width 0.08255)
			(type default)
		)
		(layer "In9.Cu")
	)
	(gr_line
		(start 148.836126 -103.721408)
		(end 149.177756 -103.380032)
		(stroke
			(width 0.08255)
			(type default)
		)
		(layer "In9.Cu")
	)
	(gr_line
		(start 148.84527 -130.47091)
		(end 149.247352 -129.86893)
		(stroke
			(width 0.08255)
			(type default)
		)
		(layer "In9.Cu")
	)
	(gr_line
		(start 148.874226 -106.934508)
		(end 149.215856 -106.593132)
		(stroke
			(width 0.08255)
			(type default)
		)
		(layer "In9.Cu")
	)
	(gr_line
		(start 148.94433 -123.804426)
		(end 148.883116 -123.656598)
		(stroke
			(width 0.08255)
			(type default)
		)
		(layer "In9.Cu")
	)
	(gr_line
		(start 148.952458 -115.975638)
		(end 149.141942 -115.517676)
		(stroke
			(width 0.08255)
			(type default)
		)
		(layer "In9.Cu")
	)
	(gr_line
		(start 149.008846 -114.80292)
		(end 149.242272 -114.239548)
		(stroke
			(width 0.08255)
			(type default)
		)
		(layer "In9.Cu")
	)
	(gr_line
		(start 149.081236 -130.627374)
		(end 149.238208 -130.596132)
		(stroke
			(width 0.08255)
			(type default)
		)
		(layer "In9.Cu")
	)
	(gr_line
		(start 149.141942 -115.517676)
		(end 149.080728 -115.369848)
		(stroke
			(width 0.08255)
			(type default)
		)
		(layer "In9.Cu")
	)
	(gr_line
		(start 149.177756 -103.380032)
		(end 149.177756 -103.25608)
		(stroke
			(width 0.08255)
			(type default)
		)
		(layer "In9.Cu")
	)
	(gr_line
		(start 149.215856 -106.593132)
		(end 149.215856 -106.46918)
		(stroke
			(width 0.08255)
			(type default)
		)
		(layer "In9.Cu")
	)
	(gr_line
		(start 149.22881 -120.868694)
		(end 149.388576 -120.868694)
		(stroke
			(width 0.08255)
			(type default)
		)
		(layer "In9.Cu")
	)
	(gr_line
		(start 149.238208 -130.596132)
		(end 149.513544 -130.184144)
		(stroke
			(width 0.08255)
			(type default)
		)
		(layer "In9.Cu")
	)
	(gr_line
		(start 149.268688 -109.495336)
		(end 149.728682 -109.035342)
		(stroke
			(width 0.08255)
			(type default)
		)
		(layer "In9.Cu")
	)
	(gr_line
		(start 149.270974 -114.910108)
		(end 149.385528 -114.862864)
		(stroke
			(width 0.08255)
			(type default)
		)
		(layer "In9.Cu")
	)
	(gr_line
		(start 149.319488 -102.71379)
		(end 149.786848 -102.24643)
		(stroke
			(width 0.08255)
			(type default)
		)
		(layer "In9.Cu")
	)
	(gr_line
		(start 149.357588 -105.92689)
		(end 149.824948 -105.45953)
		(stroke
			(width 0.08255)
			(type default)
		)
		(layer "In9.Cu")
	)
	(gr_line
		(start 149.385528 -114.862864)
		(end 149.550882 -114.463576)
		(stroke
			(width 0.08255)
			(type default)
		)
		(layer "In9.Cu")
	)
	(gr_line
		(start 149.388576 -120.868694)
		(end 149.729952 -120.527318)
		(stroke
			(width 0.08255)
			(type default)
		)
		(layer "In9.Cu")
	)
	(gr_line
		(start 149.407372 -113.840768)
		(end 149.640798 -113.277142)
		(stroke
			(width 0.08255)
			(type default)
		)
		(layer "In9.Cu")
	)
	(gr_line
		(start 149.469602 -109.694726)
		(end 149.586442 -109.694726)
		(stroke
			(width 0.08255)
			(type default)
		)
		(layer "In9.Cu")
	)
	(gr_line
		(start 149.513544 -130.184144)
		(end 149.482302 -130.027172)
		(stroke
			(width 0.08255)
			(type default)
		)
		(layer "In9.Cu")
	)
	(gr_line
		(start 149.520656 -102.91318)
		(end 149.644608 -102.91318)
		(stroke
			(width 0.08255)
			(type default)
		)
		(layer "In9.Cu")
	)
	(gr_line
		(start 149.522688 -129.457196)
		(end 149.925024 -128.854962)
		(stroke
			(width 0.08255)
			(type default)
		)
		(layer "In9.Cu")
	)
	(gr_line
		(start 149.550882 -114.463576)
		(end 149.503384 -114.349022)
		(stroke
			(width 0.08255)
			(type default)
		)
		(layer "In9.Cu")
	)
	(gr_line
		(start 149.558756 -106.12628)
		(end 149.682708 -106.12628)
		(stroke
			(width 0.08255)
			(type default)
		)
		(layer "In9.Cu")
	)
	(gr_line
		(start 149.586442 -109.694726)
		(end 149.928072 -109.35335)
		(stroke
			(width 0.08255)
			(type default)
		)
		(layer "In9.Cu")
	)
	(gr_line
		(start 149.644608 -102.91318)
		(end 149.986238 -102.57155)
		(stroke
			(width 0.08255)
			(type default)
		)
		(layer "In9.Cu")
	)
	(gr_line
		(start 149.6695 -113.947956)
		(end 149.784054 -113.900458)
		(stroke
			(width 0.08255)
			(type default)
		)
		(layer "In9.Cu")
	)
	(gr_line
		(start 149.682708 -106.12628)
		(end 150.024338 -105.78465)
		(stroke
			(width 0.08255)
			(type default)
		)
		(layer "In9.Cu")
	)
	(gr_line
		(start 149.729952 -120.527318)
		(end 149.729952 -120.367552)
		(stroke
			(width 0.08255)
			(type default)
		)
		(layer "In9.Cu")
	)
	(gr_line
		(start 149.758654 -129.61366)
		(end 149.915626 -129.582164)
		(stroke
			(width 0.08255)
			(type default)
		)
		(layer "In9.Cu")
	)
	(gr_line
		(start 149.784054 -113.900458)
		(end 149.949662 -113.501424)
		(stroke
			(width 0.08255)
			(type default)
		)
		(layer "In9.Cu")
	)
	(gr_line
		(start 149.911054 -312.202576)
		(end 149.933406 -311.875678)
		(stroke
			(width 0.08255)
			(type default)
		)
		(layer "In9.Cu")
	)
	(gr_line
		(start 149.915626 -129.582164)
		(end 150.190962 -129.170176)
		(stroke
			(width 0.08255)
			(type default)
		)
		(layer "In9.Cu")
	)
	(gr_line
		(start 149.928072 -109.35335)
		(end 149.928072 -109.23651)
		(stroke
			(width 0.08255)
			(type default)
		)
		(layer "In9.Cu")
	)
	(gr_line
		(start 149.934676 -311.874408)
		(end 150.042118 -311.781444)
		(stroke
			(width 0.08255)
			(type default)
		)
		(layer "In9.Cu")
	)
	(gr_line
		(start 149.949662 -113.501424)
		(end 149.902164 -113.386616)
		(stroke
			(width 0.08255)
			(type default)
		)
		(layer "In9.Cu")
	)
	(gr_line
		(start 149.964394 -315.080396)
		(end 150.057612 -314.973208)
		(stroke
			(width 0.08255)
			(type default)
		)
		(layer "In9.Cu")
	)
	(gr_line
		(start 149.986238 -102.57155)
		(end 149.986238 -102.447598)
		(stroke
			(width 0.08255)
			(type default)
		)
		(layer "In9.Cu")
	)
	(gr_line
		(start 150.023068 -314.47867)
		(end 149.915626 -314.385706)
		(stroke
			(width 0.08255)
			(type default)
		)
		(layer "In9.Cu")
	)
	(gr_line
		(start 150.024338 -105.78465)
		(end 150.024338 -105.660698)
		(stroke
			(width 0.08255)
			(type default)
		)
		(layer "In9.Cu")
	)
	(gr_line
		(start 150.042118 -311.781444)
		(end 150.076154 -311.286906)
		(stroke
			(width 0.08255)
			(type default)
		)
		(layer "In9.Cu")
	)
	(gr_line
		(start 150.057612 -314.973208)
		(end 150.023068 -314.47867)
		(stroke
			(width 0.08255)
			(type default)
		)
		(layer "In9.Cu")
	)
	(gr_line
		(start 150.076154 -311.286906)
		(end 149.982428 -311.179718)
		(stroke
			(width 0.08255)
			(type default)
		)
		(layer "In9.Cu")
	)
	(gr_line
		(start 150.190962 -129.170176)
		(end 150.15972 -129.013458)
		(stroke
			(width 0.08255)
			(type default)
		)
		(layer "In9.Cu")
	)
	(gr_line
		(start 150.200106 -128.443228)
		(end 150.538942 -127.936244)
		(stroke
			(width 0.08255)
			(type default)
		)
		(layer "In9.Cu")
	)
	(gr_line
		(start 150.291546 -316.496446)
		(end 150.170388 -316.422532)
		(stroke
			(width 0.08255)
			(type default)
		)
		(layer "In9.Cu")
	)
	(gr_line
		(start 150.33371 -317.099188)
		(end 150.407878 -316.97803)
		(stroke
			(width 0.08255)
			(type default)
		)
		(layer "In9.Cu")
	)
	(gr_line
		(start 150.407878 -316.97803)
		(end 150.291546 -316.496446)
		(stroke
			(width 0.08255)
			(type default)
		)
		(layer "In9.Cu")
	)
	(gr_line
		(start 150.436326 -128.599692)
		(end 150.557738 -128.575562)
		(stroke
			(width 0.08255)
			(type default)
		)
		(layer "In9.Cu")
	)
	(gr_line
		(start 150.543768 -139.561062)
		(end 150.266654 -138.892026)
		(stroke
			(width 0.08255)
			(type default)
		)
		(layer "In9.Cu")
	)
	(gr_line
		(start 150.557738 -128.575562)
		(end 150.798022 -128.216152)
		(stroke
			(width 0.08255)
			(type default)
		)
		(layer "In9.Cu")
	)
	(gr_line
		(start 150.676864 -138.846052)
		(end 150.528782 -138.784584)
		(stroke
			(width 0.08255)
			(type default)
		)
		(layer "In9.Cu")
	)
	(gr_line
		(start 150.798022 -128.216152)
		(end 150.773638 -128.094486)
		(stroke
			(width 0.08255)
			(type default)
		)
		(layer "In9.Cu")
	)
	(gr_line
		(start 150.800054 -127.545338)
		(end 150.806658 -127.535432)
		(stroke
			(width 0.08255)
			(type default)
		)
		(layer "In9.Cu")
	)
	(gr_line
		(start 150.80488 -139.451588)
		(end 150.866348 -139.30376)
		(stroke
			(width 0.08255)
			(type default)
		)
		(layer "In9.Cu")
	)
	(gr_line
		(start 150.806658 -127.535432)
		(end 151.145748 -127.028194)
		(stroke
			(width 0.08255)
			(type default)
		)
		(layer "In9.Cu")
	)
	(gr_line
		(start 150.866348 -139.30376)
		(end 150.676864 -138.846052)
		(stroke
			(width 0.08255)
			(type default)
		)
		(layer "In9.Cu")
	)
	(gr_line
		(start 150.934674 -119.797068)
		(end 151.225504 -120.087898)
		(stroke
			(width 0.08255)
			(type default)
		)
		(layer "In9.Cu")
	)
	(gr_line
		(start 150.934674 -112.493552)
		(end 151.225504 -112.784382)
		(stroke
			(width 0.08255)
			(type default)
		)
		(layer "In9.Cu")
	)
	(gr_line
		(start 150.934674 -112.211612)
		(end 151.225504 -111.920782)
		(stroke
			(width 0.08255)
			(type default)
		)
		(layer "In9.Cu")
	)
	(gr_line
		(start 150.934674 -108.89361)
		(end 151.225504 -109.18444)
		(stroke
			(width 0.08255)
			(type default)
		)
		(layer "In9.Cu")
	)
	(gr_line
		(start 150.934674 -108.61167)
		(end 151.225504 -108.32084)
		(stroke
			(width 0.08255)
			(type default)
		)
		(layer "In9.Cu")
	)
	(gr_line
		(start 150.934674 -105.293668)
		(end 151.225504 -105.584498)
		(stroke
			(width 0.08255)
			(type default)
		)
		(layer "In9.Cu")
	)
	(gr_line
		(start 150.934674 -105.011728)
		(end 151.225504 -104.720898)
		(stroke
			(width 0.08255)
			(type default)
		)
		(layer "In9.Cu")
	)
	(gr_line
		(start 151.010366 -140.687552)
		(end 150.733252 -140.018516)
		(stroke
			(width 0.08255)
			(type default)
		)
		(layer "In9.Cu")
	)
	(gr_line
		(start 151.034496 -127.702056)
		(end 151.0411 -127.69215)
		(stroke
			(width 0.08255)
			(type default)
		)
		(layer "In9.Cu")
	)
	(gr_line
		(start 151.042878 -127.691896)
		(end 151.164544 -127.667512)
		(stroke
			(width 0.08255)
			(type default)
		)
		(layer "In9.Cu")
	)
	(gr_line
		(start 151.143462 -139.972288)
		(end 150.99538 -139.911074)
		(stroke
			(width 0.08255)
			(type default)
		)
		(layer "In9.Cu")
	)
	(gr_line
		(start 151.164544 -127.667512)
		(end 151.404574 -127.308356)
		(stroke
			(width 0.08255)
			(type default)
		)
		(layer "In9.Cu")
	)
	(gr_line
		(start 151.225758 -121.321576)
		(end 151.809958 -121.321576)
		(stroke
			(width 0.08255)
			(type default)
		)
		(layer "In9.Cu")
	)
	(gr_line
		(start 151.227028 -121.604786)
		(end 151.314658 -121.692416)
		(stroke
			(width 0.08255)
			(type default)
		)
		(layer "In9.Cu")
	)
	(gr_line
		(start 151.271732 -140.578332)
		(end 151.332946 -140.43025)
		(stroke
			(width 0.08255)
			(type default)
		)
		(layer "In9.Cu")
	)
	(gr_line
		(start 151.314658 -121.692416)
		(end 151.721058 -121.692416)
		(stroke
			(width 0.08255)
			(type default)
		)
		(layer "In9.Cu")
	)
	(gr_line
		(start 151.332946 -140.43025)
		(end 151.143462 -139.972288)
		(stroke
			(width 0.08255)
			(type default)
		)
		(layer "In9.Cu")
	)
	(gr_line
		(start 151.404574 -127.308356)
		(end 151.380444 -127.186436)
		(stroke
			(width 0.08255)
			(type default)
		)
		(layer "In9.Cu")
	)
	(gr_line
		(start 151.529288 -142.97025)
		(end 151.493728 -142.246858)
		(stroke
			(width 0.08255)
			(type default)
		)
		(layer "In9.Cu")
	)
	(gr_line
		(start 151.544274 -101.693472)
		(end 151.835104 -101.984302)
		(stroke
			(width 0.08255)
			(type default)
		)
		(layer "In9.Cu")
	)
	(gr_line
		(start 151.544274 -101.411532)
		(end 151.835104 -101.120702)
		(stroke
			(width 0.08255)
			(type default)
		)
		(layer "In9.Cu")
	)
	(gr_line
		(start 151.589232 -144.18818)
		(end 151.553672 -143.464788)
		(stroke
			(width 0.08255)
			(type default)
		)
		(layer "In9.Cu")
	)
	(gr_line
		(start 151.649176 -145.40611)
		(end 151.613616 -144.682718)
		(stroke
			(width 0.08255)
			(type default)
		)
		(layer "In9.Cu")
	)
	(gr_line
		(start 151.70912 -146.62404)
		(end 151.67356 -145.900648)
		(stroke
			(width 0.08255)
			(type default)
		)
		(layer "In9.Cu")
	)
	(gr_line
		(start 151.721058 -121.692416)
		(end 151.808688 -121.604786)
		(stroke
			(width 0.08255)
			(type default)
		)
		(layer "In9.Cu")
	)
	(gr_line
		(start 151.751284 -308.865778)
		(end 151.779732 -308.865778)
		(stroke
			(width 0.05715)
			(type default)
		)
		(layer "In9.Cu")
	)
	(gr_line
		(start 151.765 -302.215804)
		(end 151.793448 -302.215804)
		(stroke
			(width 0.05715)
			(type default)
		)
		(layer "In9.Cu")
	)
	(gr_line
		(start 151.765 -301.933864)
		(end 151.793448 -301.933864)
		(stroke
			(width 0.05715)
			(type default)
		)
		(layer "In9.Cu")
	)
	(gr_line
		(start 151.769064 -147.842224)
		(end 151.733504 -147.118578)
		(stroke
			(width 0.08255)
			(type default)
		)
		(layer "In9.Cu")
	)
	(gr_line
		(start 151.779732 -308.865778)
		(end 151.825452 -308.820058)
		(stroke
			(width 0.05715)
			(type default)
		)
		(layer "In9.Cu")
	)
	(gr_line
		(start 151.793448 -302.215804)
		(end 151.839168 -302.170084)
		(stroke
			(width 0.05715)
			(type default)
		)
		(layer "In9.Cu")
	)
	(gr_line
		(start 151.793448 -301.933864)
		(end 151.839168 -301.979584)
		(stroke
			(width 0.05715)
			(type default)
		)
		(layer "In9.Cu")
	)
	(gr_line
		(start 151.812244 -142.955518)
		(end 151.91994 -142.836646)
		(stroke
			(width 0.08255)
			(type default)
		)
		(layer "In9.Cu")
	)
	(gr_line
		(start 151.872188 -144.173448)
		(end 151.979884 -144.054576)
		(stroke
			(width 0.08255)
			(type default)
		)
		(layer "In9.Cu")
	)
	(gr_line
		(start 151.895556 -142.3416)
		(end 151.776684 -142.234412)
		(stroke
			(width 0.08255)
			(type default)
		)
		(layer "In9.Cu")
	)
	(gr_line
		(start 151.91994 -142.836646)
		(end 151.895556 -142.3416)
		(stroke
			(width 0.08255)
			(type default)
		)
		(layer "In9.Cu")
	)
	(gr_line
		(start 151.932132 -145.391378)
		(end 152.039828 -145.272506)
		(stroke
			(width 0.08255)
			(type default)
		)
		(layer "In9.Cu")
	)
	(gr_line
		(start 151.949658 -132.531612)
		(end 152.660858 -132.531612)
		(stroke
			(width 0.08255)
			(type default)
		)
		(layer "In9.Cu")
	)
	(gr_line
		(start 151.950928 -132.814822)
		(end 152.063958 -132.927852)
		(stroke
			(width 0.08255)
			(type default)
		)
		(layer "In9.Cu")
	)
	(gr_line
		(start 151.9555 -143.55953)
		(end 151.836628 -143.452342)
		(stroke
			(width 0.08255)
			(type default)
		)
		(layer "In9.Cu")
	)
	(gr_line
		(start 151.979884 -144.054576)
		(end 151.9555 -143.55953)
		(stroke
			(width 0.08255)
			(type default)
		)
		(layer "In9.Cu")
	)
	(gr_line
		(start 151.992076 -146.609308)
		(end 152.099772 -146.490436)
		(stroke
			(width 0.08255)
			(type default)
		)
		(layer "In9.Cu")
	)
	(gr_line
		(start 152.015444 -144.77746)
		(end 151.896572 -144.670272)
		(stroke
			(width 0.08255)
			(type default)
		)
		(layer "In9.Cu")
	)
	(gr_line
		(start 152.039828 -145.272506)
		(end 152.015444 -144.77746)
		(stroke
			(width 0.08255)
			(type default)
		)
		(layer "In9.Cu")
	)
	(gr_line
		(start 152.05202 -147.827238)
		(end 152.159716 -147.708366)
		(stroke
			(width 0.08255)
			(type default)
		)
		(layer "In9.Cu")
	)
	(gr_line
		(start 152.063958 -132.927852)
		(end 152.546558 -132.927852)
		(stroke
			(width 0.08255)
			(type default)
		)
		(layer "In9.Cu")
	)
	(gr_line
		(start 152.075388 -145.99539)
		(end 151.956516 -145.887948)
		(stroke
			(width 0.08255)
			(type default)
		)
		(layer "In9.Cu")
	)
	(gr_line
		(start 152.099772 -146.490436)
		(end 152.075388 -145.99539)
		(stroke
			(width 0.08255)
			(type default)
		)
		(layer "In9.Cu")
	)
	(gr_line
		(start 152.135332 -147.213574)
		(end 152.01646 -147.105878)
		(stroke
			(width 0.08255)
			(type default)
		)
		(layer "In9.Cu")
	)
	(gr_line
		(start 152.159716 -147.708366)
		(end 152.135332 -147.213574)
		(stroke
			(width 0.08255)
			(type default)
		)
		(layer "In9.Cu")
	)
	(gr_line
		(start 152.216358 -121.321576)
		(end 152.800558 -121.321576)
		(stroke
			(width 0.08255)
			(type default)
		)
		(layer "In9.Cu")
	)
	(gr_line
		(start 152.217628 -121.604786)
		(end 152.305258 -121.692416)
		(stroke
			(width 0.08255)
			(type default)
		)
		(layer "In9.Cu")
	)
	(gr_line
		(start 152.305258 -121.692416)
		(end 152.711658 -121.692416)
		(stroke
			(width 0.08255)
			(type default)
		)
		(layer "In9.Cu")
	)
	(gr_line
		(start 152.546558 -132.927852)
		(end 152.659588 -132.814822)
		(stroke
			(width 0.08255)
			(type default)
		)
		(layer "In9.Cu")
	)
	(gr_line
		(start 152.711658 -121.692416)
		(end 152.799288 -121.604786)
		(stroke
			(width 0.08255)
			(type default)
		)
		(layer "In9.Cu")
	)
	(gr_line
		(start 153.2382 -302.549814)
		(end 152.94991 -302.549814)
		(stroke
			(width 0.05715)
			(type default)
		)
		(layer "In9.Cu")
	)
	(gr_line
		(start 153.24074 -316.799722)
		(end 152.94991 -316.799722)
		(stroke
			(width 0.05715)
			(type default)
		)
		(layer "In9.Cu")
	)
	(gr_line
		(start 153.25217 -137.480802)
		(end 153.110438 -137.480802)
		(stroke
			(width 0.08255)
			(type default)
		)
		(layer "In9.Cu")
	)
	(gr_line
		(start 153.28392 -318.950848)
		(end 153.28392 -318.9224)
		(stroke
			(width 0.05715)
			(type default)
		)
		(layer "In9.Cu")
	)
	(gr_line
		(start 153.28392 -318.9224)
		(end 153.32964 -318.87668)
		(stroke
			(width 0.05715)
			(type default)
		)
		(layer "In9.Cu")
	)
	(gr_line
		(start 153.32964 -316.888622)
		(end 153.24074 -316.799722)
		(stroke
			(width 0.05715)
			(type default)
		)
		(layer "In9.Cu")
	)
	(gr_line
		(start 153.332942 -302.455072)
		(end 153.2382 -302.549814)
		(stroke
			(width 0.05715)
			(type default)
		)
		(layer "In9.Cu")
	)
	(gr_line
		(start 153.39441 -138.165332)
		(end 152.90927 -137.680192)
		(stroke
			(width 0.08255)
			(type default)
		)
		(layer "In9.Cu")
	)
	(gr_line
		(start 153.524712 -302.455326)
		(end 153.6192 -302.549814)
		(stroke
			(width 0.05715)
			(type default)
		)
		(layer "In9.Cu")
	)
	(gr_line
		(start 153.524712 -302.453802)
		(end 153.524712 -302.455326)
		(stroke
			(width 0.05715)
			(type default)
		)
		(layer "In9.Cu")
	)
	(gr_line
		(start 153.576782 -132.813552)
		(end 153.867612 -133.104382)
		(stroke
			(width 0.08255)
			(type default)
		)
		(layer "In9.Cu")
	)
	(gr_line
		(start 153.576782 -132.531612)
		(end 153.867612 -132.240782)
		(stroke
			(width 0.08255)
			(type default)
		)
		(layer "In9.Cu")
	)
	(gr_line
		(start 153.576782 -125.203712)
		(end 153.867612 -125.494542)
		(stroke
			(width 0.08255)
			(type default)
		)
		(layer "In9.Cu")
	)
	(gr_line
		(start 153.576782 -124.921772)
		(end 153.867612 -124.630942)
		(stroke
			(width 0.08255)
			(type default)
		)
		(layer "In9.Cu")
	)
	(gr_line
		(start 153.576782 -121.603516)
		(end 153.867612 -121.894346)
		(stroke
			(width 0.08255)
			(type default)
		)
		(layer "In9.Cu")
	)
	(gr_line
		(start 153.576782 -121.321576)
		(end 153.867612 -121.030746)
		(stroke
			(width 0.08255)
			(type default)
		)
		(layer "In9.Cu")
	)
	(gr_line
		(start 153.577036 -136.413748)
		(end 153.577036 -136.413494)
		(stroke
			(width 0.08255)
			(type default)
		)
		(layer "In9.Cu")
	)
	(gr_line
		(start 153.577036 -136.413748)
		(end 153.867612 -136.704324)
		(stroke
			(width 0.08255)
			(type default)
		)
		(layer "In9.Cu")
	)
	(gr_line
		(start 153.577036 -136.1313)
		(end 153.577036 -136.131554)
		(stroke
			(width 0.08255)
			(type default)
		)
		(layer "In9.Cu")
	)
	(gr_line
		(start 153.577036 -136.1313)
		(end 153.867612 -135.840724)
		(stroke
			(width 0.08255)
			(type default)
		)
		(layer "In9.Cu")
	)
	(gr_line
		(start 153.5938 -137.964164)
		(end 153.5938 -137.822178)
		(stroke
			(width 0.08255)
			(type default)
		)
		(layer "In9.Cu")
	)
	(gr_line
		(start 153.5938 -137.822178)
		(end 153.25217 -137.480802)
		(stroke
			(width 0.08255)
			(type default)
		)
		(layer "In9.Cu")
	)
	(gr_line
		(start 153.6192 -302.549814)
		(end 153.89987 -302.549814)
		(stroke
			(width 0.05715)
			(type default)
		)
		(layer "In9.Cu")
	)
	(gr_line
		(start 154.351228 -140.656056)
		(end 154.217624 -139.98321)
		(stroke
			(width 0.08255)
			(type default)
		)
		(layer "In9.Cu")
	)
	(gr_line
		(start 154.588718 -141.852142)
		(end 154.447748 -141.141704)
		(stroke
			(width 0.08255)
			(type default)
		)
		(layer "In9.Cu")
	)
	(gr_line
		(start 154.613864 -140.008102)
		(end 154.495754 -139.929362)
		(stroke
			(width 0.08255)
			(type default)
		)
		(layer "In9.Cu")
	)
	(gr_line
		(start 154.62885 -140.600176)
		(end 154.707844 -140.481812)
		(stroke
			(width 0.08255)
			(type default)
		)
		(layer "In9.Cu")
	)
	(gr_line
		(start 154.707844 -140.481812)
		(end 154.613864 -140.008102)
		(stroke
			(width 0.08255)
			(type default)
		)
		(layer "In9.Cu")
	)
	(gr_line
		(start 154.826462 -143.048228)
		(end 154.685238 -142.33779)
		(stroke
			(width 0.08255)
			(type default)
		)
		(layer "In9.Cu")
	)
	(gr_line
		(start 154.858974 -141.176756)
		(end 154.725624 -141.087856)
		(stroke
			(width 0.08255)
			(type default)
		)
		(layer "In9.Cu")
	)
	(gr_line
		(start 154.86634 -141.796262)
		(end 154.955494 -141.662912)
		(stroke
			(width 0.08255)
			(type default)
		)
		(layer "In9.Cu")
	)
	(gr_line
		(start 154.955494 -141.662912)
		(end 154.858974 -141.176756)
		(stroke
			(width 0.08255)
			(type default)
		)
		(layer "In9.Cu")
	)
	(gr_line
		(start 155.063952 -144.244314)
		(end 154.922728 -143.533876)
		(stroke
			(width 0.08255)
			(type default)
		)
		(layer "In9.Cu")
	)
	(gr_line
		(start 155.096718 -142.372842)
		(end 154.963114 -142.283688)
		(stroke
			(width 0.08255)
			(type default)
		)
		(layer "In9.Cu")
	)
	(gr_line
		(start 155.104084 -142.992602)
		(end 155.193238 -142.858998)
		(stroke
			(width 0.08255)
			(type default)
		)
		(layer "In9.Cu")
	)
	(gr_line
		(start 155.140914 -309.199788)
		(end 154.850084 -309.199788)
		(stroke
			(width 0.05715)
			(type default)
		)
		(layer "In9.Cu")
	)
	(gr_line
		(start 155.184348 -319.941448)
		(end 155.184348 -319.913)
		(stroke
			(width 0.05715)
			(type default)
		)
		(layer "In9.Cu")
	)
	(gr_line
		(start 155.184348 -319.913)
		(end 155.230068 -319.86728)
		(stroke
			(width 0.05715)
			(type default)
		)
		(layer "In9.Cu")
	)
	(gr_line
		(start 155.193238 -142.858998)
		(end 155.096718 -142.372842)
		(stroke
			(width 0.08255)
			(type default)
		)
		(layer "In9.Cu")
	)
	(gr_line
		(start 155.229814 -309.110888)
		(end 155.140914 -309.199788)
		(stroke
			(width 0.05715)
			(type default)
		)
		(layer "In9.Cu")
	)
	(gr_line
		(start 155.301442 -145.4404)
		(end 155.160218 -144.729962)
		(stroke
			(width 0.08255)
			(type default)
		)
		(layer "In9.Cu")
	)
	(gr_line
		(start 155.334462 -143.568928)
		(end 155.200858 -143.47952)
		(stroke
			(width 0.08255)
			(type default)
		)
		(layer "In9.Cu")
	)
	(gr_line
		(start 155.341574 -144.188688)
		(end 155.430982 -144.055084)
		(stroke
			(width 0.08255)
			(type default)
		)
		(layer "In9.Cu")
	)
	(gr_line
		(start 155.430982 -144.055084)
		(end 155.334462 -143.568928)
		(stroke
			(width 0.08255)
			(type default)
		)
		(layer "In9.Cu")
	)
	(gr_line
		(start 155.466288 -319.941448)
		(end 155.466288 -319.913)
		(stroke
			(width 0.05715)
			(type default)
		)
		(layer "In9.Cu")
	)
	(gr_line
		(start 155.466288 -319.913)
		(end 155.420568 -319.86728)
		(stroke
			(width 0.05715)
			(type default)
		)
		(layer "In9.Cu")
	)
	(gr_line
		(start 155.538932 -146.636486)
		(end 155.397962 -145.926048)
		(stroke
			(width 0.08255)
			(type default)
		)
		(layer "In9.Cu")
	)
	(gr_line
		(start 155.571952 -144.765014)
		(end 155.438348 -144.67586)
		(stroke
			(width 0.08255)
			(type default)
		)
		(layer "In9.Cu")
	)
	(gr_line
		(start 155.579064 -145.384774)
		(end 155.668472 -145.25117)
		(stroke
			(width 0.08255)
			(type default)
		)
		(layer "In9.Cu")
	)
	(gr_line
		(start 155.668472 -145.25117)
		(end 155.571952 -144.765014)
		(stroke
			(width 0.08255)
			(type default)
		)
		(layer "In9.Cu")
	)
	(gr_line
		(start 155.711144 -316.419992)
		(end 155.800044 -316.508892)
		(stroke
			(width 0.05715)
			(type default)
		)
		(layer "In9.Cu")
	)
	(gr_line
		(start 155.711144 -316.229492)
		(end 155.800044 -316.140592)
		(stroke
			(width 0.05715)
			(type default)
		)
		(layer "In9.Cu")
	)
	(gr_line
		(start 155.776676 -147.832572)
		(end 155.635452 -147.122134)
		(stroke
			(width 0.08255)
			(type default)
		)
		(layer "In9.Cu")
	)
	(gr_line
		(start 155.800044 -316.508892)
		(end 155.800044 -316.799722)
		(stroke
			(width 0.05715)
			(type default)
		)
		(layer "In9.Cu")
	)
	(gr_line
		(start 155.800044 -316.140592)
		(end 155.800044 -315.849762)
		(stroke
			(width 0.05715)
			(type default)
		)
		(layer "In9.Cu")
	)
	(gr_line
		(start 155.809442 -145.9611)
		(end 155.675838 -145.871946)
		(stroke
			(width 0.08255)
			(type default)
		)
		(layer "In9.Cu")
	)
	(gr_line
		(start 155.816554 -146.580606)
		(end 155.905962 -146.447256)
		(stroke
			(width 0.08255)
			(type default)
		)
		(layer "In9.Cu")
	)
	(gr_line
		(start 155.905962 -146.447256)
		(end 155.809442 -145.9611)
		(stroke
			(width 0.08255)
			(type default)
		)
		(layer "In9.Cu")
	)
	(gr_line
		(start 156.014166 -149.028912)
		(end 155.872942 -148.31822)
		(stroke
			(width 0.08255)
			(type default)
		)
		(layer "In9.Cu")
	)
	(gr_line
		(start 156.046932 -147.157186)
		(end 155.913328 -147.068032)
		(stroke
			(width 0.08255)
			(type default)
		)
		(layer "In9.Cu")
	)
	(gr_line
		(start 156.054298 -147.776946)
		(end 156.143452 -147.643342)
		(stroke
			(width 0.08255)
			(type default)
		)
		(layer "In9.Cu")
	)
	(gr_line
		(start 156.143452 -147.643342)
		(end 156.046932 -147.157186)
		(stroke
			(width 0.08255)
			(type default)
		)
		(layer "In9.Cu")
	)
	(gr_line
		(start 156.232352 -148.31822)
		(end 156.151072 -148.263864)
		(stroke
			(width 0.08255)
			(type default)
		)
		(layer "In9.Cu")
	)
	(gr_line
		(start 156.291788 -148.973032)
		(end 156.346144 -148.891752)
		(stroke
			(width 0.08255)
			(type default)
		)
		(layer "In9.Cu")
	)
	(gr_line
		(start 156.346144 -148.891752)
		(end 156.232352 -148.31822)
		(stroke
			(width 0.08255)
			(type default)
		)
		(layer "In9.Cu")
	)
	(gr_line
		(start 157.084268 -319.890648)
		(end 157.084268 -319.8622)
		(stroke
			(width 0.05715)
			(type default)
		)
		(layer "In9.Cu")
	)
	(gr_line
		(start 157.084268 -319.8622)
		(end 157.129988 -319.81648)
		(stroke
			(width 0.05715)
			(type default)
		)
		(layer "In9.Cu")
	)
	(gr_line
		(start 157.366208 -319.890648)
		(end 157.366208 -319.8622)
		(stroke
			(width 0.05715)
			(type default)
		)
		(layer "In9.Cu")
	)
	(gr_line
		(start 157.366208 -319.8622)
		(end 157.320488 -319.81648)
		(stroke
			(width 0.05715)
			(type default)
		)
		(layer "In9.Cu")
	)
	(gr_line
		(start 157.611318 -316.419992)
		(end 157.700218 -316.508892)
		(stroke
			(width 0.05715)
			(type default)
		)
		(layer "In9.Cu")
	)
	(gr_line
		(start 157.611318 -316.229492)
		(end 157.700218 -316.140592)
		(stroke
			(width 0.05715)
			(type default)
		)
		(layer "In9.Cu")
	)
	(gr_line
		(start 157.699964 -316.799722)
		(end 157.700218 -316.799468)
		(stroke
			(width 0.05715)
			(type default)
		)
		(layer "In9.Cu")
	)
	(gr_line
		(start 157.700218 -316.508892)
		(end 157.700218 -316.799468)
		(stroke
			(width 0.05715)
			(type default)
		)
		(layer "In9.Cu")
	)
	(gr_line
		(start 157.700218 -316.140592)
		(end 157.700218 -315.850016)
		(stroke
			(width 0.05715)
			(type default)
		)
		(layer "In9.Cu")
	)
	(gr_line
		(start 157.700218 -315.850016)
		(end 157.699964 -315.849762)
		(stroke
			(width 0.05715)
			(type default)
		)
		(layer "In9.Cu")
	)
	(gr_line
		(start 158.033974 -319.865248)
		(end 158.033974 -319.8368)
		(stroke
			(width 0.05715)
			(type default)
		)
		(layer "In9.Cu")
	)
	(gr_line
		(start 158.033974 -319.8368)
		(end 158.079694 -319.79108)
		(stroke
			(width 0.05715)
			(type default)
		)
		(layer "In9.Cu")
	)
	(gr_line
		(start 158.315914 -319.865248)
		(end 158.315914 -319.8368)
		(stroke
			(width 0.05715)
			(type default)
		)
		(layer "In9.Cu")
	)
	(gr_line
		(start 158.315914 -319.8368)
		(end 158.270194 -319.79108)
		(stroke
			(width 0.05715)
			(type default)
		)
		(layer "In9.Cu")
	)
	(gr_line
		(start 158.561024 -318.320166)
		(end 158.649924 -318.409066)
		(stroke
			(width 0.05715)
			(type default)
		)
		(layer "In9.Cu")
	)
	(gr_line
		(start 158.561024 -318.129666)
		(end 158.649924 -318.040766)
		(stroke
			(width 0.05715)
			(type default)
		)
		(layer "In9.Cu")
	)
	(gr_line
		(start 158.649924 -318.409066)
		(end 158.649924 -318.699896)
		(stroke
			(width 0.05715)
			(type default)
		)
		(layer "In9.Cu")
	)
	(gr_line
		(start 158.649924 -318.040766)
		(end 158.649924 -317.749936)
		(stroke
			(width 0.05715)
			(type default)
		)
		(layer "In9.Cu")
	)
	(gr_line
		(start 159.910018 -383.490216)
		(end 159.910018 -383.107946)
		(stroke
			(width 0.08255)
			(type default)
		)
		(layer "In9.Cu")
	)
	(gr_line
		(start 159.910018 -383.107946)
		(end 160.037018 -382.980946)
		(stroke
			(width 0.08255)
			(type default)
		)
		(layer "In9.Cu")
	)
	(gr_line
		(start 160.39465 -361.860084)
		(end 160.411922 -361.737402)
		(stroke
			(width 0.08255)
			(type default)
		)
		(layer "In9.Cu")
	)
	(gr_line
		(start 160.6931 -362.255816)
		(end 160.39465 -361.860084)
		(stroke
			(width 0.08255)
			(type default)
		)
		(layer "In9.Cu")
	)
	(gr_line
		(start 160.815782 -362.273088)
		(end 160.6931 -362.255816)
		(stroke
			(width 0.08255)
			(type default)
		)
		(layer "In9.Cu")
	)
	(gr_line
		(start 160.941512 -362.43768)
		(end 160.81756 -362.273342)
		(stroke
			(width 0.08255)
			(type default)
		)
		(layer "In9.Cu")
	)
	(gr_line
		(start 161.092896 -362.82884)
		(end 161.115248 -362.670598)
		(stroke
			(width 0.08255)
			(type default)
		)
		(layer "In9.Cu")
	)
	(gr_line
		(start 161.391346 -363.224826)
		(end 161.092896 -362.82884)
		(stroke
			(width 0.08255)
			(type default)
		)
		(layer "In9.Cu")
	)
	(gr_line
		(start 161.549588 -363.246924)
		(end 161.391346 -363.224826)
		(stroke
			(width 0.08255)
			(type default)
		)
		(layer "In9.Cu")
	)
	(gr_line
		(start 161.826702 -363.802676)
		(end 161.849054 -363.64418)
		(stroke
			(width 0.08255)
			(type default)
		)
		(layer "In9.Cu")
	)
	(gr_line
		(start 162.109658 -394.333222)
		(end 162.109658 -394.191236)
		(stroke
			(width 0.08255)
			(type default)
		)
		(layer "In9.Cu")
	)
	(gr_line
		(start 162.109912 -410.589984)
		(end 162.109912 -410.208222)
		(stroke
			(width 0.08255)
			(type default)
		)
		(layer "In9.Cu")
	)
	(gr_line
		(start 162.109912 -410.208222)
		(end 162.236912 -410.081222)
		(stroke
			(width 0.08255)
			(type default)
		)
		(layer "In9.Cu")
	)
	(gr_line
		(start 162.109912 -409.672282)
		(end 162.236912 -409.799282)
		(stroke
			(width 0.08255)
			(type default)
		)
		(layer "In9.Cu")
	)
	(gr_line
		(start 162.109912 -409.290012)
		(end 162.109912 -409.672282)
		(stroke
			(width 0.08255)
			(type default)
		)
		(layer "In9.Cu")
	)
	(gr_line
		(start 162.125152 -364.198662)
		(end 161.826702 -363.802676)
		(stroke
			(width 0.08255)
			(type default)
		)
		(layer "In9.Cu")
	)
	(gr_line
		(start 162.283648 -364.22076)
		(end 162.125152 -364.198662)
		(stroke
			(width 0.08255)
			(type default)
		)
		(layer "In9.Cu")
	)
	(gr_line
		(start 162.460178 -394.683742)
		(end 162.109658 -394.333222)
		(stroke
			(width 0.08255)
			(type default)
		)
		(layer "In9.Cu")
	)
	(gr_line
		(start 162.560508 -364.776512)
		(end 162.58286 -364.618016)
		(stroke
			(width 0.08255)
			(type default)
		)
		(layer "In9.Cu")
	)
	(gr_line
		(start 162.602164 -394.683742)
		(end 162.460178 -394.683742)
		(stroke
			(width 0.08255)
			(type default)
		)
		(layer "In9.Cu")
	)
	(gr_line
		(start 162.803332 -394.484352)
		(end 162.309048 -393.990068)
		(stroke
			(width 0.08255)
			(type default)
		)
		(layer "In9.Cu")
	)
	(gr_line
		(start 162.858958 -365.172498)
		(end 162.560508 -364.776512)
		(stroke
			(width 0.08255)
			(type default)
		)
		(layer "In9.Cu")
	)
	(gr_line
		(start 163.017454 -365.194596)
		(end 162.858958 -365.172498)
		(stroke
			(width 0.08255)
			(type default)
		)
		(layer "In9.Cu")
	)
	(gr_line
		(start 163.294314 -365.750348)
		(end 163.316666 -365.591852)
		(stroke
			(width 0.08255)
			(type default)
		)
		(layer "In9.Cu")
	)
	(gr_line
		(start 163.592764 -366.146334)
		(end 163.294314 -365.750348)
		(stroke
			(width 0.08255)
			(type default)
		)
		(layer "In9.Cu")
	)
	(gr_line
		(start 163.75126 -366.168432)
		(end 163.592764 -366.146334)
		(stroke
			(width 0.08255)
			(type default)
		)
		(layer "In9.Cu")
	)
	(gr_line
		(start 164.028374 -366.724184)
		(end 164.050472 -366.565434)
		(stroke
			(width 0.08255)
			(type default)
		)
		(layer "In9.Cu")
	)
	(gr_line
		(start 164.31006 -382.572006)
		(end 164.43706 -382.699006)
		(stroke
			(width 0.08255)
			(type default)
		)
		(layer "In9.Cu")
	)
	(gr_line
		(start 164.31006 -382.18999)
		(end 164.31006 -382.572006)
		(stroke
			(width 0.08255)
			(type default)
		)
		(layer "In9.Cu")
	)
	(gr_line
		(start 164.32657 -367.119916)
		(end 164.028374 -366.724184)
		(stroke
			(width 0.08255)
			(type default)
		)
		(layer "In9.Cu")
	)
	(gr_line
		(start 164.48532 -367.142268)
		(end 164.32657 -367.119916)
		(stroke
			(width 0.08255)
			(type default)
		)
		(layer "In9.Cu")
	)
	(gr_line
		(start 166.496238 -363.078522)
		(end 166.532814 -362.95965)
		(stroke
			(width 0.08255)
			(type default)
		)
		(layer "In9.Cu")
	)
	(gr_line
		(start 166.727886 -363.516672)
		(end 166.496238 -363.078522)
		(stroke
			(width 0.08255)
			(type default)
		)
		(layer "In9.Cu")
	)
	(gr_line
		(start 166.846758 -363.553248)
		(end 166.727886 -363.516672)
		(stroke
			(width 0.08255)
			(type default)
		)
		(layer "In9.Cu")
	)
	(gr_line
		(start 167.042338 -364.111794)
		(end 167.078914 -363.992922)
		(stroke
			(width 0.08255)
			(type default)
		)
		(layer "In9.Cu")
	)
	(gr_line
		(start 167.097456 -363.42193)
		(end 166.783004 -362.826554)
		(stroke
			(width 0.08255)
			(type default)
		)
		(layer "In9.Cu")
	)
	(gr_line
		(start 167.273986 -364.549944)
		(end 167.042338 -364.111794)
		(stroke
			(width 0.08255)
			(type default)
		)
		(layer "In9.Cu")
	)
	(gr_line
		(start 167.392604 -364.58652)
		(end 167.273986 -364.549944)
		(stroke
			(width 0.08255)
			(type default)
		)
		(layer "In9.Cu")
	)
	(gr_line
		(start 167.588692 -365.145066)
		(end 167.625014 -365.026194)
		(stroke
			(width 0.08255)
			(type default)
		)
		(layer "In9.Cu")
	)
	(gr_line
		(start 167.643556 -364.455202)
		(end 167.32885 -363.859826)
		(stroke
			(width 0.08255)
			(type default)
		)
		(layer "In9.Cu")
	)
	(gr_line
		(start 167.82034 -365.583216)
		(end 167.588692 -365.145066)
		(stroke
			(width 0.08255)
			(type default)
		)
		(layer "In9.Cu")
	)
	(gr_line
		(start 167.938704 -365.619792)
		(end 167.82034 -365.583216)
		(stroke
			(width 0.08255)
			(type default)
		)
		(layer "In9.Cu")
	)
	(gr_line
		(start 168.189656 -365.488728)
		(end 167.87495 -364.893098)
		(stroke
			(width 0.08255)
			(type default)
		)
		(layer "In9.Cu")
	)
	(gr_line
		(start 168.371266 -366.435386)
		(end 167.940482 -365.6203)
		(stroke
			(width 0.08255)
			(type default)
		)
		(layer "In9.Cu")
	)
	(gr_line
		(start 168.62044 -366.30356)
		(end 168.189656 -365.488728)
		(stroke
			(width 0.08255)
			(type default)
		)
		(layer "In9.Cu")
	)
	(gr_line
		(start 168.710102 -383.490216)
		(end 168.710102 -383.1082)
		(stroke
			(width 0.08255)
			(type default)
		)
		(layer "In9.Cu")
	)
	(gr_line
		(start 168.710102 -383.1082)
		(end 168.837102 -382.9812)
		(stroke
			(width 0.08255)
			(type default)
		)
		(layer "In9.Cu")
	)
	(gr_line
		(start 168.710102 -382.57226)
		(end 168.837102 -382.69926)
		(stroke
			(width 0.08255)
			(type default)
		)
		(layer "In9.Cu")
	)
	(gr_line
		(start 168.710102 -382.18999)
		(end 168.710102 -382.57226)
		(stroke
			(width 0.08255)
			(type default)
		)
		(layer "In9.Cu")
	)
	(gr_line
		(start 171.864274 -362.71327)
		(end 171.917106 -362.601002)
		(stroke
			(width 0.08255)
			(type default)
		)
		(layer "In9.Cu")
	)
	(gr_line
		(start 172.032422 -363.17936)
		(end 171.864274 -362.71327)
		(stroke
			(width 0.08255)
			(type default)
		)
		(layer "In9.Cu")
	)
	(gr_line
		(start 172.14469 -363.232192)
		(end 172.032422 -363.17936)
		(stroke
			(width 0.08255)
			(type default)
		)
		(layer "In9.Cu")
	)
	(gr_line
		(start 172.260514 -363.812582)
		(end 172.313346 -363.700314)
		(stroke
			(width 0.08255)
			(type default)
		)
		(layer "In9.Cu")
	)
	(gr_line
		(start 172.411644 -363.13745)
		(end 172.183298 -362.50372)
		(stroke
			(width 0.08255)
			(type default)
		)
		(layer "In9.Cu")
	)
	(gr_line
		(start 172.428662 -364.278672)
		(end 172.260514 -363.812582)
		(stroke
			(width 0.08255)
			(type default)
		)
		(layer "In9.Cu")
	)
	(gr_line
		(start 172.54093 -364.331504)
		(end 172.428662 -364.278672)
		(stroke
			(width 0.08255)
			(type default)
		)
		(layer "In9.Cu")
	)
	(gr_line
		(start 172.656754 -364.911894)
		(end 172.709586 -364.799626)
		(stroke
			(width 0.08255)
			(type default)
		)
		(layer "In9.Cu")
	)
	(gr_line
		(start 172.807884 -364.236508)
		(end 172.579538 -363.603032)
		(stroke
			(width 0.08255)
			(type default)
		)
		(layer "In9.Cu")
	)
	(gr_line
		(start 172.825156 -365.377984)
		(end 172.656754 -364.911894)
		(stroke
			(width 0.08255)
			(type default)
		)
		(layer "In9.Cu")
	)
	(gr_line
		(start 172.93717 -365.430816)
		(end 172.825156 -365.377984)
		(stroke
			(width 0.08255)
			(type default)
		)
		(layer "In9.Cu")
	)
	(gr_line
		(start 173.10989 -383.490216)
		(end 173.10989 -383.1082)
		(stroke
			(width 0.08255)
			(type default)
		)
		(layer "In9.Cu")
	)
	(gr_line
		(start 173.10989 -383.1082)
		(end 173.23689 -382.9812)
		(stroke
			(width 0.08255)
			(type default)
		)
		(layer "In9.Cu")
	)
	(gr_line
		(start 173.10989 -382.57226)
		(end 173.23689 -382.69926)
		(stroke
			(width 0.08255)
			(type default)
		)
		(layer "In9.Cu")
	)
	(gr_line
		(start 173.10989 -382.18999)
		(end 173.10989 -382.57226)
		(stroke
			(width 0.08255)
			(type default)
		)
		(layer "In9.Cu")
	)
	(gr_line
		(start 173.204124 -365.336074)
		(end 172.975778 -364.702344)
		(stroke
			(width 0.08255)
			(type default)
		)
		(layer "In9.Cu")
	)
	(gr_line
		(start 173.345602 -366.559846)
		(end 172.938948 -365.431578)
		(stroke
			(width 0.08255)
			(type default)
		)
		(layer "In9.Cu")
	)
	(gr_line
		(start 173.610778 -366.464088)
		(end 173.204124 -365.336074)
		(stroke
			(width 0.08255)
			(type default)
		)
		(layer "In9.Cu")
	)
	(gr_line
		(start 175.07966 -364.903766)
		(end 175.158654 -364.764574)
		(stroke
			(width 0.08255)
			(type default)
		)
		(layer "In9.Cu")
	)
	(gr_line
		(start 175.211232 -365.38154)
		(end 175.07966 -364.903766)
		(stroke
			(width 0.08255)
			(type default)
		)
		(layer "In9.Cu")
	)
	(gr_line
		(start 175.310038 -384.590036)
		(end 175.310038 -384.20802)
		(stroke
			(width 0.08255)
			(type default)
		)
		(layer "In9.Cu")
	)
	(gr_line
		(start 175.310038 -384.20802)
		(end 175.437038 -384.08102)
		(stroke
			(width 0.08255)
			(type default)
		)
		(layer "In9.Cu")
	)
	(gr_line
		(start 175.310038 -383.67208)
		(end 175.437038 -383.79908)
		(stroke
			(width 0.08255)
			(type default)
		)
		(layer "In9.Cu")
	)
	(gr_line
		(start 175.310038 -383.290064)
		(end 175.310038 -383.67208)
		(stroke
			(width 0.08255)
			(type default)
		)
		(layer "In9.Cu")
	)
	(gr_line
		(start 175.350424 -365.46028)
		(end 175.211232 -365.38154)
		(stroke
			(width 0.08255)
			(type default)
		)
		(layer "In9.Cu")
	)
	(gr_line
		(start 175.623728 -365.386366)
		(end 175.431196 -364.68812)
		(stroke
			(width 0.08255)
			(type default)
		)
		(layer "In9.Cu")
	)
	(gr_line
		(start 175.810418 -367.125504)
		(end 175.351948 -365.461296)
		(stroke
			(width 0.08255)
			(type default)
		)
		(layer "In9.Cu")
	)
	(gr_line
		(start 176.082198 -367.050574)
		(end 175.623728 -365.386366)
		(stroke
			(width 0.08255)
			(type default)
		)
		(layer "In9.Cu")
	)
	(gr_line
		(start 176.083976 -271.554448)
		(end 176.083976 -271.526)
		(stroke
			(width 0.05715)
			(type default)
		)
		(layer "In9.Cu")
	)
	(gr_line
		(start 176.129696 -271.600168)
		(end 176.083976 -271.554448)
		(stroke
			(width 0.05715)
			(type default)
		)
		(layer "In9.Cu")
	)
	(gr_line
		(start 176.320196 -271.600168)
		(end 176.365916 -271.554448)
		(stroke
			(width 0.05715)
			(type default)
		)
		(layer "In9.Cu")
	)
	(gr_line
		(start 176.365916 -271.554448)
		(end 176.365916 -271.526)
		(stroke
			(width 0.05715)
			(type default)
		)
		(layer "In9.Cu")
	)
	(gr_line
		(start 176.699926 -280.699718)
		(end 176.699926 -280.434288)
		(stroke
			(width 0.05715)
			(type default)
		)
		(layer "In9.Cu")
	)
	(gr_line
		(start 176.699926 -280.434288)
		(end 176.585626 -280.319988)
		(stroke
			(width 0.05715)
			(type default)
		)
		(layer "In9.Cu")
	)
	(gr_line
		(start 176.699926 -280.015188)
		(end 176.585626 -280.129488)
		(stroke
			(width 0.05715)
			(type default)
		)
		(layer "In9.Cu")
	)
	(gr_line
		(start 176.699926 -279.749504)
		(end 176.699926 -280.015188)
		(stroke
			(width 0.05715)
			(type default)
		)
		(layer "In9.Cu")
	)
	(gr_line
		(start 177.983896 -271.554448)
		(end 177.983896 -271.526)
		(stroke
			(width 0.05715)
			(type default)
		)
		(layer "In9.Cu")
	)
	(gr_line
		(start 178.029616 -271.600168)
		(end 177.983896 -271.554448)
		(stroke
			(width 0.05715)
			(type default)
		)
		(layer "In9.Cu")
	)
	(gr_line
		(start 178.220116 -271.600168)
		(end 178.265836 -271.554448)
		(stroke
			(width 0.05715)
			(type default)
		)
		(layer "In9.Cu")
	)
	(gr_line
		(start 178.265836 -271.554448)
		(end 178.265836 -271.526)
		(stroke
			(width 0.05715)
			(type default)
		)
		(layer "In9.Cu")
	)
	(gr_line
		(start 178.599846 -280.699718)
		(end 178.599846 -280.434288)
		(stroke
			(width 0.05715)
			(type default)
		)
		(layer "In9.Cu")
	)
	(gr_line
		(start 178.599846 -280.434288)
		(end 178.485546 -280.319988)
		(stroke
			(width 0.05715)
			(type default)
		)
		(layer "In9.Cu")
	)
	(gr_line
		(start 178.599846 -280.015188)
		(end 178.485546 -280.129488)
		(stroke
			(width 0.05715)
			(type default)
		)
		(layer "In9.Cu")
	)
	(gr_line
		(start 178.599846 -279.749504)
		(end 178.599846 -280.015188)
		(stroke
			(width 0.05715)
			(type default)
		)
		(layer "In9.Cu")
	)
	(gr_line
		(start 179.88407 -271.554448)
		(end 179.88407 -271.526)
		(stroke
			(width 0.05715)
			(type default)
		)
		(layer "In9.Cu")
	)
	(gr_line
		(start 179.92979 -271.600168)
		(end 179.88407 -271.554448)
		(stroke
			(width 0.05715)
			(type default)
		)
		(layer "In9.Cu")
	)
	(gr_line
		(start 180.12029 -271.600168)
		(end 180.16601 -271.554448)
		(stroke
			(width 0.05715)
			(type default)
		)
		(layer "In9.Cu")
	)
	(gr_line
		(start 180.16601 -271.554448)
		(end 180.16601 -271.526)
		(stroke
			(width 0.05715)
			(type default)
		)
		(layer "In9.Cu")
	)
	(gr_line
		(start 180.50002 -280.699718)
		(end 180.50002 -280.434288)
		(stroke
			(width 0.05715)
			(type default)
		)
		(layer "In9.Cu")
	)
	(gr_line
		(start 180.50002 -280.434288)
		(end 180.38572 -280.319988)
		(stroke
			(width 0.05715)
			(type default)
		)
		(layer "In9.Cu")
	)
	(gr_line
		(start 180.50002 -280.015188)
		(end 180.38572 -280.129488)
		(stroke
			(width 0.05715)
			(type default)
		)
		(layer "In9.Cu")
	)
	(gr_line
		(start 180.50002 -279.749504)
		(end 180.50002 -280.015188)
		(stroke
			(width 0.05715)
			(type default)
		)
		(layer "In9.Cu")
	)
	(gr_line
		(start 181.78399 -271.554448)
		(end 181.78399 -271.526)
		(stroke
			(width 0.05715)
			(type default)
		)
		(layer "In9.Cu")
	)
	(gr_line
		(start 181.82971 -271.600168)
		(end 181.78399 -271.554448)
		(stroke
			(width 0.05715)
			(type default)
		)
		(layer "In9.Cu")
	)
	(gr_line
		(start 182.02021 -271.600168)
		(end 182.06593 -271.554448)
		(stroke
			(width 0.05715)
			(type default)
		)
		(layer "In9.Cu")
	)
	(gr_line
		(start 182.06593 -271.554448)
		(end 182.06593 -271.526)
		(stroke
			(width 0.05715)
			(type default)
		)
		(layer "In9.Cu")
	)
	(gr_line
		(start 182.39994 -280.699718)
		(end 182.39994 -280.434288)
		(stroke
			(width 0.05715)
			(type default)
		)
		(layer "In9.Cu")
	)
	(gr_line
		(start 182.39994 -280.434288)
		(end 182.28564 -280.319988)
		(stroke
			(width 0.05715)
			(type default)
		)
		(layer "In9.Cu")
	)
	(gr_line
		(start 182.39994 -280.015188)
		(end 182.28564 -280.129488)
		(stroke
			(width 0.05715)
			(type default)
		)
		(layer "In9.Cu")
	)
	(gr_line
		(start 182.39994 -279.749504)
		(end 182.39994 -280.015188)
		(stroke
			(width 0.05715)
			(type default)
		)
		(layer "In9.Cu")
	)
	(gr_line
		(start 182.97017 -271.546066)
		(end 183.01589 -271.500346)
		(stroke
			(width 0.05715)
			(type default)
		)
		(layer "In9.Cu")
	)
	(gr_line
		(start 183.01589 -271.500346)
		(end 183.01589 -271.471898)
		(stroke
			(width 0.05715)
			(type default)
		)
		(layer "In9.Cu")
	)
	(gr_line
		(start 183.349646 -278.115268)
		(end 183.235346 -278.229568)
		(stroke
			(width 0.05715)
			(type default)
		)
		(layer "In9.Cu")
	)
	(gr_line
		(start 183.349646 -277.849838)
		(end 183.349646 -278.115268)
		(stroke
			(width 0.05715)
			(type default)
		)
		(layer "In9.Cu")
	)
	(gr_line
		(start 183.68391 -271.554448)
		(end 183.68391 -271.526)
		(stroke
			(width 0.05715)
			(type default)
		)
		(layer "In9.Cu")
	)
	(gr_line
		(start 183.72963 -271.600168)
		(end 183.68391 -271.554448)
		(stroke
			(width 0.05715)
			(type default)
		)
		(layer "In9.Cu")
	)
	(gr_line
		(start 183.92013 -271.600168)
		(end 183.96585 -271.554448)
		(stroke
			(width 0.05715)
			(type default)
		)
		(layer "In9.Cu")
	)
	(gr_line
		(start 183.96585 -271.554448)
		(end 183.96585 -271.526)
		(stroke
			(width 0.05715)
			(type default)
		)
		(layer "In9.Cu")
	)
	(gr_line
		(start 184.29986 -280.699718)
		(end 184.29986 -280.434288)
		(stroke
			(width 0.05715)
			(type default)
		)
		(layer "In9.Cu")
	)
	(gr_line
		(start 184.29986 -280.434288)
		(end 184.18556 -280.319988)
		(stroke
			(width 0.05715)
			(type default)
		)
		(layer "In9.Cu")
	)
	(gr_line
		(start 184.29986 -280.015188)
		(end 184.18556 -280.129488)
		(stroke
			(width 0.05715)
			(type default)
		)
		(layer "In9.Cu")
	)
	(gr_line
		(start 184.29986 -279.749504)
		(end 184.29986 -280.015188)
		(stroke
			(width 0.05715)
			(type default)
		)
		(layer "In9.Cu")
	)
	(gr_line
		(start 185.584084 -271.554448)
		(end 185.584084 -271.526)
		(stroke
			(width 0.05715)
			(type default)
		)
		(layer "In9.Cu")
	)
	(gr_line
		(start 185.584084 -269.77975)
		(end 185.584084 -269.05585)
		(stroke
			(width 0.08255)
			(type default)
		)
		(layer "In9.Cu")
	)
	(gr_line
		(start 185.584084 -268.56055)
		(end 185.584084 -267.83665)
		(stroke
			(width 0.08255)
			(type default)
		)
		(layer "In9.Cu")
	)
	(gr_line
		(start 185.584084 -267.34135)
		(end 185.584084 -266.61745)
		(stroke
			(width 0.08255)
			(type default)
		)
		(layer "In9.Cu")
	)
	(gr_line
		(start 185.629804 -271.600168)
		(end 185.584084 -271.554448)
		(stroke
			(width 0.05715)
			(type default)
		)
		(layer "In9.Cu")
	)
	(gr_line
		(start 185.820304 -271.600168)
		(end 185.866024 -271.554448)
		(stroke
			(width 0.05715)
			(type default)
		)
		(layer "In9.Cu")
	)
	(gr_line
		(start 185.866024 -271.554448)
		(end 185.866024 -271.526)
		(stroke
			(width 0.05715)
			(type default)
		)
		(layer "In9.Cu")
	)
	(gr_line
		(start 185.867294 -269.77848)
		(end 186.005724 -269.64005)
		(stroke
			(width 0.08255)
			(type default)
		)
		(layer "In9.Cu")
	)
	(gr_line
		(start 185.867294 -268.55928)
		(end 186.005724 -268.42085)
		(stroke
			(width 0.08255)
			(type default)
		)
		(layer "In9.Cu")
	)
	(gr_line
		(start 185.867294 -267.34008)
		(end 186.005724 -267.20165)
		(stroke
			(width 0.08255)
			(type default)
		)
		(layer "In9.Cu")
	)
	(gr_line
		(start 186.005724 -269.64005)
		(end 186.005724 -269.19555)
		(stroke
			(width 0.08255)
			(type default)
		)
		(layer "In9.Cu")
	)
	(gr_line
		(start 186.005724 -269.19555)
		(end 185.867294 -269.05712)
		(stroke
			(width 0.08255)
			(type default)
		)
		(layer "In9.Cu")
	)
	(gr_line
		(start 186.005724 -268.42085)
		(end 186.005724 -267.97635)
		(stroke
			(width 0.08255)
			(type default)
		)
		(layer "In9.Cu")
	)
	(gr_line
		(start 186.005724 -267.97635)
		(end 185.867294 -267.83792)
		(stroke
			(width 0.08255)
			(type default)
		)
		(layer "In9.Cu")
	)
	(gr_line
		(start 186.005724 -267.20165)
		(end 186.005724 -266.75715)
		(stroke
			(width 0.08255)
			(type default)
		)
		(layer "In9.Cu")
	)
	(gr_line
		(start 186.005724 -266.75715)
		(end 185.867294 -266.61872)
		(stroke
			(width 0.08255)
			(type default)
		)
		(layer "In9.Cu")
	)
	(gr_line
		(start 186.200034 -280.699718)
		(end 186.200034 -280.434288)
		(stroke
			(width 0.05715)
			(type default)
		)
		(layer "In9.Cu")
	)
	(gr_line
		(start 186.200034 -280.434288)
		(end 186.085734 -280.319988)
		(stroke
			(width 0.05715)
			(type default)
		)
		(layer "In9.Cu")
	)
	(gr_line
		(start 186.200034 -280.015188)
		(end 186.085734 -280.129488)
		(stroke
			(width 0.05715)
			(type default)
		)
		(layer "In9.Cu")
	)
	(gr_line
		(start 186.200034 -279.749504)
		(end 186.200034 -280.015188)
		(stroke
			(width 0.05715)
			(type default)
		)
		(layer "In9.Cu")
	)
	(gr_line
		(start 187.484004 -271.554448)
		(end 187.484004 -271.526)
		(stroke
			(width 0.05715)
			(type default)
		)
		(layer "In9.Cu")
	)
	(gr_line
		(start 187.529724 -271.600168)
		(end 187.484004 -271.554448)
		(stroke
			(width 0.05715)
			(type default)
		)
		(layer "In9.Cu")
	)
	(gr_line
		(start 187.720224 -271.600168)
		(end 187.765944 -271.554448)
		(stroke
			(width 0.05715)
			(type default)
		)
		(layer "In9.Cu")
	)
	(gr_line
		(start 187.765944 -271.554448)
		(end 187.765944 -271.526)
		(stroke
			(width 0.05715)
			(type default)
		)
		(layer "In9.Cu")
	)
	(gr_line
		(start 188.099954 -280.699718)
		(end 188.099954 -280.434288)
		(stroke
			(width 0.05715)
			(type default)
		)
		(layer "In9.Cu")
	)
	(gr_line
		(start 188.099954 -280.434288)
		(end 187.985654 -280.319988)
		(stroke
			(width 0.05715)
			(type default)
		)
		(layer "In9.Cu")
	)
	(gr_line
		(start 188.099954 -280.015188)
		(end 187.985654 -280.129488)
		(stroke
			(width 0.05715)
			(type default)
		)
		(layer "In9.Cu")
	)
	(gr_line
		(start 188.099954 -279.749504)
		(end 188.099954 -280.015188)
		(stroke
			(width 0.05715)
			(type default)
		)
		(layer "In9.Cu")
	)
	(gr_line
		(start 189.383924 -271.554448)
		(end 189.383924 -271.526)
		(stroke
			(width 0.05715)
			(type default)
		)
		(layer "In9.Cu")
	)
	(gr_line
		(start 189.429644 -271.600168)
		(end 189.383924 -271.554448)
		(stroke
			(width 0.05715)
			(type default)
		)
		(layer "In9.Cu")
	)
	(gr_line
		(start 189.620144 -271.600168)
		(end 189.665864 -271.554448)
		(stroke
			(width 0.05715)
			(type default)
		)
		(layer "In9.Cu")
	)
	(gr_line
		(start 189.665864 -271.554448)
		(end 189.665864 -271.526)
		(stroke
			(width 0.05715)
			(type default)
		)
		(layer "In9.Cu")
	)
	(gr_line
		(start 189.999874 -280.699718)
		(end 189.999874 -280.434288)
		(stroke
			(width 0.05715)
			(type default)
		)
		(layer "In9.Cu")
	)
	(gr_line
		(start 189.999874 -280.434288)
		(end 189.885574 -280.319988)
		(stroke
			(width 0.05715)
			(type default)
		)
		(layer "In9.Cu")
	)
	(gr_line
		(start 189.999874 -280.015188)
		(end 189.885574 -280.129488)
		(stroke
			(width 0.05715)
			(type default)
		)
		(layer "In9.Cu")
	)
	(gr_line
		(start 189.999874 -279.749504)
		(end 189.999874 -280.015188)
		(stroke
			(width 0.05715)
			(type default)
		)
		(layer "In9.Cu")
	)
	(gr_line
		(start 196.579998 -199.893174)
		(end 196.580252 -199.893174)
		(stroke
			(width 0.08255)
			(type default)
		)
		(layer "In9.Cu")
	)
	(gr_line
		(start 197.600062 -276.899878)
		(end 197.865492 -276.899878)
		(stroke
			(width 0.05715)
			(type default)
		)
		(layer "In9.Cu")
	)
	(gr_line
		(start 197.865492 -276.899878)
		(end 197.979792 -276.785578)
		(stroke
			(width 0.05715)
			(type default)
		)
		(layer "In9.Cu")
	)
	(gr_line
		(start 197.922896 -143.188436)
		(end 197.632066 -143.479266)
		(stroke
			(width 0.08255)
			(type default)
		)
		(layer "In9.Cu")
	)
	(gr_line
		(start 198.884286 -271.8054)
		(end 198.884286 -271.776952)
		(stroke
			(width 0.05715)
			(type default)
		)
		(layer "In9.Cu")
	)
	(gr_line
		(start 198.930006 -271.85112)
		(end 198.884286 -271.8054)
		(stroke
			(width 0.05715)
			(type default)
		)
		(layer "In9.Cu")
	)
	(gr_line
		(start 200.192386 -143.282162)
		(end 200.145142 -143.167608)
		(stroke
			(width 0.08255)
			(type default)
		)
		(layer "In9.Cu")
	)
	(gr_line
		(start 200.650348 -143.4719)
		(end 200.192386 -143.282162)
		(stroke
			(width 0.08255)
			(type default)
		)
		(layer "In9.Cu")
	)
	(gr_line
		(start 200.764902 -143.424402)
		(end 200.650348 -143.4719)
		(stroke
			(width 0.08255)
			(type default)
		)
		(layer "In9.Cu")
	)
	(gr_line
		(start 202.466448 -144.90192)
		(end 202.466448 -144.777968)
		(stroke
			(width 0.08255)
			(type default)
		)
		(layer "In9.Cu")
	)
	(gr_line
		(start 202.816968 -145.25244)
		(end 202.466448 -144.90192)
		(stroke
			(width 0.08255)
			(type default)
		)
		(layer "In9.Cu")
	)
	(gr_line
		(start 202.94092 -145.25244)
		(end 202.816968 -145.25244)
		(stroke
			(width 0.08255)
			(type default)
		)
		(layer "In9.Cu")
	)
	(gr_line
		(start 203.29271 -145.728182)
		(end 203.29271 -145.60423)
		(stroke
			(width 0.08255)
			(type default)
		)
		(layer "In9.Cu")
	)
	(gr_line
		(start 203.64323 -146.078702)
		(end 203.29271 -145.728182)
		(stroke
			(width 0.08255)
			(type default)
		)
		(layer "In9.Cu")
	)
	(gr_line
		(start 203.767182 -146.078702)
		(end 203.64323 -146.078702)
		(stroke
			(width 0.08255)
			(type default)
		)
		(layer "In9.Cu")
	)
	(gr_line
		(start 204.17028 -146.605752)
		(end 204.17028 -146.4818)
		(stroke
			(width 0.08255)
			(type default)
		)
		(layer "In9.Cu")
	)
	(gr_line
		(start 204.520546 -146.956018)
		(end 204.17028 -146.605752)
		(stroke
			(width 0.08255)
			(type default)
		)
		(layer "In9.Cu")
	)
	(gr_line
		(start 204.644498 -146.956018)
		(end 204.520546 -146.956018)
		(stroke
			(width 0.08255)
			(type default)
		)
		(layer "In9.Cu")
	)
	(gr_line
		(start 205.124304 -147.718272)
		(end 205.148434 -147.596606)
		(stroke
			(width 0.08255)
			(type default)
		)
		(layer "In9.Cu")
	)
	(gr_line
		(start 205.39964 -148.13026)
		(end 205.124304 -147.718272)
		(stroke
			(width 0.08255)
			(type default)
		)
		(layer "In9.Cu")
	)
	(gr_line
		(start 205.521306 -148.154644)
		(end 205.39964 -148.13026)
		(stroke
			(width 0.08255)
			(type default)
		)
		(layer "In9.Cu")
	)
	(gr_line
		(start 205.523084 -148.154898)
		(end 205.52283 -148.154898)
		(stroke
			(width 0.08255)
			(type default)
		)
		(layer "In9.Cu")
	)
	(gr_line
		(start 206.100426 -149.38121)
		(end 206.147924 -149.266656)
		(stroke
			(width 0.08255)
			(type default)
		)
		(layer "In9.Cu")
	)
	(gr_line
		(start 206.290418 -149.839172)
		(end 206.100426 -149.38121)
		(stroke
			(width 0.08255)
			(type default)
		)
		(layer "In9.Cu")
	)
	(gr_line
		(start 206.404718 -149.886416)
		(end 206.290418 -149.839172)
		(stroke
			(width 0.08255)
			(type default)
		)
		(layer "In9.Cu")
	)
	(gr_line
		(start 206.406496 -149.887178)
		(end 206.406242 -149.887178)
		(stroke
			(width 0.08255)
			(type default)
		)
		(layer "In9.Cu")
	)
	(gr_line
		(start 210.66125 -85.3948)
		(end 211.38515 -85.3948)
		(stroke
			(width 0.08255)
			(type default)
		)
		(layer "In9.Cu")
	)
	(gr_line
		(start 210.66252 -85.67801)
		(end 210.77555 -85.79104)
		(stroke
			(width 0.08255)
			(type default)
		)
		(layer "In9.Cu")
	)
	(gr_line
		(start 210.77555 -85.79104)
		(end 211.27085 -85.79104)
		(stroke
			(width 0.08255)
			(type default)
		)
		(layer "In9.Cu")
	)
	(gr_line
		(start 211.27085 -85.79104)
		(end 211.38388 -85.67801)
		(stroke
			(width 0.08255)
			(type default)
		)
		(layer "In9.Cu")
	)
	(gr_line
		(start 211.88045 -85.3948)
		(end 212.60435 -85.3948)
		(stroke
			(width 0.08255)
			(type default)
		)
		(layer "In9.Cu")
	)
	(gr_line
		(start 211.88172 -85.67801)
		(end 211.99475 -85.79104)
		(stroke
			(width 0.08255)
			(type default)
		)
		(layer "In9.Cu")
	)
	(gr_line
		(start 211.99475 -85.79104)
		(end 212.49005 -85.79104)
		(stroke
			(width 0.08255)
			(type default)
		)
		(layer "In9.Cu")
	)
	(gr_line
		(start 212.49005 -85.79104)
		(end 212.60308 -85.67801)
		(stroke
			(width 0.08255)
			(type default)
		)
		(layer "In9.Cu")
	)
	(gr_line
		(start 213.09965 -85.3948)
		(end 213.82355 -85.3948)
		(stroke
			(width 0.08255)
			(type default)
		)
		(layer "In9.Cu")
	)
	(gr_line
		(start 213.10092 -85.67801)
		(end 213.21395 -85.79104)
		(stroke
			(width 0.08255)
			(type default)
		)
		(layer "In9.Cu")
	)
	(gr_line
		(start 213.21395 -85.79104)
		(end 213.70925 -85.79104)
		(stroke
			(width 0.08255)
			(type default)
		)
		(layer "In9.Cu")
	)
	(gr_line
		(start 213.70925 -85.79104)
		(end 213.82228 -85.67801)
		(stroke
			(width 0.08255)
			(type default)
		)
		(layer "In9.Cu")
	)
	(gr_line
		(start 214.31885 -85.3948)
		(end 215.04275 -85.3948)
		(stroke
			(width 0.08255)
			(type default)
		)
		(layer "In9.Cu")
	)
	(gr_line
		(start 214.32012 -85.67801)
		(end 214.43315 -85.79104)
		(stroke
			(width 0.08255)
			(type default)
		)
		(layer "In9.Cu")
	)
	(gr_line
		(start 214.43315 -85.79104)
		(end 214.92845 -85.79104)
		(stroke
			(width 0.08255)
			(type default)
		)
		(layer "In9.Cu")
	)
	(gr_line
		(start 214.92845 -85.79104)
		(end 215.04148 -85.67801)
		(stroke
			(width 0.08255)
			(type default)
		)
		(layer "In9.Cu")
	)
	(gr_line
		(start 231.64165 -80.6958)
		(end 232.36555 -80.6958)
		(stroke
			(width 0.08255)
			(type default)
		)
		(layer "In9.Cu")
	)
	(gr_line
		(start 231.64292 -80.97901)
		(end 231.75595 -81.09204)
		(stroke
			(width 0.08255)
			(type default)
		)
		(layer "In9.Cu")
	)
	(gr_line
		(start 231.75595 -81.09204)
		(end 232.25125 -81.09204)
		(stroke
			(width 0.08255)
			(type default)
		)
		(layer "In9.Cu")
	)
	(gr_line
		(start 232.25125 -81.09204)
		(end 232.36428 -80.97901)
		(stroke
			(width 0.08255)
			(type default)
		)
		(layer "In9.Cu")
	)
	(gr_line
		(start 234.20705 -80.6958)
		(end 234.93095 -80.6958)
		(stroke
			(width 0.08255)
			(type default)
		)
		(layer "In9.Cu")
	)
	(gr_line
		(start 234.20832 -80.97901)
		(end 234.32135 -81.09204)
		(stroke
			(width 0.08255)
			(type default)
		)
		(layer "In9.Cu")
	)
	(gr_line
		(start 234.32135 -81.09204)
		(end 234.81665 -81.09204)
		(stroke
			(width 0.08255)
			(type default)
		)
		(layer "In9.Cu")
	)
	(gr_line
		(start 234.81665 -81.09204)
		(end 234.92968 -80.97901)
		(stroke
			(width 0.08255)
			(type default)
		)
		(layer "In9.Cu")
	)
	(gr_line
		(start 234.8611 -336.402426)
		(end 235.1278 -336.669126)
		(stroke
			(width 0.06985)
			(type default)
		)
		(layer "In9.Cu")
	)
	(gr_line
		(start 237.10265 -81.2546)
		(end 237.82655 -81.2546)
		(stroke
			(width 0.08255)
			(type default)
		)
		(layer "In9.Cu")
	)
	(gr_line
		(start 237.10392 -81.53781)
		(end 237.21695 -81.65084)
		(stroke
			(width 0.08255)
			(type default)
		)
		(layer "In9.Cu")
	)
	(gr_line
		(start 237.21695 -81.65084)
		(end 237.71225 -81.65084)
		(stroke
			(width 0.08255)
			(type default)
		)
		(layer "In9.Cu")
	)
	(gr_line
		(start 237.71225 -81.65084)
		(end 237.82528 -81.53781)
		(stroke
			(width 0.08255)
			(type default)
		)
		(layer "In9.Cu")
	)
	(gr_line
		(start 238.5822 -87.976202)
		(end 238.87303 -88.267032)
		(stroke
			(width 0.08255)
			(type default)
		)
		(layer "In9.Cu")
	)
	(gr_line
		(start 238.880904 -82.016346)
		(end 238.590074 -82.307176)
		(stroke
			(width 0.08255)
			(type default)
		)
		(layer "In9.Cu")
	)
	(gr_line
		(start 239.162844 -82.016346)
		(end 239.453674 -82.307176)
		(stroke
			(width 0.08255)
			(type default)
		)
		(layer "In9.Cu")
	)
	(gr_line
		(start 239.4458 -87.976202)
		(end 239.15497 -88.267032)
		(stroke
			(width 0.08255)
			(type default)
		)
		(layer "In9.Cu")
	)
	(gr_line
		(start 258.22783 -151.935942)
		(end 258.22783 -151.935688)
		(stroke
			(width 0.08255)
			(type default)
		)
		(layer "In9.Cu")
	)
	(gr_line
		(start 259.245608 -108.980732)
		(end 259.35305 -108.721398)
		(stroke
			(width 0.08255)
			(type default)
		)
		(layer "In9.Cu")
	)
	(gr_line
		(start 259.310632 -111.674148)
		(end 259.578094 -111.02848)
		(stroke
			(width 0.08255)
			(type default)
		)
		(layer "In9.Cu")
	)
	(gr_line
		(start 259.35305 -108.721398)
		(end 259.630164 -108.052362)
		(stroke
			(width 0.08255)
			(type default)
		)
		(layer "In9.Cu")
	)
	(gr_line
		(start 259.505958 -109.088682)
		(end 259.6134 -108.829348)
		(stroke
			(width 0.08255)
			(type default)
		)
		(layer "In9.Cu")
	)
	(gr_line
		(start 259.57276 -111.78159)
		(end 259.703824 -111.72698)
		(stroke
			(width 0.08255)
			(type default)
		)
		(layer "In9.Cu")
	)
	(gr_line
		(start 259.615178 -108.828586)
		(end 259.763006 -108.767626)
		(stroke
			(width 0.08255)
			(type default)
		)
		(layer "In9.Cu")
	)
	(gr_line
		(start 259.630164 -108.052362)
		(end 259.819648 -107.594908)
		(stroke
			(width 0.08255)
			(type default)
		)
		(layer "In9.Cu")
	)
	(gr_line
		(start 259.703824 -111.72698)
		(end 259.893816 -111.269272)
		(stroke
			(width 0.08255)
			(type default)
		)
		(layer "In9.Cu")
	)
	(gr_line
		(start 259.763006 -108.767626)
		(end 259.95249 -108.309664)
		(stroke
			(width 0.08255)
			(type default)
		)
		(layer "In9.Cu")
	)
	(gr_line
		(start 259.767578 -110.571026)
		(end 260.03504 -109.925358)
		(stroke
			(width 0.08255)
			(type default)
		)
		(layer "In9.Cu")
	)
	(gr_line
		(start 259.819648 -107.594908)
		(end 260.096762 -106.925872)
		(stroke
			(width 0.08255)
			(type default)
		)
		(layer "In9.Cu")
	)
	(gr_line
		(start 259.890514 -108.160312)
		(end 260.079998 -107.702858)
		(stroke
			(width 0.08255)
			(type default)
		)
		(layer "In9.Cu")
	)
	(gr_line
		(start 259.893816 -111.269272)
		(end 259.839206 -111.137954)
		(stroke
			(width 0.08255)
			(type default)
		)
		(layer "In9.Cu")
	)
	(gr_line
		(start 259.95249 -108.309664)
		(end 259.891276 -108.16209)
		(stroke
			(width 0.08255)
			(type default)
		)
		(layer "In9.Cu")
	)
	(gr_line
		(start 260.029706 -110.678468)
		(end 260.16077 -110.623858)
		(stroke
			(width 0.08255)
			(type default)
		)
		(layer "In9.Cu")
	)
	(gr_line
		(start 260.081776 -107.702096)
		(end 260.229604 -107.641136)
		(stroke
			(width 0.08255)
			(type default)
		)
		(layer "In9.Cu")
	)
	(gr_line
		(start 260.16077 -110.623858)
		(end 260.350762 -110.16615)
		(stroke
			(width 0.08255)
			(type default)
		)
		(layer "In9.Cu")
	)
	(gr_line
		(start 260.224524 -109.467904)
		(end 260.491986 -108.822236)
		(stroke
			(width 0.08255)
			(type default)
		)
		(layer "In9.Cu")
	)
	(gr_line
		(start 260.229604 -107.641136)
		(end 260.419088 -107.183174)
		(stroke
			(width 0.08255)
			(type default)
		)
		(layer "In9.Cu")
	)
	(gr_line
		(start 260.350762 -110.16615)
		(end 260.296152 -110.034832)
		(stroke
			(width 0.08255)
			(type default)
		)
		(layer "In9.Cu")
	)
	(gr_line
		(start 260.419088 -107.183174)
		(end 260.357874 -107.035346)
		(stroke
			(width 0.08255)
			(type default)
		)
		(layer "In9.Cu")
	)
	(gr_line
		(start 260.486652 -109.575346)
		(end 260.617716 -109.520736)
		(stroke
			(width 0.08255)
			(type default)
		)
		(layer "In9.Cu")
	)
	(gr_line
		(start 260.617716 -109.520736)
		(end 260.807708 -109.063028)
		(stroke
			(width 0.08255)
			(type default)
		)
		(layer "In9.Cu")
	)
	(gr_line
		(start 260.641338 -114.302794)
		(end 260.918198 -113.633758)
		(stroke
			(width 0.08255)
			(type default)
		)
		(layer "In9.Cu")
	)
	(gr_line
		(start 260.68147 -108.364782)
		(end 260.948932 -107.719114)
		(stroke
			(width 0.08255)
			(type default)
		)
		(layer "In9.Cu")
	)
	(gr_line
		(start 260.79323 -306.826666)
		(end 260.79323 -306.578762)
		(stroke
			(width 0.06985)
			(type default)
		)
		(layer "In9.Cu")
	)
	(gr_line
		(start 260.79323 -306.578762)
		(end 261.062978 -306.309014)
		(stroke
			(width 0.06985)
			(type default)
		)
		(layer "In9.Cu")
	)
	(gr_line
		(start 260.807708 -109.063028)
		(end 260.753098 -108.93171)
		(stroke
			(width 0.08255)
			(type default)
		)
		(layer "In9.Cu")
	)
	(gr_line
		(start 260.901688 -114.410744)
		(end 260.901942 -114.410744)
		(stroke
			(width 0.08255)
			(type default)
		)
		(layer "In9.Cu")
	)
	(gr_line
		(start 260.903466 -114.409982)
		(end 261.051294 -114.349022)
		(stroke
			(width 0.08255)
			(type default)
		)
		(layer "In9.Cu")
	)
	(gr_line
		(start 260.942074 -108.472732)
		(end 260.942074 -108.472478)
		(stroke
			(width 0.08255)
			(type default)
		)
		(layer "In9.Cu")
	)
	(gr_line
		(start 260.943852 -108.471716)
		(end 261.074916 -108.417614)
		(stroke
			(width 0.08255)
			(type default)
		)
		(layer "In9.Cu")
	)
	(gr_line
		(start 261.051294 -114.349022)
		(end 261.240778 -113.89106)
		(stroke
			(width 0.08255)
			(type default)
		)
		(layer "In9.Cu")
	)
	(gr_line
		(start 261.062978 -306.309014)
		(end 261.310882 -306.309014)
		(stroke
			(width 0.06985)
			(type default)
		)
		(layer "In9.Cu")
	)
	(gr_line
		(start 261.074916 -108.417614)
		(end 261.264654 -107.959652)
		(stroke
			(width 0.08255)
			(type default)
		)
		(layer "In9.Cu")
	)
	(gr_line
		(start 261.107682 -113.176304)
		(end 261.384796 -112.507268)
		(stroke
			(width 0.08255)
			(type default)
		)
		(layer "In9.Cu")
	)
	(gr_line
		(start 261.128256 -130.237484)
		(end 261.259574 -130.183382)
		(stroke
			(width 0.08255)
			(type default)
		)
		(layer "In9.Cu")
	)
	(gr_line
		(start 261.240778 -113.89106)
		(end 261.179564 -113.743232)
		(stroke
			(width 0.08255)
			(type default)
		)
		(layer "In9.Cu")
	)
	(gr_line
		(start 261.259574 -130.183382)
		(end 261.444486 -129.737104)
		(stroke
			(width 0.08255)
			(type default)
		)
		(layer "In9.Cu")
	)
	(gr_line
		(start 261.264654 -107.959652)
		(end 261.210298 -107.828588)
		(stroke
			(width 0.08255)
			(type default)
		)
		(layer "In9.Cu")
	)
	(gr_line
		(start 261.36981 -113.283492)
		(end 261.517892 -113.222532)
		(stroke
			(width 0.08255)
			(type default)
		)
		(layer "In9.Cu")
	)
	(gr_line
		(start 261.41045 -118.061486)
		(end 261.658354 -117.462808)
		(stroke
			(width 0.08255)
			(type default)
		)
		(layer "In9.Cu")
	)
	(gr_line
		(start 261.444486 -129.737104)
		(end 261.389876 -129.605786)
		(stroke
			(width 0.08255)
			(type default)
		)
		(layer "In9.Cu")
	)
	(gr_line
		(start 261.490968 -105.118154)
		(end 261.994142 -104.61498)
		(stroke
			(width 0.08255)
			(type default)
		)
		(layer "In9.Cu")
	)
	(gr_line
		(start 261.517892 -113.222532)
		(end 261.707376 -112.76457)
		(stroke
			(width 0.08255)
			(type default)
		)
		(layer "In9.Cu")
	)
	(gr_line
		(start 261.57428 -112.049814)
		(end 261.851394 -111.380778)
		(stroke
			(width 0.08255)
			(type default)
		)
		(layer "In9.Cu")
	)
	(gr_line
		(start 261.596886 -129.103374)
		(end 261.596632 -129.103374)
		(stroke
			(width 0.08255)
			(type default)
		)
		(layer "In9.Cu")
	)
	(gr_line
		(start 261.59841 -129.102612)
		(end 261.729728 -129.04851)
		(stroke
			(width 0.08255)
			(type default)
		)
		(layer "In9.Cu")
	)
	(gr_line
		(start 261.63651 -305.983386)
		(end 261.63651 -305.735482)
		(stroke
			(width 0.06985)
			(type default)
		)
		(layer "In9.Cu")
	)
	(gr_line
		(start 261.63651 -305.735482)
		(end 261.906258 -305.465734)
		(stroke
			(width 0.06985)
			(type default)
		)
		(layer "In9.Cu")
	)
	(gr_line
		(start 261.672578 -118.168928)
		(end 261.770622 -118.128288)
		(stroke
			(width 0.08255)
			(type default)
		)
		(layer "In9.Cu")
	)
	(gr_line
		(start 261.692136 -105.317544)
		(end 261.851902 -105.317544)
		(stroke
			(width 0.08255)
			(type default)
		)
		(layer "In9.Cu")
	)
	(gr_line
		(start 261.707376 -112.76457)
		(end 261.645908 -112.616742)
		(stroke
			(width 0.08255)
			(type default)
		)
		(layer "In9.Cu")
	)
	(gr_line
		(start 261.729728 -129.04851)
		(end 261.914386 -128.602232)
		(stroke
			(width 0.08255)
			(type default)
		)
		(layer "In9.Cu")
	)
	(gr_line
		(start 261.747254 -130.798824)
		(end 262.005064 -130.176524)
		(stroke
			(width 0.08255)
			(type default)
		)
		(layer "In9.Cu")
	)
	(gr_line
		(start 261.770622 -118.128288)
		(end 261.96036 -117.670326)
		(stroke
			(width 0.08255)
			(type default)
		)
		(layer "In9.Cu")
	)
	(gr_line
		(start 261.83463 -112.157764)
		(end 261.834884 -112.157764)
		(stroke
			(width 0.08255)
			(type default)
		)
		(layer "In9.Cu")
	)
	(gr_line
		(start 261.836408 -112.157002)
		(end 261.984236 -112.096042)
		(stroke
			(width 0.08255)
			(type default)
		)
		(layer "In9.Cu")
	)
	(gr_line
		(start 261.847838 -117.005354)
		(end 262.125206 -116.336318)
		(stroke
			(width 0.08255)
			(type default)
		)
		(layer "In9.Cu")
	)
	(gr_line
		(start 261.851902 -105.317544)
		(end 262.193532 -104.975914)
		(stroke
			(width 0.08255)
			(type default)
		)
		(layer "In9.Cu")
	)
	(gr_line
		(start 261.906258 -305.465734)
		(end 262.154162 -305.465734)
		(stroke
			(width 0.06985)
			(type default)
		)
		(layer "In9.Cu")
	)
	(gr_line
		(start 261.914386 -128.602232)
		(end 261.86003 -128.471168)
		(stroke
			(width 0.08255)
			(type default)
		)
		(layer "In9.Cu")
	)
	(gr_line
		(start 261.96036 -117.670326)
		(end 261.91972 -117.572282)
		(stroke
			(width 0.08255)
			(type default)
		)
		(layer "In9.Cu")
	)
	(gr_line
		(start 261.984236 -112.096042)
		(end 262.17372 -111.63808)
		(stroke
			(width 0.08255)
			(type default)
		)
		(layer "In9.Cu")
	)
	(gr_line
		(start 262.007858 -130.906774)
		(end 262.007858 -130.90652)
		(stroke
			(width 0.08255)
			(type default)
		)
		(layer "In9.Cu")
	)
	(gr_line
		(start 262.009636 -130.905758)
		(end 262.123936 -130.858514)
		(stroke
			(width 0.08255)
			(type default)
		)
		(layer "In9.Cu")
	)
	(gr_line
		(start 262.040878 -110.923324)
		(end 262.317738 -110.254288)
		(stroke
			(width 0.08255)
			(type default)
		)
		(layer "In9.Cu")
	)
	(gr_line
		(start 262.043926 -128.023874)
		(end 262.043926 -128.02362)
		(stroke
			(width 0.08255)
			(type default)
		)
		(layer "In9.Cu")
	)
	(gr_line
		(start 262.045704 -128.022858)
		(end 262.177022 -127.968756)
		(stroke
			(width 0.08255)
			(type default)
		)
		(layer "In9.Cu")
	)
	(gr_line
		(start 262.078216 -106.054906)
		(end 262.5725 -105.560622)
		(stroke
			(width 0.08255)
			(type default)
		)
		(layer "In9.Cu")
	)
	(gr_line
		(start 262.104886 -151.234902)
		(end 262.104886 -151.235156)
		(stroke
			(width 0.08255)
			(type default)
		)
		(layer "In9.Cu")
	)
	(gr_line
		(start 262.109966 -117.112542)
		(end 262.258048 -117.051582)
		(stroke
			(width 0.08255)
			(type default)
		)
		(layer "In9.Cu")
	)
	(gr_line
		(start 262.111998 -111.488728)
		(end 262.111744 -111.488728)
		(stroke
			(width 0.08255)
			(type default)
		)
		(layer "In9.Cu")
	)
	(gr_line
		(start 262.123936 -130.858514)
		(end 262.313928 -130.400552)
		(stroke
			(width 0.08255)
			(type default)
		)
		(layer "In9.Cu")
	)
	(gr_line
		(start 262.17372 -111.63808)
		(end 262.112506 -111.490506)
		(stroke
			(width 0.08255)
			(type default)
		)
		(layer "In9.Cu")
	)
	(gr_line
		(start 262.177022 -127.968756)
		(end 262.36168 -127.522478)
		(stroke
			(width 0.08255)
			(type default)
		)
		(layer "In9.Cu")
	)
	(gr_line
		(start 262.193532 -104.975914)
		(end 262.193532 -104.816148)
		(stroke
			(width 0.08255)
			(type default)
		)
		(layer "In9.Cu")
	)
	(gr_line
		(start 262.194548 -129.71907)
		(end 262.452104 -129.097024)
		(stroke
			(width 0.08255)
			(type default)
		)
		(layer "In9.Cu")
	)
	(gr_line
		(start 262.258048 -117.051582)
		(end 262.447786 -116.59362)
		(stroke
			(width 0.08255)
			(type default)
		)
		(layer "In9.Cu")
	)
	(gr_line
		(start 262.259572 -121.681494)
		(end 262.536686 -121.012458)
		(stroke
			(width 0.08255)
			(type default)
		)
		(layer "In9.Cu")
	)
	(gr_line
		(start 262.279384 -106.254296)
		(end 262.42137 -106.254296)
		(stroke
			(width 0.08255)
			(type default)
		)
		(layer "In9.Cu")
	)
	(gr_line
		(start 262.301228 -111.031274)
		(end 262.301482 -111.031274)
		(stroke
			(width 0.08255)
			(type default)
		)
		(layer "In9.Cu")
	)
	(gr_line
		(start 262.302752 -111.030512)
		(end 262.450834 -110.969552)
		(stroke
			(width 0.08255)
			(type default)
		)
		(layer "In9.Cu")
	)
	(gr_line
		(start 262.313928 -130.400552)
		(end 262.266176 -130.285998)
		(stroke
			(width 0.08255)
			(type default)
		)
		(layer "In9.Cu")
	)
	(gr_line
		(start 262.31469 -115.878864)
		(end 262.591804 -115.209828)
		(stroke
			(width 0.08255)
			(type default)
		)
		(layer "In9.Cu")
	)
	(gr_line
		(start 262.335264 -104.273858)
		(end 262.838438 -103.770684)
		(stroke
			(width 0.08255)
			(type default)
		)
		(layer "In9.Cu")
	)
	(gr_line
		(start 262.36168 -127.522478)
		(end 262.307324 -127.391414)
		(stroke
			(width 0.08255)
			(type default)
		)
		(layer "In9.Cu")
	)
	(gr_line
		(start 262.42137 -106.254296)
		(end 262.77189 -105.903776)
		(stroke
			(width 0.08255)
			(type default)
		)
		(layer "In9.Cu")
	)
	(gr_line
		(start 262.447786 -116.59362)
		(end 262.386318 -116.445538)
		(stroke
			(width 0.08255)
			(type default)
		)
		(layer "In9.Cu")
	)
	(gr_line
		(start 262.450834 -110.969552)
		(end 262.640318 -110.51159)
		(stroke
			(width 0.08255)
			(type default)
		)
		(layer "In9.Cu")
	)
	(gr_line
		(start 262.455152 -129.82702)
		(end 262.454898 -129.82702)
		(stroke
			(width 0.08255)
			(type default)
		)
		(layer "In9.Cu")
	)
	(gr_line
		(start 262.456676 -129.826258)
		(end 262.570976 -129.779014)
		(stroke
			(width 0.08255)
			(type default)
		)
		(layer "In9.Cu")
	)
	(gr_line
		(start 262.49122 -126.94412)
		(end 262.49122 -126.943866)
		(stroke
			(width 0.08255)
			(type default)
		)
		(layer "In9.Cu")
	)
	(gr_line
		(start 262.492998 -126.943104)
		(end 262.624316 -126.889002)
		(stroke
			(width 0.08255)
			(type default)
		)
		(layer "In9.Cu")
	)
	(gr_line
		(start 262.507222 -109.796834)
		(end 262.784336 -109.127798)
		(stroke
			(width 0.08255)
			(type default)
		)
		(layer "In9.Cu")
	)
	(gr_line
		(start 262.521446 -121.788936)
		(end 262.669782 -121.727722)
		(stroke
			(width 0.08255)
			(type default)
		)
		(layer "In9.Cu")
	)
	(gr_line
		(start 262.536432 -104.473248)
		(end 262.696198 -104.473248)
		(stroke
			(width 0.08255)
			(type default)
		)
		(layer "In9.Cu")
	)
	(gr_line
		(start 262.570976 -129.779014)
		(end 262.760968 -129.321052)
		(stroke
			(width 0.08255)
			(type default)
		)
		(layer "In9.Cu")
	)
	(gr_line
		(start 262.576564 -115.986306)
		(end 262.724646 -115.925092)
		(stroke
			(width 0.08255)
			(type default)
		)
		(layer "In9.Cu")
	)
	(gr_line
		(start 262.624316 -126.889002)
		(end 262.808974 -126.442724)
		(stroke
			(width 0.08255)
			(type default)
		)
		(layer "In9.Cu")
	)
	(gr_line
		(start 262.640318 -110.51159)
		(end 262.579104 -110.363762)
		(stroke
			(width 0.08255)
			(type default)
		)
		(layer "In9.Cu")
	)
	(gr_line
		(start 262.641588 -128.63957)
		(end 262.899398 -128.01727)
		(stroke
			(width 0.08255)
			(type default)
		)
		(layer "In9.Cu")
	)
	(gr_line
		(start 262.669782 -121.727722)
		(end 262.859266 -121.26976)
		(stroke
			(width 0.08255)
			(type default)
		)
		(layer "In9.Cu")
	)
	(gr_line
		(start 262.696198 -104.473248)
		(end 263.037828 -104.131618)
		(stroke
			(width 0.08255)
			(type default)
		)
		(layer "In9.Cu")
	)
	(gr_line
		(start 262.724646 -115.925092)
		(end 262.914384 -115.46713)
		(stroke
			(width 0.08255)
			(type default)
		)
		(layer "In9.Cu")
	)
	(gr_line
		(start 262.72617 -120.555004)
		(end 263.003284 -119.885968)
		(stroke
			(width 0.08255)
			(type default)
		)
		(layer "In9.Cu")
	)
	(gr_line
		(start 262.745474 -304.874422)
		(end 262.745474 -304.626518)
		(stroke
			(width 0.06985)
			(type default)
		)
		(layer "In9.Cu")
	)
	(gr_line
		(start 262.745474 -304.626518)
		(end 263.015222 -304.35677)
		(stroke
			(width 0.06985)
			(type default)
		)
		(layer "In9.Cu")
	)
	(gr_line
		(start 262.760968 -129.321052)
		(end 262.71347 -129.206498)
		(stroke
			(width 0.08255)
			(type default)
		)
		(layer "In9.Cu")
	)
	(gr_line
		(start 262.76935 -109.904276)
		(end 262.917432 -109.843062)
		(stroke
			(width 0.08255)
			(type default)
		)
		(layer "In9.Cu")
	)
	(gr_line
		(start 262.77189 -105.903776)
		(end 262.77189 -105.76179)
		(stroke
			(width 0.08255)
			(type default)
		)
		(layer "In9.Cu")
	)
	(gr_line
		(start 262.781288 -114.752374)
		(end 263.058402 -114.083338)
		(stroke
			(width 0.08255)
			(type default)
		)
		(layer "In9.Cu")
	)
	(gr_line
		(start 262.808974 -126.442724)
		(end 262.754364 -126.31166)
		(stroke
			(width 0.08255)
			(type default)
		)
		(layer "In9.Cu")
	)
	(gr_line
		(start 262.859266 -121.26976)
		(end 262.797798 -121.121932)
		(stroke
			(width 0.08255)
			(type default)
		)
		(layer "In9.Cu")
	)
	(gr_line
		(start 262.902192 -128.74752)
		(end 262.902192 -128.747266)
		(stroke
			(width 0.08255)
			(type default)
		)
		(layer "In9.Cu")
	)
	(gr_line
		(start 262.90397 -128.746504)
		(end 263.01827 -128.69926)
		(stroke
			(width 0.08255)
			(type default)
		)
		(layer "In9.Cu")
	)
	(gr_line
		(start 262.914384 -115.46713)
		(end 262.852916 -115.319048)
		(stroke
			(width 0.08255)
			(type default)
		)
		(layer "In9.Cu")
	)
	(gr_line
		(start 262.917432 -109.843062)
		(end 263.106916 -109.3851)
		(stroke
			(width 0.08255)
			(type default)
		)
		(layer "In9.Cu")
	)
	(gr_line
		(start 262.922512 -105.21061)
		(end 263.416796 -104.716326)
		(stroke
			(width 0.08255)
			(type default)
		)
		(layer "In9.Cu")
	)
	(gr_line
		(start 262.938514 -125.864366)
		(end 262.93826 -125.864366)
		(stroke
			(width 0.08255)
			(type default)
		)
		(layer "In9.Cu")
	)
	(gr_line
		(start 262.940038 -125.863604)
		(end 263.071356 -125.809502)
		(stroke
			(width 0.08255)
			(type default)
		)
		(layer "In9.Cu")
	)
	(gr_line
		(start 262.988298 -120.662446)
		(end 263.13638 -120.601232)
		(stroke
			(width 0.08255)
			(type default)
		)
		(layer "In9.Cu")
	)
	(gr_line
		(start 263.015222 -304.35677)
		(end 263.263126 -304.35677)
		(stroke
			(width 0.06985)
			(type default)
		)
		(layer "In9.Cu")
	)
	(gr_line
		(start 263.01827 -128.69926)
		(end 263.208262 -128.241298)
		(stroke
			(width 0.08255)
			(type default)
		)
		(layer "In9.Cu")
	)
	(gr_line
		(start 263.037828 -104.131618)
		(end 263.037828 -103.971852)
		(stroke
			(width 0.08255)
			(type default)
		)
		(layer "In9.Cu")
	)
	(gr_line
		(start 263.043416 -114.859816)
		(end 263.191244 -114.798602)
		(stroke
			(width 0.08255)
			(type default)
		)
		(layer "In9.Cu")
	)
	(gr_line
		(start 263.071356 -125.809502)
		(end 263.256014 -125.363224)
		(stroke
			(width 0.08255)
			(type default)
		)
		(layer "In9.Cu")
	)
	(gr_line
		(start 263.088882 -127.559816)
		(end 263.346692 -126.937516)
		(stroke
			(width 0.08255)
			(type default)
		)
		(layer "In9.Cu")
	)
	(gr_line
		(start 263.106916 -109.3851)
		(end 263.045448 -109.237272)
		(stroke
			(width 0.08255)
			(type default)
		)
		(layer "In9.Cu")
	)
	(gr_line
		(start 263.12368 -105.41)
		(end 263.265666 -105.41)
		(stroke
			(width 0.08255)
			(type default)
		)
		(layer "In9.Cu")
	)
	(gr_line
		(start 263.13638 -120.601232)
		(end 263.325864 -120.14327)
		(stroke
			(width 0.08255)
			(type default)
		)
		(layer "In9.Cu")
	)
	(gr_line
		(start 263.13638 -108.277914)
		(end 263.157716 -108.226098)
		(stroke
			(width 0.08255)
			(type default)
		)
		(layer "In9.Cu")
	)
	(gr_line
		(start 263.157716 -108.226098)
		(end 263.158224 -108.226098)
		(stroke
			(width 0.08255)
			(type default)
		)
		(layer "In9.Cu")
	)
	(gr_line
		(start 263.158224 -108.226098)
		(end 263.197848 -108.186474)
		(stroke
			(width 0.08255)
			(type default)
		)
		(layer "In9.Cu")
	)
	(gr_line
		(start 263.17956 -103.429562)
		(end 263.682734 -102.926388)
		(stroke
			(width 0.08255)
			(type default)
		)
		(layer "In9.Cu")
	)
	(gr_line
		(start 263.191244 -114.798602)
		(end 263.380982 -114.34064)
		(stroke
			(width 0.08255)
			(type default)
		)
		(layer "In9.Cu")
	)
	(gr_line
		(start 263.192768 -119.428514)
		(end 263.469882 -118.759478)
		(stroke
			(width 0.08255)
			(type default)
		)
		(layer "In9.Cu")
	)
	(gr_line
		(start 263.208262 -128.241298)
		(end 263.160764 -128.126744)
		(stroke
			(width 0.08255)
			(type default)
		)
		(layer "In9.Cu")
	)
	(gr_line
		(start 263.247886 -113.625884)
		(end 263.525 -112.956848)
		(stroke
			(width 0.08255)
			(type default)
		)
		(layer "In9.Cu")
	)
	(gr_line
		(start 263.256014 -125.363224)
		(end 263.201658 -125.232414)
		(stroke
			(width 0.08255)
			(type default)
		)
		(layer "In9.Cu")
	)
	(gr_line
		(start 263.265666 -105.41)
		(end 263.616186 -105.05948)
		(stroke
			(width 0.08255)
			(type default)
		)
		(layer "In9.Cu")
	)
	(gr_line
		(start 263.325864 -120.14327)
		(end 263.264396 -119.995442)
		(stroke
			(width 0.08255)
			(type default)
		)
		(layer "In9.Cu")
	)
	(gr_line
		(start 263.349486 -127.667766)
		(end 263.349486 -127.667512)
		(stroke
			(width 0.08255)
			(type default)
		)
		(layer "In9.Cu")
	)
	(gr_line
		(start 263.351264 -127.66675)
		(end 263.465564 -127.619506)
		(stroke
			(width 0.08255)
			(type default)
		)
		(layer "In9.Cu")
	)
	(gr_line
		(start 263.380728 -103.628952)
		(end 263.540494 -103.628952)
		(stroke
			(width 0.08255)
			(type default)
		)
		(layer "In9.Cu")
	)
	(gr_line
		(start 263.380982 -114.34064)
		(end 263.319514 -114.192812)
		(stroke
			(width 0.08255)
			(type default)
		)
		(layer "In9.Cu")
	)
	(gr_line
		(start 263.387078 -124.784104)
		(end 263.51865 -124.730002)
		(stroke
			(width 0.08255)
			(type default)
		)
		(layer "In9.Cu")
	)
	(gr_line
		(start 263.397238 -108.385864)
		(end 263.396984 -108.385864)
		(stroke
			(width 0.08255)
			(type default)
		)
		(layer "In9.Cu")
	)
	(gr_line
		(start 263.454896 -119.535956)
		(end 263.602978 -119.474742)
		(stroke
			(width 0.08255)
			(type default)
		)
		(layer "In9.Cu")
	)
	(gr_line
		(start 263.465564 -127.619506)
		(end 263.655556 -127.161544)
		(stroke
			(width 0.08255)
			(type default)
		)
		(layer "In9.Cu")
	)
	(gr_line
		(start 263.510014 -113.733326)
		(end 263.658096 -113.672112)
		(stroke
			(width 0.08255)
			(type default)
		)
		(layer "In9.Cu")
	)
	(gr_line
		(start 263.51865 -124.730002)
		(end 263.703308 -124.283724)
		(stroke
			(width 0.08255)
			(type default)
		)
		(layer "In9.Cu")
	)
	(gr_line
		(start 263.536176 -126.480062)
		(end 263.793732 -125.858016)
		(stroke
			(width 0.08255)
			(type default)
		)
		(layer "In9.Cu")
	)
	(gr_line
		(start 263.540494 -103.628952)
		(end 263.882124 -103.287322)
		(stroke
			(width 0.08255)
			(type default)
		)
		(layer "In9.Cu")
	)
	(gr_line
		(start 263.602978 -119.474742)
		(end 263.792462 -119.01678)
		(stroke
			(width 0.08255)
			(type default)
		)
		(layer "In9.Cu")
	)
	(gr_line
		(start 263.616186 -105.05948)
		(end 263.616186 -104.917494)
		(stroke
			(width 0.08255)
			(type default)
		)
		(layer "In9.Cu")
	)
	(gr_line
		(start 263.655556 -127.161544)
		(end 263.607804 -127.04699)
		(stroke
			(width 0.08255)
			(type default)
		)
		(layer "In9.Cu")
	)
	(gr_line
		(start 263.658096 -113.672112)
		(end 263.84758 -113.21415)
		(stroke
			(width 0.08255)
			(type default)
		)
		(layer "In9.Cu")
	)
	(gr_line
		(start 263.659366 -118.302024)
		(end 263.93648 -117.632988)
		(stroke
			(width 0.08255)
			(type default)
		)
		(layer "In9.Cu")
	)
	(gr_line
		(start 263.703308 -124.283724)
		(end 263.648698 -124.15266)
		(stroke
			(width 0.08255)
			(type default)
		)
		(layer "In9.Cu")
	)
	(gr_line
		(start 263.70661 -138.41476)
		(end 263.429242 -137.745724)
		(stroke
			(width 0.08255)
			(type default)
		)
		(layer "In9.Cu")
	)
	(gr_line
		(start 263.714484 -112.499394)
		(end 263.991598 -111.830358)
		(stroke
			(width 0.08255)
			(type default)
		)
		(layer "In9.Cu")
	)
	(gr_line
		(start 263.721088 -107.663234)
		(end 264.215372 -107.16895)
		(stroke
			(width 0.08255)
			(type default)
		)
		(layer "In9.Cu")
	)
	(gr_line
		(start 263.766808 -104.366314)
		(end 264.261092 -103.87203)
		(stroke
			(width 0.08255)
			(type default)
		)
		(layer "In9.Cu")
	)
	(gr_line
		(start 263.792462 -119.01678)
		(end 263.730994 -118.868952)
		(stroke
			(width 0.08255)
			(type default)
		)
		(layer "In9.Cu")
	)
	(gr_line
		(start 263.79678 -126.588012)
		(end 263.796526 -126.588012)
		(stroke
			(width 0.08255)
			(type default)
		)
		(layer "In9.Cu")
	)
	(gr_line
		(start 263.798304 -126.58725)
		(end 263.912604 -126.540006)
		(stroke
			(width 0.08255)
			(type default)
		)
		(layer "In9.Cu")
	)
	(gr_line
		(start 263.832848 -123.705366)
		(end 263.832594 -123.705366)
		(stroke
			(width 0.08255)
			(type default)
		)
		(layer "In9.Cu")
	)
	(gr_line
		(start 263.834372 -123.704604)
		(end 263.96569 -123.650502)
		(stroke
			(width 0.08255)
			(type default)
		)
		(layer "In9.Cu")
	)
	(gr_line
		(start 263.839452 -137.69975)
		(end 263.69137 -137.638536)
		(stroke
			(width 0.08255)
			(type default)
		)
		(layer "In9.Cu")
	)
	(gr_line
		(start 263.84758 -113.21415)
		(end 263.786112 -113.066322)
		(stroke
			(width 0.08255)
			(type default)
		)
		(layer "In9.Cu")
	)
	(gr_line
		(start 263.882124 -103.287322)
		(end 263.882124 -103.127556)
		(stroke
			(width 0.08255)
			(type default)
		)
		(layer "In9.Cu")
	)
	(gr_line
		(start 263.912604 -126.540006)
		(end 264.102596 -126.082044)
		(stroke
			(width 0.08255)
			(type default)
		)
		(layer "In9.Cu")
	)
	(gr_line
		(start 263.921494 -118.409466)
		(end 264.069576 -118.348252)
		(stroke
			(width 0.08255)
			(type default)
		)
		(layer "In9.Cu")
	)
	(gr_line
		(start 263.922256 -107.862624)
		(end 264.064242 -107.862624)
		(stroke
			(width 0.08255)
			(type default)
		)
		(layer "In9.Cu")
	)
	(gr_line
		(start 263.96569 -123.650502)
		(end 264.150348 -123.204224)
		(stroke
			(width 0.08255)
			(type default)
		)
		(layer "In9.Cu")
	)
	(gr_line
		(start 263.967722 -138.30554)
		(end 264.028936 -138.157458)
		(stroke
			(width 0.08255)
			(type default)
		)
		(layer "In9.Cu")
	)
	(gr_line
		(start 263.967976 -104.565704)
		(end 264.109962 -104.565704)
		(stroke
			(width 0.08255)
			(type default)
		)
		(layer "In9.Cu")
	)
	(gr_line
		(start 263.976612 -112.606836)
		(end 264.124694 -112.545622)
		(stroke
			(width 0.08255)
			(type default)
		)
		(layer "In9.Cu")
	)
	(gr_line
		(start 263.983216 -125.400562)
		(end 264.241026 -124.778262)
		(stroke
			(width 0.08255)
			(type default)
		)
		(layer "In9.Cu")
	)
	(gr_line
		(start 264.023856 -102.585266)
		(end 264.52703 -102.082092)
		(stroke
			(width 0.08255)
			(type default)
		)
		(layer "In9.Cu")
	)
	(gr_line
		(start 264.028936 -138.157458)
		(end 263.839452 -137.69975)
		(stroke
			(width 0.08255)
			(type default)
		)
		(layer "In9.Cu")
	)
	(gr_line
		(start 264.064242 -107.862624)
		(end 264.414762 -107.512104)
		(stroke
			(width 0.08255)
			(type default)
		)
		(layer "In9.Cu")
	)
	(gr_line
		(start 264.069576 -118.348252)
		(end 264.25906 -117.89029)
		(stroke
			(width 0.08255)
			(type default)
		)
		(layer "In9.Cu")
	)
	(gr_line
		(start 264.102596 -126.082044)
		(end 264.055098 -125.96749)
		(stroke
			(width 0.08255)
			(type default)
		)
		(layer "In9.Cu")
	)
	(gr_line
		(start 264.109962 -104.565704)
		(end 264.460482 -104.215184)
		(stroke
			(width 0.08255)
			(type default)
		)
		(layer "In9.Cu")
	)
	(gr_line
		(start 264.124694 -112.545622)
		(end 264.314178 -112.08766)
		(stroke
			(width 0.08255)
			(type default)
		)
		(layer "In9.Cu")
	)
	(gr_line
		(start 264.125964 -117.175534)
		(end 264.403078 -116.506498)
		(stroke
			(width 0.08255)
			(type default)
		)
		(layer "In9.Cu")
	)
	(gr_line
		(start 264.150348 -123.204224)
		(end 264.095992 -123.07316)
		(stroke
			(width 0.08255)
			(type default)
		)
		(layer "In9.Cu")
	)
	(gr_line
		(start 264.173208 -139.54125)
		(end 263.896094 -138.872214)
		(stroke
			(width 0.08255)
			(type default)
		)
		(layer "In9.Cu")
	)
	(gr_line
		(start 264.181082 -111.372904)
		(end 264.458196 -110.703868)
		(stroke
			(width 0.08255)
			(type default)
		)
		(layer "In9.Cu")
	)
	(gr_line
		(start 264.225024 -102.784656)
		(end 264.38479 -102.784656)
		(stroke
			(width 0.08255)
			(type default)
		)
		(layer "In9.Cu")
	)
	(gr_line
		(start 264.24382 -125.508512)
		(end 264.24382 -125.508258)
		(stroke
			(width 0.08255)
			(type default)
		)
		(layer "In9.Cu")
	)
	(gr_line
		(start 264.245598 -125.507496)
		(end 264.359898 -125.460252)
		(stroke
			(width 0.08255)
			(type default)
		)
		(layer "In9.Cu")
	)
	(gr_line
		(start 264.25906 -117.89029)
		(end 264.197592 -117.742462)
		(stroke
			(width 0.08255)
			(type default)
		)
		(layer "In9.Cu")
	)
	(gr_line
		(start 264.267696 -131.484624)
		(end 264.670032 -130.882644)
		(stroke
			(width 0.08255)
			(type default)
		)
		(layer "In9.Cu")
	)
	(gr_line
		(start 264.281412 -122.625104)
		(end 264.41273 -122.571002)
		(stroke
			(width 0.08255)
			(type default)
		)
		(layer "In9.Cu")
	)
	(gr_line
		(start 264.306304 -138.82624)
		(end 264.157968 -138.764772)
		(stroke
			(width 0.08255)
			(type default)
		)
		(layer "In9.Cu")
	)
	(gr_line
		(start 264.314178 -112.08766)
		(end 264.252964 -111.939832)
		(stroke
			(width 0.08255)
			(type default)
		)
		(layer "In9.Cu")
	)
	(gr_line
		(start 264.359898 -125.460252)
		(end 264.54989 -125.00229)
		(stroke
			(width 0.08255)
			(type default)
		)
		(layer "In9.Cu")
	)
	(gr_line
		(start 264.38479 -102.784656)
		(end 264.72642 -102.443026)
		(stroke
			(width 0.08255)
			(type default)
		)
		(layer "In9.Cu")
	)
	(gr_line
		(start 264.388092 -117.282976)
		(end 264.536174 -117.221762)
		(stroke
			(width 0.08255)
			(type default)
		)
		(layer "In9.Cu")
	)
	(gr_line
		(start 264.41273 -122.571002)
		(end 264.597388 -122.124724)
		(stroke
			(width 0.08255)
			(type default)
		)
		(layer "In9.Cu")
	)
	(gr_line
		(start 264.414762 -107.512104)
		(end 264.414762 -107.370118)
		(stroke
			(width 0.08255)
			(type default)
		)
		(layer "In9.Cu")
	)
	(gr_line
		(start 264.43051 -124.320808)
		(end 264.68832 -123.698508)
		(stroke
			(width 0.08255)
			(type default)
		)
		(layer "In9.Cu")
	)
	(gr_line
		(start 264.43432 -139.43203)
		(end 264.495788 -139.283948)
		(stroke
			(width 0.08255)
			(type default)
		)
		(layer "In9.Cu")
	)
	(gr_line
		(start 264.44321 -111.480092)
		(end 264.591292 -111.419132)
		(stroke
			(width 0.08255)
			(type default)
		)
		(layer "In9.Cu")
	)
	(gr_line
		(start 264.460482 -104.215184)
		(end 264.460482 -104.073198)
		(stroke
			(width 0.08255)
			(type default)
		)
		(layer "In9.Cu")
	)
	(gr_line
		(start 264.495788 -139.283948)
		(end 264.306304 -138.82624)
		(stroke
			(width 0.08255)
			(type default)
		)
		(layer "In9.Cu")
	)
	(gr_line
		(start 264.503662 -131.641088)
		(end 264.660634 -131.609846)
		(stroke
			(width 0.08255)
			(type default)
		)
		(layer "In9.Cu")
	)
	(gr_line
		(start 264.536174 -117.221762)
		(end 264.725658 -116.7638)
		(stroke
			(width 0.08255)
			(type default)
		)
		(layer "In9.Cu")
	)
	(gr_line
		(start 264.54989 -125.00229)
		(end 264.502392 -124.887736)
		(stroke
			(width 0.08255)
			(type default)
		)
		(layer "In9.Cu")
	)
	(gr_line
		(start 264.565384 -106.818938)
		(end 265.077702 -106.30662)
		(stroke
			(width 0.08255)
			(type default)
		)
		(layer "In9.Cu")
	)
	(gr_line
		(start 264.591292 -111.419132)
		(end 264.780776 -110.96117)
		(stroke
			(width 0.08255)
			(type default)
		)
		(layer "In9.Cu")
	)
	(gr_line
		(start 264.592562 -116.049044)
		(end 264.869676 -115.380008)
		(stroke
			(width 0.08255)
			(type default)
		)
		(layer "In9.Cu")
	)
	(gr_line
		(start 264.597388 -122.124724)
		(end 264.543032 -121.99366)
		(stroke
			(width 0.08255)
			(type default)
		)
		(layer "In9.Cu")
	)
	(gr_line
		(start 264.611104 -103.522018)
		(end 265.07821 -103.054912)
		(stroke
			(width 0.08255)
			(type default)
		)
		(layer "In9.Cu")
	)
	(gr_line
		(start 264.639806 -140.66774)
		(end 264.362692 -139.998704)
		(stroke
			(width 0.08255)
			(type default)
		)
		(layer "In9.Cu")
	)
	(gr_line
		(start 264.660634 -131.609846)
		(end 264.93597 -131.197858)
		(stroke
			(width 0.08255)
			(type default)
		)
		(layer "In9.Cu")
	)
	(gr_line
		(start 264.691114 -124.428758)
		(end 264.691114 -124.428504)
		(stroke
			(width 0.08255)
			(type default)
		)
		(layer "In9.Cu")
	)
	(gr_line
		(start 264.692892 -124.427742)
		(end 264.807192 -124.380498)
		(stroke
			(width 0.08255)
			(type default)
		)
		(layer "In9.Cu")
	)
	(gr_line
		(start 264.725658 -116.7638)
		(end 264.66419 -116.615972)
		(stroke
			(width 0.08255)
			(type default)
		)
		(layer "In9.Cu")
	)
	(gr_line
		(start 264.72642 -102.443026)
		(end 264.72642 -102.28326)
		(stroke
			(width 0.08255)
			(type default)
		)
		(layer "In9.Cu")
	)
	(gr_line
		(start 264.766552 -107.018328)
		(end 264.926572 -107.018328)
		(stroke
			(width 0.08255)
			(type default)
		)
		(layer "In9.Cu")
	)
	(gr_line
		(start 264.772902 -139.95273)
		(end 264.624566 -139.891262)
		(stroke
			(width 0.08255)
			(type default)
		)
		(layer "In9.Cu")
	)
	(gr_line
		(start 264.780776 -110.96117)
		(end 264.719562 -110.813342)
		(stroke
			(width 0.08255)
			(type default)
		)
		(layer "In9.Cu")
	)
	(gr_line
		(start 264.807192 -124.380498)
		(end 264.99693 -123.92279)
		(stroke
			(width 0.08255)
			(type default)
		)
		(layer "In9.Cu")
	)
	(gr_line
		(start 264.812272 -103.721408)
		(end 264.93597 -103.721408)
		(stroke
			(width 0.08255)
			(type default)
		)
		(layer "In9.Cu")
	)
	(gr_line
		(start 264.85469 -116.156486)
		(end 265.002772 -116.095272)
		(stroke
			(width 0.08255)
			(type default)
		)
		(layer "In9.Cu")
	)
	(gr_line
		(start 264.868152 -101.74097)
		(end 265.371072 -101.23805)
		(stroke
			(width 0.08255)
			(type default)
		)
		(layer "In9.Cu")
	)
	(gr_line
		(start 264.900918 -140.558266)
		(end 264.962386 -140.410438)
		(stroke
			(width 0.08255)
			(type default)
		)
		(layer "In9.Cu")
	)
	(gr_line
		(start 264.926572 -107.018328)
		(end 265.277092 -106.667808)
		(stroke
			(width 0.08255)
			(type default)
		)
		(layer "In9.Cu")
	)
	(gr_line
		(start 264.93597 -131.197858)
		(end 264.904728 -131.040886)
		(stroke
			(width 0.08255)
			(type default)
		)
		(layer "In9.Cu")
	)
	(gr_line
		(start 264.93597 -103.721408)
		(end 265.2776 -103.380032)
		(stroke
			(width 0.08255)
			(type default)
		)
		(layer "In9.Cu")
	)
	(gr_line
		(start 264.945114 -130.47091)
		(end 265.347196 -129.86893)
		(stroke
			(width 0.08255)
			(type default)
		)
		(layer "In9.Cu")
	)
	(gr_line
		(start 264.962386 -140.410438)
		(end 264.772902 -139.95273)
		(stroke
			(width 0.08255)
			(type default)
		)
		(layer "In9.Cu")
	)
	(gr_line
		(start 264.99693 -123.92279)
		(end 264.949432 -123.807982)
		(stroke
			(width 0.08255)
			(type default)
		)
		(layer "In9.Cu")
	)
	(gr_line
		(start 265.002772 -116.095272)
		(end 265.192256 -115.63731)
		(stroke
			(width 0.08255)
			(type default)
		)
		(layer "In9.Cu")
	)
	(gr_line
		(start 265.05916 -114.922554)
		(end 265.336274 -114.253518)
		(stroke
			(width 0.08255)
			(type default)
		)
		(layer "In9.Cu")
	)
	(gr_line
		(start 265.06932 -101.94036)
		(end 265.229086 -101.94036)
		(stroke
			(width 0.08255)
			(type default)
		)
		(layer "In9.Cu")
	)
	(gr_line
		(start 265.086846 -141.74724)
		(end 264.82929 -141.125194)
		(stroke
			(width 0.08255)
			(type default)
		)
		(layer "In9.Cu")
	)
	(gr_line
		(start 265.18108 -130.627374)
		(end 265.338052 -130.596132)
		(stroke
			(width 0.08255)
			(type default)
		)
		(layer "In9.Cu")
	)
	(gr_line
		(start 265.192256 -115.63731)
		(end 265.131042 -115.489482)
		(stroke
			(width 0.08255)
			(type default)
		)
		(layer "In9.Cu")
	)
	(gr_line
		(start 265.205972 -141.06525)
		(end 265.091418 -141.017752)
		(stroke
			(width 0.08255)
			(type default)
		)
		(layer "In9.Cu")
	)
	(gr_line
		(start 265.229086 -101.94036)
		(end 265.570462 -101.598984)
		(stroke
			(width 0.08255)
			(type default)
		)
		(layer "In9.Cu")
	)
	(gr_line
		(start 265.277092 -106.667808)
		(end 265.277092 -106.507788)
		(stroke
			(width 0.08255)
			(type default)
		)
		(layer "In9.Cu")
	)
	(gr_line
		(start 265.2776 -103.380032)
		(end 265.2776 -103.25608)
		(stroke
			(width 0.08255)
			(type default)
		)
		(layer "In9.Cu")
	)
	(gr_line
		(start 265.321288 -115.029742)
		(end 265.46937 -114.968782)
		(stroke
			(width 0.08255)
			(type default)
		)
		(layer "In9.Cu")
	)
	(gr_line
		(start 265.328654 -120.868694)
		(end 265.48842 -120.868694)
		(stroke
			(width 0.08255)
			(type default)
		)
		(layer "In9.Cu")
	)
	(gr_line
		(start 265.338052 -130.596132)
		(end 265.613388 -130.184144)
		(stroke
			(width 0.08255)
			(type default)
		)
		(layer "In9.Cu")
	)
	(gr_line
		(start 265.348212 -141.63802)
		(end 265.39571 -141.523212)
		(stroke
			(width 0.08255)
			(type default)
		)
		(layer "In9.Cu")
	)
	(gr_line
		(start 265.368532 -109.495336)
		(end 265.828526 -109.035342)
		(stroke
			(width 0.08255)
			(type default)
		)
		(layer "In9.Cu")
	)
	(gr_line
		(start 265.39571 -141.523212)
		(end 265.205972 -141.06525)
		(stroke
			(width 0.08255)
			(type default)
		)
		(layer "In9.Cu")
	)
	(gr_line
		(start 265.419332 -102.71379)
		(end 265.886692 -102.24643)
		(stroke
			(width 0.08255)
			(type default)
		)
		(layer "In9.Cu")
	)
	(gr_line
		(start 265.427714 -105.956608)
		(end 265.940032 -105.44429)
		(stroke
			(width 0.08255)
			(type default)
		)
		(layer "In9.Cu")
	)
	(gr_line
		(start 265.46937 -114.968782)
		(end 265.658854 -114.51082)
		(stroke
			(width 0.08255)
			(type default)
		)
		(layer "In9.Cu")
	)
	(gr_line
		(start 265.47191 -122.386852)
		(end 265.966194 -121.892568)
		(stroke
			(width 0.08255)
			(type default)
		)
		(layer "In9.Cu")
	)
	(gr_line
		(start 265.48842 -120.868694)
		(end 265.829796 -120.527318)
		(stroke
			(width 0.08255)
			(type default)
		)
		(layer "In9.Cu")
	)
	(gr_line
		(start 265.525758 -113.796064)
		(end 265.802872 -113.127028)
		(stroke
			(width 0.08255)
			(type default)
		)
		(layer "In9.Cu")
	)
	(gr_line
		(start 265.5697 -109.694726)
		(end 265.686286 -109.694726)
		(stroke
			(width 0.08255)
			(type default)
		)
		(layer "In9.Cu")
	)
	(gr_line
		(start 265.570462 -101.598984)
		(end 265.570462 -101.439218)
		(stroke
			(width 0.08255)
			(type default)
		)
		(layer "In9.Cu")
	)
	(gr_line
		(start 265.613388 -130.184144)
		(end 265.582146 -130.027172)
		(stroke
			(width 0.08255)
			(type default)
		)
		(layer "In9.Cu")
	)
	(gr_line
		(start 265.6205 -102.91318)
		(end 265.744452 -102.91318)
		(stroke
			(width 0.08255)
			(type default)
		)
		(layer "In9.Cu")
	)
	(gr_line
		(start 265.622532 -129.457196)
		(end 266.024868 -128.854962)
		(stroke
			(width 0.08255)
			(type default)
		)
		(layer "In9.Cu")
	)
	(gr_line
		(start 265.628882 -106.155998)
		(end 265.788902 -106.155998)
		(stroke
			(width 0.08255)
			(type default)
		)
		(layer "In9.Cu")
	)
	(gr_line
		(start 265.658854 -114.51082)
		(end 265.59764 -114.362992)
		(stroke
			(width 0.08255)
			(type default)
		)
		(layer "In9.Cu")
	)
	(gr_line
		(start 265.673078 -122.586242)
		(end 265.815064 -122.586242)
		(stroke
			(width 0.08255)
			(type default)
		)
		(layer "In9.Cu")
	)
	(gr_line
		(start 265.686286 -109.694726)
		(end 266.027916 -109.35335)
		(stroke
			(width 0.08255)
			(type default)
		)
		(layer "In9.Cu")
	)
	(gr_line
		(start 265.744452 -102.91318)
		(end 266.086082 -102.57155)
		(stroke
			(width 0.08255)
			(type default)
		)
		(layer "In9.Cu")
	)
	(gr_line
		(start 265.787886 -113.903252)
		(end 265.935968 -113.842292)
		(stroke
			(width 0.08255)
			(type default)
		)
		(layer "In9.Cu")
	)
	(gr_line
		(start 265.788902 -106.155998)
		(end 266.139422 -105.805478)
		(stroke
			(width 0.08255)
			(type default)
		)
		(layer "In9.Cu")
	)
	(gr_line
		(start 265.815064 -122.586242)
		(end 266.165584 -122.235722)
		(stroke
			(width 0.08255)
			(type default)
		)
		(layer "In9.Cu")
	)
	(gr_line
		(start 265.829796 -120.527318)
		(end 265.829796 -120.367552)
		(stroke
			(width 0.08255)
			(type default)
		)
		(layer "In9.Cu")
	)
	(gr_line
		(start 265.858498 -129.61366)
		(end 266.01547 -129.582164)
		(stroke
			(width 0.08255)
			(type default)
		)
		(layer "In9.Cu")
	)
	(gr_line
		(start 265.935968 -113.842292)
		(end 266.125452 -113.38433)
		(stroke
			(width 0.08255)
			(type default)
		)
		(layer "In9.Cu")
	)
	(gr_line
		(start 266.01547 -129.582164)
		(end 266.290806 -129.170176)
		(stroke
			(width 0.08255)
			(type default)
		)
		(layer "In9.Cu")
	)
	(gr_line
		(start 266.027916 -109.35335)
		(end 266.027916 -109.23651)
		(stroke
			(width 0.08255)
			(type default)
		)
		(layer "In9.Cu")
	)
	(gr_line
		(start 266.086082 -102.57155)
		(end 266.086082 -102.447598)
		(stroke
			(width 0.08255)
			(type default)
		)
		(layer "In9.Cu")
	)
	(gr_line
		(start 266.125452 -113.38433)
		(end 266.064238 -113.236502)
		(stroke
			(width 0.08255)
			(type default)
		)
		(layer "In9.Cu")
	)
	(gr_line
		(start 266.139422 -105.805478)
		(end 266.139422 -105.645458)
		(stroke
			(width 0.08255)
			(type default)
		)
		(layer "In9.Cu")
	)
	(gr_line
		(start 266.165584 -122.235722)
		(end 266.165584 -122.093736)
		(stroke
			(width 0.08255)
			(type default)
		)
		(layer "In9.Cu")
	)
	(gr_line
		(start 266.290806 -129.170176)
		(end 266.259564 -129.013458)
		(stroke
			(width 0.08255)
			(type default)
		)
		(layer "In9.Cu")
	)
	(gr_line
		(start 266.29995 -128.443228)
		(end 266.638786 -127.936244)
		(stroke
			(width 0.08255)
			(type default)
		)
		(layer "In9.Cu")
	)
	(gr_line
		(start 266.489942 -139.189968)
		(end 266.212828 -138.520932)
		(stroke
			(width 0.08255)
			(type default)
		)
		(layer "In9.Cu")
	)
	(gr_line
		(start 266.53617 -128.599692)
		(end 266.657582 -128.575562)
		(stroke
			(width 0.08255)
			(type default)
		)
		(layer "In9.Cu")
	)
	(gr_line
		(start 266.622784 -138.474704)
		(end 266.474956 -138.413744)
		(stroke
			(width 0.08255)
			(type default)
		)
		(layer "In9.Cu")
	)
	(gr_line
		(start 266.657582 -128.575562)
		(end 266.897866 -128.216152)
		(stroke
			(width 0.08255)
			(type default)
		)
		(layer "In9.Cu")
	)
	(gr_line
		(start 266.751054 -139.080494)
		(end 266.812268 -138.932666)
		(stroke
			(width 0.08255)
			(type default)
		)
		(layer "In9.Cu")
	)
	(gr_line
		(start 266.812268 -138.932666)
		(end 266.622784 -138.474704)
		(stroke
			(width 0.08255)
			(type default)
		)
		(layer "In9.Cu")
	)
	(gr_line
		(start 266.897866 -128.216152)
		(end 266.873482 -128.094486)
		(stroke
			(width 0.08255)
			(type default)
		)
		(layer "In9.Cu")
	)
	(gr_line
		(start 266.899898 -127.545338)
		(end 266.906502 -127.535432)
		(stroke
			(width 0.08255)
			(type default)
		)
		(layer "In9.Cu")
	)
	(gr_line
		(start 266.906502 -127.535432)
		(end 267.245592 -127.028194)
		(stroke
			(width 0.08255)
			(type default)
		)
		(layer "In9.Cu")
	)
	(gr_line
		(start 266.95654 -140.316458)
		(end 266.679426 -139.647422)
		(stroke
			(width 0.08255)
			(type default)
		)
		(layer "In9.Cu")
	)
	(gr_line
		(start 267.034772 -119.797068)
		(end 267.325602 -120.087898)
		(stroke
			(width 0.08255)
			(type default)
		)
		(layer "In9.Cu")
	)
	(gr_line
		(start 267.034772 -112.493552)
		(end 267.325602 -112.784382)
		(stroke
			(width 0.08255)
			(type default)
		)
		(layer "In9.Cu")
	)
	(gr_line
		(start 267.034772 -112.211612)
		(end 267.325602 -111.920782)
		(stroke
			(width 0.08255)
			(type default)
		)
		(layer "In9.Cu")
	)
	(gr_line
		(start 267.034772 -108.89361)
		(end 267.325602 -109.18444)
		(stroke
			(width 0.08255)
			(type default)
		)
		(layer "In9.Cu")
	)
	(gr_line
		(start 267.034772 -108.61167)
		(end 267.325602 -108.32084)
		(stroke
			(width 0.08255)
			(type default)
		)
		(layer "In9.Cu")
	)
	(gr_line
		(start 267.034772 -105.293668)
		(end 267.325602 -105.584498)
		(stroke
			(width 0.08255)
			(type default)
		)
		(layer "In9.Cu")
	)
	(gr_line
		(start 267.034772 -105.011728)
		(end 267.325602 -104.720898)
		(stroke
			(width 0.08255)
			(type default)
		)
		(layer "In9.Cu")
	)
	(gr_line
		(start 267.089636 -139.601448)
		(end 266.941554 -139.53998)
		(stroke
			(width 0.08255)
			(type default)
		)
		(layer "In9.Cu")
	)
	(gr_line
		(start 267.142722 -127.691896)
		(end 267.264388 -127.667512)
		(stroke
			(width 0.08255)
			(type default)
		)
		(layer "In9.Cu")
	)
	(gr_line
		(start 267.217906 -140.207238)
		(end 267.27912 -140.059156)
		(stroke
			(width 0.08255)
			(type default)
		)
		(layer "In9.Cu")
	)
	(gr_line
		(start 267.264388 -127.667512)
		(end 267.504418 -127.308356)
		(stroke
			(width 0.08255)
			(type default)
		)
		(layer "In9.Cu")
	)
	(gr_line
		(start 267.27912 -140.059156)
		(end 267.089636 -139.601448)
		(stroke
			(width 0.08255)
			(type default)
		)
		(layer "In9.Cu")
	)
	(gr_line
		(start 267.301726 -100.08362)
		(end 267.959078 -99.811078)
		(stroke
			(width 0.08255)
			(type default)
		)
		(layer "In9.Cu")
	)
	(gr_line
		(start 267.325602 -121.321576)
		(end 267.909802 -121.321576)
		(stroke
			(width 0.08255)
			(type default)
		)
		(layer "In9.Cu")
	)
	(gr_line
		(start 267.326872 -121.604786)
		(end 267.414502 -121.692416)
		(stroke
			(width 0.08255)
			(type default)
		)
		(layer "In9.Cu")
	)
	(gr_line
		(start 267.339064 -300.284388)
		(end 267.354558 -300.268894)
		(stroke
			(width 0.04445)
			(type default)
		)
		(layer "In9.Cu")
	)
	(gr_line
		(start 267.354558 -300.268894)
		(end 267.452602 -300.268894)
		(stroke
			(width 0.04445)
			(type default)
		)
		(layer "In9.Cu")
	)
	(gr_line
		(start 267.410946 -100.344732)
		(end 267.559028 -100.4062)
		(stroke
			(width 0.08255)
			(type default)
		)
		(layer "In9.Cu")
	)
	(gr_line
		(start 267.414502 -121.692416)
		(end 267.820902 -121.692416)
		(stroke
			(width 0.08255)
			(type default)
		)
		(layer "In9.Cu")
	)
	(gr_line
		(start 267.452602 -300.268894)
		(end 267.453364 -300.268386)
		(stroke
			(width 0.04445)
			(type default)
		)
		(layer "In9.Cu")
	)
	(gr_line
		(start 267.504418 -127.308356)
		(end 267.480288 -127.186436)
		(stroke
			(width 0.08255)
			(type default)
		)
		(layer "In9.Cu")
	)
	(gr_line
		(start 267.559028 -100.4062)
		(end 268.005306 -100.221542)
		(stroke
			(width 0.08255)
			(type default)
		)
		(layer "In9.Cu")
	)
	(gr_line
		(start 267.644372 -101.693472)
		(end 267.935202 -101.984302)
		(stroke
			(width 0.08255)
			(type default)
		)
		(layer "In9.Cu")
	)
	(gr_line
		(start 267.644372 -101.411532)
		(end 267.935202 -101.120702)
		(stroke
			(width 0.08255)
			(type default)
		)
		(layer "In9.Cu")
	)
	(gr_line
		(start 267.675614 -143.914368)
		(end 267.640054 -143.19123)
		(stroke
			(width 0.08255)
			(type default)
		)
		(layer "In9.Cu")
	)
	(gr_line
		(start 267.736828 -145.15846)
		(end 267.701268 -144.435322)
		(stroke
			(width 0.08255)
			(type default)
		)
		(layer "In9.Cu")
	)
	(gr_line
		(start 267.796772 -146.37639)
		(end 267.761212 -145.652998)
		(stroke
			(width 0.08255)
			(type default)
		)
		(layer "In9.Cu")
	)
	(gr_line
		(start 267.820902 -121.692416)
		(end 267.908532 -121.604786)
		(stroke
			(width 0.08255)
			(type default)
		)
		(layer "In9.Cu")
	)
	(gr_line
		(start 267.856716 -147.59432)
		(end 267.821156 -146.870928)
		(stroke
			(width 0.08255)
			(type default)
		)
		(layer "In9.Cu")
	)
	(gr_line
		(start 267.91666 -148.812504)
		(end 267.8811 -148.088858)
		(stroke
			(width 0.08255)
			(type default)
		)
		(layer "In9.Cu")
	)
	(gr_line
		(start 267.95857 -143.899636)
		(end 268.066266 -143.781018)
		(stroke
			(width 0.08255)
			(type default)
		)
		(layer "In9.Cu")
	)
	(gr_line
		(start 268.005306 -100.221542)
		(end 268.06652 -100.073206)
		(stroke
			(width 0.08255)
			(type default)
		)
		(layer "In9.Cu")
	)
	(gr_line
		(start 268.019784 -145.143728)
		(end 268.12748 -145.02511)
		(stroke
			(width 0.08255)
			(type default)
		)
		(layer "In9.Cu")
	)
	(gr_line
		(start 268.041882 -143.285972)
		(end 267.92301 -143.178784)
		(stroke
			(width 0.08255)
			(type default)
		)
		(layer "In9.Cu")
	)
	(gr_line
		(start 268.049502 -132.531612)
		(end 268.760702 -132.531612)
		(stroke
			(width 0.08255)
			(type default)
		)
		(layer "In9.Cu")
	)
	(gr_line
		(start 268.050772 -132.814822)
		(end 268.163802 -132.927852)
		(stroke
			(width 0.08255)
			(type default)
		)
		(layer "In9.Cu")
	)
	(gr_line
		(start 268.066266 -143.781018)
		(end 268.041882 -143.285972)
		(stroke
			(width 0.08255)
			(type default)
		)
		(layer "In9.Cu")
	)
	(gr_line
		(start 268.079728 -146.361658)
		(end 268.187424 -146.242786)
		(stroke
			(width 0.08255)
			(type default)
		)
		(layer "In9.Cu")
	)
	(gr_line
		(start 268.103096 -144.530064)
		(end 267.984224 -144.422876)
		(stroke
			(width 0.08255)
			(type default)
		)
		(layer "In9.Cu")
	)
	(gr_line
		(start 268.12748 -145.02511)
		(end 268.103096 -144.530064)
		(stroke
			(width 0.08255)
			(type default)
		)
		(layer "In9.Cu")
	)
	(gr_line
		(start 268.139672 -147.579588)
		(end 268.247368 -147.460716)
		(stroke
			(width 0.08255)
			(type default)
		)
		(layer "In9.Cu")
	)
	(gr_line
		(start 268.16304 -145.74774)
		(end 268.044168 -145.640298)
		(stroke
			(width 0.08255)
			(type default)
		)
		(layer "In9.Cu")
	)
	(gr_line
		(start 268.163802 -132.927852)
		(end 268.646402 -132.927852)
		(stroke
			(width 0.08255)
			(type default)
		)
		(layer "In9.Cu")
	)
	(gr_line
		(start 268.187424 -146.242786)
		(end 268.16304 -145.74774)
		(stroke
			(width 0.08255)
			(type default)
		)
		(layer "In9.Cu")
	)
	(gr_line
		(start 268.199362 -148.797518)
		(end 268.307312 -148.678646)
		(stroke
			(width 0.08255)
			(type default)
		)
		(layer "In9.Cu")
	)
	(gr_line
		(start 268.222984 -146.965924)
		(end 268.104112 -146.858228)
		(stroke
			(width 0.08255)
			(type default)
		)
		(layer "In9.Cu")
	)
	(gr_line
		(start 268.247368 -147.460716)
		(end 268.222984 -146.965924)
		(stroke
			(width 0.08255)
			(type default)
		)
		(layer "In9.Cu")
	)
	(gr_line
		(start 268.282928 -148.183854)
		(end 268.164056 -148.076158)
		(stroke
			(width 0.08255)
			(type default)
		)
		(layer "In9.Cu")
	)
	(gr_line
		(start 268.307312 -148.678646)
		(end 268.282928 -148.183854)
		(stroke
			(width 0.08255)
			(type default)
		)
		(layer "In9.Cu")
	)
	(gr_line
		(start 268.316202 -121.321576)
		(end 268.900402 -121.321576)
		(stroke
			(width 0.08255)
			(type default)
		)
		(layer "In9.Cu")
	)
	(gr_line
		(start 268.317472 -121.604786)
		(end 268.405102 -121.692416)
		(stroke
			(width 0.08255)
			(type default)
		)
		(layer "In9.Cu")
	)
	(gr_line
		(start 268.405102 -121.692416)
		(end 268.811502 -121.692416)
		(stroke
			(width 0.08255)
			(type default)
		)
		(layer "In9.Cu")
	)
	(gr_line
		(start 268.646402 -132.927852)
		(end 268.759432 -132.814822)
		(stroke
			(width 0.08255)
			(type default)
		)
		(layer "In9.Cu")
	)
	(gr_line
		(start 268.811502 -121.692416)
		(end 268.899132 -121.604786)
		(stroke
			(width 0.08255)
			(type default)
		)
		(layer "In9.Cu")
	)
	(gr_line
		(start 269.352014 -137.480802)
		(end 269.210282 -137.480802)
		(stroke
			(width 0.08255)
			(type default)
		)
		(layer "In9.Cu")
	)
	(gr_line
		(start 269.494254 -138.165332)
		(end 269.009114 -137.680192)
		(stroke
			(width 0.08255)
			(type default)
		)
		(layer "In9.Cu")
	)
	(gr_line
		(start 269.67688 -136.413494)
		(end 269.96771 -136.704324)
		(stroke
			(width 0.08255)
			(type default)
		)
		(layer "In9.Cu")
	)
	(gr_line
		(start 269.67688 -136.131554)
		(end 269.96771 -135.840724)
		(stroke
			(width 0.08255)
			(type default)
		)
		(layer "In9.Cu")
	)
	(gr_line
		(start 269.67688 -132.813552)
		(end 269.96771 -133.104382)
		(stroke
			(width 0.08255)
			(type default)
		)
		(layer "In9.Cu")
	)
	(gr_line
		(start 269.67688 -132.531612)
		(end 269.96771 -132.240782)
		(stroke
			(width 0.08255)
			(type default)
		)
		(layer "In9.Cu")
	)
	(gr_line
		(start 269.67688 -125.203712)
		(end 269.96771 -125.494542)
		(stroke
			(width 0.08255)
			(type default)
		)
		(layer "In9.Cu")
	)
	(gr_line
		(start 269.67688 -124.921772)
		(end 269.96771 -124.630942)
		(stroke
			(width 0.08255)
			(type default)
		)
		(layer "In9.Cu")
	)
	(gr_line
		(start 269.67688 -121.603516)
		(end 269.96771 -121.894346)
		(stroke
			(width 0.08255)
			(type default)
		)
		(layer "In9.Cu")
	)
	(gr_line
		(start 269.67688 -121.321576)
		(end 269.96771 -121.030746)
		(stroke
			(width 0.08255)
			(type default)
		)
		(layer "In9.Cu")
	)
	(gr_line
		(start 269.67688 -99.887024)
		(end 269.96771 -100.177854)
		(stroke
			(width 0.08255)
			(type default)
		)
		(layer "In9.Cu")
	)
	(gr_line
		(start 269.67688 -99.605084)
		(end 269.96771 -99.314254)
		(stroke
			(width 0.08255)
			(type default)
		)
		(layer "In9.Cu")
	)
	(gr_line
		(start 269.693644 -137.964164)
		(end 269.693644 -137.822178)
		(stroke
			(width 0.08255)
			(type default)
		)
		(layer "In9.Cu")
	)
	(gr_line
		(start 269.693644 -137.822178)
		(end 269.352014 -137.480802)
		(stroke
			(width 0.08255)
			(type default)
		)
		(layer "In9.Cu")
	)
	(gr_line
		(start 270.451072 -140.656056)
		(end 270.317468 -139.98321)
		(stroke
			(width 0.08255)
			(type default)
		)
		(layer "In9.Cu")
	)
	(gr_line
		(start 270.683736 -141.826996)
		(end 270.547592 -141.141704)
		(stroke
			(width 0.08255)
			(type default)
		)
		(layer "In9.Cu")
	)
	(gr_line
		(start 270.713708 -140.008102)
		(end 270.595598 -139.929362)
		(stroke
			(width 0.08255)
			(type default)
		)
		(layer "In9.Cu")
	)
	(gr_line
		(start 270.728694 -140.600176)
		(end 270.807688 -140.481812)
		(stroke
			(width 0.08255)
			(type default)
		)
		(layer "In9.Cu")
	)
	(gr_line
		(start 270.807688 -140.481812)
		(end 270.713708 -140.008102)
		(stroke
			(width 0.08255)
			(type default)
		)
		(layer "In9.Cu")
	)
	(gr_line
		(start 270.916146 -142.997936)
		(end 270.780002 -142.312644)
		(stroke
			(width 0.08255)
			(type default)
		)
		(layer "In9.Cu")
	)
	(gr_line
		(start 270.944086 -141.16685)
		(end 270.825468 -141.087856)
		(stroke
			(width 0.08255)
			(type default)
		)
		(layer "In9.Cu")
	)
	(gr_line
		(start 270.961358 -141.771116)
		(end 271.040352 -141.652752)
		(stroke
			(width 0.08255)
			(type default)
		)
		(layer "In9.Cu")
	)
	(gr_line
		(start 271.040352 -141.652752)
		(end 270.944086 -141.16685)
		(stroke
			(width 0.08255)
			(type default)
		)
		(layer "In9.Cu")
	)
	(gr_line
		(start 271.14881 -144.168876)
		(end 271.012666 -143.483584)
		(stroke
			(width 0.08255)
			(type default)
		)
		(layer "In9.Cu")
	)
	(gr_line
		(start 271.17675 -142.33779)
		(end 271.058132 -142.258542)
		(stroke
			(width 0.08255)
			(type default)
		)
		(layer "In9.Cu")
	)
	(gr_line
		(start 271.193768 -142.942056)
		(end 271.273016 -142.823692)
		(stroke
			(width 0.08255)
			(type default)
		)
		(layer "In9.Cu")
	)
	(gr_line
		(start 271.273016 -142.823692)
		(end 271.17675 -142.33779)
		(stroke
			(width 0.08255)
			(type default)
		)
		(layer "In9.Cu")
	)
	(gr_line
		(start 271.38122 -145.339816)
		(end 271.24533 -144.654524)
		(stroke
			(width 0.08255)
			(type default)
		)
		(layer "In9.Cu")
	)
	(gr_line
		(start 271.409414 -143.50873)
		(end 271.290542 -143.429482)
		(stroke
			(width 0.08255)
			(type default)
		)
		(layer "In9.Cu")
	)
	(gr_line
		(start 271.426432 -144.11325)
		(end 271.50568 -143.994632)
		(stroke
			(width 0.08255)
			(type default)
		)
		(layer "In9.Cu")
	)
	(gr_line
		(start 271.50568 -143.994632)
		(end 271.409414 -143.50873)
		(stroke
			(width 0.08255)
			(type default)
		)
		(layer "In9.Cu")
	)
	(gr_line
		(start 271.613884 -146.510756)
		(end 271.47774 -145.825464)
		(stroke
			(width 0.08255)
			(type default)
		)
		(layer "In9.Cu")
	)
	(gr_line
		(start 271.642078 -144.67967)
		(end 271.523206 -144.600422)
		(stroke
			(width 0.08255)
			(type default)
		)
		(layer "In9.Cu")
	)
	(gr_line
		(start 271.659096 -145.28419)
		(end 271.738344 -145.165572)
		(stroke
			(width 0.08255)
			(type default)
		)
		(layer "In9.Cu")
	)
	(gr_line
		(start 271.715738 -299.224954)
		(end 271.424908 -299.224954)
		(stroke
			(width 0.04445)
			(type default)
		)
		(layer "In9.Cu")
	)
	(gr_line
		(start 271.738344 -145.165572)
		(end 271.642078 -144.67967)
		(stroke
			(width 0.08255)
			(type default)
		)
		(layer "In9.Cu")
	)
	(gr_line
		(start 271.804638 -299.313854)
		(end 271.715738 -299.224954)
		(stroke
			(width 0.04445)
			(type default)
		)
		(layer "In9.Cu")
	)
	(gr_line
		(start 271.846548 -147.68195)
		(end 271.710404 -146.996404)
		(stroke
			(width 0.08255)
			(type default)
		)
		(layer "In9.Cu")
	)
	(gr_line
		(start 271.874742 -145.85061)
		(end 271.755616 -145.771108)
		(stroke
			(width 0.08255)
			(type default)
		)
		(layer "In9.Cu")
	)
	(gr_line
		(start 271.891506 -146.455384)
		(end 271.971008 -146.336512)
		(stroke
			(width 0.08255)
			(type default)
		)
		(layer "In9.Cu")
	)
	(gr_line
		(start 271.971008 -146.336512)
		(end 271.874742 -145.85061)
		(stroke
			(width 0.08255)
			(type default)
		)
		(layer "In9.Cu")
	)
	(gr_line
		(start 272.084038 -148.878036)
		(end 271.942814 -148.167344)
		(stroke
			(width 0.08255)
			(type default)
		)
		(layer "In9.Cu")
	)
	(gr_line
		(start 272.107406 -147.02155)
		(end 271.98828 -146.942048)
		(stroke
			(width 0.08255)
			(type default)
		)
		(layer "In9.Cu")
	)
	(gr_line
		(start 272.12417 -147.626324)
		(end 272.203672 -147.507452)
		(stroke
			(width 0.08255)
			(type default)
		)
		(layer "In9.Cu")
	)
	(gr_line
		(start 272.203672 -147.507452)
		(end 272.107406 -147.02155)
		(stroke
			(width 0.08255)
			(type default)
		)
		(layer "In9.Cu")
	)
	(gr_line
		(start 272.354802 -148.202396)
		(end 272.22069 -148.112988)
		(stroke
			(width 0.08255)
			(type default)
		)
		(layer "In9.Cu")
	)
	(gr_line
		(start 272.36166 -148.82241)
		(end 272.451322 -148.688552)
		(stroke
			(width 0.08255)
			(type default)
		)
		(layer "In9.Cu")
	)
	(gr_line
		(start 272.451322 -148.688552)
		(end 272.354802 -148.202396)
		(stroke
			(width 0.08255)
			(type default)
		)
		(layer "In9.Cu")
	)
	(gr_line
		(start 286.483806 -319.916048)
		(end 286.483806 -319.8876)
		(stroke
			(width 0.05715)
			(type default)
		)
		(layer "In9.Cu")
	)
	(gr_line
		(start 286.483806 -319.8876)
		(end 286.529526 -319.84188)
		(stroke
			(width 0.05715)
			(type default)
		)
		(layer "In9.Cu")
	)
	(gr_line
		(start 286.765746 -319.916048)
		(end 286.765746 -319.8876)
		(stroke
			(width 0.05715)
			(type default)
		)
		(layer "In9.Cu")
	)
	(gr_line
		(start 286.765746 -319.8876)
		(end 286.720026 -319.84188)
		(stroke
			(width 0.05715)
			(type default)
		)
		(layer "In9.Cu")
	)
	(gr_line
		(start 287.010856 -316.419992)
		(end 287.099756 -316.508892)
		(stroke
			(width 0.05715)
			(type default)
		)
		(layer "In9.Cu")
	)
	(gr_line
		(start 287.010856 -316.229492)
		(end 287.099756 -316.140592)
		(stroke
			(width 0.05715)
			(type default)
		)
		(layer "In9.Cu")
	)
	(gr_line
		(start 287.099756 -316.508892)
		(end 287.099756 -316.799722)
		(stroke
			(width 0.05715)
			(type default)
		)
		(layer "In9.Cu")
	)
	(gr_line
		(start 287.099756 -316.140592)
		(end 287.099756 -315.849762)
		(stroke
			(width 0.05715)
			(type default)
		)
		(layer "In9.Cu")
	)
	(gr_line
		(start 288.38398 -319.916048)
		(end 288.38398 -319.8876)
		(stroke
			(width 0.05715)
			(type default)
		)
		(layer "In9.Cu")
	)
	(gr_line
		(start 288.38398 -319.8876)
		(end 288.4297 -319.84188)
		(stroke
			(width 0.05715)
			(type default)
		)
		(layer "In9.Cu")
	)
	(gr_line
		(start 288.66592 -319.916048)
		(end 288.66592 -319.8876)
		(stroke
			(width 0.05715)
			(type default)
		)
		(layer "In9.Cu")
	)
	(gr_line
		(start 288.66592 -319.8876)
		(end 288.6202 -319.84188)
		(stroke
			(width 0.05715)
			(type default)
		)
		(layer "In9.Cu")
	)
	(gr_line
		(start 288.91103 -316.419992)
		(end 288.99993 -316.508892)
		(stroke
			(width 0.05715)
			(type default)
		)
		(layer "In9.Cu")
	)
	(gr_line
		(start 288.91103 -316.229492)
		(end 288.99993 -316.140592)
		(stroke
			(width 0.05715)
			(type default)
		)
		(layer "In9.Cu")
	)
	(gr_line
		(start 288.99993 -316.508892)
		(end 288.99993 -316.799722)
		(stroke
			(width 0.05715)
			(type default)
		)
		(layer "In9.Cu")
	)
	(gr_line
		(start 288.99993 -316.140592)
		(end 288.99993 -315.849762)
		(stroke
			(width 0.05715)
			(type default)
		)
		(layer "In9.Cu")
	)
	(gr_line
		(start 291.23386 -271.500346)
		(end 291.23386 -271.471898)
		(stroke
			(width 0.05715)
			(type default)
		)
		(layer "In9.Cu")
	)
	(gr_line
		(start 291.27958 -271.546066)
		(end 291.23386 -271.500346)
		(stroke
			(width 0.05715)
			(type default)
		)
		(layer "In9.Cu")
	)
	(gr_line
		(start 291.47008 -271.546066)
		(end 291.5158 -271.500346)
		(stroke
			(width 0.05715)
			(type default)
		)
		(layer "In9.Cu")
	)
	(gr_line
		(start 291.5158 -271.500346)
		(end 291.5158 -271.471898)
		(stroke
			(width 0.05715)
			(type default)
		)
		(layer "In9.Cu")
	)
	(gr_line
		(start 291.849556 -278.799798)
		(end 291.849556 -278.534368)
		(stroke
			(width 0.05715)
			(type default)
		)
		(layer "In9.Cu")
	)
	(gr_line
		(start 291.849556 -278.534368)
		(end 291.735256 -278.420068)
		(stroke
			(width 0.05715)
			(type default)
		)
		(layer "In9.Cu")
	)
	(gr_line
		(start 291.849556 -278.115268)
		(end 291.735256 -278.229568)
		(stroke
			(width 0.05715)
			(type default)
		)
		(layer "In9.Cu")
	)
	(gr_line
		(start 291.849556 -277.849838)
		(end 291.849556 -278.115268)
		(stroke
			(width 0.05715)
			(type default)
		)
		(layer "In9.Cu")
	)
	(gr_line
		(start 292.18382 -271.554448)
		(end 292.18382 -271.526)
		(stroke
			(width 0.05715)
			(type default)
		)
		(layer "In9.Cu")
	)
	(gr_line
		(start 292.22954 -271.600168)
		(end 292.18382 -271.554448)
		(stroke
			(width 0.05715)
			(type default)
		)
		(layer "In9.Cu")
	)
	(gr_line
		(start 292.42004 -271.600168)
		(end 292.46576 -271.554448)
		(stroke
			(width 0.05715)
			(type default)
		)
		(layer "In9.Cu")
	)
	(gr_line
		(start 292.46576 -271.554448)
		(end 292.46576 -271.526)
		(stroke
			(width 0.05715)
			(type default)
		)
		(layer "In9.Cu")
	)
	(gr_line
		(start 292.79977 -280.699718)
		(end 292.79977 -280.434288)
		(stroke
			(width 0.05715)
			(type default)
		)
		(layer "In9.Cu")
	)
	(gr_line
		(start 292.79977 -280.434288)
		(end 292.68547 -280.319988)
		(stroke
			(width 0.05715)
			(type default)
		)
		(layer "In9.Cu")
	)
	(gr_line
		(start 292.79977 -280.015188)
		(end 292.68547 -280.129488)
		(stroke
			(width 0.05715)
			(type default)
		)
		(layer "In9.Cu")
	)
	(gr_line
		(start 292.79977 -279.749504)
		(end 292.79977 -280.015188)
		(stroke
			(width 0.05715)
			(type default)
		)
		(layer "In9.Cu")
	)
	(gr_line
		(start 294.08374 -271.554448)
		(end 294.08374 -271.526)
		(stroke
			(width 0.05715)
			(type default)
		)
		(layer "In9.Cu")
	)
	(gr_line
		(start 294.12946 -271.600168)
		(end 294.08374 -271.554448)
		(stroke
			(width 0.05715)
			(type default)
		)
		(layer "In9.Cu")
	)
	(gr_line
		(start 294.31996 -271.600168)
		(end 294.36568 -271.554448)
		(stroke
			(width 0.05715)
			(type default)
		)
		(layer "In9.Cu")
	)
	(gr_line
		(start 294.36568 -271.554448)
		(end 294.36568 -271.526)
		(stroke
			(width 0.05715)
			(type default)
		)
		(layer "In9.Cu")
	)
	(gr_line
		(start 294.69969 -280.699718)
		(end 294.69969 -280.434288)
		(stroke
			(width 0.05715)
			(type default)
		)
		(layer "In9.Cu")
	)
	(gr_line
		(start 294.69969 -280.434288)
		(end 294.58539 -280.319988)
		(stroke
			(width 0.05715)
			(type default)
		)
		(layer "In9.Cu")
	)
	(gr_line
		(start 294.69969 -280.015188)
		(end 294.58539 -280.129488)
		(stroke
			(width 0.05715)
			(type default)
		)
		(layer "In9.Cu")
	)
	(gr_line
		(start 294.69969 -279.749504)
		(end 294.69969 -280.015188)
		(stroke
			(width 0.05715)
			(type default)
		)
		(layer "In9.Cu")
	)
	(gr_line
		(start 295.983914 -271.554448)
		(end 295.983914 -271.526)
		(stroke
			(width 0.05715)
			(type default)
		)
		(layer "In9.Cu")
	)
	(gr_line
		(start 295.983914 -269.36065)
		(end 295.983914 -268.66215)
		(stroke
			(width 0.08255)
			(type default)
		)
		(layer "In9.Cu")
	)
	(gr_line
		(start 296.029634 -271.600168)
		(end 295.983914 -271.554448)
		(stroke
			(width 0.05715)
			(type default)
		)
		(layer "In9.Cu")
	)
	(gr_line
		(start 296.220134 -271.600168)
		(end 296.265854 -271.554448)
		(stroke
			(width 0.05715)
			(type default)
		)
		(layer "In9.Cu")
	)
	(gr_line
		(start 296.265854 -271.554448)
		(end 296.265854 -271.526)
		(stroke
			(width 0.05715)
			(type default)
		)
		(layer "In9.Cu")
	)
	(gr_line
		(start 296.267124 -269.35938)
		(end 296.367454 -269.25905)
		(stroke
			(width 0.08255)
			(type default)
		)
		(layer "In9.Cu")
	)
	(gr_line
		(start 296.367454 -269.25905)
		(end 296.367454 -268.76375)
		(stroke
			(width 0.08255)
			(type default)
		)
		(layer "In9.Cu")
	)
	(gr_line
		(start 296.367454 -268.76375)
		(end 296.267124 -268.66342)
		(stroke
			(width 0.08255)
			(type default)
		)
		(layer "In9.Cu")
	)
	(gr_line
		(start 296.599864 -280.699718)
		(end 296.599864 -280.434288)
		(stroke
			(width 0.05715)
			(type default)
		)
		(layer "In9.Cu")
	)
	(gr_line
		(start 296.599864 -280.434288)
		(end 296.485564 -280.319988)
		(stroke
			(width 0.05715)
			(type default)
		)
		(layer "In9.Cu")
	)
	(gr_line
		(start 296.599864 -280.015188)
		(end 296.485564 -280.129488)
		(stroke
			(width 0.05715)
			(type default)
		)
		(layer "In9.Cu")
	)
	(gr_line
		(start 296.599864 -279.749504)
		(end 296.599864 -280.015188)
		(stroke
			(width 0.05715)
			(type default)
		)
		(layer "In9.Cu")
	)
	(gr_line
		(start 297.620436 -332.305914)
		(end 297.523154 -332.348586)
		(stroke
			(width 0.08255)
			(type default)
		)
		(layer "In9.Cu")
	)
	(gr_line
		(start 297.883834 -271.554448)
		(end 297.883834 -271.526)
		(stroke
			(width 0.05715)
			(type default)
		)
		(layer "In9.Cu")
	)
	(gr_line
		(start 297.908472 -330.134468)
		(end 297.811698 -330.177902)
		(stroke
			(width 0.08255)
			(type default)
		)
		(layer "In9.Cu")
	)
	(gr_line
		(start 297.929554 -271.600168)
		(end 297.883834 -271.554448)
		(stroke
			(width 0.05715)
			(type default)
		)
		(layer "In9.Cu")
	)
	(gr_line
		(start 298.02328 -332.847442)
		(end 297.419522 -332.612238)
		(stroke
			(width 0.08255)
			(type default)
		)
		(layer "In9.Cu")
	)
	(gr_line
		(start 298.082208 -332.486)
		(end 297.620436 -332.305914)
		(stroke
			(width 0.08255)
			(type default)
		)
		(layer "In9.Cu")
	)
	(gr_line
		(start 298.120054 -271.600168)
		(end 298.165774 -271.554448)
		(stroke
			(width 0.05715)
			(type default)
		)
		(layer "In9.Cu")
	)
	(gr_line
		(start 298.12488 -332.583028)
		(end 298.082208 -332.486)
		(stroke
			(width 0.08255)
			(type default)
		)
		(layer "In9.Cu")
	)
	(gr_line
		(start 298.165774 -271.554448)
		(end 298.165774 -271.526)
		(stroke
			(width 0.05715)
			(type default)
		)
		(layer "In9.Cu")
	)
	(gr_line
		(start 298.31538 -330.672948)
		(end 297.709844 -330.442316)
		(stroke
			(width 0.08255)
			(type default)
		)
		(layer "In9.Cu")
	)
	(gr_line
		(start 298.371768 -330.310998)
		(end 297.908472 -330.134468)
		(stroke
			(width 0.08255)
			(type default)
		)
		(layer "In9.Cu")
	)
	(gr_line
		(start 298.414948 -330.407772)
		(end 298.371768 -330.310998)
		(stroke
			(width 0.08255)
			(type default)
		)
		(layer "In9.Cu")
	)
	(gr_line
		(start 298.499784 -280.699718)
		(end 298.499784 -280.434288)
		(stroke
			(width 0.05715)
			(type default)
		)
		(layer "In9.Cu")
	)
	(gr_line
		(start 298.499784 -280.434288)
		(end 298.385484 -280.319988)
		(stroke
			(width 0.05715)
			(type default)
		)
		(layer "In9.Cu")
	)
	(gr_line
		(start 298.499784 -280.015188)
		(end 298.385484 -280.129488)
		(stroke
			(width 0.05715)
			(type default)
		)
		(layer "In9.Cu")
	)
	(gr_line
		(start 298.499784 -279.749504)
		(end 298.499784 -280.015188)
		(stroke
			(width 0.05715)
			(type default)
		)
		(layer "In9.Cu")
	)
	(gr_line
		(start 299.070014 -271.546066)
		(end 299.115734 -271.500346)
		(stroke
			(width 0.05715)
			(type default)
		)
		(layer "In9.Cu")
	)
	(gr_line
		(start 299.115734 -271.500346)
		(end 299.115734 -271.471898)
		(stroke
			(width 0.05715)
			(type default)
		)
		(layer "In9.Cu")
	)
	(gr_line
		(start 299.44949 -278.115268)
		(end 299.33519 -278.229568)
		(stroke
			(width 0.05715)
			(type default)
		)
		(layer "In9.Cu")
	)
	(gr_line
		(start 299.44949 -277.849838)
		(end 299.44949 -278.115268)
		(stroke
			(width 0.05715)
			(type default)
		)
		(layer "In9.Cu")
	)
	(gr_line
		(start 299.783754 -271.554448)
		(end 299.783754 -271.526)
		(stroke
			(width 0.05715)
			(type default)
		)
		(layer "In9.Cu")
	)
	(gr_line
		(start 299.829474 -271.600168)
		(end 299.783754 -271.554448)
		(stroke
			(width 0.05715)
			(type default)
		)
		(layer "In9.Cu")
	)
	(gr_line
		(start 300.019974 -271.600168)
		(end 300.065694 -271.554448)
		(stroke
			(width 0.05715)
			(type default)
		)
		(layer "In9.Cu")
	)
	(gr_line
		(start 300.065694 -271.554448)
		(end 300.065694 -271.526)
		(stroke
			(width 0.05715)
			(type default)
		)
		(layer "In9.Cu")
	)
	(gr_line
		(start 300.399704 -280.699718)
		(end 300.399704 -280.434288)
		(stroke
			(width 0.05715)
			(type default)
		)
		(layer "In9.Cu")
	)
	(gr_line
		(start 300.399704 -280.434288)
		(end 300.285404 -280.319988)
		(stroke
			(width 0.05715)
			(type default)
		)
		(layer "In9.Cu")
	)
	(gr_line
		(start 300.399704 -280.015188)
		(end 300.285404 -280.129488)
		(stroke
			(width 0.05715)
			(type default)
		)
		(layer "In9.Cu")
	)
	(gr_line
		(start 300.399704 -279.749504)
		(end 300.399704 -280.015188)
		(stroke
			(width 0.05715)
			(type default)
		)
		(layer "In9.Cu")
	)
	(gr_line
		(start 301.683928 -271.554448)
		(end 301.683928 -271.526)
		(stroke
			(width 0.05715)
			(type default)
		)
		(layer "In9.Cu")
	)
	(gr_line
		(start 301.729648 -271.600168)
		(end 301.683928 -271.554448)
		(stroke
			(width 0.05715)
			(type default)
		)
		(layer "In9.Cu")
	)
	(gr_line
		(start 301.920148 -271.600168)
		(end 301.965868 -271.554448)
		(stroke
			(width 0.05715)
			(type default)
		)
		(layer "In9.Cu")
	)
	(gr_line
		(start 301.965868 -271.554448)
		(end 301.965868 -271.526)
		(stroke
			(width 0.05715)
			(type default)
		)
		(layer "In9.Cu")
	)
	(gr_line
		(start 302.299878 -280.699718)
		(end 302.299878 -280.434288)
		(stroke
			(width 0.05715)
			(type default)
		)
		(layer "In9.Cu")
	)
	(gr_line
		(start 302.299878 -280.434288)
		(end 302.185578 -280.319988)
		(stroke
			(width 0.05715)
			(type default)
		)
		(layer "In9.Cu")
	)
	(gr_line
		(start 302.299878 -280.015188)
		(end 302.185578 -280.129488)
		(stroke
			(width 0.05715)
			(type default)
		)
		(layer "In9.Cu")
	)
	(gr_line
		(start 302.299878 -279.749504)
		(end 302.299878 -280.015188)
		(stroke
			(width 0.05715)
			(type default)
		)
		(layer "In9.Cu")
	)
	(gr_line
		(start 303.583848 -271.554448)
		(end 303.583848 -271.526)
		(stroke
			(width 0.05715)
			(type default)
		)
		(layer "In9.Cu")
	)
	(gr_line
		(start 303.629568 -271.600168)
		(end 303.583848 -271.554448)
		(stroke
			(width 0.05715)
			(type default)
		)
		(layer "In9.Cu")
	)
	(gr_line
		(start 303.820068 -271.600168)
		(end 303.865788 -271.554448)
		(stroke
			(width 0.05715)
			(type default)
		)
		(layer "In9.Cu")
	)
	(gr_line
		(start 303.865788 -271.554448)
		(end 303.865788 -271.526)
		(stroke
			(width 0.05715)
			(type default)
		)
		(layer "In9.Cu")
	)
	(gr_line
		(start 304.199798 -280.699718)
		(end 304.199798 -280.434288)
		(stroke
			(width 0.05715)
			(type default)
		)
		(layer "In9.Cu")
	)
	(gr_line
		(start 304.199798 -280.434288)
		(end 304.085498 -280.319988)
		(stroke
			(width 0.05715)
			(type default)
		)
		(layer "In9.Cu")
	)
	(gr_line
		(start 304.199798 -280.015188)
		(end 304.085498 -280.129488)
		(stroke
			(width 0.05715)
			(type default)
		)
		(layer "In9.Cu")
	)
	(gr_line
		(start 304.199798 -279.749504)
		(end 304.199798 -280.015188)
		(stroke
			(width 0.05715)
			(type default)
		)
		(layer "In9.Cu")
	)
	(gr_line
		(start 305.483768 -271.554448)
		(end 305.483768 -271.526)
		(stroke
			(width 0.05715)
			(type default)
		)
		(layer "In9.Cu")
	)
	(gr_line
		(start 305.529488 -271.600168)
		(end 305.483768 -271.554448)
		(stroke
			(width 0.05715)
			(type default)
		)
		(layer "In9.Cu")
	)
	(gr_line
		(start 305.719988 -271.600168)
		(end 305.765708 -271.554448)
		(stroke
			(width 0.05715)
			(type default)
		)
		(layer "In9.Cu")
	)
	(gr_line
		(start 305.765708 -271.554448)
		(end 305.765708 -271.526)
		(stroke
			(width 0.05715)
			(type default)
		)
		(layer "In9.Cu")
	)
	(gr_line
		(start 306.099718 -280.699718)
		(end 306.099718 -280.434288)
		(stroke
			(width 0.05715)
			(type default)
		)
		(layer "In9.Cu")
	)
	(gr_line
		(start 306.099718 -280.434288)
		(end 305.985418 -280.319988)
		(stroke
			(width 0.05715)
			(type default)
		)
		(layer "In9.Cu")
	)
	(gr_line
		(start 306.099718 -280.015188)
		(end 305.985418 -280.129488)
		(stroke
			(width 0.05715)
			(type default)
		)
		(layer "In9.Cu")
	)
	(gr_line
		(start 306.099718 -279.749504)
		(end 306.099718 -280.015188)
		(stroke
			(width 0.05715)
			(type default)
		)
		(layer "In9.Cu")
	)
	(gr_line
		(start 312.679842 -199.893174)
		(end 312.680096 -199.893174)
		(stroke
			(width 0.08255)
			(type default)
		)
		(layer "In9.Cu")
	)
	(gr_line
		(start 313.699906 -276.899878)
		(end 313.965336 -276.899878)
		(stroke
			(width 0.05715)
			(type default)
		)
		(layer "In9.Cu")
	)
	(gr_line
		(start 313.965336 -276.899878)
		(end 314.079636 -276.785578)
		(stroke
			(width 0.05715)
			(type default)
		)
		(layer "In9.Cu")
	)
	(gr_line
		(start 314.022994 -143.188436)
		(end 313.732164 -143.479266)
		(stroke
			(width 0.08255)
			(type default)
		)
		(layer "In9.Cu")
	)
	(gr_line
		(start 314.98413 -271.8054)
		(end 314.98413 -271.776952)
		(stroke
			(width 0.05715)
			(type default)
		)
		(layer "In9.Cu")
	)
	(gr_line
		(start 315.02985 -271.85112)
		(end 314.98413 -271.8054)
		(stroke
			(width 0.05715)
			(type default)
		)
		(layer "In9.Cu")
	)
	(gr_line
		(start 316.29223 -143.282162)
		(end 316.244986 -143.167608)
		(stroke
			(width 0.08255)
			(type default)
		)
		(layer "In9.Cu")
	)
	(gr_line
		(start 316.750192 -143.4719)
		(end 316.29223 -143.282162)
		(stroke
			(width 0.08255)
			(type default)
		)
		(layer "In9.Cu")
	)
	(gr_line
		(start 316.864746 -143.424402)
		(end 316.750192 -143.4719)
		(stroke
			(width 0.08255)
			(type default)
		)
		(layer "In9.Cu")
	)
	(gr_line
		(start 318.566292 -144.90192)
		(end 318.566292 -144.777968)
		(stroke
			(width 0.08255)
			(type default)
		)
		(layer "In9.Cu")
	)
	(gr_line
		(start 318.916812 -145.25244)
		(end 318.566292 -144.90192)
		(stroke
			(width 0.08255)
			(type default)
		)
		(layer "In9.Cu")
	)
	(gr_line
		(start 319.040764 -145.25244)
		(end 318.916812 -145.25244)
		(stroke
			(width 0.08255)
			(type default)
		)
		(layer "In9.Cu")
	)
	(gr_line
		(start 319.392554 -145.728182)
		(end 319.392554 -145.60423)
		(stroke
			(width 0.08255)
			(type default)
		)
		(layer "In9.Cu")
	)
	(gr_line
		(start 319.743074 -146.078702)
		(end 319.392554 -145.728182)
		(stroke
			(width 0.08255)
			(type default)
		)
		(layer "In9.Cu")
	)
	(gr_line
		(start 319.867026 -146.078702)
		(end 319.743074 -146.078702)
		(stroke
			(width 0.08255)
			(type default)
		)
		(layer "In9.Cu")
	)
	(gr_line
		(start 320.270124 -146.605752)
		(end 320.270124 -146.4818)
		(stroke
			(width 0.08255)
			(type default)
		)
		(layer "In9.Cu")
	)
	(gr_line
		(start 320.62039 -146.956018)
		(end 320.270124 -146.605752)
		(stroke
			(width 0.08255)
			(type default)
		)
		(layer "In9.Cu")
	)
	(gr_line
		(start 320.744342 -146.956018)
		(end 320.62039 -146.956018)
		(stroke
			(width 0.08255)
			(type default)
		)
		(layer "In9.Cu")
	)
	(gr_line
		(start 321.224148 -147.718272)
		(end 321.248278 -147.596606)
		(stroke
			(width 0.08255)
			(type default)
		)
		(layer "In9.Cu")
	)
	(gr_line
		(start 321.499484 -148.13026)
		(end 321.224148 -147.718272)
		(stroke
			(width 0.08255)
			(type default)
		)
		(layer "In9.Cu")
	)
	(gr_line
		(start 321.62115 -148.154644)
		(end 321.499484 -148.13026)
		(stroke
			(width 0.08255)
			(type default)
		)
		(layer "In9.Cu")
	)
	(gr_line
		(start 321.622928 -148.154898)
		(end 321.622674 -148.154898)
		(stroke
			(width 0.08255)
			(type default)
		)
		(layer "In9.Cu")
	)
	(gr_line
		(start 322.20027 -149.38121)
		(end 322.247768 -149.266656)
		(stroke
			(width 0.08255)
			(type default)
		)
		(layer "In9.Cu")
	)
	(gr_line
		(start 322.390262 -149.839172)
		(end 322.20027 -149.38121)
		(stroke
			(width 0.08255)
			(type default)
		)
		(layer "In9.Cu")
	)
	(gr_line
		(start 322.504562 -149.886416)
		(end 322.390262 -149.839172)
		(stroke
			(width 0.08255)
			(type default)
		)
		(layer "In9.Cu")
	)
	(gr_line
		(start 322.50634 -149.887178)
		(end 322.506086 -149.887178)
		(stroke
			(width 0.08255)
			(type default)
		)
		(layer "In9.Cu")
	)
	(gr_line
		(start 331.333094 -363.469174)
		(end 331.291692 -363.371384)
		(stroke
			(width 0.08255)
			(type default)
		)
		(layer "In9.Cu")
	)
	(gr_line
		(start 331.792326 -363.655102)
		(end 331.333094 -363.469174)
		(stroke
			(width 0.08255)
			(type default)
		)
		(layer "In9.Cu")
	)
	(gr_line
		(start 331.890116 -363.6137)
		(end 331.792326 -363.655102)
		(stroke
			(width 0.08255)
			(type default)
		)
		(layer "In9.Cu")
	)
	(gr_line
		(start 331.997558 -363.351572)
		(end 331.396848 -363.108494)
		(stroke
			(width 0.08255)
			(type default)
		)
		(layer "In9.Cu")
	)
	(gr_line
		(start 332.392782 -363.89818)
		(end 332.35138 -363.80039)
		(stroke
			(width 0.08255)
			(type default)
		)
		(layer "In9.Cu")
	)
	(gr_line
		(start 332.852014 -364.084108)
		(end 332.392782 -363.89818)
		(stroke
			(width 0.08255)
			(type default)
		)
		(layer "In9.Cu")
	)
	(gr_line
		(start 332.950058 -364.042706)
		(end 332.852014 -364.084108)
		(stroke
			(width 0.08255)
			(type default)
		)
		(layer "In9.Cu")
	)
	(gr_line
		(start 333.057246 -363.780578)
		(end 332.456282 -363.5375)
		(stroke
			(width 0.08255)
			(type default)
		)
		(layer "In9.Cu")
	)
	(gr_line
		(start 333.45247 -364.326932)
		(end 333.411068 -364.229396)
		(stroke
			(width 0.08255)
			(type default)
		)
		(layer "In9.Cu")
	)
	(gr_line
		(start 333.911702 -364.513114)
		(end 333.45247 -364.326932)
		(stroke
			(width 0.08255)
			(type default)
		)
		(layer "In9.Cu")
	)
	(gr_line
		(start 334.009492 -364.471712)
		(end 333.911702 -364.513114)
		(stroke
			(width 0.08255)
			(type default)
		)
		(layer "In9.Cu")
	)
	(gr_line
		(start 334.116934 -364.209584)
		(end 333.51597 -363.966506)
		(stroke
			(width 0.08255)
			(type default)
		)
		(layer "In9.Cu")
	)
	(gr_line
		(start 335.445608 -362.823252)
		(end 335.408016 -362.724192)
		(stroke
			(width 0.08255)
			(type default)
		)
		(layer "In9.Cu")
	)
	(gr_line
		(start 335.897474 -363.027214)
		(end 335.445608 -362.823252)
		(stroke
			(width 0.08255)
			(type default)
		)
		(layer "In9.Cu")
	)
	(gr_line
		(start 335.996788 -362.989368)
		(end 335.897474 -363.027214)
		(stroke
			(width 0.08255)
			(type default)
		)
		(layer "In9.Cu")
	)
	(gr_line
		(start 336.114136 -362.731812)
		(end 335.523332 -362.46562)
		(stroke
			(width 0.08255)
			(type default)
		)
		(layer "In9.Cu")
	)
	(gr_line
		(start 336.48777 -363.292898)
		(end 336.450178 -363.193838)
		(stroke
			(width 0.08255)
			(type default)
		)
		(layer "In9.Cu")
	)
	(gr_line
		(start 336.939636 -363.49686)
		(end 336.48777 -363.292898)
		(stroke
			(width 0.08255)
			(type default)
		)
		(layer "In9.Cu")
	)
	(gr_line
		(start 337.038696 -363.459014)
		(end 336.939636 -363.49686)
		(stroke
			(width 0.08255)
			(type default)
		)
		(layer "In9.Cu")
	)
	(gr_line
		(start 337.156298 -363.201458)
		(end 336.565494 -362.935266)
		(stroke
			(width 0.08255)
			(type default)
		)
		(layer "In9.Cu")
	)
	(gr_line
		(start 337.402678 -366.390428)
		(end 337.380834 -366.286542)
		(stroke
			(width 0.08255)
			(type default)
		)
		(layer "In9.Cu")
	)
	(gr_line
		(start 337.529932 -363.762798)
		(end 337.49234 -363.663484)
		(stroke
			(width 0.08255)
			(type default)
		)
		(layer "In9.Cu")
	)
	(gr_line
		(start 337.816952 -366.662208)
		(end 337.402678 -366.390428)
		(stroke
			(width 0.08255)
			(type default)
		)
		(layer "In9.Cu")
	)
	(gr_line
		(start 337.920838 -366.640618)
		(end 337.816952 -366.662208)
		(stroke
			(width 0.08255)
			(type default)
		)
		(layer "In9.Cu")
	)
	(gr_line
		(start 337.981798 -363.966506)
		(end 337.529932 -363.762798)
		(stroke
			(width 0.08255)
			(type default)
		)
		(layer "In9.Cu")
	)
	(gr_line
		(start 338.077302 -366.404652)
		(end 337.535266 -366.049052)
		(stroke
			(width 0.08255)
			(type default)
		)
		(layer "In9.Cu")
	)
	(gr_line
		(start 338.081112 -363.928914)
		(end 337.981798 -363.966506)
		(stroke
			(width 0.08255)
			(type default)
		)
		(layer "In9.Cu")
	)
	(gr_line
		(start 338.19846 -363.671104)
		(end 337.607656 -363.404912)
		(stroke
			(width 0.08255)
			(type default)
		)
		(layer "In9.Cu")
	)
	(gr_line
		(start 338.35848 -367.0173)
		(end 338.33689 -366.913668)
		(stroke
			(width 0.08255)
			(type default)
		)
		(layer "In9.Cu")
	)
	(gr_line
		(start 338.772754 -367.28908)
		(end 338.35848 -367.0173)
		(stroke
			(width 0.08255)
			(type default)
		)
		(layer "In9.Cu")
	)
	(gr_line
		(start 338.87664 -367.26749)
		(end 338.772754 -367.28908)
		(stroke
			(width 0.08255)
			(type default)
		)
		(layer "In9.Cu")
	)
	(gr_line
		(start 339.033104 -367.031524)
		(end 338.491322 -366.676178)
		(stroke
			(width 0.08255)
			(type default)
		)
		(layer "In9.Cu")
	)
	(gr_line
		(start 339.314536 -367.644172)
		(end 339.292692 -367.540286)
		(stroke
			(width 0.08255)
			(type default)
		)
		(layer "In9.Cu")
	)
	(gr_line
		(start 339.72881 -367.915952)
		(end 339.314536 -367.644172)
		(stroke
			(width 0.08255)
			(type default)
		)
		(layer "In9.Cu")
	)
	(gr_line
		(start 339.832696 -367.894362)
		(end 339.72881 -367.915952)
		(stroke
			(width 0.08255)
			(type default)
		)
		(layer "In9.Cu")
	)
	(gr_line
		(start 339.988906 -367.658142)
		(end 339.447124 -367.30305)
		(stroke
			(width 0.08255)
			(type default)
		)
		(layer "In9.Cu")
	)
	(gr_line
		(start 340.29015 -375.69013)
		(end 340.29015 -375.308114)
		(stroke
			(width 0.08255)
			(type default)
		)
		(layer "In9.Cu")
	)
	(gr_line
		(start 340.29015 -375.308114)
		(end 340.41715 -375.181114)
		(stroke
			(width 0.08255)
			(type default)
		)
		(layer "In9.Cu")
	)
	(gr_line
		(start 340.29015 -374.772174)
		(end 340.41715 -374.899174)
		(stroke
			(width 0.08255)
			(type default)
		)
		(layer "In9.Cu")
	)
	(gr_line
		(start 340.29015 -374.390158)
		(end 340.29015 -374.772174)
		(stroke
			(width 0.08255)
			(type default)
		)
		(layer "In9.Cu")
	)
	(gr_line
		(start 341.228172 -365.881412)
		(end 341.209376 -365.776764)
		(stroke
			(width 0.08255)
			(type default)
		)
		(layer "In9.Cu")
	)
	(gr_line
		(start 341.370412 -365.543846)
		(end 341.370412 -365.5441)
		(stroke
			(width 0.08255)
			(type default)
		)
		(layer "In9.Cu")
	)
	(gr_line
		(start 341.634826 -366.164622)
		(end 341.228172 -365.881412)
		(stroke
			(width 0.08255)
			(type default)
		)
		(layer "In9.Cu")
	)
	(gr_line
		(start 341.739474 -366.145826)
		(end 341.634826 -366.164622)
		(stroke
			(width 0.08255)
			(type default)
		)
		(layer "In9.Cu")
	)
	(gr_line
		(start 341.902288 -365.913924)
		(end 341.370412 -365.543846)
		(stroke
			(width 0.08255)
			(type default)
		)
		(layer "In9.Cu")
	)
	(gr_line
		(start 342.166448 -366.534446)
		(end 342.147652 -366.430052)
		(stroke
			(width 0.08255)
			(type default)
		)
		(layer "In9.Cu")
	)
	(gr_line
		(start 342.573102 -366.817656)
		(end 342.166448 -366.534446)
		(stroke
			(width 0.08255)
			(type default)
		)
		(layer "In9.Cu")
	)
	(gr_line
		(start 342.67775 -366.79886)
		(end 342.573102 -366.817656)
		(stroke
			(width 0.08255)
			(type default)
		)
		(layer "In9.Cu")
	)
	(gr_line
		(start 342.840564 -366.567212)
		(end 342.308688 -366.19688)
		(stroke
			(width 0.08255)
			(type default)
		)
		(layer "In9.Cu")
	)
	(gr_line
		(start 343.104724 -367.18748)
		(end 343.085928 -367.083086)
		(stroke
			(width 0.08255)
			(type default)
		)
		(layer "In9.Cu")
	)
	(gr_line
		(start 343.511378 -367.47069)
		(end 343.104724 -367.18748)
		(stroke
			(width 0.08255)
			(type default)
		)
		(layer "In9.Cu")
	)
	(gr_line
		(start 343.61628 -367.452148)
		(end 343.511378 -367.47069)
		(stroke
			(width 0.08255)
			(type default)
		)
		(layer "In9.Cu")
	)
	(gr_line
		(start 343.77884 -367.220246)
		(end 343.246964 -366.849914)
		(stroke
			(width 0.08255)
			(type default)
		)
		(layer "In9.Cu")
	)
	(gr_line
		(start 344.689938 -375.69013)
		(end 344.689938 -375.308114)
		(stroke
			(width 0.08255)
			(type default)
		)
		(layer "In9.Cu")
	)
	(gr_line
		(start 344.689938 -375.308114)
		(end 344.816938 -375.181114)
		(stroke
			(width 0.08255)
			(type default)
		)
		(layer "In9.Cu")
	)
	(gr_line
		(start 344.689938 -374.772174)
		(end 344.816938 -374.899174)
		(stroke
			(width 0.08255)
			(type default)
		)
		(layer "In9.Cu")
	)
	(gr_line
		(start 344.689938 -374.390158)
		(end 344.689938 -374.772174)
		(stroke
			(width 0.08255)
			(type default)
		)
		(layer "In9.Cu")
	)
	(gr_line
		(start 366.85347 -315.22416)
		(end 367.120932 -314.578492)
		(stroke
			(width 0.08255)
			(type default)
		)
		(layer "In9.Cu")
	)
	(gr_line
		(start 367.114074 -315.33211)
		(end 367.11382 -315.33211)
		(stroke
			(width 0.08255)
			(type default)
		)
		(layer "In9.Cu")
	)
	(gr_line
		(start 367.115598 -315.331348)
		(end 367.246662 -315.276992)
		(stroke
			(width 0.08255)
			(type default)
		)
		(layer "In9.Cu")
	)
	(gr_line
		(start 367.246662 -315.276992)
		(end 367.4364 -314.819284)
		(stroke
			(width 0.08255)
			(type default)
		)
		(layer "In9.Cu")
	)
	(gr_line
		(start 367.310416 -314.121038)
		(end 367.577878 -313.47537)
		(stroke
			(width 0.08255)
			(type default)
		)
		(layer "In9.Cu")
	)
	(gr_line
		(start 367.381282 -314.686442)
		(end 367.381536 -314.686442)
		(stroke
			(width 0.08255)
			(type default)
		)
		(layer "In9.Cu")
	)
	(gr_line
		(start 367.4364 -314.819284)
		(end 367.382044 -314.68822)
		(stroke
			(width 0.08255)
			(type default)
		)
		(layer "In9.Cu")
	)
	(gr_line
		(start 367.57102 -314.228988)
		(end 367.570766 -314.228988)
		(stroke
			(width 0.08255)
			(type default)
		)
		(layer "In9.Cu")
	)
	(gr_line
		(start 367.572544 -314.228226)
		(end 367.703608 -314.17387)
		(stroke
			(width 0.08255)
			(type default)
		)
		(layer "In9.Cu")
	)
	(gr_line
		(start 367.703608 -314.17387)
		(end 367.893346 -313.716162)
		(stroke
			(width 0.08255)
			(type default)
		)
		(layer "In9.Cu")
	)
	(gr_line
		(start 367.767108 -313.01817)
		(end 368.03457 -312.372248)
		(stroke
			(width 0.08255)
			(type default)
		)
		(layer "In9.Cu")
	)
	(gr_line
		(start 367.838228 -313.58332)
		(end 367.838482 -313.58332)
		(stroke
			(width 0.08255)
			(type default)
		)
		(layer "In9.Cu")
	)
	(gr_line
		(start 367.893346 -313.716162)
		(end 367.83899 -313.585098)
		(stroke
			(width 0.08255)
			(type default)
		)
		(layer "In9.Cu")
	)
	(gr_line
		(start 368.027712 -313.12612)
		(end 368.027712 -313.125866)
		(stroke
			(width 0.08255)
			(type default)
		)
		(layer "In9.Cu")
	)
	(gr_line
		(start 368.02949 -313.125104)
		(end 368.160554 -313.070748)
		(stroke
			(width 0.08255)
			(type default)
		)
		(layer "In9.Cu")
	)
	(gr_line
		(start 368.160554 -313.070748)
		(end 368.350292 -312.61304)
		(stroke
			(width 0.08255)
			(type default)
		)
		(layer "In9.Cu")
	)
	(gr_line
		(start 368.350292 -312.61304)
		(end 368.295936 -312.481722)
		(stroke
			(width 0.08255)
			(type default)
		)
		(layer "In9.Cu")
	)
	(gr_line
		(start 369.379754 -309.748682)
		(end 369.434872 -309.645558)
		(stroke
			(width 0.08255)
			(type default)
		)
		(layer "In9.Cu")
	)
	(gr_line
		(start 369.434872 -309.645558)
		(end 369.435126 -309.645304)
		(stroke
			(width 0.08255)
			(type default)
		)
		(layer "In9.Cu")
	)
	(gr_line
		(start 369.435126 -309.645304)
		(end 369.709446 -309.132224)
		(stroke
			(width 0.08255)
			(type default)
		)
		(layer "In9.Cu")
	)
	(gr_line
		(start 369.630198 -309.881016)
		(end 369.766342 -309.839614)
		(stroke
			(width 0.08255)
			(type default)
		)
		(layer "In9.Cu")
	)
	(gr_line
		(start 369.715542 -311.416446)
		(end 370.044726 -310.799988)
		(stroke
			(width 0.08255)
			(type default)
		)
		(layer "In9.Cu")
	)
	(gr_line
		(start 369.766342 -309.839614)
		(end 370.000022 -309.402734)
		(stroke
			(width 0.08255)
			(type default)
		)
		(layer "In9.Cu")
	)
	(gr_line
		(start 369.942872 -308.695344)
		(end 370.27231 -308.078886)
		(stroke
			(width 0.08255)
			(type default)
		)
		(layer "In9.Cu")
	)
	(gr_line
		(start 369.964208 -311.549288)
		(end 369.963954 -311.549288)
		(stroke
			(width 0.08255)
			(type default)
		)
		(layer "In9.Cu")
	)
	(gr_line
		(start 369.965732 -311.54878)
		(end 370.101622 -311.507632)
		(stroke
			(width 0.08255)
			(type default)
		)
		(layer "In9.Cu")
	)
	(gr_line
		(start 370.000022 -309.402734)
		(end 369.95862 -309.26659)
		(stroke
			(width 0.08255)
			(type default)
		)
		(layer "In9.Cu")
	)
	(gr_line
		(start 370.101622 -311.507632)
		(end 370.335302 -311.070498)
		(stroke
			(width 0.08255)
			(type default)
		)
		(layer "In9.Cu")
	)
	(gr_line
		(start 370.193062 -308.827932)
		(end 370.329206 -308.78653)
		(stroke
			(width 0.08255)
			(type default)
		)
		(layer "In9.Cu")
	)
	(gr_line
		(start 370.247672 -312.814208)
		(end 370.576856 -312.19775)
		(stroke
			(width 0.08255)
			(type default)
		)
		(layer "In9.Cu")
	)
	(gr_line
		(start 370.278152 -310.363362)
		(end 370.60759 -309.74665)
		(stroke
			(width 0.08255)
			(type default)
		)
		(layer "In9.Cu")
	)
	(gr_line
		(start 370.293392 -310.93283)
		(end 370.293646 -310.933084)
		(stroke
			(width 0.08255)
			(type default)
		)
		(layer "In9.Cu")
	)
	(gr_line
		(start 370.329206 -308.78653)
		(end 370.562886 -308.34965)
		(stroke
			(width 0.08255)
			(type default)
		)
		(layer "In9.Cu")
	)
	(gr_line
		(start 370.335302 -311.070498)
		(end 370.2939 -310.934608)
		(stroke
			(width 0.08255)
			(type default)
		)
		(layer "In9.Cu")
	)
	(gr_line
		(start 370.496338 -312.94705)
		(end 370.496084 -312.94705)
		(stroke
			(width 0.08255)
			(type default)
		)
		(layer "In9.Cu")
	)
	(gr_line
		(start 370.497862 -312.946542)
		(end 370.633752 -312.905394)
		(stroke
			(width 0.08255)
			(type default)
		)
		(layer "In9.Cu")
	)
	(gr_line
		(start 370.505736 -307.64226)
		(end 370.835174 -307.025802)
		(stroke
			(width 0.08255)
			(type default)
		)
		(layer "In9.Cu")
	)
	(gr_line
		(start 370.527072 -310.496204)
		(end 370.526818 -310.496204)
		(stroke
			(width 0.08255)
			(type default)
		)
		(layer "In9.Cu")
	)
	(gr_line
		(start 370.528596 -310.495696)
		(end 370.664486 -310.454294)
		(stroke
			(width 0.08255)
			(type default)
		)
		(layer "In9.Cu")
	)
	(gr_line
		(start 370.562886 -308.34965)
		(end 370.521484 -308.213506)
		(stroke
			(width 0.08255)
			(type default)
		)
		(layer "In9.Cu")
	)
	(gr_line
		(start 370.633752 -312.905394)
		(end 370.867432 -312.46826)
		(stroke
			(width 0.08255)
			(type default)
		)
		(layer "In9.Cu")
	)
	(gr_line
		(start 370.664486 -310.454294)
		(end 370.898166 -310.017414)
		(stroke
			(width 0.08255)
			(type default)
		)
		(layer "In9.Cu")
	)
	(gr_line
		(start 370.755926 -307.774848)
		(end 370.891816 -307.733446)
		(stroke
			(width 0.08255)
			(type default)
		)
		(layer "In9.Cu")
	)
	(gr_line
		(start 370.767864 -311.840626)
		(end 370.810282 -311.761124)
		(stroke
			(width 0.08255)
			(type default)
		)
		(layer "In9.Cu")
	)
	(gr_line
		(start 370.810282 -311.761124)
		(end 371.139974 -311.144412)
		(stroke
			(width 0.08255)
			(type default)
		)
		(layer "In9.Cu")
	)
	(gr_line
		(start 370.841016 -309.310024)
		(end 371.170454 -308.69382)
		(stroke
			(width 0.08255)
			(type default)
		)
		(layer "In9.Cu")
	)
	(gr_line
		(start 370.856256 -309.879746)
		(end 370.85651 -309.879746)
		(stroke
			(width 0.08255)
			(type default)
		)
		(layer "In9.Cu")
	)
	(gr_line
		(start 370.867432 -312.46826)
		(end 370.826284 -312.332116)
		(stroke
			(width 0.08255)
			(type default)
		)
		(layer "In9.Cu")
	)
	(gr_line
		(start 370.891816 -307.733446)
		(end 371.12575 -307.296566)
		(stroke
			(width 0.08255)
			(type default)
		)
		(layer "In9.Cu")
	)
	(gr_line
		(start 370.898166 -310.017414)
		(end 370.856764 -309.881524)
		(stroke
			(width 0.08255)
			(type default)
		)
		(layer "In9.Cu")
	)
	(gr_line
		(start 371.01653 -311.973468)
		(end 371.058948 -311.893966)
		(stroke
			(width 0.08255)
			(type default)
		)
		(layer "In9.Cu")
	)
	(gr_line
		(start 371.060726 -311.893458)
		(end 371.196362 -311.85231)
		(stroke
			(width 0.08255)
			(type default)
		)
		(layer "In9.Cu")
	)
	(gr_line
		(start 371.068346 -306.589176)
		(end 371.398038 -305.972718)
		(stroke
			(width 0.08255)
			(type default)
		)
		(layer "In9.Cu")
	)
	(gr_line
		(start 371.089936 -309.44312)
		(end 371.089682 -309.44312)
		(stroke
			(width 0.08255)
			(type default)
		)
		(layer "In9.Cu")
	)
	(gr_line
		(start 371.09146 -309.442612)
		(end 371.22735 -309.40121)
		(stroke
			(width 0.08255)
			(type default)
		)
		(layer "In9.Cu")
	)
	(gr_line
		(start 371.12575 -307.296566)
		(end 371.084348 -307.160422)
		(stroke
			(width 0.08255)
			(type default)
		)
		(layer "In9.Cu")
	)
	(gr_line
		(start 371.196362 -311.85231)
		(end 371.430042 -311.415176)
		(stroke
			(width 0.08255)
			(type default)
		)
		(layer "In9.Cu")
	)
	(gr_line
		(start 371.22735 -309.40121)
		(end 371.46103 -308.96433)
		(stroke
			(width 0.08255)
			(type default)
		)
		(layer "In9.Cu")
	)
	(gr_line
		(start 371.31879 -306.721764)
		(end 371.45468 -306.680362)
		(stroke
			(width 0.08255)
			(type default)
		)
		(layer "In9.Cu")
	)
	(gr_line
		(start 371.372892 -310.70804)
		(end 371.70233 -310.091582)
		(stroke
			(width 0.08255)
			(type default)
		)
		(layer "In9.Cu")
	)
	(gr_line
		(start 371.388386 -311.277508)
		(end 371.38864 -311.277508)
		(stroke
			(width 0.08255)
			(type default)
		)
		(layer "In9.Cu")
	)
	(gr_line
		(start 371.40388 -308.25694)
		(end 371.733318 -307.640736)
		(stroke
			(width 0.08255)
			(type default)
		)
		(layer "In9.Cu")
	)
	(gr_line
		(start 371.430042 -311.415176)
		(end 371.388894 -311.279286)
		(stroke
			(width 0.08255)
			(type default)
		)
		(layer "In9.Cu")
	)
	(gr_line
		(start 371.45468 -306.680362)
		(end 371.688614 -306.243482)
		(stroke
			(width 0.08255)
			(type default)
		)
		(layer "In9.Cu")
	)
	(gr_line
		(start 371.46103 -308.96433)
		(end 371.419628 -308.82844)
		(stroke
			(width 0.08255)
			(type default)
		)
		(layer "In9.Cu")
	)
	(gr_line
		(start 371.62359 -310.840374)
		(end 371.759226 -310.799226)
		(stroke
			(width 0.08255)
			(type default)
		)
		(layer "In9.Cu")
	)
	(gr_line
		(start 371.65407 -308.389528)
		(end 371.78996 -308.348126)
		(stroke
			(width 0.08255)
			(type default)
		)
		(layer "In9.Cu")
	)
	(gr_line
		(start 371.688614 -306.243482)
		(end 371.647212 -306.107338)
		(stroke
			(width 0.08255)
			(type default)
		)
		(layer "In9.Cu")
	)
	(gr_line
		(start 371.759226 -310.799226)
		(end 371.992906 -310.362092)
		(stroke
			(width 0.08255)
			(type default)
		)
		(layer "In9.Cu")
	)
	(gr_line
		(start 371.78996 -308.348126)
		(end 372.023894 -307.911246)
		(stroke
			(width 0.08255)
			(type default)
		)
		(layer "In9.Cu")
	)
	(gr_line
		(start 371.935756 -309.654956)
		(end 372.265194 -309.038244)
		(stroke
			(width 0.08255)
			(type default)
		)
		(layer "In9.Cu")
	)
	(gr_line
		(start 371.950996 -310.224424)
		(end 371.95125 -310.224678)
		(stroke
			(width 0.08255)
			(type default)
		)
		(layer "In9.Cu")
	)
	(gr_line
		(start 371.962934 -314.316618)
		(end 372.292372 -313.70016)
		(stroke
			(width 0.08255)
			(type default)
		)
		(layer "In9.Cu")
	)
	(gr_line
		(start 371.966744 -307.203856)
		(end 372.296182 -306.587398)
		(stroke
			(width 0.08255)
			(type default)
		)
		(layer "In9.Cu")
	)
	(gr_line
		(start 371.992906 -310.362092)
		(end 371.951504 -310.226202)
		(stroke
			(width 0.08255)
			(type default)
		)
		(layer "In9.Cu")
	)
	(gr_line
		(start 372.023894 -307.911246)
		(end 371.982492 -307.775102)
		(stroke
			(width 0.08255)
			(type default)
		)
		(layer "In9.Cu")
	)
	(gr_line
		(start 372.184676 -309.788052)
		(end 372.184422 -309.787798)
		(stroke
			(width 0.08255)
			(type default)
		)
		(layer "In9.Cu")
	)
	(gr_line
		(start 372.1862 -309.78729)
		(end 372.32209 -309.745888)
		(stroke
			(width 0.08255)
			(type default)
		)
		(layer "In9.Cu")
	)
	(gr_line
		(start 372.211854 -314.449714)
		(end 372.2116 -314.44946)
		(stroke
			(width 0.08255)
			(type default)
		)
		(layer "In9.Cu")
	)
	(gr_line
		(start 372.213378 -314.448952)
		(end 372.349268 -314.407804)
		(stroke
			(width 0.08255)
			(type default)
		)
		(layer "In9.Cu")
	)
	(gr_line
		(start 372.216934 -307.336444)
		(end 372.352824 -307.295042)
		(stroke
			(width 0.08255)
			(type default)
		)
		(layer "In9.Cu")
	)
	(gr_line
		(start 372.32209 -309.745888)
		(end 372.55577 -309.309008)
		(stroke
			(width 0.08255)
			(type default)
		)
		(layer "In9.Cu")
	)
	(gr_line
		(start 372.349268 -314.407804)
		(end 372.582948 -313.97067)
		(stroke
			(width 0.08255)
			(type default)
		)
		(layer "In9.Cu")
	)
	(gr_line
		(start 372.352824 -307.295042)
		(end 372.586758 -306.858162)
		(stroke
			(width 0.08255)
			(type default)
		)
		(layer "In9.Cu")
	)
	(gr_line
		(start 372.49862 -308.601618)
		(end 372.828058 -307.985414)
		(stroke
			(width 0.08255)
			(type default)
		)
		(layer "In9.Cu")
	)
	(gr_line
		(start 372.51386 -309.17134)
		(end 372.514114 -309.17134)
		(stroke
			(width 0.08255)
			(type default)
		)
		(layer "In9.Cu")
	)
	(gr_line
		(start 372.525798 -313.263534)
		(end 372.855236 -312.646822)
		(stroke
			(width 0.08255)
			(type default)
		)
		(layer "In9.Cu")
	)
	(gr_line
		(start 372.541038 -313.833002)
		(end 372.541292 -313.833256)
		(stroke
			(width 0.08255)
			(type default)
		)
		(layer "In9.Cu")
	)
	(gr_line
		(start 372.55577 -309.309008)
		(end 372.514368 -309.173118)
		(stroke
			(width 0.08255)
			(type default)
		)
		(layer "In9.Cu")
	)
	(gr_line
		(start 372.582948 -313.97067)
		(end 372.541546 -313.83478)
		(stroke
			(width 0.08255)
			(type default)
		)
		(layer "In9.Cu")
	)
	(gr_line
		(start 372.586758 -306.858162)
		(end 372.545356 -306.722018)
		(stroke
			(width 0.08255)
			(type default)
		)
		(layer "In9.Cu")
	)
	(gr_line
		(start 372.74754 -308.734714)
		(end 372.747286 -308.734714)
		(stroke
			(width 0.08255)
			(type default)
		)
		(layer "In9.Cu")
	)
	(gr_line
		(start 372.74881 -308.734206)
		(end 372.884954 -308.692804)
		(stroke
			(width 0.08255)
			(type default)
		)
		(layer "In9.Cu")
	)
	(gr_line
		(start 372.774718 -313.39663)
		(end 372.774464 -313.396376)
		(stroke
			(width 0.08255)
			(type default)
		)
		(layer "In9.Cu")
	)
	(gr_line
		(start 372.776242 -313.395868)
		(end 372.912132 -313.354466)
		(stroke
			(width 0.08255)
			(type default)
		)
		(layer "In9.Cu")
	)
	(gr_line
		(start 372.884954 -308.692804)
		(end 373.118634 -308.255924)
		(stroke
			(width 0.08255)
			(type default)
		)
		(layer "In9.Cu")
	)
	(gr_line
		(start 372.912132 -313.354466)
		(end 373.145812 -312.917586)
		(stroke
			(width 0.08255)
			(type default)
		)
		(layer "In9.Cu")
	)
	(gr_line
		(start 373.061484 -307.548534)
		(end 373.390668 -306.93233)
		(stroke
			(width 0.08255)
			(type default)
		)
		(layer "In9.Cu")
	)
	(gr_line
		(start 373.088662 -312.210196)
		(end 373.4181 -311.593992)
		(stroke
			(width 0.08255)
			(type default)
		)
		(layer "In9.Cu")
	)
	(gr_line
		(start 373.103902 -312.779918)
		(end 373.104156 -312.779918)
		(stroke
			(width 0.08255)
			(type default)
		)
		(layer "In9.Cu")
	)
	(gr_line
		(start 373.118634 -308.255924)
		(end 373.077232 -308.11978)
		(stroke
			(width 0.08255)
			(type default)
		)
		(layer "In9.Cu")
	)
	(gr_line
		(start 373.145812 -312.917586)
		(end 373.10441 -312.781696)
		(stroke
			(width 0.08255)
			(type default)
		)
		(layer "In9.Cu")
	)
	(gr_line
		(start 373.15394 -305.31308)
		(end 373.647716 -304.81905)
		(stroke
			(width 0.08255)
			(type default)
		)
		(layer "In9.Cu")
	)
	(gr_line
		(start 373.26316 -316.498986)
		(end 373.679212 -315.938154)
		(stroke
			(width 0.08255)
			(type default)
		)
		(layer "In9.Cu")
	)
	(gr_line
		(start 373.311674 -307.681122)
		(end 373.447564 -307.639974)
		(stroke
			(width 0.08255)
			(type default)
		)
		(layer "In9.Cu")
	)
	(gr_line
		(start 373.337582 -312.343292)
		(end 373.337328 -312.343292)
		(stroke
			(width 0.08255)
			(type default)
		)
		(layer "In9.Cu")
	)
	(gr_line
		(start 373.338852 -312.342784)
		(end 373.474996 -312.301382)
		(stroke
			(width 0.08255)
			(type default)
		)
		(layer "In9.Cu")
	)
	(gr_line
		(start 373.355108 -305.51247)
		(end 373.497094 -305.51247)
		(stroke
			(width 0.08255)
			(type default)
		)
		(layer "In9.Cu")
	)
	(gr_line
		(start 373.447564 -307.639974)
		(end 373.681244 -307.20284)
		(stroke
			(width 0.08255)
			(type default)
		)
		(layer "In9.Cu")
	)
	(gr_line
		(start 373.458232 -314.25261)
		(end 373.843042 -313.669426)
		(stroke
			(width 0.08255)
			(type default)
		)
		(layer "In9.Cu")
	)
	(gr_line
		(start 373.474996 -312.301382)
		(end 373.708676 -311.864502)
		(stroke
			(width 0.08255)
			(type default)
		)
		(layer "In9.Cu")
	)
	(gr_line
		(start 373.491252 -316.66688)
		(end 373.63146 -316.646306)
		(stroke
			(width 0.08255)
			(type default)
		)
		(layer "In9.Cu")
	)
	(gr_line
		(start 373.497094 -305.51247)
		(end 373.84736 -305.16195)
		(stroke
			(width 0.08255)
			(type default)
		)
		(layer "In9.Cu")
	)
	(gr_line
		(start 373.63146 -316.646306)
		(end 373.926862 -316.248034)
		(stroke
			(width 0.08255)
			(type default)
		)
		(layer "In9.Cu")
	)
	(gr_line
		(start 373.651526 -311.157112)
		(end 373.980964 -310.540654)
		(stroke
			(width 0.08255)
			(type default)
		)
		(layer "In9.Cu")
	)
	(gr_line
		(start 373.681244 -307.20284)
		(end 373.640096 -307.066696)
		(stroke
			(width 0.08255)
			(type default)
		)
		(layer "In9.Cu")
	)
	(gr_line
		(start 373.695214 -314.407804)
		(end 373.834406 -314.379356)
		(stroke
			(width 0.08255)
			(type default)
		)
		(layer "In9.Cu")
	)
	(gr_line
		(start 373.708676 -311.864502)
		(end 373.667274 -311.728612)
		(stroke
			(width 0.08255)
			(type default)
		)
		(layer "In9.Cu")
	)
	(gr_line
		(start 373.834406 -314.379356)
		(end 374.107456 -313.96559)
		(stroke
			(width 0.08255)
			(type default)
		)
		(layer "In9.Cu")
	)
	(gr_line
		(start 373.84736 -305.16195)
		(end 373.84736 -305.019964)
		(stroke
			(width 0.08255)
			(type default)
		)
		(layer "In9.Cu")
	)
	(gr_line
		(start 373.901716 -311.2897)
		(end 374.03786 -311.248298)
		(stroke
			(width 0.08255)
			(type default)
		)
		(layer "In9.Cu")
	)
	(gr_line
		(start 373.926862 -316.248034)
		(end 373.906034 -316.107826)
		(stroke
			(width 0.08255)
			(type default)
		)
		(layer "In9.Cu")
	)
	(gr_line
		(start 373.97436 -315.54039)
		(end 374.390666 -314.979304)
		(stroke
			(width 0.08255)
			(type default)
		)
		(layer "In9.Cu")
	)
	(gr_line
		(start 373.997982 -304.468784)
		(end 374.492012 -303.9745)
		(stroke
			(width 0.08255)
			(type default)
		)
		(layer "In9.Cu")
	)
	(gr_line
		(start 374.015762 -315.957966)
		(end 374.200674 -315.708284)
		(stroke
			(width 0.08255)
			(type default)
		)
		(layer "In9.Cu")
	)
	(gr_line
		(start 374.03786 -311.248298)
		(end 374.27154 -310.811418)
		(stroke
			(width 0.08255)
			(type default)
		)
		(layer "In9.Cu")
	)
	(gr_line
		(start 374.107456 -313.96559)
		(end 374.078754 -313.826652)
		(stroke
			(width 0.08255)
			(type default)
		)
		(layer "In9.Cu")
	)
	(gr_line
		(start 374.115838 -313.256168)
		(end 374.500648 -312.672984)
		(stroke
			(width 0.08255)
			(type default)
		)
		(layer "In9.Cu")
	)
	(gr_line
		(start 374.19915 -304.668174)
		(end 374.341136 -304.668174)
		(stroke
			(width 0.08255)
			(type default)
		)
		(layer "In9.Cu")
	)
	(gr_line
		(start 374.202706 -315.70803)
		(end 374.342914 -315.687202)
		(stroke
			(width 0.08255)
			(type default)
		)
		(layer "In9.Cu")
	)
	(gr_line
		(start 374.214136 -310.104028)
		(end 374.543574 -309.487824)
		(stroke
			(width 0.08255)
			(type default)
		)
		(layer "In9.Cu")
	)
	(gr_line
		(start 374.25884 -316.96025)
		(end 374.674892 -316.399164)
		(stroke
			(width 0.08255)
			(type default)
		)
		(layer "In9.Cu")
	)
	(gr_line
		(start 374.27154 -310.811418)
		(end 374.230138 -310.675274)
		(stroke
			(width 0.08255)
			(type default)
		)
		(layer "In9.Cu")
	)
	(gr_line
		(start 374.327928 -151.935942)
		(end 374.327928 -151.935688)
		(stroke
			(width 0.08255)
			(type default)
		)
		(layer "In9.Cu")
	)
	(gr_line
		(start 374.341136 -304.668174)
		(end 374.691402 -304.317654)
		(stroke
			(width 0.08255)
			(type default)
		)
		(layer "In9.Cu")
	)
	(gr_line
		(start 374.342914 -315.687202)
		(end 374.638316 -315.289184)
		(stroke
			(width 0.08255)
			(type default)
		)
		(layer "In9.Cu")
	)
	(gr_line
		(start 374.35282 -313.411362)
		(end 374.492012 -313.382914)
		(stroke
			(width 0.08255)
			(type default)
		)
		(layer "In9.Cu")
	)
	(gr_line
		(start 374.394476 -305.64836)
		(end 374.88876 -305.15433)
		(stroke
			(width 0.08255)
			(type default)
		)
		(layer "In9.Cu")
	)
	(gr_line
		(start 374.46458 -310.236616)
		(end 374.60047 -310.195468)
		(stroke
			(width 0.08255)
			(type default)
		)
		(layer "In9.Cu")
	)
	(gr_line
		(start 374.486932 -317.128144)
		(end 374.627394 -317.107316)
		(stroke
			(width 0.08255)
			(type default)
		)
		(layer "In9.Cu")
	)
	(gr_line
		(start 374.492012 -313.382914)
		(end 374.765062 -312.969148)
		(stroke
			(width 0.08255)
			(type default)
		)
		(layer "In9.Cu")
	)
	(gr_line
		(start 374.492012 -303.9745)
		(end 374.828816 -303.637696)
		(stroke
			(width 0.08255)
			(type default)
		)
		(layer "In9.Cu")
	)
	(gr_line
		(start 374.595644 -305.848004)
		(end 374.737884 -305.848004)
		(stroke
			(width 0.08255)
			(type default)
		)
		(layer "In9.Cu")
	)
	(gr_line
		(start 374.60047 -310.195468)
		(end 374.83415 -309.758334)
		(stroke
			(width 0.08255)
			(type default)
		)
		(layer "In9.Cu")
	)
	(gr_line
		(start 374.627394 -317.107316)
		(end 374.922796 -316.709298)
		(stroke
			(width 0.08255)
			(type default)
		)
		(layer "In9.Cu")
	)
	(gr_line
		(start 374.638316 -315.289184)
		(end 374.617488 -315.148722)
		(stroke
			(width 0.08255)
			(type default)
		)
		(layer "In9.Cu")
	)
	(gr_line
		(start 374.685814 -314.58154)
		(end 375.10212 -314.020454)
		(stroke
			(width 0.08255)
			(type default)
		)
		(layer "In9.Cu")
	)
	(gr_line
		(start 374.691402 -304.317654)
		(end 374.691402 -304.175668)
		(stroke
			(width 0.08255)
			(type default)
		)
		(layer "In9.Cu")
	)
	(gr_line
		(start 374.691402 -304.17389)
		(end 375.028206 -303.837086)
		(stroke
			(width 0.08255)
			(type default)
		)
		(layer "In9.Cu")
	)
	(gr_line
		(start 374.737884 -305.848004)
		(end 375.088404 -305.497484)
		(stroke
			(width 0.08255)
			(type default)
		)
		(layer "In9.Cu")
	)
	(gr_line
		(start 374.765062 -312.969148)
		(end 374.73636 -312.829956)
		(stroke
			(width 0.08255)
			(type default)
		)
		(layer "In9.Cu")
	)
	(gr_line
		(start 374.773444 -312.259726)
		(end 375.158254 -311.676542)
		(stroke
			(width 0.08255)
			(type default)
		)
		(layer "In9.Cu")
	)
	(gr_line
		(start 374.80367 -314.895738)
		(end 374.912128 -314.749434)
		(stroke
			(width 0.08255)
			(type default)
		)
		(layer "In9.Cu")
	)
	(gr_line
		(start 374.83415 -309.758334)
		(end 374.793002 -309.62219)
		(stroke
			(width 0.08255)
			(type default)
		)
		(layer "In9.Cu")
	)
	(gr_line
		(start 374.913906 -314.74918)
		(end 375.054368 -314.728352)
		(stroke
			(width 0.08255)
			(type default)
		)
		(layer "In9.Cu")
	)
	(gr_line
		(start 374.922796 -316.709298)
		(end 374.901968 -316.568582)
		(stroke
			(width 0.08255)
			(type default)
		)
		(layer "In9.Cu")
	)
	(gr_line
		(start 374.969786 -316.0014)
		(end 375.386346 -315.44006)
		(stroke
			(width 0.08255)
			(type default)
		)
		(layer "In9.Cu")
	)
	(gr_line
		(start 375.010426 -312.41492)
		(end 375.149618 -312.386472)
		(stroke
			(width 0.08255)
			(type default)
		)
		(layer "In9.Cu")
	)
	(gr_line
		(start 375.054368 -314.728352)
		(end 375.34977 -314.330334)
		(stroke
			(width 0.08255)
			(type default)
		)
		(layer "In9.Cu")
	)
	(gr_line
		(start 375.088404 -305.497484)
		(end 375.08815 -305.355498)
		(stroke
			(width 0.08255)
			(type default)
		)
		(layer "In9.Cu")
	)
	(gr_line
		(start 375.149618 -312.386472)
		(end 375.422668 -311.972706)
		(stroke
			(width 0.08255)
			(type default)
		)
		(layer "In9.Cu")
	)
	(gr_line
		(start 375.197878 -316.169294)
		(end 375.338594 -316.148466)
		(stroke
			(width 0.08255)
			(type default)
		)
		(layer "In9.Cu")
	)
	(gr_line
		(start 375.338594 -316.148466)
		(end 375.633996 -315.750194)
		(stroke
			(width 0.08255)
			(type default)
		)
		(layer "In9.Cu")
	)
	(gr_line
		(start 375.345706 -108.980732)
		(end 375.453148 -108.721398)
		(stroke
			(width 0.08255)
			(type default)
		)
		(layer "In9.Cu")
	)
	(gr_line
		(start 375.34977 -314.330334)
		(end 375.328942 -314.189872)
		(stroke
			(width 0.08255)
			(type default)
		)
		(layer "In9.Cu")
	)
	(gr_line
		(start 375.397014 -313.62269)
		(end 375.813574 -313.06135)
		(stroke
			(width 0.08255)
			(type default)
		)
		(layer "In9.Cu")
	)
	(gr_line
		(start 375.41073 -111.674148)
		(end 375.678192 -111.02848)
		(stroke
			(width 0.08255)
			(type default)
		)
		(layer "In9.Cu")
	)
	(gr_line
		(start 375.422668 -311.972706)
		(end 375.393966 -311.833514)
		(stroke
			(width 0.08255)
			(type default)
		)
		(layer "In9.Cu")
	)
	(gr_line
		(start 375.43105 -311.263284)
		(end 375.816114 -310.679846)
		(stroke
			(width 0.08255)
			(type default)
		)
		(layer "In9.Cu")
	)
	(gr_line
		(start 375.453148 -108.721398)
		(end 375.730262 -108.052362)
		(stroke
			(width 0.08255)
			(type default)
		)
		(layer "In9.Cu")
	)
	(gr_line
		(start 375.591832 -313.83351)
		(end 375.623582 -313.790584)
		(stroke
			(width 0.08255)
			(type default)
		)
		(layer "In9.Cu")
	)
	(gr_line
		(start 375.606056 -109.088682)
		(end 375.713498 -108.829348)
		(stroke
			(width 0.08255)
			(type default)
		)
		(layer "In9.Cu")
	)
	(gr_line
		(start 375.62536 -313.79033)
		(end 375.765822 -313.769502)
		(stroke
			(width 0.08255)
			(type default)
		)
		(layer "In9.Cu")
	)
	(gr_line
		(start 375.633996 -315.750194)
		(end 375.613168 -315.609732)
		(stroke
			(width 0.08255)
			(type default)
		)
		(layer "In9.Cu")
	)
	(gr_line
		(start 375.668032 -311.418478)
		(end 375.807224 -311.389776)
		(stroke
			(width 0.08255)
			(type default)
		)
		(layer "In9.Cu")
	)
	(gr_line
		(start 375.672858 -111.78159)
		(end 375.803922 -111.72698)
		(stroke
			(width 0.08255)
			(type default)
		)
		(layer "In9.Cu")
	)
	(gr_line
		(start 375.68124 -315.04255)
		(end 376.097546 -314.48121)
		(stroke
			(width 0.08255)
			(type default)
		)
		(layer "In9.Cu")
	)
	(gr_line
		(start 375.715276 -108.828586)
		(end 375.863104 -108.767626)
		(stroke
			(width 0.08255)
			(type default)
		)
		(layer "In9.Cu")
	)
	(gr_line
		(start 375.730262 -108.052362)
		(end 375.919746 -107.594908)
		(stroke
			(width 0.08255)
			(type default)
		)
		(layer "In9.Cu")
	)
	(gr_line
		(start 375.765822 -313.769502)
		(end 376.061224 -313.371484)
		(stroke
			(width 0.08255)
			(type default)
		)
		(layer "In9.Cu")
	)
	(gr_line
		(start 375.803922 -111.72698)
		(end 375.993914 -111.269272)
		(stroke
			(width 0.08255)
			(type default)
		)
		(layer "In9.Cu")
	)
	(gr_line
		(start 375.807224 -311.389776)
		(end 376.080274 -310.976264)
		(stroke
			(width 0.08255)
			(type default)
		)
		(layer "In9.Cu")
	)
	(gr_line
		(start 375.863104 -108.767626)
		(end 376.052588 -108.309664)
		(stroke
			(width 0.08255)
			(type default)
		)
		(layer "In9.Cu")
	)
	(gr_line
		(start 375.867676 -110.571026)
		(end 376.135138 -109.925358)
		(stroke
			(width 0.08255)
			(type default)
		)
		(layer "In9.Cu")
	)
	(gr_line
		(start 375.903744 -329.378564)
		(end 375.854976 -329.329796)
		(stroke
			(width 0.08255)
			(type default)
		)
		(layer "In9.Cu")
	)
	(gr_line
		(start 375.909332 -315.21019)
		(end 376.049794 -315.189362)
		(stroke
			(width 0.08255)
			(type default)
		)
		(layer "In9.Cu")
	)
	(gr_line
		(start 375.919746 -107.594908)
		(end 376.19686 -106.925872)
		(stroke
			(width 0.08255)
			(type default)
		)
		(layer "In9.Cu")
	)
	(gr_line
		(start 375.969784 -329.399392)
		(end 375.903744 -329.378564)
		(stroke
			(width 0.08255)
			(type default)
		)
		(layer "In9.Cu")
	)
	(gr_line
		(start 375.990612 -108.160312)
		(end 376.180096 -107.702858)
		(stroke
			(width 0.08255)
			(type default)
		)
		(layer "In9.Cu")
	)
	(gr_line
		(start 375.993914 -111.269272)
		(end 375.939304 -111.137954)
		(stroke
			(width 0.08255)
			(type default)
		)
		(layer "In9.Cu")
	)
	(gr_line
		(start 376.049794 -315.189362)
		(end 376.345196 -314.79109)
		(stroke
			(width 0.08255)
			(type default)
		)
		(layer "In9.Cu")
	)
	(gr_line
		(start 376.052588 -108.309664)
		(end 375.991374 -108.16209)
		(stroke
			(width 0.08255)
			(type default)
		)
		(layer "In9.Cu")
	)
	(gr_line
		(start 376.061224 -313.371484)
		(end 376.040396 -313.231022)
		(stroke
			(width 0.08255)
			(type default)
		)
		(layer "In9.Cu")
	)
	(gr_line
		(start 376.080274 -310.976264)
		(end 376.051826 -310.836818)
		(stroke
			(width 0.08255)
			(type default)
		)
		(layer "In9.Cu")
	)
	(gr_line
		(start 376.117612 -307.663088)
		(end 376.611896 -307.168804)
		(stroke
			(width 0.08255)
			(type default)
		)
		(layer "In9.Cu")
	)
	(gr_line
		(start 376.129804 -110.678468)
		(end 376.260868 -110.623858)
		(stroke
			(width 0.08255)
			(type default)
		)
		(layer "In9.Cu")
	)
	(gr_line
		(start 376.181874 -107.702096)
		(end 376.329702 -107.641136)
		(stroke
			(width 0.08255)
			(type default)
		)
		(layer "In9.Cu")
	)
	(gr_line
		(start 376.260868 -110.623858)
		(end 376.45086 -110.16615)
		(stroke
			(width 0.08255)
			(type default)
		)
		(layer "In9.Cu")
	)
	(gr_line
		(start 376.31878 -307.862478)
		(end 376.460766 -307.862478)
		(stroke
			(width 0.08255)
			(type default)
		)
		(layer "In9.Cu")
	)
	(gr_line
		(start 376.324622 -109.467904)
		(end 376.592084 -108.822236)
		(stroke
			(width 0.08255)
			(type default)
		)
		(layer "In9.Cu")
	)
	(gr_line
		(start 376.329702 -107.641136)
		(end 376.519186 -107.183174)
		(stroke
			(width 0.08255)
			(type default)
		)
		(layer "In9.Cu")
	)
	(gr_line
		(start 376.341132 -314.152788)
		(end 376.39244 -314.083446)
		(stroke
			(width 0.08255)
			(type default)
		)
		(layer "In9.Cu")
	)
	(gr_line
		(start 376.345196 -314.79109)
		(end 376.324368 -314.650882)
		(stroke
			(width 0.08255)
			(type default)
		)
		(layer "In9.Cu")
	)
	(gr_line
		(start 376.39244 -314.083446)
		(end 376.809 -313.522106)
		(stroke
			(width 0.08255)
			(type default)
		)
		(layer "In9.Cu")
	)
	(gr_line
		(start 376.45086 -110.16615)
		(end 376.39625 -110.034832)
		(stroke
			(width 0.08255)
			(type default)
		)
		(layer "In9.Cu")
	)
	(gr_line
		(start 376.460766 -307.862478)
		(end 376.811286 -307.511958)
		(stroke
			(width 0.08255)
			(type default)
		)
		(layer "In9.Cu")
	)
	(gr_line
		(start 376.519186 -107.183174)
		(end 376.457972 -107.035346)
		(stroke
			(width 0.08255)
			(type default)
		)
		(layer "In9.Cu")
	)
	(gr_line
		(start 376.58675 -109.575346)
		(end 376.717814 -109.520736)
		(stroke
			(width 0.08255)
			(type default)
		)
		(layer "In9.Cu")
	)
	(gr_line
		(start 376.620786 -314.251086)
		(end 376.761248 -314.230258)
		(stroke
			(width 0.08255)
			(type default)
		)
		(layer "In9.Cu")
	)
	(gr_line
		(start 376.701812 -309.549292)
		(end 377.196096 -309.055008)
		(stroke
			(width 0.08255)
			(type default)
		)
		(layer "In9.Cu")
	)
	(gr_line
		(start 376.717814 -109.520736)
		(end 376.907806 -109.063028)
		(stroke
			(width 0.08255)
			(type default)
		)
		(layer "In9.Cu")
	)
	(gr_line
		(start 376.741436 -114.302794)
		(end 377.018296 -113.633758)
		(stroke
			(width 0.08255)
			(type default)
		)
		(layer "In9.Cu")
	)
	(gr_line
		(start 376.761248 -314.230258)
		(end 377.05665 -313.83224)
		(stroke
			(width 0.08255)
			(type default)
		)
		(layer "In9.Cu")
	)
	(gr_line
		(start 376.781568 -108.364782)
		(end 377.04903 -107.719114)
		(stroke
			(width 0.08255)
			(type default)
		)
		(layer "In9.Cu")
	)
	(gr_line
		(start 376.811286 -307.511958)
		(end 376.811286 -307.369972)
		(stroke
			(width 0.08255)
			(type default)
		)
		(layer "In9.Cu")
	)
	(gr_line
		(start 376.890026 -327.659238)
		(end 376.841258 -327.61047)
		(stroke
			(width 0.08255)
			(type default)
		)
		(layer "In9.Cu")
	)
	(gr_line
		(start 376.902726 -309.748936)
		(end 377.044966 -309.748936)
		(stroke
			(width 0.08255)
			(type default)
		)
		(layer "In9.Cu")
	)
	(gr_line
		(start 376.907806 -109.063028)
		(end 376.853196 -108.93171)
		(stroke
			(width 0.08255)
			(type default)
		)
		(layer "In9.Cu")
	)
	(gr_line
		(start 376.956066 -327.680066)
		(end 376.890026 -327.659238)
		(stroke
			(width 0.08255)
			(type default)
		)
		(layer "In9.Cu")
	)
	(gr_line
		(start 376.956066 -327.680066)
		(end 376.956066 -327.679812)
		(stroke
			(width 0.08255)
			(type default)
		)
		(layer "In9.Cu")
	)
	(gr_line
		(start 376.961908 -306.818792)
		(end 377.456192 -306.324508)
		(stroke
			(width 0.08255)
			(type default)
		)
		(layer "In9.Cu")
	)
	(gr_line
		(start 377.001786 -114.410744)
		(end 377.00204 -114.410744)
		(stroke
			(width 0.08255)
			(type default)
		)
		(layer "In9.Cu")
	)
	(gr_line
		(start 377.003564 -114.409982)
		(end 377.151392 -114.349022)
		(stroke
			(width 0.08255)
			(type default)
		)
		(layer "In9.Cu")
	)
	(gr_line
		(start 377.042172 -108.472732)
		(end 377.042172 -108.472478)
		(stroke
			(width 0.08255)
			(type default)
		)
		(layer "In9.Cu")
	)
	(gr_line
		(start 377.04395 -108.471716)
		(end 377.175014 -108.417614)
		(stroke
			(width 0.08255)
			(type default)
		)
		(layer "In9.Cu")
	)
	(gr_line
		(start 377.044966 -309.748936)
		(end 377.395486 -309.398416)
		(stroke
			(width 0.08255)
			(type default)
		)
		(layer "In9.Cu")
	)
	(gr_line
		(start 377.05665 -313.83224)
		(end 377.035822 -313.691524)
		(stroke
			(width 0.08255)
			(type default)
		)
		(layer "In9.Cu")
	)
	(gr_line
		(start 377.151392 -114.349022)
		(end 377.340876 -113.89106)
		(stroke
			(width 0.08255)
			(type default)
		)
		(layer "In9.Cu")
	)
	(gr_line
		(start 377.163076 -307.018182)
		(end 377.305062 -307.018182)
		(stroke
			(width 0.08255)
			(type default)
		)
		(layer "In9.Cu")
	)
	(gr_line
		(start 377.175014 -108.417614)
		(end 377.364752 -107.959652)
		(stroke
			(width 0.08255)
			(type default)
		)
		(layer "In9.Cu")
	)
	(gr_line
		(start 377.20778 -113.176304)
		(end 377.484894 -112.507268)
		(stroke
			(width 0.08255)
			(type default)
		)
		(layer "In9.Cu")
	)
	(gr_line
		(start 377.228354 -130.237484)
		(end 377.359672 -130.183382)
		(stroke
			(width 0.08255)
			(type default)
		)
		(layer "In9.Cu")
	)
	(gr_line
		(start 377.305062 -307.018182)
		(end 377.655582 -306.667662)
		(stroke
			(width 0.08255)
			(type default)
		)
		(layer "In9.Cu")
	)
	(gr_line
		(start 377.340876 -113.89106)
		(end 377.279662 -113.743232)
		(stroke
			(width 0.08255)
			(type default)
		)
		(layer "In9.Cu")
	)
	(gr_line
		(start 377.359672 -130.183382)
		(end 377.544584 -129.737104)
		(stroke
			(width 0.08255)
			(type default)
		)
		(layer "In9.Cu")
	)
	(gr_line
		(start 377.364752 -107.959652)
		(end 377.310396 -107.828588)
		(stroke
			(width 0.08255)
			(type default)
		)
		(layer "In9.Cu")
	)
	(gr_line
		(start 377.395486 -309.398416)
		(end 377.395486 -309.256176)
		(stroke
			(width 0.08255)
			(type default)
		)
		(layer "In9.Cu")
	)
	(gr_line
		(start 377.469908 -113.283492)
		(end 377.61799 -113.222532)
		(stroke
			(width 0.08255)
			(type default)
		)
		(layer "In9.Cu")
	)
	(gr_line
		(start 377.510548 -118.061486)
		(end 377.758452 -117.462808)
		(stroke
			(width 0.08255)
			(type default)
		)
		(layer "In9.Cu")
	)
	(gr_line
		(start 377.530106 -151.433276)
		(end 377.530106 -151.43353)
		(stroke
			(width 0.08255)
			(type default)
		)
		(layer "In9.Cu")
	)
	(gr_line
		(start 377.544584 -129.737104)
		(end 377.489974 -129.605786)
		(stroke
			(width 0.08255)
			(type default)
		)
		(layer "In9.Cu")
	)
	(gr_line
		(start 377.545854 -308.704996)
		(end 378.040392 -308.210712)
		(stroke
			(width 0.08255)
			(type default)
		)
		(layer "In9.Cu")
	)
	(gr_line
		(start 377.591066 -105.118154)
		(end 378.09424 -104.61498)
		(stroke
			(width 0.08255)
			(type default)
		)
		(layer "In9.Cu")
	)
	(gr_line
		(start 377.61799 -113.222532)
		(end 377.807474 -112.76457)
		(stroke
			(width 0.08255)
			(type default)
		)
		(layer "In9.Cu")
	)
	(gr_line
		(start 377.655582 -306.667662)
		(end 377.655582 -306.525676)
		(stroke
			(width 0.08255)
			(type default)
		)
		(layer "In9.Cu")
	)
	(gr_line
		(start 377.674378 -112.049814)
		(end 377.951492 -111.380778)
		(stroke
			(width 0.08255)
			(type default)
		)
		(layer "In9.Cu")
	)
	(gr_line
		(start 377.696984 -129.103374)
		(end 377.69673 -129.103374)
		(stroke
			(width 0.08255)
			(type default)
		)
		(layer "In9.Cu")
	)
	(gr_line
		(start 377.698508 -129.102612)
		(end 377.829826 -129.04851)
		(stroke
			(width 0.08255)
			(type default)
		)
		(layer "In9.Cu")
	)
	(gr_line
		(start 377.747022 -308.90464)
		(end 377.889262 -308.90464)
		(stroke
			(width 0.08255)
			(type default)
		)
		(layer "In9.Cu")
	)
	(gr_line
		(start 377.772676 -118.168928)
		(end 377.87072 -118.128288)
		(stroke
			(width 0.08255)
			(type default)
		)
		(layer "In9.Cu")
	)
	(gr_line
		(start 377.792234 -105.317544)
		(end 377.952 -105.317544)
		(stroke
			(width 0.08255)
			(type default)
		)
		(layer "In9.Cu")
	)
	(gr_line
		(start 377.798584 -120.185942)
		(end 378.05614 -119.563896)
		(stroke
			(width 0.08255)
			(type default)
		)
		(layer "In9.Cu")
	)
	(gr_line
		(start 377.807474 -112.76457)
		(end 377.746006 -112.616742)
		(stroke
			(width 0.08255)
			(type default)
		)
		(layer "In9.Cu")
	)
	(gr_line
		(start 377.829826 -129.04851)
		(end 378.014484 -128.602232)
		(stroke
			(width 0.08255)
			(type default)
		)
		(layer "In9.Cu")
	)
	(gr_line
		(start 377.847352 -130.798824)
		(end 378.105162 -130.176524)
		(stroke
			(width 0.08255)
			(type default)
		)
		(layer "In9.Cu")
	)
	(gr_line
		(start 377.87072 -118.128288)
		(end 378.060458 -117.670326)
		(stroke
			(width 0.08255)
			(type default)
		)
		(layer "In9.Cu")
	)
	(gr_line
		(start 377.889262 -308.90464)
		(end 378.239782 -308.55412)
		(stroke
			(width 0.08255)
			(type default)
		)
		(layer "In9.Cu")
	)
	(gr_line
		(start 377.934728 -112.157764)
		(end 377.934982 -112.157764)
		(stroke
			(width 0.08255)
			(type default)
		)
		(layer "In9.Cu")
	)
	(gr_line
		(start 377.936506 -112.157002)
		(end 378.084334 -112.096042)
		(stroke
			(width 0.08255)
			(type default)
		)
		(layer "In9.Cu")
	)
	(gr_line
		(start 377.947936 -117.005354)
		(end 378.225304 -116.336318)
		(stroke
			(width 0.08255)
			(type default)
		)
		(layer "In9.Cu")
	)
	(gr_line
		(start 377.952 -105.317544)
		(end 378.29363 -104.975914)
		(stroke
			(width 0.08255)
			(type default)
		)
		(layer "In9.Cu")
	)
	(gr_line
		(start 378.014484 -128.602232)
		(end 377.960128 -128.471168)
		(stroke
			(width 0.08255)
			(type default)
		)
		(layer "In9.Cu")
	)
	(gr_line
		(start 378.060458 -117.670326)
		(end 378.019818 -117.572282)
		(stroke
			(width 0.08255)
			(type default)
		)
		(layer "In9.Cu")
	)
	(gr_line
		(start 378.060712 -120.293384)
		(end 378.175266 -120.245886)
		(stroke
			(width 0.08255)
			(type default)
		)
		(layer "In9.Cu")
	)
	(gr_line
		(start 378.084334 -112.096042)
		(end 378.273818 -111.63808)
		(stroke
			(width 0.08255)
			(type default)
		)
		(layer "In9.Cu")
	)
	(gr_line
		(start 378.107956 -130.906774)
		(end 378.107956 -130.90652)
		(stroke
			(width 0.08255)
			(type default)
		)
		(layer "In9.Cu")
	)
	(gr_line
		(start 378.109734 -130.905758)
		(end 378.224034 -130.858514)
		(stroke
			(width 0.08255)
			(type default)
		)
		(layer "In9.Cu")
	)
	(gr_line
		(start 378.140976 -110.923324)
		(end 378.417836 -110.254288)
		(stroke
			(width 0.08255)
			(type default)
		)
		(layer "In9.Cu")
	)
	(gr_line
		(start 378.144024 -128.023874)
		(end 378.144024 -128.02362)
		(stroke
			(width 0.08255)
			(type default)
		)
		(layer "In9.Cu")
	)
	(gr_line
		(start 378.145802 -128.022858)
		(end 378.27712 -127.968756)
		(stroke
			(width 0.08255)
			(type default)
		)
		(layer "In9.Cu")
	)
	(gr_line
		(start 378.175266 -120.245886)
		(end 378.365004 -119.787924)
		(stroke
			(width 0.08255)
			(type default)
		)
		(layer "In9.Cu")
	)
	(gr_line
		(start 378.178314 -106.054906)
		(end 378.672598 -105.560622)
		(stroke
			(width 0.08255)
			(type default)
		)
		(layer "In9.Cu")
	)
	(gr_line
		(start 378.204984 -151.234902)
		(end 378.204984 -151.235156)
		(stroke
			(width 0.08255)
			(type default)
		)
		(layer "In9.Cu")
	)
	(gr_line
		(start 378.210064 -117.112542)
		(end 378.358146 -117.051582)
		(stroke
			(width 0.08255)
			(type default)
		)
		(layer "In9.Cu")
	)
	(gr_line
		(start 378.212096 -111.488728)
		(end 378.211842 -111.488728)
		(stroke
			(width 0.08255)
			(type default)
		)
		(layer "In9.Cu")
	)
	(gr_line
		(start 378.224034 -130.858514)
		(end 378.414026 -130.400552)
		(stroke
			(width 0.08255)
			(type default)
		)
		(layer "In9.Cu")
	)
	(gr_line
		(start 378.239782 -308.55412)
		(end 378.239782 -308.41188)
		(stroke
			(width 0.08255)
			(type default)
		)
		(layer "In9.Cu")
	)
	(gr_line
		(start 378.245624 -119.106442)
		(end 378.50318 -118.484396)
		(stroke
			(width 0.08255)
			(type default)
		)
		(layer "In9.Cu")
	)
	(gr_line
		(start 378.273818 -111.63808)
		(end 378.212604 -111.490506)
		(stroke
			(width 0.08255)
			(type default)
		)
		(layer "In9.Cu")
	)
	(gr_line
		(start 378.27712 -127.968756)
		(end 378.461778 -127.522478)
		(stroke
			(width 0.08255)
			(type default)
		)
		(layer "In9.Cu")
	)
	(gr_line
		(start 378.29363 -104.975914)
		(end 378.29363 -104.816148)
		(stroke
			(width 0.08255)
			(type default)
		)
		(layer "In9.Cu")
	)
	(gr_line
		(start 378.294646 -129.71907)
		(end 378.552202 -129.097024)
		(stroke
			(width 0.08255)
			(type default)
		)
		(layer "In9.Cu")
	)
	(gr_line
		(start 378.358146 -117.051582)
		(end 378.547884 -116.59362)
		(stroke
			(width 0.08255)
			(type default)
		)
		(layer "In9.Cu")
	)
	(gr_line
		(start 378.35967 -121.681494)
		(end 378.636784 -121.012458)
		(stroke
			(width 0.08255)
			(type default)
		)
		(layer "In9.Cu")
	)
	(gr_line
		(start 378.365004 -119.787924)
		(end 378.317252 -119.67337)
		(stroke
			(width 0.08255)
			(type default)
		)
		(layer "In9.Cu")
	)
	(gr_line
		(start 378.379482 -106.254296)
		(end 378.521468 -106.254296)
		(stroke
			(width 0.08255)
			(type default)
		)
		(layer "In9.Cu")
	)
	(gr_line
		(start 378.390404 -307.8607)
		(end 378.884688 -307.366416)
		(stroke
			(width 0.08255)
			(type default)
		)
		(layer "In9.Cu")
	)
	(gr_line
		(start 378.401326 -111.031274)
		(end 378.40158 -111.031274)
		(stroke
			(width 0.08255)
			(type default)
		)
		(layer "In9.Cu")
	)
	(gr_line
		(start 378.40285 -111.030512)
		(end 378.550932 -110.969552)
		(stroke
			(width 0.08255)
			(type default)
		)
		(layer "In9.Cu")
	)
	(gr_line
		(start 378.414026 -130.400552)
		(end 378.366274 -130.285998)
		(stroke
			(width 0.08255)
			(type default)
		)
		(layer "In9.Cu")
	)
	(gr_line
		(start 378.414788 -115.878864)
		(end 378.691902 -115.209828)
		(stroke
			(width 0.08255)
			(type default)
		)
		(layer "In9.Cu")
	)
	(gr_line
		(start 378.435362 -104.273858)
		(end 378.938536 -103.770684)
		(stroke
			(width 0.08255)
			(type default)
		)
		(layer "In9.Cu")
	)
	(gr_line
		(start 378.460762 -333.285592)
		(end 378.438918 -333.278734)
		(stroke
			(width 0.08255)
			(type default)
		)
		(layer "In9.Cu")
	)
	(gr_line
		(start 378.461778 -127.522478)
		(end 378.407422 -127.391414)
		(stroke
			(width 0.08255)
			(type default)
		)
		(layer "In9.Cu")
	)
	(gr_line
		(start 378.48032 -333.291688)
		(end 378.464064 -333.286608)
		(stroke
			(width 0.08255)
			(type default)
		)
		(layer "In9.Cu")
	)
	(gr_line
		(start 378.486416 -333.291688)
		(end 378.48032 -333.291688)
		(stroke
			(width 0.08255)
			(type default)
		)
		(layer "In9.Cu")
	)
	(gr_line
		(start 378.507752 -119.213884)
		(end 378.622306 -119.166386)
		(stroke
			(width 0.08255)
			(type default)
		)
		(layer "In9.Cu")
	)
	(gr_line
		(start 378.521468 -106.254296)
		(end 378.871988 -105.903776)
		(stroke
			(width 0.08255)
			(type default)
		)
		(layer "In9.Cu")
	)
	(gr_line
		(start 378.524008 -333.009748)
		(end 378.523754 -333.009748)
		(stroke
			(width 0.08255)
			(type default)
		)
		(layer "In9.Cu")
	)
	(gr_line
		(start 378.547884 -116.59362)
		(end 378.486416 -116.445538)
		(stroke
			(width 0.08255)
			(type default)
		)
		(layer "In9.Cu")
	)
	(gr_line
		(start 378.550932 -110.969552)
		(end 378.740416 -110.51159)
		(stroke
			(width 0.08255)
			(type default)
		)
		(layer "In9.Cu")
	)
	(gr_line
		(start 378.554996 -333.01686)
		(end 378.538486 -333.01305)
		(stroke
			(width 0.08255)
			(type default)
		)
		(layer "In9.Cu")
	)
	(gr_line
		(start 378.55525 -129.82702)
		(end 378.554996 -129.82702)
		(stroke
			(width 0.08255)
			(type default)
		)
		(layer "In9.Cu")
	)
	(gr_line
		(start 378.556774 -129.826258)
		(end 378.671074 -129.779014)
		(stroke
			(width 0.08255)
			(type default)
		)
		(layer "In9.Cu")
	)
	(gr_line
		(start 378.591318 -308.060344)
		(end 378.733558 -308.060344)
		(stroke
			(width 0.08255)
			(type default)
		)
		(layer "In9.Cu")
	)
	(gr_line
		(start 378.591318 -126.94412)
		(end 378.591318 -126.943866)
		(stroke
			(width 0.08255)
			(type default)
		)
		(layer "In9.Cu")
	)
	(gr_line
		(start 378.593096 -126.943104)
		(end 378.724414 -126.889002)
		(stroke
			(width 0.08255)
			(type default)
		)
		(layer "In9.Cu")
	)
	(gr_line
		(start 378.60732 -109.796834)
		(end 378.884434 -109.127798)
		(stroke
			(width 0.08255)
			(type default)
		)
		(layer "In9.Cu")
	)
	(gr_line
		(start 378.618496 -311.547764)
		(end 379.11278 -311.05348)
		(stroke
			(width 0.08255)
			(type default)
		)
		(layer "In9.Cu")
	)
	(gr_line
		(start 378.621544 -121.788936)
		(end 378.76988 -121.727722)
		(stroke
			(width 0.08255)
			(type default)
		)
		(layer "In9.Cu")
	)
	(gr_line
		(start 378.622306 -119.166386)
		(end 378.812044 -118.708424)
		(stroke
			(width 0.08255)
			(type default)
		)
		(layer "In9.Cu")
	)
	(gr_line
		(start 378.63653 -104.473248)
		(end 378.796296 -104.473248)
		(stroke
			(width 0.08255)
			(type default)
		)
		(layer "In9.Cu")
	)
	(gr_line
		(start 378.671074 -129.779014)
		(end 378.861066 -129.321052)
		(stroke
			(width 0.08255)
			(type default)
		)
		(layer "In9.Cu")
	)
	(gr_line
		(start 378.676662 -115.986306)
		(end 378.824744 -115.925092)
		(stroke
			(width 0.08255)
			(type default)
		)
		(layer "In9.Cu")
	)
	(gr_line
		(start 378.681996 -309.98541)
		(end 379.17628 -309.491126)
		(stroke
			(width 0.08255)
			(type default)
		)
		(layer "In9.Cu")
	)
	(gr_line
		(start 378.692664 -118.026942)
		(end 378.95022 -117.404896)
		(stroke
			(width 0.08255)
			(type default)
		)
		(layer "In9.Cu")
	)
	(gr_line
		(start 378.724414 -126.889002)
		(end 378.909072 -126.442724)
		(stroke
			(width 0.08255)
			(type default)
		)
		(layer "In9.Cu")
	)
	(gr_line
		(start 378.733558 -308.060344)
		(end 379.084078 -307.709824)
		(stroke
			(width 0.08255)
			(type default)
		)
		(layer "In9.Cu")
	)
	(gr_line
		(start 378.740416 -110.51159)
		(end 378.679202 -110.363762)
		(stroke
			(width 0.08255)
			(type default)
		)
		(layer "In9.Cu")
	)
	(gr_line
		(start 378.741686 -128.63957)
		(end 378.999496 -128.01727)
		(stroke
			(width 0.08255)
			(type default)
		)
		(layer "In9.Cu")
	)
	(gr_line
		(start 378.76988 -121.727722)
		(end 378.959364 -121.26976)
		(stroke
			(width 0.08255)
			(type default)
		)
		(layer "In9.Cu")
	)
	(gr_line
		(start 378.796296 -104.473248)
		(end 379.137926 -104.131618)
		(stroke
			(width 0.08255)
			(type default)
		)
		(layer "In9.Cu")
	)
	(gr_line
		(start 378.812044 -118.708424)
		(end 378.764546 -118.59387)
		(stroke
			(width 0.08255)
			(type default)
		)
		(layer "In9.Cu")
	)
	(gr_line
		(start 378.819664 -311.747154)
		(end 378.96165 -311.747154)
		(stroke
			(width 0.08255)
			(type default)
		)
		(layer "In9.Cu")
	)
	(gr_line
		(start 378.824744 -115.925092)
		(end 379.014482 -115.46713)
		(stroke
			(width 0.08255)
			(type default)
		)
		(layer "In9.Cu")
	)
	(gr_line
		(start 378.826268 -120.555004)
		(end 379.103382 -119.885968)
		(stroke
			(width 0.08255)
			(type default)
		)
		(layer "In9.Cu")
	)
	(gr_line
		(start 378.861066 -129.321052)
		(end 378.813568 -129.206498)
		(stroke
			(width 0.08255)
			(type default)
		)
		(layer "In9.Cu")
	)
	(gr_line
		(start 378.869448 -109.904276)
		(end 379.01753 -109.843062)
		(stroke
			(width 0.08255)
			(type default)
		)
		(layer "In9.Cu")
	)
	(gr_line
		(start 378.871988 -105.903776)
		(end 378.871988 -105.76179)
		(stroke
			(width 0.08255)
			(type default)
		)
		(layer "In9.Cu")
	)
	(gr_line
		(start 378.881386 -114.752374)
		(end 379.1585 -114.083338)
		(stroke
			(width 0.08255)
			(type default)
		)
		(layer "In9.Cu")
	)
	(gr_line
		(start 378.883164 -310.1848)
		(end 379.02515 -310.1848)
		(stroke
			(width 0.08255)
			(type default)
		)
		(layer "In9.Cu")
	)
	(gr_line
		(start 378.909072 -126.442724)
		(end 378.854462 -126.31166)
		(stroke
			(width 0.08255)
			(type default)
		)
		(layer "In9.Cu")
	)
	(gr_line
		(start 378.954792 -118.134384)
		(end 379.069346 -118.086886)
		(stroke
			(width 0.08255)
			(type default)
		)
		(layer "In9.Cu")
	)
	(gr_line
		(start 378.959364 -121.26976)
		(end 378.897896 -121.121932)
		(stroke
			(width 0.08255)
			(type default)
		)
		(layer "In9.Cu")
	)
	(gr_line
		(start 378.96165 -311.747154)
		(end 379.31217 -311.396634)
		(stroke
			(width 0.08255)
			(type default)
		)
		(layer "In9.Cu")
	)
	(gr_line
		(start 379.00229 -128.74752)
		(end 379.00229 -128.747266)
		(stroke
			(width 0.08255)
			(type default)
		)
		(layer "In9.Cu")
	)
	(gr_line
		(start 379.004068 -128.746504)
		(end 379.118368 -128.69926)
		(stroke
			(width 0.08255)
			(type default)
		)
		(layer "In9.Cu")
	)
	(gr_line
		(start 379.014482 -115.46713)
		(end 378.953014 -115.319048)
		(stroke
			(width 0.08255)
			(type default)
		)
		(layer "In9.Cu")
	)
	(gr_line
		(start 379.01753 -109.843062)
		(end 379.207014 -109.3851)
		(stroke
			(width 0.08255)
			(type default)
		)
		(layer "In9.Cu")
	)
	(gr_line
		(start 379.02261 -105.21061)
		(end 379.516894 -104.716326)
		(stroke
			(width 0.08255)
			(type default)
		)
		(layer "In9.Cu")
	)
	(gr_line
		(start 379.02515 -310.1848)
		(end 379.37567 -309.83428)
		(stroke
			(width 0.08255)
			(type default)
		)
		(layer "In9.Cu")
	)
	(gr_line
		(start 379.038612 -125.864366)
		(end 379.038358 -125.864366)
		(stroke
			(width 0.08255)
			(type default)
		)
		(layer "In9.Cu")
	)
	(gr_line
		(start 379.040136 -125.863604)
		(end 379.171454 -125.809502)
		(stroke
			(width 0.08255)
			(type default)
		)
		(layer "In9.Cu")
	)
	(gr_line
		(start 379.069346 -118.086886)
		(end 379.259084 -117.628924)
		(stroke
			(width 0.08255)
			(type default)
		)
		(layer "In9.Cu")
	)
	(gr_line
		(start 379.084078 -307.709824)
		(end 379.084078 -307.567584)
		(stroke
			(width 0.08255)
			(type default)
		)
		(layer "In9.Cu")
	)
	(gr_line
		(start 379.088396 -120.662446)
		(end 379.236478 -120.601232)
		(stroke
			(width 0.08255)
			(type default)
		)
		(layer "In9.Cu")
	)
	(gr_line
		(start 379.118368 -128.69926)
		(end 379.30836 -128.241298)
		(stroke
			(width 0.08255)
			(type default)
		)
		(layer "In9.Cu")
	)
	(gr_line
		(start 379.137926 -104.131618)
		(end 379.137926 -103.971852)
		(stroke
			(width 0.08255)
			(type default)
		)
		(layer "In9.Cu")
	)
	(gr_line
		(start 379.139704 -116.947442)
		(end 379.39726 -116.325396)
		(stroke
			(width 0.08255)
			(type default)
		)
		(layer "In9.Cu")
	)
	(gr_line
		(start 379.143514 -114.859816)
		(end 379.291342 -114.798602)
		(stroke
			(width 0.08255)
			(type default)
		)
		(layer "In9.Cu")
	)
	(gr_line
		(start 379.171454 -125.809502)
		(end 379.356112 -125.363224)
		(stroke
			(width 0.08255)
			(type default)
		)
		(layer "In9.Cu")
	)
	(gr_line
		(start 379.18898 -127.559816)
		(end 379.44679 -126.937516)
		(stroke
			(width 0.08255)
			(type default)
		)
		(layer "In9.Cu")
	)
	(gr_line
		(start 379.207014 -109.3851)
		(end 379.145546 -109.237272)
		(stroke
			(width 0.08255)
			(type default)
		)
		(layer "In9.Cu")
	)
	(gr_line
		(start 379.223778 -105.41)
		(end 379.365764 -105.41)
		(stroke
			(width 0.08255)
			(type default)
		)
		(layer "In9.Cu")
	)
	(gr_line
		(start 379.236478 -120.601232)
		(end 379.425962 -120.14327)
		(stroke
			(width 0.08255)
			(type default)
		)
		(layer "In9.Cu")
	)
	(gr_line
		(start 379.236478 -108.277914)
		(end 379.257814 -108.226098)
		(stroke
			(width 0.08255)
			(type default)
		)
		(layer "In9.Cu")
	)
	(gr_line
		(start 379.257814 -108.226098)
		(end 379.258322 -108.226098)
		(stroke
			(width 0.08255)
			(type default)
		)
		(layer "In9.Cu")
	)
	(gr_line
		(start 379.258322 -108.226098)
		(end 379.297946 -108.186474)
		(stroke
			(width 0.08255)
			(type default)
		)
		(layer "In9.Cu")
	)
	(gr_line
		(start 379.259084 -117.628924)
		(end 379.211586 -117.51437)
		(stroke
			(width 0.08255)
			(type default)
		)
		(layer "In9.Cu")
	)
	(gr_line
		(start 379.279658 -103.429562)
		(end 379.782832 -102.926388)
		(stroke
			(width 0.08255)
			(type default)
		)
		(layer "In9.Cu")
	)
	(gr_line
		(start 379.291342 -114.798602)
		(end 379.48108 -114.34064)
		(stroke
			(width 0.08255)
			(type default)
		)
		(layer "In9.Cu")
	)
	(gr_line
		(start 379.292866 -119.428514)
		(end 379.56998 -118.759478)
		(stroke
			(width 0.08255)
			(type default)
		)
		(layer "In9.Cu")
	)
	(gr_line
		(start 379.30836 -128.241298)
		(end 379.260862 -128.126744)
		(stroke
			(width 0.08255)
			(type default)
		)
		(layer "In9.Cu")
	)
	(gr_line
		(start 379.31217 -311.396634)
		(end 379.31217 -311.254648)
		(stroke
			(width 0.08255)
			(type default)
		)
		(layer "In9.Cu")
	)
	(gr_line
		(start 379.347984 -113.625884)
		(end 379.625098 -112.956848)
		(stroke
			(width 0.08255)
			(type default)
		)
		(layer "In9.Cu")
	)
	(gr_line
		(start 379.356112 -125.363224)
		(end 379.301756 -125.232414)
		(stroke
			(width 0.08255)
			(type default)
		)
		(layer "In9.Cu")
	)
	(gr_line
		(start 379.365764 -105.41)
		(end 379.716284 -105.05948)
		(stroke
			(width 0.08255)
			(type default)
		)
		(layer "In9.Cu")
	)
	(gr_line
		(start 379.37567 -309.83428)
		(end 379.37567 -309.692294)
		(stroke
			(width 0.08255)
			(type default)
		)
		(layer "In9.Cu")
	)
	(gr_line
		(start 379.401832 -117.05463)
		(end 379.516386 -117.007386)
		(stroke
			(width 0.08255)
			(type default)
		)
		(layer "In9.Cu")
	)
	(gr_line
		(start 379.425962 -120.14327)
		(end 379.364494 -119.995442)
		(stroke
			(width 0.08255)
			(type default)
		)
		(layer "In9.Cu")
	)
	(gr_line
		(start 379.449584 -127.667766)
		(end 379.449584 -127.667512)
		(stroke
			(width 0.08255)
			(type default)
		)
		(layer "In9.Cu")
	)
	(gr_line
		(start 379.451362 -127.66675)
		(end 379.565662 -127.619506)
		(stroke
			(width 0.08255)
			(type default)
		)
		(layer "In9.Cu")
	)
	(gr_line
		(start 379.462792 -310.703468)
		(end 379.957076 -310.209184)
		(stroke
			(width 0.08255)
			(type default)
		)
		(layer "In9.Cu")
	)
	(gr_line
		(start 379.480826 -103.628952)
		(end 379.640592 -103.628952)
		(stroke
			(width 0.08255)
			(type default)
		)
		(layer "In9.Cu")
	)
	(gr_line
		(start 379.48108 -114.34064)
		(end 379.419612 -114.192812)
		(stroke
			(width 0.08255)
			(type default)
		)
		(layer "In9.Cu")
	)
	(gr_line
		(start 379.487176 -124.784104)
		(end 379.618748 -124.730002)
		(stroke
			(width 0.08255)
			(type default)
		)
		(layer "In9.Cu")
	)
	(gr_line
		(start 379.497336 -108.385864)
		(end 379.497082 -108.385864)
		(stroke
			(width 0.08255)
			(type default)
		)
		(layer "In9.Cu")
	)
	(gr_line
		(start 379.516386 -117.007386)
		(end 379.706124 -116.549424)
		(stroke
			(width 0.08255)
			(type default)
		)
		(layer "In9.Cu")
	)
	(gr_line
		(start 379.526292 -309.141114)
		(end 380.020576 -308.64683)
		(stroke
			(width 0.08255)
			(type default)
		)
		(layer "In9.Cu")
	)
	(gr_line
		(start 379.554994 -119.535956)
		(end 379.703076 -119.474742)
		(stroke
			(width 0.08255)
			(type default)
		)
		(layer "In9.Cu")
	)
	(gr_line
		(start 379.565662 -127.619506)
		(end 379.755654 -127.161544)
		(stroke
			(width 0.08255)
			(type default)
		)
		(layer "In9.Cu")
	)
	(gr_line
		(start 379.586744 -115.867942)
		(end 379.844554 -115.245896)
		(stroke
			(width 0.08255)
			(type default)
		)
		(layer "In9.Cu")
	)
	(gr_line
		(start 379.610112 -113.733326)
		(end 379.758194 -113.672112)
		(stroke
			(width 0.08255)
			(type default)
		)
		(layer "In9.Cu")
	)
	(gr_line
		(start 379.618748 -124.730002)
		(end 379.803406 -124.283724)
		(stroke
			(width 0.08255)
			(type default)
		)
		(layer "In9.Cu")
	)
	(gr_line
		(start 379.636274 -126.480062)
		(end 379.89383 -125.858016)
		(stroke
			(width 0.08255)
			(type default)
		)
		(layer "In9.Cu")
	)
	(gr_line
		(start 379.640592 -103.628952)
		(end 379.982222 -103.287322)
		(stroke
			(width 0.08255)
			(type default)
		)
		(layer "In9.Cu")
	)
	(gr_line
		(start 379.66396 -310.902858)
		(end 379.805946 -310.902858)
		(stroke
			(width 0.08255)
			(type default)
		)
		(layer "In9.Cu")
	)
	(gr_line
		(start 379.703076 -119.474742)
		(end 379.89256 -119.01678)
		(stroke
			(width 0.08255)
			(type default)
		)
		(layer "In9.Cu")
	)
	(gr_line
		(start 379.706124 -116.549424)
		(end 379.658626 -116.43487)
		(stroke
			(width 0.08255)
			(type default)
		)
		(layer "In9.Cu")
	)
	(gr_line
		(start 379.716284 -105.05948)
		(end 379.716284 -104.917494)
		(stroke
			(width 0.08255)
			(type default)
		)
		(layer "In9.Cu")
	)
	(gr_line
		(start 379.72746 -309.340504)
		(end 379.869446 -309.340504)
		(stroke
			(width 0.08255)
			(type default)
		)
		(layer "In9.Cu")
	)
	(gr_line
		(start 379.755654 -127.161544)
		(end 379.707902 -127.04699)
		(stroke
			(width 0.08255)
			(type default)
		)
		(layer "In9.Cu")
	)
	(gr_line
		(start 379.758194 -113.672112)
		(end 379.947678 -113.21415)
		(stroke
			(width 0.08255)
			(type default)
		)
		(layer "In9.Cu")
	)
	(gr_line
		(start 379.759464 -118.302024)
		(end 380.036578 -117.632988)
		(stroke
			(width 0.08255)
			(type default)
		)
		(layer "In9.Cu")
	)
	(gr_line
		(start 379.803406 -124.283724)
		(end 379.748796 -124.15266)
		(stroke
			(width 0.08255)
			(type default)
		)
		(layer "In9.Cu")
	)
	(gr_line
		(start 379.805946 -310.902858)
		(end 380.156466 -310.552338)
		(stroke
			(width 0.08255)
			(type default)
		)
		(layer "In9.Cu")
	)
	(gr_line
		(start 379.806708 -138.41476)
		(end 379.52934 -137.745724)
		(stroke
			(width 0.08255)
			(type default)
		)
		(layer "In9.Cu")
	)
	(gr_line
		(start 379.814582 -112.499394)
		(end 380.091696 -111.830358)
		(stroke
			(width 0.08255)
			(type default)
		)
		(layer "In9.Cu")
	)
	(gr_line
		(start 379.821186 -107.663234)
		(end 380.31547 -107.16895)
		(stroke
			(width 0.08255)
			(type default)
		)
		(layer "In9.Cu")
	)
	(gr_line
		(start 379.848872 -115.97513)
		(end 379.963426 -115.927886)
		(stroke
			(width 0.08255)
			(type default)
		)
		(layer "In9.Cu")
	)
	(gr_line
		(start 379.866906 -104.366314)
		(end 380.36119 -103.87203)
		(stroke
			(width 0.08255)
			(type default)
		)
		(layer "In9.Cu")
	)
	(gr_line
		(start 379.869446 -309.340504)
		(end 380.219966 -308.989984)
		(stroke
			(width 0.08255)
			(type default)
		)
		(layer "In9.Cu")
	)
	(gr_line
		(start 379.89256 -119.01678)
		(end 379.831092 -118.868952)
		(stroke
			(width 0.08255)
			(type default)
		)
		(layer "In9.Cu")
	)
	(gr_line
		(start 379.896878 -126.588012)
		(end 379.896624 -126.588012)
		(stroke
			(width 0.08255)
			(type default)
		)
		(layer "In9.Cu")
	)
	(gr_line
		(start 379.898402 -126.58725)
		(end 380.012702 -126.540006)
		(stroke
			(width 0.08255)
			(type default)
		)
		(layer "In9.Cu")
	)
	(gr_line
		(start 379.932946 -123.705366)
		(end 379.932692 -123.705366)
		(stroke
			(width 0.08255)
			(type default)
		)
		(layer "In9.Cu")
	)
	(gr_line
		(start 379.93447 -123.704604)
		(end 380.065788 -123.650502)
		(stroke
			(width 0.08255)
			(type default)
		)
		(layer "In9.Cu")
	)
	(gr_line
		(start 379.93955 -137.69975)
		(end 379.791468 -137.638536)
		(stroke
			(width 0.08255)
			(type default)
		)
		(layer "In9.Cu")
	)
	(gr_line
		(start 379.947678 -113.21415)
		(end 379.88621 -113.066322)
		(stroke
			(width 0.08255)
			(type default)
		)
		(layer "In9.Cu")
	)
	(gr_line
		(start 379.963426 -115.927886)
		(end 380.153164 -115.469924)
		(stroke
			(width 0.08255)
			(type default)
		)
		(layer "In9.Cu")
	)
	(gr_line
		(start 379.982222 -103.287322)
		(end 379.982222 -103.127556)
		(stroke
			(width 0.08255)
			(type default)
		)
		(layer "In9.Cu")
	)
	(gr_line
		(start 380.012702 -126.540006)
		(end 380.202694 -126.082044)
		(stroke
			(width 0.08255)
			(type default)
		)
		(layer "In9.Cu")
	)
	(gr_line
		(start 380.021592 -118.409466)
		(end 380.169674 -118.348252)
		(stroke
			(width 0.08255)
			(type default)
		)
		(layer "In9.Cu")
	)
	(gr_line
		(start 380.022354 -107.862624)
		(end 380.16434 -107.862624)
		(stroke
			(width 0.08255)
			(type default)
		)
		(layer "In9.Cu")
	)
	(gr_line
		(start 380.034038 -114.788442)
		(end 380.291594 -114.166396)
		(stroke
			(width 0.08255)
			(type default)
		)
		(layer "In9.Cu")
	)
	(gr_line
		(start 380.065788 -123.650502)
		(end 380.250446 -123.204224)
		(stroke
			(width 0.08255)
			(type default)
		)
		(layer "In9.Cu")
	)
	(gr_line
		(start 380.06782 -138.30554)
		(end 380.129034 -138.157458)
		(stroke
			(width 0.08255)
			(type default)
		)
		(layer "In9.Cu")
	)
	(gr_line
		(start 380.068074 -104.565704)
		(end 380.21006 -104.565704)
		(stroke
			(width 0.08255)
			(type default)
		)
		(layer "In9.Cu")
	)
	(gr_line
		(start 380.07671 -112.606836)
		(end 380.224792 -112.545622)
		(stroke
			(width 0.08255)
			(type default)
		)
		(layer "In9.Cu")
	)
	(gr_line
		(start 380.083314 -125.400562)
		(end 380.341124 -124.778262)
		(stroke
			(width 0.08255)
			(type default)
		)
		(layer "In9.Cu")
	)
	(gr_line
		(start 380.105158 -115.353846)
		(end 380.104904 -115.353846)
		(stroke
			(width 0.08255)
			(type default)
		)
		(layer "In9.Cu")
	)
	(gr_line
		(start 380.123954 -102.585266)
		(end 380.627128 -102.082092)
		(stroke
			(width 0.08255)
			(type default)
		)
		(layer "In9.Cu")
	)
	(gr_line
		(start 380.129034 -138.157458)
		(end 379.93955 -137.69975)
		(stroke
			(width 0.08255)
			(type default)
		)
		(layer "In9.Cu")
	)
	(gr_line
		(start 380.153164 -115.469924)
		(end 380.105666 -115.355624)
		(stroke
			(width 0.08255)
			(type default)
		)
		(layer "In9.Cu")
	)
	(gr_line
		(start 380.156466 -310.552338)
		(end 380.156466 -310.410352)
		(stroke
			(width 0.08255)
			(type default)
		)
		(layer "In9.Cu")
	)
	(gr_line
		(start 380.16434 -107.862624)
		(end 380.51486 -107.512104)
		(stroke
			(width 0.08255)
			(type default)
		)
		(layer "In9.Cu")
	)
	(gr_line
		(start 380.169674 -118.348252)
		(end 380.359158 -117.89029)
		(stroke
			(width 0.08255)
			(type default)
		)
		(layer "In9.Cu")
	)
	(gr_line
		(start 380.202694 -126.082044)
		(end 380.155196 -125.96749)
		(stroke
			(width 0.08255)
			(type default)
		)
		(layer "In9.Cu")
	)
	(gr_line
		(start 380.21006 -104.565704)
		(end 380.56058 -104.215184)
		(stroke
			(width 0.08255)
			(type default)
		)
		(layer "In9.Cu")
	)
	(gr_line
		(start 380.219966 -308.989984)
		(end 380.219966 -308.847998)
		(stroke
			(width 0.08255)
			(type default)
		)
		(layer "In9.Cu")
	)
	(gr_line
		(start 380.224792 -112.545622)
		(end 380.414276 -112.08766)
		(stroke
			(width 0.08255)
			(type default)
		)
		(layer "In9.Cu")
	)
	(gr_line
		(start 380.226062 -117.175534)
		(end 380.503176 -116.506498)
		(stroke
			(width 0.08255)
			(type default)
		)
		(layer "In9.Cu")
	)
	(gr_line
		(start 380.250446 -123.204224)
		(end 380.19609 -123.07316)
		(stroke
			(width 0.08255)
			(type default)
		)
		(layer "In9.Cu")
	)
	(gr_line
		(start 380.273306 -139.54125)
		(end 379.996192 -138.872214)
		(stroke
			(width 0.08255)
			(type default)
		)
		(layer "In9.Cu")
	)
	(gr_line
		(start 380.28118 -111.372904)
		(end 380.558294 -110.703868)
		(stroke
			(width 0.08255)
			(type default)
		)
		(layer "In9.Cu")
	)
	(gr_line
		(start 380.294388 -114.896392)
		(end 380.294642 -114.896392)
		(stroke
			(width 0.08255)
			(type default)
		)
		(layer "In9.Cu")
	)
	(gr_line
		(start 380.296166 -114.89563)
		(end 380.410466 -114.848132)
		(stroke
			(width 0.08255)
			(type default)
		)
		(layer "In9.Cu")
	)
	(gr_line
		(start 380.307088 -309.859172)
		(end 380.801372 -309.364888)
		(stroke
			(width 0.08255)
			(type default)
		)
		(layer "In9.Cu")
	)
	(gr_line
		(start 380.325122 -102.784656)
		(end 380.484888 -102.784656)
		(stroke
			(width 0.08255)
			(type default)
		)
		(layer "In9.Cu")
	)
	(gr_line
		(start 380.343918 -125.508512)
		(end 380.343918 -125.508258)
		(stroke
			(width 0.08255)
			(type default)
		)
		(layer "In9.Cu")
	)
	(gr_line
		(start 380.345696 -125.507496)
		(end 380.459996 -125.460252)
		(stroke
			(width 0.08255)
			(type default)
		)
		(layer "In9.Cu")
	)
	(gr_line
		(start 380.359158 -117.89029)
		(end 380.29769 -117.742462)
		(stroke
			(width 0.08255)
			(type default)
		)
		(layer "In9.Cu")
	)
	(gr_line
		(start 380.367794 -131.484624)
		(end 380.77013 -130.882644)
		(stroke
			(width 0.08255)
			(type default)
		)
		(layer "In9.Cu")
	)
	(gr_line
		(start 380.370588 -308.296818)
		(end 380.864618 -307.802788)
		(stroke
			(width 0.08255)
			(type default)
		)
		(layer "In9.Cu")
	)
	(gr_line
		(start 380.38151 -122.625104)
		(end 380.512828 -122.571002)
		(stroke
			(width 0.08255)
			(type default)
		)
		(layer "In9.Cu")
	)
	(gr_line
		(start 380.406402 -138.82624)
		(end 380.258066 -138.764772)
		(stroke
			(width 0.08255)
			(type default)
		)
		(layer "In9.Cu")
	)
	(gr_line
		(start 380.410466 -114.848132)
		(end 380.600204 -114.39017)
		(stroke
			(width 0.08255)
			(type default)
		)
		(layer "In9.Cu")
	)
	(gr_line
		(start 380.414276 -112.08766)
		(end 380.353062 -111.939832)
		(stroke
			(width 0.08255)
			(type default)
		)
		(layer "In9.Cu")
	)
	(gr_line
		(start 380.459996 -125.460252)
		(end 380.649988 -125.00229)
		(stroke
			(width 0.08255)
			(type default)
		)
		(layer "In9.Cu")
	)
	(gr_line
		(start 380.481078 -113.708688)
		(end 380.738634 -113.086642)
		(stroke
			(width 0.08255)
			(type default)
		)
		(layer "In9.Cu")
	)
	(gr_line
		(start 380.484888 -102.784656)
		(end 380.826518 -102.443026)
		(stroke
			(width 0.08255)
			(type default)
		)
		(layer "In9.Cu")
	)
	(gr_line
		(start 380.48819 -117.282976)
		(end 380.636272 -117.221762)
		(stroke
			(width 0.08255)
			(type default)
		)
		(layer "In9.Cu")
	)
	(gr_line
		(start 380.508256 -310.058562)
		(end 380.650242 -310.058562)
		(stroke
			(width 0.08255)
			(type default)
		)
		(layer "In9.Cu")
	)
	(gr_line
		(start 380.512828 -122.571002)
		(end 380.697486 -122.124724)
		(stroke
			(width 0.08255)
			(type default)
		)
		(layer "In9.Cu")
	)
	(gr_line
		(start 380.51486 -107.512104)
		(end 380.51486 -107.370118)
		(stroke
			(width 0.08255)
			(type default)
		)
		(layer "In9.Cu")
	)
	(gr_line
		(start 380.530608 -124.320808)
		(end 380.788418 -123.698508)
		(stroke
			(width 0.08255)
			(type default)
		)
		(layer "In9.Cu")
	)
	(gr_line
		(start 380.534418 -139.43203)
		(end 380.595886 -139.283948)
		(stroke
			(width 0.08255)
			(type default)
		)
		(layer "In9.Cu")
	)
	(gr_line
		(start 380.543308 -111.480092)
		(end 380.69139 -111.419132)
		(stroke
			(width 0.08255)
			(type default)
		)
		(layer "In9.Cu")
	)
	(gr_line
		(start 380.552198 -114.274346)
		(end 380.551944 -114.274092)
		(stroke
			(width 0.08255)
			(type default)
		)
		(layer "In9.Cu")
	)
	(gr_line
		(start 380.56058 -104.215184)
		(end 380.56058 -104.073198)
		(stroke
			(width 0.08255)
			(type default)
		)
		(layer "In9.Cu")
	)
	(gr_line
		(start 380.571756 -308.496208)
		(end 380.713488 -308.496208)
		(stroke
			(width 0.08255)
			(type default)
		)
		(layer "In9.Cu")
	)
	(gr_line
		(start 380.595886 -139.283948)
		(end 380.406402 -138.82624)
		(stroke
			(width 0.08255)
			(type default)
		)
		(layer "In9.Cu")
	)
	(gr_line
		(start 380.600204 -114.39017)
		(end 380.552706 -114.27587)
		(stroke
			(width 0.08255)
			(type default)
		)
		(layer "In9.Cu")
	)
	(gr_line
		(start 380.60376 -131.641088)
		(end 380.760732 -131.609846)
		(stroke
			(width 0.08255)
			(type default)
		)
		(layer "In9.Cu")
	)
	(gr_line
		(start 380.636272 -117.221762)
		(end 380.825756 -116.7638)
		(stroke
			(width 0.08255)
			(type default)
		)
		(layer "In9.Cu")
	)
	(gr_line
		(start 380.649988 -125.00229)
		(end 380.60249 -124.887736)
		(stroke
			(width 0.08255)
			(type default)
		)
		(layer "In9.Cu")
	)
	(gr_line
		(start 380.650242 -310.058562)
		(end 381.000762 -309.708042)
		(stroke
			(width 0.08255)
			(type default)
		)
		(layer "In9.Cu")
	)
	(gr_line
		(start 380.665482 -106.818938)
		(end 381.1778 -106.30662)
		(stroke
			(width 0.08255)
			(type default)
		)
		(layer "In9.Cu")
	)
	(gr_line
		(start 380.69139 -111.419132)
		(end 380.880874 -110.96117)
		(stroke
			(width 0.08255)
			(type default)
		)
		(layer "In9.Cu")
	)
	(gr_line
		(start 380.69266 -116.049044)
		(end 380.969774 -115.380008)
		(stroke
			(width 0.08255)
			(type default)
		)
		(layer "In9.Cu")
	)
	(gr_line
		(start 380.697486 -122.124724)
		(end 380.64313 -121.99366)
		(stroke
			(width 0.08255)
			(type default)
		)
		(layer "In9.Cu")
	)
	(gr_line
		(start 380.711202 -103.522018)
		(end 381.178308 -103.054912)
		(stroke
			(width 0.08255)
			(type default)
		)
		(layer "In9.Cu")
	)
	(gr_line
		(start 380.713488 -308.496208)
		(end 381.064008 -308.145688)
		(stroke
			(width 0.08255)
			(type default)
		)
		(layer "In9.Cu")
	)
	(gr_line
		(start 380.739904 -140.66774)
		(end 380.46279 -139.998704)
		(stroke
			(width 0.08255)
			(type default)
		)
		(layer "In9.Cu")
	)
	(gr_line
		(start 380.741428 -113.816638)
		(end 380.741682 -113.816638)
		(stroke
			(width 0.08255)
			(type default)
		)
		(layer "In9.Cu")
	)
	(gr_line
		(start 380.743206 -113.815876)
		(end 380.85776 -113.768632)
		(stroke
			(width 0.08255)
			(type default)
		)
		(layer "In9.Cu")
	)
	(gr_line
		(start 380.760732 -131.609846)
		(end 381.036068 -131.197858)
		(stroke
			(width 0.08255)
			(type default)
		)
		(layer "In9.Cu")
	)
	(gr_line
		(start 380.791212 -124.428758)
		(end 380.791212 -124.428504)
		(stroke
			(width 0.08255)
			(type default)
		)
		(layer "In9.Cu")
	)
	(gr_line
		(start 380.79299 -124.427742)
		(end 380.90729 -124.380498)
		(stroke
			(width 0.08255)
			(type default)
		)
		(layer "In9.Cu")
	)
	(gr_line
		(start 380.825756 -116.7638)
		(end 380.764288 -116.615972)
		(stroke
			(width 0.08255)
			(type default)
		)
		(layer "In9.Cu")
	)
	(gr_line
		(start 380.826518 -102.443026)
		(end 380.826518 -102.28326)
		(stroke
			(width 0.08255)
			(type default)
		)
		(layer "In9.Cu")
	)
	(gr_line
		(start 380.85776 -113.768632)
		(end 381.047498 -113.31067)
		(stroke
			(width 0.08255)
			(type default)
		)
		(layer "In9.Cu")
	)
	(gr_line
		(start 380.86665 -107.018328)
		(end 381.02667 -107.018328)
		(stroke
			(width 0.08255)
			(type default)
		)
		(layer "In9.Cu")
	)
	(gr_line
		(start 380.873 -139.95273)
		(end 380.724664 -139.891262)
		(stroke
			(width 0.08255)
			(type default)
		)
		(layer "In9.Cu")
	)
	(gr_line
		(start 380.880874 -110.96117)
		(end 380.81966 -110.813342)
		(stroke
			(width 0.08255)
			(type default)
		)
		(layer "In9.Cu")
	)
	(gr_line
		(start 380.90729 -124.380498)
		(end 381.097028 -123.92279)
		(stroke
			(width 0.08255)
			(type default)
		)
		(layer "In9.Cu")
	)
	(gr_line
		(start 380.91237 -103.721408)
		(end 381.036068 -103.721408)
		(stroke
			(width 0.08255)
			(type default)
		)
		(layer "In9.Cu")
	)
	(gr_line
		(start 380.928118 -112.629188)
		(end 381.185928 -112.007142)
		(stroke
			(width 0.08255)
			(type default)
		)
		(layer "In9.Cu")
	)
	(gr_line
		(start 380.954788 -116.156486)
		(end 381.10287 -116.095272)
		(stroke
			(width 0.08255)
			(type default)
		)
		(layer "In9.Cu")
	)
	(gr_line
		(start 380.96825 -101.74097)
		(end 381.47117 -101.23805)
		(stroke
			(width 0.08255)
			(type default)
		)
		(layer "In9.Cu")
	)
	(gr_line
		(start 381.000762 -309.708042)
		(end 381.000762 -309.566056)
		(stroke
			(width 0.08255)
			(type default)
		)
		(layer "In9.Cu")
	)
	(gr_line
		(start 381.001016 -140.558266)
		(end 381.062484 -140.410438)
		(stroke
			(width 0.08255)
			(type default)
		)
		(layer "In9.Cu")
	)
	(gr_line
		(start 381.02667 -107.018328)
		(end 381.37719 -106.667808)
		(stroke
			(width 0.08255)
			(type default)
		)
		(layer "In9.Cu")
	)
	(gr_line
		(start 381.036068 -131.197858)
		(end 381.004826 -131.040886)
		(stroke
			(width 0.08255)
			(type default)
		)
		(layer "In9.Cu")
	)
	(gr_line
		(start 381.036068 -103.721408)
		(end 381.377698 -103.380032)
		(stroke
			(width 0.08255)
			(type default)
		)
		(layer "In9.Cu")
	)
	(gr_line
		(start 381.045212 -130.47091)
		(end 381.447294 -129.86893)
		(stroke
			(width 0.08255)
			(type default)
		)
		(layer "In9.Cu")
	)
	(gr_line
		(start 381.047498 -113.31067)
		(end 381 -113.196116)
		(stroke
			(width 0.08255)
			(type default)
		)
		(layer "In9.Cu")
	)
	(gr_line
		(start 381.062484 -140.410438)
		(end 380.873 -139.95273)
		(stroke
			(width 0.08255)
			(type default)
		)
		(layer "In9.Cu")
	)
	(gr_line
		(start 381.064008 -308.145688)
		(end 381.064008 -308.003956)
		(stroke
			(width 0.08255)
			(type default)
		)
		(layer "In9.Cu")
	)
	(gr_line
		(start 381.097028 -123.92279)
		(end 381.04953 -123.807982)
		(stroke
			(width 0.08255)
			(type default)
		)
		(layer "In9.Cu")
	)
	(gr_line
		(start 381.10287 -116.095272)
		(end 381.292354 -115.63731)
		(stroke
			(width 0.08255)
			(type default)
		)
		(layer "In9.Cu")
	)
	(gr_line
		(start 381.159258 -114.922554)
		(end 381.436372 -114.253518)
		(stroke
			(width 0.08255)
			(type default)
		)
		(layer "In9.Cu")
	)
	(gr_line
		(start 381.169418 -101.94036)
		(end 381.329184 -101.94036)
		(stroke
			(width 0.08255)
			(type default)
		)
		(layer "In9.Cu")
	)
	(gr_line
		(start 381.186944 -141.74724)
		(end 380.929388 -141.125194)
		(stroke
			(width 0.08255)
			(type default)
		)
		(layer "In9.Cu")
	)
	(gr_line
		(start 381.190246 -112.736376)
		(end 381.305054 -112.689132)
		(stroke
			(width 0.08255)
			(type default)
		)
		(layer "In9.Cu")
	)
	(gr_line
		(start 381.281178 -130.627374)
		(end 381.43815 -130.596132)
		(stroke
			(width 0.08255)
			(type default)
		)
		(layer "In9.Cu")
	)
	(gr_line
		(start 381.292354 -115.63731)
		(end 381.23114 -115.489482)
		(stroke
			(width 0.08255)
			(type default)
		)
		(layer "In9.Cu")
	)
	(gr_line
		(start 381.305054 -112.689132)
		(end 381.494792 -112.23117)
		(stroke
			(width 0.08255)
			(type default)
		)
		(layer "In9.Cu")
	)
	(gr_line
		(start 381.30607 -141.06525)
		(end 381.191516 -141.017752)
		(stroke
			(width 0.08255)
			(type default)
		)
		(layer "In9.Cu")
	)
	(gr_line
		(start 381.329184 -101.94036)
		(end 381.67056 -101.598984)
		(stroke
			(width 0.08255)
			(type default)
		)
		(layer "In9.Cu")
	)
	(gr_line
		(start 381.375412 -111.549688)
		(end 381.396748 -111.497872)
		(stroke
			(width 0.08255)
			(type default)
		)
		(layer "In9.Cu")
	)
	(gr_line
		(start 381.37719 -106.667808)
		(end 381.37719 -106.507788)
		(stroke
			(width 0.08255)
			(type default)
		)
		(layer "In9.Cu")
	)
	(gr_line
		(start 381.377698 -103.380032)
		(end 381.377698 -103.25608)
		(stroke
			(width 0.08255)
			(type default)
		)
		(layer "In9.Cu")
	)
	(gr_line
		(start 381.396748 -111.497872)
		(end 381.436626 -111.457994)
		(stroke
			(width 0.08255)
			(type default)
		)
		(layer "In9.Cu")
	)
	(gr_line
		(start 381.421386 -115.029742)
		(end 381.569468 -114.968782)
		(stroke
			(width 0.08255)
			(type default)
		)
		(layer "In9.Cu")
	)
	(gr_line
		(start 381.428752 -120.868694)
		(end 381.588518 -120.868694)
		(stroke
			(width 0.08255)
			(type default)
		)
		(layer "In9.Cu")
	)
	(gr_line
		(start 381.43815 -130.596132)
		(end 381.713486 -130.184144)
		(stroke
			(width 0.08255)
			(type default)
		)
		(layer "In9.Cu")
	)
	(gr_line
		(start 381.44831 -141.63802)
		(end 381.495808 -141.523212)
		(stroke
			(width 0.08255)
			(type default)
		)
		(layer "In9.Cu")
	)
	(gr_line
		(start 381.46863 -109.495336)
		(end 381.928624 -109.035342)
		(stroke
			(width 0.08255)
			(type default)
		)
		(layer "In9.Cu")
	)
	(gr_line
		(start 381.494792 -112.23117)
		(end 381.44704 -112.116362)
		(stroke
			(width 0.08255)
			(type default)
		)
		(layer "In9.Cu")
	)
	(gr_line
		(start 381.495808 -141.523212)
		(end 381.30607 -141.06525)
		(stroke
			(width 0.08255)
			(type default)
		)
		(layer "In9.Cu")
	)
	(gr_line
		(start 381.51943 -102.71379)
		(end 381.98679 -102.24643)
		(stroke
			(width 0.08255)
			(type default)
		)
		(layer "In9.Cu")
	)
	(gr_line
		(start 381.527812 -105.956608)
		(end 382.04013 -105.44429)
		(stroke
			(width 0.08255)
			(type default)
		)
		(layer "In9.Cu")
	)
	(gr_line
		(start 381.569468 -114.968782)
		(end 381.758952 -114.51082)
		(stroke
			(width 0.08255)
			(type default)
		)
		(layer "In9.Cu")
	)
	(gr_line
		(start 381.572008 -122.386852)
		(end 382.066292 -121.892568)
		(stroke
			(width 0.08255)
			(type default)
		)
		(layer "In9.Cu")
	)
	(gr_line
		(start 381.588518 -120.868694)
		(end 381.929894 -120.527318)
		(stroke
			(width 0.08255)
			(type default)
		)
		(layer "In9.Cu")
	)
	(gr_line
		(start 381.625856 -113.796064)
		(end 381.90297 -113.127028)
		(stroke
			(width 0.08255)
			(type default)
		)
		(layer "In9.Cu")
	)
	(gr_line
		(start 381.636016 -111.657384)
		(end 381.636016 -111.657638)
		(stroke
			(width 0.08255)
			(type default)
		)
		(layer "In9.Cu")
	)
	(gr_line
		(start 381.669798 -109.694726)
		(end 381.786384 -109.694726)
		(stroke
			(width 0.08255)
			(type default)
		)
		(layer "In9.Cu")
	)
	(gr_line
		(start 381.67056 -101.598984)
		(end 381.67056 -101.439218)
		(stroke
			(width 0.08255)
			(type default)
		)
		(layer "In9.Cu")
	)
	(gr_line
		(start 381.713486 -130.184144)
		(end 381.682244 -130.027172)
		(stroke
			(width 0.08255)
			(type default)
		)
		(layer "In9.Cu")
	)
	(gr_line
		(start 381.720598 -102.91318)
		(end 381.84455 -102.91318)
		(stroke
			(width 0.08255)
			(type default)
		)
		(layer "In9.Cu")
	)
	(gr_line
		(start 381.72263 -129.457196)
		(end 382.124966 -128.854962)
		(stroke
			(width 0.08255)
			(type default)
		)
		(layer "In9.Cu")
	)
	(gr_line
		(start 381.72898 -106.155998)
		(end 381.889 -106.155998)
		(stroke
			(width 0.08255)
			(type default)
		)
		(layer "In9.Cu")
	)
	(gr_line
		(start 381.758952 -114.51082)
		(end 381.697738 -114.362992)
		(stroke
			(width 0.08255)
			(type default)
		)
		(layer "In9.Cu")
	)
	(gr_line
		(start 381.773176 -122.586242)
		(end 381.915162 -122.586242)
		(stroke
			(width 0.08255)
			(type default)
		)
		(layer "In9.Cu")
	)
	(gr_line
		(start 381.786384 -109.694726)
		(end 382.128014 -109.35335)
		(stroke
			(width 0.08255)
			(type default)
		)
		(layer "In9.Cu")
	)
	(gr_line
		(start 381.84455 -102.91318)
		(end 382.18618 -102.57155)
		(stroke
			(width 0.08255)
			(type default)
		)
		(layer "In9.Cu")
	)
	(gr_line
		(start 381.887984 -113.903252)
		(end 382.036066 -113.842292)
		(stroke
			(width 0.08255)
			(type default)
		)
		(layer "In9.Cu")
	)
	(gr_line
		(start 381.889 -106.155998)
		(end 382.23952 -105.805478)
		(stroke
			(width 0.08255)
			(type default)
		)
		(layer "In9.Cu")
	)
	(gr_line
		(start 381.915162 -122.586242)
		(end 382.265682 -122.235722)
		(stroke
			(width 0.08255)
			(type default)
		)
		(layer "In9.Cu")
	)
	(gr_line
		(start 381.929894 -120.527318)
		(end 381.929894 -120.367552)
		(stroke
			(width 0.08255)
			(type default)
		)
		(layer "In9.Cu")
	)
	(gr_line
		(start 381.958596 -129.61366)
		(end 382.115568 -129.582164)
		(stroke
			(width 0.08255)
			(type default)
		)
		(layer "In9.Cu")
	)
	(gr_line
		(start 382.036066 -113.842292)
		(end 382.22555 -113.38433)
		(stroke
			(width 0.08255)
			(type default)
		)
		(layer "In9.Cu")
	)
	(gr_line
		(start 382.115568 -129.582164)
		(end 382.390904 -129.170176)
		(stroke
			(width 0.08255)
			(type default)
		)
		(layer "In9.Cu")
	)
	(gr_line
		(start 382.128014 -109.35335)
		(end 382.128014 -109.23651)
		(stroke
			(width 0.08255)
			(type default)
		)
		(layer "In9.Cu")
	)
	(gr_line
		(start 382.18618 -102.57155)
		(end 382.18618 -102.447598)
		(stroke
			(width 0.08255)
			(type default)
		)
		(layer "In9.Cu")
	)
	(gr_line
		(start 382.22555 -113.38433)
		(end 382.164336 -113.236502)
		(stroke
			(width 0.08255)
			(type default)
		)
		(layer "In9.Cu")
	)
	(gr_line
		(start 382.23952 -105.805478)
		(end 382.23952 -105.645458)
		(stroke
			(width 0.08255)
			(type default)
		)
		(layer "In9.Cu")
	)
	(gr_line
		(start 382.265682 -122.235722)
		(end 382.265682 -122.093736)
		(stroke
			(width 0.08255)
			(type default)
		)
		(layer "In9.Cu")
	)
	(gr_line
		(start 382.390904 -129.170176)
		(end 382.359662 -129.013458)
		(stroke
			(width 0.08255)
			(type default)
		)
		(layer "In9.Cu")
	)
	(gr_line
		(start 382.400048 -128.443228)
		(end 382.738884 -127.936244)
		(stroke
			(width 0.08255)
			(type default)
		)
		(layer "In9.Cu")
	)
	(gr_line
		(start 382.453134 -110.883446)
		(end 382.561084 -110.838742)
		(stroke
			(width 0.08255)
			(type default)
		)
		(layer "In9.Cu")
	)
	(gr_line
		(start 382.561084 -110.838742)
		(end 382.561338 -110.838742)
		(stroke
			(width 0.08255)
			(type default)
		)
		(layer "In9.Cu")
	)
	(gr_line
		(start 382.561338 -110.838742)
		(end 383.110486 -110.611158)
		(stroke
			(width 0.08255)
			(type default)
		)
		(layer "In9.Cu")
	)
	(gr_line
		(start 382.562608 -111.144558)
		(end 382.710436 -111.206026)
		(stroke
			(width 0.08255)
			(type default)
		)
		(layer "In9.Cu")
	)
	(gr_line
		(start 382.59004 -139.189968)
		(end 382.312926 -138.520932)
		(stroke
			(width 0.08255)
			(type default)
		)
		(layer "In9.Cu")
	)
	(gr_line
		(start 382.636268 -128.599692)
		(end 382.75768 -128.575562)
		(stroke
			(width 0.08255)
			(type default)
		)
		(layer "In9.Cu")
	)
	(gr_line
		(start 382.710436 -111.206026)
		(end 383.156714 -111.021368)
		(stroke
			(width 0.08255)
			(type default)
		)
		(layer "In9.Cu")
	)
	(gr_line
		(start 382.722882 -138.474704)
		(end 382.575054 -138.413744)
		(stroke
			(width 0.08255)
			(type default)
		)
		(layer "In9.Cu")
	)
	(gr_line
		(start 382.75768 -128.575562)
		(end 382.997964 -128.216152)
		(stroke
			(width 0.08255)
			(type default)
		)
		(layer "In9.Cu")
	)
	(gr_line
		(start 382.851152 -139.080494)
		(end 382.912366 -138.932666)
		(stroke
			(width 0.08255)
			(type default)
		)
		(layer "In9.Cu")
	)
	(gr_line
		(start 382.912366 -138.932666)
		(end 382.722882 -138.474704)
		(stroke
			(width 0.08255)
			(type default)
		)
		(layer "In9.Cu")
	)
	(gr_line
		(start 382.997964 -128.216152)
		(end 382.97358 -128.094486)
		(stroke
			(width 0.08255)
			(type default)
		)
		(layer "In9.Cu")
	)
	(gr_line
		(start 383.0066 -127.535432)
		(end 383.34569 -127.028194)
		(stroke
			(width 0.08255)
			(type default)
		)
		(layer "In9.Cu")
	)
	(gr_line
		(start 383.056638 -140.316458)
		(end 382.779524 -139.647422)
		(stroke
			(width 0.08255)
			(type default)
		)
		(layer "In9.Cu")
	)
	(gr_line
		(start 383.13487 -119.797068)
		(end 383.4257 -120.087898)
		(stroke
			(width 0.08255)
			(type default)
		)
		(layer "In9.Cu")
	)
	(gr_line
		(start 383.13487 -112.493552)
		(end 383.4257 -112.784382)
		(stroke
			(width 0.08255)
			(type default)
		)
		(layer "In9.Cu")
	)
	(gr_line
		(start 383.13487 -112.211612)
		(end 383.4257 -111.920782)
		(stroke
			(width 0.08255)
			(type default)
		)
		(layer "In9.Cu")
	)
	(gr_line
		(start 383.13487 -108.89361)
		(end 383.4257 -109.18444)
		(stroke
			(width 0.08255)
			(type default)
		)
		(layer "In9.Cu")
	)
	(gr_line
		(start 383.13487 -108.61167)
		(end 383.4257 -108.32084)
		(stroke
			(width 0.08255)
			(type default)
		)
		(layer "In9.Cu")
	)
	(gr_line
		(start 383.13487 -105.293668)
		(end 383.4257 -105.584498)
		(stroke
			(width 0.08255)
			(type default)
		)
		(layer "In9.Cu")
	)
	(gr_line
		(start 383.13487 -105.011728)
		(end 383.4257 -104.720898)
		(stroke
			(width 0.08255)
			(type default)
		)
		(layer "In9.Cu")
	)
	(gr_line
		(start 383.156714 -111.021368)
		(end 383.217674 -110.873286)
		(stroke
			(width 0.08255)
			(type default)
		)
		(layer "In9.Cu")
	)
	(gr_line
		(start 383.189734 -139.601448)
		(end 383.041652 -139.53998)
		(stroke
			(width 0.08255)
			(type default)
		)
		(layer "In9.Cu")
	)
	(gr_line
		(start 383.234438 -127.702056)
		(end 383.241042 -127.69215)
		(stroke
			(width 0.08255)
			(type default)
		)
		(layer "In9.Cu")
	)
	(gr_line
		(start 383.24282 -127.691896)
		(end 383.364486 -127.667512)
		(stroke
			(width 0.08255)
			(type default)
		)
		(layer "In9.Cu")
	)
	(gr_line
		(start 383.318004 -140.207238)
		(end 383.379218 -140.059156)
		(stroke
			(width 0.08255)
			(type default)
		)
		(layer "In9.Cu")
	)
	(gr_line
		(start 383.364486 -127.667512)
		(end 383.604516 -127.308356)
		(stroke
			(width 0.08255)
			(type default)
		)
		(layer "In9.Cu")
	)
	(gr_line
		(start 383.379218 -140.059156)
		(end 383.189734 -139.601448)
		(stroke
			(width 0.08255)
			(type default)
		)
		(layer "In9.Cu")
	)
	(gr_line
		(start 383.401824 -100.08362)
		(end 384.059176 -99.811078)
		(stroke
			(width 0.08255)
			(type default)
		)
		(layer "In9.Cu")
	)
	(gr_line
		(start 383.4257 -121.321576)
		(end 384.0099 -121.321576)
		(stroke
			(width 0.08255)
			(type default)
		)
		(layer "In9.Cu")
	)
	(gr_line
		(start 383.42697 -121.604786)
		(end 383.5146 -121.692416)
		(stroke
			(width 0.08255)
			(type default)
		)
		(layer "In9.Cu")
	)
	(gr_line
		(start 383.511044 -100.344732)
		(end 383.659126 -100.4062)
		(stroke
			(width 0.08255)
			(type default)
		)
		(layer "In9.Cu")
	)
	(gr_line
		(start 383.5146 -121.692416)
		(end 383.921 -121.692416)
		(stroke
			(width 0.08255)
			(type default)
		)
		(layer "In9.Cu")
	)
	(gr_line
		(start 383.604516 -127.308356)
		(end 383.580386 -127.186436)
		(stroke
			(width 0.08255)
			(type default)
		)
		(layer "In9.Cu")
	)
	(gr_line
		(start 383.659126 -100.4062)
		(end 384.105404 -100.221542)
		(stroke
			(width 0.08255)
			(type default)
		)
		(layer "In9.Cu")
	)
	(gr_line
		(start 383.74447 -101.693472)
		(end 384.0353 -101.984302)
		(stroke
			(width 0.08255)
			(type default)
		)
		(layer "In9.Cu")
	)
	(gr_line
		(start 383.74447 -101.411532)
		(end 384.0353 -101.120702)
		(stroke
			(width 0.08255)
			(type default)
		)
		(layer "In9.Cu")
	)
	(gr_line
		(start 383.775712 -143.914368)
		(end 383.740152 -143.19123)
		(stroke
			(width 0.08255)
			(type default)
		)
		(layer "In9.Cu")
	)
	(gr_line
		(start 383.836926 -145.15846)
		(end 383.801366 -144.435322)
		(stroke
			(width 0.08255)
			(type default)
		)
		(layer "In9.Cu")
	)
	(gr_line
		(start 383.892552 -307.915818)
		(end 383.921 -307.915818)
		(stroke
			(width 0.05715)
			(type default)
		)
		(layer "In9.Cu")
	)
	(gr_line
		(start 383.892552 -307.633878)
		(end 383.921 -307.633878)
		(stroke
			(width 0.05715)
			(type default)
		)
		(layer "In9.Cu")
	)
	(gr_line
		(start 383.892552 -306.965858)
		(end 383.921 -306.965858)
		(stroke
			(width 0.05715)
			(type default)
		)
		(layer "In9.Cu")
	)
	(gr_line
		(start 383.892552 -306.683918)
		(end 383.921 -306.683918)
		(stroke
			(width 0.05715)
			(type default)
		)
		(layer "In9.Cu")
	)
	(gr_line
		(start 383.892552 -306.015898)
		(end 383.921 -306.015898)
		(stroke
			(width 0.05715)
			(type default)
		)
		(layer "In9.Cu")
	)
	(gr_line
		(start 383.892552 -305.733958)
		(end 383.921 -305.733958)
		(stroke
			(width 0.05715)
			(type default)
		)
		(layer "In9.Cu")
	)
	(gr_line
		(start 383.892552 -305.065938)
		(end 383.921 -305.065938)
		(stroke
			(width 0.05715)
			(type default)
		)
		(layer "In9.Cu")
	)
	(gr_line
		(start 383.892552 -304.783998)
		(end 383.921 -304.783998)
		(stroke
			(width 0.05715)
			(type default)
		)
		(layer "In9.Cu")
	)
	(gr_line
		(start 383.892552 -303.165764)
		(end 383.921 -303.165764)
		(stroke
			(width 0.05715)
			(type default)
		)
		(layer "In9.Cu")
	)
	(gr_line
		(start 383.892552 -302.883824)
		(end 383.921 -302.883824)
		(stroke
			(width 0.05715)
			(type default)
		)
		(layer "In9.Cu")
	)
	(gr_line
		(start 383.892552 -302.215804)
		(end 383.921 -302.215804)
		(stroke
			(width 0.05715)
			(type default)
		)
		(layer "In9.Cu")
	)
	(gr_line
		(start 383.892552 -301.933864)
		(end 383.921 -301.933864)
		(stroke
			(width 0.05715)
			(type default)
		)
		(layer "In9.Cu")
	)
	(gr_line
		(start 383.89687 -146.37639)
		(end 383.86131 -145.652998)
		(stroke
			(width 0.08255)
			(type default)
		)
		(layer "In9.Cu")
	)
	(gr_line
		(start 383.921 -307.915818)
		(end 383.96672 -307.870098)
		(stroke
			(width 0.05715)
			(type default)
		)
		(layer "In9.Cu")
	)
	(gr_line
		(start 383.921 -307.633878)
		(end 383.96672 -307.679598)
		(stroke
			(width 0.05715)
			(type default)
		)
		(layer "In9.Cu")
	)
	(gr_line
		(start 383.921 -306.965858)
		(end 383.96672 -306.920138)
		(stroke
			(width 0.05715)
			(type default)
		)
		(layer "In9.Cu")
	)
	(gr_line
		(start 383.921 -306.683918)
		(end 383.96672 -306.729638)
		(stroke
			(width 0.05715)
			(type default)
		)
		(layer "In9.Cu")
	)
	(gr_line
		(start 383.921 -306.015898)
		(end 383.96672 -305.970178)
		(stroke
			(width 0.05715)
			(type default)
		)
		(layer "In9.Cu")
	)
	(gr_line
		(start 383.921 -305.733958)
		(end 383.96672 -305.779678)
		(stroke
			(width 0.05715)
			(type default)
		)
		(layer "In9.Cu")
	)
	(gr_line
		(start 383.921 -305.065938)
		(end 383.96672 -305.020218)
		(stroke
			(width 0.05715)
			(type default)
		)
		(layer "In9.Cu")
	)
	(gr_line
		(start 383.921 -304.783998)
		(end 383.96672 -304.829718)
		(stroke
			(width 0.05715)
			(type default)
		)
		(layer "In9.Cu")
	)
	(gr_line
		(start 383.921 -303.165764)
		(end 383.96672 -303.120044)
		(stroke
			(width 0.05715)
			(type default)
		)
		(layer "In9.Cu")
	)
	(gr_line
		(start 383.921 -302.883824)
		(end 383.96672 -302.929544)
		(stroke
			(width 0.05715)
			(type default)
		)
		(layer "In9.Cu")
	)
	(gr_line
		(start 383.921 -302.215804)
		(end 383.96672 -302.170084)
		(stroke
			(width 0.05715)
			(type default)
		)
		(layer "In9.Cu")
	)
	(gr_line
		(start 383.921 -301.933864)
		(end 383.96672 -301.979584)
		(stroke
			(width 0.05715)
			(type default)
		)
		(layer "In9.Cu")
	)
	(gr_line
		(start 383.921 -121.692416)
		(end 384.00863 -121.604786)
		(stroke
			(width 0.08255)
			(type default)
		)
		(layer "In9.Cu")
	)
	(gr_line
		(start 383.956814 -147.59432)
		(end 383.921254 -146.870928)
		(stroke
			(width 0.08255)
			(type default)
		)
		(layer "In9.Cu")
	)
	(gr_line
		(start 384.016758 -148.812504)
		(end 383.981198 -148.088858)
		(stroke
			(width 0.08255)
			(type default)
		)
		(layer "In9.Cu")
	)
	(gr_line
		(start 384.058668 -143.899636)
		(end 384.166364 -143.781018)
		(stroke
			(width 0.08255)
			(type default)
		)
		(layer "In9.Cu")
	)
	(gr_line
		(start 384.105404 -100.221542)
		(end 384.166618 -100.073206)
		(stroke
			(width 0.08255)
			(type default)
		)
		(layer "In9.Cu")
	)
	(gr_line
		(start 384.119882 -145.143728)
		(end 384.227578 -145.02511)
		(stroke
			(width 0.08255)
			(type default)
		)
		(layer "In9.Cu")
	)
	(gr_line
		(start 384.14198 -143.285972)
		(end 384.023108 -143.178784)
		(stroke
			(width 0.08255)
			(type default)
		)
		(layer "In9.Cu")
	)
	(gr_line
		(start 384.1496 -132.531612)
		(end 384.8608 -132.531612)
		(stroke
			(width 0.08255)
			(type default)
		)
		(layer "In9.Cu")
	)
	(gr_line
		(start 384.15087 -132.814822)
		(end 384.2639 -132.927852)
		(stroke
			(width 0.08255)
			(type default)
		)
		(layer "In9.Cu")
	)
	(gr_line
		(start 384.166364 -143.781018)
		(end 384.14198 -143.285972)
		(stroke
			(width 0.08255)
			(type default)
		)
		(layer "In9.Cu")
	)
	(gr_line
		(start 384.179826 -146.361658)
		(end 384.287522 -146.242786)
		(stroke
			(width 0.08255)
			(type default)
		)
		(layer "In9.Cu")
	)
	(gr_line
		(start 384.203194 -144.530064)
		(end 384.084322 -144.422876)
		(stroke
			(width 0.08255)
			(type default)
		)
		(layer "In9.Cu")
	)
	(gr_line
		(start 384.227578 -145.02511)
		(end 384.203194 -144.530064)
		(stroke
			(width 0.08255)
			(type default)
		)
		(layer "In9.Cu")
	)
	(gr_line
		(start 384.23977 -147.579588)
		(end 384.347466 -147.460716)
		(stroke
			(width 0.08255)
			(type default)
		)
		(layer "In9.Cu")
	)
	(gr_line
		(start 384.263138 -145.74774)
		(end 384.144266 -145.640298)
		(stroke
			(width 0.08255)
			(type default)
		)
		(layer "In9.Cu")
	)
	(gr_line
		(start 384.2639 -132.927852)
		(end 384.7465 -132.927852)
		(stroke
			(width 0.08255)
			(type default)
		)
		(layer "In9.Cu")
	)
	(gr_line
		(start 384.287522 -146.242786)
		(end 384.263138 -145.74774)
		(stroke
			(width 0.08255)
			(type default)
		)
		(layer "In9.Cu")
	)
	(gr_line
		(start 384.29946 -148.797518)
		(end 384.40741 -148.678646)
		(stroke
			(width 0.08255)
			(type default)
		)
		(layer "In9.Cu")
	)
	(gr_line
		(start 384.323082 -146.965924)
		(end 384.20421 -146.858228)
		(stroke
			(width 0.08255)
			(type default)
		)
		(layer "In9.Cu")
	)
	(gr_line
		(start 384.347466 -147.460716)
		(end 384.323082 -146.965924)
		(stroke
			(width 0.08255)
			(type default)
		)
		(layer "In9.Cu")
	)
	(gr_line
		(start 384.383026 -148.183854)
		(end 384.264154 -148.076158)
		(stroke
			(width 0.08255)
			(type default)
		)
		(layer "In9.Cu")
	)
	(gr_line
		(start 384.40741 -148.678646)
		(end 384.383026 -148.183854)
		(stroke
			(width 0.08255)
			(type default)
		)
		(layer "In9.Cu")
	)
	(gr_line
		(start 384.4163 -121.321576)
		(end 385.0005 -121.321576)
		(stroke
			(width 0.08255)
			(type default)
		)
		(layer "In9.Cu")
	)
	(gr_line
		(start 384.41757 -121.604786)
		(end 384.5052 -121.692416)
		(stroke
			(width 0.08255)
			(type default)
		)
		(layer "In9.Cu")
	)
	(gr_line
		(start 384.4798 -110.405164)
		(end 385.191 -110.405164)
		(stroke
			(width 0.08255)
			(type default)
		)
		(layer "In9.Cu")
	)
	(gr_line
		(start 384.48107 -110.688374)
		(end 384.5941 -110.801404)
		(stroke
			(width 0.08255)
			(type default)
		)
		(layer "In9.Cu")
	)
	(gr_line
		(start 384.5052 -121.692416)
		(end 384.9116 -121.692416)
		(stroke
			(width 0.08255)
			(type default)
		)
		(layer "In9.Cu")
	)
	(gr_line
		(start 384.5941 -110.801404)
		(end 385.0767 -110.801404)
		(stroke
			(width 0.08255)
			(type default)
		)
		(layer "In9.Cu")
	)
	(gr_line
		(start 384.679952 -301.265844)
		(end 384.7084 -301.265844)
		(stroke
			(width 0.05715)
			(type default)
		)
		(layer "In9.Cu")
	)
	(gr_line
		(start 384.679952 -300.983904)
		(end 384.7084 -300.983904)
		(stroke
			(width 0.05715)
			(type default)
		)
		(layer "In9.Cu")
	)
	(gr_line
		(start 384.7084 -301.265844)
		(end 384.75412 -301.220124)
		(stroke
			(width 0.05715)
			(type default)
		)
		(layer "In9.Cu")
	)
	(gr_line
		(start 384.7084 -300.983904)
		(end 384.75412 -301.029624)
		(stroke
			(width 0.05715)
			(type default)
		)
		(layer "In9.Cu")
	)
	(gr_line
		(start 384.7465 -132.927852)
		(end 384.85953 -132.814822)
		(stroke
			(width 0.08255)
			(type default)
		)
		(layer "In9.Cu")
	)
	(gr_line
		(start 384.9116 -121.692416)
		(end 384.99923 -121.604786)
		(stroke
			(width 0.08255)
			(type default)
		)
		(layer "In9.Cu")
	)
	(gr_line
		(start 385.0767 -110.801404)
		(end 385.18973 -110.688374)
		(stroke
			(width 0.08255)
			(type default)
		)
		(layer "In9.Cu")
	)
	(gr_line
		(start 385.438142 -308.249828)
		(end 385.149852 -308.249828)
		(stroke
			(width 0.05715)
			(type default)
		)
		(layer "In9.Cu")
	)
	(gr_line
		(start 385.438142 -306.349908)
		(end 385.149852 -306.349908)
		(stroke
			(width 0.05715)
			(type default)
		)
		(layer "In9.Cu")
	)
	(gr_line
		(start 385.438142 -302.549814)
		(end 385.149852 -302.549814)
		(stroke
			(width 0.05715)
			(type default)
		)
		(layer "In9.Cu")
	)
	(gr_line
		(start 385.452112 -137.480802)
		(end 385.31038 -137.480802)
		(stroke
			(width 0.08255)
			(type default)
		)
		(layer "In9.Cu")
	)
	(gr_line
		(start 385.532884 -308.155086)
		(end 385.438142 -308.249828)
		(stroke
			(width 0.05715)
			(type default)
		)
		(layer "In9.Cu")
	)
	(gr_line
		(start 385.532884 -306.255166)
		(end 385.438142 -306.349908)
		(stroke
			(width 0.05715)
			(type default)
		)
		(layer "In9.Cu")
	)
	(gr_line
		(start 385.532884 -302.455072)
		(end 385.438142 -302.549814)
		(stroke
			(width 0.05715)
			(type default)
		)
		(layer "In9.Cu")
	)
	(gr_line
		(start 385.594352 -138.165332)
		(end 385.109212 -137.680192)
		(stroke
			(width 0.08255)
			(type default)
		)
		(layer "In9.Cu")
	)
	(gr_line
		(start 385.724654 -308.15534)
		(end 385.819142 -308.249828)
		(stroke
			(width 0.05715)
			(type default)
		)
		(layer "In9.Cu")
	)
	(gr_line
		(start 385.724654 -308.153816)
		(end 385.724654 -308.15534)
		(stroke
			(width 0.05715)
			(type default)
		)
		(layer "In9.Cu")
	)
	(gr_line
		(start 385.724654 -306.25542)
		(end 385.819142 -306.349908)
		(stroke
			(width 0.05715)
			(type default)
		)
		(layer "In9.Cu")
	)
	(gr_line
		(start 385.724654 -306.253896)
		(end 385.724654 -306.25542)
		(stroke
			(width 0.05715)
			(type default)
		)
		(layer "In9.Cu")
	)
	(gr_line
		(start 385.724654 -302.455326)
		(end 385.819142 -302.549814)
		(stroke
			(width 0.05715)
			(type default)
		)
		(layer "In9.Cu")
	)
	(gr_line
		(start 385.724654 -302.453802)
		(end 385.724654 -302.455326)
		(stroke
			(width 0.05715)
			(type default)
		)
		(layer "In9.Cu")
	)
	(gr_line
		(start 385.776978 -136.413494)
		(end 386.067808 -136.704324)
		(stroke
			(width 0.08255)
			(type default)
		)
		(layer "In9.Cu")
	)
	(gr_line
		(start 385.776978 -136.131554)
		(end 386.067808 -135.840724)
		(stroke
			(width 0.08255)
			(type default)
		)
		(layer "In9.Cu")
	)
	(gr_line
		(start 385.776978 -132.813552)
		(end 386.067808 -133.104382)
		(stroke
			(width 0.08255)
			(type default)
		)
		(layer "In9.Cu")
	)
	(gr_line
		(start 385.776978 -132.531612)
		(end 386.067808 -132.240782)
		(stroke
			(width 0.08255)
			(type default)
		)
		(layer "In9.Cu")
	)
	(gr_line
		(start 385.776978 -125.203712)
		(end 386.067808 -125.494542)
		(stroke
			(width 0.08255)
			(type default)
		)
		(layer "In9.Cu")
	)
	(gr_line
		(start 385.776978 -124.921772)
		(end 386.067808 -124.630942)
		(stroke
			(width 0.08255)
			(type default)
		)
		(layer "In9.Cu")
	)
	(gr_line
		(start 385.776978 -121.603516)
		(end 386.067808 -121.894346)
		(stroke
			(width 0.08255)
			(type default)
		)
		(layer "In9.Cu")
	)
	(gr_line
		(start 385.776978 -121.321576)
		(end 386.067808 -121.030746)
		(stroke
			(width 0.08255)
			(type default)
		)
		(layer "In9.Cu")
	)
	(gr_line
		(start 385.776978 -110.687104)
		(end 386.067808 -110.977934)
		(stroke
			(width 0.08255)
			(type default)
		)
		(layer "In9.Cu")
	)
	(gr_line
		(start 385.776978 -110.405164)
		(end 386.067808 -110.114334)
		(stroke
			(width 0.08255)
			(type default)
		)
		(layer "In9.Cu")
	)
	(gr_line
		(start 385.776978 -99.887024)
		(end 386.067808 -100.177854)
		(stroke
			(width 0.08255)
			(type default)
		)
		(layer "In9.Cu")
	)
	(gr_line
		(start 385.776978 -99.605084)
		(end 386.067808 -99.314254)
		(stroke
			(width 0.08255)
			(type default)
		)
		(layer "In9.Cu")
	)
	(gr_line
		(start 385.793742 -137.964164)
		(end 385.793742 -137.822178)
		(stroke
			(width 0.08255)
			(type default)
		)
		(layer "In9.Cu")
	)
	(gr_line
		(start 385.793742 -137.822178)
		(end 385.452112 -137.480802)
		(stroke
			(width 0.08255)
			(type default)
		)
		(layer "In9.Cu")
	)
	(gr_line
		(start 385.819142 -308.249828)
		(end 386.099812 -308.249828)
		(stroke
			(width 0.05715)
			(type default)
		)
		(layer "In9.Cu")
	)
	(gr_line
		(start 385.819142 -306.349908)
		(end 386.099812 -306.349908)
		(stroke
			(width 0.05715)
			(type default)
		)
		(layer "In9.Cu")
	)
	(gr_line
		(start 385.819142 -302.549814)
		(end 386.099812 -302.549814)
		(stroke
			(width 0.05715)
			(type default)
		)
		(layer "In9.Cu")
	)
	(gr_line
		(start 386.55117 -140.656056)
		(end 386.417566 -139.98321)
		(stroke
			(width 0.08255)
			(type default)
		)
		(layer "In9.Cu")
	)
	(gr_line
		(start 386.783834 -141.826996)
		(end 386.64769 -141.141704)
		(stroke
			(width 0.08255)
			(type default)
		)
		(layer "In9.Cu")
	)
	(gr_line
		(start 386.813806 -140.008102)
		(end 386.695696 -139.929362)
		(stroke
			(width 0.08255)
			(type default)
		)
		(layer "In9.Cu")
	)
	(gr_line
		(start 386.828792 -140.600176)
		(end 386.907786 -140.481812)
		(stroke
			(width 0.08255)
			(type default)
		)
		(layer "In9.Cu")
	)
	(gr_line
		(start 386.907786 -140.481812)
		(end 386.813806 -140.008102)
		(stroke
			(width 0.08255)
			(type default)
		)
		(layer "In9.Cu")
	)
	(gr_line
		(start 387.016244 -142.997936)
		(end 386.8801 -142.312644)
		(stroke
			(width 0.08255)
			(type default)
		)
		(layer "In9.Cu")
	)
	(gr_line
		(start 387.044184 -141.16685)
		(end 386.925566 -141.087856)
		(stroke
			(width 0.08255)
			(type default)
		)
		(layer "In9.Cu")
	)
	(gr_line
		(start 387.061456 -141.771116)
		(end 387.14045 -141.652752)
		(stroke
			(width 0.08255)
			(type default)
		)
		(layer "In9.Cu")
	)
	(gr_line
		(start 387.14045 -141.652752)
		(end 387.044184 -141.16685)
		(stroke
			(width 0.08255)
			(type default)
		)
		(layer "In9.Cu")
	)
	(gr_line
		(start 387.248908 -144.168876)
		(end 387.112764 -143.483584)
		(stroke
			(width 0.08255)
			(type default)
		)
		(layer "In9.Cu")
	)
	(gr_line
		(start 387.276848 -142.33779)
		(end 387.15823 -142.258542)
		(stroke
			(width 0.08255)
			(type default)
		)
		(layer "In9.Cu")
	)
	(gr_line
		(start 387.293866 -142.942056)
		(end 387.373114 -142.823692)
		(stroke
			(width 0.08255)
			(type default)
		)
		(layer "In9.Cu")
	)
	(gr_line
		(start 387.338316 -307.299868)
		(end 387.050026 -307.299868)
		(stroke
			(width 0.05715)
			(type default)
		)
		(layer "In9.Cu")
	)
	(gr_line
		(start 387.338316 -305.399948)
		(end 387.050026 -305.399948)
		(stroke
			(width 0.05715)
			(type default)
		)
		(layer "In9.Cu")
	)
	(gr_line
		(start 387.338316 -303.499774)
		(end 387.050026 -303.499774)
		(stroke
			(width 0.05715)
			(type default)
		)
		(layer "In9.Cu")
	)
	(gr_line
		(start 387.338316 -301.599854)
		(end 387.050026 -301.599854)
		(stroke
			(width 0.05715)
			(type default)
		)
		(layer "In9.Cu")
	)
	(gr_line
		(start 387.373114 -142.823692)
		(end 387.276848 -142.33779)
		(stroke
			(width 0.08255)
			(type default)
		)
		(layer "In9.Cu")
	)
	(gr_line
		(start 387.433058 -307.205126)
		(end 387.338316 -307.299868)
		(stroke
			(width 0.05715)
			(type default)
		)
		(layer "In9.Cu")
	)
	(gr_line
		(start 387.433058 -305.305206)
		(end 387.338316 -305.399948)
		(stroke
			(width 0.05715)
			(type default)
		)
		(layer "In9.Cu")
	)
	(gr_line
		(start 387.433058 -303.405032)
		(end 387.338316 -303.499774)
		(stroke
			(width 0.05715)
			(type default)
		)
		(layer "In9.Cu")
	)
	(gr_line
		(start 387.433058 -301.505112)
		(end 387.338316 -301.599854)
		(stroke
			(width 0.05715)
			(type default)
		)
		(layer "In9.Cu")
	)
	(gr_line
		(start 387.481318 -145.339816)
		(end 387.345428 -144.654524)
		(stroke
			(width 0.08255)
			(type default)
		)
		(layer "In9.Cu")
	)
	(gr_line
		(start 387.509512 -143.50873)
		(end 387.39064 -143.429482)
		(stroke
			(width 0.08255)
			(type default)
		)
		(layer "In9.Cu")
	)
	(gr_line
		(start 387.52653 -144.11325)
		(end 387.605778 -143.994632)
		(stroke
			(width 0.08255)
			(type default)
		)
		(layer "In9.Cu")
	)
	(gr_line
		(start 387.605778 -143.994632)
		(end 387.509512 -143.50873)
		(stroke
			(width 0.08255)
			(type default)
		)
		(layer "In9.Cu")
	)
	(gr_line
		(start 387.624828 -307.20538)
		(end 387.719316 -307.299868)
		(stroke
			(width 0.05715)
			(type default)
		)
		(layer "In9.Cu")
	)
	(gr_line
		(start 387.624828 -307.203856)
		(end 387.624828 -307.20538)
		(stroke
			(width 0.05715)
			(type default)
		)
		(layer "In9.Cu")
	)
	(gr_line
		(start 387.624828 -305.30546)
		(end 387.719316 -305.399948)
		(stroke
			(width 0.05715)
			(type default)
		)
		(layer "In9.Cu")
	)
	(gr_line
		(start 387.624828 -305.303936)
		(end 387.624828 -305.30546)
		(stroke
			(width 0.05715)
			(type default)
		)
		(layer "In9.Cu")
	)
	(gr_line
		(start 387.624828 -303.405286)
		(end 387.719316 -303.499774)
		(stroke
			(width 0.05715)
			(type default)
		)
		(layer "In9.Cu")
	)
	(gr_line
		(start 387.624828 -303.403762)
		(end 387.624828 -303.405286)
		(stroke
			(width 0.05715)
			(type default)
		)
		(layer "In9.Cu")
	)
	(gr_line
		(start 387.624828 -301.505366)
		(end 387.719316 -301.599854)
		(stroke
			(width 0.05715)
			(type default)
		)
		(layer "In9.Cu")
	)
	(gr_line
		(start 387.624828 -301.503842)
		(end 387.624828 -301.505366)
		(stroke
			(width 0.05715)
			(type default)
		)
		(layer "In9.Cu")
	)
	(gr_line
		(start 387.713982 -146.510756)
		(end 387.577838 -145.825464)
		(stroke
			(width 0.08255)
			(type default)
		)
		(layer "In9.Cu")
	)
	(gr_line
		(start 387.719316 -307.299868)
		(end 387.999986 -307.299868)
		(stroke
			(width 0.05715)
			(type default)
		)
		(layer "In9.Cu")
	)
	(gr_line
		(start 387.719316 -305.399948)
		(end 387.999986 -305.399948)
		(stroke
			(width 0.05715)
			(type default)
		)
		(layer "In9.Cu")
	)
	(gr_line
		(start 387.719316 -303.499774)
		(end 387.999986 -303.499774)
		(stroke
			(width 0.05715)
			(type default)
		)
		(layer "In9.Cu")
	)
	(gr_line
		(start 387.719316 -301.599854)
		(end 387.999986 -301.599854)
		(stroke
			(width 0.05715)
			(type default)
		)
		(layer "In9.Cu")
	)
	(gr_line
		(start 387.742176 -144.67967)
		(end 387.623304 -144.600422)
		(stroke
			(width 0.08255)
			(type default)
		)
		(layer "In9.Cu")
	)
	(gr_line
		(start 387.759194 -145.28419)
		(end 387.838442 -145.165572)
		(stroke
			(width 0.08255)
			(type default)
		)
		(layer "In9.Cu")
	)
	(gr_line
		(start 387.838442 -145.165572)
		(end 387.742176 -144.67967)
		(stroke
			(width 0.08255)
			(type default)
		)
		(layer "In9.Cu")
	)
	(gr_line
		(start 387.946646 -147.68195)
		(end 387.810502 -146.996404)
		(stroke
			(width 0.08255)
			(type default)
		)
		(layer "In9.Cu")
	)
	(gr_line
		(start 387.97484 -145.85061)
		(end 387.855714 -145.771108)
		(stroke
			(width 0.08255)
			(type default)
		)
		(layer "In9.Cu")
	)
	(gr_line
		(start 387.991604 -146.455384)
		(end 388.071106 -146.336512)
		(stroke
			(width 0.08255)
			(type default)
		)
		(layer "In9.Cu")
	)
	(gr_line
		(start 388.071106 -146.336512)
		(end 387.97484 -145.85061)
		(stroke
			(width 0.08255)
			(type default)
		)
		(layer "In9.Cu")
	)
	(gr_line
		(start 388.184136 -148.878036)
		(end 388.042912 -148.167344)
		(stroke
			(width 0.08255)
			(type default)
		)
		(layer "In9.Cu")
	)
	(gr_line
		(start 388.207504 -147.02155)
		(end 388.088378 -146.942048)
		(stroke
			(width 0.08255)
			(type default)
		)
		(layer "In9.Cu")
	)
	(gr_line
		(start 388.224268 -147.626324)
		(end 388.30377 -147.507452)
		(stroke
			(width 0.08255)
			(type default)
		)
		(layer "In9.Cu")
	)
	(gr_line
		(start 388.30377 -147.507452)
		(end 388.207504 -147.02155)
		(stroke
			(width 0.08255)
			(type default)
		)
		(layer "In9.Cu")
	)
	(gr_line
		(start 388.4549 -148.202396)
		(end 388.320788 -148.112988)
		(stroke
			(width 0.08255)
			(type default)
		)
		(layer "In9.Cu")
	)
	(gr_line
		(start 388.461758 -148.82241)
		(end 388.55142 -148.688552)
		(stroke
			(width 0.08255)
			(type default)
		)
		(layer "In9.Cu")
	)
	(gr_line
		(start 388.55142 -148.688552)
		(end 388.4549 -148.202396)
		(stroke
			(width 0.08255)
			(type default)
		)
		(layer "In9.Cu")
	)
	(gr_line
		(start 407.333958 -271.500346)
		(end 407.333958 -271.471898)
		(stroke
			(width 0.05715)
			(type default)
		)
		(layer "In9.Cu")
	)
	(gr_line
		(start 407.379678 -271.546066)
		(end 407.333958 -271.500346)
		(stroke
			(width 0.05715)
			(type default)
		)
		(layer "In9.Cu")
	)
	(gr_line
		(start 407.570178 -271.546066)
		(end 407.615898 -271.500346)
		(stroke
			(width 0.05715)
			(type default)
		)
		(layer "In9.Cu")
	)
	(gr_line
		(start 407.615898 -271.500346)
		(end 407.615898 -271.471898)
		(stroke
			(width 0.05715)
			(type default)
		)
		(layer "In9.Cu")
	)
	(gr_line
		(start 407.949654 -278.799798)
		(end 407.949654 -278.534368)
		(stroke
			(width 0.05715)
			(type default)
		)
		(layer "In9.Cu")
	)
	(gr_line
		(start 407.949654 -278.534368)
		(end 407.835354 -278.420068)
		(stroke
			(width 0.05715)
			(type default)
		)
		(layer "In9.Cu")
	)
	(gr_line
		(start 407.949654 -278.115268)
		(end 407.835354 -278.229568)
		(stroke
			(width 0.05715)
			(type default)
		)
		(layer "In9.Cu")
	)
	(gr_line
		(start 407.949654 -277.849838)
		(end 407.949654 -278.115268)
		(stroke
			(width 0.05715)
			(type default)
		)
		(layer "In9.Cu")
	)
	(gr_line
		(start 408.030172 -340.004146)
		(end 408.030172 -340.0044)
		(stroke
			(width 0.08255)
			(type default)
		)
		(layer "In9.Cu")
	)
	(gr_line
		(start 408.082496 -340.138004)
		(end 408.030934 -340.005924)
		(stroke
			(width 0.08255)
			(type default)
		)
		(layer "In9.Cu")
	)
	(gr_line
		(start 408.283918 -271.554448)
		(end 408.283918 -271.526)
		(stroke
			(width 0.05715)
			(type default)
		)
		(layer "In9.Cu")
	)
	(gr_line
		(start 408.329638 -271.600168)
		(end 408.283918 -271.554448)
		(stroke
			(width 0.05715)
			(type default)
		)
		(layer "In9.Cu")
	)
	(gr_line
		(start 408.475688 -358.065578)
		(end 408.475434 -358.065578)
		(stroke
			(width 0.08255)
			(type default)
		)
		(layer "In9.Cu")
	)
	(gr_line
		(start 408.520138 -271.600168)
		(end 408.565858 -271.554448)
		(stroke
			(width 0.05715)
			(type default)
		)
		(layer "In9.Cu")
	)
	(gr_line
		(start 408.536648 -340.336632)
		(end 408.082496 -340.138004)
		(stroke
			(width 0.08255)
			(type default)
		)
		(layer "In9.Cu")
	)
	(gr_line
		(start 408.565858 -271.554448)
		(end 408.565858 -271.526)
		(stroke
			(width 0.05715)
			(type default)
		)
		(layer "In9.Cu")
	)
	(gr_line
		(start 408.668982 -340.28507)
		(end 408.536648 -340.336632)
		(stroke
			(width 0.08255)
			(type default)
		)
		(layer "In9.Cu")
	)
	(gr_line
		(start 408.783536 -340.02599)
		(end 408.143202 -339.745828)
		(stroke
			(width 0.08255)
			(type default)
		)
		(layer "In9.Cu")
	)
	(gr_line
		(start 408.899868 -280.699718)
		(end 408.899868 -280.434288)
		(stroke
			(width 0.05715)
			(type default)
		)
		(layer "In9.Cu")
	)
	(gr_line
		(start 408.899868 -280.434288)
		(end 408.785568 -280.319988)
		(stroke
			(width 0.05715)
			(type default)
		)
		(layer "In9.Cu")
	)
	(gr_line
		(start 408.899868 -280.015188)
		(end 408.785568 -280.129488)
		(stroke
			(width 0.05715)
			(type default)
		)
		(layer "In9.Cu")
	)
	(gr_line
		(start 408.899868 -279.749504)
		(end 408.899868 -280.015188)
		(stroke
			(width 0.05715)
			(type default)
		)
		(layer "In9.Cu")
	)
	(gr_line
		(start 409.176474 -340.616286)
		(end 409.124912 -340.48446)
		(stroke
			(width 0.08255)
			(type default)
		)
		(layer "In9.Cu")
	)
	(gr_line
		(start 409.630626 -340.815168)
		(end 409.176474 -340.616286)
		(stroke
			(width 0.08255)
			(type default)
		)
		(layer "In9.Cu")
	)
	(gr_line
		(start 409.76296 -340.763352)
		(end 409.630626 -340.815168)
		(stroke
			(width 0.08255)
			(type default)
		)
		(layer "In9.Cu")
	)
	(gr_line
		(start 409.87726 -340.504272)
		(end 409.23718 -340.224364)
		(stroke
			(width 0.08255)
			(type default)
		)
		(layer "In9.Cu")
	)
	(gr_line
		(start 410.183838 -271.554448)
		(end 410.183838 -271.526)
		(stroke
			(width 0.05715)
			(type default)
		)
		(layer "In9.Cu")
	)
	(gr_line
		(start 410.229558 -271.600168)
		(end 410.183838 -271.554448)
		(stroke
			(width 0.05715)
			(type default)
		)
		(layer "In9.Cu")
	)
	(gr_line
		(start 410.420058 -271.600168)
		(end 410.465778 -271.554448)
		(stroke
			(width 0.05715)
			(type default)
		)
		(layer "In9.Cu")
	)
	(gr_line
		(start 410.465778 -271.554448)
		(end 410.465778 -271.526)
		(stroke
			(width 0.05715)
			(type default)
		)
		(layer "In9.Cu")
	)
	(gr_line
		(start 410.799788 -280.699718)
		(end 410.799788 -280.434288)
		(stroke
			(width 0.05715)
			(type default)
		)
		(layer "In9.Cu")
	)
	(gr_line
		(start 410.799788 -280.434288)
		(end 410.685488 -280.319988)
		(stroke
			(width 0.05715)
			(type default)
		)
		(layer "In9.Cu")
	)
	(gr_line
		(start 410.799788 -280.015188)
		(end 410.685488 -280.129488)
		(stroke
			(width 0.05715)
			(type default)
		)
		(layer "In9.Cu")
	)
	(gr_line
		(start 410.799788 -279.749504)
		(end 410.799788 -280.015188)
		(stroke
			(width 0.05715)
			(type default)
		)
		(layer "In9.Cu")
	)
	(gr_line
		(start 412.015686 -340.469728)
		(end 411.963616 -340.337394)
		(stroke
			(width 0.08255)
			(type default)
		)
		(layer "In9.Cu")
	)
	(gr_line
		(start 412.084012 -271.554448)
		(end 412.084012 -271.526)
		(stroke
			(width 0.05715)
			(type default)
		)
		(layer "In9.Cu")
	)
	(gr_line
		(start 412.084012 -269.36065)
		(end 412.084012 -268.66215)
		(stroke
			(width 0.08255)
			(type default)
		)
		(layer "In9.Cu")
	)
	(gr_line
		(start 412.129732 -271.600168)
		(end 412.084012 -271.554448)
		(stroke
			(width 0.05715)
			(type default)
		)
		(layer "In9.Cu")
	)
	(gr_line
		(start 412.320232 -271.600168)
		(end 412.365952 -271.554448)
		(stroke
			(width 0.05715)
			(type default)
		)
		(layer "In9.Cu")
	)
	(gr_line
		(start 412.365952 -271.554448)
		(end 412.365952 -271.526)
		(stroke
			(width 0.05715)
			(type default)
		)
		(layer "In9.Cu")
	)
	(gr_line
		(start 412.367222 -269.35938)
		(end 412.467552 -269.25905)
		(stroke
			(width 0.08255)
			(type default)
		)
		(layer "In9.Cu")
	)
	(gr_line
		(start 412.467552 -269.25905)
		(end 412.467552 -268.76375)
		(stroke
			(width 0.08255)
			(type default)
		)
		(layer "In9.Cu")
	)
	(gr_line
		(start 412.467552 -268.76375)
		(end 412.367222 -268.66342)
		(stroke
			(width 0.08255)
			(type default)
		)
		(layer "In9.Cu")
	)
	(gr_line
		(start 412.469584 -340.668356)
		(end 412.015686 -340.469728)
		(stroke
			(width 0.08255)
			(type default)
		)
		(layer "In9.Cu")
	)
	(gr_line
		(start 412.602172 -340.61654)
		(end 412.469584 -340.668356)
		(stroke
			(width 0.08255)
			(type default)
		)
		(layer "In9.Cu")
	)
	(gr_line
		(start 412.699962 -280.699718)
		(end 412.699962 -280.434288)
		(stroke
			(width 0.05715)
			(type default)
		)
		(layer "In9.Cu")
	)
	(gr_line
		(start 412.699962 -280.434288)
		(end 412.585662 -280.319988)
		(stroke
			(width 0.05715)
			(type default)
		)
		(layer "In9.Cu")
	)
	(gr_line
		(start 412.699962 -280.015188)
		(end 412.585662 -280.129488)
		(stroke
			(width 0.05715)
			(type default)
		)
		(layer "In9.Cu")
	)
	(gr_line
		(start 412.699962 -279.749504)
		(end 412.699962 -280.015188)
		(stroke
			(width 0.05715)
			(type default)
		)
		(layer "In9.Cu")
	)
	(gr_line
		(start 412.716472 -340.35746)
		(end 412.076138 -340.077552)
		(stroke
			(width 0.08255)
			(type default)
		)
		(layer "In9.Cu")
	)
	(gr_line
		(start 413.033972 -271.500346)
		(end 413.033972 -271.471898)
		(stroke
			(width 0.05715)
			(type default)
		)
		(layer "In9.Cu")
	)
	(gr_line
		(start 413.079692 -271.546066)
		(end 413.033972 -271.500346)
		(stroke
			(width 0.05715)
			(type default)
		)
		(layer "In9.Cu")
	)
	(gr_line
		(start 413.270192 -271.546066)
		(end 413.315912 -271.500346)
		(stroke
			(width 0.05715)
			(type default)
		)
		(layer "In9.Cu")
	)
	(gr_line
		(start 413.315912 -271.500346)
		(end 413.315912 -271.471898)
		(stroke
			(width 0.05715)
			(type default)
		)
		(layer "In9.Cu")
	)
	(gr_line
		(start 413.649668 -278.799798)
		(end 413.649668 -278.534368)
		(stroke
			(width 0.05715)
			(type default)
		)
		(layer "In9.Cu")
	)
	(gr_line
		(start 413.649668 -278.534368)
		(end 413.535368 -278.420068)
		(stroke
			(width 0.05715)
			(type default)
		)
		(layer "In9.Cu")
	)
	(gr_line
		(start 413.649668 -278.115268)
		(end 413.535368 -278.229568)
		(stroke
			(width 0.05715)
			(type default)
		)
		(layer "In9.Cu")
	)
	(gr_line
		(start 413.649668 -277.849838)
		(end 413.649668 -278.115268)
		(stroke
			(width 0.05715)
			(type default)
		)
		(layer "In9.Cu")
	)
	(gr_line
		(start 413.983932 -271.554448)
		(end 413.983932 -271.526)
		(stroke
			(width 0.05715)
			(type default)
		)
		(layer "In9.Cu")
	)
	(gr_line
		(start 414.029652 -271.600168)
		(end 413.983932 -271.554448)
		(stroke
			(width 0.05715)
			(type default)
		)
		(layer "In9.Cu")
	)
	(gr_line
		(start 414.220152 -271.600168)
		(end 414.265872 -271.554448)
		(stroke
			(width 0.05715)
			(type default)
		)
		(layer "In9.Cu")
	)
	(gr_line
		(start 414.265872 -271.554448)
		(end 414.265872 -271.526)
		(stroke
			(width 0.05715)
			(type default)
		)
		(layer "In9.Cu")
	)
	(gr_line
		(start 414.322006 -390.898634)
		(end 414.307782 -390.757156)
		(stroke
			(width 0.08255)
			(type default)
		)
		(layer "In9.Cu")
	)
	(gr_line
		(start 414.413192 -340.266274)
		(end 414.412938 -340.266528)
		(stroke
			(width 0.08255)
			(type default)
		)
		(layer "In9.Cu")
	)
	(gr_line
		(start 414.465516 -340.400132)
		(end 414.413954 -340.268306)
		(stroke
			(width 0.08255)
			(type default)
		)
		(layer "In9.Cu")
	)
	(gr_line
		(start 414.599882 -280.699718)
		(end 414.599882 -280.434288)
		(stroke
			(width 0.05715)
			(type default)
		)
		(layer "In9.Cu")
	)
	(gr_line
		(start 414.599882 -280.434288)
		(end 414.485582 -280.319988)
		(stroke
			(width 0.05715)
			(type default)
		)
		(layer "In9.Cu")
	)
	(gr_line
		(start 414.599882 -280.015188)
		(end 414.485582 -280.129488)
		(stroke
			(width 0.05715)
			(type default)
		)
		(layer "In9.Cu")
	)
	(gr_line
		(start 414.599882 -279.749504)
		(end 414.599882 -280.015188)
		(stroke
			(width 0.05715)
			(type default)
		)
		(layer "In9.Cu")
	)
	(gr_line
		(start 414.706308 -391.211816)
		(end 414.322006 -390.898634)
		(stroke
			(width 0.08255)
			(type default)
		)
		(layer "In9.Cu")
	)
	(gr_line
		(start 414.84804 -391.197592)
		(end 414.706308 -391.211816)
		(stroke
			(width 0.08255)
			(type default)
		)
		(layer "In9.Cu")
	)
	(gr_line
		(start 414.919668 -340.59876)
		(end 414.465516 -340.400132)
		(stroke
			(width 0.08255)
			(type default)
		)
		(layer "In9.Cu")
	)
	(gr_line
		(start 415.027618 -390.97839)
		(end 414.485836 -390.536938)
		(stroke
			(width 0.08255)
			(type default)
		)
		(layer "In9.Cu")
	)
	(gr_line
		(start 415.051494 -340.546944)
		(end 414.919668 -340.59876)
		(stroke
			(width 0.08255)
			(type default)
		)
		(layer "In9.Cu")
	)
	(gr_line
		(start 415.053272 -340.546436)
		(end 415.053526 -340.546182)
		(stroke
			(width 0.08255)
			(type default)
		)
		(layer "In9.Cu")
	)
	(gr_line
		(start 415.166302 -340.288118)
		(end 414.525968 -340.00821)
		(stroke
			(width 0.08255)
			(type default)
		)
		(layer "In9.Cu")
	)
	(gr_line
		(start 415.170112 -271.546066)
		(end 415.215832 -271.500346)
		(stroke
			(width 0.05715)
			(type default)
		)
		(layer "In9.Cu")
	)
	(gr_line
		(start 415.215832 -271.500346)
		(end 415.215832 -271.471898)
		(stroke
			(width 0.05715)
			(type default)
		)
		(layer "In9.Cu")
	)
	(gr_line
		(start 415.247582 -391.65276)
		(end 415.233358 -391.511282)
		(stroke
			(width 0.08255)
			(type default)
		)
		(layer "In9.Cu")
	)
	(gr_line
		(start 415.50717 -340.744556)
		(end 415.506916 -340.74481)
		(stroke
			(width 0.08255)
			(type default)
		)
		(layer "In9.Cu")
	)
	(gr_line
		(start 415.549588 -278.115268)
		(end 415.435288 -278.229568)
		(stroke
			(width 0.05715)
			(type default)
		)
		(layer "In9.Cu")
	)
	(gr_line
		(start 415.549588 -277.849838)
		(end 415.549588 -278.115268)
		(stroke
			(width 0.05715)
			(type default)
		)
		(layer "In9.Cu")
	)
	(gr_line
		(start 415.559494 -340.878414)
		(end 415.507932 -340.746588)
		(stroke
			(width 0.08255)
			(type default)
		)
		(layer "In9.Cu")
	)
	(gr_line
		(start 415.631884 -391.965942)
		(end 415.247582 -391.65276)
		(stroke
			(width 0.08255)
			(type default)
		)
		(layer "In9.Cu")
	)
	(gr_line
		(start 415.773362 -391.951718)
		(end 415.631884 -391.965942)
		(stroke
			(width 0.08255)
			(type default)
		)
		(layer "In9.Cu")
	)
	(gr_line
		(start 415.883852 -271.554448)
		(end 415.883852 -271.526)
		(stroke
			(width 0.05715)
			(type default)
		)
		(layer "In9.Cu")
	)
	(gr_line
		(start 415.929572 -271.600168)
		(end 415.883852 -271.554448)
		(stroke
			(width 0.05715)
			(type default)
		)
		(layer "In9.Cu")
	)
	(gr_line
		(start 415.953194 -391.73277)
		(end 415.411412 -391.291064)
		(stroke
			(width 0.08255)
			(type default)
		)
		(layer "In9.Cu")
	)
	(gr_line
		(start 416.013646 -341.077042)
		(end 415.559494 -340.878414)
		(stroke
			(width 0.08255)
			(type default)
		)
		(layer "In9.Cu")
	)
	(gr_line
		(start 416.120072 -271.600168)
		(end 416.165792 -271.554448)
		(stroke
			(width 0.05715)
			(type default)
		)
		(layer "In9.Cu")
	)
	(gr_line
		(start 416.145726 -341.025226)
		(end 416.013646 -341.077042)
		(stroke
			(width 0.08255)
			(type default)
		)
		(layer "In9.Cu")
	)
	(gr_line
		(start 416.165792 -271.554448)
		(end 416.165792 -271.526)
		(stroke
			(width 0.05715)
			(type default)
		)
		(layer "In9.Cu")
	)
	(gr_line
		(start 416.173412 -392.40714)
		(end 416.158934 -392.265662)
		(stroke
			(width 0.08255)
			(type default)
		)
		(layer "In9.Cu")
	)
	(gr_line
		(start 416.26028 -340.7664)
		(end 415.619946 -340.486492)
		(stroke
			(width 0.08255)
			(type default)
		)
		(layer "In9.Cu")
	)
	(gr_line
		(start 416.499802 -280.699718)
		(end 416.499802 -280.434288)
		(stroke
			(width 0.05715)
			(type default)
		)
		(layer "In9.Cu")
	)
	(gr_line
		(start 416.499802 -280.434288)
		(end 416.385502 -280.319988)
		(stroke
			(width 0.05715)
			(type default)
		)
		(layer "In9.Cu")
	)
	(gr_line
		(start 416.499802 -280.015188)
		(end 416.385502 -280.129488)
		(stroke
			(width 0.05715)
			(type default)
		)
		(layer "In9.Cu")
	)
	(gr_line
		(start 416.499802 -279.749504)
		(end 416.499802 -280.015188)
		(stroke
			(width 0.05715)
			(type default)
		)
		(layer "In9.Cu")
	)
	(gr_line
		(start 416.55746 -392.720322)
		(end 416.173412 -392.40714)
		(stroke
			(width 0.08255)
			(type default)
		)
		(layer "In9.Cu")
	)
	(gr_line
		(start 416.698938 -392.705844)
		(end 416.55746 -392.720322)
		(stroke
			(width 0.08255)
			(type default)
		)
		(layer "In9.Cu")
	)
	(gr_line
		(start 416.87877 -392.486896)
		(end 416.336988 -392.045444)
		(stroke
			(width 0.08255)
			(type default)
		)
		(layer "In9.Cu")
	)
	(gr_line
		(start 417.784026 -271.554448)
		(end 417.784026 -271.526)
		(stroke
			(width 0.05715)
			(type default)
		)
		(layer "In9.Cu")
	)
	(gr_line
		(start 417.829746 -271.600168)
		(end 417.784026 -271.554448)
		(stroke
			(width 0.05715)
			(type default)
		)
		(layer "In9.Cu")
	)
	(gr_line
		(start 418.020246 -271.600168)
		(end 418.065966 -271.554448)
		(stroke
			(width 0.05715)
			(type default)
		)
		(layer "In9.Cu")
	)
	(gr_line
		(start 418.065966 -271.554448)
		(end 418.065966 -271.526)
		(stroke
			(width 0.05715)
			(type default)
		)
		(layer "In9.Cu")
	)
	(gr_line
		(start 418.399976 -280.699718)
		(end 418.399976 -280.434288)
		(stroke
			(width 0.05715)
			(type default)
		)
		(layer "In9.Cu")
	)
	(gr_line
		(start 418.399976 -280.434288)
		(end 418.285676 -280.319988)
		(stroke
			(width 0.05715)
			(type default)
		)
		(layer "In9.Cu")
	)
	(gr_line
		(start 418.399976 -280.015188)
		(end 418.285676 -280.129488)
		(stroke
			(width 0.05715)
			(type default)
		)
		(layer "In9.Cu")
	)
	(gr_line
		(start 418.399976 -279.749504)
		(end 418.399976 -280.015188)
		(stroke
			(width 0.05715)
			(type default)
		)
		(layer "In9.Cu")
	)
	(gr_line
		(start 418.408612 -393.96289)
		(end 418.347652 -393.834366)
		(stroke
			(width 0.08255)
			(type default)
		)
		(layer "In9.Cu")
	)
	(gr_line
		(start 418.561774 -340.97341)
		(end 418.562028 -340.97341)
		(stroke
			(width 0.08255)
			(type default)
		)
		(layer "In9.Cu")
	)
	(gr_line
		(start 418.624512 -341.10295)
		(end 418.56279 -340.974934)
		(stroke
			(width 0.08255)
			(type default)
		)
		(layer "In9.Cu")
	)
	(gr_line
		(start 418.875464 -394.128752)
		(end 418.408612 -393.96289)
		(stroke
			(width 0.08255)
			(type default)
		)
		(layer "In9.Cu")
	)
	(gr_line
		(start 419.003988 -394.067792)
		(end 418.875464 -394.128752)
		(stroke
			(width 0.08255)
			(type default)
		)
		(layer "In9.Cu")
	)
	(gr_line
		(start 419.09238 -341.266018)
		(end 418.624512 -341.10295)
		(stroke
			(width 0.08255)
			(type default)
		)
		(layer "In9.Cu")
	)
	(gr_line
		(start 419.099746 -393.801346)
		(end 418.441378 -393.567158)
		(stroke
			(width 0.08255)
			(type default)
		)
		(layer "In9.Cu")
	)
	(gr_line
		(start 419.220396 -341.204296)
		(end 419.09238 -341.266018)
		(stroke
			(width 0.08255)
			(type default)
		)
		(layer "In9.Cu")
	)
	(gr_line
		(start 419.31463 -340.937342)
		(end 418.654738 -340.707218)
		(stroke
			(width 0.08255)
			(type default)
		)
		(layer "In9.Cu")
	)
	(gr_line
		(start 419.48989 -409.490164)
		(end 419.48989 -409.108148)
		(stroke
			(width 0.08255)
			(type default)
		)
		(layer "In9.Cu")
	)
	(gr_line
		(start 419.48989 -409.108148)
		(end 419.61689 -408.981148)
		(stroke
			(width 0.08255)
			(type default)
		)
		(layer "In9.Cu")
	)
	(gr_line
		(start 419.48989 -408.572208)
		(end 419.61689 -408.699208)
		(stroke
			(width 0.08255)
			(type default)
		)
		(layer "In9.Cu")
	)
	(gr_line
		(start 419.48989 -408.190192)
		(end 419.48989 -408.572208)
		(stroke
			(width 0.08255)
			(type default)
		)
		(layer "In9.Cu")
	)
	(gr_line
		(start 419.553644 -391.945368)
		(end 419.451028 -391.908792)
		(stroke
			(width 0.08255)
			(type default)
		)
		(layer "In9.Cu")
	)
	(gr_line
		(start 419.615366 -392.075416)
		(end 419.554406 -391.946892)
		(stroke
			(width 0.08255)
			(type default)
		)
		(layer "In9.Cu")
	)
	(gr_line
		(start 419.648132 -391.679684)
		(end 419.545516 -391.643108)
		(stroke
			(width 0.08255)
			(type default)
		)
		(layer "In9.Cu")
	)
	(gr_line
		(start 419.683946 -271.554448)
		(end 419.683946 -271.526)
		(stroke
			(width 0.05715)
			(type default)
		)
		(layer "In9.Cu")
	)
	(gr_line
		(start 419.729666 -271.600168)
		(end 419.683946 -271.554448)
		(stroke
			(width 0.05715)
			(type default)
		)
		(layer "In9.Cu")
	)
	(gr_line
		(start 419.920166 -271.600168)
		(end 419.965886 -271.554448)
		(stroke
			(width 0.05715)
			(type default)
		)
		(layer "In9.Cu")
	)
	(gr_line
		(start 419.965886 -271.554448)
		(end 419.965886 -271.526)
		(stroke
			(width 0.05715)
			(type default)
		)
		(layer "In9.Cu")
	)
	(gr_line
		(start 420.082218 -392.241532)
		(end 419.615366 -392.075416)
		(stroke
			(width 0.08255)
			(type default)
		)
		(layer "In9.Cu")
	)
	(gr_line
		(start 420.210488 -392.180572)
		(end 420.082218 -392.241532)
		(stroke
			(width 0.08255)
			(type default)
		)
		(layer "In9.Cu")
	)
	(gr_line
		(start 420.260526 -393.429998)
		(end 420.260526 -393.430252)
		(stroke
			(width 0.08255)
			(type default)
		)
		(layer "In9.Cu")
	)
	(gr_line
		(start 420.299896 -280.699718)
		(end 420.299896 -280.434288)
		(stroke
			(width 0.05715)
			(type default)
		)
		(layer "In9.Cu")
	)
	(gr_line
		(start 420.299896 -280.434288)
		(end 420.185596 -280.319988)
		(stroke
			(width 0.05715)
			(type default)
		)
		(layer "In9.Cu")
	)
	(gr_line
		(start 420.299896 -280.015188)
		(end 420.185596 -280.129488)
		(stroke
			(width 0.05715)
			(type default)
		)
		(layer "In9.Cu")
	)
	(gr_line
		(start 420.299896 -279.749504)
		(end 420.299896 -280.015188)
		(stroke
			(width 0.05715)
			(type default)
		)
		(layer "In9.Cu")
	)
	(gr_line
		(start 420.3065 -391.914126)
		(end 419.648132 -391.679684)
		(stroke
			(width 0.08255)
			(type default)
		)
		(layer "In9.Cu")
	)
	(gr_line
		(start 420.322248 -393.560046)
		(end 420.261288 -393.431776)
		(stroke
			(width 0.08255)
			(type default)
		)
		(layer "In9.Cu")
	)
	(gr_line
		(start 420.740332 -392.47572)
		(end 420.679372 -392.347196)
		(stroke
			(width 0.08255)
			(type default)
		)
		(layer "In9.Cu")
	)
	(gr_line
		(start 420.7891 -393.726162)
		(end 420.322248 -393.560046)
		(stroke
			(width 0.08255)
			(type default)
		)
		(layer "In9.Cu")
	)
	(gr_line
		(start 420.91737 -393.665202)
		(end 420.7891 -393.726162)
		(stroke
			(width 0.08255)
			(type default)
		)
		(layer "In9.Cu")
	)
	(gr_line
		(start 421.013382 -393.398756)
		(end 420.355014 -393.164568)
		(stroke
			(width 0.08255)
			(type default)
		)
		(layer "In9.Cu")
	)
	(gr_line
		(start 421.207184 -392.641836)
		(end 420.740332 -392.47572)
		(stroke
			(width 0.08255)
			(type default)
		)
		(layer "In9.Cu")
	)
	(gr_line
		(start 421.335708 -392.580876)
		(end 421.207184 -392.641836)
		(stroke
			(width 0.08255)
			(type default)
		)
		(layer "In9.Cu")
	)
	(gr_line
		(start 421.431466 -392.314176)
		(end 420.773098 -392.079988)
		(stroke
			(width 0.08255)
			(type default)
		)
		(layer "In9.Cu")
	)
	(gr_line
		(start 421.583866 -271.554448)
		(end 421.583866 -271.526)
		(stroke
			(width 0.05715)
			(type default)
		)
		(layer "In9.Cu")
	)
	(gr_line
		(start 421.629586 -271.600168)
		(end 421.583866 -271.554448)
		(stroke
			(width 0.05715)
			(type default)
		)
		(layer "In9.Cu")
	)
	(gr_line
		(start 421.689784 -410.589984)
		(end 421.689784 -410.207968)
		(stroke
			(width 0.08255)
			(type default)
		)
		(layer "In9.Cu")
	)
	(gr_line
		(start 421.689784 -410.207968)
		(end 421.816784 -410.080968)
		(stroke
			(width 0.08255)
			(type default)
		)
		(layer "In9.Cu")
	)
	(gr_line
		(start 421.689784 -409.672028)
		(end 421.816784 -409.799028)
		(stroke
			(width 0.08255)
			(type default)
		)
		(layer "In9.Cu")
	)
	(gr_line
		(start 421.689784 -409.290012)
		(end 421.689784 -409.672028)
		(stroke
			(width 0.08255)
			(type default)
		)
		(layer "In9.Cu")
	)
	(gr_line
		(start 421.820086 -271.600168)
		(end 421.865806 -271.554448)
		(stroke
			(width 0.05715)
			(type default)
		)
		(layer "In9.Cu")
	)
	(gr_line
		(start 421.865298 -392.876024)
		(end 421.804338 -392.7475)
		(stroke
			(width 0.08255)
			(type default)
		)
		(layer "In9.Cu")
	)
	(gr_line
		(start 421.865806 -271.554448)
		(end 421.865806 -271.526)
		(stroke
			(width 0.05715)
			(type default)
		)
		(layer "In9.Cu")
	)
	(gr_line
		(start 422.199816 -280.699718)
		(end 422.199816 -280.434288)
		(stroke
			(width 0.05715)
			(type default)
		)
		(layer "In9.Cu")
	)
	(gr_line
		(start 422.199816 -280.434288)
		(end 422.085516 -280.319988)
		(stroke
			(width 0.05715)
			(type default)
		)
		(layer "In9.Cu")
	)
	(gr_line
		(start 422.199816 -280.015188)
		(end 422.085516 -280.129488)
		(stroke
			(width 0.05715)
			(type default)
		)
		(layer "In9.Cu")
	)
	(gr_line
		(start 422.199816 -279.749504)
		(end 422.199816 -280.015188)
		(stroke
			(width 0.05715)
			(type default)
		)
		(layer "In9.Cu")
	)
	(gr_line
		(start 422.33215 -393.04214)
		(end 421.865298 -392.876024)
		(stroke
			(width 0.08255)
			(type default)
		)
		(layer "In9.Cu")
	)
	(gr_line
		(start 422.460674 -392.98118)
		(end 422.33215 -393.04214)
		(stroke
			(width 0.08255)
			(type default)
		)
		(layer "In9.Cu")
	)
	(gr_line
		(start 422.556432 -392.71448)
		(end 421.898064 -392.480292)
		(stroke
			(width 0.08255)
			(type default)
		)
		(layer "In9.Cu")
	)
	(gr_line
		(start 423.465498 -393.809982)
		(end 423.465498 -393.667996)
		(stroke
			(width 0.08255)
			(type default)
		)
		(layer "In9.Cu")
	)
	(gr_line
		(start 423.816018 -394.160502)
		(end 423.465498 -393.809982)
		(stroke
			(width 0.08255)
			(type default)
		)
		(layer "In9.Cu")
	)
	(gr_line
		(start 423.889932 -409.490164)
		(end 423.889932 -409.108148)
		(stroke
			(width 0.08255)
			(type default)
		)
		(layer "In9.Cu")
	)
	(gr_line
		(start 423.889932 -409.108148)
		(end 424.016932 -408.981148)
		(stroke
			(width 0.08255)
			(type default)
		)
		(layer "In9.Cu")
	)
	(gr_line
		(start 423.889932 -408.572208)
		(end 424.016932 -408.699208)
		(stroke
			(width 0.08255)
			(type default)
		)
		(layer "In9.Cu")
	)
	(gr_line
		(start 423.889932 -408.190192)
		(end 423.889932 -408.572208)
		(stroke
			(width 0.08255)
			(type default)
		)
		(layer "In9.Cu")
	)
	(gr_line
		(start 423.958004 -394.160502)
		(end 423.816018 -394.160502)
		(stroke
			(width 0.08255)
			(type default)
		)
		(layer "In9.Cu")
	)
	(gr_line
		(start 424.159172 -393.961112)
		(end 423.664888 -393.466828)
		(stroke
			(width 0.08255)
			(type default)
		)
		(layer "In9.Cu")
	)
	(gr_line
		(start 426.424344 -393.003024)
		(end 426.392848 -392.864086)
		(stroke
			(width 0.08255)
			(type default)
		)
		(layer "In9.Cu")
	)
	(gr_line
		(start 426.84319 -393.267692)
		(end 426.424344 -393.003024)
		(stroke
			(width 0.08255)
			(type default)
		)
		(layer "In9.Cu")
	)
	(gr_line
		(start 426.982128 -393.23645)
		(end 426.84319 -393.267692)
		(stroke
			(width 0.08255)
			(type default)
		)
		(layer "In9.Cu")
	)
	(gr_line
		(start 427.134274 -392.997436)
		(end 426.543216 -392.62431)
		(stroke
			(width 0.08255)
			(type default)
		)
		(layer "In9.Cu")
	)
	(gr_line
		(start 427.433486 -393.640818)
		(end 427.402244 -393.50188)
		(stroke
			(width 0.08255)
			(type default)
		)
		(layer "In9.Cu")
	)
	(gr_line
		(start 427.852586 -393.905486)
		(end 427.433486 -393.640818)
		(stroke
			(width 0.08255)
			(type default)
		)
		(layer "In9.Cu")
	)
	(gr_line
		(start 427.991524 -393.874244)
		(end 427.852586 -393.905486)
		(stroke
			(width 0.08255)
			(type default)
		)
		(layer "In9.Cu")
	)
	(gr_line
		(start 428.14367 -393.63523)
		(end 427.552612 -393.262104)
		(stroke
			(width 0.08255)
			(type default)
		)
		(layer "In9.Cu")
	)
	(gr_line
		(start 428.289974 -409.490164)
		(end 428.289974 -409.108148)
		(stroke
			(width 0.08255)
			(type default)
		)
		(layer "In9.Cu")
	)
	(gr_line
		(start 428.289974 -409.108148)
		(end 428.416974 -408.981148)
		(stroke
			(width 0.08255)
			(type default)
		)
		(layer "In9.Cu")
	)
	(gr_line
		(start 428.289974 -408.572208)
		(end 428.416974 -408.699208)
		(stroke
			(width 0.08255)
			(type default)
		)
		(layer "In9.Cu")
	)
	(gr_line
		(start 428.289974 -408.190192)
		(end 428.289974 -408.572208)
		(stroke
			(width 0.08255)
			(type default)
		)
		(layer "In9.Cu")
	)
	(gr_line
		(start 428.77994 -199.893174)
		(end 428.780194 -199.893174)
		(stroke
			(width 0.08255)
			(type default)
		)
		(layer "In9.Cu")
	)
	(gr_line
		(start 429.800004 -276.899878)
		(end 430.065434 -276.899878)
		(stroke
			(width 0.05715)
			(type default)
		)
		(layer "In9.Cu")
	)
	(gr_line
		(start 430.065434 -276.899878)
		(end 430.179734 -276.785578)
		(stroke
			(width 0.05715)
			(type default)
		)
		(layer "In9.Cu")
	)
	(gr_line
		(start 430.123092 -143.188436)
		(end 429.832262 -143.479266)
		(stroke
			(width 0.08255)
			(type default)
		)
		(layer "In9.Cu")
	)
	(gr_line
		(start 430.489868 -410.589984)
		(end 430.489868 -410.207968)
		(stroke
			(width 0.08255)
			(type default)
		)
		(layer "In9.Cu")
	)
	(gr_line
		(start 430.489868 -410.207968)
		(end 430.616868 -410.080968)
		(stroke
			(width 0.08255)
			(type default)
		)
		(layer "In9.Cu")
	)
	(gr_line
		(start 430.489868 -409.672028)
		(end 430.616868 -409.799028)
		(stroke
			(width 0.08255)
			(type default)
		)
		(layer "In9.Cu")
	)
	(gr_line
		(start 430.489868 -409.290012)
		(end 430.489868 -409.672028)
		(stroke
			(width 0.08255)
			(type default)
		)
		(layer "In9.Cu")
	)
	(gr_line
		(start 430.936146 -393.254992)
		(end 430.904904 -393.116562)
		(stroke
			(width 0.08255)
			(type default)
		)
		(layer "In9.Cu")
	)
	(gr_line
		(start 431.084228 -271.8054)
		(end 431.084228 -271.776952)
		(stroke
			(width 0.05715)
			(type default)
		)
		(layer "In9.Cu")
	)
	(gr_line
		(start 431.129948 -271.85112)
		(end 431.084228 -271.8054)
		(stroke
			(width 0.05715)
			(type default)
		)
		(layer "In9.Cu")
	)
	(gr_line
		(start 431.354992 -393.51966)
		(end 430.936146 -393.254992)
		(stroke
			(width 0.08255)
			(type default)
		)
		(layer "In9.Cu")
	)
	(gr_line
		(start 431.493676 -393.488418)
		(end 431.354992 -393.51966)
		(stroke
			(width 0.08255)
			(type default)
		)
		(layer "In9.Cu")
	)
	(gr_line
		(start 431.645822 -393.249658)
		(end 431.055018 -392.876278)
		(stroke
			(width 0.08255)
			(type default)
		)
		(layer "In9.Cu")
	)
	(gr_line
		(start 431.945288 -393.892786)
		(end 431.914046 -393.754102)
		(stroke
			(width 0.08255)
			(type default)
		)
		(layer "In9.Cu")
	)
	(gr_line
		(start 432.364388 -394.157454)
		(end 431.945288 -393.892786)
		(stroke
			(width 0.08255)
			(type default)
		)
		(layer "In9.Cu")
	)
	(gr_line
		(start 432.392328 -143.282162)
		(end 432.345084 -143.167608)
		(stroke
			(width 0.08255)
			(type default)
		)
		(layer "In9.Cu")
	)
	(gr_line
		(start 432.503072 -394.126212)
		(end 432.364388 -394.157454)
		(stroke
			(width 0.08255)
			(type default)
		)
		(layer "In9.Cu")
	)
	(gr_line
		(start 432.654964 -393.887198)
		(end 432.064414 -393.514072)
		(stroke
			(width 0.08255)
			(type default)
		)
		(layer "In9.Cu")
	)
	(gr_line
		(start 432.689762 -409.490164)
		(end 432.689762 -409.108148)
		(stroke
			(width 0.08255)
			(type default)
		)
		(layer "In9.Cu")
	)
	(gr_line
		(start 432.689762 -409.108148)
		(end 432.816762 -408.981148)
		(stroke
			(width 0.08255)
			(type default)
		)
		(layer "In9.Cu")
	)
	(gr_line
		(start 432.689762 -408.572208)
		(end 432.816762 -408.699208)
		(stroke
			(width 0.08255)
			(type default)
		)
		(layer "In9.Cu")
	)
	(gr_line
		(start 432.689762 -408.190192)
		(end 432.689762 -408.572208)
		(stroke
			(width 0.08255)
			(type default)
		)
		(layer "In9.Cu")
	)
	(gr_line
		(start 432.85029 -143.4719)
		(end 432.392328 -143.282162)
		(stroke
			(width 0.08255)
			(type default)
		)
		(layer "In9.Cu")
	)
	(gr_line
		(start 432.964844 -143.424402)
		(end 432.85029 -143.4719)
		(stroke
			(width 0.08255)
			(type default)
		)
		(layer "In9.Cu")
	)
	(gr_line
		(start 434.66639 -144.90192)
		(end 434.66639 -144.777968)
		(stroke
			(width 0.08255)
			(type default)
		)
		(layer "In9.Cu")
	)
	(gr_line
		(start 434.88991 -410.589984)
		(end 434.88991 -410.207968)
		(stroke
			(width 0.08255)
			(type default)
		)
		(layer "In9.Cu")
	)
	(gr_line
		(start 434.88991 -410.207968)
		(end 435.01691 -410.080968)
		(stroke
			(width 0.08255)
			(type default)
		)
		(layer "In9.Cu")
	)
	(gr_line
		(start 434.88991 -409.672028)
		(end 435.01691 -409.799028)
		(stroke
			(width 0.08255)
			(type default)
		)
		(layer "In9.Cu")
	)
	(gr_line
		(start 434.88991 -409.290012)
		(end 434.88991 -409.672028)
		(stroke
			(width 0.08255)
			(type default)
		)
		(layer "In9.Cu")
	)
	(gr_line
		(start 435.01691 -145.25244)
		(end 434.66639 -144.90192)
		(stroke
			(width 0.08255)
			(type default)
		)
		(layer "In9.Cu")
	)
	(gr_line
		(start 435.140862 -145.25244)
		(end 435.01691 -145.25244)
		(stroke
			(width 0.08255)
			(type default)
		)
		(layer "In9.Cu")
	)
	(gr_line
		(start 435.492652 -145.728182)
		(end 435.492652 -145.60423)
		(stroke
			(width 0.08255)
			(type default)
		)
		(layer "In9.Cu")
	)
	(gr_line
		(start 435.843172 -146.078702)
		(end 435.492652 -145.728182)
		(stroke
			(width 0.08255)
			(type default)
		)
		(layer "In9.Cu")
	)
	(gr_line
		(start 435.967124 -146.078702)
		(end 435.843172 -146.078702)
		(stroke
			(width 0.08255)
			(type default)
		)
		(layer "In9.Cu")
	)
	(gr_line
		(start 436.370222 -146.605752)
		(end 436.370222 -146.4818)
		(stroke
			(width 0.08255)
			(type default)
		)
		(layer "In9.Cu")
	)
	(gr_line
		(start 436.720488 -146.956018)
		(end 436.370222 -146.605752)
		(stroke
			(width 0.08255)
			(type default)
		)
		(layer "In9.Cu")
	)
	(gr_line
		(start 436.84444 -146.956018)
		(end 436.720488 -146.956018)
		(stroke
			(width 0.08255)
			(type default)
		)
		(layer "In9.Cu")
	)
	(gr_line
		(start 437.324246 -147.718272)
		(end 437.348376 -147.596606)
		(stroke
			(width 0.08255)
			(type default)
		)
		(layer "In9.Cu")
	)
	(gr_line
		(start 437.599582 -148.13026)
		(end 437.324246 -147.718272)
		(stroke
			(width 0.08255)
			(type default)
		)
		(layer "In9.Cu")
	)
	(gr_line
		(start 437.721248 -148.154644)
		(end 437.599582 -148.13026)
		(stroke
			(width 0.08255)
			(type default)
		)
		(layer "In9.Cu")
	)
	(gr_line
		(start 437.723026 -148.154898)
		(end 437.722772 -148.154898)
		(stroke
			(width 0.08255)
			(type default)
		)
		(layer "In9.Cu")
	)
	(gr_line
		(start 438.300368 -149.38121)
		(end 438.347866 -149.266656)
		(stroke
			(width 0.08255)
			(type default)
		)
		(layer "In9.Cu")
	)
	(gr_line
		(start 438.49036 -149.839172)
		(end 438.300368 -149.38121)
		(stroke
			(width 0.08255)
			(type default)
		)
		(layer "In9.Cu")
	)
	(gr_line
		(start 438.60466 -149.886416)
		(end 438.49036 -149.839172)
		(stroke
			(width 0.08255)
			(type default)
		)
		(layer "In9.Cu")
	)
	(gr_line
		(start 438.606438 -149.887178)
		(end 438.606184 -149.887178)
		(stroke
			(width 0.08255)
			(type default)
		)
		(layer "In9.Cu")
	)
	(gr_circle
		(center -51.689 -317.1952)
		(end -51.435 -317.1952)
		(stroke
			(width 0.1016)
			(type default)
		)
		(fill no)
		(layer "In10.Cu")
	)
	(gr_poly
		(pts
			(arc
				(start 265.615928 -377.679966)
				(mid 265.635451 -377.676065)
				(end 265.651996 -377.66498)
			)
			(arc
				(start 265.851386 -377.46559)
				(mid 265.862497 -377.449056)
				(end 265.866372 -377.429522)
			)
			(arc
				(start 265.866372 -368.884962)
				(mid 265.862471 -368.865439)
				(end 265.851386 -368.848894)
			)
			(arc
				(start 265.514582 -368.51209)
				(mid 265.498048 -368.500979)
				(end 265.478514 -368.497104)
			)
			(arc
				(start 242.901216 -368.497104)
				(mid 242.881693 -368.501005)
				(end 242.865148 -368.51209)
			)
			(arc
				(start 242.760754 -368.616484)
				(mid 242.749643 -368.633018)
				(end 242.745768 -368.652552)
			)
			(arc
				(start 242.745768 -377.268994)
				(mid 242.749669 -377.288517)
				(end 242.760754 -377.305062)
			)
			(arc
				(start 243.120672 -377.66498)
				(mid 243.137206 -377.676091)
				(end 243.15674 -377.679966)
			)
		)
		(stroke
			(width 0)
			(type solid)
		)
		(fill yes)
		(layer "In10.Cu")
		(net "P12V_STBY_R2")
	)
	(gr_poly
		(pts
			(arc
				(start 43.702986 -312.049922)
				(mid 43.296586 -312.049922)
				(end 43.702986 -312.049922)
			)
		)
		(stroke
			(width 0)
			(type solid)
		)
		(fill yes)
		(layer "In10.Cu")
		(net "P5E_PEX0_STN6_TX_DN<111>")
	)
	(gr_poly
		(pts
			(arc
				(start 43.702986 -311.099962)
				(mid 43.296586 -311.099962)
				(end 43.702986 -311.099962)
			)
		)
		(stroke
			(width 0)
			(type solid)
		)
		(fill yes)
		(layer "In10.Cu")
		(net "P5E_PEX0_STN6_TX_DP<111>")
	)
	(gr_poly
		(pts
			(arc
				(start 44.652946 -313.949842)
				(mid 44.246546 -313.949842)
				(end 44.652946 -313.949842)
			)
		)
		(stroke
			(width 0)
			(type solid)
		)
		(fill yes)
		(layer "In10.Cu")
		(net "P5E_PEX0_STN6_TX_DN<110>")
	)
	(gr_poly
		(pts
			(arc
				(start 44.652946 -312.999882)
				(mid 44.246546 -312.999882)
				(end 44.652946 -312.999882)
			)
		)
		(stroke
			(width 0)
			(type solid)
		)
		(fill yes)
		(layer "In10.Cu")
		(net "P5E_PEX0_STN6_TX_DP<110>")
	)
	(gr_poly
		(pts
			(arc
				(start 44.652946 -278.799798)
				(mid 44.246546 -278.799798)
				(end 44.652946 -278.799798)
			)
		)
		(stroke
			(width 0)
			(type solid)
		)
		(fill yes)
		(layer "In10.Cu")
		(net "P5E_PEX0_STN2_TX_DP<47>")
	)
	(gr_poly
		(pts
			(arc
				(start 44.652946 -277.849838)
				(mid 44.246546 -277.849838)
				(end 44.652946 -277.849838)
			)
		)
		(stroke
			(width 0)
			(type solid)
		)
		(fill yes)
		(layer "In10.Cu")
		(net "P5E_PEX0_STN2_TX_DN<47>")
	)
	(gr_poly
		(pts
			(arc
				(start 45.60316 -312.049922)
				(mid 45.19676 -312.049922)
				(end 45.60316 -312.049922)
			)
		)
		(stroke
			(width 0)
			(type solid)
		)
		(fill yes)
		(layer "In10.Cu")
		(net "P5E_PEX0_STN6_TX_DN<109>")
	)
	(gr_poly
		(pts
			(arc
				(start 45.60316 -311.099962)
				(mid 45.19676 -311.099962)
				(end 45.60316 -311.099962)
			)
		)
		(stroke
			(width 0)
			(type solid)
		)
		(fill yes)
		(layer "In10.Cu")
		(net "P5E_PEX0_STN6_TX_DP<109>")
	)
	(gr_poly
		(pts
			(arc
				(start 45.60316 -280.699718)
				(mid 45.19676 -280.699718)
				(end 45.60316 -280.699718)
			)
		)
		(stroke
			(width 0)
			(type solid)
		)
		(fill yes)
		(layer "In10.Cu")
		(net "P5E_PEX0_STN2_TX_DP<46>")
	)
	(gr_poly
		(pts
			(arc
				(start 45.60316 -279.749504)
				(mid 45.19676 -279.749504)
				(end 45.60316 -279.749504)
			)
		)
		(stroke
			(width 0)
			(type solid)
		)
		(fill yes)
		(layer "In10.Cu")
		(net "P5E_PEX0_STN2_TX_DN<46>")
	)
	(gr_poly
		(pts
			(arc
				(start 46.55312 -313.949842)
				(mid 46.14672 -313.949842)
				(end 46.55312 -313.949842)
			)
		)
		(stroke
			(width 0)
			(type solid)
		)
		(fill yes)
		(layer "In10.Cu")
		(net "P5E_PEX0_STN6_TX_DN<108>")
	)
	(gr_poly
		(pts
			(arc
				(start 46.55312 -312.999882)
				(mid 46.14672 -312.999882)
				(end 46.55312 -312.999882)
			)
		)
		(stroke
			(width 0)
			(type solid)
		)
		(fill yes)
		(layer "In10.Cu")
		(net "P5E_PEX0_STN6_TX_DP<108>")
	)
	(gr_poly
		(pts
			(arc
				(start 46.55312 -278.799798)
				(mid 46.14672 -278.799798)
				(end 46.55312 -278.799798)
			)
		)
		(stroke
			(width 0)
			(type solid)
		)
		(fill yes)
		(layer "In10.Cu")
		(net "P5E_PEX0_STN2_TX_DP<45>")
	)
	(gr_poly
		(pts
			(arc
				(start 46.55312 -277.849838)
				(mid 46.14672 -277.849838)
				(end 46.55312 -277.849838)
			)
		)
		(stroke
			(width 0)
			(type solid)
		)
		(fill yes)
		(layer "In10.Cu")
		(net "P5E_PEX0_STN2_TX_DN<45>")
	)
	(gr_poly
		(pts
			(arc
				(start 47.50308 -312.049922)
				(mid 47.09668 -312.049922)
				(end 47.50308 -312.049922)
			)
		)
		(stroke
			(width 0)
			(type solid)
		)
		(fill yes)
		(layer "In10.Cu")
		(net "P5E_PEX0_STN6_TX_DN<107>")
	)
	(gr_poly
		(pts
			(arc
				(start 47.50308 -311.099962)
				(mid 47.09668 -311.099962)
				(end 47.50308 -311.099962)
			)
		)
		(stroke
			(width 0)
			(type solid)
		)
		(fill yes)
		(layer "In10.Cu")
		(net "P5E_PEX0_STN6_TX_DP<107>")
	)
	(gr_poly
		(pts
			(arc
				(start 47.50308 -280.699718)
				(mid 47.09668 -280.699718)
				(end 47.50308 -280.699718)
			)
		)
		(stroke
			(width 0)
			(type solid)
		)
		(fill yes)
		(layer "In10.Cu")
		(net "P5E_PEX0_STN2_TX_DP<44>")
	)
	(gr_poly
		(pts
			(arc
				(start 47.50308 -279.749504)
				(mid 47.09668 -279.749504)
				(end 47.50308 -279.749504)
			)
		)
		(stroke
			(width 0)
			(type solid)
		)
		(fill yes)
		(layer "In10.Cu")
		(net "P5E_PEX0_STN2_TX_DN<44>")
	)
	(gr_poly
		(pts
			(arc
				(start 48.45304 -313.949842)
				(mid 48.04664 -313.949842)
				(end 48.45304 -313.949842)
			)
		)
		(stroke
			(width 0)
			(type solid)
		)
		(fill yes)
		(layer "In10.Cu")
		(net "P5E_PEX0_STN6_TX_DN<106>")
	)
	(gr_poly
		(pts
			(arc
				(start 48.45304 -312.999882)
				(mid 48.04664 -312.999882)
				(end 48.45304 -312.999882)
			)
		)
		(stroke
			(width 0)
			(type solid)
		)
		(fill yes)
		(layer "In10.Cu")
		(net "P5E_PEX0_STN6_TX_DP<106>")
	)
	(gr_poly
		(pts
			(arc
				(start 48.45304 -278.799798)
				(mid 48.04664 -278.799798)
				(end 48.45304 -278.799798)
			)
		)
		(stroke
			(width 0)
			(type solid)
		)
		(fill yes)
		(layer "In10.Cu")
		(net "P5E_PEX0_STN2_TX_DP<43>")
	)
	(gr_poly
		(pts
			(arc
				(start 48.45304 -277.849838)
				(mid 48.04664 -277.849838)
				(end 48.45304 -277.849838)
			)
		)
		(stroke
			(width 0)
			(type solid)
		)
		(fill yes)
		(layer "In10.Cu")
		(net "P5E_PEX0_STN2_TX_DN<43>")
	)
	(gr_poly
		(pts
			(arc
				(start 49.403 -312.049922)
				(mid 48.9966 -312.049922)
				(end 49.403 -312.049922)
			)
		)
		(stroke
			(width 0)
			(type solid)
		)
		(fill yes)
		(layer "In10.Cu")
		(net "P5E_PEX0_STN6_TX_DN<105>")
	)
	(gr_poly
		(pts
			(arc
				(start 49.403 -311.099962)
				(mid 48.9966 -311.099962)
				(end 49.403 -311.099962)
			)
		)
		(stroke
			(width 0)
			(type solid)
		)
		(fill yes)
		(layer "In10.Cu")
		(net "P5E_PEX0_STN6_TX_DP<105>")
	)
	(gr_poly
		(pts
			(arc
				(start 49.403 -280.699718)
				(mid 48.9966 -280.699718)
				(end 49.403 -280.699718)
			)
		)
		(stroke
			(width 0)
			(type solid)
		)
		(fill yes)
		(layer "In10.Cu")
		(net "P5E_PEX0_STN2_TX_DP<42>")
	)
	(gr_poly
		(pts
			(arc
				(start 49.403 -279.749504)
				(mid 48.9966 -279.749504)
				(end 49.403 -279.749504)
			)
		)
		(stroke
			(width 0)
			(type solid)
		)
		(fill yes)
		(layer "In10.Cu")
		(net "P5E_PEX0_STN2_TX_DN<42>")
	)
	(gr_poly
		(pts
			(arc
				(start 50.35296 -313.949842)
				(mid 49.94656 -313.949842)
				(end 50.35296 -313.949842)
			)
		)
		(stroke
			(width 0)
			(type solid)
		)
		(fill yes)
		(layer "In10.Cu")
		(net "P5E_PEX0_STN6_TX_DN<104>")
	)
	(gr_poly
		(pts
			(arc
				(start 50.35296 -312.999882)
				(mid 49.94656 -312.999882)
				(end 50.35296 -312.999882)
			)
		)
		(stroke
			(width 0)
			(type solid)
		)
		(fill yes)
		(layer "In10.Cu")
		(net "P5E_PEX0_STN6_TX_DP<104>")
	)
	(gr_poly
		(pts
			(arc
				(start 50.35296 -278.799798)
				(mid 49.94656 -278.799798)
				(end 50.35296 -278.799798)
			)
		)
		(stroke
			(width 0)
			(type solid)
		)
		(fill yes)
		(layer "In10.Cu")
		(net "P5E_PEX0_STN2_TX_DP<41>")
	)
	(gr_poly
		(pts
			(arc
				(start 50.35296 -277.849838)
				(mid 49.94656 -277.849838)
				(end 50.35296 -277.849838)
			)
		)
		(stroke
			(width 0)
			(type solid)
		)
		(fill yes)
		(layer "In10.Cu")
		(net "P5E_PEX0_STN2_TX_DN<41>")
	)
	(gr_poly
		(pts
			(arc
				(start 51.303174 -312.049922)
				(mid 50.896774 -312.049922)
				(end 51.303174 -312.049922)
			)
		)
		(stroke
			(width 0)
			(type solid)
		)
		(fill yes)
		(layer "In10.Cu")
		(net "P5E_PEX0_STN6_TX_DN<103>")
	)
	(gr_poly
		(pts
			(arc
				(start 51.303174 -311.099962)
				(mid 50.896774 -311.099962)
				(end 51.303174 -311.099962)
			)
		)
		(stroke
			(width 0)
			(type solid)
		)
		(fill yes)
		(layer "In10.Cu")
		(net "P5E_PEX0_STN6_TX_DP<103>")
	)
	(gr_poly
		(pts
			(arc
				(start 51.303174 -280.699718)
				(mid 50.896774 -280.699718)
				(end 51.303174 -280.699718)
			)
		)
		(stroke
			(width 0)
			(type solid)
		)
		(fill yes)
		(layer "In10.Cu")
		(net "P5E_PEX0_STN2_TX_DP<40>")
	)
	(gr_poly
		(pts
			(arc
				(start 51.303174 -279.749504)
				(mid 50.896774 -279.749504)
				(end 51.303174 -279.749504)
			)
		)
		(stroke
			(width 0)
			(type solid)
		)
		(fill yes)
		(layer "In10.Cu")
		(net "P5E_PEX0_STN2_TX_DN<40>")
	)
	(gr_poly
		(pts
			(arc
				(start 52.253134 -313.949842)
				(mid 51.846734 -313.949842)
				(end 52.253134 -313.949842)
			)
		)
		(stroke
			(width 0)
			(type solid)
		)
		(fill yes)
		(layer "In10.Cu")
		(net "P5E_PEX0_STN6_TX_DN<102>")
	)
	(gr_poly
		(pts
			(arc
				(start 52.253134 -312.999882)
				(mid 51.846734 -312.999882)
				(end 52.253134 -312.999882)
			)
		)
		(stroke
			(width 0)
			(type solid)
		)
		(fill yes)
		(layer "In10.Cu")
		(net "P5E_PEX0_STN6_TX_DP<102>")
	)
	(gr_poly
		(pts
			(arc
				(start 52.253134 -278.799798)
				(mid 51.846734 -278.799798)
				(end 52.253134 -278.799798)
			)
		)
		(stroke
			(width 0)
			(type solid)
		)
		(fill yes)
		(layer "In10.Cu")
		(net "P5E_PEX0_STN2_TX_DP<39>")
	)
	(gr_poly
		(pts
			(arc
				(start 52.253134 -277.849838)
				(mid 51.846734 -277.849838)
				(end 52.253134 -277.849838)
			)
		)
		(stroke
			(width 0)
			(type solid)
		)
		(fill yes)
		(layer "In10.Cu")
		(net "P5E_PEX0_STN2_TX_DN<39>")
	)
	(gr_poly
		(pts
			(arc
				(start 53.203094 -312.049922)
				(mid 52.796694 -312.049922)
				(end 53.203094 -312.049922)
			)
		)
		(stroke
			(width 0)
			(type solid)
		)
		(fill yes)
		(layer "In10.Cu")
		(net "P5E_PEX0_STN6_TX_DN<101>")
	)
	(gr_poly
		(pts
			(arc
				(start 53.203094 -311.099962)
				(mid 52.796694 -311.099962)
				(end 53.203094 -311.099962)
			)
		)
		(stroke
			(width 0)
			(type solid)
		)
		(fill yes)
		(layer "In10.Cu")
		(net "P5E_PEX0_STN6_TX_DP<101>")
	)
	(gr_poly
		(pts
			(arc
				(start 53.203094 -280.699718)
				(mid 52.796694 -280.699718)
				(end 53.203094 -280.699718)
			)
		)
		(stroke
			(width 0)
			(type solid)
		)
		(fill yes)
		(layer "In10.Cu")
		(net "P5E_PEX0_STN2_TX_DP<38>")
	)
	(gr_poly
		(pts
			(arc
				(start 53.203094 -279.749504)
				(mid 52.796694 -279.749504)
				(end 53.203094 -279.749504)
			)
		)
		(stroke
			(width 0)
			(type solid)
		)
		(fill yes)
		(layer "In10.Cu")
		(net "P5E_PEX0_STN2_TX_DN<38>")
	)
	(gr_poly
		(pts
			(arc
				(start 54.153054 -313.949842)
				(mid 53.746654 -313.949842)
				(end 54.153054 -313.949842)
			)
		)
		(stroke
			(width 0)
			(type solid)
		)
		(fill yes)
		(layer "In10.Cu")
		(net "P5E_PEX0_STN6_TX_DN<100>")
	)
	(gr_poly
		(pts
			(arc
				(start 54.153054 -312.999882)
				(mid 53.746654 -312.999882)
				(end 54.153054 -312.999882)
			)
		)
		(stroke
			(width 0)
			(type solid)
		)
		(fill yes)
		(layer "In10.Cu")
		(net "P5E_PEX0_STN6_TX_DP<100>")
	)
	(gr_poly
		(pts
			(arc
				(start 54.153054 -278.799798)
				(mid 53.746654 -278.799798)
				(end 54.153054 -278.799798)
			)
		)
		(stroke
			(width 0)
			(type solid)
		)
		(fill yes)
		(layer "In10.Cu")
		(net "P5E_PEX0_STN2_TX_DP<37>")
	)
	(gr_poly
		(pts
			(arc
				(start 54.153054 -277.849838)
				(mid 53.746654 -277.849838)
				(end 54.153054 -277.849838)
			)
		)
		(stroke
			(width 0)
			(type solid)
		)
		(fill yes)
		(layer "In10.Cu")
		(net "P5E_PEX0_STN2_TX_DN<37>")
	)
	(gr_poly
		(pts
			(arc
				(start 55.103014 -312.049922)
				(mid 54.696614 -312.049922)
				(end 55.103014 -312.049922)
			)
		)
		(stroke
			(width 0)
			(type solid)
		)
		(fill yes)
		(layer "In10.Cu")
		(net "P5E_PEX0_STN6_TX_DN<99>")
	)
	(gr_poly
		(pts
			(arc
				(start 55.103014 -311.099962)
				(mid 54.696614 -311.099962)
				(end 55.103014 -311.099962)
			)
		)
		(stroke
			(width 0)
			(type solid)
		)
		(fill yes)
		(layer "In10.Cu")
		(net "P5E_PEX0_STN6_TX_DP<99>")
	)
	(gr_poly
		(pts
			(arc
				(start 55.103014 -280.699718)
				(mid 54.696614 -280.699718)
				(end 55.103014 -280.699718)
			)
		)
		(stroke
			(width 0)
			(type solid)
		)
		(fill yes)
		(layer "In10.Cu")
		(net "P5E_PEX0_STN2_TX_DP<36>")
	)
	(gr_poly
		(pts
			(arc
				(start 55.103014 -279.749504)
				(mid 54.696614 -279.749504)
				(end 55.103014 -279.749504)
			)
		)
		(stroke
			(width 0)
			(type solid)
		)
		(fill yes)
		(layer "In10.Cu")
		(net "P5E_PEX0_STN2_TX_DN<36>")
	)
	(gr_poly
		(pts
			(arc
				(start 56.052974 -313.949842)
				(mid 55.646574 -313.949842)
				(end 56.052974 -313.949842)
			)
		)
		(stroke
			(width 0)
			(type solid)
		)
		(fill yes)
		(layer "In10.Cu")
		(net "P5E_PEX0_STN6_TX_DN<98>")
	)
	(gr_poly
		(pts
			(arc
				(start 56.052974 -312.999882)
				(mid 55.646574 -312.999882)
				(end 56.052974 -312.999882)
			)
		)
		(stroke
			(width 0)
			(type solid)
		)
		(fill yes)
		(layer "In10.Cu")
		(net "P5E_PEX0_STN6_TX_DP<98>")
	)
	(gr_poly
		(pts
			(arc
				(start 56.052974 -278.799798)
				(mid 55.646574 -278.799798)
				(end 56.052974 -278.799798)
			)
		)
		(stroke
			(width 0)
			(type solid)
		)
		(fill yes)
		(layer "In10.Cu")
		(net "P5E_PEX0_STN2_TX_DP<35>")
	)
	(gr_poly
		(pts
			(arc
				(start 56.052974 -277.849838)
				(mid 55.646574 -277.849838)
				(end 56.052974 -277.849838)
			)
		)
		(stroke
			(width 0)
			(type solid)
		)
		(fill yes)
		(layer "In10.Cu")
		(net "P5E_PEX0_STN2_TX_DN<35>")
	)
	(gr_poly
		(pts
			(arc
				(start 57.002934 -280.699718)
				(mid 56.596534 -280.699718)
				(end 57.002934 -280.699718)
			)
		)
		(stroke
			(width 0)
			(type solid)
		)
		(fill yes)
		(layer "In10.Cu")
		(net "P5E_PEX0_STN2_TX_DP<34>")
	)
	(gr_poly
		(pts
			(arc
				(start 57.002934 -279.749504)
				(mid 56.596534 -279.749504)
				(end 57.002934 -279.749504)
			)
		)
		(stroke
			(width 0)
			(type solid)
		)
		(fill yes)
		(layer "In10.Cu")
		(net "P5E_PEX0_STN2_TX_DN<34>")
	)
	(gr_poly
		(pts
			(arc
				(start 57.003188 -312.049922)
				(mid 56.596788 -312.049922)
				(end 57.003188 -312.049922)
			)
		)
		(stroke
			(width 0)
			(type solid)
		)
		(fill yes)
		(layer "In10.Cu")
		(net "P5E_PEX0_STN6_TX_DN<97>")
	)
	(gr_poly
		(pts
			(arc
				(start 57.003188 -311.099962)
				(mid 56.596788 -311.099962)
				(end 57.003188 -311.099962)
			)
		)
		(stroke
			(width 0)
			(type solid)
		)
		(fill yes)
		(layer "In10.Cu")
		(net "P5E_PEX0_STN6_TX_DP<97>")
	)
	(gr_poly
		(pts
			(arc
				(start 57.953148 -313.949842)
				(mid 57.546748 -313.949842)
				(end 57.953148 -313.949842)
			)
		)
		(stroke
			(width 0)
			(type solid)
		)
		(fill yes)
		(layer "In10.Cu")
		(net "P5E_PEX0_STN6_TX_DN<96>")
	)
	(gr_poly
		(pts
			(arc
				(start 57.953148 -312.999882)
				(mid 57.546748 -312.999882)
				(end 57.953148 -312.999882)
			)
		)
		(stroke
			(width 0)
			(type solid)
		)
		(fill yes)
		(layer "In10.Cu")
		(net "P5E_PEX0_STN6_TX_DP<96>")
	)
	(gr_poly
		(pts
			(arc
				(start 57.953148 -278.799798)
				(mid 57.546748 -278.799798)
				(end 57.953148 -278.799798)
			)
		)
		(stroke
			(width 0)
			(type solid)
		)
		(fill yes)
		(layer "In10.Cu")
		(net "P5E_PEX0_STN2_TX_DP<33>")
	)
	(gr_poly
		(pts
			(arc
				(start 57.953148 -277.849838)
				(mid 57.546748 -277.849838)
				(end 57.953148 -277.849838)
			)
		)
		(stroke
			(width 0)
			(type solid)
		)
		(fill yes)
		(layer "In10.Cu")
		(net "P5E_PEX0_STN2_TX_DN<33>")
	)
	(gr_poly
		(pts
			(arc
				(start 58.903108 -280.699718)
				(mid 58.496708 -280.699718)
				(end 58.903108 -280.699718)
			)
		)
		(stroke
			(width 0)
			(type solid)
		)
		(fill yes)
		(layer "In10.Cu")
		(net "P5E_PEX0_STN2_TX_DP<32>")
	)
	(gr_poly
		(pts
			(arc
				(start 58.903108 -279.749504)
				(mid 58.496708 -279.749504)
				(end 58.903108 -279.749504)
			)
		)
		(stroke
			(width 0)
			(type solid)
		)
		(fill yes)
		(layer "In10.Cu")
		(net "P5E_PEX0_STN2_TX_DN<32>")
	)
	(gr_poly
		(pts
			(arc
				(start 74.102976 -316.799722)
				(mid 73.696576 -316.799722)
				(end 74.102976 -316.799722)
			)
		)
		(stroke
			(width 0)
			(type solid)
		)
		(fill yes)
		(layer "In10.Cu")
		(net "P5E_PEX0_STN4_RX_DN<79>")
	)
	(gr_poly
		(pts
			(arc
				(start 74.102976 -315.849762)
				(mid 73.696576 -315.849762)
				(end 74.102976 -315.849762)
			)
		)
		(stroke
			(width 0)
			(type solid)
		)
		(fill yes)
		(layer "In10.Cu")
		(net "P5E_PEX0_STN4_RX_DP<79>")
	)
	(gr_poly
		(pts
			(arc
				(start 74.102976 -312.049922)
				(mid 73.696576 -312.049922)
				(end 74.102976 -312.049922)
			)
		)
		(stroke
			(width 0)
			(type solid)
		)
		(fill yes)
		(layer "In10.Cu")
		(net "P5E_PEX0_STN4_TX_DN<79>")
	)
	(gr_poly
		(pts
			(arc
				(start 74.102976 -311.099962)
				(mid 73.696576 -311.099962)
				(end 74.102976 -311.099962)
			)
		)
		(stroke
			(width 0)
			(type solid)
		)
		(fill yes)
		(layer "In10.Cu")
		(net "P5E_PEX0_STN4_TX_DP<79>")
	)
	(gr_poly
		(pts
			(arc
				(start 75.05319 -318.699896)
				(mid 74.64679 -318.699896)
				(end 75.05319 -318.699896)
			)
		)
		(stroke
			(width 0)
			(type solid)
		)
		(fill yes)
		(layer "In10.Cu")
		(net "P5E_PEX0_STN4_RX_DN<78>")
	)
	(gr_poly
		(pts
			(arc
				(start 75.05319 -317.749936)
				(mid 74.64679 -317.749936)
				(end 75.05319 -317.749936)
			)
		)
		(stroke
			(width 0)
			(type solid)
		)
		(fill yes)
		(layer "In10.Cu")
		(net "P5E_PEX0_STN4_RX_DP<78>")
	)
	(gr_poly
		(pts
			(arc
				(start 75.05319 -313.949842)
				(mid 74.64679 -313.949842)
				(end 75.05319 -313.949842)
			)
		)
		(stroke
			(width 0)
			(type solid)
		)
		(fill yes)
		(layer "In10.Cu")
		(net "P5E_PEX0_STN4_TX_DN<78>")
	)
	(gr_poly
		(pts
			(arc
				(start 75.05319 -312.999882)
				(mid 74.64679 -312.999882)
				(end 75.05319 -312.999882)
			)
		)
		(stroke
			(width 0)
			(type solid)
		)
		(fill yes)
		(layer "In10.Cu")
		(net "P5E_PEX0_STN4_TX_DP<78>")
	)
	(gr_poly
		(pts
			(arc
				(start 75.05319 -308.249828)
				(mid 74.64679 -308.249828)
				(end 75.05319 -308.249828)
			)
		)
		(stroke
			(width 0)
			(type solid)
		)
		(fill yes)
		(layer "In10.Cu")
		(net "P5E_PEX0_STN4_TX_DP<68>")
	)
	(gr_poly
		(pts
			(arc
				(start 75.05319 -306.349908)
				(mid 74.64679 -306.349908)
				(end 75.05319 -306.349908)
			)
		)
		(stroke
			(width 0)
			(type solid)
		)
		(fill yes)
		(layer "In10.Cu")
		(net "P5E_PEX0_STN4_TX_DP<66>")
	)
	(gr_poly
		(pts
			(arc
				(start 75.05319 -304.449734)
				(mid 74.64679 -304.449734)
				(end 75.05319 -304.449734)
			)
		)
		(stroke
			(width 0)
			(type solid)
		)
		(fill yes)
		(layer "In10.Cu")
		(net "P5E_PEX0_STN4_TX_DP<64>")
	)
	(gr_poly
		(pts
			(arc
				(start 76.00315 -316.799722)
				(mid 75.59675 -316.799722)
				(end 76.00315 -316.799722)
			)
		)
		(stroke
			(width 0)
			(type solid)
		)
		(fill yes)
		(layer "In10.Cu")
		(net "P5E_PEX0_STN4_RX_DN<77>")
	)
	(gr_poly
		(pts
			(arc
				(start 76.00315 -315.849762)
				(mid 75.59675 -315.849762)
				(end 76.00315 -315.849762)
			)
		)
		(stroke
			(width 0)
			(type solid)
		)
		(fill yes)
		(layer "In10.Cu")
		(net "P5E_PEX0_STN4_RX_DP<77>")
	)
	(gr_poly
		(pts
			(arc
				(start 76.00315 -312.049922)
				(mid 75.59675 -312.049922)
				(end 76.00315 -312.049922)
			)
		)
		(stroke
			(width 0)
			(type solid)
		)
		(fill yes)
		(layer "In10.Cu")
		(net "P5E_PEX0_STN4_TX_DN<77>")
	)
	(gr_poly
		(pts
			(arc
				(start 76.00315 -311.099962)
				(mid 75.59675 -311.099962)
				(end 76.00315 -311.099962)
			)
		)
		(stroke
			(width 0)
			(type solid)
		)
		(fill yes)
		(layer "In10.Cu")
		(net "P5E_PEX0_STN4_TX_DP<77>")
	)
	(gr_poly
		(pts
			(arc
				(start 76.00315 -308.249828)
				(mid 75.59675 -308.249828)
				(end 76.00315 -308.249828)
			)
		)
		(stroke
			(width 0)
			(type solid)
		)
		(fill yes)
		(layer "In10.Cu")
		(net "P5E_PEX0_STN4_TX_DN<68>")
	)
	(gr_poly
		(pts
			(arc
				(start 76.00315 -306.349908)
				(mid 75.59675 -306.349908)
				(end 76.00315 -306.349908)
			)
		)
		(stroke
			(width 0)
			(type solid)
		)
		(fill yes)
		(layer "In10.Cu")
		(net "P5E_PEX0_STN4_TX_DN<66>")
	)
	(gr_poly
		(pts
			(arc
				(start 76.00315 -304.449734)
				(mid 75.59675 -304.449734)
				(end 76.00315 -304.449734)
			)
		)
		(stroke
			(width 0)
			(type solid)
		)
		(fill yes)
		(layer "In10.Cu")
		(net "P5E_PEX0_STN4_TX_DN<64>")
	)
	(gr_poly
		(pts
			(arc
				(start 76.95311 -318.699896)
				(mid 76.54671 -318.699896)
				(end 76.95311 -318.699896)
			)
		)
		(stroke
			(width 0)
			(type solid)
		)
		(fill yes)
		(layer "In10.Cu")
		(net "P5E_PEX0_STN4_RX_DN<76>")
	)
	(gr_poly
		(pts
			(arc
				(start 76.95311 -317.749936)
				(mid 76.54671 -317.749936)
				(end 76.95311 -317.749936)
			)
		)
		(stroke
			(width 0)
			(type solid)
		)
		(fill yes)
		(layer "In10.Cu")
		(net "P5E_PEX0_STN4_RX_DP<76>")
	)
	(gr_poly
		(pts
			(arc
				(start 76.95311 -313.949842)
				(mid 76.54671 -313.949842)
				(end 76.95311 -313.949842)
			)
		)
		(stroke
			(width 0)
			(type solid)
		)
		(fill yes)
		(layer "In10.Cu")
		(net "P5E_PEX0_STN4_TX_DN<76>")
	)
	(gr_poly
		(pts
			(arc
				(start 76.95311 -312.999882)
				(mid 76.54671 -312.999882)
				(end 76.95311 -312.999882)
			)
		)
		(stroke
			(width 0)
			(type solid)
		)
		(fill yes)
		(layer "In10.Cu")
		(net "P5E_PEX0_STN4_TX_DP<76>")
	)
	(gr_poly
		(pts
			(arc
				(start 76.95311 -309.199788)
				(mid 76.54671 -309.199788)
				(end 76.95311 -309.199788)
			)
		)
		(stroke
			(width 0)
			(type solid)
		)
		(fill yes)
		(layer "In10.Cu")
		(net "P5E_PEX0_STN4_TX_DP<69>")
	)
	(gr_poly
		(pts
			(arc
				(start 76.95311 -307.299868)
				(mid 76.54671 -307.299868)
				(end 76.95311 -307.299868)
			)
		)
		(stroke
			(width 0)
			(type solid)
		)
		(fill yes)
		(layer "In10.Cu")
		(net "P5E_PEX0_STN4_TX_DP<67>")
	)
	(gr_poly
		(pts
			(arc
				(start 76.95311 -305.399948)
				(mid 76.54671 -305.399948)
				(end 76.95311 -305.399948)
			)
		)
		(stroke
			(width 0)
			(type solid)
		)
		(fill yes)
		(layer "In10.Cu")
		(net "P5E_PEX0_STN4_TX_DP<65>")
	)
	(gr_poly
		(pts
			(arc
				(start 77.90307 -316.799722)
				(mid 77.49667 -316.799722)
				(end 77.90307 -316.799722)
			)
		)
		(stroke
			(width 0)
			(type solid)
		)
		(fill yes)
		(layer "In10.Cu")
		(net "P5E_PEX0_STN4_RX_DN<75>")
	)
	(gr_poly
		(pts
			(arc
				(start 77.90307 -315.849762)
				(mid 77.49667 -315.849762)
				(end 77.90307 -315.849762)
			)
		)
		(stroke
			(width 0)
			(type solid)
		)
		(fill yes)
		(layer "In10.Cu")
		(net "P5E_PEX0_STN4_RX_DP<75>")
	)
	(gr_poly
		(pts
			(arc
				(start 77.90307 -312.049922)
				(mid 77.49667 -312.049922)
				(end 77.90307 -312.049922)
			)
		)
		(stroke
			(width 0)
			(type solid)
		)
		(fill yes)
		(layer "In10.Cu")
		(net "P5E_PEX0_STN4_TX_DN<75>")
	)
	(gr_poly
		(pts
			(arc
				(start 77.90307 -311.099962)
				(mid 77.49667 -311.099962)
				(end 77.90307 -311.099962)
			)
		)
		(stroke
			(width 0)
			(type solid)
		)
		(fill yes)
		(layer "In10.Cu")
		(net "P5E_PEX0_STN4_TX_DP<75>")
	)
	(gr_poly
		(pts
			(arc
				(start 77.90307 -309.199788)
				(mid 77.49667 -309.199788)
				(end 77.90307 -309.199788)
			)
		)
		(stroke
			(width 0)
			(type solid)
		)
		(fill yes)
		(layer "In10.Cu")
		(net "P5E_PEX0_STN4_TX_DN<69>")
	)
	(gr_poly
		(pts
			(arc
				(start 77.90307 -307.299868)
				(mid 77.49667 -307.299868)
				(end 77.90307 -307.299868)
			)
		)
		(stroke
			(width 0)
			(type solid)
		)
		(fill yes)
		(layer "In10.Cu")
		(net "P5E_PEX0_STN4_TX_DN<67>")
	)
	(gr_poly
		(pts
			(arc
				(start 77.90307 -305.399948)
				(mid 77.49667 -305.399948)
				(end 77.90307 -305.399948)
			)
		)
		(stroke
			(width 0)
			(type solid)
		)
		(fill yes)
		(layer "In10.Cu")
		(net "P5E_PEX0_STN4_TX_DN<65>")
	)
	(gr_poly
		(pts
			(arc
				(start 78.85303 -318.699896)
				(mid 78.44663 -318.699896)
				(end 78.85303 -318.699896)
			)
		)
		(stroke
			(width 0)
			(type solid)
		)
		(fill yes)
		(layer "In10.Cu")
		(net "P5E_PEX0_STN4_RX_DN<74>")
	)
	(gr_poly
		(pts
			(arc
				(start 78.85303 -317.749936)
				(mid 78.44663 -317.749936)
				(end 78.85303 -317.749936)
			)
		)
		(stroke
			(width 0)
			(type solid)
		)
		(fill yes)
		(layer "In10.Cu")
		(net "P5E_PEX0_STN4_RX_DP<74>")
	)
	(gr_poly
		(pts
			(arc
				(start 78.85303 -313.949842)
				(mid 78.44663 -313.949842)
				(end 78.85303 -313.949842)
			)
		)
		(stroke
			(width 0)
			(type solid)
		)
		(fill yes)
		(layer "In10.Cu")
		(net "P5E_PEX0_STN4_TX_DN<74>")
	)
	(gr_poly
		(pts
			(arc
				(start 78.85303 -312.999882)
				(mid 78.44663 -312.999882)
				(end 78.85303 -312.999882)
			)
		)
		(stroke
			(width 0)
			(type solid)
		)
		(fill yes)
		(layer "In10.Cu")
		(net "P5E_PEX0_STN4_TX_DP<74>")
	)
	(gr_poly
		(pts
			(arc
				(start 79.80299 -316.799722)
				(mid 79.39659 -316.799722)
				(end 79.80299 -316.799722)
			)
		)
		(stroke
			(width 0)
			(type solid)
		)
		(fill yes)
		(layer "In10.Cu")
		(net "P5E_PEX0_STN4_RX_DN<73>")
	)
	(gr_poly
		(pts
			(arc
				(start 79.80299 -315.849762)
				(mid 79.39659 -315.849762)
				(end 79.80299 -315.849762)
			)
		)
		(stroke
			(width 0)
			(type solid)
		)
		(fill yes)
		(layer "In10.Cu")
		(net "P5E_PEX0_STN4_RX_DP<73>")
	)
	(gr_poly
		(pts
			(arc
				(start 79.80299 -312.049922)
				(mid 79.39659 -312.049922)
				(end 79.80299 -312.049922)
			)
		)
		(stroke
			(width 0)
			(type solid)
		)
		(fill yes)
		(layer "In10.Cu")
		(net "P5E_PEX0_STN4_TX_DN<73>")
	)
	(gr_poly
		(pts
			(arc
				(start 79.80299 -311.099962)
				(mid 79.39659 -311.099962)
				(end 79.80299 -311.099962)
			)
		)
		(stroke
			(width 0)
			(type solid)
		)
		(fill yes)
		(layer "In10.Cu")
		(net "P5E_PEX0_STN4_TX_DP<73>")
	)
	(gr_poly
		(pts
			(arc
				(start 79.80299 -309.199788)
				(mid 79.39659 -309.199788)
				(end 79.80299 -309.199788)
			)
		)
		(stroke
			(width 0)
			(type solid)
		)
		(fill yes)
		(layer "In10.Cu")
		(net "P5E_PEX0_STN4_RX_DP<69>")
	)
	(gr_poly
		(pts
			(arc
				(start 79.80299 -307.299868)
				(mid 79.39659 -307.299868)
				(end 79.80299 -307.299868)
			)
		)
		(stroke
			(width 0)
			(type solid)
		)
		(fill yes)
		(layer "In10.Cu")
		(net "P5E_PEX0_STN4_RX_DP<67>")
	)
	(gr_poly
		(pts
			(arc
				(start 79.80299 -305.399948)
				(mid 79.39659 -305.399948)
				(end 79.80299 -305.399948)
			)
		)
		(stroke
			(width 0)
			(type solid)
		)
		(fill yes)
		(layer "In10.Cu")
		(net "P5E_PEX0_STN4_RX_DP<65>")
	)
	(gr_poly
		(pts
			(arc
				(start 80.75295 -318.699896)
				(mid 80.34655 -318.699896)
				(end 80.75295 -318.699896)
			)
		)
		(stroke
			(width 0)
			(type solid)
		)
		(fill yes)
		(layer "In10.Cu")
		(net "P5E_PEX0_STN4_RX_DN<72>")
	)
	(gr_poly
		(pts
			(arc
				(start 80.75295 -317.749936)
				(mid 80.34655 -317.749936)
				(end 80.75295 -317.749936)
			)
		)
		(stroke
			(width 0)
			(type solid)
		)
		(fill yes)
		(layer "In10.Cu")
		(net "P5E_PEX0_STN4_RX_DP<72>")
	)
	(gr_poly
		(pts
			(arc
				(start 80.75295 -313.949842)
				(mid 80.34655 -313.949842)
				(end 80.75295 -313.949842)
			)
		)
		(stroke
			(width 0)
			(type solid)
		)
		(fill yes)
		(layer "In10.Cu")
		(net "P5E_PEX0_STN4_TX_DN<72>")
	)
	(gr_poly
		(pts
			(arc
				(start 80.75295 -312.999882)
				(mid 80.34655 -312.999882)
				(end 80.75295 -312.999882)
			)
		)
		(stroke
			(width 0)
			(type solid)
		)
		(fill yes)
		(layer "In10.Cu")
		(net "P5E_PEX0_STN4_TX_DP<72>")
	)
	(gr_poly
		(pts
			(arc
				(start 80.75295 -309.199788)
				(mid 80.34655 -309.199788)
				(end 80.75295 -309.199788)
			)
		)
		(stroke
			(width 0)
			(type solid)
		)
		(fill yes)
		(layer "In10.Cu")
		(net "P5E_PEX0_STN4_RX_DN<69>")
	)
	(gr_poly
		(pts
			(arc
				(start 80.75295 -307.299868)
				(mid 80.34655 -307.299868)
				(end 80.75295 -307.299868)
			)
		)
		(stroke
			(width 0)
			(type solid)
		)
		(fill yes)
		(layer "In10.Cu")
		(net "P5E_PEX0_STN4_RX_DN<67>")
	)
	(gr_poly
		(pts
			(arc
				(start 80.75295 -305.399948)
				(mid 80.34655 -305.399948)
				(end 80.75295 -305.399948)
			)
		)
		(stroke
			(width 0)
			(type solid)
		)
		(fill yes)
		(layer "In10.Cu")
		(net "P5E_PEX0_STN4_RX_DN<65>")
	)
	(gr_poly
		(pts
			(arc
				(start 81.703164 -316.799722)
				(mid 81.296764 -316.799722)
				(end 81.703164 -316.799722)
			)
		)
		(stroke
			(width 0)
			(type solid)
		)
		(fill yes)
		(layer "In10.Cu")
		(net "P5E_PEX0_STN4_RX_DP<71>")
	)
	(gr_poly
		(pts
			(arc
				(start 81.703164 -314.899802)
				(mid 81.296764 -314.899802)
				(end 81.703164 -314.899802)
			)
		)
		(stroke
			(width 0)
			(type solid)
		)
		(fill yes)
		(layer "In10.Cu")
		(net "P5E_PEX0_STN4_TX_DP<71>")
	)
	(gr_poly
		(pts
			(arc
				(start 81.703164 -312.049922)
				(mid 81.296764 -312.049922)
				(end 81.703164 -312.049922)
			)
		)
		(stroke
			(width 0)
			(type solid)
		)
		(fill yes)
		(layer "In10.Cu")
		(net "P5E_PEX0_STN4_TX_DP<70>")
	)
	(gr_poly
		(pts
			(arc
				(start 81.703164 -310.149748)
				(mid 81.296764 -310.149748)
				(end 81.703164 -310.149748)
			)
		)
		(stroke
			(width 0)
			(type solid)
		)
		(fill yes)
		(layer "In10.Cu")
		(net "P5E_PEX0_STN4_RX_DP<70>")
	)
	(gr_poly
		(pts
			(arc
				(start 81.703164 -308.249828)
				(mid 81.296764 -308.249828)
				(end 81.703164 -308.249828)
			)
		)
		(stroke
			(width 0)
			(type solid)
		)
		(fill yes)
		(layer "In10.Cu")
		(net "P5E_PEX0_STN4_RX_DP<68>")
	)
	(gr_poly
		(pts
			(arc
				(start 81.703164 -306.349908)
				(mid 81.296764 -306.349908)
				(end 81.703164 -306.349908)
			)
		)
		(stroke
			(width 0)
			(type solid)
		)
		(fill yes)
		(layer "In10.Cu")
		(net "P5E_PEX0_STN4_RX_DP<66>")
	)
	(gr_poly
		(pts
			(arc
				(start 81.703164 -304.449734)
				(mid 81.296764 -304.449734)
				(end 81.703164 -304.449734)
			)
		)
		(stroke
			(width 0)
			(type solid)
		)
		(fill yes)
		(layer "In10.Cu")
		(net "P5E_PEX0_STN4_RX_DP<64>")
	)
	(gr_poly
		(pts
			(arc
				(start 82.653124 -316.799722)
				(mid 82.246724 -316.799722)
				(end 82.653124 -316.799722)
			)
		)
		(stroke
			(width 0)
			(type solid)
		)
		(fill yes)
		(layer "In10.Cu")
		(net "P5E_PEX0_STN4_RX_DN<71>")
	)
	(gr_poly
		(pts
			(arc
				(start 82.653124 -314.899802)
				(mid 82.246724 -314.899802)
				(end 82.653124 -314.899802)
			)
		)
		(stroke
			(width 0)
			(type solid)
		)
		(fill yes)
		(layer "In10.Cu")
		(net "P5E_PEX0_STN4_TX_DN<71>")
	)
	(gr_poly
		(pts
			(arc
				(start 82.653124 -312.049922)
				(mid 82.246724 -312.049922)
				(end 82.653124 -312.049922)
			)
		)
		(stroke
			(width 0)
			(type solid)
		)
		(fill yes)
		(layer "In10.Cu")
		(net "P5E_PEX0_STN4_TX_DN<70>")
	)
	(gr_poly
		(pts
			(arc
				(start 82.653124 -310.149748)
				(mid 82.246724 -310.149748)
				(end 82.653124 -310.149748)
			)
		)
		(stroke
			(width 0)
			(type solid)
		)
		(fill yes)
		(layer "In10.Cu")
		(net "P5E_PEX0_STN4_RX_DN<70>")
	)
	(gr_poly
		(pts
			(arc
				(start 82.653124 -308.249828)
				(mid 82.246724 -308.249828)
				(end 82.653124 -308.249828)
			)
		)
		(stroke
			(width 0)
			(type solid)
		)
		(fill yes)
		(layer "In10.Cu")
		(net "P5E_PEX0_STN4_RX_DN<68>")
	)
	(gr_poly
		(pts
			(arc
				(start 82.653124 -306.349908)
				(mid 82.246724 -306.349908)
				(end 82.653124 -306.349908)
			)
		)
		(stroke
			(width 0)
			(type solid)
		)
		(fill yes)
		(layer "In10.Cu")
		(net "P5E_PEX0_STN4_RX_DN<66>")
	)
	(gr_poly
		(pts
			(arc
				(start 82.653124 -304.449734)
				(mid 82.246724 -304.449734)
				(end 82.653124 -304.449734)
			)
		)
		(stroke
			(width 0)
			(type solid)
		)
		(fill yes)
		(layer "In10.Cu")
		(net "P5E_PEX0_STN4_RX_DN<64>")
	)
	(gr_poly
		(pts
			(arc
				(start 153.15311 -314.899802)
				(mid 152.74671 -314.899802)
				(end 153.15311 -314.899802)
			)
		)
		(stroke
			(width 0)
			(type solid)
		)
		(fill yes)
		(layer "In10.Cu")
		(net "P5E_PEX1_STN7_TX_DN<122>")
	)
	(gr_poly
		(pts
			(arc
				(start 153.15311 -312.049922)
				(mid 152.74671 -312.049922)
				(end 153.15311 -312.049922)
			)
		)
		(stroke
			(width 0)
			(type solid)
		)
		(fill yes)
		(layer "In10.Cu")
		(net "P5E_PEX1_STN7_TX_DN<121>")
	)
	(gr_poly
		(pts
			(arc
				(start 154.10307 -314.899802)
				(mid 153.69667 -314.899802)
				(end 154.10307 -314.899802)
			)
		)
		(stroke
			(width 0)
			(type solid)
		)
		(fill yes)
		(layer "In10.Cu")
		(net "P5E_PEX1_STN7_TX_DP<122>")
	)
	(gr_poly
		(pts
			(arc
				(start 154.10307 -312.049922)
				(mid 153.69667 -312.049922)
				(end 154.10307 -312.049922)
			)
		)
		(stroke
			(width 0)
			(type solid)
		)
		(fill yes)
		(layer "In10.Cu")
		(net "P5E_PEX1_STN7_TX_DP<121>")
	)
	(gr_poly
		(pts
			(arc
				(start 155.053284 -313.949842)
				(mid 154.646884 -313.949842)
				(end 155.053284 -313.949842)
			)
		)
		(stroke
			(width 0)
			(type solid)
		)
		(fill yes)
		(layer "In10.Cu")
		(net "P5E_PEX1_STN7_TX_DN<123>")
	)
	(gr_poly
		(pts
			(arc
				(start 155.053284 -312.999882)
				(mid 154.646884 -312.999882)
				(end 155.053284 -312.999882)
			)
		)
		(stroke
			(width 0)
			(type solid)
		)
		(fill yes)
		(layer "In10.Cu")
		(net "P5E_PEX1_STN7_TX_DP<123>")
	)
	(gr_poly
		(pts
			(arc
				(start 156.003244 -312.049922)
				(mid 155.596844 -312.049922)
				(end 156.003244 -312.049922)
			)
		)
		(stroke
			(width 0)
			(type solid)
		)
		(fill yes)
		(layer "In10.Cu")
		(net "P5E_PEX1_STN7_TX_DN<124>")
	)
	(gr_poly
		(pts
			(arc
				(start 156.003244 -311.099962)
				(mid 155.596844 -311.099962)
				(end 156.003244 -311.099962)
			)
		)
		(stroke
			(width 0)
			(type solid)
		)
		(fill yes)
		(layer "In10.Cu")
		(net "P5E_PEX1_STN7_TX_DP<124>")
	)
	(gr_poly
		(pts
			(arc
				(start 156.953204 -313.949842)
				(mid 156.546804 -313.949842)
				(end 156.953204 -313.949842)
			)
		)
		(stroke
			(width 0)
			(type solid)
		)
		(fill yes)
		(layer "In10.Cu")
		(net "P5E_PEX1_STN7_TX_DN<125>")
	)
	(gr_poly
		(pts
			(arc
				(start 156.953204 -312.999882)
				(mid 156.546804 -312.999882)
				(end 156.953204 -312.999882)
			)
		)
		(stroke
			(width 0)
			(type solid)
		)
		(fill yes)
		(layer "In10.Cu")
		(net "P5E_PEX1_STN7_TX_DP<125>")
	)
	(gr_poly
		(pts
			(arc
				(start 157.903164 -312.049922)
				(mid 157.496764 -312.049922)
				(end 157.903164 -312.049922)
			)
		)
		(stroke
			(width 0)
			(type solid)
		)
		(fill yes)
		(layer "In10.Cu")
		(net "P5E_PEX1_STN7_TX_DN<126>")
	)
	(gr_poly
		(pts
			(arc
				(start 157.903164 -311.099962)
				(mid 157.496764 -311.099962)
				(end 157.903164 -311.099962)
			)
		)
		(stroke
			(width 0)
			(type solid)
		)
		(fill yes)
		(layer "In10.Cu")
		(net "P5E_PEX1_STN7_TX_DP<126>")
	)
	(gr_poly
		(pts
			(arc
				(start 157.903164 -309.199788)
				(mid 157.496764 -309.199788)
				(end 157.903164 -309.199788)
			)
		)
		(stroke
			(width 0)
			(type solid)
		)
		(fill yes)
		(layer "In10.Cu")
		(net "P5E_PEX1_STN7_TX_DN<120>")
	)
	(gr_poly
		(pts
			(arc
				(start 157.903164 -307.299868)
				(mid 157.496764 -307.299868)
				(end 157.903164 -307.299868)
			)
		)
		(stroke
			(width 0)
			(type solid)
		)
		(fill yes)
		(layer "In10.Cu")
		(net "P5E_PEX1_STN7_TX_DN<118>")
	)
	(gr_poly
		(pts
			(arc
				(start 157.903164 -305.399948)
				(mid 157.496764 -305.399948)
				(end 157.903164 -305.399948)
			)
		)
		(stroke
			(width 0)
			(type solid)
		)
		(fill yes)
		(layer "In10.Cu")
		(net "P5E_PEX1_STN7_TX_DN<116>")
	)
	(gr_poly
		(pts
			(arc
				(start 157.903164 -303.499774)
				(mid 157.496764 -303.499774)
				(end 157.903164 -303.499774)
			)
		)
		(stroke
			(width 0)
			(type solid)
		)
		(fill yes)
		(layer "In10.Cu")
		(net "P5E_PEX1_STN7_TX_DN<114>")
	)
	(gr_poly
		(pts
			(arc
				(start 157.903164 -301.599854)
				(mid 157.496764 -301.599854)
				(end 157.903164 -301.599854)
			)
		)
		(stroke
			(width 0)
			(type solid)
		)
		(fill yes)
		(layer "In10.Cu")
		(net "P5E_PEX1_STN7_TX_DN<112>")
	)
	(gr_poly
		(pts
			(arc
				(start 158.853124 -313.949842)
				(mid 158.446724 -313.949842)
				(end 158.853124 -313.949842)
			)
		)
		(stroke
			(width 0)
			(type solid)
		)
		(fill yes)
		(layer "In10.Cu")
		(net "P5E_PEX1_STN7_TX_DN<127>")
	)
	(gr_poly
		(pts
			(arc
				(start 158.853124 -312.999882)
				(mid 158.446724 -312.999882)
				(end 158.853124 -312.999882)
			)
		)
		(stroke
			(width 0)
			(type solid)
		)
		(fill yes)
		(layer "In10.Cu")
		(net "P5E_PEX1_STN7_TX_DP<127>")
	)
	(gr_poly
		(pts
			(arc
				(start 158.853124 -309.199788)
				(mid 158.446724 -309.199788)
				(end 158.853124 -309.199788)
			)
		)
		(stroke
			(width 0)
			(type solid)
		)
		(fill yes)
		(layer "In10.Cu")
		(net "P5E_PEX1_STN7_TX_DP<120>")
	)
	(gr_poly
		(pts
			(arc
				(start 158.853124 -307.299868)
				(mid 158.446724 -307.299868)
				(end 158.853124 -307.299868)
			)
		)
		(stroke
			(width 0)
			(type solid)
		)
		(fill yes)
		(layer "In10.Cu")
		(net "P5E_PEX1_STN7_TX_DP<118>")
	)
	(gr_poly
		(pts
			(arc
				(start 158.853124 -305.399948)
				(mid 158.446724 -305.399948)
				(end 158.853124 -305.399948)
			)
		)
		(stroke
			(width 0)
			(type solid)
		)
		(fill yes)
		(layer "In10.Cu")
		(net "P5E_PEX1_STN7_TX_DP<116>")
	)
	(gr_poly
		(pts
			(arc
				(start 158.853124 -303.499774)
				(mid 158.446724 -303.499774)
				(end 158.853124 -303.499774)
			)
		)
		(stroke
			(width 0)
			(type solid)
		)
		(fill yes)
		(layer "In10.Cu")
		(net "P5E_PEX1_STN7_TX_DP<114>")
	)
	(gr_poly
		(pts
			(arc
				(start 158.853124 -301.599854)
				(mid 158.446724 -301.599854)
				(end 158.853124 -301.599854)
			)
		)
		(stroke
			(width 0)
			(type solid)
		)
		(fill yes)
		(layer "In10.Cu")
		(net "P5E_PEX1_STN7_TX_DP<112>")
	)
	(gr_poly
		(pts
			(arc
				(start 159.803084 -316.799722)
				(mid 159.396684 -316.799722)
				(end 159.803084 -316.799722)
			)
		)
		(stroke
			(width 0)
			(type solid)
		)
		(fill yes)
		(layer "In10.Cu")
		(net "P5E_PEX1_STN6_RX_DN<111>")
	)
	(gr_poly
		(pts
			(arc
				(start 159.803084 -315.849762)
				(mid 159.396684 -315.849762)
				(end 159.803084 -315.849762)
			)
		)
		(stroke
			(width 0)
			(type solid)
		)
		(fill yes)
		(layer "In10.Cu")
		(net "P5E_PEX1_STN6_RX_DP<111>")
	)
	(gr_poly
		(pts
			(arc
				(start 159.803084 -312.049922)
				(mid 159.396684 -312.049922)
				(end 159.803084 -312.049922)
			)
		)
		(stroke
			(width 0)
			(type solid)
		)
		(fill yes)
		(layer "In10.Cu")
		(net "P5E_PEX1_STN6_TX_DN<111>")
	)
	(gr_poly
		(pts
			(arc
				(start 159.803084 -311.099962)
				(mid 159.396684 -311.099962)
				(end 159.803084 -311.099962)
			)
		)
		(stroke
			(width 0)
			(type solid)
		)
		(fill yes)
		(layer "In10.Cu")
		(net "P5E_PEX1_STN6_TX_DP<111>")
	)
	(gr_poly
		(pts
			(arc
				(start 159.803084 -308.249828)
				(mid 159.396684 -308.249828)
				(end 159.803084 -308.249828)
			)
		)
		(stroke
			(width 0)
			(type solid)
		)
		(fill yes)
		(layer "In10.Cu")
		(net "P5E_PEX1_STN7_TX_DN<119>")
	)
	(gr_poly
		(pts
			(arc
				(start 159.803084 -306.349908)
				(mid 159.396684 -306.349908)
				(end 159.803084 -306.349908)
			)
		)
		(stroke
			(width 0)
			(type solid)
		)
		(fill yes)
		(layer "In10.Cu")
		(net "P5E_PEX1_STN7_TX_DN<117>")
	)
	(gr_poly
		(pts
			(arc
				(start 159.803084 -304.449734)
				(mid 159.396684 -304.449734)
				(end 159.803084 -304.449734)
			)
		)
		(stroke
			(width 0)
			(type solid)
		)
		(fill yes)
		(layer "In10.Cu")
		(net "P5E_PEX1_STN7_TX_DN<115>")
	)
	(gr_poly
		(pts
			(arc
				(start 159.803084 -302.549814)
				(mid 159.396684 -302.549814)
				(end 159.803084 -302.549814)
			)
		)
		(stroke
			(width 0)
			(type solid)
		)
		(fill yes)
		(layer "In10.Cu")
		(net "P5E_PEX1_STN7_TX_DN<113>")
	)
	(gr_poly
		(pts
			(arc
				(start 160.753044 -318.699896)
				(mid 160.346644 -318.699896)
				(end 160.753044 -318.699896)
			)
		)
		(stroke
			(width 0)
			(type solid)
		)
		(fill yes)
		(layer "In10.Cu")
		(net "P5E_PEX1_STN6_RX_DN<110>")
	)
	(gr_poly
		(pts
			(arc
				(start 160.753044 -317.749936)
				(mid 160.346644 -317.749936)
				(end 160.753044 -317.749936)
			)
		)
		(stroke
			(width 0)
			(type solid)
		)
		(fill yes)
		(layer "In10.Cu")
		(net "P5E_PEX1_STN6_RX_DP<110>")
	)
	(gr_poly
		(pts
			(arc
				(start 160.753044 -313.949842)
				(mid 160.346644 -313.949842)
				(end 160.753044 -313.949842)
			)
		)
		(stroke
			(width 0)
			(type solid)
		)
		(fill yes)
		(layer "In10.Cu")
		(net "P5E_PEX1_STN6_TX_DN<110>")
	)
	(gr_poly
		(pts
			(arc
				(start 160.753044 -312.999882)
				(mid 160.346644 -312.999882)
				(end 160.753044 -312.999882)
			)
		)
		(stroke
			(width 0)
			(type solid)
		)
		(fill yes)
		(layer "In10.Cu")
		(net "P5E_PEX1_STN6_TX_DP<110>")
	)
	(gr_poly
		(pts
			(arc
				(start 160.753044 -308.249828)
				(mid 160.346644 -308.249828)
				(end 160.753044 -308.249828)
			)
		)
		(stroke
			(width 0)
			(type solid)
		)
		(fill yes)
		(layer "In10.Cu")
		(net "P5E_PEX1_STN7_TX_DP<119>")
	)
	(gr_poly
		(pts
			(arc
				(start 160.753044 -306.349908)
				(mid 160.346644 -306.349908)
				(end 160.753044 -306.349908)
			)
		)
		(stroke
			(width 0)
			(type solid)
		)
		(fill yes)
		(layer "In10.Cu")
		(net "P5E_PEX1_STN7_TX_DP<117>")
	)
	(gr_poly
		(pts
			(arc
				(start 160.753044 -304.449734)
				(mid 160.346644 -304.449734)
				(end 160.753044 -304.449734)
			)
		)
		(stroke
			(width 0)
			(type solid)
		)
		(fill yes)
		(layer "In10.Cu")
		(net "P5E_PEX1_STN7_TX_DP<115>")
	)
	(gr_poly
		(pts
			(arc
				(start 160.753044 -302.549814)
				(mid 160.346644 -302.549814)
				(end 160.753044 -302.549814)
			)
		)
		(stroke
			(width 0)
			(type solid)
		)
		(fill yes)
		(layer "In10.Cu")
		(net "P5E_PEX1_STN7_TX_DP<113>")
	)
	(gr_poly
		(pts
			(arc
				(start 160.753044 -278.799798)
				(mid 160.346644 -278.799798)
				(end 160.753044 -278.799798)
			)
		)
		(stroke
			(width 0)
			(type solid)
		)
		(fill yes)
		(layer "In10.Cu")
		(net "P5E_PEX1_STN2_TX_DP<47>")
	)
	(gr_poly
		(pts
			(arc
				(start 160.753044 -277.849838)
				(mid 160.346644 -277.849838)
				(end 160.753044 -277.849838)
			)
		)
		(stroke
			(width 0)
			(type solid)
		)
		(fill yes)
		(layer "In10.Cu")
		(net "P5E_PEX1_STN2_TX_DN<47>")
	)
	(gr_poly
		(pts
			(arc
				(start 161.703258 -316.799722)
				(mid 161.296858 -316.799722)
				(end 161.703258 -316.799722)
			)
		)
		(stroke
			(width 0)
			(type solid)
		)
		(fill yes)
		(layer "In10.Cu")
		(net "P5E_PEX1_STN6_RX_DN<109>")
	)
	(gr_poly
		(pts
			(arc
				(start 161.703258 -315.849762)
				(mid 161.296858 -315.849762)
				(end 161.703258 -315.849762)
			)
		)
		(stroke
			(width 0)
			(type solid)
		)
		(fill yes)
		(layer "In10.Cu")
		(net "P5E_PEX1_STN6_RX_DP<109>")
	)
	(gr_poly
		(pts
			(arc
				(start 161.703258 -312.049922)
				(mid 161.296858 -312.049922)
				(end 161.703258 -312.049922)
			)
		)
		(stroke
			(width 0)
			(type solid)
		)
		(fill yes)
		(layer "In10.Cu")
		(net "P5E_PEX1_STN6_TX_DN<109>")
	)
	(gr_poly
		(pts
			(arc
				(start 161.703258 -311.099962)
				(mid 161.296858 -311.099962)
				(end 161.703258 -311.099962)
			)
		)
		(stroke
			(width 0)
			(type solid)
		)
		(fill yes)
		(layer "In10.Cu")
		(net "P5E_PEX1_STN6_TX_DP<109>")
	)
	(gr_poly
		(pts
			(arc
				(start 161.703258 -280.699718)
				(mid 161.296858 -280.699718)
				(end 161.703258 -280.699718)
			)
		)
		(stroke
			(width 0)
			(type solid)
		)
		(fill yes)
		(layer "In10.Cu")
		(net "P5E_PEX1_STN2_TX_DP<46>")
	)
	(gr_poly
		(pts
			(arc
				(start 161.703258 -279.749504)
				(mid 161.296858 -279.749504)
				(end 161.703258 -279.749504)
			)
		)
		(stroke
			(width 0)
			(type solid)
		)
		(fill yes)
		(layer "In10.Cu")
		(net "P5E_PEX1_STN2_TX_DN<46>")
	)
	(gr_poly
		(pts
			(arc
				(start 162.653218 -318.699896)
				(mid 162.246818 -318.699896)
				(end 162.653218 -318.699896)
			)
		)
		(stroke
			(width 0)
			(type solid)
		)
		(fill yes)
		(layer "In10.Cu")
		(net "P5E_PEX1_STN6_RX_DN<108>")
	)
	(gr_poly
		(pts
			(arc
				(start 162.653218 -317.749936)
				(mid 162.246818 -317.749936)
				(end 162.653218 -317.749936)
			)
		)
		(stroke
			(width 0)
			(type solid)
		)
		(fill yes)
		(layer "In10.Cu")
		(net "P5E_PEX1_STN6_RX_DP<108>")
	)
	(gr_poly
		(pts
			(arc
				(start 162.653218 -313.949842)
				(mid 162.246818 -313.949842)
				(end 162.653218 -313.949842)
			)
		)
		(stroke
			(width 0)
			(type solid)
		)
		(fill yes)
		(layer "In10.Cu")
		(net "P5E_PEX1_STN6_TX_DN<108>")
	)
	(gr_poly
		(pts
			(arc
				(start 162.653218 -312.999882)
				(mid 162.246818 -312.999882)
				(end 162.653218 -312.999882)
			)
		)
		(stroke
			(width 0)
			(type solid)
		)
		(fill yes)
		(layer "In10.Cu")
		(net "P5E_PEX1_STN6_TX_DP<108>")
	)
	(gr_poly
		(pts
			(arc
				(start 162.653218 -278.799798)
				(mid 162.246818 -278.799798)
				(end 162.653218 -278.799798)
			)
		)
		(stroke
			(width 0)
			(type solid)
		)
		(fill yes)
		(layer "In10.Cu")
		(net "P5E_PEX1_STN2_TX_DP<45>")
	)
	(gr_poly
		(pts
			(arc
				(start 162.653218 -277.849838)
				(mid 162.246818 -277.849838)
				(end 162.653218 -277.849838)
			)
		)
		(stroke
			(width 0)
			(type solid)
		)
		(fill yes)
		(layer "In10.Cu")
		(net "P5E_PEX1_STN2_TX_DN<45>")
	)
	(gr_poly
		(pts
			(arc
				(start 163.603178 -316.799722)
				(mid 163.196778 -316.799722)
				(end 163.603178 -316.799722)
			)
		)
		(stroke
			(width 0)
			(type solid)
		)
		(fill yes)
		(layer "In10.Cu")
		(net "P5E_PEX1_STN6_RX_DN<107>")
	)
	(gr_poly
		(pts
			(arc
				(start 163.603178 -315.849762)
				(mid 163.196778 -315.849762)
				(end 163.603178 -315.849762)
			)
		)
		(stroke
			(width 0)
			(type solid)
		)
		(fill yes)
		(layer "In10.Cu")
		(net "P5E_PEX1_STN6_RX_DP<107>")
	)
	(gr_poly
		(pts
			(arc
				(start 163.603178 -312.049922)
				(mid 163.196778 -312.049922)
				(end 163.603178 -312.049922)
			)
		)
		(stroke
			(width 0)
			(type solid)
		)
		(fill yes)
		(layer "In10.Cu")
		(net "P5E_PEX1_STN6_TX_DN<107>")
	)
	(gr_poly
		(pts
			(arc
				(start 163.603178 -311.099962)
				(mid 163.196778 -311.099962)
				(end 163.603178 -311.099962)
			)
		)
		(stroke
			(width 0)
			(type solid)
		)
		(fill yes)
		(layer "In10.Cu")
		(net "P5E_PEX1_STN6_TX_DP<107>")
	)
	(gr_poly
		(pts
			(arc
				(start 163.603178 -280.699718)
				(mid 163.196778 -280.699718)
				(end 163.603178 -280.699718)
			)
		)
		(stroke
			(width 0)
			(type solid)
		)
		(fill yes)
		(layer "In10.Cu")
		(net "P5E_PEX1_STN2_TX_DP<44>")
	)
	(gr_poly
		(pts
			(arc
				(start 163.603178 -279.749504)
				(mid 163.196778 -279.749504)
				(end 163.603178 -279.749504)
			)
		)
		(stroke
			(width 0)
			(type solid)
		)
		(fill yes)
		(layer "In10.Cu")
		(net "P5E_PEX1_STN2_TX_DN<44>")
	)
	(gr_poly
		(pts
			(arc
				(start 164.553138 -318.699896)
				(mid 164.146738 -318.699896)
				(end 164.553138 -318.699896)
			)
		)
		(stroke
			(width 0)
			(type solid)
		)
		(fill yes)
		(layer "In10.Cu")
		(net "P5E_PEX1_STN6_RX_DN<106>")
	)
	(gr_poly
		(pts
			(arc
				(start 164.553138 -317.749936)
				(mid 164.146738 -317.749936)
				(end 164.553138 -317.749936)
			)
		)
		(stroke
			(width 0)
			(type solid)
		)
		(fill yes)
		(layer "In10.Cu")
		(net "P5E_PEX1_STN6_RX_DP<106>")
	)
	(gr_poly
		(pts
			(arc
				(start 164.553138 -313.949842)
				(mid 164.146738 -313.949842)
				(end 164.553138 -313.949842)
			)
		)
		(stroke
			(width 0)
			(type solid)
		)
		(fill yes)
		(layer "In10.Cu")
		(net "P5E_PEX1_STN6_TX_DN<106>")
	)
	(gr_poly
		(pts
			(arc
				(start 164.553138 -312.999882)
				(mid 164.146738 -312.999882)
				(end 164.553138 -312.999882)
			)
		)
		(stroke
			(width 0)
			(type solid)
		)
		(fill yes)
		(layer "In10.Cu")
		(net "P5E_PEX1_STN6_TX_DP<106>")
	)
	(gr_poly
		(pts
			(arc
				(start 164.553138 -278.799798)
				(mid 164.146738 -278.799798)
				(end 164.553138 -278.799798)
			)
		)
		(stroke
			(width 0)
			(type solid)
		)
		(fill yes)
		(layer "In10.Cu")
		(net "P5E_PEX1_STN2_TX_DP<43>")
	)
	(gr_poly
		(pts
			(arc
				(start 164.553138 -277.849838)
				(mid 164.146738 -277.849838)
				(end 164.553138 -277.849838)
			)
		)
		(stroke
			(width 0)
			(type solid)
		)
		(fill yes)
		(layer "In10.Cu")
		(net "P5E_PEX1_STN2_TX_DN<43>")
	)
	(gr_poly
		(pts
			(arc
				(start 165.503098 -316.799722)
				(mid 165.096698 -316.799722)
				(end 165.503098 -316.799722)
			)
		)
		(stroke
			(width 0)
			(type solid)
		)
		(fill yes)
		(layer "In10.Cu")
		(net "P5E_PEX1_STN6_RX_DN<105>")
	)
	(gr_poly
		(pts
			(arc
				(start 165.503098 -315.849762)
				(mid 165.096698 -315.849762)
				(end 165.503098 -315.849762)
			)
		)
		(stroke
			(width 0)
			(type solid)
		)
		(fill yes)
		(layer "In10.Cu")
		(net "P5E_PEX1_STN6_RX_DP<105>")
	)
	(gr_poly
		(pts
			(arc
				(start 165.503098 -312.049922)
				(mid 165.096698 -312.049922)
				(end 165.503098 -312.049922)
			)
		)
		(stroke
			(width 0)
			(type solid)
		)
		(fill yes)
		(layer "In10.Cu")
		(net "P5E_PEX1_STN6_TX_DN<105>")
	)
	(gr_poly
		(pts
			(arc
				(start 165.503098 -311.099962)
				(mid 165.096698 -311.099962)
				(end 165.503098 -311.099962)
			)
		)
		(stroke
			(width 0)
			(type solid)
		)
		(fill yes)
		(layer "In10.Cu")
		(net "P5E_PEX1_STN6_TX_DP<105>")
	)
	(gr_poly
		(pts
			(arc
				(start 165.503098 -280.699718)
				(mid 165.096698 -280.699718)
				(end 165.503098 -280.699718)
			)
		)
		(stroke
			(width 0)
			(type solid)
		)
		(fill yes)
		(layer "In10.Cu")
		(net "P5E_PEX1_STN2_TX_DP<42>")
	)
	(gr_poly
		(pts
			(arc
				(start 165.503098 -279.749504)
				(mid 165.096698 -279.749504)
				(end 165.503098 -279.749504)
			)
		)
		(stroke
			(width 0)
			(type solid)
		)
		(fill yes)
		(layer "In10.Cu")
		(net "P5E_PEX1_STN2_TX_DN<42>")
	)
	(gr_poly
		(pts
			(arc
				(start 166.453058 -318.699896)
				(mid 166.046658 -318.699896)
				(end 166.453058 -318.699896)
			)
		)
		(stroke
			(width 0)
			(type solid)
		)
		(fill yes)
		(layer "In10.Cu")
		(net "P5E_PEX1_STN6_RX_DN<104>")
	)
	(gr_poly
		(pts
			(arc
				(start 166.453058 -317.749936)
				(mid 166.046658 -317.749936)
				(end 166.453058 -317.749936)
			)
		)
		(stroke
			(width 0)
			(type solid)
		)
		(fill yes)
		(layer "In10.Cu")
		(net "P5E_PEX1_STN6_RX_DP<104>")
	)
	(gr_poly
		(pts
			(arc
				(start 166.453058 -313.949842)
				(mid 166.046658 -313.949842)
				(end 166.453058 -313.949842)
			)
		)
		(stroke
			(width 0)
			(type solid)
		)
		(fill yes)
		(layer "In10.Cu")
		(net "P5E_PEX1_STN6_TX_DN<104>")
	)
	(gr_poly
		(pts
			(arc
				(start 166.453058 -312.999882)
				(mid 166.046658 -312.999882)
				(end 166.453058 -312.999882)
			)
		)
		(stroke
			(width 0)
			(type solid)
		)
		(fill yes)
		(layer "In10.Cu")
		(net "P5E_PEX1_STN6_TX_DP<104>")
	)
	(gr_poly
		(pts
			(arc
				(start 166.453058 -278.799798)
				(mid 166.046658 -278.799798)
				(end 166.453058 -278.799798)
			)
		)
		(stroke
			(width 0)
			(type solid)
		)
		(fill yes)
		(layer "In10.Cu")
		(net "P5E_PEX1_STN2_TX_DP<41>")
	)
	(gr_poly
		(pts
			(arc
				(start 166.453058 -277.849838)
				(mid 166.046658 -277.849838)
				(end 166.453058 -277.849838)
			)
		)
		(stroke
			(width 0)
			(type solid)
		)
		(fill yes)
		(layer "In10.Cu")
		(net "P5E_PEX1_STN2_TX_DN<41>")
	)
	(gr_poly
		(pts
			(arc
				(start 167.403272 -280.699718)
				(mid 166.996872 -280.699718)
				(end 167.403272 -280.699718)
			)
		)
		(stroke
			(width 0)
			(type solid)
		)
		(fill yes)
		(layer "In10.Cu")
		(net "P5E_PEX1_STN2_TX_DP<40>")
	)
	(gr_poly
		(pts
			(arc
				(start 167.403272 -279.749504)
				(mid 166.996872 -279.749504)
				(end 167.403272 -279.749504)
			)
		)
		(stroke
			(width 0)
			(type solid)
		)
		(fill yes)
		(layer "In10.Cu")
		(net "P5E_PEX1_STN2_TX_DN<40>")
	)
	(gr_poly
		(pts
			(arc
				(start 168.353232 -278.799798)
				(mid 167.946832 -278.799798)
				(end 168.353232 -278.799798)
			)
		)
		(stroke
			(width 0)
			(type solid)
		)
		(fill yes)
		(layer "In10.Cu")
		(net "P5E_PEX1_STN2_TX_DP<39>")
	)
	(gr_poly
		(pts
			(arc
				(start 168.353232 -277.849838)
				(mid 167.946832 -277.849838)
				(end 168.353232 -277.849838)
			)
		)
		(stroke
			(width 0)
			(type solid)
		)
		(fill yes)
		(layer "In10.Cu")
		(net "P5E_PEX1_STN2_TX_DN<39>")
	)
	(gr_poly
		(pts
			(arc
				(start 169.303192 -280.699718)
				(mid 168.896792 -280.699718)
				(end 169.303192 -280.699718)
			)
		)
		(stroke
			(width 0)
			(type solid)
		)
		(fill yes)
		(layer "In10.Cu")
		(net "P5E_PEX1_STN2_TX_DP<38>")
	)
	(gr_poly
		(pts
			(arc
				(start 169.303192 -279.749504)
				(mid 168.896792 -279.749504)
				(end 169.303192 -279.749504)
			)
		)
		(stroke
			(width 0)
			(type solid)
		)
		(fill yes)
		(layer "In10.Cu")
		(net "P5E_PEX1_STN2_TX_DN<38>")
	)
	(gr_poly
		(pts
			(arc
				(start 170.253152 -278.799798)
				(mid 169.846752 -278.799798)
				(end 170.253152 -278.799798)
			)
		)
		(stroke
			(width 0)
			(type solid)
		)
		(fill yes)
		(layer "In10.Cu")
		(net "P5E_PEX1_STN2_TX_DP<37>")
	)
	(gr_poly
		(pts
			(arc
				(start 170.253152 -277.849838)
				(mid 169.846752 -277.849838)
				(end 170.253152 -277.849838)
			)
		)
		(stroke
			(width 0)
			(type solid)
		)
		(fill yes)
		(layer "In10.Cu")
		(net "P5E_PEX1_STN2_TX_DN<37>")
	)
	(gr_poly
		(pts
			(arc
				(start 171.203112 -280.699718)
				(mid 170.796712 -280.699718)
				(end 171.203112 -280.699718)
			)
		)
		(stroke
			(width 0)
			(type solid)
		)
		(fill yes)
		(layer "In10.Cu")
		(net "P5E_PEX1_STN2_TX_DP<36>")
	)
	(gr_poly
		(pts
			(arc
				(start 171.203112 -279.749504)
				(mid 170.796712 -279.749504)
				(end 171.203112 -279.749504)
			)
		)
		(stroke
			(width 0)
			(type solid)
		)
		(fill yes)
		(layer "In10.Cu")
		(net "P5E_PEX1_STN2_TX_DN<36>")
	)
	(gr_poly
		(pts
			(arc
				(start 172.153072 -278.799798)
				(mid 171.746672 -278.799798)
				(end 172.153072 -278.799798)
			)
		)
		(stroke
			(width 0)
			(type solid)
		)
		(fill yes)
		(layer "In10.Cu")
		(net "P5E_PEX1_STN2_TX_DP<35>")
	)
	(gr_poly
		(pts
			(arc
				(start 172.153072 -277.849838)
				(mid 171.746672 -277.849838)
				(end 172.153072 -277.849838)
			)
		)
		(stroke
			(width 0)
			(type solid)
		)
		(fill yes)
		(layer "In10.Cu")
		(net "P5E_PEX1_STN2_TX_DN<35>")
	)
	(gr_poly
		(pts
			(arc
				(start 173.103032 -280.699718)
				(mid 172.696632 -280.699718)
				(end 173.103032 -280.699718)
			)
		)
		(stroke
			(width 0)
			(type solid)
		)
		(fill yes)
		(layer "In10.Cu")
		(net "P5E_PEX1_STN2_TX_DP<34>")
	)
	(gr_poly
		(pts
			(arc
				(start 173.103032 -279.749504)
				(mid 172.696632 -279.749504)
				(end 173.103032 -279.749504)
			)
		)
		(stroke
			(width 0)
			(type solid)
		)
		(fill yes)
		(layer "In10.Cu")
		(net "P5E_PEX1_STN2_TX_DN<34>")
	)
	(gr_poly
		(pts
			(arc
				(start 174.053246 -278.799798)
				(mid 173.646846 -278.799798)
				(end 174.053246 -278.799798)
			)
		)
		(stroke
			(width 0)
			(type solid)
		)
		(fill yes)
		(layer "In10.Cu")
		(net "P5E_PEX1_STN2_TX_DP<33>")
	)
	(gr_poly
		(pts
			(arc
				(start 174.053246 -277.849838)
				(mid 173.646846 -277.849838)
				(end 174.053246 -277.849838)
			)
		)
		(stroke
			(width 0)
			(type solid)
		)
		(fill yes)
		(layer "In10.Cu")
		(net "P5E_PEX1_STN2_TX_DN<33>")
	)
	(gr_poly
		(pts
			(arc
				(start 175.003206 -280.699718)
				(mid 174.596806 -280.699718)
				(end 175.003206 -280.699718)
			)
		)
		(stroke
			(width 0)
			(type solid)
		)
		(fill yes)
		(layer "In10.Cu")
		(net "P5E_PEX1_STN2_TX_DP<32>")
	)
	(gr_poly
		(pts
			(arc
				(start 175.003206 -279.749504)
				(mid 174.596806 -279.749504)
				(end 175.003206 -279.749504)
			)
		)
		(stroke
			(width 0)
			(type solid)
		)
		(fill yes)
		(layer "In10.Cu")
		(net "P5E_PEX1_STN2_TX_DN<32>")
	)
	(gr_poly
		(pts
			(arc
				(start 182.60314 -316.799722)
				(mid 182.19674 -316.799722)
				(end 182.60314 -316.799722)
			)
		)
		(stroke
			(width 0)
			(type solid)
		)
		(fill yes)
		(layer "In10.Cu")
		(net "P5E_PEX1_STN5_RX_DN<88>")
	)
	(gr_poly
		(pts
			(arc
				(start 182.60314 -315.849762)
				(mid 182.19674 -315.849762)
				(end 182.60314 -315.849762)
			)
		)
		(stroke
			(width 0)
			(type solid)
		)
		(fill yes)
		(layer "In10.Cu")
		(net "P5E_PEX1_STN5_RX_DP<88>")
	)
	(gr_poly
		(pts
			(arc
				(start 182.60314 -312.049922)
				(mid 182.19674 -312.049922)
				(end 182.60314 -312.049922)
			)
		)
		(stroke
			(width 0)
			(type solid)
		)
		(fill yes)
		(layer "In10.Cu")
		(net "P5E_PEX1_STN5_TX_DN<88>")
	)
	(gr_poly
		(pts
			(arc
				(start 182.60314 -311.099962)
				(mid 182.19674 -311.099962)
				(end 182.60314 -311.099962)
			)
		)
		(stroke
			(width 0)
			(type solid)
		)
		(fill yes)
		(layer "In10.Cu")
		(net "P5E_PEX1_STN5_TX_DP<88>")
	)
	(gr_poly
		(pts
			(arc
				(start 183.5531 -318.699896)
				(mid 183.1467 -318.699896)
				(end 183.5531 -318.699896)
			)
		)
		(stroke
			(width 0)
			(type solid)
		)
		(fill yes)
		(layer "In10.Cu")
		(net "P5E_PEX1_STN5_RX_DN<89>")
	)
	(gr_poly
		(pts
			(arc
				(start 183.5531 -317.749936)
				(mid 183.1467 -317.749936)
				(end 183.5531 -317.749936)
			)
		)
		(stroke
			(width 0)
			(type solid)
		)
		(fill yes)
		(layer "In10.Cu")
		(net "P5E_PEX1_STN5_RX_DP<89>")
	)
	(gr_poly
		(pts
			(arc
				(start 183.5531 -313.949842)
				(mid 183.1467 -313.949842)
				(end 183.5531 -313.949842)
			)
		)
		(stroke
			(width 0)
			(type solid)
		)
		(fill yes)
		(layer "In10.Cu")
		(net "P5E_PEX1_STN5_TX_DN<89>")
	)
	(gr_poly
		(pts
			(arc
				(start 183.5531 -312.999882)
				(mid 183.1467 -312.999882)
				(end 183.5531 -312.999882)
			)
		)
		(stroke
			(width 0)
			(type solid)
		)
		(fill yes)
		(layer "In10.Cu")
		(net "P5E_PEX1_STN5_TX_DP<89>")
	)
	(gr_poly
		(pts
			(arc
				(start 184.50306 -316.799722)
				(mid 184.09666 -316.799722)
				(end 184.50306 -316.799722)
			)
		)
		(stroke
			(width 0)
			(type solid)
		)
		(fill yes)
		(layer "In10.Cu")
		(net "P5E_PEX1_STN5_RX_DN<90>")
	)
	(gr_poly
		(pts
			(arc
				(start 184.50306 -315.849762)
				(mid 184.09666 -315.849762)
				(end 184.50306 -315.849762)
			)
		)
		(stroke
			(width 0)
			(type solid)
		)
		(fill yes)
		(layer "In10.Cu")
		(net "P5E_PEX1_STN5_RX_DP<90>")
	)
	(gr_poly
		(pts
			(arc
				(start 184.50306 -312.049922)
				(mid 184.09666 -312.049922)
				(end 184.50306 -312.049922)
			)
		)
		(stroke
			(width 0)
			(type solid)
		)
		(fill yes)
		(layer "In10.Cu")
		(net "P5E_PEX1_STN5_TX_DN<90>")
	)
	(gr_poly
		(pts
			(arc
				(start 184.50306 -311.099962)
				(mid 184.09666 -311.099962)
				(end 184.50306 -311.099962)
			)
		)
		(stroke
			(width 0)
			(type solid)
		)
		(fill yes)
		(layer "In10.Cu")
		(net "P5E_PEX1_STN5_TX_DP<90>")
	)
	(gr_poly
		(pts
			(arc
				(start 185.453274 -318.699896)
				(mid 185.046874 -318.699896)
				(end 185.453274 -318.699896)
			)
		)
		(stroke
			(width 0)
			(type solid)
		)
		(fill yes)
		(layer "In10.Cu")
		(net "P5E_PEX1_STN5_RX_DN<91>")
	)
	(gr_poly
		(pts
			(arc
				(start 185.453274 -317.749936)
				(mid 185.046874 -317.749936)
				(end 185.453274 -317.749936)
			)
		)
		(stroke
			(width 0)
			(type solid)
		)
		(fill yes)
		(layer "In10.Cu")
		(net "P5E_PEX1_STN5_RX_DP<91>")
	)
	(gr_poly
		(pts
			(arc
				(start 185.453274 -313.949842)
				(mid 185.046874 -313.949842)
				(end 185.453274 -313.949842)
			)
		)
		(stroke
			(width 0)
			(type solid)
		)
		(fill yes)
		(layer "In10.Cu")
		(net "P5E_PEX1_STN5_TX_DN<91>")
	)
	(gr_poly
		(pts
			(arc
				(start 185.453274 -312.999882)
				(mid 185.046874 -312.999882)
				(end 185.453274 -312.999882)
			)
		)
		(stroke
			(width 0)
			(type solid)
		)
		(fill yes)
		(layer "In10.Cu")
		(net "P5E_PEX1_STN5_TX_DP<91>")
	)
	(gr_poly
		(pts
			(arc
				(start 186.403234 -316.799722)
				(mid 185.996834 -316.799722)
				(end 186.403234 -316.799722)
			)
		)
		(stroke
			(width 0)
			(type solid)
		)
		(fill yes)
		(layer "In10.Cu")
		(net "P5E_PEX1_STN5_RX_DN<92>")
	)
	(gr_poly
		(pts
			(arc
				(start 186.403234 -315.849762)
				(mid 185.996834 -315.849762)
				(end 186.403234 -315.849762)
			)
		)
		(stroke
			(width 0)
			(type solid)
		)
		(fill yes)
		(layer "In10.Cu")
		(net "P5E_PEX1_STN5_RX_DP<92>")
	)
	(gr_poly
		(pts
			(arc
				(start 186.403234 -312.049922)
				(mid 185.996834 -312.049922)
				(end 186.403234 -312.049922)
			)
		)
		(stroke
			(width 0)
			(type solid)
		)
		(fill yes)
		(layer "In10.Cu")
		(net "P5E_PEX1_STN5_TX_DN<92>")
	)
	(gr_poly
		(pts
			(arc
				(start 186.403234 -311.099962)
				(mid 185.996834 -311.099962)
				(end 186.403234 -311.099962)
			)
		)
		(stroke
			(width 0)
			(type solid)
		)
		(fill yes)
		(layer "In10.Cu")
		(net "P5E_PEX1_STN5_TX_DP<92>")
	)
	(gr_poly
		(pts
			(arc
				(start 187.353194 -318.699896)
				(mid 186.946794 -318.699896)
				(end 187.353194 -318.699896)
			)
		)
		(stroke
			(width 0)
			(type solid)
		)
		(fill yes)
		(layer "In10.Cu")
		(net "P5E_PEX1_STN5_RX_DN<93>")
	)
	(gr_poly
		(pts
			(arc
				(start 187.353194 -317.749936)
				(mid 186.946794 -317.749936)
				(end 187.353194 -317.749936)
			)
		)
		(stroke
			(width 0)
			(type solid)
		)
		(fill yes)
		(layer "In10.Cu")
		(net "P5E_PEX1_STN5_RX_DP<93>")
	)
	(gr_poly
		(pts
			(arc
				(start 187.353194 -313.949842)
				(mid 186.946794 -313.949842)
				(end 187.353194 -313.949842)
			)
		)
		(stroke
			(width 0)
			(type solid)
		)
		(fill yes)
		(layer "In10.Cu")
		(net "P5E_PEX1_STN5_TX_DN<93>")
	)
	(gr_poly
		(pts
			(arc
				(start 187.353194 -312.999882)
				(mid 186.946794 -312.999882)
				(end 187.353194 -312.999882)
			)
		)
		(stroke
			(width 0)
			(type solid)
		)
		(fill yes)
		(layer "In10.Cu")
		(net "P5E_PEX1_STN5_TX_DP<93>")
	)
	(gr_poly
		(pts
			(arc
				(start 188.303154 -316.799722)
				(mid 187.896754 -316.799722)
				(end 188.303154 -316.799722)
			)
		)
		(stroke
			(width 0)
			(type solid)
		)
		(fill yes)
		(layer "In10.Cu")
		(net "P5E_PEX1_STN5_RX_DN<94>")
	)
	(gr_poly
		(pts
			(arc
				(start 188.303154 -315.849762)
				(mid 187.896754 -315.849762)
				(end 188.303154 -315.849762)
			)
		)
		(stroke
			(width 0)
			(type solid)
		)
		(fill yes)
		(layer "In10.Cu")
		(net "P5E_PEX1_STN5_RX_DP<94>")
	)
	(gr_poly
		(pts
			(arc
				(start 188.303154 -312.049922)
				(mid 187.896754 -312.049922)
				(end 188.303154 -312.049922)
			)
		)
		(stroke
			(width 0)
			(type solid)
		)
		(fill yes)
		(layer "In10.Cu")
		(net "P5E_PEX1_STN5_TX_DN<94>")
	)
	(gr_poly
		(pts
			(arc
				(start 188.303154 -311.099962)
				(mid 187.896754 -311.099962)
				(end 188.303154 -311.099962)
			)
		)
		(stroke
			(width 0)
			(type solid)
		)
		(fill yes)
		(layer "In10.Cu")
		(net "P5E_PEX1_STN5_TX_DP<94>")
	)
	(gr_poly
		(pts
			(arc
				(start 189.253114 -318.699896)
				(mid 188.846714 -318.699896)
				(end 189.253114 -318.699896)
			)
		)
		(stroke
			(width 0)
			(type solid)
		)
		(fill yes)
		(layer "In10.Cu")
		(net "P5E_PEX1_STN5_RX_DN<95>")
	)
	(gr_poly
		(pts
			(arc
				(start 189.253114 -317.749936)
				(mid 188.846714 -317.749936)
				(end 189.253114 -317.749936)
			)
		)
		(stroke
			(width 0)
			(type solid)
		)
		(fill yes)
		(layer "In10.Cu")
		(net "P5E_PEX1_STN5_RX_DP<95>")
	)
	(gr_poly
		(pts
			(arc
				(start 189.253114 -313.949842)
				(mid 188.846714 -313.949842)
				(end 189.253114 -313.949842)
			)
		)
		(stroke
			(width 0)
			(type solid)
		)
		(fill yes)
		(layer "In10.Cu")
		(net "P5E_PEX1_STN5_TX_DN<95>")
	)
	(gr_poly
		(pts
			(arc
				(start 189.253114 -312.999882)
				(mid 188.846714 -312.999882)
				(end 189.253114 -312.999882)
			)
		)
		(stroke
			(width 0)
			(type solid)
		)
		(fill yes)
		(layer "In10.Cu")
		(net "P5E_PEX1_STN5_TX_DP<95>")
	)
	(gr_poly
		(pts
			(arc
				(start 275.902928 -312.049922)
				(mid 275.496528 -312.049922)
				(end 275.902928 -312.049922)
			)
		)
		(stroke
			(width 0)
			(type solid)
		)
		(fill yes)
		(layer "In10.Cu")
		(net "P5E_PEX2_STN6_TX_DN<111>")
	)
	(gr_poly
		(pts
			(arc
				(start 275.902928 -311.099962)
				(mid 275.496528 -311.099962)
				(end 275.902928 -311.099962)
			)
		)
		(stroke
			(width 0)
			(type solid)
		)
		(fill yes)
		(layer "In10.Cu")
		(net "P5E_PEX2_STN6_TX_DP<111>")
	)
	(gr_poly
		(pts
			(arc
				(start 276.852888 -313.949842)
				(mid 276.446488 -313.949842)
				(end 276.852888 -313.949842)
			)
		)
		(stroke
			(width 0)
			(type solid)
		)
		(fill yes)
		(layer "In10.Cu")
		(net "P5E_PEX2_STN6_TX_DN<110>")
	)
	(gr_poly
		(pts
			(arc
				(start 276.852888 -312.999882)
				(mid 276.446488 -312.999882)
				(end 276.852888 -312.999882)
			)
		)
		(stroke
			(width 0)
			(type solid)
		)
		(fill yes)
		(layer "In10.Cu")
		(net "P5E_PEX2_STN6_TX_DP<110>")
	)
	(gr_poly
		(pts
			(arc
				(start 276.852888 -278.799798)
				(mid 276.446488 -278.799798)
				(end 276.852888 -278.799798)
			)
		)
		(stroke
			(width 0)
			(type solid)
		)
		(fill yes)
		(layer "In10.Cu")
		(net "P5E_PEX2_STN2_TX_DP<47>")
	)
	(gr_poly
		(pts
			(arc
				(start 276.852888 -277.849838)
				(mid 276.446488 -277.849838)
				(end 276.852888 -277.849838)
			)
		)
		(stroke
			(width 0)
			(type solid)
		)
		(fill yes)
		(layer "In10.Cu")
		(net "P5E_PEX2_STN2_TX_DN<47>")
	)
	(gr_poly
		(pts
			(arc
				(start 277.803102 -312.049922)
				(mid 277.396702 -312.049922)
				(end 277.803102 -312.049922)
			)
		)
		(stroke
			(width 0)
			(type solid)
		)
		(fill yes)
		(layer "In10.Cu")
		(net "P5E_PEX2_STN6_TX_DN<109>")
	)
	(gr_poly
		(pts
			(arc
				(start 277.803102 -311.099962)
				(mid 277.396702 -311.099962)
				(end 277.803102 -311.099962)
			)
		)
		(stroke
			(width 0)
			(type solid)
		)
		(fill yes)
		(layer "In10.Cu")
		(net "P5E_PEX2_STN6_TX_DP<109>")
	)
	(gr_poly
		(pts
			(arc
				(start 277.803102 -280.699464)
				(mid 277.396702 -280.699464)
				(end 277.803102 -280.699464)
			)
		)
		(stroke
			(width 0)
			(type solid)
		)
		(fill yes)
		(layer "In10.Cu")
		(net "P5E_PEX2_STN2_TX_DP<46>")
	)
	(gr_poly
		(pts
			(arc
				(start 277.803102 -279.749504)
				(mid 277.396702 -279.749504)
				(end 277.803102 -279.749504)
			)
		)
		(stroke
			(width 0)
			(type solid)
		)
		(fill yes)
		(layer "In10.Cu")
		(net "P5E_PEX2_STN2_TX_DN<46>")
	)
	(gr_poly
		(pts
			(arc
				(start 278.753062 -313.949842)
				(mid 278.346662 -313.949842)
				(end 278.753062 -313.949842)
			)
		)
		(stroke
			(width 0)
			(type solid)
		)
		(fill yes)
		(layer "In10.Cu")
		(net "P5E_PEX2_STN6_TX_DN<108>")
	)
	(gr_poly
		(pts
			(arc
				(start 278.753062 -312.999882)
				(mid 278.346662 -312.999882)
				(end 278.753062 -312.999882)
			)
		)
		(stroke
			(width 0)
			(type solid)
		)
		(fill yes)
		(layer "In10.Cu")
		(net "P5E_PEX2_STN6_TX_DP<108>")
	)
	(gr_poly
		(pts
			(arc
				(start 278.753062 -278.799798)
				(mid 278.346662 -278.799798)
				(end 278.753062 -278.799798)
			)
		)
		(stroke
			(width 0)
			(type solid)
		)
		(fill yes)
		(layer "In10.Cu")
		(net "P5E_PEX2_STN2_TX_DP<45>")
	)
	(gr_poly
		(pts
			(arc
				(start 278.753062 -277.849838)
				(mid 278.346662 -277.849838)
				(end 278.753062 -277.849838)
			)
		)
		(stroke
			(width 0)
			(type solid)
		)
		(fill yes)
		(layer "In10.Cu")
		(net "P5E_PEX2_STN2_TX_DN<45>")
	)
	(gr_poly
		(pts
			(arc
				(start 279.703022 -312.049922)
				(mid 279.296622 -312.049922)
				(end 279.703022 -312.049922)
			)
		)
		(stroke
			(width 0)
			(type solid)
		)
		(fill yes)
		(layer "In10.Cu")
		(net "P5E_PEX2_STN6_TX_DN<107>")
	)
	(gr_poly
		(pts
			(arc
				(start 279.703022 -311.099962)
				(mid 279.296622 -311.099962)
				(end 279.703022 -311.099962)
			)
		)
		(stroke
			(width 0)
			(type solid)
		)
		(fill yes)
		(layer "In10.Cu")
		(net "P5E_PEX2_STN6_TX_DP<107>")
	)
	(gr_poly
		(pts
			(arc
				(start 279.703022 -280.699464)
				(mid 279.296622 -280.699464)
				(end 279.703022 -280.699464)
			)
		)
		(stroke
			(width 0)
			(type solid)
		)
		(fill yes)
		(layer "In10.Cu")
		(net "P5E_PEX2_STN2_TX_DP<44>")
	)
	(gr_poly
		(pts
			(arc
				(start 279.703022 -279.749504)
				(mid 279.296622 -279.749504)
				(end 279.703022 -279.749504)
			)
		)
		(stroke
			(width 0)
			(type solid)
		)
		(fill yes)
		(layer "In10.Cu")
		(net "P5E_PEX2_STN2_TX_DN<44>")
	)
	(gr_poly
		(pts
			(arc
				(start 280.652982 -313.949842)
				(mid 280.246582 -313.949842)
				(end 280.652982 -313.949842)
			)
		)
		(stroke
			(width 0)
			(type solid)
		)
		(fill yes)
		(layer "In10.Cu")
		(net "P5E_PEX2_STN6_TX_DN<106>")
	)
	(gr_poly
		(pts
			(arc
				(start 280.652982 -312.999882)
				(mid 280.246582 -312.999882)
				(end 280.652982 -312.999882)
			)
		)
		(stroke
			(width 0)
			(type solid)
		)
		(fill yes)
		(layer "In10.Cu")
		(net "P5E_PEX2_STN6_TX_DP<106>")
	)
	(gr_poly
		(pts
			(arc
				(start 280.652982 -278.799798)
				(mid 280.246582 -278.799798)
				(end 280.652982 -278.799798)
			)
		)
		(stroke
			(width 0)
			(type solid)
		)
		(fill yes)
		(layer "In10.Cu")
		(net "P5E_PEX2_STN2_TX_DP<43>")
	)
	(gr_poly
		(pts
			(arc
				(start 280.652982 -277.849838)
				(mid 280.246582 -277.849838)
				(end 280.652982 -277.849838)
			)
		)
		(stroke
			(width 0)
			(type solid)
		)
		(fill yes)
		(layer "In10.Cu")
		(net "P5E_PEX2_STN2_TX_DN<43>")
	)
	(gr_poly
		(pts
			(arc
				(start 281.602942 -312.049922)
				(mid 281.196542 -312.049922)
				(end 281.602942 -312.049922)
			)
		)
		(stroke
			(width 0)
			(type solid)
		)
		(fill yes)
		(layer "In10.Cu")
		(net "P5E_PEX2_STN6_TX_DN<105>")
	)
	(gr_poly
		(pts
			(arc
				(start 281.602942 -311.099962)
				(mid 281.196542 -311.099962)
				(end 281.602942 -311.099962)
			)
		)
		(stroke
			(width 0)
			(type solid)
		)
		(fill yes)
		(layer "In10.Cu")
		(net "P5E_PEX2_STN6_TX_DP<105>")
	)
	(gr_poly
		(pts
			(arc
				(start 281.602942 -280.699464)
				(mid 281.196542 -280.699464)
				(end 281.602942 -280.699464)
			)
		)
		(stroke
			(width 0)
			(type solid)
		)
		(fill yes)
		(layer "In10.Cu")
		(net "P5E_PEX2_STN2_TX_DP<42>")
	)
	(gr_poly
		(pts
			(arc
				(start 281.602942 -279.749504)
				(mid 281.196542 -279.749504)
				(end 281.602942 -279.749504)
			)
		)
		(stroke
			(width 0)
			(type solid)
		)
		(fill yes)
		(layer "In10.Cu")
		(net "P5E_PEX2_STN2_TX_DN<42>")
	)
	(gr_poly
		(pts
			(arc
				(start 282.552902 -313.949842)
				(mid 282.146502 -313.949842)
				(end 282.552902 -313.949842)
			)
		)
		(stroke
			(width 0)
			(type solid)
		)
		(fill yes)
		(layer "In10.Cu")
		(net "P5E_PEX2_STN6_TX_DN<104>")
	)
	(gr_poly
		(pts
			(arc
				(start 282.552902 -312.999882)
				(mid 282.146502 -312.999882)
				(end 282.552902 -312.999882)
			)
		)
		(stroke
			(width 0)
			(type solid)
		)
		(fill yes)
		(layer "In10.Cu")
		(net "P5E_PEX2_STN6_TX_DP<104>")
	)
	(gr_poly
		(pts
			(arc
				(start 282.552902 -278.799798)
				(mid 282.146502 -278.799798)
				(end 282.552902 -278.799798)
			)
		)
		(stroke
			(width 0)
			(type solid)
		)
		(fill yes)
		(layer "In10.Cu")
		(net "P5E_PEX2_STN2_TX_DP<41>")
	)
	(gr_poly
		(pts
			(arc
				(start 282.552902 -277.849838)
				(mid 282.146502 -277.849838)
				(end 282.552902 -277.849838)
			)
		)
		(stroke
			(width 0)
			(type solid)
		)
		(fill yes)
		(layer "In10.Cu")
		(net "P5E_PEX2_STN2_TX_DN<41>")
	)
	(gr_poly
		(pts
			(arc
				(start 283.503116 -312.049922)
				(mid 283.096716 -312.049922)
				(end 283.503116 -312.049922)
			)
		)
		(stroke
			(width 0)
			(type solid)
		)
		(fill yes)
		(layer "In10.Cu")
		(net "P5E_PEX2_STN6_TX_DN<103>")
	)
	(gr_poly
		(pts
			(arc
				(start 283.503116 -311.099962)
				(mid 283.096716 -311.099962)
				(end 283.503116 -311.099962)
			)
		)
		(stroke
			(width 0)
			(type solid)
		)
		(fill yes)
		(layer "In10.Cu")
		(net "P5E_PEX2_STN6_TX_DP<103>")
	)
	(gr_poly
		(pts
			(arc
				(start 283.503116 -280.699464)
				(mid 283.096716 -280.699464)
				(end 283.503116 -280.699464)
			)
		)
		(stroke
			(width 0)
			(type solid)
		)
		(fill yes)
		(layer "In10.Cu")
		(net "P5E_PEX2_STN2_TX_DP<40>")
	)
	(gr_poly
		(pts
			(arc
				(start 283.503116 -279.749504)
				(mid 283.096716 -279.749504)
				(end 283.503116 -279.749504)
			)
		)
		(stroke
			(width 0)
			(type solid)
		)
		(fill yes)
		(layer "In10.Cu")
		(net "P5E_PEX2_STN2_TX_DN<40>")
	)
	(gr_poly
		(pts
			(arc
				(start 284.453076 -313.949842)
				(mid 284.046676 -313.949842)
				(end 284.453076 -313.949842)
			)
		)
		(stroke
			(width 0)
			(type solid)
		)
		(fill yes)
		(layer "In10.Cu")
		(net "P5E_PEX2_STN6_TX_DN<102>")
	)
	(gr_poly
		(pts
			(arc
				(start 284.453076 -312.999882)
				(mid 284.046676 -312.999882)
				(end 284.453076 -312.999882)
			)
		)
		(stroke
			(width 0)
			(type solid)
		)
		(fill yes)
		(layer "In10.Cu")
		(net "P5E_PEX2_STN6_TX_DP<102>")
	)
	(gr_poly
		(pts
			(arc
				(start 284.453076 -278.799798)
				(mid 284.046676 -278.799798)
				(end 284.453076 -278.799798)
			)
		)
		(stroke
			(width 0)
			(type solid)
		)
		(fill yes)
		(layer "In10.Cu")
		(net "P5E_PEX2_STN2_TX_DP<39>")
	)
	(gr_poly
		(pts
			(arc
				(start 284.453076 -277.849838)
				(mid 284.046676 -277.849838)
				(end 284.453076 -277.849838)
			)
		)
		(stroke
			(width 0)
			(type solid)
		)
		(fill yes)
		(layer "In10.Cu")
		(net "P5E_PEX2_STN2_TX_DN<39>")
	)
	(gr_poly
		(pts
			(arc
				(start 285.403036 -312.049922)
				(mid 284.996636 -312.049922)
				(end 285.403036 -312.049922)
			)
		)
		(stroke
			(width 0)
			(type solid)
		)
		(fill yes)
		(layer "In10.Cu")
		(net "P5E_PEX2_STN6_TX_DN<101>")
	)
	(gr_poly
		(pts
			(arc
				(start 285.403036 -311.099962)
				(mid 284.996636 -311.099962)
				(end 285.403036 -311.099962)
			)
		)
		(stroke
			(width 0)
			(type solid)
		)
		(fill yes)
		(layer "In10.Cu")
		(net "P5E_PEX2_STN6_TX_DP<101>")
	)
	(gr_poly
		(pts
			(arc
				(start 285.403036 -280.699464)
				(mid 284.996636 -280.699464)
				(end 285.403036 -280.699464)
			)
		)
		(stroke
			(width 0)
			(type solid)
		)
		(fill yes)
		(layer "In10.Cu")
		(net "P5E_PEX2_STN2_TX_DP<38>")
	)
	(gr_poly
		(pts
			(arc
				(start 285.403036 -279.749504)
				(mid 284.996636 -279.749504)
				(end 285.403036 -279.749504)
			)
		)
		(stroke
			(width 0)
			(type solid)
		)
		(fill yes)
		(layer "In10.Cu")
		(net "P5E_PEX2_STN2_TX_DN<38>")
	)
	(gr_poly
		(pts
			(arc
				(start 286.352996 -313.949842)
				(mid 285.946596 -313.949842)
				(end 286.352996 -313.949842)
			)
		)
		(stroke
			(width 0)
			(type solid)
		)
		(fill yes)
		(layer "In10.Cu")
		(net "P5E_PEX2_STN6_TX_DN<100>")
	)
	(gr_poly
		(pts
			(arc
				(start 286.352996 -312.999882)
				(mid 285.946596 -312.999882)
				(end 286.352996 -312.999882)
			)
		)
		(stroke
			(width 0)
			(type solid)
		)
		(fill yes)
		(layer "In10.Cu")
		(net "P5E_PEX2_STN6_TX_DP<100>")
	)
	(gr_poly
		(pts
			(arc
				(start 286.352996 -278.799798)
				(mid 285.946596 -278.799798)
				(end 286.352996 -278.799798)
			)
		)
		(stroke
			(width 0)
			(type solid)
		)
		(fill yes)
		(layer "In10.Cu")
		(net "P5E_PEX2_STN2_TX_DP<37>")
	)
	(gr_poly
		(pts
			(arc
				(start 286.352996 -277.849838)
				(mid 285.946596 -277.849838)
				(end 286.352996 -277.849838)
			)
		)
		(stroke
			(width 0)
			(type solid)
		)
		(fill yes)
		(layer "In10.Cu")
		(net "P5E_PEX2_STN2_TX_DN<37>")
	)
	(gr_poly
		(pts
			(arc
				(start 287.302956 -312.049922)
				(mid 286.896556 -312.049922)
				(end 287.302956 -312.049922)
			)
		)
		(stroke
			(width 0)
			(type solid)
		)
		(fill yes)
		(layer "In10.Cu")
		(net "P5E_PEX2_STN6_TX_DN<99>")
	)
	(gr_poly
		(pts
			(arc
				(start 287.302956 -311.099962)
				(mid 286.896556 -311.099962)
				(end 287.302956 -311.099962)
			)
		)
		(stroke
			(width 0)
			(type solid)
		)
		(fill yes)
		(layer "In10.Cu")
		(net "P5E_PEX2_STN6_TX_DP<99>")
	)
	(gr_poly
		(pts
			(arc
				(start 287.302956 -280.699464)
				(mid 286.896556 -280.699464)
				(end 287.302956 -280.699464)
			)
		)
		(stroke
			(width 0)
			(type solid)
		)
		(fill yes)
		(layer "In10.Cu")
		(net "P5E_PEX2_STN2_TX_DP<36>")
	)
	(gr_poly
		(pts
			(arc
				(start 287.302956 -279.749504)
				(mid 286.896556 -279.749504)
				(end 287.302956 -279.749504)
			)
		)
		(stroke
			(width 0)
			(type solid)
		)
		(fill yes)
		(layer "In10.Cu")
		(net "P5E_PEX2_STN2_TX_DN<36>")
	)
	(gr_poly
		(pts
			(arc
				(start 288.252916 -313.949842)
				(mid 287.846516 -313.949842)
				(end 288.252916 -313.949842)
			)
		)
		(stroke
			(width 0)
			(type solid)
		)
		(fill yes)
		(layer "In10.Cu")
		(net "P5E_PEX2_STN6_TX_DN<98>")
	)
	(gr_poly
		(pts
			(arc
				(start 288.252916 -312.999882)
				(mid 287.846516 -312.999882)
				(end 288.252916 -312.999882)
			)
		)
		(stroke
			(width 0)
			(type solid)
		)
		(fill yes)
		(layer "In10.Cu")
		(net "P5E_PEX2_STN6_TX_DP<98>")
	)
	(gr_poly
		(pts
			(arc
				(start 288.252916 -278.799798)
				(mid 287.846516 -278.799798)
				(end 288.252916 -278.799798)
			)
		)
		(stroke
			(width 0)
			(type solid)
		)
		(fill yes)
		(layer "In10.Cu")
		(net "P5E_PEX2_STN2_TX_DP<35>")
	)
	(gr_poly
		(pts
			(arc
				(start 288.252916 -277.849838)
				(mid 287.846516 -277.849838)
				(end 288.252916 -277.849838)
			)
		)
		(stroke
			(width 0)
			(type solid)
		)
		(fill yes)
		(layer "In10.Cu")
		(net "P5E_PEX2_STN2_TX_DN<35>")
	)
	(gr_poly
		(pts
			(arc
				(start 289.202876 -280.699464)
				(mid 288.796476 -280.699464)
				(end 289.202876 -280.699464)
			)
		)
		(stroke
			(width 0)
			(type solid)
		)
		(fill yes)
		(layer "In10.Cu")
		(net "P5E_PEX2_STN2_TX_DP<34>")
	)
	(gr_poly
		(pts
			(arc
				(start 289.202876 -279.749504)
				(mid 288.796476 -279.749504)
				(end 289.202876 -279.749504)
			)
		)
		(stroke
			(width 0)
			(type solid)
		)
		(fill yes)
		(layer "In10.Cu")
		(net "P5E_PEX2_STN2_TX_DN<34>")
	)
	(gr_poly
		(pts
			(arc
				(start 289.20313 -312.049922)
				(mid 288.79673 -312.049922)
				(end 289.20313 -312.049922)
			)
		)
		(stroke
			(width 0)
			(type solid)
		)
		(fill yes)
		(layer "In10.Cu")
		(net "P5E_PEX2_STN6_TX_DN<97>")
	)
	(gr_poly
		(pts
			(arc
				(start 289.20313 -311.099962)
				(mid 288.79673 -311.099962)
				(end 289.20313 -311.099962)
			)
		)
		(stroke
			(width 0)
			(type solid)
		)
		(fill yes)
		(layer "In10.Cu")
		(net "P5E_PEX2_STN6_TX_DP<97>")
	)
	(gr_poly
		(pts
			(arc
				(start 290.15309 -313.949842)
				(mid 289.74669 -313.949842)
				(end 290.15309 -313.949842)
			)
		)
		(stroke
			(width 0)
			(type solid)
		)
		(fill yes)
		(layer "In10.Cu")
		(net "P5E_PEX2_STN6_TX_DN<96>")
	)
	(gr_poly
		(pts
			(arc
				(start 290.15309 -312.999882)
				(mid 289.74669 -312.999882)
				(end 290.15309 -312.999882)
			)
		)
		(stroke
			(width 0)
			(type solid)
		)
		(fill yes)
		(layer "In10.Cu")
		(net "P5E_PEX2_STN6_TX_DP<96>")
	)
	(gr_poly
		(pts
			(arc
				(start 290.15309 -278.799798)
				(mid 289.74669 -278.799798)
				(end 290.15309 -278.799798)
			)
		)
		(stroke
			(width 0)
			(type solid)
		)
		(fill yes)
		(layer "In10.Cu")
		(net "P5E_PEX2_STN2_TX_DP<33>")
	)
	(gr_poly
		(pts
			(arc
				(start 290.15309 -277.849838)
				(mid 289.74669 -277.849838)
				(end 290.15309 -277.849838)
			)
		)
		(stroke
			(width 0)
			(type solid)
		)
		(fill yes)
		(layer "In10.Cu")
		(net "P5E_PEX2_STN2_TX_DN<33>")
	)
	(gr_poly
		(pts
			(arc
				(start 291.10305 -280.699464)
				(mid 290.69665 -280.699464)
				(end 291.10305 -280.699464)
			)
		)
		(stroke
			(width 0)
			(type solid)
		)
		(fill yes)
		(layer "In10.Cu")
		(net "P5E_PEX2_STN2_TX_DP<32>")
	)
	(gr_poly
		(pts
			(arc
				(start 291.10305 -279.749504)
				(mid 290.69665 -279.749504)
				(end 291.10305 -279.749504)
			)
		)
		(stroke
			(width 0)
			(type solid)
		)
		(fill yes)
		(layer "In10.Cu")
		(net "P5E_PEX2_STN2_TX_DN<32>")
	)
	(gr_poly
		(pts
			(arc
				(start 306.302918 -316.799722)
				(mid 305.896518 -316.799722)
				(end 306.302918 -316.799722)
			)
		)
		(stroke
			(width 0)
			(type solid)
		)
		(fill yes)
		(layer "In10.Cu")
		(net "P5E_PEX2_STN4_RX_DN<79>")
	)
	(gr_poly
		(pts
			(arc
				(start 306.302918 -315.849762)
				(mid 305.896518 -315.849762)
				(end 306.302918 -315.849762)
			)
		)
		(stroke
			(width 0)
			(type solid)
		)
		(fill yes)
		(layer "In10.Cu")
		(net "P5E_PEX2_STN4_RX_DP<79>")
	)
	(gr_poly
		(pts
			(arc
				(start 306.302918 -312.049922)
				(mid 305.896518 -312.049922)
				(end 306.302918 -312.049922)
			)
		)
		(stroke
			(width 0)
			(type solid)
		)
		(fill yes)
		(layer "In10.Cu")
		(net "P5E_PEX2_STN4_TX_DN<79>")
	)
	(gr_poly
		(pts
			(arc
				(start 306.302918 -311.099962)
				(mid 305.896518 -311.099962)
				(end 306.302918 -311.099962)
			)
		)
		(stroke
			(width 0)
			(type solid)
		)
		(fill yes)
		(layer "In10.Cu")
		(net "P5E_PEX2_STN4_TX_DP<79>")
	)
	(gr_poly
		(pts
			(arc
				(start 307.253132 -318.699896)
				(mid 306.846732 -318.699896)
				(end 307.253132 -318.699896)
			)
		)
		(stroke
			(width 0)
			(type solid)
		)
		(fill yes)
		(layer "In10.Cu")
		(net "P5E_PEX2_STN4_RX_DN<78>")
	)
	(gr_poly
		(pts
			(arc
				(start 307.253132 -317.749936)
				(mid 306.846732 -317.749936)
				(end 307.253132 -317.749936)
			)
		)
		(stroke
			(width 0)
			(type solid)
		)
		(fill yes)
		(layer "In10.Cu")
		(net "P5E_PEX2_STN4_RX_DP<78>")
	)
	(gr_poly
		(pts
			(arc
				(start 307.253132 -313.949842)
				(mid 306.846732 -313.949842)
				(end 307.253132 -313.949842)
			)
		)
		(stroke
			(width 0)
			(type solid)
		)
		(fill yes)
		(layer "In10.Cu")
		(net "P5E_PEX2_STN4_TX_DN<78>")
	)
	(gr_poly
		(pts
			(arc
				(start 307.253132 -312.999882)
				(mid 306.846732 -312.999882)
				(end 307.253132 -312.999882)
			)
		)
		(stroke
			(width 0)
			(type solid)
		)
		(fill yes)
		(layer "In10.Cu")
		(net "P5E_PEX2_STN4_TX_DP<78>")
	)
	(gr_poly
		(pts
			(arc
				(start 307.253132 -308.249828)
				(mid 306.846732 -308.249828)
				(end 307.253132 -308.249828)
			)
		)
		(stroke
			(width 0)
			(type solid)
		)
		(fill yes)
		(layer "In10.Cu")
		(net "P5E_PEX2_STN4_TX_DP<68>")
	)
	(gr_poly
		(pts
			(arc
				(start 307.253132 -306.349908)
				(mid 306.846732 -306.349908)
				(end 307.253132 -306.349908)
			)
		)
		(stroke
			(width 0)
			(type solid)
		)
		(fill yes)
		(layer "In10.Cu")
		(net "P5E_PEX2_STN4_TX_DP<66>")
	)
	(gr_poly
		(pts
			(arc
				(start 307.253132 -304.449734)
				(mid 306.846732 -304.449734)
				(end 307.253132 -304.449734)
			)
		)
		(stroke
			(width 0)
			(type solid)
		)
		(fill yes)
		(layer "In10.Cu")
		(net "P5E_PEX2_STN4_TX_DP<64>")
	)
	(gr_poly
		(pts
			(arc
				(start 308.203092 -316.799722)
				(mid 307.796692 -316.799722)
				(end 308.203092 -316.799722)
			)
		)
		(stroke
			(width 0)
			(type solid)
		)
		(fill yes)
		(layer "In10.Cu")
		(net "P5E_PEX2_STN4_RX_DN<77>")
	)
	(gr_poly
		(pts
			(arc
				(start 308.203092 -315.849762)
				(mid 307.796692 -315.849762)
				(end 308.203092 -315.849762)
			)
		)
		(stroke
			(width 0)
			(type solid)
		)
		(fill yes)
		(layer "In10.Cu")
		(net "P5E_PEX2_STN4_RX_DP<77>")
	)
	(gr_poly
		(pts
			(arc
				(start 308.203092 -312.049922)
				(mid 307.796692 -312.049922)
				(end 308.203092 -312.049922)
			)
		)
		(stroke
			(width 0)
			(type solid)
		)
		(fill yes)
		(layer "In10.Cu")
		(net "P5E_PEX2_STN4_TX_DN<77>")
	)
	(gr_poly
		(pts
			(arc
				(start 308.203092 -311.099962)
				(mid 307.796692 -311.099962)
				(end 308.203092 -311.099962)
			)
		)
		(stroke
			(width 0)
			(type solid)
		)
		(fill yes)
		(layer "In10.Cu")
		(net "P5E_PEX2_STN4_TX_DP<77>")
	)
	(gr_poly
		(pts
			(arc
				(start 308.203092 -308.249828)
				(mid 307.796692 -308.249828)
				(end 308.203092 -308.249828)
			)
		)
		(stroke
			(width 0)
			(type solid)
		)
		(fill yes)
		(layer "In10.Cu")
		(net "P5E_PEX2_STN4_TX_DN<68>")
	)
	(gr_poly
		(pts
			(arc
				(start 308.203092 -306.349908)
				(mid 307.796692 -306.349908)
				(end 308.203092 -306.349908)
			)
		)
		(stroke
			(width 0)
			(type solid)
		)
		(fill yes)
		(layer "In10.Cu")
		(net "P5E_PEX2_STN4_TX_DN<66>")
	)
	(gr_poly
		(pts
			(arc
				(start 308.203092 -304.449734)
				(mid 307.796692 -304.449734)
				(end 308.203092 -304.449734)
			)
		)
		(stroke
			(width 0)
			(type solid)
		)
		(fill yes)
		(layer "In10.Cu")
		(net "P5E_PEX2_STN4_TX_DN<64>")
	)
	(gr_poly
		(pts
			(arc
				(start 309.153052 -318.699896)
				(mid 308.746652 -318.699896)
				(end 309.153052 -318.699896)
			)
		)
		(stroke
			(width 0)
			(type solid)
		)
		(fill yes)
		(layer "In10.Cu")
		(net "P5E_PEX2_STN4_RX_DN<76>")
	)
	(gr_poly
		(pts
			(arc
				(start 309.153052 -317.749936)
				(mid 308.746652 -317.749936)
				(end 309.153052 -317.749936)
			)
		)
		(stroke
			(width 0)
			(type solid)
		)
		(fill yes)
		(layer "In10.Cu")
		(net "P5E_PEX2_STN4_RX_DP<76>")
	)
	(gr_poly
		(pts
			(arc
				(start 309.153052 -313.949842)
				(mid 308.746652 -313.949842)
				(end 309.153052 -313.949842)
			)
		)
		(stroke
			(width 0)
			(type solid)
		)
		(fill yes)
		(layer "In10.Cu")
		(net "P5E_PEX2_STN4_TX_DN<76>")
	)
	(gr_poly
		(pts
			(arc
				(start 309.153052 -312.999882)
				(mid 308.746652 -312.999882)
				(end 309.153052 -312.999882)
			)
		)
		(stroke
			(width 0)
			(type solid)
		)
		(fill yes)
		(layer "In10.Cu")
		(net "P5E_PEX2_STN4_TX_DP<76>")
	)
	(gr_poly
		(pts
			(arc
				(start 309.153052 -309.199788)
				(mid 308.746652 -309.199788)
				(end 309.153052 -309.199788)
			)
		)
		(stroke
			(width 0)
			(type solid)
		)
		(fill yes)
		(layer "In10.Cu")
		(net "P5E_PEX2_STN4_TX_DP<69>")
	)
	(gr_poly
		(pts
			(arc
				(start 309.153052 -307.299868)
				(mid 308.746652 -307.299868)
				(end 309.153052 -307.299868)
			)
		)
		(stroke
			(width 0)
			(type solid)
		)
		(fill yes)
		(layer "In10.Cu")
		(net "P5E_PEX2_STN4_TX_DP<67>")
	)
	(gr_poly
		(pts
			(arc
				(start 309.153052 -305.399948)
				(mid 308.746652 -305.399948)
				(end 309.153052 -305.399948)
			)
		)
		(stroke
			(width 0)
			(type solid)
		)
		(fill yes)
		(layer "In10.Cu")
		(net "P5E_PEX2_STN4_TX_DP<65>")
	)
	(gr_poly
		(pts
			(arc
				(start 310.103012 -316.799722)
				(mid 309.696612 -316.799722)
				(end 310.103012 -316.799722)
			)
		)
		(stroke
			(width 0)
			(type solid)
		)
		(fill yes)
		(layer "In10.Cu")
		(net "P5E_PEX2_STN4_RX_DN<75>")
	)
	(gr_poly
		(pts
			(arc
				(start 310.103012 -315.849762)
				(mid 309.696612 -315.849762)
				(end 310.103012 -315.849762)
			)
		)
		(stroke
			(width 0)
			(type solid)
		)
		(fill yes)
		(layer "In10.Cu")
		(net "P5E_PEX2_STN4_RX_DP<75>")
	)
	(gr_poly
		(pts
			(arc
				(start 310.103012 -312.049922)
				(mid 309.696612 -312.049922)
				(end 310.103012 -312.049922)
			)
		)
		(stroke
			(width 0)
			(type solid)
		)
		(fill yes)
		(layer "In10.Cu")
		(net "P5E_PEX2_STN4_TX_DN<75>")
	)
	(gr_poly
		(pts
			(arc
				(start 310.103012 -311.099962)
				(mid 309.696612 -311.099962)
				(end 310.103012 -311.099962)
			)
		)
		(stroke
			(width 0)
			(type solid)
		)
		(fill yes)
		(layer "In10.Cu")
		(net "P5E_PEX2_STN4_TX_DP<75>")
	)
	(gr_poly
		(pts
			(arc
				(start 310.103012 -309.199788)
				(mid 309.696612 -309.199788)
				(end 310.103012 -309.199788)
			)
		)
		(stroke
			(width 0)
			(type solid)
		)
		(fill yes)
		(layer "In10.Cu")
		(net "P5E_PEX2_STN4_TX_DN<69>")
	)
	(gr_poly
		(pts
			(arc
				(start 310.103012 -307.299868)
				(mid 309.696612 -307.299868)
				(end 310.103012 -307.299868)
			)
		)
		(stroke
			(width 0)
			(type solid)
		)
		(fill yes)
		(layer "In10.Cu")
		(net "P5E_PEX2_STN4_TX_DN<67>")
	)
	(gr_poly
		(pts
			(arc
				(start 310.103012 -305.399948)
				(mid 309.696612 -305.399948)
				(end 310.103012 -305.399948)
			)
		)
		(stroke
			(width 0)
			(type solid)
		)
		(fill yes)
		(layer "In10.Cu")
		(net "P5E_PEX2_STN4_TX_DN<65>")
	)
	(gr_poly
		(pts
			(arc
				(start 311.052972 -318.699896)
				(mid 310.646572 -318.699896)
				(end 311.052972 -318.699896)
			)
		)
		(stroke
			(width 0)
			(type solid)
		)
		(fill yes)
		(layer "In10.Cu")
		(net "P5E_PEX2_STN4_RX_DN<74>")
	)
	(gr_poly
		(pts
			(arc
				(start 311.052972 -317.749936)
				(mid 310.646572 -317.749936)
				(end 311.052972 -317.749936)
			)
		)
		(stroke
			(width 0)
			(type solid)
		)
		(fill yes)
		(layer "In10.Cu")
		(net "P5E_PEX2_STN4_RX_DP<74>")
	)
	(gr_poly
		(pts
			(arc
				(start 311.052972 -313.949842)
				(mid 310.646572 -313.949842)
				(end 311.052972 -313.949842)
			)
		)
		(stroke
			(width 0)
			(type solid)
		)
		(fill yes)
		(layer "In10.Cu")
		(net "P5E_PEX2_STN4_TX_DN<74>")
	)
	(gr_poly
		(pts
			(arc
				(start 311.052972 -312.999882)
				(mid 310.646572 -312.999882)
				(end 311.052972 -312.999882)
			)
		)
		(stroke
			(width 0)
			(type solid)
		)
		(fill yes)
		(layer "In10.Cu")
		(net "P5E_PEX2_STN4_TX_DP<74>")
	)
	(gr_poly
		(pts
			(arc
				(start 312.002932 -316.799722)
				(mid 311.596532 -316.799722)
				(end 312.002932 -316.799722)
			)
		)
		(stroke
			(width 0)
			(type solid)
		)
		(fill yes)
		(layer "In10.Cu")
		(net "P5E_PEX2_STN4_RX_DN<73>")
	)
	(gr_poly
		(pts
			(arc
				(start 312.002932 -315.849762)
				(mid 311.596532 -315.849762)
				(end 312.002932 -315.849762)
			)
		)
		(stroke
			(width 0)
			(type solid)
		)
		(fill yes)
		(layer "In10.Cu")
		(net "P5E_PEX2_STN4_RX_DP<73>")
	)
	(gr_poly
		(pts
			(arc
				(start 312.002932 -312.049922)
				(mid 311.596532 -312.049922)
				(end 312.002932 -312.049922)
			)
		)
		(stroke
			(width 0)
			(type solid)
		)
		(fill yes)
		(layer "In10.Cu")
		(net "P5E_PEX2_STN4_TX_DN<73>")
	)
	(gr_poly
		(pts
			(arc
				(start 312.002932 -311.099962)
				(mid 311.596532 -311.099962)
				(end 312.002932 -311.099962)
			)
		)
		(stroke
			(width 0)
			(type solid)
		)
		(fill yes)
		(layer "In10.Cu")
		(net "P5E_PEX2_STN4_TX_DP<73>")
	)
	(gr_poly
		(pts
			(arc
				(start 312.002932 -309.199788)
				(mid 311.596532 -309.199788)
				(end 312.002932 -309.199788)
			)
		)
		(stroke
			(width 0)
			(type solid)
		)
		(fill yes)
		(layer "In10.Cu")
		(net "P5E_PEX2_STN4_RX_DP<69>")
	)
	(gr_poly
		(pts
			(arc
				(start 312.002932 -307.299868)
				(mid 311.596532 -307.299868)
				(end 312.002932 -307.299868)
			)
		)
		(stroke
			(width 0)
			(type solid)
		)
		(fill yes)
		(layer "In10.Cu")
		(net "P5E_PEX2_STN4_RX_DP<67>")
	)
	(gr_poly
		(pts
			(arc
				(start 312.002932 -305.399948)
				(mid 311.596532 -305.399948)
				(end 312.002932 -305.399948)
			)
		)
		(stroke
			(width 0)
			(type solid)
		)
		(fill yes)
		(layer "In10.Cu")
		(net "P5E_PEX2_STN4_RX_DP<65>")
	)
	(gr_poly
		(pts
			(arc
				(start 312.952892 -318.699896)
				(mid 312.546492 -318.699896)
				(end 312.952892 -318.699896)
			)
		)
		(stroke
			(width 0)
			(type solid)
		)
		(fill yes)
		(layer "In10.Cu")
		(net "P5E_PEX2_STN4_RX_DN<72>")
	)
	(gr_poly
		(pts
			(arc
				(start 312.952892 -317.749936)
				(mid 312.546492 -317.749936)
				(end 312.952892 -317.749936)
			)
		)
		(stroke
			(width 0)
			(type solid)
		)
		(fill yes)
		(layer "In10.Cu")
		(net "P5E_PEX2_STN4_RX_DP<72>")
	)
	(gr_poly
		(pts
			(arc
				(start 312.952892 -313.949842)
				(mid 312.546492 -313.949842)
				(end 312.952892 -313.949842)
			)
		)
		(stroke
			(width 0)
			(type solid)
		)
		(fill yes)
		(layer "In10.Cu")
		(net "P5E_PEX2_STN4_TX_DN<72>")
	)
	(gr_poly
		(pts
			(arc
				(start 312.952892 -312.999882)
				(mid 312.546492 -312.999882)
				(end 312.952892 -312.999882)
			)
		)
		(stroke
			(width 0)
			(type solid)
		)
		(fill yes)
		(layer "In10.Cu")
		(net "P5E_PEX2_STN4_TX_DP<72>")
	)
	(gr_poly
		(pts
			(arc
				(start 312.952892 -309.199788)
				(mid 312.546492 -309.199788)
				(end 312.952892 -309.199788)
			)
		)
		(stroke
			(width 0)
			(type solid)
		)
		(fill yes)
		(layer "In10.Cu")
		(net "P5E_PEX2_STN4_RX_DN<69>")
	)
	(gr_poly
		(pts
			(arc
				(start 312.952892 -307.299868)
				(mid 312.546492 -307.299868)
				(end 312.952892 -307.299868)
			)
		)
		(stroke
			(width 0)
			(type solid)
		)
		(fill yes)
		(layer "In10.Cu")
		(net "P5E_PEX2_STN4_RX_DN<67>")
	)
	(gr_poly
		(pts
			(arc
				(start 312.952892 -305.399948)
				(mid 312.546492 -305.399948)
				(end 312.952892 -305.399948)
			)
		)
		(stroke
			(width 0)
			(type solid)
		)
		(fill yes)
		(layer "In10.Cu")
		(net "P5E_PEX2_STN4_RX_DN<65>")
	)
	(gr_poly
		(pts
			(arc
				(start 313.903106 -316.799722)
				(mid 313.496706 -316.799722)
				(end 313.903106 -316.799722)
			)
		)
		(stroke
			(width 0)
			(type solid)
		)
		(fill yes)
		(layer "In10.Cu")
		(net "P5E_PEX2_STN4_RX_DP<71>")
	)
	(gr_poly
		(pts
			(arc
				(start 313.903106 -314.899802)
				(mid 313.496706 -314.899802)
				(end 313.903106 -314.899802)
			)
		)
		(stroke
			(width 0)
			(type solid)
		)
		(fill yes)
		(layer "In10.Cu")
		(net "P5E_PEX2_STN4_TX_DP<71>")
	)
	(gr_poly
		(pts
			(arc
				(start 313.903106 -312.049922)
				(mid 313.496706 -312.049922)
				(end 313.903106 -312.049922)
			)
		)
		(stroke
			(width 0)
			(type solid)
		)
		(fill yes)
		(layer "In10.Cu")
		(net "P5E_PEX2_STN4_TX_DP<70>")
	)
	(gr_poly
		(pts
			(arc
				(start 313.903106 -310.149748)
				(mid 313.496706 -310.149748)
				(end 313.903106 -310.149748)
			)
		)
		(stroke
			(width 0)
			(type solid)
		)
		(fill yes)
		(layer "In10.Cu")
		(net "P5E_PEX2_STN4_RX_DP<70>")
	)
	(gr_poly
		(pts
			(arc
				(start 313.903106 -308.249828)
				(mid 313.496706 -308.249828)
				(end 313.903106 -308.249828)
			)
		)
		(stroke
			(width 0)
			(type solid)
		)
		(fill yes)
		(layer "In10.Cu")
		(net "P5E_PEX2_STN4_RX_DP<68>")
	)
	(gr_poly
		(pts
			(arc
				(start 313.903106 -306.349908)
				(mid 313.496706 -306.349908)
				(end 313.903106 -306.349908)
			)
		)
		(stroke
			(width 0)
			(type solid)
		)
		(fill yes)
		(layer "In10.Cu")
		(net "P5E_PEX2_STN4_RX_DP<66>")
	)
	(gr_poly
		(pts
			(arc
				(start 313.903106 -304.449734)
				(mid 313.496706 -304.449734)
				(end 313.903106 -304.449734)
			)
		)
		(stroke
			(width 0)
			(type solid)
		)
		(fill yes)
		(layer "In10.Cu")
		(net "P5E_PEX2_STN4_RX_DP<64>")
	)
	(gr_poly
		(pts
			(arc
				(start 314.853066 -316.799722)
				(mid 314.446666 -316.799722)
				(end 314.853066 -316.799722)
			)
		)
		(stroke
			(width 0)
			(type solid)
		)
		(fill yes)
		(layer "In10.Cu")
		(net "P5E_PEX2_STN4_RX_DN<71>")
	)
	(gr_poly
		(pts
			(arc
				(start 314.853066 -314.899802)
				(mid 314.446666 -314.899802)
				(end 314.853066 -314.899802)
			)
		)
		(stroke
			(width 0)
			(type solid)
		)
		(fill yes)
		(layer "In10.Cu")
		(net "P5E_PEX2_STN4_TX_DN<71>")
	)
	(gr_poly
		(pts
			(arc
				(start 314.853066 -312.049922)
				(mid 314.446666 -312.049922)
				(end 314.853066 -312.049922)
			)
		)
		(stroke
			(width 0)
			(type solid)
		)
		(fill yes)
		(layer "In10.Cu")
		(net "P5E_PEX2_STN4_TX_DN<70>")
	)
	(gr_poly
		(pts
			(arc
				(start 314.853066 -310.149748)
				(mid 314.446666 -310.149748)
				(end 314.853066 -310.149748)
			)
		)
		(stroke
			(width 0)
			(type solid)
		)
		(fill yes)
		(layer "In10.Cu")
		(net "P5E_PEX2_STN4_RX_DN<70>")
	)
	(gr_poly
		(pts
			(arc
				(start 314.853066 -308.249828)
				(mid 314.446666 -308.249828)
				(end 314.853066 -308.249828)
			)
		)
		(stroke
			(width 0)
			(type solid)
		)
		(fill yes)
		(layer "In10.Cu")
		(net "P5E_PEX2_STN4_RX_DN<68>")
	)
	(gr_poly
		(pts
			(arc
				(start 314.853066 -306.349908)
				(mid 314.446666 -306.349908)
				(end 314.853066 -306.349908)
			)
		)
		(stroke
			(width 0)
			(type solid)
		)
		(fill yes)
		(layer "In10.Cu")
		(net "P5E_PEX2_STN4_RX_DN<66>")
	)
	(gr_poly
		(pts
			(arc
				(start 314.853066 -304.449734)
				(mid 314.446666 -304.449734)
				(end 314.853066 -304.449734)
			)
		)
		(stroke
			(width 0)
			(type solid)
		)
		(fill yes)
		(layer "In10.Cu")
		(net "P5E_PEX2_STN4_RX_DN<64>")
	)
	(gr_poly
		(pts
			(arc
				(start 385.353052 -314.899802)
				(mid 384.946652 -314.899802)
				(end 385.353052 -314.899802)
			)
		)
		(stroke
			(width 0)
			(type solid)
		)
		(fill yes)
		(layer "In10.Cu")
		(net "P5E_PEX3_STN7_TX_DN<122>")
	)
	(gr_poly
		(pts
			(arc
				(start 385.353052 -312.049922)
				(mid 384.946652 -312.049922)
				(end 385.353052 -312.049922)
			)
		)
		(stroke
			(width 0)
			(type solid)
		)
		(fill yes)
		(layer "In10.Cu")
		(net "P5E_PEX3_STN7_TX_DN<121>")
	)
	(gr_poly
		(pts
			(arc
				(start 386.303012 -314.899802)
				(mid 385.896612 -314.899802)
				(end 386.303012 -314.899802)
			)
		)
		(stroke
			(width 0)
			(type solid)
		)
		(fill yes)
		(layer "In10.Cu")
		(net "P5E_PEX3_STN7_TX_DP<122>")
	)
	(gr_poly
		(pts
			(arc
				(start 386.303012 -312.049922)
				(mid 385.896612 -312.049922)
				(end 386.303012 -312.049922)
			)
		)
		(stroke
			(width 0)
			(type solid)
		)
		(fill yes)
		(layer "In10.Cu")
		(net "P5E_PEX3_STN7_TX_DP<121>")
	)
	(gr_poly
		(pts
			(arc
				(start 387.253226 -313.949842)
				(mid 386.846826 -313.949842)
				(end 387.253226 -313.949842)
			)
		)
		(stroke
			(width 0)
			(type solid)
		)
		(fill yes)
		(layer "In10.Cu")
		(net "P5E_PEX3_STN7_TX_DN<123>")
	)
	(gr_poly
		(pts
			(arc
				(start 387.253226 -312.999882)
				(mid 386.846826 -312.999882)
				(end 387.253226 -312.999882)
			)
		)
		(stroke
			(width 0)
			(type solid)
		)
		(fill yes)
		(layer "In10.Cu")
		(net "P5E_PEX3_STN7_TX_DP<123>")
	)
	(gr_poly
		(pts
			(arc
				(start 388.203186 -312.049922)
				(mid 387.796786 -312.049922)
				(end 388.203186 -312.049922)
			)
		)
		(stroke
			(width 0)
			(type solid)
		)
		(fill yes)
		(layer "In10.Cu")
		(net "P5E_PEX3_STN7_TX_DN<124>")
	)
	(gr_poly
		(pts
			(arc
				(start 388.203186 -311.099962)
				(mid 387.796786 -311.099962)
				(end 388.203186 -311.099962)
			)
		)
		(stroke
			(width 0)
			(type solid)
		)
		(fill yes)
		(layer "In10.Cu")
		(net "P5E_PEX3_STN7_TX_DP<124>")
	)
	(gr_poly
		(pts
			(arc
				(start 389.153146 -313.949842)
				(mid 388.746746 -313.949842)
				(end 389.153146 -313.949842)
			)
		)
		(stroke
			(width 0)
			(type solid)
		)
		(fill yes)
		(layer "In10.Cu")
		(net "P5E_PEX3_STN7_TX_DN<125>")
	)
	(gr_poly
		(pts
			(arc
				(start 389.153146 -312.999882)
				(mid 388.746746 -312.999882)
				(end 389.153146 -312.999882)
			)
		)
		(stroke
			(width 0)
			(type solid)
		)
		(fill yes)
		(layer "In10.Cu")
		(net "P5E_PEX3_STN7_TX_DP<125>")
	)
	(gr_poly
		(pts
			(arc
				(start 390.103106 -312.049922)
				(mid 389.696706 -312.049922)
				(end 390.103106 -312.049922)
			)
		)
		(stroke
			(width 0)
			(type solid)
		)
		(fill yes)
		(layer "In10.Cu")
		(net "P5E_PEX3_STN7_TX_DN<126>")
	)
	(gr_poly
		(pts
			(arc
				(start 390.103106 -311.099962)
				(mid 389.696706 -311.099962)
				(end 390.103106 -311.099962)
			)
		)
		(stroke
			(width 0)
			(type solid)
		)
		(fill yes)
		(layer "In10.Cu")
		(net "P5E_PEX3_STN7_TX_DP<126>")
	)
	(gr_poly
		(pts
			(arc
				(start 390.103106 -309.199788)
				(mid 389.696706 -309.199788)
				(end 390.103106 -309.199788)
			)
		)
		(stroke
			(width 0)
			(type solid)
		)
		(fill yes)
		(layer "In10.Cu")
		(net "P5E_PEX3_STN7_TX_DN<120>")
	)
	(gr_poly
		(pts
			(arc
				(start 390.103106 -307.299868)
				(mid 389.696706 -307.299868)
				(end 390.103106 -307.299868)
			)
		)
		(stroke
			(width 0)
			(type solid)
		)
		(fill yes)
		(layer "In10.Cu")
		(net "P5E_PEX3_STN7_TX_DN<118>")
	)
	(gr_poly
		(pts
			(arc
				(start 390.103106 -305.399948)
				(mid 389.696706 -305.399948)
				(end 390.103106 -305.399948)
			)
		)
		(stroke
			(width 0)
			(type solid)
		)
		(fill yes)
		(layer "In10.Cu")
		(net "P5E_PEX3_STN7_TX_DN<116>")
	)
	(gr_poly
		(pts
			(arc
				(start 390.103106 -303.499774)
				(mid 389.696706 -303.499774)
				(end 390.103106 -303.499774)
			)
		)
		(stroke
			(width 0)
			(type solid)
		)
		(fill yes)
		(layer "In10.Cu")
		(net "P5E_PEX3_STN7_TX_DN<114>")
	)
	(gr_poly
		(pts
			(arc
				(start 390.103106 -301.599854)
				(mid 389.696706 -301.599854)
				(end 390.103106 -301.599854)
			)
		)
		(stroke
			(width 0)
			(type solid)
		)
		(fill yes)
		(layer "In10.Cu")
		(net "P5E_PEX3_STN7_TX_DN<112>")
	)
	(gr_poly
		(pts
			(arc
				(start 391.053066 -313.949842)
				(mid 390.646666 -313.949842)
				(end 391.053066 -313.949842)
			)
		)
		(stroke
			(width 0)
			(type solid)
		)
		(fill yes)
		(layer "In10.Cu")
		(net "P5E_PEX3_STN7_TX_DN<127>")
	)
	(gr_poly
		(pts
			(arc
				(start 391.053066 -312.999882)
				(mid 390.646666 -312.999882)
				(end 391.053066 -312.999882)
			)
		)
		(stroke
			(width 0)
			(type solid)
		)
		(fill yes)
		(layer "In10.Cu")
		(net "P5E_PEX3_STN7_TX_DP<127>")
	)
	(gr_poly
		(pts
			(arc
				(start 391.053066 -309.199788)
				(mid 390.646666 -309.199788)
				(end 391.053066 -309.199788)
			)
		)
		(stroke
			(width 0)
			(type solid)
		)
		(fill yes)
		(layer "In10.Cu")
		(net "P5E_PEX3_STN7_TX_DP<120>")
	)
	(gr_poly
		(pts
			(arc
				(start 391.053066 -307.299868)
				(mid 390.646666 -307.299868)
				(end 391.053066 -307.299868)
			)
		)
		(stroke
			(width 0)
			(type solid)
		)
		(fill yes)
		(layer "In10.Cu")
		(net "P5E_PEX3_STN7_TX_DP<118>")
	)
	(gr_poly
		(pts
			(arc
				(start 391.053066 -305.399948)
				(mid 390.646666 -305.399948)
				(end 391.053066 -305.399948)
			)
		)
		(stroke
			(width 0)
			(type solid)
		)
		(fill yes)
		(layer "In10.Cu")
		(net "P5E_PEX3_STN7_TX_DP<116>")
	)
	(gr_poly
		(pts
			(arc
				(start 391.053066 -303.499774)
				(mid 390.646666 -303.499774)
				(end 391.053066 -303.499774)
			)
		)
		(stroke
			(width 0)
			(type solid)
		)
		(fill yes)
		(layer "In10.Cu")
		(net "P5E_PEX3_STN7_TX_DP<114>")
	)
	(gr_poly
		(pts
			(arc
				(start 391.053066 -301.599854)
				(mid 390.646666 -301.599854)
				(end 391.053066 -301.599854)
			)
		)
		(stroke
			(width 0)
			(type solid)
		)
		(fill yes)
		(layer "In10.Cu")
		(net "P5E_PEX3_STN7_TX_DP<112>")
	)
	(gr_poly
		(pts
			(arc
				(start 392.003026 -316.799722)
				(mid 391.596626 -316.799722)
				(end 392.003026 -316.799722)
			)
		)
		(stroke
			(width 0)
			(type solid)
		)
		(fill yes)
		(layer "In10.Cu")
		(net "P5E_PEX3_STN6_RX_DN<111>")
	)
	(gr_poly
		(pts
			(arc
				(start 392.003026 -315.849762)
				(mid 391.596626 -315.849762)
				(end 392.003026 -315.849762)
			)
		)
		(stroke
			(width 0)
			(type solid)
		)
		(fill yes)
		(layer "In10.Cu")
		(net "P5E_PEX3_STN6_RX_DP<111>")
	)
	(gr_poly
		(pts
			(arc
				(start 392.003026 -312.049922)
				(mid 391.596626 -312.049922)
				(end 392.003026 -312.049922)
			)
		)
		(stroke
			(width 0)
			(type solid)
		)
		(fill yes)
		(layer "In10.Cu")
		(net "P5E_PEX3_STN6_TX_DN<111>")
	)
	(gr_poly
		(pts
			(arc
				(start 392.003026 -311.099962)
				(mid 391.596626 -311.099962)
				(end 392.003026 -311.099962)
			)
		)
		(stroke
			(width 0)
			(type solid)
		)
		(fill yes)
		(layer "In10.Cu")
		(net "P5E_PEX3_STN6_TX_DP<111>")
	)
	(gr_poly
		(pts
			(arc
				(start 392.003026 -308.249828)
				(mid 391.596626 -308.249828)
				(end 392.003026 -308.249828)
			)
		)
		(stroke
			(width 0)
			(type solid)
		)
		(fill yes)
		(layer "In10.Cu")
		(net "P5E_PEX3_STN7_TX_DN<119>")
	)
	(gr_poly
		(pts
			(arc
				(start 392.003026 -306.349908)
				(mid 391.596626 -306.349908)
				(end 392.003026 -306.349908)
			)
		)
		(stroke
			(width 0)
			(type solid)
		)
		(fill yes)
		(layer "In10.Cu")
		(net "P5E_PEX3_STN7_TX_DN<117>")
	)
	(gr_poly
		(pts
			(arc
				(start 392.003026 -304.449734)
				(mid 391.596626 -304.449734)
				(end 392.003026 -304.449734)
			)
		)
		(stroke
			(width 0)
			(type solid)
		)
		(fill yes)
		(layer "In10.Cu")
		(net "P5E_PEX3_STN7_TX_DN<115>")
	)
	(gr_poly
		(pts
			(arc
				(start 392.003026 -302.549814)
				(mid 391.596626 -302.549814)
				(end 392.003026 -302.549814)
			)
		)
		(stroke
			(width 0)
			(type solid)
		)
		(fill yes)
		(layer "In10.Cu")
		(net "P5E_PEX3_STN7_TX_DN<113>")
	)
	(gr_poly
		(pts
			(arc
				(start 392.952986 -318.699896)
				(mid 392.546586 -318.699896)
				(end 392.952986 -318.699896)
			)
		)
		(stroke
			(width 0)
			(type solid)
		)
		(fill yes)
		(layer "In10.Cu")
		(net "P5E_PEX3_STN6_RX_DN<110>")
	)
	(gr_poly
		(pts
			(arc
				(start 392.952986 -317.749936)
				(mid 392.546586 -317.749936)
				(end 392.952986 -317.749936)
			)
		)
		(stroke
			(width 0)
			(type solid)
		)
		(fill yes)
		(layer "In10.Cu")
		(net "P5E_PEX3_STN6_RX_DP<110>")
	)
	(gr_poly
		(pts
			(arc
				(start 392.952986 -313.949842)
				(mid 392.546586 -313.949842)
				(end 392.952986 -313.949842)
			)
		)
		(stroke
			(width 0)
			(type solid)
		)
		(fill yes)
		(layer "In10.Cu")
		(net "P5E_PEX3_STN6_TX_DN<110>")
	)
	(gr_poly
		(pts
			(arc
				(start 392.952986 -312.999882)
				(mid 392.546586 -312.999882)
				(end 392.952986 -312.999882)
			)
		)
		(stroke
			(width 0)
			(type solid)
		)
		(fill yes)
		(layer "In10.Cu")
		(net "P5E_PEX3_STN6_TX_DP<110>")
	)
	(gr_poly
		(pts
			(arc
				(start 392.952986 -308.249828)
				(mid 392.546586 -308.249828)
				(end 392.952986 -308.249828)
			)
		)
		(stroke
			(width 0)
			(type solid)
		)
		(fill yes)
		(layer "In10.Cu")
		(net "P5E_PEX3_STN7_TX_DP<119>")
	)
	(gr_poly
		(pts
			(arc
				(start 392.952986 -306.349908)
				(mid 392.546586 -306.349908)
				(end 392.952986 -306.349908)
			)
		)
		(stroke
			(width 0)
			(type solid)
		)
		(fill yes)
		(layer "In10.Cu")
		(net "P5E_PEX3_STN7_TX_DP<117>")
	)
	(gr_poly
		(pts
			(arc
				(start 392.952986 -304.449734)
				(mid 392.546586 -304.449734)
				(end 392.952986 -304.449734)
			)
		)
		(stroke
			(width 0)
			(type solid)
		)
		(fill yes)
		(layer "In10.Cu")
		(net "P5E_PEX3_STN7_TX_DP<115>")
	)
	(gr_poly
		(pts
			(arc
				(start 392.952986 -302.549814)
				(mid 392.546586 -302.549814)
				(end 392.952986 -302.549814)
			)
		)
		(stroke
			(width 0)
			(type solid)
		)
		(fill yes)
		(layer "In10.Cu")
		(net "P5E_PEX3_STN7_TX_DP<113>")
	)
	(gr_poly
		(pts
			(arc
				(start 392.952986 -278.799798)
				(mid 392.546586 -278.799798)
				(end 392.952986 -278.799798)
			)
		)
		(stroke
			(width 0)
			(type solid)
		)
		(fill yes)
		(layer "In10.Cu")
		(net "P5E_PEX3_STN2_TX_DP<47>")
	)
	(gr_poly
		(pts
			(arc
				(start 392.952986 -277.849838)
				(mid 392.546586 -277.849838)
				(end 392.952986 -277.849838)
			)
		)
		(stroke
			(width 0)
			(type solid)
		)
		(fill yes)
		(layer "In10.Cu")
		(net "P5E_PEX3_STN2_TX_DN<47>")
	)
	(gr_poly
		(pts
			(arc
				(start 393.9032 -316.799722)
				(mid 393.4968 -316.799722)
				(end 393.9032 -316.799722)
			)
		)
		(stroke
			(width 0)
			(type solid)
		)
		(fill yes)
		(layer "In10.Cu")
		(net "P5E_PEX3_STN6_RX_DN<109>")
	)
	(gr_poly
		(pts
			(arc
				(start 393.9032 -315.849762)
				(mid 393.4968 -315.849762)
				(end 393.9032 -315.849762)
			)
		)
		(stroke
			(width 0)
			(type solid)
		)
		(fill yes)
		(layer "In10.Cu")
		(net "P5E_PEX3_STN6_RX_DP<109>")
	)
	(gr_poly
		(pts
			(arc
				(start 393.9032 -312.049922)
				(mid 393.4968 -312.049922)
				(end 393.9032 -312.049922)
			)
		)
		(stroke
			(width 0)
			(type solid)
		)
		(fill yes)
		(layer "In10.Cu")
		(net "P5E_PEX3_STN6_TX_DN<109>")
	)
	(gr_poly
		(pts
			(arc
				(start 393.9032 -311.099962)
				(mid 393.4968 -311.099962)
				(end 393.9032 -311.099962)
			)
		)
		(stroke
			(width 0)
			(type solid)
		)
		(fill yes)
		(layer "In10.Cu")
		(net "P5E_PEX3_STN6_TX_DP<109>")
	)
	(gr_poly
		(pts
			(arc
				(start 393.9032 -280.699464)
				(mid 393.4968 -280.699464)
				(end 393.9032 -280.699464)
			)
		)
		(stroke
			(width 0)
			(type solid)
		)
		(fill yes)
		(layer "In10.Cu")
		(net "P5E_PEX3_STN2_TX_DP<46>")
	)
	(gr_poly
		(pts
			(arc
				(start 393.9032 -279.749504)
				(mid 393.4968 -279.749504)
				(end 393.9032 -279.749504)
			)
		)
		(stroke
			(width 0)
			(type solid)
		)
		(fill yes)
		(layer "In10.Cu")
		(net "P5E_PEX3_STN2_TX_DN<46>")
	)
	(gr_poly
		(pts
			(arc
				(start 394.85316 -318.699896)
				(mid 394.44676 -318.699896)
				(end 394.85316 -318.699896)
			)
		)
		(stroke
			(width 0)
			(type solid)
		)
		(fill yes)
		(layer "In10.Cu")
		(net "P5E_PEX3_STN6_RX_DN<108>")
	)
	(gr_poly
		(pts
			(arc
				(start 394.85316 -317.749936)
				(mid 394.44676 -317.749936)
				(end 394.85316 -317.749936)
			)
		)
		(stroke
			(width 0)
			(type solid)
		)
		(fill yes)
		(layer "In10.Cu")
		(net "P5E_PEX3_STN6_RX_DP<108>")
	)
	(gr_poly
		(pts
			(arc
				(start 394.85316 -313.949842)
				(mid 394.44676 -313.949842)
				(end 394.85316 -313.949842)
			)
		)
		(stroke
			(width 0)
			(type solid)
		)
		(fill yes)
		(layer "In10.Cu")
		(net "P5E_PEX3_STN6_TX_DN<108>")
	)
	(gr_poly
		(pts
			(arc
				(start 394.85316 -312.999882)
				(mid 394.44676 -312.999882)
				(end 394.85316 -312.999882)
			)
		)
		(stroke
			(width 0)
			(type solid)
		)
		(fill yes)
		(layer "In10.Cu")
		(net "P5E_PEX3_STN6_TX_DP<108>")
	)
	(gr_poly
		(pts
			(arc
				(start 394.85316 -278.799798)
				(mid 394.44676 -278.799798)
				(end 394.85316 -278.799798)
			)
		)
		(stroke
			(width 0)
			(type solid)
		)
		(fill yes)
		(layer "In10.Cu")
		(net "P5E_PEX3_STN2_TX_DP<45>")
	)
	(gr_poly
		(pts
			(arc
				(start 394.85316 -277.849838)
				(mid 394.44676 -277.849838)
				(end 394.85316 -277.849838)
			)
		)
		(stroke
			(width 0)
			(type solid)
		)
		(fill yes)
		(layer "In10.Cu")
		(net "P5E_PEX3_STN2_TX_DN<45>")
	)
	(gr_poly
		(pts
			(arc
				(start 395.80312 -316.799722)
				(mid 395.39672 -316.799722)
				(end 395.80312 -316.799722)
			)
		)
		(stroke
			(width 0)
			(type solid)
		)
		(fill yes)
		(layer "In10.Cu")
		(net "P5E_PEX3_STN6_RX_DN<107>")
	)
	(gr_poly
		(pts
			(arc
				(start 395.80312 -315.849762)
				(mid 395.39672 -315.849762)
				(end 395.80312 -315.849762)
			)
		)
		(stroke
			(width 0)
			(type solid)
		)
		(fill yes)
		(layer "In10.Cu")
		(net "P5E_PEX3_STN6_RX_DP<107>")
	)
	(gr_poly
		(pts
			(arc
				(start 395.80312 -312.049922)
				(mid 395.39672 -312.049922)
				(end 395.80312 -312.049922)
			)
		)
		(stroke
			(width 0)
			(type solid)
		)
		(fill yes)
		(layer "In10.Cu")
		(net "P5E_PEX3_STN6_TX_DN<107>")
	)
	(gr_poly
		(pts
			(arc
				(start 395.80312 -311.099962)
				(mid 395.39672 -311.099962)
				(end 395.80312 -311.099962)
			)
		)
		(stroke
			(width 0)
			(type solid)
		)
		(fill yes)
		(layer "In10.Cu")
		(net "P5E_PEX3_STN6_TX_DP<107>")
	)
	(gr_poly
		(pts
			(arc
				(start 395.80312 -280.699464)
				(mid 395.39672 -280.699464)
				(end 395.80312 -280.699464)
			)
		)
		(stroke
			(width 0)
			(type solid)
		)
		(fill yes)
		(layer "In10.Cu")
		(net "P5E_PEX3_STN2_TX_DP<44>")
	)
	(gr_poly
		(pts
			(arc
				(start 395.80312 -279.749504)
				(mid 395.39672 -279.749504)
				(end 395.80312 -279.749504)
			)
		)
		(stroke
			(width 0)
			(type solid)
		)
		(fill yes)
		(layer "In10.Cu")
		(net "P5E_PEX3_STN2_TX_DN<44>")
	)
	(gr_poly
		(pts
			(arc
				(start 396.75308 -318.699896)
				(mid 396.34668 -318.699896)
				(end 396.75308 -318.699896)
			)
		)
		(stroke
			(width 0)
			(type solid)
		)
		(fill yes)
		(layer "In10.Cu")
		(net "P5E_PEX3_STN6_RX_DN<106>")
	)
	(gr_poly
		(pts
			(arc
				(start 396.75308 -317.749936)
				(mid 396.34668 -317.749936)
				(end 396.75308 -317.749936)
			)
		)
		(stroke
			(width 0)
			(type solid)
		)
		(fill yes)
		(layer "In10.Cu")
		(net "P5E_PEX3_STN6_RX_DP<106>")
	)
	(gr_poly
		(pts
			(arc
				(start 396.75308 -313.949842)
				(mid 396.34668 -313.949842)
				(end 396.75308 -313.949842)
			)
		)
		(stroke
			(width 0)
			(type solid)
		)
		(fill yes)
		(layer "In10.Cu")
		(net "P5E_PEX3_STN6_TX_DN<106>")
	)
	(gr_poly
		(pts
			(arc
				(start 396.75308 -312.999882)
				(mid 396.34668 -312.999882)
				(end 396.75308 -312.999882)
			)
		)
		(stroke
			(width 0)
			(type solid)
		)
		(fill yes)
		(layer "In10.Cu")
		(net "P5E_PEX3_STN6_TX_DP<106>")
	)
	(gr_poly
		(pts
			(arc
				(start 396.75308 -278.799798)
				(mid 396.34668 -278.799798)
				(end 396.75308 -278.799798)
			)
		)
		(stroke
			(width 0)
			(type solid)
		)
		(fill yes)
		(layer "In10.Cu")
		(net "P5E_PEX3_STN2_TX_DP<43>")
	)
	(gr_poly
		(pts
			(arc
				(start 396.75308 -277.849838)
				(mid 396.34668 -277.849838)
				(end 396.75308 -277.849838)
			)
		)
		(stroke
			(width 0)
			(type solid)
		)
		(fill yes)
		(layer "In10.Cu")
		(net "P5E_PEX3_STN2_TX_DN<43>")
	)
	(gr_poly
		(pts
			(arc
				(start 397.70304 -316.799722)
				(mid 397.29664 -316.799722)
				(end 397.70304 -316.799722)
			)
		)
		(stroke
			(width 0)
			(type solid)
		)
		(fill yes)
		(layer "In10.Cu")
		(net "P5E_PEX3_STN6_RX_DN<105>")
	)
	(gr_poly
		(pts
			(arc
				(start 397.70304 -315.849762)
				(mid 397.29664 -315.849762)
				(end 397.70304 -315.849762)
			)
		)
		(stroke
			(width 0)
			(type solid)
		)
		(fill yes)
		(layer "In10.Cu")
		(net "P5E_PEX3_STN6_RX_DP<105>")
	)
	(gr_poly
		(pts
			(arc
				(start 397.70304 -312.049922)
				(mid 397.29664 -312.049922)
				(end 397.70304 -312.049922)
			)
		)
		(stroke
			(width 0)
			(type solid)
		)
		(fill yes)
		(layer "In10.Cu")
		(net "P5E_PEX3_STN6_TX_DN<105>")
	)
	(gr_poly
		(pts
			(arc
				(start 397.70304 -311.099962)
				(mid 397.29664 -311.099962)
				(end 397.70304 -311.099962)
			)
		)
		(stroke
			(width 0)
			(type solid)
		)
		(fill yes)
		(layer "In10.Cu")
		(net "P5E_PEX3_STN6_TX_DP<105>")
	)
	(gr_poly
		(pts
			(arc
				(start 397.70304 -280.699464)
				(mid 397.29664 -280.699464)
				(end 397.70304 -280.699464)
			)
		)
		(stroke
			(width 0)
			(type solid)
		)
		(fill yes)
		(layer "In10.Cu")
		(net "P5E_PEX3_STN2_TX_DP<42>")
	)
	(gr_poly
		(pts
			(arc
				(start 397.70304 -279.749504)
				(mid 397.29664 -279.749504)
				(end 397.70304 -279.749504)
			)
		)
		(stroke
			(width 0)
			(type solid)
		)
		(fill yes)
		(layer "In10.Cu")
		(net "P5E_PEX3_STN2_TX_DN<42>")
	)
	(gr_poly
		(pts
			(arc
				(start 398.653 -318.699896)
				(mid 398.2466 -318.699896)
				(end 398.653 -318.699896)
			)
		)
		(stroke
			(width 0)
			(type solid)
		)
		(fill yes)
		(layer "In10.Cu")
		(net "P5E_PEX3_STN6_RX_DN<104>")
	)
	(gr_poly
		(pts
			(arc
				(start 398.653 -317.749936)
				(mid 398.2466 -317.749936)
				(end 398.653 -317.749936)
			)
		)
		(stroke
			(width 0)
			(type solid)
		)
		(fill yes)
		(layer "In10.Cu")
		(net "P5E_PEX3_STN6_RX_DP<104>")
	)
	(gr_poly
		(pts
			(arc
				(start 398.653 -313.949842)
				(mid 398.2466 -313.949842)
				(end 398.653 -313.949842)
			)
		)
		(stroke
			(width 0)
			(type solid)
		)
		(fill yes)
		(layer "In10.Cu")
		(net "P5E_PEX3_STN6_TX_DN<104>")
	)
	(gr_poly
		(pts
			(arc
				(start 398.653 -312.999882)
				(mid 398.2466 -312.999882)
				(end 398.653 -312.999882)
			)
		)
		(stroke
			(width 0)
			(type solid)
		)
		(fill yes)
		(layer "In10.Cu")
		(net "P5E_PEX3_STN6_TX_DP<104>")
	)
	(gr_poly
		(pts
			(arc
				(start 398.653 -278.799798)
				(mid 398.2466 -278.799798)
				(end 398.653 -278.799798)
			)
		)
		(stroke
			(width 0)
			(type solid)
		)
		(fill yes)
		(layer "In10.Cu")
		(net "P5E_PEX3_STN2_TX_DP<41>")
	)
	(gr_poly
		(pts
			(arc
				(start 398.653 -277.849838)
				(mid 398.2466 -277.849838)
				(end 398.653 -277.849838)
			)
		)
		(stroke
			(width 0)
			(type solid)
		)
		(fill yes)
		(layer "In10.Cu")
		(net "P5E_PEX3_STN2_TX_DN<41>")
	)
	(gr_poly
		(pts
			(arc
				(start 399.603214 -280.699464)
				(mid 399.196814 -280.699464)
				(end 399.603214 -280.699464)
			)
		)
		(stroke
			(width 0)
			(type solid)
		)
		(fill yes)
		(layer "In10.Cu")
		(net "P5E_PEX3_STN2_TX_DP<40>")
	)
	(gr_poly
		(pts
			(arc
				(start 399.603214 -279.749504)
				(mid 399.196814 -279.749504)
				(end 399.603214 -279.749504)
			)
		)
		(stroke
			(width 0)
			(type solid)
		)
		(fill yes)
		(layer "In10.Cu")
		(net "P5E_PEX3_STN2_TX_DN<40>")
	)
	(gr_poly
		(pts
			(arc
				(start 400.553174 -278.799798)
				(mid 400.146774 -278.799798)
				(end 400.553174 -278.799798)
			)
		)
		(stroke
			(width 0)
			(type solid)
		)
		(fill yes)
		(layer "In10.Cu")
		(net "P5E_PEX3_STN2_TX_DP<39>")
	)
	(gr_poly
		(pts
			(arc
				(start 400.553174 -277.849838)
				(mid 400.146774 -277.849838)
				(end 400.553174 -277.849838)
			)
		)
		(stroke
			(width 0)
			(type solid)
		)
		(fill yes)
		(layer "In10.Cu")
		(net "P5E_PEX3_STN2_TX_DN<39>")
	)
	(gr_poly
		(pts
			(arc
				(start 401.503134 -280.699464)
				(mid 401.096734 -280.699464)
				(end 401.503134 -280.699464)
			)
		)
		(stroke
			(width 0)
			(type solid)
		)
		(fill yes)
		(layer "In10.Cu")
		(net "P5E_PEX3_STN2_TX_DP<38>")
	)
	(gr_poly
		(pts
			(arc
				(start 401.503134 -279.749504)
				(mid 401.096734 -279.749504)
				(end 401.503134 -279.749504)
			)
		)
		(stroke
			(width 0)
			(type solid)
		)
		(fill yes)
		(layer "In10.Cu")
		(net "P5E_PEX3_STN2_TX_DN<38>")
	)
	(gr_poly
		(pts
			(arc
				(start 402.453094 -278.799798)
				(mid 402.046694 -278.799798)
				(end 402.453094 -278.799798)
			)
		)
		(stroke
			(width 0)
			(type solid)
		)
		(fill yes)
		(layer "In10.Cu")
		(net "P5E_PEX3_STN2_TX_DP<37>")
	)
	(gr_poly
		(pts
			(arc
				(start 402.453094 -277.849838)
				(mid 402.046694 -277.849838)
				(end 402.453094 -277.849838)
			)
		)
		(stroke
			(width 0)
			(type solid)
		)
		(fill yes)
		(layer "In10.Cu")
		(net "P5E_PEX3_STN2_TX_DN<37>")
	)
	(gr_poly
		(pts
			(arc
				(start 403.403054 -280.699464)
				(mid 402.996654 -280.699464)
				(end 403.403054 -280.699464)
			)
		)
		(stroke
			(width 0)
			(type solid)
		)
		(fill yes)
		(layer "In10.Cu")
		(net "P5E_PEX3_STN2_TX_DP<36>")
	)
	(gr_poly
		(pts
			(arc
				(start 403.403054 -279.749504)
				(mid 402.996654 -279.749504)
				(end 403.403054 -279.749504)
			)
		)
		(stroke
			(width 0)
			(type solid)
		)
		(fill yes)
		(layer "In10.Cu")
		(net "P5E_PEX3_STN2_TX_DN<36>")
	)
	(gr_poly
		(pts
			(arc
				(start 404.353014 -278.799798)
				(mid 403.946614 -278.799798)
				(end 404.353014 -278.799798)
			)
		)
		(stroke
			(width 0)
			(type solid)
		)
		(fill yes)
		(layer "In10.Cu")
		(net "P5E_PEX3_STN2_TX_DP<35>")
	)
	(gr_poly
		(pts
			(arc
				(start 404.353014 -277.849838)
				(mid 403.946614 -277.849838)
				(end 404.353014 -277.849838)
			)
		)
		(stroke
			(width 0)
			(type solid)
		)
		(fill yes)
		(layer "In10.Cu")
		(net "P5E_PEX3_STN2_TX_DN<35>")
	)
	(gr_poly
		(pts
			(arc
				(start 405.302974 -280.699464)
				(mid 404.896574 -280.699464)
				(end 405.302974 -280.699464)
			)
		)
		(stroke
			(width 0)
			(type solid)
		)
		(fill yes)
		(layer "In10.Cu")
		(net "P5E_PEX3_STN2_TX_DP<34>")
	)
	(gr_poly
		(pts
			(arc
				(start 405.302974 -279.749504)
				(mid 404.896574 -279.749504)
				(end 405.302974 -279.749504)
			)
		)
		(stroke
			(width 0)
			(type solid)
		)
		(fill yes)
		(layer "In10.Cu")
		(net "P5E_PEX3_STN2_TX_DN<34>")
	)
	(gr_poly
		(pts
			(arc
				(start 406.253188 -278.799798)
				(mid 405.846788 -278.799798)
				(end 406.253188 -278.799798)
			)
		)
		(stroke
			(width 0)
			(type solid)
		)
		(fill yes)
		(layer "In10.Cu")
		(net "P5E_PEX3_STN2_TX_DP<33>")
	)
	(gr_poly
		(pts
			(arc
				(start 406.253188 -277.849838)
				(mid 405.846788 -277.849838)
				(end 406.253188 -277.849838)
			)
		)
		(stroke
			(width 0)
			(type solid)
		)
		(fill yes)
		(layer "In10.Cu")
		(net "P5E_PEX3_STN2_TX_DN<33>")
	)
	(gr_poly
		(pts
			(arc
				(start 407.203148 -280.699464)
				(mid 406.796748 -280.699464)
				(end 407.203148 -280.699464)
			)
		)
		(stroke
			(width 0)
			(type solid)
		)
		(fill yes)
		(layer "In10.Cu")
		(net "P5E_PEX3_STN2_TX_DP<32>")
	)
	(gr_poly
		(pts
			(arc
				(start 407.203148 -279.749504)
				(mid 406.796748 -279.749504)
				(end 407.203148 -279.749504)
			)
		)
		(stroke
			(width 0)
			(type solid)
		)
		(fill yes)
		(layer "In10.Cu")
		(net "P5E_PEX3_STN2_TX_DN<32>")
	)
	(gr_poly
		(pts
			(arc
				(start 414.803082 -316.799722)
				(mid 414.396682 -316.799722)
				(end 414.803082 -316.799722)
			)
		)
		(stroke
			(width 0)
			(type solid)
		)
		(fill yes)
		(layer "In10.Cu")
		(net "P5E_PEX3_STN5_RX_DN<88>")
	)
	(gr_poly
		(pts
			(arc
				(start 414.803082 -315.849762)
				(mid 414.396682 -315.849762)
				(end 414.803082 -315.849762)
			)
		)
		(stroke
			(width 0)
			(type solid)
		)
		(fill yes)
		(layer "In10.Cu")
		(net "P5E_PEX3_STN5_RX_DP<88>")
	)
	(gr_poly
		(pts
			(arc
				(start 414.803082 -312.049922)
				(mid 414.396682 -312.049922)
				(end 414.803082 -312.049922)
			)
		)
		(stroke
			(width 0)
			(type solid)
		)
		(fill yes)
		(layer "In10.Cu")
		(net "P5E_PEX3_STN5_TX_DN<88>")
	)
	(gr_poly
		(pts
			(arc
				(start 414.803082 -311.099962)
				(mid 414.396682 -311.099962)
				(end 414.803082 -311.099962)
			)
		)
		(stroke
			(width 0)
			(type solid)
		)
		(fill yes)
		(layer "In10.Cu")
		(net "P5E_PEX3_STN5_TX_DP<88>")
	)
	(gr_poly
		(pts
			(arc
				(start 415.753042 -318.699896)
				(mid 415.346642 -318.699896)
				(end 415.753042 -318.699896)
			)
		)
		(stroke
			(width 0)
			(type solid)
		)
		(fill yes)
		(layer "In10.Cu")
		(net "P5E_PEX3_STN5_RX_DN<89>")
	)
	(gr_poly
		(pts
			(arc
				(start 415.753042 -317.749936)
				(mid 415.346642 -317.749936)
				(end 415.753042 -317.749936)
			)
		)
		(stroke
			(width 0)
			(type solid)
		)
		(fill yes)
		(layer "In10.Cu")
		(net "P5E_PEX3_STN5_RX_DP<89>")
	)
	(gr_poly
		(pts
			(arc
				(start 415.753042 -313.949842)
				(mid 415.346642 -313.949842)
				(end 415.753042 -313.949842)
			)
		)
		(stroke
			(width 0)
			(type solid)
		)
		(fill yes)
		(layer "In10.Cu")
		(net "P5E_PEX3_STN5_TX_DN<89>")
	)
	(gr_poly
		(pts
			(arc
				(start 415.753042 -312.999882)
				(mid 415.346642 -312.999882)
				(end 415.753042 -312.999882)
			)
		)
		(stroke
			(width 0)
			(type solid)
		)
		(fill yes)
		(layer "In10.Cu")
		(net "P5E_PEX3_STN5_TX_DP<89>")
	)
	(gr_poly
		(pts
			(arc
				(start 416.703002 -316.799722)
				(mid 416.296602 -316.799722)
				(end 416.703002 -316.799722)
			)
		)
		(stroke
			(width 0)
			(type solid)
		)
		(fill yes)
		(layer "In10.Cu")
		(net "P5E_PEX3_STN5_RX_DN<90>")
	)
	(gr_poly
		(pts
			(arc
				(start 416.703002 -315.849762)
				(mid 416.296602 -315.849762)
				(end 416.703002 -315.849762)
			)
		)
		(stroke
			(width 0)
			(type solid)
		)
		(fill yes)
		(layer "In10.Cu")
		(net "P5E_PEX3_STN5_RX_DP<90>")
	)
	(gr_poly
		(pts
			(arc
				(start 416.703002 -312.049922)
				(mid 416.296602 -312.049922)
				(end 416.703002 -312.049922)
			)
		)
		(stroke
			(width 0)
			(type solid)
		)
		(fill yes)
		(layer "In10.Cu")
		(net "P5E_PEX3_STN5_TX_DN<90>")
	)
	(gr_poly
		(pts
			(arc
				(start 416.703002 -311.099962)
				(mid 416.296602 -311.099962)
				(end 416.703002 -311.099962)
			)
		)
		(stroke
			(width 0)
			(type solid)
		)
		(fill yes)
		(layer "In10.Cu")
		(net "P5E_PEX3_STN5_TX_DP<90>")
	)
	(gr_poly
		(pts
			(arc
				(start 417.653216 -318.699896)
				(mid 417.246816 -318.699896)
				(end 417.653216 -318.699896)
			)
		)
		(stroke
			(width 0)
			(type solid)
		)
		(fill yes)
		(layer "In10.Cu")
		(net "P5E_PEX3_STN5_RX_DN<91>")
	)
	(gr_poly
		(pts
			(arc
				(start 417.653216 -317.749936)
				(mid 417.246816 -317.749936)
				(end 417.653216 -317.749936)
			)
		)
		(stroke
			(width 0)
			(type solid)
		)
		(fill yes)
		(layer "In10.Cu")
		(net "P5E_PEX3_STN5_RX_DP<91>")
	)
	(gr_poly
		(pts
			(arc
				(start 417.653216 -313.949842)
				(mid 417.246816 -313.949842)
				(end 417.653216 -313.949842)
			)
		)
		(stroke
			(width 0)
			(type solid)
		)
		(fill yes)
		(layer "In10.Cu")
		(net "P5E_PEX3_STN5_TX_DN<91>")
	)
	(gr_poly
		(pts
			(arc
				(start 417.653216 -312.999882)
				(mid 417.246816 -312.999882)
				(end 417.653216 -312.999882)
			)
		)
		(stroke
			(width 0)
			(type solid)
		)
		(fill yes)
		(layer "In10.Cu")
		(net "P5E_PEX3_STN5_TX_DP<91>")
	)
	(gr_poly
		(pts
			(arc
				(start 418.603176 -316.799722)
				(mid 418.196776 -316.799722)
				(end 418.603176 -316.799722)
			)
		)
		(stroke
			(width 0)
			(type solid)
		)
		(fill yes)
		(layer "In10.Cu")
		(net "P5E_PEX3_STN5_RX_DN<92>")
	)
	(gr_poly
		(pts
			(arc
				(start 418.603176 -315.849762)
				(mid 418.196776 -315.849762)
				(end 418.603176 -315.849762)
			)
		)
		(stroke
			(width 0)
			(type solid)
		)
		(fill yes)
		(layer "In10.Cu")
		(net "P5E_PEX3_STN5_RX_DP<92>")
	)
	(gr_poly
		(pts
			(arc
				(start 418.603176 -312.049922)
				(mid 418.196776 -312.049922)
				(end 418.603176 -312.049922)
			)
		)
		(stroke
			(width 0)
			(type solid)
		)
		(fill yes)
		(layer "In10.Cu")
		(net "P5E_PEX3_STN5_TX_DN<92>")
	)
	(gr_poly
		(pts
			(arc
				(start 418.603176 -311.099962)
				(mid 418.196776 -311.099962)
				(end 418.603176 -311.099962)
			)
		)
		(stroke
			(width 0)
			(type solid)
		)
		(fill yes)
		(layer "In10.Cu")
		(net "P5E_PEX3_STN5_TX_DP<92>")
	)
	(gr_poly
		(pts
			(arc
				(start 419.553136 -318.699896)
				(mid 419.146736 -318.699896)
				(end 419.553136 -318.699896)
			)
		)
		(stroke
			(width 0)
			(type solid)
		)
		(fill yes)
		(layer "In10.Cu")
		(net "P5E_PEX3_STN5_RX_DN<93>")
	)
	(gr_poly
		(pts
			(arc
				(start 419.553136 -317.749936)
				(mid 419.146736 -317.749936)
				(end 419.553136 -317.749936)
			)
		)
		(stroke
			(width 0)
			(type solid)
		)
		(fill yes)
		(layer "In10.Cu")
		(net "P5E_PEX3_STN5_RX_DP<93>")
	)
	(gr_poly
		(pts
			(arc
				(start 419.553136 -313.949842)
				(mid 419.146736 -313.949842)
				(end 419.553136 -313.949842)
			)
		)
		(stroke
			(width 0)
			(type solid)
		)
		(fill yes)
		(layer "In10.Cu")
		(net "P5E_PEX3_STN5_TX_DN<93>")
	)
	(gr_poly
		(pts
			(arc
				(start 419.553136 -312.999882)
				(mid 419.146736 -312.999882)
				(end 419.553136 -312.999882)
			)
		)
		(stroke
			(width 0)
			(type solid)
		)
		(fill yes)
		(layer "In10.Cu")
		(net "P5E_PEX3_STN5_TX_DP<93>")
	)
	(gr_poly
		(pts
			(arc
				(start 420.503096 -316.799722)
				(mid 420.096696 -316.799722)
				(end 420.503096 -316.799722)
			)
		)
		(stroke
			(width 0)
			(type solid)
		)
		(fill yes)
		(layer "In10.Cu")
		(net "P5E_PEX3_STN5_RX_DN<94>")
	)
	(gr_poly
		(pts
			(arc
				(start 420.503096 -315.849762)
				(mid 420.096696 -315.849762)
				(end 420.503096 -315.849762)
			)
		)
		(stroke
			(width 0)
			(type solid)
		)
		(fill yes)
		(layer "In10.Cu")
		(net "P5E_PEX3_STN5_RX_DP<94>")
	)
	(gr_poly
		(pts
			(arc
				(start 420.503096 -312.049922)
				(mid 420.096696 -312.049922)
				(end 420.503096 -312.049922)
			)
		)
		(stroke
			(width 0)
			(type solid)
		)
		(fill yes)
		(layer "In10.Cu")
		(net "P5E_PEX3_STN5_TX_DN<94>")
	)
	(gr_poly
		(pts
			(arc
				(start 420.503096 -311.099962)
				(mid 420.096696 -311.099962)
				(end 420.503096 -311.099962)
			)
		)
		(stroke
			(width 0)
			(type solid)
		)
		(fill yes)
		(layer "In10.Cu")
		(net "P5E_PEX3_STN5_TX_DP<94>")
	)
	(gr_poly
		(pts
			(arc
				(start 421.453056 -318.699896)
				(mid 421.046656 -318.699896)
				(end 421.453056 -318.699896)
			)
		)
		(stroke
			(width 0)
			(type solid)
		)
		(fill yes)
		(layer "In10.Cu")
		(net "P5E_PEX3_STN5_RX_DN<95>")
	)
	(gr_poly
		(pts
			(arc
				(start 421.453056 -317.749936)
				(mid 421.046656 -317.749936)
				(end 421.453056 -317.749936)
			)
		)
		(stroke
			(width 0)
			(type solid)
		)
		(fill yes)
		(layer "In10.Cu")
		(net "P5E_PEX3_STN5_RX_DP<95>")
	)
	(gr_poly
		(pts
			(arc
				(start 421.453056 -313.949842)
				(mid 421.046656 -313.949842)
				(end 421.453056 -313.949842)
			)
		)
		(stroke
			(width 0)
			(type solid)
		)
		(fill yes)
		(layer "In10.Cu")
		(net "P5E_PEX3_STN5_TX_DN<95>")
	)
	(gr_poly
		(pts
			(arc
				(start 421.453056 -312.999882)
				(mid 421.046656 -312.999882)
				(end 421.453056 -312.999882)
			)
		)
		(stroke
			(width 0)
			(type solid)
		)
		(fill yes)
		(layer "In10.Cu")
		(net "P5E_PEX3_STN5_TX_DP<95>")
	)
	(gr_poly
		(pts
			(arc
				(start 241.741198 -376.399806)
				(mid 241.763367 -376.39459)
				(end 241.781076 -376.380248)
			)
			(arc
				(start 241.781076 -376.380248)
				(mid 241.793461 -376.365378)
				(end 241.80673 -376.351292)
			)
			(xy 242.08994 -376.068082)
			(arc
				(start 242.09502 -376.063002)
				(mid 242.106647 -376.046325)
				(end 242.110768 -376.026426)
			)
			(arc
				(start 242.110768 -368.666268)
				(mid 242.106867 -368.646745)
				(end 242.095782 -368.6302)
			)
			(arc
				(start 241.977672 -368.51209)
				(mid 241.961138 -368.500979)
				(end 241.941604 -368.497104)
			)
			(arc
				(start 236.370368 -368.497104)
				(mid 236.350845 -368.501005)
				(end 236.3343 -368.51209)
			)
			(arc
				(start 236.123734 -368.722656)
				(mid 236.112623 -368.73919)
				(end 236.108748 -368.758724)
			)
			(arc
				(start 236.108748 -376.146314)
				(mid 236.112649 -376.165837)
				(end 236.123734 -376.182382)
			)
			(arc
				(start 236.326172 -376.38482)
				(mid 236.342706 -376.395931)
				(end 236.36224 -376.399806)
			)
		)
		(stroke
			(width 0)
			(type solid)
		)
		(fill yes)
		(layer "In10.Cu")
		(net "P12V_STBY_R1")
	)
	(gr_poly
		(pts
			(arc
				(start 235.60151 -413.087058)
				(mid 235.621033 -413.083157)
				(end 235.637578 -413.072072)
			)
			(arc
				(start 236.756956 -411.952694)
				(mid 236.768067 -411.93616)
				(end 236.771942 -411.916626)
			)
			(arc
				(start 236.771942 -402.84527)
				(mid 236.796095 -402.723754)
				(end 236.864906 -402.620734)
			)
			(arc
				(start 238.766604 -400.719036)
				(mid 238.869636 -400.650255)
				(end 238.99114 -400.626072)
			)
			(arc
				(start 242.910868 -400.626072)
				(mid 242.930391 -400.622171)
				(end 242.946936 -400.611086)
			)
			(arc
				(start 243.79682 -399.761202)
				(mid 243.807931 -399.744668)
				(end 243.811806 -399.725134)
			)
			(arc
				(start 243.811806 -392.09472)
				(mid 243.835959 -391.973204)
				(end 243.90477 -391.870184)
			)
			(arc
				(start 244.93093 -390.844024)
				(mid 245.033962 -390.775243)
				(end 245.155466 -390.75106)
			)
			(arc
				(start 259.056124 -390.75106)
				(mid 259.075647 -390.747159)
				(end 259.092192 -390.736074)
			)
			(arc
				(start 262.00481 -387.823456)
				(mid 262.015921 -387.806922)
				(end 262.019796 -387.787388)
			)
			(arc
				(start 262.019796 -379.197616)
				(mid 262.015895 -379.178093)
				(end 262.00481 -379.161548)
			)
			(arc
				(start 261.967472 -379.12421)
				(mid 261.950938 -379.113099)
				(end 261.931404 -379.109224)
			)
			(arc
				(start 240.584482 -379.109224)
				(mid 240.564959 -379.113125)
				(end 240.548414 -379.12421)
			)
			(arc
				(start 239.998504 -379.67412)
				(mid 239.895472 -379.742901)
				(end 239.773968 -379.767084)
			)
			(arc
				(start 237.129066 -379.767084)
				(mid 237.00755 -379.742931)
				(end 236.90453 -379.67412)
			)
			(arc
				(start 232.953814 -375.723404)
				(mid 232.885033 -375.620372)
				(end 232.86085 -375.498868)
			)
			(arc
				(start 232.86085 -372.11508)
				(mid 232.856949 -372.095557)
				(end 232.845864 -372.079012)
			)
			(arc
				(start 232.203752 -371.4369)
				(mid 232.134971 -371.333868)
				(end 232.110788 -371.212364)
			)
			(arc
				(start 232.110788 -371.075712)
				(mid 232.106887 -371.056189)
				(end 232.095802 -371.039644)
			)
			(arc
				(start 232.035858 -370.9797)
				(mid 231.967077 -370.876668)
				(end 231.942894 -370.755164)
			)
			(arc
				(start 231.942894 -367.397792)
				(mid 231.938993 -367.378269)
				(end 231.927908 -367.361724)
			)
			(arc
				(start 231.89057 -367.324386)
				(mid 231.874036 -367.313275)
				(end 231.854502 -367.3094)
			)
			(arc
				(start 228.741986 -367.3094)
				(mid 228.722463 -367.313301)
				(end 228.705918 -367.324386)
			)
			(arc
				(start 228.66858 -367.361724)
				(mid 228.657469 -367.378258)
				(end 228.653594 -367.397792)
			)
			(arc
				(start 228.653594 -370.74856)
				(mid 228.629441 -370.870076)
				(end 228.56063 -370.973096)
			)
			(arc
				(start 228.481128 -371.052598)
				(mid 228.470017 -371.069132)
				(end 228.466142 -371.088666)
			)
			(arc
				(start 228.466142 -371.354096)
				(mid 228.441989 -371.475612)
				(end 228.373178 -371.578632)
			)
			(arc
				(start 227.178362 -372.773448)
				(mid 227.167251 -372.789982)
				(end 227.163376 -372.809516)
			)
			(arc
				(start 227.163376 -374.166384)
				(mid 227.139223 -374.2879)
				(end 227.070412 -374.39092)
			)
			(arc
				(start 225.794062 -375.66727)
				(mid 225.69103 -375.736051)
				(end 225.569526 -375.760234)
			)
			(arc
				(start 223.648016 -375.760234)
				(mid 223.5265 -375.736081)
				(end 223.42348 -375.66727)
			)
			(arc
				(start 221.55531 -373.7991)
				(mid 221.486529 -373.696068)
				(end 221.462346 -373.574564)
			)
			(arc
				(start 221.462346 -371.091714)
				(mid 221.458445 -371.072191)
				(end 221.44736 -371.055646)
			)
			(arc
				(start 221.361508 -370.969794)
				(mid 221.292727 -370.866762)
				(end 221.268544 -370.745258)
			)
			(arc
				(start 221.268544 -367.391442)
				(mid 221.264643 -367.371919)
				(end 221.253558 -367.355374)
			)
			(arc
				(start 221.225872 -367.327688)
				(mid 221.209338 -367.316577)
				(end 221.189804 -367.312702)
			)
			(arc
				(start 218.110308 -367.312702)
				(mid 218.090785 -367.316603)
				(end 218.07424 -367.327688)
			)
			(arc
				(start 217.967306 -367.434622)
				(mid 217.956195 -367.451156)
				(end 217.95232 -367.47069)
			)
			(arc
				(start 217.95232 -370.719096)
				(mid 217.928167 -370.840612)
				(end 217.859356 -370.943632)
			)
			(arc
				(start 216.82964 -371.973348)
				(mid 216.726608 -372.042129)
				(end 216.605104 -372.066312)
			)
			(arc
				(start 210.424014 -372.066312)
				(mid 210.302498 -372.042159)
				(end 210.199478 -371.973348)
			)
			(arc
				(start 210.067906 -371.841776)
				(mid 209.999125 -371.738744)
				(end 209.974942 -371.61724)
			)
			(arc
				(start 209.974942 -371.309138)
				(mid 209.971041 -371.289615)
				(end 209.959956 -371.27307)
			)
			(arc
				(start 209.949034 -371.262148)
				(mid 209.9325 -371.251037)
				(end 209.912966 -371.247162)
			)
			(arc
				(start 209.559144 -371.247162)
				(mid 209.437628 -371.223009)
				(end 209.334608 -371.154198)
			)
			(arc
				(start 208.669382 -370.488972)
				(mid 208.652848 -370.477861)
				(end 208.633314 -370.473986)
			)
			(arc
				(start 208.394554 -370.473986)
				(mid 208.273038 -370.449833)
				(end 208.170018 -370.381022)
			)
			(arc
				(start 208.11744 -370.328444)
				(mid 208.048659 -370.225412)
				(end 208.024476 -370.103908)
			)
			(arc
				(start 208.024476 -367.401348)
				(mid 208.020575 -367.381825)
				(end 208.00949 -367.36528)
			)
			(arc
				(start 207.981804 -367.337594)
				(mid 207.96527 -367.326483)
				(end 207.945736 -367.322608)
			)
			(arc
				(start 204.823822 -367.322608)
				(mid 204.804299 -367.326509)
				(end 204.787754 -367.337594)
			)
			(arc
				(start 204.740002 -367.385346)
				(mid 204.728891 -367.40188)
				(end 204.725016 -367.421414)
			)
			(arc
				(start 204.725016 -370.796312)
				(mid 204.728917 -370.815835)
				(end 204.740002 -370.83238)
			)
			(arc
				(start 204.77353 -370.865908)
				(mid 204.842311 -370.96894)
				(end 204.866494 -371.090444)
			)
			(arc
				(start 204.866494 -374.47474)
				(mid 204.870058 -374.493432)
				(end 204.88021 -374.509538)
			)
			(arc
				(start 204.88021 -374.509538)
				(mid 204.94326 -374.609679)
				(end 204.9653 -374.725946)
			)
			(arc
				(start 204.9653 -387.02361)
				(mid 204.969201 -387.043133)
				(end 204.980286 -387.059678)
			)
			(arc
				(start 207.47482 -389.554212)
				(mid 207.543601 -389.657244)
				(end 207.567784 -389.778748)
			)
			(arc
				(start 207.567784 -411.696662)
				(mid 207.571685 -411.716185)
				(end 207.58277 -411.73273)
			)
			(arc
				(start 208.922112 -413.072072)
				(mid 208.938646 -413.083183)
				(end 208.95818 -413.087058)
			)
		)
		(stroke
			(width 0)
			(type solid)
		)
		(fill yes)
		(layer "In10.Cu")
		(net "P12V_STBY")
	)
	(gr_poly
		(pts
			(xy 465.600034 -461.99552) (xy 465.655841 -461.994997) (xy 465.767141 -461.986654) (xy 465.877508 -461.970017)
			(xy 465.986322 -461.945179) (xy 466.092976 -461.912278) (xy 466.196873 -461.8715) (xy 466.297432 -461.823072)
			(xy 466.394091 -461.767264) (xy 466.48631 -461.70439) (xy 466.573572 -461.6348) (xy 466.65539 -461.558883)
			(xy 466.731306 -461.477065) (xy 466.800896 -461.389802) (xy 466.86377 -461.297583) (xy 466.919577 -461.200923)
			(xy 466.968004 -461.100364) (xy 467.008782 -460.996466) (xy 467.041681 -460.889812) (xy 467.066519 -460.780998)
			(xy 467.083155 -460.670631) (xy 467.091497 -460.559331) (xy 467.09203 -460.503524) (xy 467.09203 -422.58996)
			(xy 467.091507 -422.534153) (xy 467.083163 -422.422853) (xy 467.066526 -422.312487) (xy 467.041687 -422.203672)
			(xy 467.008787 -422.097019) (xy 466.968009 -421.993121) (xy 466.91958 -421.892562) (xy 466.863773 -421.795903)
			(xy 466.800898 -421.703684) (xy 466.731308 -421.616422) (xy 466.655392 -421.534604) (xy 466.573573 -421.458688)
			(xy 466.486311 -421.389098) (xy 466.394092 -421.326224) (xy 466.297433 -421.270417) (xy 466.196873 -421.221989)
			(xy 466.092976 -421.181211) (xy 465.986322 -421.148311) (xy 465.877508 -421.123473) (xy 465.767141 -421.106836)
			(xy 465.655841 -421.098493) (xy 465.600034 -421.097964) (xy 447.939922 -421.097964) (xy 447.884114 -421.098485)
			(xy 447.77281 -421.106824) (xy 447.66244 -421.123458) (xy 447.553622 -421.148293) (xy 447.446964 -421.181191)
			(xy 447.343062 -421.221967) (xy 447.242499 -421.270394) (xy 447.145835 -421.3262) (xy 447.053613 -421.389074)
			(xy 446.966346 -421.458664) (xy 446.884524 -421.53458) (xy 446.808604 -421.616399) (xy 446.739011 -421.703663)
			(xy 446.676133 -421.795883) (xy 446.620323 -421.892544) (xy 446.571892 -421.993106) (xy 446.531111 -422.097005)
			(xy 446.498209 -422.203662) (xy 446.47337 -422.312479) (xy 446.456731 -422.422848) (xy 446.448387 -422.534152)
			(xy 446.447926 -422.58996) (xy 446.447926 -429.090074) (xy 446.447433 -429.160429) (xy 446.439545 -429.300916)
			(xy 446.423792 -429.440741) (xy 446.400224 -429.579462) (xy 446.368915 -429.716643) (xy 446.329963 -429.851854)
			(xy 446.283491 -429.984667) (xy 446.229646 -430.114666) (xy 446.168596 -430.241441) (xy 446.100533 -430.364593)
			(xy 446.025673 -430.483736) (xy 445.94425 -430.598494) (xy 445.856521 -430.708505) (xy 445.762761 -430.813425)
			(xy 445.663266 -430.912922) (xy 445.558348 -431.006684) (xy 445.448338 -431.094416) (xy 445.333582 -431.175842)
			(xy 445.214442 -431.250705) (xy 445.091291 -431.31877) (xy 444.964517 -431.379823) (xy 444.834519 -431.433671)
			(xy 444.701707 -431.480146) (xy 444.566498 -431.519101) (xy 444.429317 -431.550413) (xy 444.290596 -431.573985)
			(xy 444.150772 -431.589741) (xy 444.010285 -431.597632) (xy 443.93993 -431.59807) (xy 371.24005 -431.59807)
			(xy 371.169695 -431.597587) (xy 371.029207 -431.5897) (xy 370.889383 -431.573948) (xy 370.750661 -431.550381)
			(xy 370.613479 -431.519072) (xy 370.478269 -431.480121) (xy 370.345455 -431.433649) (xy 370.215456 -431.379804)
			(xy 370.088681 -431.318754) (xy 369.965528 -431.250691) (xy 369.846385 -431.175831) (xy 369.731628 -431.094407)
			(xy 369.621616 -431.006677) (xy 369.516697 -430.912917) (xy 369.4172 -430.813421) (xy 369.323438 -430.708502)
			(xy 369.235707 -430.598492) (xy 369.154283 -430.483735) (xy 369.079421 -430.364593) (xy 369.011357 -430.241441)
			(xy 368.950306 -430.114666) (xy 368.896459 -429.984667) (xy 368.849986 -429.851854) (xy 368.811034 -429.716644)
			(xy 368.779724 -429.579463) (xy 368.756155 -429.440741) (xy 368.740402 -429.300917) (xy 368.732514 -429.160429)
			(xy 368.732054 -429.090074) (xy 368.732054 -422.58996) (xy 368.731543 -422.534154) (xy 368.7232 -422.422854)
			(xy 368.706562 -422.31249) (xy 368.681723 -422.203677) (xy 368.648822 -422.097024) (xy 368.608042 -421.993129)
			(xy 368.559613 -421.892571) (xy 368.503804 -421.795914) (xy 368.440929 -421.703697) (xy 368.371337 -421.616438)
			(xy 368.29542 -421.534622) (xy 368.2136 -421.458709) (xy 368.126337 -421.389123) (xy 368.034117 -421.326252)
			(xy 367.937456 -421.270449) (xy 367.836896 -421.222025) (xy 367.732998 -421.181251) (xy 367.626344 -421.148356)
			(xy 367.51753 -421.123523) (xy 367.407164 -421.106891) (xy 367.295864 -421.098554) (xy 367.240058 -421.097964)
			(xy 359.940098 -421.097964) (xy 359.88429 -421.098486) (xy 359.772988 -421.106827) (xy 359.662619 -421.123462)
			(xy 359.553802 -421.148298) (xy 359.447146 -421.181197) (xy 359.343246 -421.221974) (xy 359.242684 -421.270401)
			(xy 359.146022 -421.326208) (xy 359.053801 -421.389082) (xy 358.966536 -421.458672) (xy 358.884716 -421.534589)
			(xy 358.808797 -421.616407) (xy 358.739205 -421.70367) (xy 358.676328 -421.79589) (xy 358.620519 -421.892551)
			(xy 358.572089 -421.993111) (xy 358.53131 -422.09701) (xy 358.498408 -422.203666) (xy 358.473569 -422.312482)
			(xy 358.456931 -422.42285) (xy 358.448587 -422.534152) (xy 358.448102 -422.58996) (xy 358.448102 -429.090074)
			(xy 358.447618 -429.160429) (xy 358.43973 -429.300916) (xy 358.423977 -429.440741) (xy 358.400409 -429.579462)
			(xy 358.369099 -429.716643) (xy 358.330147 -429.851853) (xy 358.283675 -429.984667) (xy 358.229829 -430.114665)
			(xy 358.168779 -430.24144) (xy 358.100716 -430.364593) (xy 358.025856 -430.483735) (xy 357.944432 -430.598492)
			(xy 357.856702 -430.708504) (xy 357.762942 -430.813423) (xy 357.663446 -430.91292) (xy 357.558528 -431.006682)
			(xy 357.448518 -431.094413) (xy 357.333762 -431.175838) (xy 357.21462 -431.2507) (xy 357.091469 -431.318764)
			(xy 356.964695 -431.379816) (xy 356.834697 -431.433664) (xy 356.701884 -431.480138) (xy 356.566674 -431.519091)
			(xy 356.429493 -431.550403) (xy 356.290772 -431.573973) (xy 356.150948 -431.589728) (xy 356.010461 -431.597618)
			(xy 355.940106 -431.59807) (xy 283.239972 -431.59807) (xy 283.169619 -431.597576) (xy 283.029135 -431.589685)
			(xy 282.889313 -431.573929) (xy 282.750596 -431.550359) (xy 282.613418 -431.519047) (xy 282.478212 -431.480093)
			(xy 282.345402 -431.43362) (xy 282.215407 -431.379772) (xy 282.088636 -431.318721) (xy 281.965488 -431.250657)
			(xy 281.84635 -431.175796) (xy 281.731596 -431.094372) (xy 281.621589 -431.006642) (xy 281.516674 -430.912882)
			(xy 281.417181 -430.813387) (xy 281.323423 -430.70847) (xy 281.235695 -430.598461) (xy 281.154274 -430.483705)
			(xy 281.079415 -430.364565) (xy 281.011354 -430.241416) (xy 280.950306 -430.114643) (xy 280.896461 -429.984647)
			(xy 280.84999 -429.851837) (xy 280.811039 -429.71663) (xy 280.779731 -429.579451) (xy 280.756163 -429.440733)
			(xy 280.740411 -429.300912) (xy 280.732523 -429.160427) (xy 280.731976 -429.090074) (xy 280.731976 -422.58996)
			(xy 280.731453 -422.534154) (xy 280.723109 -422.422855) (xy 280.706471 -422.31249) (xy 280.681633 -422.203678)
			(xy 280.648732 -422.097025) (xy 280.607953 -421.99313) (xy 280.559525 -421.892573) (xy 280.503717 -421.795915)
			(xy 280.440842 -421.703699) (xy 280.371251 -421.616439) (xy 280.295334 -421.534623) (xy 280.213516 -421.45871)
			(xy 280.126253 -421.389123) (xy 280.034034 -421.326251) (xy 279.937374 -421.270447) (xy 279.836815 -421.222023)
			(xy 279.732918 -421.181248) (xy 279.626264 -421.148352) (xy 279.517451 -421.123517) (xy 279.407085 -421.106884)
			(xy 279.295786 -421.098545) (xy 279.23998 -421.097964) (xy 276.880066 -421.097964) (xy 276.824259 -421.098487)
			(xy 276.712958 -421.10683) (xy 276.602591 -421.123467) (xy 276.493777 -421.148305) (xy 276.387122 -421.181205)
			(xy 276.283225 -421.221984) (xy 276.182665 -421.270412) (xy 276.086005 -421.326219) (xy 275.993786 -421.389094)
			(xy 275.906523 -421.458684) (xy 275.824704 -421.5346) (xy 275.748787 -421.616418) (xy 275.679197 -421.703681)
			(xy 275.616322 -421.7959) (xy 275.560514 -421.892559) (xy 275.512086 -421.993119) (xy 275.471307 -422.097017)
			(xy 275.438407 -422.203671) (xy 275.413568 -422.312485) (xy 275.396931 -422.422852) (xy 275.388587 -422.534153)
			(xy 275.38807 -422.58996) (xy 275.38807 -430.55794) (xy 275.387576 -430.628293) (xy 275.379684 -430.768777)
			(xy 275.363928 -430.908597) (xy 275.340357 -431.047314) (xy 275.309045 -431.184492) (xy 275.27009 -431.319698)
			(xy 275.223616 -431.452506) (xy 275.169769 -431.582501) (xy 275.108717 -431.709271) (xy 275.040653 -431.832419)
			(xy 274.965792 -431.951557) (xy 274.884368 -432.066309) (xy 274.796638 -432.176316) (xy 274.702878 -432.281231)
			(xy 274.603383 -432.380723) (xy 274.498466 -432.474481) (xy 274.388457 -432.562208) (xy 274.273702 -432.643629)
			(xy 274.154562 -432.718487) (xy 274.031412 -432.786547) (xy 273.90464 -432.847596) (xy 273.774645 -432.90144)
			(xy 273.641835 -432.94791) (xy 273.506628 -432.986861) (xy 273.36945 -433.018169) (xy 273.230732 -433.041737)
			(xy 273.090911 -433.05749) (xy 272.950427 -433.065377) (xy 272.880074 -433.065936) (xy 202.360022 -433.065936)
			(xy 202.289667 -433.065443) (xy 202.14918 -433.057555) (xy 202.009355 -433.041802) (xy 201.870634 -433.018234)
			(xy 201.733452 -432.986924) (xy 201.598242 -432.947972) (xy 201.465429 -432.9015) (xy 201.33543 -432.847655)
			(xy 201.208655 -432.786605) (xy 201.085502 -432.718542) (xy 200.96636 -432.643682) (xy 200.851602 -432.562259)
			(xy 200.74159 -432.47453) (xy 200.63667 -432.38077) (xy 200.537173 -432.281275) (xy 200.44341 -432.176357)
			(xy 200.355678 -432.066348) (xy 200.274252 -431.951592) (xy 200.199389 -431.832451) (xy 200.131324 -431.7093)
			(xy 200.070271 -431.582527) (xy 200.016422 -431.452529) (xy 199.969947 -431.319717) (xy 199.930991 -431.184508)
			(xy 199.899679 -431.047327) (xy 199.876107 -430.908606) (xy 199.86035 -430.768782) (xy 199.852458 -430.628295)
			(xy 199.852026 -430.55794) (xy 199.852026 -422.58996) (xy 199.851503 -422.534154) (xy 199.843159 -422.422853)
			(xy 199.826522 -422.312487) (xy 199.801683 -422.203673) (xy 199.768783 -422.097019) (xy 199.728004 -421.993122)
			(xy 199.679576 -421.892563) (xy 199.623769 -421.795904) (xy 199.560894 -421.703685) (xy 199.491304 -421.616423)
			(xy 199.415387 -421.534606) (xy 199.333569 -421.45869) (xy 199.246306 -421.3891) (xy 199.154088 -421.326226)
			(xy 199.057428 -421.270419) (xy 198.956869 -421.221992) (xy 198.852972 -421.181214) (xy 198.746318 -421.148314)
			(xy 198.637503 -421.123476) (xy 198.527137 -421.10684) (xy 198.415836 -421.098497) (xy 198.36003 -421.097964)
			(xy 188.36005 -421.097964) (xy 188.304244 -421.098488) (xy 188.192943 -421.106832) (xy 188.082578 -421.12347)
			(xy 187.973764 -421.148309) (xy 187.86711 -421.18121) (xy 187.763214 -421.221988) (xy 187.662655 -421.270417)
			(xy 187.565996 -421.326225) (xy 187.473778 -421.389099) (xy 187.386516 -421.458689) (xy 187.304699 -421.534606)
			(xy 187.228783 -421.616424) (xy 187.159193 -421.703686) (xy 187.096319 -421.795905) (xy 187.040512 -421.892564)
			(xy 186.992084 -421.993123) (xy 186.951306 -422.09702) (xy 186.918406 -422.203673) (xy 186.893568 -422.312487)
			(xy 186.876931 -422.422853) (xy 186.868587 -422.534154) (xy 186.868054 -422.58996) (xy 186.868054 -429.090074)
			(xy 186.86757 -429.160428) (xy 186.859682 -429.300915) (xy 186.843929 -429.440738) (xy 186.820361 -429.579458)
			(xy 186.789051 -429.716639) (xy 186.750099 -429.851848) (xy 186.703626 -429.98466) (xy 186.64978 -430.114658)
			(xy 186.58873 -430.241431) (xy 186.520667 -430.364582) (xy 186.445806 -430.483723) (xy 186.364382 -430.598479)
			(xy 186.276652 -430.708489) (xy 186.182891 -430.813407) (xy 186.083395 -430.912902) (xy 185.978477 -431.006662)
			(xy 185.868467 -431.094392) (xy 185.75371 -431.175815) (xy 185.634569 -431.250675) (xy 185.511417 -431.318737)
			(xy 185.384643 -431.379787) (xy 185.254645 -431.433632) (xy 185.121833 -431.480104) (xy 184.986623 -431.519055)
			(xy 184.849443 -431.550364) (xy 184.710722 -431.573931) (xy 184.570899 -431.589684) (xy 184.430412 -431.597571)
			(xy 184.360058 -431.59807) (xy 111.660178 -431.59807) (xy 111.589825 -431.597585) (xy 111.449339 -431.589694)
			(xy 111.309518 -431.573939) (xy 111.170799 -431.550369) (xy 111.033621 -431.519057) (xy 110.898414 -431.480103)
			(xy 110.765603 -431.43363) (xy 110.635608 -431.379782) (xy 110.508836 -431.318731) (xy 110.385687 -431.250667)
			(xy 110.266548 -431.175806) (xy 110.151794 -431.094382) (xy 110.041786 -431.006651) (xy 109.93687 -430.912891)
			(xy 109.837376 -430.813395) (xy 109.743618 -430.708478) (xy 109.65589 -430.598468) (xy 109.574468 -430.483712)
			(xy 109.499608 -430.364572) (xy 109.431547 -430.241421) (xy 109.370498 -430.114648) (xy 109.316653 -429.984652)
			(xy 109.270182 -429.851841) (xy 109.231231 -429.716633) (xy 109.199922 -429.579454) (xy 109.176354 -429.440735)
			(xy 109.160602 -429.300913) (xy 109.152714 -429.160427) (xy 109.152182 -429.090074) (xy 109.152182 -422.58996)
			(xy 109.151659 -422.534154) (xy 109.143315 -422.422855) (xy 109.126678 -422.31249) (xy 109.101839 -422.203677)
			(xy 109.068938 -422.097025) (xy 109.02816 -421.993129) (xy 108.979731 -421.892571) (xy 108.923923 -421.795914)
			(xy 108.861048 -421.703697) (xy 108.791457 -421.616437) (xy 108.715541 -421.534621) (xy 108.633722 -421.458707)
			(xy 108.546459 -421.38912) (xy 108.45424 -421.326248) (xy 108.357581 -421.270444) (xy 108.257021 -421.222019)
			(xy 108.153124 -421.181244) (xy 108.046471 -421.148347) (xy 107.937657 -421.123512) (xy 107.827292 -421.106879)
			(xy 107.715992 -421.098539) (xy 107.660186 -421.097964) (xy 100.359972 -421.097964) (xy 100.304165 -421.098487)
			(xy 100.192864 -421.106829) (xy 100.082497 -421.123466) (xy 99.973681 -421.148304) (xy 99.867027 -421.181204)
			(xy 99.763129 -421.221982) (xy 99.662568 -421.27041) (xy 99.565908 -421.326217) (xy 99.473689 -421.389091)
			(xy 99.386425 -421.458681) (xy 99.304606 -421.534598) (xy 99.228689 -421.616416) (xy 99.159099 -421.703679)
			(xy 99.096223 -421.795898) (xy 99.040415 -421.892558) (xy 98.991987 -421.993118) (xy 98.951208 -422.097015)
			(xy 98.918307 -422.20367) (xy 98.893468 -422.312485) (xy 98.876831 -422.422852) (xy 98.868487 -422.534153)
			(xy 98.867976 -422.58996) (xy 98.867976 -429.090074) (xy 98.867492 -429.160428) (xy 98.859604 -429.300915)
			(xy 98.843851 -429.440739) (xy 98.820283 -429.57946) (xy 98.788973 -429.716641) (xy 98.750021 -429.85185)
			(xy 98.703549 -429.984663) (xy 98.649703 -430.114661) (xy 98.588652 -430.241435) (xy 98.520589 -430.364587)
			(xy 98.445729 -430.483729) (xy 98.364305 -430.598485) (xy 98.276575 -430.708496) (xy 98.182814 -430.813414)
			(xy 98.083319 -430.91291) (xy 97.9784 -431.006671) (xy 97.86839 -431.094401) (xy 97.753634 -431.175825)
			(xy 97.634492 -431.250686) (xy 97.511341 -431.31875) (xy 97.384567 -431.3798) (xy 97.254569 -431.433647)
			(xy 97.121756 -431.480119) (xy 96.986547 -431.519072) (xy 96.849366 -431.550382) (xy 96.710645 -431.57395)
			(xy 96.570821 -431.589704) (xy 96.430334 -431.597592) (xy 96.35998 -431.59807) (xy 23.6601 -431.59807)
			(xy 23.589746 -431.597586) (xy 23.44926 -431.589696) (xy 23.309437 -431.573942) (xy 23.170718 -431.550372)
			(xy 23.033539 -431.519062) (xy 22.89833 -431.480109) (xy 22.765519 -431.433636) (xy 22.635522 -431.379789)
			(xy 22.50875 -431.318738) (xy 22.385599 -431.250675) (xy 22.266459 -431.175813) (xy 22.151704 -431.094389)
			(xy 22.041695 -431.006659) (xy 21.936778 -430.912899) (xy 21.837283 -430.813403) (xy 21.743524 -430.708485)
			(xy 21.655795 -430.598475) (xy 21.574372 -430.483719) (xy 21.499512 -430.364578) (xy 21.43145 -430.241427)
			(xy 21.370401 -430.114654) (xy 21.316555 -429.984657) (xy 21.270083 -429.851845) (xy 21.231132 -429.716636)
			(xy 21.199823 -429.579456) (xy 21.176255 -429.440737) (xy 21.160502 -429.300914) (xy 21.152614 -429.160428)
			(xy 21.152104 -429.090074) (xy 21.152104 -422.58996) (xy 21.151595 -422.534153) (xy 21.143254 -422.42285)
			(xy 21.126618 -422.312481) (xy 21.101782 -422.203665) (xy 21.068883 -422.097009) (xy 21.028105 -421.993109)
			(xy 20.979677 -421.892548) (xy 20.92387 -421.795886) (xy 20.860995 -421.703666) (xy 20.791404 -421.616402)
			(xy 20.715486 -421.534582) (xy 20.633667 -421.458665) (xy 20.546403 -421.389074) (xy 20.454182 -421.326199)
			(xy 20.357521 -421.270392) (xy 20.256959 -421.221964) (xy 20.153059 -421.181187) (xy 20.046403 -421.148288)
			(xy 19.937587 -421.123451) (xy 19.827218 -421.106816) (xy 19.715915 -421.098475) (xy 19.660108 -421.097964)
			(xy 1.999996 -421.097964) (xy 1.944189 -421.098486) (xy 1.832887 -421.106827) (xy 1.72252 -421.123463)
			(xy 1.613705 -421.148299) (xy 1.50705 -421.181198) (xy 1.403151 -421.221976) (xy 1.302591 -421.270403)
			(xy 1.20593 -421.32621) (xy 1.113711 -421.389085) (xy 1.026448 -421.458675) (xy 0.944629 -421.534592)
			(xy 0.868712 -421.616411) (xy 0.799122 -421.703674) (xy 0.736248 -421.795894) (xy 0.680441 -421.892554)
			(xy 0.632014 -421.993115) (xy 0.591237 -422.097013) (xy 0.558338 -422.203669) (xy 0.533502 -422.312484)
			(xy 0.516867 -422.422851) (xy 0.508526 -422.534153) (xy 0.508 -422.58996) (xy 0.508 -457.5681) (xy 2.904225 -457.5681)
			(xy 2.904225 -457.43896) (xy 2.912175 -457.310065) (xy 2.928045 -457.181905) (xy 2.951774 -457.054964)
			(xy 2.983273 -456.929725) (xy 3.022422 -456.806662) (xy 3.069073 -456.686243) (xy 3.123048 -456.568924)
			(xy 3.184143 -456.45515) (xy 3.252126 -456.345353) (xy 3.32674 -456.23995) (xy 3.407701 -456.13934)
			(xy 3.494701 -456.043905) (xy 3.587412 -455.954006) (xy 3.685482 -455.869985) (xy 3.788537 -455.792161)
			(xy 3.896188 -455.720829) (xy 4.008027 -455.656259) (xy 4.123628 -455.598697) (xy 4.242553 -455.54836)
			(xy 4.364352 -455.50544) (xy 4.488562 -455.470099) (xy 4.614711 -455.442472) (xy 4.742323 -455.422663)
			(xy 4.870912 -455.410747) (xy 4.99999 -455.406771) (xy 5.129068 -455.410747) (xy 5.257657 -455.422663)
			(xy 5.385269 -455.442472) (xy 5.511418 -455.470099) (xy 5.635628 -455.50544) (xy 5.757427 -455.54836)
			(xy 5.876352 -455.598697) (xy 5.991953 -455.656259) (xy 6.103792 -455.720829) (xy 6.211443 -455.792161)
			(xy 6.314498 -455.869985) (xy 6.412568 -455.954006) (xy 6.505279 -456.043905) (xy 6.592279 -456.13934)
			(xy 6.67324 -456.23995) (xy 6.747854 -456.345353) (xy 6.815837 -456.45515) (xy 6.876932 -456.568924)
			(xy 6.930907 -456.686243) (xy 6.977558 -456.806662) (xy 7.016707 -456.929725) (xy 7.048206 -457.054964)
			(xy 7.071935 -457.181905) (xy 7.087805 -457.310065) (xy 7.095755 -457.43896) (xy 7.096252 -457.50353)
			(xy 7.095755 -457.5681) (xy 460.504275 -457.5681) (xy 460.504275 -457.43896) (xy 460.512225 -457.310065)
			(xy 460.528095 -457.181905) (xy 460.551824 -457.054964) (xy 460.583323 -456.929725) (xy 460.622472 -456.806662)
			(xy 460.669123 -456.686243) (xy 460.723098 -456.568924) (xy 460.784193 -456.45515) (xy 460.852176 -456.345353)
			(xy 460.92679 -456.23995) (xy 461.007751 -456.13934) (xy 461.094751 -456.043905) (xy 461.187462 -455.954006)
			(xy 461.285532 -455.869985) (xy 461.388587 -455.792161) (xy 461.496238 -455.720829) (xy 461.608077 -455.656259)
			(xy 461.723678 -455.598697) (xy 461.842603 -455.54836) (xy 461.964402 -455.50544) (xy 462.088612 -455.470099)
			(xy 462.214761 -455.442472) (xy 462.342373 -455.422663) (xy 462.470962 -455.410747) (xy 462.60004 -455.406771)
			(xy 462.729118 -455.410747) (xy 462.857707 -455.422663) (xy 462.985319 -455.442472) (xy 463.111468 -455.470099)
			(xy 463.235678 -455.50544) (xy 463.357477 -455.54836) (xy 463.476402 -455.598697) (xy 463.592003 -455.656259)
			(xy 463.703842 -455.720829) (xy 463.811493 -455.792161) (xy 463.914548 -455.869985) (xy 464.012618 -455.954006)
			(xy 464.105329 -456.043905) (xy 464.192329 -456.13934) (xy 464.27329 -456.23995) (xy 464.347904 -456.345353)
			(xy 464.415887 -456.45515) (xy 464.476982 -456.568924) (xy 464.530957 -456.686243) (xy 464.577608 -456.806662)
			(xy 464.616757 -456.929725) (xy 464.648256 -457.054964) (xy 464.671985 -457.181905) (xy 464.687855 -457.310065)
			(xy 464.695805 -457.43896) (xy 464.696302 -457.50353) (xy 464.695805 -457.5681) (xy 464.687855 -457.696995)
			(xy 464.671985 -457.825155) (xy 464.648256 -457.952096) (xy 464.616757 -458.077335) (xy 464.577608 -458.200398)
			(xy 464.530957 -458.320817) (xy 464.476982 -458.438136) (xy 464.415887 -458.55191) (xy 464.347904 -458.661707)
			(xy 464.27329 -458.76711) (xy 464.192329 -458.86772) (xy 464.105329 -458.963155) (xy 464.012618 -459.053054)
			(xy 463.914548 -459.137075) (xy 463.811493 -459.214899) (xy 463.703842 -459.286231) (xy 463.592003 -459.350801)
			(xy 463.476402 -459.408363) (xy 463.357477 -459.4587) (xy 463.235678 -459.50162) (xy 463.111468 -459.536961)
			(xy 462.985319 -459.564588) (xy 462.857707 -459.584397) (xy 462.729118 -459.596313) (xy 462.60004 -459.60029)
			(xy 462.470962 -459.596313) (xy 462.342373 -459.584397) (xy 462.214761 -459.564588) (xy 462.088612 -459.536961)
			(xy 461.964402 -459.50162) (xy 461.842603 -459.4587) (xy 461.723678 -459.408363) (xy 461.608077 -459.350801)
			(xy 461.496238 -459.286231) (xy 461.388587 -459.214899) (xy 461.285532 -459.137075) (xy 461.187462 -459.053054)
			(xy 461.094751 -458.963155) (xy 461.007751 -458.86772) (xy 460.92679 -458.76711) (xy 460.852176 -458.661707)
			(xy 460.784193 -458.55191) (xy 460.723098 -458.438136) (xy 460.669123 -458.320817) (xy 460.622472 -458.200398)
			(xy 460.583323 -458.077335) (xy 460.551824 -457.952096) (xy 460.528095 -457.825155) (xy 460.512225 -457.696995)
			(xy 460.504275 -457.5681) (xy 7.095755 -457.5681) (xy 7.087805 -457.696995) (xy 7.071935 -457.825155)
			(xy 7.048206 -457.952096) (xy 7.016707 -458.077335) (xy 6.977558 -458.200398) (xy 6.930907 -458.320817)
			(xy 6.876932 -458.438136) (xy 6.815837 -458.55191) (xy 6.747854 -458.661707) (xy 6.67324 -458.76711)
			(xy 6.592279 -458.86772) (xy 6.505279 -458.963155) (xy 6.412568 -459.053054) (xy 6.314498 -459.137075)
			(xy 6.211443 -459.214899) (xy 6.103792 -459.286231) (xy 5.991953 -459.350801) (xy 5.876352 -459.408363)
			(xy 5.757427 -459.4587) (xy 5.635628 -459.50162) (xy 5.511418 -459.536961) (xy 5.385269 -459.564588)
			(xy 5.257657 -459.584397) (xy 5.129068 -459.596313) (xy 4.99999 -459.60029) (xy 4.870912 -459.596313)
			(xy 4.742323 -459.584397) (xy 4.614711 -459.564588) (xy 4.488562 -459.536961) (xy 4.364352 -459.50162)
			(xy 4.242553 -459.4587) (xy 4.123628 -459.408363) (xy 4.008027 -459.350801) (xy 3.896188 -459.286231)
			(xy 3.788537 -459.214899) (xy 3.685482 -459.137075) (xy 3.587412 -459.053054) (xy 3.494701 -458.963155)
			(xy 3.407701 -458.86772) (xy 3.32674 -458.76711) (xy 3.252126 -458.661707) (xy 3.184143 -458.55191)
			(xy 3.123048 -458.438136) (xy 3.069073 -458.320817) (xy 3.022422 -458.200398) (xy 2.983273 -458.077335)
			(xy 2.951774 -457.952096) (xy 2.928045 -457.825155) (xy 2.912175 -457.696995) (xy 2.904225 -457.5681)
			(xy 0.508 -457.5681) (xy 0.508 -460.503524) (xy 0.508522 -460.559331) (xy 0.516863 -460.670633) (xy 0.533498 -460.781)
			(xy 0.558335 -460.889816) (xy 0.591234 -460.996471) (xy 0.632011 -461.10037) (xy 0.680438 -461.20093)
			(xy 0.736246 -461.297591) (xy 0.79912 -461.389811) (xy 0.86871 -461.477074) (xy 0.944627 -461.558893)
			(xy 1.026446 -461.63481) (xy 1.113709 -461.7044) (xy 1.205929 -461.767274) (xy 1.30259 -461.823082)
			(xy 1.40315 -461.871509) (xy 1.507049 -461.912286) (xy 1.613704 -461.945185) (xy 1.72252 -461.970022)
			(xy 1.832887 -461.986657) (xy 1.944189 -461.994998) (xy 1.999996 -461.99552)
		)
		(stroke
			(width 0)
			(type solid)
		)
		(fill yes)
		(layer "In10.Cu")
		(net "COUPON_GND1")
	)
	(gr_poly
		(pts
			(xy 13.96492 -10.342118) (xy 14.020727 -10.341596) (xy 14.132028 -10.333253) (xy 14.242395 -10.316617)
			(xy 14.35121 -10.29178) (xy 14.457865 -10.25888) (xy 14.561763 -10.218102) (xy 14.662323 -10.169674)
			(xy 14.758983 -10.113867) (xy 14.851203 -10.050993) (xy 14.938466 -9.981402) (xy 15.020284 -9.905486)
			(xy 15.096201 -9.823667) (xy 15.165791 -9.736404) (xy 15.228666 -9.644185) (xy 15.284473 -9.547525)
			(xy 15.332901 -9.446965) (xy 15.373679 -9.343067) (xy 15.406579 -9.236412) (xy 15.431417 -9.127597)
			(xy 15.448053 -9.01723) (xy 15.456395 -8.905929) (xy 15.456916 -8.850122) (xy 15.456916 0) (xy 15.4574 0.070354)
			(xy 15.46529 0.21084) (xy 15.481044 0.350663) (xy 15.504614 0.489383) (xy 15.535924 0.626563) (xy 15.574877 0.761771)
			(xy 15.62135 0.894583) (xy 15.675197 1.02458) (xy 15.736248 1.151353) (xy 15.804311 1.274504) (xy 15.879172 1.393644)
			(xy 15.960596 1.5084) (xy 16.048326 1.618409) (xy 16.142086 1.723327) (xy 16.241582 1.822822) (xy 16.3465 1.916582)
			(xy 16.45651 2.004311) (xy 16.571266 2.085734) (xy 16.690407 2.160595) (xy 16.813558 2.228658) (xy 16.940331 2.289708)
			(xy 17.070328 2.343554) (xy 17.20314 2.390026) (xy 17.338349 2.428979) (xy 17.475529 2.460289) (xy 17.614249 2.483858)
			(xy 17.754072 2.499611) (xy 17.894558 2.5075) (xy 17.964912 2.507996) (xy 33.96488 2.507996) (xy 34.035234 2.507512)
			(xy 34.175722 2.499624) (xy 34.315546 2.48387) (xy 34.454267 2.460302) (xy 34.591448 2.428992) (xy 34.726657 2.39004)
			(xy 34.85947 2.343568) (xy 34.989468 2.289721) (xy 35.116243 2.228671) (xy 35.239395 2.160608) (xy 35.358537 2.085747)
			(xy 35.473294 2.004324) (xy 35.583304 1.916594) (xy 35.688223 1.822833) (xy 35.78772 1.723338) (xy 35.881481 1.61842)
			(xy 35.969212 1.50841) (xy 36.050636 1.393653) (xy 36.125498 1.274512) (xy 36.193562 1.151361) (xy 36.254613 1.024587)
			(xy 36.30846 0.894589) (xy 36.354934 0.761776) (xy 36.393887 0.626567) (xy 36.425198 0.489386) (xy 36.448768 0.350666)
			(xy 36.464522 0.210842) (xy 36.472412 0.070354) (xy 36.472876 0) (xy 36.472876 -8.850122) (xy 36.473399 -8.905929)
			(xy 36.481741 -9.01723) (xy 36.498377 -9.127597) (xy 36.523215 -9.236413) (xy 36.556114 -9.343067)
			(xy 36.596892 -9.446965) (xy 36.64532 -9.547526) (xy 36.701127 -9.644186) (xy 36.764002 -9.736405)
			(xy 36.833592 -9.823668) (xy 36.909508 -9.905487) (xy 36.991327 -9.981404) (xy 37.07859 -10.050995)
			(xy 37.170809 -10.113869) (xy 37.267469 -10.169677) (xy 37.368029 -10.218105) (xy 37.471927 -10.258884)
			(xy 37.578582 -10.291784) (xy 37.687397 -10.316622) (xy 37.797764 -10.333258) (xy 37.909065 -10.341601)
			(xy 37.964872 -10.342118) (xy 39.965122 -10.342118) (xy 40.020929 -10.341595) (xy 40.13223 -10.333253)
			(xy 40.242597 -10.316617) (xy 40.351412 -10.291779) (xy 40.458067 -10.258879) (xy 40.561964 -10.218102)
			(xy 40.662525 -10.169674) (xy 40.759184 -10.113866) (xy 40.851404 -10.050992) (xy 40.938667 -9.981402)
			(xy 41.020485 -9.905485) (xy 41.096402 -9.823667) (xy 41.165992 -9.736404) (xy 41.228866 -9.644184)
			(xy 41.284674 -9.547525) (xy 41.333102 -9.446964) (xy 41.373879 -9.343067) (xy 41.406779 -9.236412)
			(xy 41.431617 -9.127597) (xy 41.448253 -9.01723) (xy 41.456595 -8.905929) (xy 41.457118 -8.850122)
			(xy 41.457118 0) (xy 41.457602 0.070354) (xy 41.465492 0.21084) (xy 41.481246 0.350663) (xy 41.504816 0.489383)
			(xy 41.536126 0.626563) (xy 41.575079 0.761771) (xy 41.621552 0.894583) (xy 41.675399 1.02458) (xy 41.73645 1.151353)
			(xy 41.804513 1.274503) (xy 41.879374 1.393644) (xy 41.960798 1.508399) (xy 42.048528 1.618409) (xy 42.142288 1.723326)
			(xy 42.241784 1.822821) (xy 42.346702 1.916581) (xy 42.456712 2.00431) (xy 42.571468 2.085733) (xy 42.690609 2.160594)
			(xy 42.81376 2.228657) (xy 42.940533 2.289707) (xy 43.07053 2.343553) (xy 43.203342 2.390025) (xy 43.338551 2.428977)
			(xy 43.475731 2.460287) (xy 43.614451 2.483856) (xy 43.754274 2.499609) (xy 43.89476 2.507498) (xy 43.965114 2.507996)
			(xy 59.965082 2.507996) (xy 60.035436 2.507512) (xy 60.175924 2.499624) (xy 60.315748 2.48387) (xy 60.454468 2.460301)
			(xy 60.591649 2.428992) (xy 60.726859 2.390039) (xy 60.859672 2.343567) (xy 60.98967 2.289721) (xy 61.116444 2.22867)
			(xy 61.239596 2.160607) (xy 61.358738 2.085747) (xy 61.473495 2.004323) (xy 61.583505 1.916593) (xy 61.688424 1.822833)
			(xy 61.78792 1.723337) (xy 61.881681 1.618419) (xy 61.969412 1.508409) (xy 62.050837 1.393653) (xy 62.125698 1.274512)
			(xy 62.193762 1.15136) (xy 62.254813 1.024586) (xy 62.308661 0.894588) (xy 62.355134 0.761776) (xy 62.394087 0.626567)
			(xy 62.425398 0.489386) (xy 62.448968 0.350665) (xy 62.464722 0.210842) (xy 62.472612 0.070354) (xy 62.473078 0)
			(xy 62.473078 -8.850122) (xy 62.473601 -8.905929) (xy 62.481943 -9.01723) (xy 62.498579 -9.127597)
			(xy 62.523417 -9.236412) (xy 62.556316 -9.343067) (xy 62.597094 -9.446965) (xy 62.645522 -9.547525)
			(xy 62.701329 -9.644185) (xy 62.764204 -9.736405) (xy 62.833794 -9.823668) (xy 62.909711 -9.905487)
			(xy 62.991529 -9.981403) (xy 63.078792 -10.050994) (xy 63.171011 -10.113868) (xy 63.267671 -10.169676)
			(xy 63.368231 -10.218104) (xy 63.472129 -10.258882) (xy 63.578784 -10.291782) (xy 63.687599 -10.31662)
			(xy 63.797966 -10.333257) (xy 63.909267 -10.341599) (xy 63.965074 -10.342118) (xy 65.96507 -10.342118)
			(xy 66.020879 -10.34161) (xy 66.132184 -10.333271) (xy 66.242554 -10.316637) (xy 66.351373 -10.291802)
			(xy 66.458032 -10.258905) (xy 66.561934 -10.218128) (xy 66.662499 -10.169702) (xy 66.759163 -10.113895)
			(xy 66.851386 -10.05102) (xy 66.938653 -9.98143) (xy 67.020476 -9.905512) (xy 67.096396 -9.823693)
			(xy 67.165989 -9.736428) (xy 67.228867 -9.644207) (xy 67.284677 -9.547545) (xy 67.333108 -9.446982)
			(xy 67.373888 -9.343081) (xy 67.406789 -9.236424) (xy 67.431628 -9.127605) (xy 67.448265 -9.017235)
			(xy 67.456608 -8.905931) (xy 67.457066 -8.850122) (xy 67.457066 0) (xy 67.457559 0.070354) (xy 67.465449 0.210841)
			(xy 67.481203 0.350665) (xy 67.504772 0.489385) (xy 67.536082 0.626565) (xy 67.575035 0.761774) (xy 67.621508 0.894587)
			(xy 67.675354 1.024584) (xy 67.736404 1.151358) (xy 67.804467 1.27451) (xy 67.879328 1.393651) (xy 67.960751 1.508408)
			(xy 68.04848 1.618419) (xy 68.14224 1.723337) (xy 68.241735 1.822834) (xy 68.346652 1.916595) (xy 68.456662 2.004326)
			(xy 68.571417 2.085751) (xy 68.690557 2.160614) (xy 68.813708 2.228678) (xy 68.940481 2.289731) (xy 69.070478 2.343579)
			(xy 69.203289 2.390053) (xy 69.338498 2.429008) (xy 69.475678 2.46032) (xy 69.614398 2.483892) (xy 69.754221 2.499648)
			(xy 69.894708 2.50754) (xy 69.965062 2.507996) (xy 85.96503 2.507996) (xy 86.035383 2.507502) (xy 86.175868 2.499611)
			(xy 86.31569 2.483855) (xy 86.454408 2.460284) (xy 86.591586 2.428973) (xy 86.726793 2.390019) (xy 86.859603 2.343545)
			(xy 86.989598 2.289698) (xy 87.11637 2.228647) (xy 87.239519 2.160584) (xy 87.358658 2.085722) (xy 87.473412 2.004299)
			(xy 87.58342 1.916569) (xy 87.688336 1.822809) (xy 87.78783 1.723314) (xy 87.881588 1.618397) (xy 87.969317 1.508388)
			(xy 88.050739 1.393633) (xy 88.125599 1.274493) (xy 88.193661 1.151343) (xy 88.254711 1.024571) (xy 88.308556 0.894575)
			(xy 88.355028 0.761764) (xy 88.39398 0.626557) (xy 88.42529 0.489378) (xy 88.448859 0.35066) (xy 88.464613 0.210838)
			(xy 88.472503 0.070353) (xy 88.473026 0) (xy 88.473026 -8.850122) (xy 88.473549 -8.905928) (xy 88.481891 -9.017228)
			(xy 88.498528 -9.127594) (xy 88.523365 -9.236408) (xy 88.556265 -9.343061) (xy 88.597043 -9.446957)
			(xy 88.645472 -9.547516) (xy 88.701279 -9.644174) (xy 88.764154 -9.736392) (xy 88.833745 -9.823653)
			(xy 88.909662 -9.90547) (xy 88.99148 -9.981384) (xy 89.078743 -10.050972) (xy 89.170963 -10.113844)
			(xy 89.267623 -10.169649) (xy 89.368183 -10.218074) (xy 89.472081 -10.258849) (xy 89.578735 -10.291746)
			(xy 89.687549 -10.316581) (xy 89.797915 -10.333214) (xy 89.909216 -10.341553) (xy 89.965022 -10.342118)
			(xy 91.965018 -10.342118) (xy 92.020825 -10.341596) (xy 92.132127 -10.333254) (xy 92.242494 -10.316617)
			(xy 92.351309 -10.29178) (xy 92.457964 -10.258881) (xy 92.561862 -10.218103) (xy 92.662422 -10.169675)
			(xy 92.759082 -10.113868) (xy 92.851302 -10.050993) (xy 92.938565 -9.981403) (xy 93.020384 -9.905487)
			(xy 93.096301 -9.823668) (xy 93.165891 -9.736405) (xy 93.228766 -9.644186) (xy 93.284573 -9.547526)
			(xy 93.333001 -9.446965) (xy 93.373779 -9.343067) (xy 93.406679 -9.236413) (xy 93.431517 -9.127597)
			(xy 93.448153 -9.01723) (xy 93.456495 -8.905929) (xy 93.457014 -8.850122) (xy 93.457014 0) (xy 93.457498 0.070354)
			(xy 93.465388 0.21084) (xy 93.481142 0.350663) (xy 93.504712 0.489383) (xy 93.536022 0.626563) (xy 93.574975 0.761771)
			(xy 93.621448 0.894583) (xy 93.675295 1.02458) (xy 93.736346 1.151353) (xy 93.804409 1.274504) (xy 93.87927 1.393645)
			(xy 93.960694 1.5084) (xy 94.048424 1.61841) (xy 94.142184 1.723327) (xy 94.24168 1.822823) (xy 94.346598 1.916583)
			(xy 94.456608 2.004312) (xy 94.571364 2.085735) (xy 94.690505 2.160596) (xy 94.813655 2.228659) (xy 94.940429 2.289709)
			(xy 95.070426 2.343555) (xy 95.203238 2.390028) (xy 95.338447 2.42898) (xy 95.475627 2.46029) (xy 95.614347 2.483859)
			(xy 95.75417 2.499613) (xy 95.894656 2.507502) (xy 95.96501 2.507996) (xy 124.06503 2.507996) (xy 124.135383 2.507502)
			(xy 124.275868 2.499611) (xy 124.41569 2.483855) (xy 124.554408 2.460284) (xy 124.691586 2.428973)
			(xy 124.826793 2.390019) (xy 124.959603 2.343545) (xy 125.089598 2.289698) (xy 125.21637 2.228647)
			(xy 125.339519 2.160584) (xy 125.458658 2.085722) (xy 125.573412 2.004299) (xy 125.68342 1.916569)
			(xy 125.788336 1.822809) (xy 125.88783 1.723314) (xy 125.981588 1.618397) (xy 126.069317 1.508388)
			(xy 126.150739 1.393633) (xy 126.225599 1.274493) (xy 126.293661 1.151343) (xy 126.354711 1.024571)
			(xy 126.408556 0.894575) (xy 126.455028 0.761764) (xy 126.49398 0.626557) (xy 126.52529 0.489378)
			(xy 126.548859 0.35066) (xy 126.564613 0.210838) (xy 126.572503 0.070353) (xy 126.573026 0) (xy 126.573026 -8.850122)
			(xy 126.573549 -8.905928) (xy 126.581891 -9.017228) (xy 126.598528 -9.127594) (xy 126.623365 -9.236408)
			(xy 126.656265 -9.343061) (xy 126.697043 -9.446957) (xy 126.745472 -9.547516) (xy 126.801279 -9.644174)
			(xy 126.864154 -9.736392) (xy 126.933745 -9.823653) (xy 127.009662 -9.90547) (xy 127.09148 -9.981384)
			(xy 127.178743 -10.050972) (xy 127.270963 -10.113844) (xy 127.367623 -10.169649) (xy 127.468183 -10.218074)
			(xy 127.572081 -10.258849) (xy 127.678735 -10.291746) (xy 127.787549 -10.316581) (xy 127.897915 -10.333214)
			(xy 128.009216 -10.341553) (xy 128.065022 -10.342118) (xy 130.065018 -10.342118) (xy 130.120825 -10.341596)
			(xy 130.232127 -10.333254) (xy 130.342494 -10.316617) (xy 130.451309 -10.29178) (xy 130.557964 -10.258881)
			(xy 130.661862 -10.218103) (xy 130.762422 -10.169675) (xy 130.859082 -10.113868) (xy 130.951302 -10.050993)
			(xy 131.038565 -9.981403) (xy 131.120384 -9.905487) (xy 131.196301 -9.823668) (xy 131.265891 -9.736405)
			(xy 131.328766 -9.644186) (xy 131.384573 -9.547526) (xy 131.433001 -9.446965) (xy 131.473779 -9.343067)
			(xy 131.506679 -9.236413) (xy 131.531517 -9.127597) (xy 131.548153 -9.01723) (xy 131.556495 -8.905929)
			(xy 131.557014 -8.850122) (xy 131.557014 0) (xy 131.557498 0.070354) (xy 131.565388 0.21084) (xy 131.581142 0.350663)
			(xy 131.604712 0.489383) (xy 131.636022 0.626563) (xy 131.674975 0.761771) (xy 131.721448 0.894583)
			(xy 131.775295 1.02458) (xy 131.836346 1.151353) (xy 131.904409 1.274504) (xy 131.97927 1.393645)
			(xy 132.060694 1.5084) (xy 132.148424 1.61841) (xy 132.242184 1.723327) (xy 132.34168 1.822823) (xy 132.446598 1.916583)
			(xy 132.556608 2.004312) (xy 132.671364 2.085735) (xy 132.790505 2.160596) (xy 132.913655 2.228659)
			(xy 133.040429 2.289709) (xy 133.170426 2.343555) (xy 133.303238 2.390028) (xy 133.438447 2.42898)
			(xy 133.575627 2.46029) (xy 133.714347 2.483859) (xy 133.85417 2.499613) (xy 133.994656 2.507502)
			(xy 134.06501 2.507996) (xy 150.064978 2.507996) (xy 150.135332 2.507512) (xy 150.27582 2.499624)
			(xy 150.415644 2.483871) (xy 150.554365 2.460302) (xy 150.691546 2.428993) (xy 150.826756 2.39004)
			(xy 150.959569 2.343568) (xy 151.089567 2.289722) (xy 151.216342 2.228672) (xy 151.339494 2.160609)
			(xy 151.458636 2.085748) (xy 151.573393 2.004324) (xy 151.683404 1.916594) (xy 151.788322 1.822834)
			(xy 151.887819 1.723338) (xy 151.98158 1.61842) (xy 152.069311 1.50841) (xy 152.150736 1.393654)
			(xy 152.225598 1.274513) (xy 152.293661 1.151361) (xy 152.354713 1.024587) (xy 152.40856 0.894589)
			(xy 152.455034 0.761777) (xy 152.493987 0.626567) (xy 152.525298 0.489386) (xy 152.548868 0.350666)
			(xy 152.564622 0.210842) (xy 152.572512 0.070354) (xy 152.572974 0) (xy 152.572974 -8.850122) (xy 152.573497 -8.905929)
			(xy 152.581839 -9.017231) (xy 152.598475 -9.127598) (xy 152.623313 -9.236413) (xy 152.656212 -9.343068)
			(xy 152.69699 -9.446966) (xy 152.745418 -9.547526) (xy 152.801225 -9.644186) (xy 152.8641 -9.736406)
			(xy 152.93369 -9.823669) (xy 153.009606 -9.905488) (xy 153.091425 -9.981405) (xy 153.178688 -10.050995)
			(xy 153.270907 -10.11387) (xy 153.367567 -10.169678) (xy 153.468127 -10.218107) (xy 153.572025 -10.258885)
			(xy 153.67868 -10.291785) (xy 153.787495 -10.316623) (xy 153.897862 -10.33326) (xy 154.009163 -10.341603)
			(xy 154.06497 -10.342118) (xy 156.064966 -10.342118) (xy 156.120775 -10.34161) (xy 156.23208 -10.333271)
			(xy 156.342451 -10.316638) (xy 156.45127 -10.291803) (xy 156.557929 -10.258906) (xy 156.661832 -10.21813)
			(xy 156.762396 -10.169703) (xy 156.859061 -10.113896) (xy 156.951284 -10.051022) (xy 157.038552 -9.981431)
			(xy 157.120374 -9.905514) (xy 157.196295 -9.823694) (xy 157.265888 -9.736429) (xy 157.328766 -9.644208)
			(xy 157.384577 -9.547546) (xy 157.433007 -9.446983) (xy 157.473787 -9.343082) (xy 157.506689 -9.236424)
			(xy 157.531528 -9.127606) (xy 157.548165 -9.017236) (xy 157.556508 -8.905931) (xy 157.556962 -8.850122)
			(xy 157.556962 0) (xy 157.557455 0.070354) (xy 157.565345 0.210841) (xy 157.581099 0.350665) (xy 157.604668 0.489385)
			(xy 157.635978 0.626566) (xy 157.674931 0.761775) (xy 157.721404 0.894587) (xy 157.77525 1.024585)
			(xy 157.8363 1.151359) (xy 157.904363 1.274511) (xy 157.979224 1.393652) (xy 158.060647 1.508409)
			(xy 158.148376 1.61842) (xy 158.242136 1.723339) (xy 158.341631 1.822835) (xy 158.446548 1.916597)
			(xy 158.556557 2.004328) (xy 158.671313 2.085753) (xy 158.790453 2.160616) (xy 158.913604 2.22868)
			(xy 159.040377 2.289733) (xy 159.170374 2.343581) (xy 159.303185 2.390056) (xy 159.438394 2.429011)
			(xy 159.575574 2.460324) (xy 159.714294 2.483895) (xy 159.854117 2.499652) (xy 159.994604 2.507544)
			(xy 160.064958 2.507996) (xy 176.064926 2.507996) (xy 176.135279 2.507502) (xy 176.275764 2.499611)
			(xy 176.415586 2.483856) (xy 176.554304 2.460285) (xy 176.691483 2.428974) (xy 176.82669 2.39002)
			(xy 176.9595 2.343547) (xy 177.089496 2.289699) (xy 177.216267 2.228648) (xy 177.339416 2.160585)
			(xy 177.458556 2.085724) (xy 177.57331 2.0043) (xy 177.683318 1.91657) (xy 177.788234 1.822811) (xy 177.887728 1.723315)
			(xy 177.981487 1.618398) (xy 178.069216 1.508389) (xy 178.150638 1.393634) (xy 178.225498 1.274494)
			(xy 178.29356 1.151344) (xy 178.35461 1.024572) (xy 178.408456 0.894576) (xy 178.454928 0.761765)
			(xy 178.49388 0.626558) (xy 178.52519 0.489379) (xy 178.548759 0.35066) (xy 178.564513 0.210838)
			(xy 178.572403 0.070353) (xy 178.572922 0) (xy 178.572922 -8.850122) (xy 178.573445 -8.905928) (xy 178.581787 -9.017229)
			(xy 178.598424 -9.127594) (xy 178.623261 -9.236408) (xy 178.656161 -9.343061) (xy 178.696939 -9.446958)
			(xy 178.745367 -9.547517) (xy 178.801175 -9.644175) (xy 178.86405 -9.736393) (xy 178.93364 -9.823654)
			(xy 179.009557 -9.905471) (xy 179.091376 -9.981386) (xy 179.178639 -10.050974) (xy 179.270859 -10.113846)
			(xy 179.367519 -10.169651) (xy 179.468079 -10.218077) (xy 179.571976 -10.258852) (xy 179.678631 -10.291749)
			(xy 179.787445 -10.316584) (xy 179.897811 -10.333218) (xy 180.009112 -10.341557) (xy 180.064918 -10.342118)
			(xy 182.064914 -10.342118) (xy 182.120721 -10.341596) (xy 182.232023 -10.333254) (xy 182.34239 -10.316618)
			(xy 182.451206 -10.291781) (xy 182.557861 -10.258882) (xy 182.661759 -10.218104) (xy 182.76232 -10.169676)
			(xy 182.85898 -10.113869) (xy 182.9512 -10.050995) (xy 183.038463 -9.981405) (xy 183.120282 -9.905488)
			(xy 183.196199 -9.823669) (xy 183.26579 -9.736406) (xy 183.328665 -9.644187) (xy 183.384473 -9.547527)
			(xy 183.432901 -9.446966) (xy 183.473679 -9.343068) (xy 183.506579 -9.236413) (xy 183.531416 -9.127598)
			(xy 183.548053 -9.017231) (xy 183.556395 -8.905929) (xy 183.55691 -8.850122) (xy 183.55691 0) (xy 183.557394 0.070354)
			(xy 183.565284 0.21084) (xy 183.581038 0.350664) (xy 183.604608 0.489383) (xy 183.635918 0.626563)
			(xy 183.674871 0.761772) (xy 183.721344 0.894584) (xy 183.775191 1.024581) (xy 183.836242 1.151354)
			(xy 183.904305 1.274505) (xy 183.979166 1.393646) (xy 184.06059 1.508401) (xy 184.14832 1.618411)
			(xy 184.24208 1.723329) (xy 184.341576 1.822824) (xy 184.446493 1.916584) (xy 184.556503 2.004314)
			(xy 184.671259 2.085737) (xy 184.7904 2.160598) (xy 184.913551 2.228661) (xy 185.040325 2.289712)
			(xy 185.170322 2.343558) (xy 185.303134 2.390031) (xy 185.438342 2.428983) (xy 185.575523 2.460294)
			(xy 185.714242 2.483863) (xy 185.854066 2.499617) (xy 185.994552 2.507506) (xy 186.064906 2.507996)
			(xy 202.064874 2.507996) (xy 202.135228 2.507512) (xy 202.275716 2.499624) (xy 202.41554 2.483871)
			(xy 202.554261 2.460303) (xy 202.691443 2.428993) (xy 202.826653 2.390041) (xy 202.959466 2.343569)
			(xy 203.089464 2.289723) (xy 203.216239 2.228673) (xy 203.339391 2.16061) (xy 203.458534 2.085749)
			(xy 203.573291 2.004326) (xy 203.683302 1.916596) (xy 203.788221 1.822836) (xy 203.887718 1.72334)
			(xy 203.981479 1.618422) (xy 204.06921 1.508412) (xy 204.150635 1.393655) (xy 204.225497 1.274514)
			(xy 204.293561 1.151362) (xy 204.354613 1.024588) (xy 204.40846 0.89459) (xy 204.454933 0.761778)
			(xy 204.493887 0.626568) (xy 204.525198 0.489387) (xy 204.548768 0.350666) (xy 204.564522 0.210842)
			(xy 204.572412 0.070354) (xy 204.57287 0) (xy 204.57287 -8.850122) (xy 204.573393 -8.905929) (xy 204.581735 -9.017231)
			(xy 204.598371 -9.127598) (xy 204.623209 -9.236413) (xy 204.656108 -9.343068) (xy 204.696886 -9.446966)
			(xy 204.745314 -9.547527) (xy 204.801121 -9.644187) (xy 204.863996 -9.736407) (xy 204.933586 -9.82367)
			(xy 205.009502 -9.905489) (xy 205.091321 -9.981407) (xy 205.178583 -10.050997) (xy 205.270803 -10.113872)
			(xy 205.367463 -10.16968) (xy 205.468023 -10.218109) (xy 205.571921 -10.258888) (xy 205.678575 -10.291788)
			(xy 205.78739 -10.316626) (xy 205.897757 -10.333264) (xy 206.009059 -10.341607) (xy 206.064866 -10.342118)
			(xy 208.065116 -10.342118) (xy 208.120923 -10.341596) (xy 208.232225 -10.333254) (xy 208.342592 -10.316618)
			(xy 208.451407 -10.29178) (xy 208.558062 -10.258881) (xy 208.66196 -10.218103) (xy 208.762521 -10.169676)
			(xy 208.859181 -10.113868) (xy 208.951401 -10.050994) (xy 209.038664 -9.981404) (xy 209.120483 -9.905487)
			(xy 209.1964 -9.823669) (xy 209.26599 -9.736406) (xy 209.328865 -9.644186) (xy 209.384673 -9.547526)
			(xy 209.433101 -9.446966) (xy 209.473879 -9.343068) (xy 209.506779 -9.236413) (xy 209.531617 -9.127598)
			(xy 209.548253 -9.017231) (xy 209.556595 -8.905929) (xy 209.557112 -8.850122) (xy 209.557112 0) (xy 209.557596 0.070354)
			(xy 209.565486 0.21084) (xy 209.58124 0.350663) (xy 209.60481 0.489383) (xy 209.63612 0.626563) (xy 209.675073 0.761772)
			(xy 209.721546 0.894583) (xy 209.775393 1.02458) (xy 209.836444 1.151354) (xy 209.904507 1.274505)
			(xy 209.979368 1.393645) (xy 210.060792 1.508401) (xy 210.148522 1.618411) (xy 210.242282 1.723328)
			(xy 210.341778 1.822823) (xy 210.446696 1.916583) (xy 210.556706 2.004313) (xy 210.671462 2.085736)
			(xy 210.790602 2.160597) (xy 210.913753 2.22866) (xy 211.040527 2.289711) (xy 211.170524 2.343557)
			(xy 211.303336 2.390029) (xy 211.438545 2.428982) (xy 211.575725 2.460292) (xy 211.714444 2.483861)
			(xy 211.854268 2.499615) (xy 211.994754 2.507504) (xy 212.065108 2.507996) (xy 240.164874 2.507996)
			(xy 240.235228 2.507512) (xy 240.375716 2.499624) (xy 240.51554 2.483871) (xy 240.654261 2.460303)
			(xy 240.791443 2.428993) (xy 240.926653 2.390041) (xy 241.059466 2.343569) (xy 241.189464 2.289723)
			(xy 241.316239 2.228673) (xy 241.439391 2.16061) (xy 241.558534 2.085749) (xy 241.673291 2.004326)
			(xy 241.783302 1.916596) (xy 241.888221 1.822836) (xy 241.987718 1.72334) (xy 242.081479 1.618422)
			(xy 242.16921 1.508412) (xy 242.250635 1.393655) (xy 242.325497 1.274514) (xy 242.393561 1.151362)
			(xy 242.454613 1.024588) (xy 242.50846 0.89459) (xy 242.554933 0.761778) (xy 242.593887 0.626568)
			(xy 242.625198 0.489387) (xy 242.648768 0.350666) (xy 242.664522 0.210842) (xy 242.672412 0.070354)
			(xy 242.67287 0) (xy 242.67287 -8.850122) (xy 242.673393 -8.905929) (xy 242.681735 -9.017231) (xy 242.698371 -9.127598)
			(xy 242.723209 -9.236413) (xy 242.756108 -9.343068) (xy 242.796886 -9.446966) (xy 242.845314 -9.547527)
			(xy 242.901121 -9.644187) (xy 242.963996 -9.736407) (xy 243.033586 -9.82367) (xy 243.109502 -9.905489)
			(xy 243.191321 -9.981407) (xy 243.278583 -10.050997) (xy 243.370803 -10.113872) (xy 243.467463 -10.16968)
			(xy 243.568023 -10.218109) (xy 243.671921 -10.258888) (xy 243.778575 -10.291788) (xy 243.88739 -10.316626)
			(xy 243.997757 -10.333264) (xy 244.109059 -10.341607) (xy 244.164866 -10.342118) (xy 246.165116 -10.342118)
			(xy 246.220923 -10.341596) (xy 246.332225 -10.333254) (xy 246.442592 -10.316618) (xy 246.551407 -10.29178)
			(xy 246.658062 -10.258881) (xy 246.76196 -10.218103) (xy 246.862521 -10.169676) (xy 246.959181 -10.113868)
			(xy 247.051401 -10.050994) (xy 247.138664 -9.981404) (xy 247.220483 -9.905487) (xy 247.2964 -9.823669)
			(xy 247.36599 -9.736406) (xy 247.428865 -9.644186) (xy 247.484673 -9.547526) (xy 247.533101 -9.446966)
			(xy 247.573879 -9.343068) (xy 247.606779 -9.236413) (xy 247.631617 -9.127598) (xy 247.648253 -9.017231)
			(xy 247.656595 -8.905929) (xy 247.657112 -8.850122) (xy 247.657112 0) (xy 247.657596 0.070354) (xy 247.665486 0.21084)
			(xy 247.68124 0.350663) (xy 247.70481 0.489383) (xy 247.73612 0.626563) (xy 247.775073 0.761772)
			(xy 247.821546 0.894583) (xy 247.875393 1.02458) (xy 247.936444 1.151354) (xy 248.004507 1.274505)
			(xy 248.079368 1.393645) (xy 248.160792 1.508401) (xy 248.248522 1.618411) (xy 248.342282 1.723328)
			(xy 248.441778 1.822823) (xy 248.546696 1.916583) (xy 248.656706 2.004313) (xy 248.771462 2.085736)
			(xy 248.890602 2.160597) (xy 249.013753 2.22866) (xy 249.140527 2.289711) (xy 249.270524 2.343557)
			(xy 249.403336 2.390029) (xy 249.538545 2.428982) (xy 249.675725 2.460292) (xy 249.814444 2.483861)
			(xy 249.954268 2.499615) (xy 250.094754 2.507504) (xy 250.165108 2.507996) (xy 266.165076 2.507996)
			(xy 266.23543 2.507512) (xy 266.375918 2.499624) (xy 266.515742 2.483871) (xy 266.654463 2.460303)
			(xy 266.791644 2.428993) (xy 266.926854 2.390041) (xy 267.059667 2.343569) (xy 267.189666 2.289723)
			(xy 267.31644 2.228672) (xy 267.439593 2.160609) (xy 267.558735 2.085749) (xy 267.673492 2.004325)
			(xy 267.783503 1.916595) (xy 267.888422 1.822835) (xy 267.987918 1.723339) (xy 268.08168 1.618421)
			(xy 268.169411 1.508411) (xy 268.250835 1.393655) (xy 268.325697 1.274513) (xy 268.393761 1.151362)
			(xy 268.454813 1.024588) (xy 268.50866 0.89459) (xy 268.555134 0.761777) (xy 268.594087 0.626568)
			(xy 268.625398 0.489387) (xy 268.648968 0.350666) (xy 268.664722 0.210842) (xy 268.672612 0.070354)
			(xy 268.673072 0) (xy 268.673072 -8.850122) (xy 268.673595 -8.905929) (xy 268.681937 -9.017231) (xy 268.698573 -9.127598)
			(xy 268.723411 -9.236413) (xy 268.75631 -9.343068) (xy 268.797088 -9.446966) (xy 268.845516 -9.547526)
			(xy 268.901323 -9.644187) (xy 268.964198 -9.736406) (xy 269.033788 -9.82367) (xy 269.109704 -9.905489)
			(xy 269.191523 -9.981406) (xy 269.278786 -10.050996) (xy 269.371005 -10.113871) (xy 269.467665 -10.169679)
			(xy 269.568225 -10.218108) (xy 269.672123 -10.258886) (xy 269.778777 -10.291787) (xy 269.887592 -10.316625)
			(xy 269.997959 -10.333262) (xy 270.109261 -10.341605) (xy 270.165068 -10.342118) (xy 272.165064 -10.342118)
			(xy 272.220873 -10.34161) (xy 272.332178 -10.333272) (xy 272.442549 -10.316638) (xy 272.551368 -10.291804)
			(xy 272.658028 -10.258906) (xy 272.76193 -10.21813) (xy 272.862495 -10.169703) (xy 272.95916 -10.113897)
			(xy 273.051383 -10.051022) (xy 273.138651 -9.981432) (xy 273.220473 -9.905515) (xy 273.296394 -9.823695)
			(xy 273.365988 -9.73643) (xy 273.428866 -9.644209) (xy 273.484676 -9.547546) (xy 273.533107 -9.446983)
			(xy 273.573887 -9.343082) (xy 273.606789 -9.236425) (xy 273.631628 -9.127606) (xy 273.648265 -9.017236)
			(xy 273.656608 -8.905931) (xy 273.65706 -8.850122) (xy 273.65706 0) (xy 273.657553 0.070354) (xy 273.665443 0.210841)
			(xy 273.681197 0.350665) (xy 273.704766 0.489385) (xy 273.736076 0.626566) (xy 273.775029 0.761775)
			(xy 273.821502 0.894588) (xy 273.875348 1.024585) (xy 273.936398 1.15136) (xy 274.004461 1.274511)
			(xy 274.079321 1.393653) (xy 274.160745 1.50841) (xy 274.248474 1.618421) (xy 274.342234 1.723339)
			(xy 274.441729 1.822836) (xy 274.546646 1.916598) (xy 274.656655 2.004329) (xy 274.771411 2.085754)
			(xy 274.890551 2.160617) (xy 275.013701 2.228682) (xy 275.140474 2.289734) (xy 275.270471 2.343583)
			(xy 275.403283 2.390058) (xy 275.538492 2.429013) (xy 275.675672 2.460325) (xy 275.814392 2.483897)
			(xy 275.954215 2.499654) (xy 276.094702 2.507545) (xy 276.165056 2.507996) (xy 292.165024 2.507996)
			(xy 292.235377 2.507502) (xy 292.375862 2.499611) (xy 292.515684 2.483856) (xy 292.654403 2.460285)
			(xy 292.791581 2.428974) (xy 292.926788 2.390021) (xy 293.059599 2.343547) (xy 293.189594 2.2897)
			(xy 293.316366 2.228649) (xy 293.439515 2.160586) (xy 293.558655 2.085724) (xy 293.673409 2.004301)
			(xy 293.783417 1.916571) (xy 293.888334 1.822811) (xy 293.987828 1.723316) (xy 294.081587 1.618399)
			(xy 294.169315 1.50839) (xy 294.250738 1.393635) (xy 294.325598 1.274495) (xy 294.39366 1.151345)
			(xy 294.45471 1.024572) (xy 294.508556 0.894576) (xy 294.555028 0.761765) (xy 294.59398 0.626558)
			(xy 294.62529 0.489379) (xy 294.648859 0.35066) (xy 294.664613 0.210839) (xy 294.672503 0.070353)
			(xy 294.67302 0) (xy 294.67302 -8.850122) (xy 294.673543 -8.905928) (xy 294.681885 -9.017229) (xy 294.698522 -9.127594)
			(xy 294.723359 -9.236408) (xy 294.756259 -9.343062) (xy 294.797037 -9.446958) (xy 294.845465 -9.547517)
			(xy 294.901273 -9.644176) (xy 294.964148 -9.736394) (xy 295.033738 -9.823655) (xy 295.109655 -9.905472)
			(xy 295.191474 -9.981387) (xy 295.278737 -10.050975) (xy 295.370956 -10.113847) (xy 295.467616 -10.169652)
			(xy 295.568176 -10.218078) (xy 295.672074 -10.258853) (xy 295.778728 -10.291751) (xy 295.887543 -10.316586)
			(xy 295.997909 -10.333219) (xy 296.10921 -10.341559) (xy 296.165016 -10.342118) (xy 298.165012 -10.342118)
			(xy 298.220819 -10.341596) (xy 298.332121 -10.333254) (xy 298.442488 -10.316618) (xy 298.551304 -10.291781)
			(xy 298.657959 -10.258882) (xy 298.761858 -10.218105) (xy 298.862418 -10.169677) (xy 298.959079 -10.11387)
			(xy 299.051299 -10.050995) (xy 299.138562 -9.981405) (xy 299.220382 -9.905489) (xy 299.296299 -9.82367)
			(xy 299.365889 -9.736407) (xy 299.428764 -9.644188) (xy 299.484572 -9.547527) (xy 299.533001 -9.446967)
			(xy 299.573779 -9.343069) (xy 299.606679 -9.236414) (xy 299.631516 -9.127598) (xy 299.648153 -9.017231)
			(xy 299.656495 -8.905929) (xy 299.657008 -8.850122) (xy 299.657008 0) (xy 299.657492 0.070354) (xy 299.665382 0.21084)
			(xy 299.681136 0.350664) (xy 299.704706 0.489383) (xy 299.736016 0.626564) (xy 299.774969 0.761772)
			(xy 299.821442 0.894584) (xy 299.875289 1.024581) (xy 299.93634 1.151355) (xy 300.004403 1.274505)
			(xy 300.079264 1.393646) (xy 300.160688 1.508402) (xy 300.248418 1.618412) (xy 300.342178 1.723329)
			(xy 300.441673 1.822825) (xy 300.546591 1.916585) (xy 300.656601 2.004315) (xy 300.771357 2.085738)
			(xy 300.890498 2.160599) (xy 301.013649 2.228662) (xy 301.140423 2.289713) (xy 301.27042 2.343559)
			(xy 301.403232 2.390032) (xy 301.53844 2.428985) (xy 301.67562 2.460295) (xy 301.81434 2.483864)
			(xy 301.954163 2.499618) (xy 302.09465 2.507508) (xy 302.165004 2.507996) (xy 318.164972 2.507996)
			(xy 318.235326 2.507512) (xy 318.375814 2.499624) (xy 318.515639 2.483871) (xy 318.65436 2.460303)
			(xy 318.791541 2.428994) (xy 318.926751 2.390042) (xy 319.059564 2.34357) (xy 319.189563 2.289724)
			(xy 319.316338 2.228673) (xy 319.43949 2.160611) (xy 319.558633 2.08575) (xy 319.67339 2.004327)
			(xy 319.783401 1.916597) (xy 319.88832 1.822836) (xy 319.987817 1.723341) (xy 320.081579 1.618423)
			(xy 320.16931 1.508412) (xy 320.250734 1.393656) (xy 320.325597 1.274514) (xy 320.393661 1.151363)
			(xy 320.454712 1.024589) (xy 320.50856 0.894591) (xy 320.555033 0.761778) (xy 320.593987 0.626568)
			(xy 320.625298 0.489387) (xy 320.648868 0.350666) (xy 320.664622 0.210842) (xy 320.672512 0.070354)
			(xy 320.672968 0) (xy 320.672968 -8.850122) (xy 320.673491 -8.905929) (xy 320.681833 -9.017231) (xy 320.698469 -9.127598)
			(xy 320.723307 -9.236413) (xy 320.756206 -9.343068) (xy 320.796984 -9.446967) (xy 320.845412 -9.547527)
			(xy 320.901219 -9.644188) (xy 320.964093 -9.736408) (xy 321.033684 -9.823671) (xy 321.1096 -9.90549)
			(xy 321.191418 -9.981407) (xy 321.278681 -10.050998) (xy 321.3709 -10.113873) (xy 321.46756 -10.169682)
			(xy 321.56812 -10.21811) (xy 321.672018 -10.258889) (xy 321.778673 -10.29179) (xy 321.887488 -10.316628)
			(xy 321.997855 -10.333266) (xy 322.109157 -10.341609) (xy 322.164964 -10.342118) (xy 324.16496 -10.342118)
			(xy 324.220769 -10.34161) (xy 324.332074 -10.333272) (xy 324.442446 -10.316639) (xy 324.551265 -10.291805)
			(xy 324.657925 -10.258907) (xy 324.761827 -10.218131) (xy 324.862393 -10.169705) (xy 324.959057 -10.113898)
			(xy 325.051281 -10.051024) (xy 325.138549 -9.981433) (xy 325.220372 -9.905516) (xy 325.296293 -9.823696)
			(xy 325.365887 -9.736431) (xy 325.428765 -9.64421) (xy 325.484576 -9.547547) (xy 325.533007 -9.446984)
			(xy 325.573787 -9.343083) (xy 325.606689 -9.236425) (xy 325.631528 -9.127607) (xy 325.648165 -9.017236)
			(xy 325.656508 -8.905931) (xy 325.656956 -8.850122) (xy 325.656956 0) (xy 325.657449 0.070354) (xy 325.665339 0.210841)
			(xy 325.681093 0.350665) (xy 325.704662 0.489386) (xy 325.735972 0.626566) (xy 325.774925 0.761776)
			(xy 325.821398 0.894588) (xy 325.875244 1.024586) (xy 325.936294 1.15136) (xy 326.004357 1.274512)
			(xy 326.079217 1.393654) (xy 326.16064 1.508411) (xy 326.24837 1.618422) (xy 326.342129 1.723341)
			(xy 326.441624 1.822838) (xy 326.546542 1.916599) (xy 326.656551 2.004331) (xy 326.771306 2.085756)
			(xy 326.890447 2.160619) (xy 327.013597 2.228684) (xy 327.14037 2.289737) (xy 327.270367 2.343585)
			(xy 327.403179 2.39006) (xy 327.538387 2.429016) (xy 327.675567 2.460328) (xy 327.814287 2.4839)
			(xy 327.954111 2.499657) (xy 328.094598 2.507549) (xy 328.164952 2.507996) (xy 356.264972 2.507996)
			(xy 356.335326 2.507512) (xy 356.475814 2.499624) (xy 356.615639 2.483871) (xy 356.75436 2.460303)
			(xy 356.891541 2.428994) (xy 357.026751 2.390042) (xy 357.159564 2.34357) (xy 357.289563 2.289724)
			(xy 357.416338 2.228673) (xy 357.53949 2.160611) (xy 357.658633 2.08575) (xy 357.77339 2.004327)
			(xy 357.883401 1.916597) (xy 357.98832 1.822836) (xy 358.087817 1.723341) (xy 358.181579 1.618423)
			(xy 358.26931 1.508412) (xy 358.350734 1.393656) (xy 358.425597 1.274514) (xy 358.493661 1.151363)
			(xy 358.554712 1.024589) (xy 358.60856 0.894591) (xy 358.655033 0.761778) (xy 358.693987 0.626568)
			(xy 358.725298 0.489387) (xy 358.748868 0.350666) (xy 358.764622 0.210842) (xy 358.772512 0.070354)
			(xy 358.772968 0) (xy 358.772968 -8.850122) (xy 358.773491 -8.905929) (xy 358.781833 -9.017231) (xy 358.798469 -9.127598)
			(xy 358.823307 -9.236413) (xy 358.856206 -9.343068) (xy 358.896984 -9.446967) (xy 358.945412 -9.547527)
			(xy 359.001219 -9.644188) (xy 359.064093 -9.736408) (xy 359.133684 -9.823671) (xy 359.2096 -9.90549)
			(xy 359.291418 -9.981407) (xy 359.378681 -10.050998) (xy 359.4709 -10.113873) (xy 359.56756 -10.169682)
			(xy 359.66812 -10.21811) (xy 359.772018 -10.258889) (xy 359.878673 -10.29179) (xy 359.987488 -10.316628)
			(xy 360.097855 -10.333266) (xy 360.209157 -10.341609) (xy 360.264964 -10.342118) (xy 362.26496 -10.342118)
			(xy 362.320769 -10.34161) (xy 362.432074 -10.333272) (xy 362.542446 -10.316639) (xy 362.651265 -10.291805)
			(xy 362.757925 -10.258907) (xy 362.861827 -10.218131) (xy 362.962393 -10.169705) (xy 363.059057 -10.113898)
			(xy 363.151281 -10.051024) (xy 363.238549 -9.981433) (xy 363.320372 -9.905516) (xy 363.396293 -9.823696)
			(xy 363.465887 -9.736431) (xy 363.528765 -9.64421) (xy 363.584576 -9.547547) (xy 363.633007 -9.446984)
			(xy 363.673787 -9.343083) (xy 363.706689 -9.236425) (xy 363.731528 -9.127607) (xy 363.748165 -9.017236)
			(xy 363.756508 -8.905931) (xy 363.756956 -8.850122) (xy 363.756956 0) (xy 363.757449 0.070354) (xy 363.765339 0.210841)
			(xy 363.781093 0.350665) (xy 363.804662 0.489386) (xy 363.835972 0.626566) (xy 363.874925 0.761776)
			(xy 363.921398 0.894588) (xy 363.975244 1.024586) (xy 364.036294 1.15136) (xy 364.104357 1.274512)
			(xy 364.179217 1.393654) (xy 364.26064 1.508411) (xy 364.34837 1.618422) (xy 364.442129 1.723341)
			(xy 364.541624 1.822838) (xy 364.646542 1.916599) (xy 364.756551 2.004331) (xy 364.871306 2.085756)
			(xy 364.990447 2.160619) (xy 365.113597 2.228684) (xy 365.24037 2.289737) (xy 365.370367 2.343585)
			(xy 365.503179 2.39006) (xy 365.638387 2.429016) (xy 365.775567 2.460328) (xy 365.914287 2.4839)
			(xy 366.054111 2.499657) (xy 366.194598 2.507549) (xy 366.264952 2.507996) (xy 382.26492 2.507996)
			(xy 382.335273 2.507502) (xy 382.475759 2.499612) (xy 382.615581 2.483856) (xy 382.754299 2.460286)
			(xy 382.891478 2.428975) (xy 383.026685 2.390022) (xy 383.159496 2.343548) (xy 383.289491 2.289701)
			(xy 383.416264 2.22865) (xy 383.539413 2.160587) (xy 383.658552 2.085726) (xy 383.773307 2.004302)
			(xy 383.883316 1.916573) (xy 383.988232 1.822813) (xy 384.087726 1.723318) (xy 384.181485 1.6184)
			(xy 384.269214 1.508391) (xy 384.350637 1.393636) (xy 384.425497 1.274496) (xy 384.493559 1.151346)
			(xy 384.554609 1.024573) (xy 384.608455 0.894577) (xy 384.654928 0.761766) (xy 384.69388 0.626559)
			(xy 384.72519 0.48938) (xy 384.748759 0.350661) (xy 384.764513 0.210839) (xy 384.772403 0.070353)
			(xy 384.772916 0) (xy 384.772916 -8.850122) (xy 384.773439 -8.905928) (xy 384.781781 -9.017229) (xy 384.798418 -9.127595)
			(xy 384.823255 -9.236409) (xy 384.856155 -9.343062) (xy 384.896933 -9.446959) (xy 384.945361 -9.547518)
			(xy 385.001169 -9.644177) (xy 385.064044 -9.736395) (xy 385.133634 -9.823656) (xy 385.209551 -9.905473)
			(xy 385.29137 -9.981388) (xy 385.378633 -10.050977) (xy 385.470852 -10.113849) (xy 385.567512 -10.169655)
			(xy 385.668072 -10.218081) (xy 385.77197 -10.258856) (xy 385.878624 -10.291754) (xy 385.987439 -10.316589)
			(xy 386.097805 -10.333223) (xy 386.209106 -10.341563) (xy 386.264912 -10.342118) (xy 388.264908 -10.342118)
			(xy 388.320715 -10.341596) (xy 388.432017 -10.333255) (xy 388.542385 -10.316619) (xy 388.651201 -10.291782)
			(xy 388.757856 -10.258883) (xy 388.861755 -10.218106) (xy 388.962316 -10.169678) (xy 389.058977 -10.113871)
			(xy 389.151197 -10.050997) (xy 389.238461 -9.981407) (xy 389.32028 -9.90549) (xy 389.396198 -9.823671)
			(xy 389.465789 -9.736408) (xy 389.528664 -9.644189) (xy 389.584472 -9.547528) (xy 389.6329 -9.446968)
			(xy 389.673678 -9.343069) (xy 389.706579 -9.236414) (xy 389.731416 -9.127599) (xy 389.748053 -9.017231)
			(xy 389.756395 -8.905929) (xy 389.756904 -8.850122) (xy 389.756904 0) (xy 389.757397 0.070354) (xy 389.765287 0.21084)
			(xy 389.781041 0.350663) (xy 389.80461 0.489382) (xy 389.835921 0.626562) (xy 389.874874 0.76177)
			(xy 389.921346 0.894581) (xy 389.975193 1.024578) (xy 390.036243 1.151351) (xy 390.104306 1.274502)
			(xy 390.179167 1.393642) (xy 390.260591 1.508398) (xy 390.34832 1.618407) (xy 390.44208 1.723325)
			(xy 390.541575 1.82282) (xy 390.646493 1.91658) (xy 390.756502 2.004309) (xy 390.871258 2.085733)
			(xy 390.990398 2.160594) (xy 391.113549 2.228657) (xy 391.240322 2.289707) (xy 391.370319 2.343554)
			(xy 391.50313 2.390026) (xy 391.638338 2.428979) (xy 391.775518 2.46029) (xy 391.914237 2.483859)
			(xy 392.05406 2.499613) (xy 392.194546 2.507503) (xy 392.2649 2.507996) (xy 408.265122 2.507996)
			(xy 408.335475 2.507502) (xy 408.475961 2.499611) (xy 408.615782 2.483856) (xy 408.754501 2.460286)
			(xy 408.89168 2.428975) (xy 409.026887 2.390021) (xy 409.159697 2.343548) (xy 409.289693 2.289701)
			(xy 409.416465 2.22865) (xy 409.539614 2.160586) (xy 409.658754 2.085725) (xy 409.773508 2.004302)
			(xy 409.883516 1.916572) (xy 409.988433 1.822812) (xy 410.087927 1.723317) (xy 410.181686 1.6184)
			(xy 410.269415 1.50839) (xy 410.350837 1.393635) (xy 410.425697 1.274495) (xy 410.49376 1.151345)
			(xy 410.55481 1.024573) (xy 410.608655 0.894577) (xy 410.655128 0.761766) (xy 410.69408 0.626558)
			(xy 410.72539 0.489379) (xy 410.748959 0.350661) (xy 410.764713 0.210839) (xy 410.772603 0.070353)
			(xy 410.773118 0) (xy 410.773118 -8.850122) (xy 410.773641 -8.905928) (xy 410.781983 -9.017229) (xy 410.79862 -9.127595)
			(xy 410.823457 -9.236408) (xy 410.856357 -9.343062) (xy 410.897135 -9.446959) (xy 410.945563 -9.547518)
			(xy 411.001371 -9.644176) (xy 411.064246 -9.736394) (xy 411.133836 -9.823656) (xy 411.209753 -9.905472)
			(xy 411.291572 -9.981387) (xy 411.378835 -10.050976) (xy 411.471054 -10.113848) (xy 411.567714 -10.169653)
			(xy 411.668274 -10.218079) (xy 411.772172 -10.258855) (xy 411.878826 -10.291752) (xy 411.987641 -10.316587)
			(xy 412.098007 -10.333221) (xy 412.209308 -10.341561) (xy 412.265114 -10.342118) (xy 414.26511 -10.342118)
			(xy 414.320917 -10.341596) (xy 414.432219 -10.333254) (xy 414.542587 -10.316619) (xy 414.651402 -10.291782)
			(xy 414.758058 -10.258883) (xy 414.861956 -10.218105) (xy 414.962517 -10.169678) (xy 415.059178 -10.11387)
			(xy 415.151398 -10.050996) (xy 415.238662 -9.981406) (xy 415.320481 -9.905489) (xy 415.396398 -9.823671)
			(xy 415.465989 -9.736408) (xy 415.528864 -9.644188) (xy 415.584672 -9.547528) (xy 415.6331 -9.446967)
			(xy 415.673879 -9.343069) (xy 415.706779 -9.236414) (xy 415.731616 -9.127598) (xy 415.748253 -9.017231)
			(xy 415.756595 -8.905929) (xy 415.757106 -8.850122) (xy 415.757106 0) (xy 415.75759 0.070354) (xy 415.76548 0.210841)
			(xy 415.781234 0.350664) (xy 415.804804 0.489384) (xy 415.836114 0.626564) (xy 415.875067 0.761772)
			(xy 415.92154 0.894584) (xy 415.975387 1.024581) (xy 416.036438 1.151355) (xy 416.104501 1.274506)
			(xy 416.179362 1.393647) (xy 416.260785 1.508402) (xy 416.348515 1.618412) (xy 416.442276 1.72333)
			(xy 416.541771 1.822826) (xy 416.646689 1.916586) (xy 416.756699 2.004316) (xy 416.871455 2.085739)
			(xy 416.990596 2.1606) (xy 417.113747 2.228663) (xy 417.24052 2.289714) (xy 417.370518 2.343561)
			(xy 417.503329 2.390034) (xy 417.638538 2.428986) (xy 417.775718 2.460297) (xy 417.914438 2.483866)
			(xy 418.054261 2.49962) (xy 418.194748 2.50751) (xy 418.265102 2.507996) (xy 434.26507 2.507996)
			(xy 434.335425 2.507513) (xy 434.475912 2.499625) (xy 434.615737 2.483872) (xy 434.754458 2.460304)
			(xy 434.89164 2.428994) (xy 435.02685 2.390042) (xy 435.159663 2.34357) (xy 435.289662 2.289724)
			(xy 435.416437 2.228674) (xy 435.539589 2.160612) (xy 435.658732 2.085751) (xy 435.773489 2.004327)
			(xy 435.8835 1.916597) (xy 435.988419 1.822837) (xy 436.087916 1.723341) (xy 436.181678 1.618423)
			(xy 436.269409 1.508413) (xy 436.350834 1.393656) (xy 436.425696 1.274515) (xy 436.49376 1.151363)
			(xy 436.554812 1.024589) (xy 436.60866 0.894591) (xy 436.655133 0.761778) (xy 436.694087 0.626569)
			(xy 436.725398 0.489387) (xy 436.748967 0.350667) (xy 436.764722 0.210842) (xy 436.772612 0.070355)
			(xy 436.773066 0) (xy 436.773066 -8.850122) (xy 436.773589 -8.905929) (xy 436.781931 -9.017231) (xy 436.798567 -9.127598)
			(xy 436.823405 -9.236414) (xy 436.856304 -9.343069) (xy 436.897082 -9.446967) (xy 436.94551 -9.547528)
			(xy 437.001317 -9.644188) (xy 437.064191 -9.736408) (xy 437.133781 -9.823672) (xy 437.209698 -9.905491)
			(xy 437.291516 -9.981408) (xy 437.378779 -10.050999) (xy 437.470998 -10.113874) (xy 437.567658 -10.169683)
			(xy 437.668218 -10.218112) (xy 437.772116 -10.25889) (xy 437.878771 -10.291791) (xy 437.987586 -10.31663)
			(xy 438.097953 -10.333267) (xy 438.209255 -10.341611) (xy 438.265062 -10.342118) (xy 440.265058 -10.342118)
			(xy 440.320867 -10.34161) (xy 440.432173 -10.333272) (xy 440.542544 -10.316639) (xy 440.651364 -10.291805)
			(xy 440.758023 -10.258908) (xy 440.861926 -10.218132) (xy 440.962491 -10.169705) (xy 441.059156 -10.113899)
			(xy 441.151381 -10.051025) (xy 441.238648 -9.981434) (xy 441.320471 -9.905517) (xy 441.396392 -9.823697)
			(xy 441.465987 -9.736432) (xy 441.528865 -9.64421) (xy 441.584675 -9.547548) (xy 441.633106 -9.446985)
			(xy 441.673887 -9.343084) (xy 441.706788 -9.236425) (xy 441.731628 -9.127607) (xy 441.748265 -9.017236)
			(xy 441.756608 -8.905931) (xy 441.757054 -8.850122) (xy 441.757054 0) (xy 441.757538 0.070353) (xy 441.765428 0.210839)
			(xy 441.781182 0.350661) (xy 441.804752 0.48938) (xy 441.836062 0.626559) (xy 441.875016 0.761767)
			(xy 441.921489 0.894578) (xy 441.975336 1.024574) (xy 442.036387 1.151346) (xy 442.10445 1.274495)
			(xy 442.179312 1.393635) (xy 442.260736 1.508389) (xy 442.348466 1.618398) (xy 442.442227 1.723314)
			(xy 442.541722 1.822808) (xy 442.64664 1.916566) (xy 442.756651 2.004294) (xy 442.871407 2.085716)
			(xy 442.990548 2.160575) (xy 443.113699 2.228636) (xy 443.240472 2.289685) (xy 443.370469 2.343529)
			(xy 443.503281 2.39) (xy 443.638489 2.42895) (xy 443.775669 2.460258) (xy 443.914388 2.483825) (xy 444.054211 2.499576)
			(xy 444.194697 2.507463) (xy 444.26505 2.507996) (xy 465.600034 2.507996) (xy 465.65584 2.508519)
			(xy 465.767141 2.516862) (xy 465.877506 2.533499) (xy 465.98632 2.558338) (xy 466.092974 2.591238)
			(xy 466.19687 2.632016) (xy 466.297429 2.680445) (xy 466.394088 2.736252) (xy 466.486306 2.799127)
			(xy 466.573567 2.868717) (xy 466.655384 2.944634) (xy 466.7313 3.026452) (xy 466.800888 3.113715)
			(xy 466.863762 3.205934) (xy 466.919568 3.302594) (xy 466.967994 3.403154) (xy 467.008771 3.507051)
			(xy 467.041669 3.613705) (xy 467.066505 3.722519) (xy 467.083141 3.832885) (xy 467.091482 3.944186)
			(xy 467.09203 3.999992) (xy 467.09203 24.157686) (xy 467.091509 24.213494) (xy 467.083169 24.324797)
			(xy 467.066535 24.435167) (xy 467.041699 24.543984) (xy 467.008801 24.650641) (xy 466.968025 24.754542)
			(xy 466.919598 24.855105) (xy 466.863791 24.951768) (xy 466.800917 25.04399) (xy 466.731327 25.131255)
			(xy 466.655411 25.213077) (xy 466.573592 25.288996) (xy 466.486328 25.358589) (xy 466.394108 25.421466)
			(xy 466.297447 25.477275) (xy 466.196886 25.525705) (xy 466.092987 25.566485) (xy 465.986331 25.599387)
			(xy 465.877514 25.624226) (xy 465.767145 25.640863) (xy 465.655842 25.649207) (xy 465.600034 25.649682)
			(xy 160.11398 25.649682) (xy 160.058174 25.64916) (xy 159.946873 25.640817) (xy 159.836507 25.624181)
			(xy 159.727693 25.599343) (xy 159.62104 25.566443) (xy 159.517143 25.525665) (xy 159.416584 25.477237)
			(xy 159.319925 25.42143) (xy 159.227707 25.358555) (xy 159.140445 25.288965) (xy 159.058628 25.213048)
			(xy 158.982713 25.131229) (xy 158.913125 25.043966) (xy 158.850252 24.951746) (xy 158.794447 24.855086)
			(xy 158.746021 24.754526) (xy 158.705245 24.650628) (xy 158.672348 24.543974) (xy 158.647513 24.435159)
			(xy 158.630879 24.324793) (xy 158.622539 24.213492) (xy 158.621984 24.157686) (xy 158.621984 21.802649)
			(xy 269.304757 21.802649) (xy 269.304757 21.888399) (xy 269.312669 21.973782) (xy 269.328425 22.058072)
			(xy 269.351892 22.140548) (xy 269.382868 22.220507) (xy 269.42109 22.297267) (xy 269.466231 22.370173)
			(xy 269.517907 22.438602) (xy 269.575676 22.501972) (xy 269.639046 22.559741) (xy 269.707475 22.611417)
			(xy 269.780381 22.656558) (xy 269.857141 22.69478) (xy 269.9371 22.725756) (xy 270.019576 22.749223)
			(xy 270.103866 22.764979) (xy 270.189249 22.772891) (xy 270.274999 22.772891) (xy 270.360382 22.764979)
			(xy 270.444672 22.749223) (xy 270.527148 22.725756) (xy 270.607107 22.69478) (xy 270.683867 22.656558)
			(xy 270.756773 22.611417) (xy 270.825202 22.559741) (xy 270.888572 22.501972) (xy 270.946341 22.438602)
			(xy 270.998017 22.370173) (xy 271.043158 22.297267) (xy 271.08138 22.220507) (xy 271.112356 22.140548)
			(xy 271.135823 22.058072) (xy 271.151579 21.973782) (xy 271.159491 21.888399) (xy 271.159986 21.845524)
			(xy 271.159491 21.802649) (xy 275.654757 21.802649) (xy 275.654757 21.888399) (xy 275.662669 21.973782)
			(xy 275.678425 22.058072) (xy 275.701892 22.140548) (xy 275.732868 22.220507) (xy 275.77109 22.297267)
			(xy 275.816231 22.370173) (xy 275.867907 22.438602) (xy 275.925676 22.501972) (xy 275.989046 22.559741)
			(xy 276.057475 22.611417) (xy 276.130381 22.656558) (xy 276.207141 22.69478) (xy 276.2871 22.725756)
			(xy 276.369576 22.749223) (xy 276.453866 22.764979) (xy 276.539249 22.772891) (xy 276.624999 22.772891)
			(xy 276.710382 22.764979) (xy 276.794672 22.749223) (xy 276.877148 22.725756) (xy 276.957107 22.69478)
			(xy 277.033867 22.656558) (xy 277.106773 22.611417) (xy 277.175202 22.559741) (xy 277.238572 22.501972)
			(xy 277.296341 22.438602) (xy 277.348017 22.370173) (xy 277.393158 22.297267) (xy 277.43138 22.220507)
			(xy 277.462356 22.140548) (xy 277.485823 22.058072) (xy 277.501579 21.973782) (xy 277.509491 21.888399)
			(xy 277.509986 21.845524) (xy 277.509491 21.802649) (xy 277.508832 21.795537) (xy 308.364877 21.795537)
			(xy 308.364877 21.881287) (xy 308.372789 21.96667) (xy 308.388545 22.05096) (xy 308.412012 22.133436)
			(xy 308.442988 22.213395) (xy 308.48121 22.290155) (xy 308.526351 22.363061) (xy 308.578027 22.43149)
			(xy 308.635796 22.49486) (xy 308.699166 22.552629) (xy 308.767595 22.604305) (xy 308.840501 22.649446)
			(xy 308.917261 22.687668) (xy 308.99722 22.718644) (xy 309.079696 22.742111) (xy 309.163986 22.757867)
			(xy 309.249369 22.765779) (xy 309.335119 22.765779) (xy 309.420502 22.757867) (xy 309.504792 22.742111)
			(xy 309.587268 22.718644) (xy 309.667227 22.687668) (xy 309.743987 22.649446) (xy 309.816893 22.604305)
			(xy 309.885322 22.552629) (xy 309.948692 22.49486) (xy 310.006461 22.43149) (xy 310.058137 22.363061)
			(xy 310.103278 22.290155) (xy 310.1415 22.213395) (xy 310.172476 22.133436) (xy 310.195943 22.05096)
			(xy 310.211699 21.96667) (xy 310.219611 21.881287) (xy 310.220106 21.838412) (xy 310.219611 21.795537)
			(xy 314.714877 21.795537) (xy 314.714877 21.881287) (xy 314.722789 21.96667) (xy 314.738545 22.05096)
			(xy 314.762012 22.133436) (xy 314.792988 22.213395) (xy 314.83121 22.290155) (xy 314.876351 22.363061)
			(xy 314.928027 22.43149) (xy 314.985796 22.49486) (xy 315.049166 22.552629) (xy 315.117595 22.604305)
			(xy 315.190501 22.649446) (xy 315.267261 22.687668) (xy 315.34722 22.718644) (xy 315.429696 22.742111)
			(xy 315.513986 22.757867) (xy 315.599369 22.765779) (xy 315.685119 22.765779) (xy 315.770502 22.757867)
			(xy 315.854792 22.742111) (xy 315.937268 22.718644) (xy 316.017227 22.687668) (xy 316.093987 22.649446)
			(xy 316.166893 22.604305) (xy 316.235322 22.552629) (xy 316.298692 22.49486) (xy 316.356461 22.43149)
			(xy 316.408137 22.363061) (xy 316.453278 22.290155) (xy 316.4915 22.213395) (xy 316.522476 22.133436)
			(xy 316.545943 22.05096) (xy 316.561699 21.96667) (xy 316.569611 21.881287) (xy 316.570106 21.838412)
			(xy 316.569693 21.802649) (xy 334.455757 21.802649) (xy 334.455757 21.888399) (xy 334.463669 21.973782)
			(xy 334.479425 22.058072) (xy 334.502892 22.140548) (xy 334.533868 22.220507) (xy 334.57209 22.297267)
			(xy 334.617231 22.370173) (xy 334.668907 22.438602) (xy 334.726676 22.501972) (xy 334.790046 22.559741)
			(xy 334.858475 22.611417) (xy 334.931381 22.656558) (xy 335.008141 22.69478) (xy 335.0881 22.725756)
			(xy 335.170576 22.749223) (xy 335.254866 22.764979) (xy 335.340249 22.772891) (xy 335.425999 22.772891)
			(xy 335.511382 22.764979) (xy 335.595672 22.749223) (xy 335.678148 22.725756) (xy 335.758107 22.69478)
			(xy 335.834867 22.656558) (xy 335.907773 22.611417) (xy 335.976202 22.559741) (xy 336.039572 22.501972)
			(xy 336.097341 22.438602) (xy 336.149017 22.370173) (xy 336.194158 22.297267) (xy 336.23238 22.220507)
			(xy 336.263356 22.140548) (xy 336.286823 22.058072) (xy 336.302579 21.973782) (xy 336.310491 21.888399)
			(xy 336.310986 21.845524) (xy 336.310491 21.802649) (xy 340.805757 21.802649) (xy 340.805757 21.888399)
			(xy 340.813669 21.973782) (xy 340.829425 22.058072) (xy 340.852892 22.140548) (xy 340.883868 22.220507)
			(xy 340.92209 22.297267) (xy 340.967231 22.370173) (xy 341.018907 22.438602) (xy 341.076676 22.501972)
			(xy 341.140046 22.559741) (xy 341.208475 22.611417) (xy 341.281381 22.656558) (xy 341.358141 22.69478)
			(xy 341.4381 22.725756) (xy 341.520576 22.749223) (xy 341.604866 22.764979) (xy 341.690249 22.772891)
			(xy 341.775999 22.772891) (xy 341.861382 22.764979) (xy 341.945672 22.749223) (xy 342.028148 22.725756)
			(xy 342.108107 22.69478) (xy 342.184867 22.656558) (xy 342.257773 22.611417) (xy 342.326202 22.559741)
			(xy 342.389572 22.501972) (xy 342.447341 22.438602) (xy 342.499017 22.370173) (xy 342.544158 22.297267)
			(xy 342.58238 22.220507) (xy 342.613356 22.140548) (xy 342.636823 22.058072) (xy 342.652579 21.973782)
			(xy 342.660491 21.888399) (xy 342.660986 21.845524) (xy 342.660491 21.802649) (xy 342.659832 21.795537)
			(xy 373.515877 21.795537) (xy 373.515877 21.881287) (xy 373.523789 21.96667) (xy 373.539545 22.05096)
			(xy 373.563012 22.133436) (xy 373.593988 22.213395) (xy 373.63221 22.290155) (xy 373.677351 22.363061)
			(xy 373.729027 22.43149) (xy 373.786796 22.49486) (xy 373.850166 22.552629) (xy 373.918595 22.604305)
			(xy 373.991501 22.649446) (xy 374.068261 22.687668) (xy 374.14822 22.718644) (xy 374.230696 22.742111)
			(xy 374.314986 22.757867) (xy 374.400369 22.765779) (xy 374.486119 22.765779) (xy 374.571502 22.757867)
			(xy 374.655792 22.742111) (xy 374.738268 22.718644) (xy 374.818227 22.687668) (xy 374.894987 22.649446)
			(xy 374.967893 22.604305) (xy 375.036322 22.552629) (xy 375.099692 22.49486) (xy 375.157461 22.43149)
			(xy 375.209137 22.363061) (xy 375.254278 22.290155) (xy 375.2925 22.213395) (xy 375.323476 22.133436)
			(xy 375.346943 22.05096) (xy 375.362699 21.96667) (xy 375.370611 21.881287) (xy 375.371106 21.838412)
			(xy 375.370611 21.795537) (xy 379.865877 21.795537) (xy 379.865877 21.881287) (xy 379.873789 21.96667)
			(xy 379.889545 22.05096) (xy 379.913012 22.133436) (xy 379.943988 22.213395) (xy 379.98221 22.290155)
			(xy 380.027351 22.363061) (xy 380.079027 22.43149) (xy 380.136796 22.49486) (xy 380.200166 22.552629)
			(xy 380.268595 22.604305) (xy 380.341501 22.649446) (xy 380.418261 22.687668) (xy 380.49822 22.718644)
			(xy 380.580696 22.742111) (xy 380.664986 22.757867) (xy 380.750369 22.765779) (xy 380.836119 22.765779)
			(xy 380.921502 22.757867) (xy 381.005792 22.742111) (xy 381.088268 22.718644) (xy 381.168227 22.687668)
			(xy 381.244987 22.649446) (xy 381.317893 22.604305) (xy 381.386322 22.552629) (xy 381.449692 22.49486)
			(xy 381.507461 22.43149) (xy 381.559137 22.363061) (xy 381.604278 22.290155) (xy 381.6425 22.213395)
			(xy 381.673476 22.133436) (xy 381.696943 22.05096) (xy 381.712699 21.96667) (xy 381.720611 21.881287)
			(xy 381.721106 21.838412) (xy 381.720693 21.802649) (xy 399.098757 21.802649) (xy 399.098757 21.888399)
			(xy 399.106669 21.973782) (xy 399.122425 22.058072) (xy 399.145892 22.140548) (xy 399.176868 22.220507)
			(xy 399.21509 22.297267) (xy 399.260231 22.370173) (xy 399.311907 22.438602) (xy 399.369676 22.501972)
			(xy 399.433046 22.559741) (xy 399.501475 22.611417) (xy 399.574381 22.656558) (xy 399.651141 22.69478)
			(xy 399.7311 22.725756) (xy 399.813576 22.749223) (xy 399.897866 22.764979) (xy 399.983249 22.772891)
			(xy 400.068999 22.772891) (xy 400.154382 22.764979) (xy 400.238672 22.749223) (xy 400.321148 22.725756)
			(xy 400.401107 22.69478) (xy 400.477867 22.656558) (xy 400.550773 22.611417) (xy 400.619202 22.559741)
			(xy 400.682572 22.501972) (xy 400.740341 22.438602) (xy 400.792017 22.370173) (xy 400.837158 22.297267)
			(xy 400.87538 22.220507) (xy 400.906356 22.140548) (xy 400.929823 22.058072) (xy 400.945579 21.973782)
			(xy 400.953491 21.888399) (xy 400.953986 21.845524) (xy 400.953491 21.802649) (xy 405.448757 21.802649)
			(xy 405.448757 21.888399) (xy 405.456669 21.973782) (xy 405.472425 22.058072) (xy 405.495892 22.140548)
			(xy 405.526868 22.220507) (xy 405.56509 22.297267) (xy 405.610231 22.370173) (xy 405.661907 22.438602)
			(xy 405.719676 22.501972) (xy 405.783046 22.559741) (xy 405.851475 22.611417) (xy 405.924381 22.656558)
			(xy 406.001141 22.69478) (xy 406.0811 22.725756) (xy 406.163576 22.749223) (xy 406.247866 22.764979)
			(xy 406.333249 22.772891) (xy 406.418999 22.772891) (xy 406.504382 22.764979) (xy 406.588672 22.749223)
			(xy 406.671148 22.725756) (xy 406.751107 22.69478) (xy 406.827867 22.656558) (xy 406.900773 22.611417)
			(xy 406.969202 22.559741) (xy 407.032572 22.501972) (xy 407.090341 22.438602) (xy 407.142017 22.370173)
			(xy 407.187158 22.297267) (xy 407.22538 22.220507) (xy 407.256356 22.140548) (xy 407.279823 22.058072)
			(xy 407.295579 21.973782) (xy 407.303491 21.888399) (xy 407.303986 21.845524) (xy 407.303491 21.802649)
			(xy 407.302832 21.795537) (xy 438.158877 21.795537) (xy 438.158877 21.881287) (xy 438.166789 21.96667)
			(xy 438.182545 22.05096) (xy 438.206012 22.133436) (xy 438.236988 22.213395) (xy 438.27521 22.290155)
			(xy 438.320351 22.363061) (xy 438.372027 22.43149) (xy 438.429796 22.49486) (xy 438.493166 22.552629)
			(xy 438.561595 22.604305) (xy 438.634501 22.649446) (xy 438.711261 22.687668) (xy 438.79122 22.718644)
			(xy 438.873696 22.742111) (xy 438.957986 22.757867) (xy 439.043369 22.765779) (xy 439.129119 22.765779)
			(xy 439.214502 22.757867) (xy 439.298792 22.742111) (xy 439.381268 22.718644) (xy 439.461227 22.687668)
			(xy 439.537987 22.649446) (xy 439.610893 22.604305) (xy 439.679322 22.552629) (xy 439.742692 22.49486)
			(xy 439.800461 22.43149) (xy 439.852137 22.363061) (xy 439.897278 22.290155) (xy 439.9355 22.213395)
			(xy 439.966476 22.133436) (xy 439.989943 22.05096) (xy 440.005699 21.96667) (xy 440.013611 21.881287)
			(xy 440.014106 21.838412) (xy 440.013611 21.795537) (xy 444.508877 21.795537) (xy 444.508877 21.881287)
			(xy 444.516789 21.96667) (xy 444.532545 22.05096) (xy 444.556012 22.133436) (xy 444.586988 22.213395)
			(xy 444.62521 22.290155) (xy 444.670351 22.363061) (xy 444.722027 22.43149) (xy 444.779796 22.49486)
			(xy 444.843166 22.552629) (xy 444.911595 22.604305) (xy 444.984501 22.649446) (xy 445.061261 22.687668)
			(xy 445.14122 22.718644) (xy 445.223696 22.742111) (xy 445.307986 22.757867) (xy 445.393369 22.765779)
			(xy 445.479119 22.765779) (xy 445.564502 22.757867) (xy 445.648792 22.742111) (xy 445.731268 22.718644)
			(xy 445.811227 22.687668) (xy 445.887987 22.649446) (xy 445.960893 22.604305) (xy 446.029322 22.552629)
			(xy 446.092692 22.49486) (xy 446.150461 22.43149) (xy 446.202137 22.363061) (xy 446.247278 22.290155)
			(xy 446.2855 22.213395) (xy 446.316476 22.133436) (xy 446.339943 22.05096) (xy 446.355699 21.96667)
			(xy 446.363611 21.881287) (xy 446.364106 21.838412) (xy 446.363611 21.795537) (xy 446.355699 21.710154)
			(xy 446.339943 21.625864) (xy 446.316476 21.543388) (xy 446.2855 21.463429) (xy 446.247278 21.386669)
			(xy 446.202137 21.313763) (xy 446.150461 21.245334) (xy 446.092692 21.181964) (xy 446.029322 21.124195)
			(xy 445.988175 21.093122) (xy 460.504275 21.093122) (xy 460.504275 21.222262) (xy 460.512225 21.351157)
			(xy 460.528095 21.479317) (xy 460.551824 21.606258) (xy 460.583323 21.731497) (xy 460.622472 21.85456)
			(xy 460.669123 21.974979) (xy 460.723098 22.092298) (xy 460.784193 22.206072) (xy 460.852176 22.315869)
			(xy 460.92679 22.421272) (xy 461.007751 22.521882) (xy 461.094751 22.617317) (xy 461.187462 22.707216)
			(xy 461.285532 22.791237) (xy 461.388587 22.869061) (xy 461.496238 22.940393) (xy 461.608077 23.004963)
			(xy 461.723678 23.062525) (xy 461.842603 23.112862) (xy 461.964402 23.155782) (xy 462.088612 23.191123)
			(xy 462.214761 23.21875) (xy 462.342373 23.238559) (xy 462.470962 23.250475) (xy 462.60004 23.254452)
			(xy 462.729118 23.250475) (xy 462.857707 23.238559) (xy 462.985319 23.21875) (xy 463.111468 23.191123)
			(xy 463.235678 23.155782) (xy 463.357477 23.112862) (xy 463.476402 23.062525) (xy 463.592003 23.004963)
			(xy 463.703842 22.940393) (xy 463.811493 22.869061) (xy 463.914548 22.791237) (xy 464.012618 22.707216)
			(xy 464.105329 22.617317) (xy 464.192329 22.521882) (xy 464.27329 22.421272) (xy 464.347904 22.315869)
			(xy 464.415887 22.206072) (xy 464.476982 22.092298) (xy 464.530957 21.974979) (xy 464.577608 21.85456)
			(xy 464.616757 21.731497) (xy 464.648256 21.606258) (xy 464.671985 21.479317) (xy 464.687855 21.351157)
			(xy 464.695805 21.222262) (xy 464.696302 21.157692) (xy 464.695805 21.093122) (xy 464.687855 20.964227)
			(xy 464.671985 20.836067) (xy 464.648256 20.709126) (xy 464.616757 20.583887) (xy 464.577608 20.460824)
			(xy 464.530957 20.340405) (xy 464.476982 20.223086) (xy 464.415887 20.109312) (xy 464.347904 19.999515)
			(xy 464.27329 19.894112) (xy 464.192329 19.793502) (xy 464.105329 19.698067) (xy 464.012618 19.608168)
			(xy 463.914548 19.524147) (xy 463.811493 19.446323) (xy 463.703842 19.374991) (xy 463.592003 19.310421)
			(xy 463.476402 19.252859) (xy 463.357477 19.202522) (xy 463.235678 19.159602) (xy 463.111468 19.124261)
			(xy 462.985319 19.096634) (xy 462.857707 19.076825) (xy 462.729118 19.064909) (xy 462.60004 19.060933)
			(xy 462.470962 19.064909) (xy 462.342373 19.076825) (xy 462.214761 19.096634) (xy 462.088612 19.124261)
			(xy 461.964402 19.159602) (xy 461.842603 19.202522) (xy 461.723678 19.252859) (xy 461.608077 19.310421)
			(xy 461.496238 19.374991) (xy 461.388587 19.446323) (xy 461.285532 19.524147) (xy 461.187462 19.608168)
			(xy 461.094751 19.698067) (xy 461.007751 19.793502) (xy 460.92679 19.894112) (xy 460.852176 19.999515)
			(xy 460.784193 20.109312) (xy 460.723098 20.223086) (xy 460.669123 20.340405) (xy 460.622472 20.460824)
			(xy 460.583323 20.583887) (xy 460.551824 20.709126) (xy 460.528095 20.836067) (xy 460.512225 20.964227)
			(xy 460.504275 21.093122) (xy 445.988175 21.093122) (xy 445.960893 21.072519) (xy 445.887987 21.027378)
			(xy 445.811227 20.989156) (xy 445.731268 20.95818) (xy 445.648792 20.934713) (xy 445.564502 20.918957)
			(xy 445.479119 20.911045) (xy 445.393369 20.911045) (xy 445.307986 20.918957) (xy 445.223696 20.934713)
			(xy 445.14122 20.95818) (xy 445.061261 20.989156) (xy 444.984501 21.027378) (xy 444.911595 21.072519)
			(xy 444.843166 21.124195) (xy 444.779796 21.181964) (xy 444.722027 21.245334) (xy 444.670351 21.313763)
			(xy 444.62521 21.386669) (xy 444.586988 21.463429) (xy 444.556012 21.543388) (xy 444.532545 21.625864)
			(xy 444.516789 21.710154) (xy 444.508877 21.795537) (xy 440.013611 21.795537) (xy 440.005699 21.710154)
			(xy 439.989943 21.625864) (xy 439.966476 21.543388) (xy 439.9355 21.463429) (xy 439.897278 21.386669)
			(xy 439.852137 21.313763) (xy 439.800461 21.245334) (xy 439.742692 21.181964) (xy 439.679322 21.124195)
			(xy 439.610893 21.072519) (xy 439.537987 21.027378) (xy 439.461227 20.989156) (xy 439.381268 20.95818)
			(xy 439.298792 20.934713) (xy 439.214502 20.918957) (xy 439.129119 20.911045) (xy 439.043369 20.911045)
			(xy 438.957986 20.918957) (xy 438.873696 20.934713) (xy 438.79122 20.95818) (xy 438.711261 20.989156)
			(xy 438.634501 21.027378) (xy 438.561595 21.072519) (xy 438.493166 21.124195) (xy 438.429796 21.181964)
			(xy 438.372027 21.245334) (xy 438.320351 21.313763) (xy 438.27521 21.386669) (xy 438.236988 21.463429)
			(xy 438.206012 21.543388) (xy 438.182545 21.625864) (xy 438.166789 21.710154) (xy 438.158877 21.795537)
			(xy 407.302832 21.795537) (xy 407.295579 21.717266) (xy 407.279823 21.632976) (xy 407.256356 21.5505)
			(xy 407.22538 21.470541) (xy 407.187158 21.393781) (xy 407.142017 21.320875) (xy 407.090341 21.252446)
			(xy 407.032572 21.189076) (xy 406.969202 21.131307) (xy 406.900773 21.079631) (xy 406.827867 21.03449)
			(xy 406.751107 20.996268) (xy 406.671148 20.965292) (xy 406.588672 20.941825) (xy 406.504382 20.926069)
			(xy 406.418999 20.918157) (xy 406.333249 20.918157) (xy 406.247866 20.926069) (xy 406.163576 20.941825)
			(xy 406.0811 20.965292) (xy 406.001141 20.996268) (xy 405.924381 21.03449) (xy 405.851475 21.079631)
			(xy 405.783046 21.131307) (xy 405.719676 21.189076) (xy 405.661907 21.252446) (xy 405.610231 21.320875)
			(xy 405.56509 21.393781) (xy 405.526868 21.470541) (xy 405.495892 21.5505) (xy 405.472425 21.632976)
			(xy 405.456669 21.717266) (xy 405.448757 21.802649) (xy 400.953491 21.802649) (xy 400.945579 21.717266)
			(xy 400.929823 21.632976) (xy 400.906356 21.5505) (xy 400.87538 21.470541) (xy 400.837158 21.393781)
			(xy 400.792017 21.320875) (xy 400.740341 21.252446) (xy 400.682572 21.189076) (xy 400.619202 21.131307)
			(xy 400.550773 21.079631) (xy 400.477867 21.03449) (xy 400.401107 20.996268) (xy 400.321148 20.965292)
			(xy 400.238672 20.941825) (xy 400.154382 20.926069) (xy 400.068999 20.918157) (xy 399.983249 20.918157)
			(xy 399.897866 20.926069) (xy 399.813576 20.941825) (xy 399.7311 20.965292) (xy 399.651141 20.996268)
			(xy 399.574381 21.03449) (xy 399.501475 21.079631) (xy 399.433046 21.131307) (xy 399.369676 21.189076)
			(xy 399.311907 21.252446) (xy 399.260231 21.320875) (xy 399.21509 21.393781) (xy 399.176868 21.470541)
			(xy 399.145892 21.5505) (xy 399.122425 21.632976) (xy 399.106669 21.717266) (xy 399.098757 21.802649)
			(xy 381.720693 21.802649) (xy 381.720611 21.795537) (xy 381.712699 21.710154) (xy 381.696943 21.625864)
			(xy 381.673476 21.543388) (xy 381.6425 21.463429) (xy 381.604278 21.386669) (xy 381.559137 21.313763)
			(xy 381.507461 21.245334) (xy 381.449692 21.181964) (xy 381.386322 21.124195) (xy 381.317893 21.072519)
			(xy 381.244987 21.027378) (xy 381.168227 20.989156) (xy 381.088268 20.95818) (xy 381.005792 20.934713)
			(xy 380.921502 20.918957) (xy 380.836119 20.911045) (xy 380.750369 20.911045) (xy 380.664986 20.918957)
			(xy 380.580696 20.934713) (xy 380.49822 20.95818) (xy 380.418261 20.989156) (xy 380.341501 21.027378)
			(xy 380.268595 21.072519) (xy 380.200166 21.124195) (xy 380.136796 21.181964) (xy 380.079027 21.245334)
			(xy 380.027351 21.313763) (xy 379.98221 21.386669) (xy 379.943988 21.463429) (xy 379.913012 21.543388)
			(xy 379.889545 21.625864) (xy 379.873789 21.710154) (xy 379.865877 21.795537) (xy 375.370611 21.795537)
			(xy 375.362699 21.710154) (xy 375.346943 21.625864) (xy 375.323476 21.543388) (xy 375.2925 21.463429)
			(xy 375.254278 21.386669) (xy 375.209137 21.313763) (xy 375.157461 21.245334) (xy 375.099692 21.181964)
			(xy 375.036322 21.124195) (xy 374.967893 21.072519) (xy 374.894987 21.027378) (xy 374.818227 20.989156)
			(xy 374.738268 20.95818) (xy 374.655792 20.934713) (xy 374.571502 20.918957) (xy 374.486119 20.911045)
			(xy 374.400369 20.911045) (xy 374.314986 20.918957) (xy 374.230696 20.934713) (xy 374.14822 20.95818)
			(xy 374.068261 20.989156) (xy 373.991501 21.027378) (xy 373.918595 21.072519) (xy 373.850166 21.124195)
			(xy 373.786796 21.181964) (xy 373.729027 21.245334) (xy 373.677351 21.313763) (xy 373.63221 21.386669)
			(xy 373.593988 21.463429) (xy 373.563012 21.543388) (xy 373.539545 21.625864) (xy 373.523789 21.710154)
			(xy 373.515877 21.795537) (xy 342.659832 21.795537) (xy 342.652579 21.717266) (xy 342.636823 21.632976)
			(xy 342.613356 21.5505) (xy 342.58238 21.470541) (xy 342.544158 21.393781) (xy 342.499017 21.320875)
			(xy 342.447341 21.252446) (xy 342.389572 21.189076) (xy 342.326202 21.131307) (xy 342.257773 21.079631)
			(xy 342.184867 21.03449) (xy 342.108107 20.996268) (xy 342.028148 20.965292) (xy 341.945672 20.941825)
			(xy 341.861382 20.926069) (xy 341.775999 20.918157) (xy 341.690249 20.918157) (xy 341.604866 20.926069)
			(xy 341.520576 20.941825) (xy 341.4381 20.965292) (xy 341.358141 20.996268) (xy 341.281381 21.03449)
			(xy 341.208475 21.079631) (xy 341.140046 21.131307) (xy 341.076676 21.189076) (xy 341.018907 21.252446)
			(xy 340.967231 21.320875) (xy 340.92209 21.393781) (xy 340.883868 21.470541) (xy 340.852892 21.5505)
			(xy 340.829425 21.632976) (xy 340.813669 21.717266) (xy 340.805757 21.802649) (xy 336.310491 21.802649)
			(xy 336.302579 21.717266) (xy 336.286823 21.632976) (xy 336.263356 21.5505) (xy 336.23238 21.470541)
			(xy 336.194158 21.393781) (xy 336.149017 21.320875) (xy 336.097341 21.252446) (xy 336.039572 21.189076)
			(xy 335.976202 21.131307) (xy 335.907773 21.079631) (xy 335.834867 21.03449) (xy 335.758107 20.996268)
			(xy 335.678148 20.965292) (xy 335.595672 20.941825) (xy 335.511382 20.926069) (xy 335.425999 20.918157)
			(xy 335.340249 20.918157) (xy 335.254866 20.926069) (xy 335.170576 20.941825) (xy 335.0881 20.965292)
			(xy 335.008141 20.996268) (xy 334.931381 21.03449) (xy 334.858475 21.079631) (xy 334.790046 21.131307)
			(xy 334.726676 21.189076) (xy 334.668907 21.252446) (xy 334.617231 21.320875) (xy 334.57209 21.393781)
			(xy 334.533868 21.470541) (xy 334.502892 21.5505) (xy 334.479425 21.632976) (xy 334.463669 21.717266)
			(xy 334.455757 21.802649) (xy 316.569693 21.802649) (xy 316.569611 21.795537) (xy 316.561699 21.710154)
			(xy 316.545943 21.625864) (xy 316.522476 21.543388) (xy 316.4915 21.463429) (xy 316.453278 21.386669)
			(xy 316.408137 21.313763) (xy 316.356461 21.245334) (xy 316.298692 21.181964) (xy 316.235322 21.124195)
			(xy 316.166893 21.072519) (xy 316.093987 21.027378) (xy 316.017227 20.989156) (xy 315.937268 20.95818)
			(xy 315.854792 20.934713) (xy 315.770502 20.918957) (xy 315.685119 20.911045) (xy 315.599369 20.911045)
			(xy 315.513986 20.918957) (xy 315.429696 20.934713) (xy 315.34722 20.95818) (xy 315.267261 20.989156)
			(xy 315.190501 21.027378) (xy 315.117595 21.072519) (xy 315.049166 21.124195) (xy 314.985796 21.181964)
			(xy 314.928027 21.245334) (xy 314.876351 21.313763) (xy 314.83121 21.386669) (xy 314.792988 21.463429)
			(xy 314.762012 21.543388) (xy 314.738545 21.625864) (xy 314.722789 21.710154) (xy 314.714877 21.795537)
			(xy 310.219611 21.795537) (xy 310.211699 21.710154) (xy 310.195943 21.625864) (xy 310.172476 21.543388)
			(xy 310.1415 21.463429) (xy 310.103278 21.386669) (xy 310.058137 21.313763) (xy 310.006461 21.245334)
			(xy 309.948692 21.181964) (xy 309.885322 21.124195) (xy 309.816893 21.072519) (xy 309.743987 21.027378)
			(xy 309.667227 20.989156) (xy 309.587268 20.95818) (xy 309.504792 20.934713) (xy 309.420502 20.918957)
			(xy 309.335119 20.911045) (xy 309.249369 20.911045) (xy 309.163986 20.918957) (xy 309.079696 20.934713)
			(xy 308.99722 20.95818) (xy 308.917261 20.989156) (xy 308.840501 21.027378) (xy 308.767595 21.072519)
			(xy 308.699166 21.124195) (xy 308.635796 21.181964) (xy 308.578027 21.245334) (xy 308.526351 21.313763)
			(xy 308.48121 21.386669) (xy 308.442988 21.463429) (xy 308.412012 21.543388) (xy 308.388545 21.625864)
			(xy 308.372789 21.710154) (xy 308.364877 21.795537) (xy 277.508832 21.795537) (xy 277.501579 21.717266)
			(xy 277.485823 21.632976) (xy 277.462356 21.5505) (xy 277.43138 21.470541) (xy 277.393158 21.393781)
			(xy 277.348017 21.320875) (xy 277.296341 21.252446) (xy 277.238572 21.189076) (xy 277.175202 21.131307)
			(xy 277.106773 21.079631) (xy 277.033867 21.03449) (xy 276.957107 20.996268) (xy 276.877148 20.965292)
			(xy 276.794672 20.941825) (xy 276.710382 20.926069) (xy 276.624999 20.918157) (xy 276.539249 20.918157)
			(xy 276.453866 20.926069) (xy 276.369576 20.941825) (xy 276.2871 20.965292) (xy 276.207141 20.996268)
			(xy 276.130381 21.03449) (xy 276.057475 21.079631) (xy 275.989046 21.131307) (xy 275.925676 21.189076)
			(xy 275.867907 21.252446) (xy 275.816231 21.320875) (xy 275.77109 21.393781) (xy 275.732868 21.470541)
			(xy 275.701892 21.5505) (xy 275.678425 21.632976) (xy 275.662669 21.717266) (xy 275.654757 21.802649)
			(xy 271.159491 21.802649) (xy 271.151579 21.717266) (xy 271.135823 21.632976) (xy 271.112356 21.5505)
			(xy 271.08138 21.470541) (xy 271.043158 21.393781) (xy 270.998017 21.320875) (xy 270.946341 21.252446)
			(xy 270.888572 21.189076) (xy 270.825202 21.131307) (xy 270.756773 21.079631) (xy 270.683867 21.03449)
			(xy 270.607107 20.996268) (xy 270.527148 20.965292) (xy 270.444672 20.941825) (xy 270.360382 20.926069)
			(xy 270.274999 20.918157) (xy 270.189249 20.918157) (xy 270.103866 20.926069) (xy 270.019576 20.941825)
			(xy 269.9371 20.965292) (xy 269.857141 20.996268) (xy 269.780381 21.03449) (xy 269.707475 21.079631)
			(xy 269.639046 21.131307) (xy 269.575676 21.189076) (xy 269.517907 21.252446) (xy 269.466231 21.320875)
			(xy 269.42109 21.393781) (xy 269.382868 21.470541) (xy 269.351892 21.5505) (xy 269.328425 21.632976)
			(xy 269.312669 21.717266) (xy 269.304757 21.802649) (xy 158.621984 21.802649) (xy 158.621984 19.262649)
			(xy 209.995757 19.262649) (xy 209.995757 19.348399) (xy 210.003669 19.433782) (xy 210.019425 19.518072)
			(xy 210.042892 19.600548) (xy 210.073868 19.680507) (xy 210.11209 19.757267) (xy 210.157231 19.830173)
			(xy 210.208907 19.898602) (xy 210.266676 19.961972) (xy 210.330046 20.019741) (xy 210.398475 20.071417)
			(xy 210.471381 20.116558) (xy 210.548141 20.15478) (xy 210.6281 20.185756) (xy 210.710576 20.209223)
			(xy 210.794866 20.224979) (xy 210.880249 20.232891) (xy 210.965999 20.232891) (xy 211.051382 20.224979)
			(xy 211.135672 20.209223) (xy 211.218148 20.185756) (xy 211.298107 20.15478) (xy 211.374867 20.116558)
			(xy 211.447773 20.071417) (xy 211.516202 20.019741) (xy 211.579572 19.961972) (xy 211.637341 19.898602)
			(xy 211.689017 19.830173) (xy 211.734158 19.757267) (xy 211.77238 19.680507) (xy 211.803356 19.600548)
			(xy 211.826823 19.518072) (xy 211.842579 19.433782) (xy 211.850491 19.348399) (xy 211.850986 19.305524)
			(xy 211.850491 19.262649) (xy 216.345757 19.262649) (xy 216.345757 19.348399) (xy 216.353669 19.433782)
			(xy 216.369425 19.518072) (xy 216.392892 19.600548) (xy 216.423868 19.680507) (xy 216.46209 19.757267)
			(xy 216.507231 19.830173) (xy 216.558907 19.898602) (xy 216.616676 19.961972) (xy 216.680046 20.019741)
			(xy 216.748475 20.071417) (xy 216.821381 20.116558) (xy 216.898141 20.15478) (xy 216.9781 20.185756)
			(xy 217.060576 20.209223) (xy 217.144866 20.224979) (xy 217.230249 20.232891) (xy 217.315999 20.232891)
			(xy 217.401382 20.224979) (xy 217.485672 20.209223) (xy 217.568148 20.185756) (xy 217.648107 20.15478)
			(xy 217.724867 20.116558) (xy 217.797773 20.071417) (xy 217.866202 20.019741) (xy 217.929572 19.961972)
			(xy 217.987341 19.898602) (xy 218.039017 19.830173) (xy 218.084158 19.757267) (xy 218.12238 19.680507)
			(xy 218.153356 19.600548) (xy 218.176823 19.518072) (xy 218.192579 19.433782) (xy 218.200491 19.348399)
			(xy 218.200986 19.305524) (xy 218.200491 19.262649) (xy 218.199832 19.255537) (xy 244.026677 19.255537)
			(xy 244.026677 19.341287) (xy 244.034589 19.42667) (xy 244.050345 19.51096) (xy 244.073812 19.593436)
			(xy 244.104788 19.673395) (xy 244.14301 19.750155) (xy 244.188151 19.823061) (xy 244.239827 19.89149)
			(xy 244.297596 19.95486) (xy 244.360966 20.012629) (xy 244.429395 20.064305) (xy 244.502301 20.109446)
			(xy 244.579061 20.147668) (xy 244.65902 20.178644) (xy 244.741496 20.202111) (xy 244.825786 20.217867)
			(xy 244.911169 20.225779) (xy 244.996919 20.225779) (xy 245.082302 20.217867) (xy 245.166592 20.202111)
			(xy 245.249068 20.178644) (xy 245.329027 20.147668) (xy 245.405787 20.109446) (xy 245.478693 20.064305)
			(xy 245.547122 20.012629) (xy 245.610492 19.95486) (xy 245.668261 19.89149) (xy 245.719937 19.823061)
			(xy 245.765078 19.750155) (xy 245.8033 19.673395) (xy 245.834276 19.593436) (xy 245.857743 19.51096)
			(xy 245.873499 19.42667) (xy 245.881411 19.341287) (xy 245.881906 19.298412) (xy 245.881411 19.255537)
			(xy 250.376677 19.255537) (xy 250.376677 19.341287) (xy 250.384589 19.42667) (xy 250.400345 19.51096)
			(xy 250.423812 19.593436) (xy 250.454788 19.673395) (xy 250.49301 19.750155) (xy 250.538151 19.823061)
			(xy 250.589827 19.89149) (xy 250.647596 19.95486) (xy 250.710966 20.012629) (xy 250.779395 20.064305)
			(xy 250.852301 20.109446) (xy 250.929061 20.147668) (xy 251.00902 20.178644) (xy 251.091496 20.202111)
			(xy 251.175786 20.217867) (xy 251.261169 20.225779) (xy 251.346919 20.225779) (xy 251.432302 20.217867)
			(xy 251.516592 20.202111) (xy 251.599068 20.178644) (xy 251.679027 20.147668) (xy 251.755787 20.109446)
			(xy 251.828693 20.064305) (xy 251.897122 20.012629) (xy 251.960492 19.95486) (xy 252.018261 19.89149)
			(xy 252.069937 19.823061) (xy 252.115078 19.750155) (xy 252.1533 19.673395) (xy 252.184276 19.593436)
			(xy 252.207743 19.51096) (xy 252.223499 19.42667) (xy 252.231411 19.341287) (xy 252.231906 19.298412)
			(xy 252.231493 19.262649) (xy 269.304757 19.262649) (xy 269.304757 19.348399) (xy 269.312669 19.433782)
			(xy 269.328425 19.518072) (xy 269.351892 19.600548) (xy 269.382868 19.680507) (xy 269.42109 19.757267)
			(xy 269.466231 19.830173) (xy 269.517907 19.898602) (xy 269.575676 19.961972) (xy 269.639046 20.019741)
			(xy 269.707475 20.071417) (xy 269.780381 20.116558) (xy 269.857141 20.15478) (xy 269.9371 20.185756)
			(xy 270.019576 20.209223) (xy 270.103866 20.224979) (xy 270.189249 20.232891) (xy 270.274999 20.232891)
			(xy 270.360382 20.224979) (xy 270.444672 20.209223) (xy 270.527148 20.185756) (xy 270.607107 20.15478)
			(xy 270.62931 20.143724) (xy 274.239736 20.143724) (xy 274.239736 21.007324) (xy 274.240222 21.034593)
			(xy 274.247984 21.088577) (xy 274.263349 21.140907) (xy 274.286006 21.190517) (xy 274.315492 21.236398)
			(xy 274.351207 21.277615) (xy 274.392424 21.31333) (xy 274.438305 21.342816) (xy 274.487915 21.365473)
			(xy 274.540245 21.380838) (xy 274.594229 21.3886) (xy 274.648767 21.3886) (xy 274.702751 21.380838)
			(xy 274.755081 21.365473) (xy 274.804691 21.342816) (xy 274.850572 21.31333) (xy 274.891789 21.277615)
			(xy 274.927504 21.236398) (xy 274.95699 21.190517) (xy 274.979647 21.140907) (xy 274.995012 21.088577)
			(xy 275.002774 21.034593) (xy 275.00326 21.007324) (xy 275.00326 20.143724) (xy 275.002774 20.116455)
			(xy 274.995012 20.062471) (xy 274.979647 20.010141) (xy 274.95699 19.960531) (xy 274.927504 19.91465)
			(xy 274.891789 19.873433) (xy 274.850572 19.837718) (xy 274.804691 19.808232) (xy 274.755081 19.785575)
			(xy 274.702751 19.77021) (xy 274.648767 19.762448) (xy 274.594229 19.762448) (xy 274.540245 19.77021)
			(xy 274.487915 19.785575) (xy 274.438305 19.808232) (xy 274.392424 19.837718) (xy 274.351207 19.873433)
			(xy 274.315492 19.91465) (xy 274.286006 19.960531) (xy 274.263349 20.010141) (xy 274.247984 20.062471)
			(xy 274.240222 20.116455) (xy 274.239736 20.143724) (xy 270.62931 20.143724) (xy 270.683867 20.116558)
			(xy 270.756773 20.071417) (xy 270.825202 20.019741) (xy 270.888572 19.961972) (xy 270.946341 19.898602)
			(xy 270.998017 19.830173) (xy 271.043158 19.757267) (xy 271.08138 19.680507) (xy 271.112356 19.600548)
			(xy 271.135823 19.518072) (xy 271.151579 19.433782) (xy 271.159491 19.348399) (xy 271.159986 19.305524)
			(xy 271.159491 19.262649) (xy 275.654757 19.262649) (xy 275.654757 19.348399) (xy 275.662669 19.433782)
			(xy 275.678425 19.518072) (xy 275.701892 19.600548) (xy 275.732868 19.680507) (xy 275.77109 19.757267)
			(xy 275.816231 19.830173) (xy 275.867907 19.898602) (xy 275.925676 19.961972) (xy 275.989046 20.019741)
			(xy 276.057475 20.071417) (xy 276.130381 20.116558) (xy 276.207141 20.15478) (xy 276.2871 20.185756)
			(xy 276.369576 20.209223) (xy 276.453866 20.224979) (xy 276.539249 20.232891) (xy 276.624999 20.232891)
			(xy 276.710382 20.224979) (xy 276.794672 20.209223) (xy 276.877148 20.185756) (xy 276.957107 20.15478)
			(xy 277.033867 20.116558) (xy 277.106773 20.071417) (xy 277.175202 20.019741) (xy 277.238572 19.961972)
			(xy 277.296341 19.898602) (xy 277.348017 19.830173) (xy 277.393158 19.757267) (xy 277.43138 19.680507)
			(xy 277.462356 19.600548) (xy 277.485823 19.518072) (xy 277.501579 19.433782) (xy 277.509491 19.348399)
			(xy 277.509986 19.305524) (xy 277.509491 19.262649) (xy 277.508832 19.255537) (xy 308.364877 19.255537)
			(xy 308.364877 19.341287) (xy 308.372789 19.42667) (xy 308.388545 19.51096) (xy 308.412012 19.593436)
			(xy 308.442988 19.673395) (xy 308.48121 19.750155) (xy 308.526351 19.823061) (xy 308.578027 19.89149)
			(xy 308.635796 19.95486) (xy 308.699166 20.012629) (xy 308.767595 20.064305) (xy 308.840501 20.109446)
			(xy 308.917261 20.147668) (xy 308.99722 20.178644) (xy 309.079696 20.202111) (xy 309.163986 20.217867)
			(xy 309.249369 20.225779) (xy 309.335119 20.225779) (xy 309.420502 20.217867) (xy 309.504792 20.202111)
			(xy 309.587268 20.178644) (xy 309.667227 20.147668) (xy 309.68943 20.136612) (xy 310.871108 20.136612)
			(xy 310.871108 21.000212) (xy 310.871594 21.027481) (xy 310.879356 21.081465) (xy 310.894721 21.133795)
			(xy 310.917378 21.183405) (xy 310.946864 21.229286) (xy 310.982579 21.270503) (xy 311.023796 21.306218)
			(xy 311.069677 21.335704) (xy 311.119287 21.358361) (xy 311.171617 21.373726) (xy 311.225601 21.381488)
			(xy 311.280139 21.381488) (xy 311.334123 21.373726) (xy 311.386453 21.358361) (xy 311.436063 21.335704)
			(xy 311.481944 21.306218) (xy 311.523161 21.270503) (xy 311.558876 21.229286) (xy 311.588362 21.183405)
			(xy 311.611019 21.133795) (xy 311.626384 21.081465) (xy 311.634146 21.027481) (xy 311.634632 21.000212)
			(xy 311.634632 20.136612) (xy 311.634146 20.109343) (xy 311.626384 20.055359) (xy 311.611019 20.003029)
			(xy 311.588362 19.953419) (xy 311.558876 19.907538) (xy 311.523161 19.866321) (xy 311.481944 19.830606)
			(xy 311.436063 19.80112) (xy 311.386453 19.778463) (xy 311.334123 19.763098) (xy 311.280139 19.755336)
			(xy 311.225601 19.755336) (xy 311.171617 19.763098) (xy 311.119287 19.778463) (xy 311.069677 19.80112)
			(xy 311.023796 19.830606) (xy 310.982579 19.866321) (xy 310.946864 19.907538) (xy 310.917378 19.953419)
			(xy 310.894721 20.003029) (xy 310.879356 20.055359) (xy 310.871594 20.109343) (xy 310.871108 20.136612)
			(xy 309.68943 20.136612) (xy 309.743987 20.109446) (xy 309.816893 20.064305) (xy 309.885322 20.012629)
			(xy 309.948692 19.95486) (xy 310.006461 19.89149) (xy 310.058137 19.823061) (xy 310.103278 19.750155)
			(xy 310.1415 19.673395) (xy 310.172476 19.593436) (xy 310.195943 19.51096) (xy 310.211699 19.42667)
			(xy 310.219611 19.341287) (xy 310.220106 19.298412) (xy 310.219611 19.255537) (xy 314.714877 19.255537)
			(xy 314.714877 19.341287) (xy 314.722789 19.42667) (xy 314.738545 19.51096) (xy 314.762012 19.593436)
			(xy 314.792988 19.673395) (xy 314.83121 19.750155) (xy 314.876351 19.823061) (xy 314.928027 19.89149)
			(xy 314.985796 19.95486) (xy 315.049166 20.012629) (xy 315.117595 20.064305) (xy 315.190501 20.109446)
			(xy 315.267261 20.147668) (xy 315.34722 20.178644) (xy 315.429696 20.202111) (xy 315.513986 20.217867)
			(xy 315.599369 20.225779) (xy 315.685119 20.225779) (xy 315.770502 20.217867) (xy 315.854792 20.202111)
			(xy 315.937268 20.178644) (xy 316.017227 20.147668) (xy 316.093987 20.109446) (xy 316.166893 20.064305)
			(xy 316.235322 20.012629) (xy 316.298692 19.95486) (xy 316.356461 19.89149) (xy 316.408137 19.823061)
			(xy 316.453278 19.750155) (xy 316.4915 19.673395) (xy 316.522476 19.593436) (xy 316.545943 19.51096)
			(xy 316.561699 19.42667) (xy 316.569611 19.341287) (xy 316.570106 19.298412) (xy 316.569693 19.262649)
			(xy 334.455757 19.262649) (xy 334.455757 19.348399) (xy 334.463669 19.433782) (xy 334.479425 19.518072)
			(xy 334.502892 19.600548) (xy 334.533868 19.680507) (xy 334.57209 19.757267) (xy 334.617231 19.830173)
			(xy 334.668907 19.898602) (xy 334.726676 19.961972) (xy 334.790046 20.019741) (xy 334.858475 20.071417)
			(xy 334.931381 20.116558) (xy 335.008141 20.15478) (xy 335.0881 20.185756) (xy 335.170576 20.209223)
			(xy 335.254866 20.224979) (xy 335.340249 20.232891) (xy 335.425999 20.232891) (xy 335.511382 20.224979)
			(xy 335.595672 20.209223) (xy 335.678148 20.185756) (xy 335.758107 20.15478) (xy 335.78031 20.143724)
			(xy 339.390736 20.143724) (xy 339.390736 21.007324) (xy 339.391222 21.034593) (xy 339.398984 21.088577)
			(xy 339.414349 21.140907) (xy 339.437006 21.190517) (xy 339.466492 21.236398) (xy 339.502207 21.277615)
			(xy 339.543424 21.31333) (xy 339.589305 21.342816) (xy 339.638915 21.365473) (xy 339.691245 21.380838)
			(xy 339.745229 21.3886) (xy 339.799767 21.3886) (xy 339.853751 21.380838) (xy 339.906081 21.365473)
			(xy 339.955691 21.342816) (xy 340.001572 21.31333) (xy 340.042789 21.277615) (xy 340.078504 21.236398)
			(xy 340.10799 21.190517) (xy 340.130647 21.140907) (xy 340.146012 21.088577) (xy 340.153774 21.034593)
			(xy 340.15426 21.007324) (xy 340.15426 20.143724) (xy 340.153774 20.116455) (xy 340.146012 20.062471)
			(xy 340.130647 20.010141) (xy 340.10799 19.960531) (xy 340.078504 19.91465) (xy 340.042789 19.873433)
			(xy 340.001572 19.837718) (xy 339.955691 19.808232) (xy 339.906081 19.785575) (xy 339.853751 19.77021)
			(xy 339.799767 19.762448) (xy 339.745229 19.762448) (xy 339.691245 19.77021) (xy 339.638915 19.785575)
			(xy 339.589305 19.808232) (xy 339.543424 19.837718) (xy 339.502207 19.873433) (xy 339.466492 19.91465)
			(xy 339.437006 19.960531) (xy 339.414349 20.010141) (xy 339.398984 20.062471) (xy 339.391222 20.116455)
			(xy 339.390736 20.143724) (xy 335.78031 20.143724) (xy 335.834867 20.116558) (xy 335.907773 20.071417)
			(xy 335.976202 20.019741) (xy 336.039572 19.961972) (xy 336.097341 19.898602) (xy 336.149017 19.830173)
			(xy 336.194158 19.757267) (xy 336.23238 19.680507) (xy 336.263356 19.600548) (xy 336.286823 19.518072)
			(xy 336.302579 19.433782) (xy 336.310491 19.348399) (xy 336.310986 19.305524) (xy 336.310491 19.262649)
			(xy 340.805757 19.262649) (xy 340.805757 19.348399) (xy 340.813669 19.433782) (xy 340.829425 19.518072)
			(xy 340.852892 19.600548) (xy 340.883868 19.680507) (xy 340.92209 19.757267) (xy 340.967231 19.830173)
			(xy 341.018907 19.898602) (xy 341.076676 19.961972) (xy 341.140046 20.019741) (xy 341.208475 20.071417)
			(xy 341.281381 20.116558) (xy 341.358141 20.15478) (xy 341.4381 20.185756) (xy 341.520576 20.209223)
			(xy 341.604866 20.224979) (xy 341.690249 20.232891) (xy 341.775999 20.232891) (xy 341.861382 20.224979)
			(xy 341.945672 20.209223) (xy 342.028148 20.185756) (xy 342.108107 20.15478) (xy 342.184867 20.116558)
			(xy 342.257773 20.071417) (xy 342.326202 20.019741) (xy 342.389572 19.961972) (xy 342.447341 19.898602)
			(xy 342.499017 19.830173) (xy 342.544158 19.757267) (xy 342.58238 19.680507) (xy 342.613356 19.600548)
			(xy 342.636823 19.518072) (xy 342.652579 19.433782) (xy 342.660491 19.348399) (xy 342.660986 19.305524)
			(xy 342.660491 19.262649) (xy 342.659832 19.255537) (xy 373.515877 19.255537) (xy 373.515877 19.341287)
			(xy 373.523789 19.42667) (xy 373.539545 19.51096) (xy 373.563012 19.593436) (xy 373.593988 19.673395)
			(xy 373.63221 19.750155) (xy 373.677351 19.823061) (xy 373.729027 19.89149) (xy 373.786796 19.95486)
			(xy 373.850166 20.012629) (xy 373.918595 20.064305) (xy 373.991501 20.109446) (xy 374.068261 20.147668)
			(xy 374.14822 20.178644) (xy 374.230696 20.202111) (xy 374.314986 20.217867) (xy 374.400369 20.225779)
			(xy 374.486119 20.225779) (xy 374.571502 20.217867) (xy 374.655792 20.202111) (xy 374.738268 20.178644)
			(xy 374.818227 20.147668) (xy 374.84043 20.136612) (xy 376.022108 20.136612) (xy 376.022108 21.000212)
			(xy 376.022594 21.027481) (xy 376.030356 21.081465) (xy 376.045721 21.133795) (xy 376.068378 21.183405)
			(xy 376.097864 21.229286) (xy 376.133579 21.270503) (xy 376.174796 21.306218) (xy 376.220677 21.335704)
			(xy 376.270287 21.358361) (xy 376.322617 21.373726) (xy 376.376601 21.381488) (xy 376.431139 21.381488)
			(xy 376.485123 21.373726) (xy 376.537453 21.358361) (xy 376.587063 21.335704) (xy 376.632944 21.306218)
			(xy 376.674161 21.270503) (xy 376.709876 21.229286) (xy 376.739362 21.183405) (xy 376.762019 21.133795)
			(xy 376.777384 21.081465) (xy 376.785146 21.027481) (xy 376.785632 21.000212) (xy 376.785632 20.136612)
			(xy 376.785146 20.109343) (xy 376.777384 20.055359) (xy 376.762019 20.003029) (xy 376.739362 19.953419)
			(xy 376.709876 19.907538) (xy 376.674161 19.866321) (xy 376.632944 19.830606) (xy 376.587063 19.80112)
			(xy 376.537453 19.778463) (xy 376.485123 19.763098) (xy 376.431139 19.755336) (xy 376.376601 19.755336)
			(xy 376.322617 19.763098) (xy 376.270287 19.778463) (xy 376.220677 19.80112) (xy 376.174796 19.830606)
			(xy 376.133579 19.866321) (xy 376.097864 19.907538) (xy 376.068378 19.953419) (xy 376.045721 20.003029)
			(xy 376.030356 20.055359) (xy 376.022594 20.109343) (xy 376.022108 20.136612) (xy 374.84043 20.136612)
			(xy 374.894987 20.109446) (xy 374.967893 20.064305) (xy 375.036322 20.012629) (xy 375.099692 19.95486)
			(xy 375.157461 19.89149) (xy 375.209137 19.823061) (xy 375.254278 19.750155) (xy 375.2925 19.673395)
			(xy 375.323476 19.593436) (xy 375.346943 19.51096) (xy 375.362699 19.42667) (xy 375.370611 19.341287)
			(xy 375.371106 19.298412) (xy 375.370611 19.255537) (xy 379.865877 19.255537) (xy 379.865877 19.341287)
			(xy 379.873789 19.42667) (xy 379.889545 19.51096) (xy 379.913012 19.593436) (xy 379.943988 19.673395)
			(xy 379.98221 19.750155) (xy 380.027351 19.823061) (xy 380.079027 19.89149) (xy 380.136796 19.95486)
			(xy 380.200166 20.012629) (xy 380.268595 20.064305) (xy 380.341501 20.109446) (xy 380.418261 20.147668)
			(xy 380.49822 20.178644) (xy 380.580696 20.202111) (xy 380.664986 20.217867) (xy 380.750369 20.225779)
			(xy 380.836119 20.225779) (xy 380.921502 20.217867) (xy 381.005792 20.202111) (xy 381.088268 20.178644)
			(xy 381.168227 20.147668) (xy 381.244987 20.109446) (xy 381.317893 20.064305) (xy 381.386322 20.012629)
			(xy 381.449692 19.95486) (xy 381.507461 19.89149) (xy 381.559137 19.823061) (xy 381.604278 19.750155)
			(xy 381.6425 19.673395) (xy 381.673476 19.593436) (xy 381.696943 19.51096) (xy 381.712699 19.42667)
			(xy 381.720611 19.341287) (xy 381.721106 19.298412) (xy 381.720693 19.262649) (xy 399.098757 19.262649)
			(xy 399.098757 19.348399) (xy 399.106669 19.433782) (xy 399.122425 19.518072) (xy 399.145892 19.600548)
			(xy 399.176868 19.680507) (xy 399.21509 19.757267) (xy 399.260231 19.830173) (xy 399.311907 19.898602)
			(xy 399.369676 19.961972) (xy 399.433046 20.019741) (xy 399.501475 20.071417) (xy 399.574381 20.116558)
			(xy 399.651141 20.15478) (xy 399.7311 20.185756) (xy 399.813576 20.209223) (xy 399.897866 20.224979)
			(xy 399.983249 20.232891) (xy 400.068999 20.232891) (xy 400.154382 20.224979) (xy 400.238672 20.209223)
			(xy 400.321148 20.185756) (xy 400.401107 20.15478) (xy 400.42331 20.143724) (xy 404.033736 20.143724)
			(xy 404.033736 21.007324) (xy 404.034222 21.034593) (xy 404.041984 21.088577) (xy 404.057349 21.140907)
			(xy 404.080006 21.190517) (xy 404.109492 21.236398) (xy 404.145207 21.277615) (xy 404.186424 21.31333)
			(xy 404.232305 21.342816) (xy 404.281915 21.365473) (xy 404.334245 21.380838) (xy 404.388229 21.3886)
			(xy 404.442767 21.3886) (xy 404.496751 21.380838) (xy 404.549081 21.365473) (xy 404.598691 21.342816)
			(xy 404.644572 21.31333) (xy 404.685789 21.277615) (xy 404.721504 21.236398) (xy 404.75099 21.190517)
			(xy 404.773647 21.140907) (xy 404.789012 21.088577) (xy 404.796774 21.034593) (xy 404.79726 21.007324)
			(xy 404.79726 20.143724) (xy 404.796774 20.116455) (xy 404.789012 20.062471) (xy 404.773647 20.010141)
			(xy 404.75099 19.960531) (xy 404.721504 19.91465) (xy 404.685789 19.873433) (xy 404.644572 19.837718)
			(xy 404.598691 19.808232) (xy 404.549081 19.785575) (xy 404.496751 19.77021) (xy 404.442767 19.762448)
			(xy 404.388229 19.762448) (xy 404.334245 19.77021) (xy 404.281915 19.785575) (xy 404.232305 19.808232)
			(xy 404.186424 19.837718) (xy 404.145207 19.873433) (xy 404.109492 19.91465) (xy 404.080006 19.960531)
			(xy 404.057349 20.010141) (xy 404.041984 20.062471) (xy 404.034222 20.116455) (xy 404.033736 20.143724)
			(xy 400.42331 20.143724) (xy 400.477867 20.116558) (xy 400.550773 20.071417) (xy 400.619202 20.019741)
			(xy 400.682572 19.961972) (xy 400.740341 19.898602) (xy 400.792017 19.830173) (xy 400.837158 19.757267)
			(xy 400.87538 19.680507) (xy 400.906356 19.600548) (xy 400.929823 19.518072) (xy 400.945579 19.433782)
			(xy 400.953491 19.348399) (xy 400.953986 19.305524) (xy 400.953491 19.262649) (xy 405.448757 19.262649)
			(xy 405.448757 19.348399) (xy 405.456669 19.433782) (xy 405.472425 19.518072) (xy 405.495892 19.600548)
			(xy 405.526868 19.680507) (xy 405.56509 19.757267) (xy 405.610231 19.830173) (xy 405.661907 19.898602)
			(xy 405.719676 19.961972) (xy 405.783046 20.019741) (xy 405.851475 20.071417) (xy 405.924381 20.116558)
			(xy 406.001141 20.15478) (xy 406.0811 20.185756) (xy 406.163576 20.209223) (xy 406.247866 20.224979)
			(xy 406.333249 20.232891) (xy 406.418999 20.232891) (xy 406.504382 20.224979) (xy 406.588672 20.209223)
			(xy 406.671148 20.185756) (xy 406.751107 20.15478) (xy 406.827867 20.116558) (xy 406.900773 20.071417)
			(xy 406.969202 20.019741) (xy 407.032572 19.961972) (xy 407.090341 19.898602) (xy 407.142017 19.830173)
			(xy 407.187158 19.757267) (xy 407.22538 19.680507) (xy 407.256356 19.600548) (xy 407.279823 19.518072)
			(xy 407.295579 19.433782) (xy 407.303491 19.348399) (xy 407.303986 19.305524) (xy 407.303491 19.262649)
			(xy 407.302832 19.255537) (xy 438.158877 19.255537) (xy 438.158877 19.341287) (xy 438.166789 19.42667)
			(xy 438.182545 19.51096) (xy 438.206012 19.593436) (xy 438.236988 19.673395) (xy 438.27521 19.750155)
			(xy 438.320351 19.823061) (xy 438.372027 19.89149) (xy 438.429796 19.95486) (xy 438.493166 20.012629)
			(xy 438.561595 20.064305) (xy 438.634501 20.109446) (xy 438.711261 20.147668) (xy 438.79122 20.178644)
			(xy 438.873696 20.202111) (xy 438.957986 20.217867) (xy 439.043369 20.225779) (xy 439.129119 20.225779)
			(xy 439.214502 20.217867) (xy 439.298792 20.202111) (xy 439.381268 20.178644) (xy 439.461227 20.147668)
			(xy 439.48343 20.136612) (xy 440.665108 20.136612) (xy 440.665108 21.000212) (xy 440.665594 21.027481)
			(xy 440.673356 21.081465) (xy 440.688721 21.133795) (xy 440.711378 21.183405) (xy 440.740864 21.229286)
			(xy 440.776579 21.270503) (xy 440.817796 21.306218) (xy 440.863677 21.335704) (xy 440.913287 21.358361)
			(xy 440.965617 21.373726) (xy 441.019601 21.381488) (xy 441.074139 21.381488) (xy 441.128123 21.373726)
			(xy 441.180453 21.358361) (xy 441.230063 21.335704) (xy 441.275944 21.306218) (xy 441.317161 21.270503)
			(xy 441.352876 21.229286) (xy 441.382362 21.183405) (xy 441.405019 21.133795) (xy 441.420384 21.081465)
			(xy 441.428146 21.027481) (xy 441.428632 21.000212) (xy 441.428632 20.136612) (xy 441.428146 20.109343)
			(xy 441.420384 20.055359) (xy 441.405019 20.003029) (xy 441.382362 19.953419) (xy 441.352876 19.907538)
			(xy 441.317161 19.866321) (xy 441.275944 19.830606) (xy 441.230063 19.80112) (xy 441.180453 19.778463)
			(xy 441.128123 19.763098) (xy 441.074139 19.755336) (xy 441.019601 19.755336) (xy 440.965617 19.763098)
			(xy 440.913287 19.778463) (xy 440.863677 19.80112) (xy 440.817796 19.830606) (xy 440.776579 19.866321)
			(xy 440.740864 19.907538) (xy 440.711378 19.953419) (xy 440.688721 20.003029) (xy 440.673356 20.055359)
			(xy 440.665594 20.109343) (xy 440.665108 20.136612) (xy 439.48343 20.136612) (xy 439.537987 20.109446)
			(xy 439.610893 20.064305) (xy 439.679322 20.012629) (xy 439.742692 19.95486) (xy 439.800461 19.89149)
			(xy 439.852137 19.823061) (xy 439.897278 19.750155) (xy 439.9355 19.673395) (xy 439.966476 19.593436)
			(xy 439.989943 19.51096) (xy 440.005699 19.42667) (xy 440.013611 19.341287) (xy 440.014106 19.298412)
			(xy 440.013611 19.255537) (xy 444.508877 19.255537) (xy 444.508877 19.341287) (xy 444.516789 19.42667)
			(xy 444.532545 19.51096) (xy 444.556012 19.593436) (xy 444.586988 19.673395) (xy 444.62521 19.750155)
			(xy 444.670351 19.823061) (xy 444.722027 19.89149) (xy 444.779796 19.95486) (xy 444.843166 20.012629)
			(xy 444.911595 20.064305) (xy 444.984501 20.109446) (xy 445.061261 20.147668) (xy 445.14122 20.178644)
			(xy 445.223696 20.202111) (xy 445.307986 20.217867) (xy 445.393369 20.225779) (xy 445.479119 20.225779)
			(xy 445.564502 20.217867) (xy 445.648792 20.202111) (xy 445.731268 20.178644) (xy 445.811227 20.147668)
			(xy 445.887987 20.109446) (xy 445.960893 20.064305) (xy 446.029322 20.012629) (xy 446.092692 19.95486)
			(xy 446.150461 19.89149) (xy 446.202137 19.823061) (xy 446.247278 19.750155) (xy 446.2855 19.673395)
			(xy 446.316476 19.593436) (xy 446.339943 19.51096) (xy 446.355699 19.42667) (xy 446.363611 19.341287)
			(xy 446.364106 19.298412) (xy 446.363611 19.255537) (xy 446.355699 19.170154) (xy 446.339943 19.085864)
			(xy 446.316476 19.003388) (xy 446.2855 18.923429) (xy 446.247278 18.846669) (xy 446.202137 18.773763)
			(xy 446.150461 18.705334) (xy 446.092692 18.641964) (xy 446.029322 18.584195) (xy 445.960893 18.532519)
			(xy 445.887987 18.487378) (xy 445.811227 18.449156) (xy 445.731268 18.41818) (xy 445.648792 18.394713)
			(xy 445.564502 18.378957) (xy 445.479119 18.371045) (xy 445.393369 18.371045) (xy 445.307986 18.378957)
			(xy 445.223696 18.394713) (xy 445.14122 18.41818) (xy 445.061261 18.449156) (xy 444.984501 18.487378)
			(xy 444.911595 18.532519) (xy 444.843166 18.584195) (xy 444.779796 18.641964) (xy 444.722027 18.705334)
			(xy 444.670351 18.773763) (xy 444.62521 18.846669) (xy 444.586988 18.923429) (xy 444.556012 19.003388)
			(xy 444.532545 19.085864) (xy 444.516789 19.170154) (xy 444.508877 19.255537) (xy 440.013611 19.255537)
			(xy 440.005699 19.170154) (xy 439.989943 19.085864) (xy 439.966476 19.003388) (xy 439.9355 18.923429)
			(xy 439.897278 18.846669) (xy 439.852137 18.773763) (xy 439.800461 18.705334) (xy 439.742692 18.641964)
			(xy 439.679322 18.584195) (xy 439.610893 18.532519) (xy 439.537987 18.487378) (xy 439.461227 18.449156)
			(xy 439.381268 18.41818) (xy 439.298792 18.394713) (xy 439.214502 18.378957) (xy 439.129119 18.371045)
			(xy 439.043369 18.371045) (xy 438.957986 18.378957) (xy 438.873696 18.394713) (xy 438.79122 18.41818)
			(xy 438.711261 18.449156) (xy 438.634501 18.487378) (xy 438.561595 18.532519) (xy 438.493166 18.584195)
			(xy 438.429796 18.641964) (xy 438.372027 18.705334) (xy 438.320351 18.773763) (xy 438.27521 18.846669)
			(xy 438.236988 18.923429) (xy 438.206012 19.003388) (xy 438.182545 19.085864) (xy 438.166789 19.170154)
			(xy 438.158877 19.255537) (xy 407.302832 19.255537) (xy 407.295579 19.177266) (xy 407.279823 19.092976)
			(xy 407.256356 19.0105) (xy 407.22538 18.930541) (xy 407.187158 18.853781) (xy 407.142017 18.780875)
			(xy 407.090341 18.712446) (xy 407.032572 18.649076) (xy 406.969202 18.591307) (xy 406.900773 18.539631)
			(xy 406.827867 18.49449) (xy 406.751107 18.456268) (xy 406.671148 18.425292) (xy 406.588672 18.401825)
			(xy 406.504382 18.386069) (xy 406.418999 18.378157) (xy 406.333249 18.378157) (xy 406.247866 18.386069)
			(xy 406.163576 18.401825) (xy 406.0811 18.425292) (xy 406.001141 18.456268) (xy 405.924381 18.49449)
			(xy 405.851475 18.539631) (xy 405.783046 18.591307) (xy 405.719676 18.649076) (xy 405.661907 18.712446)
			(xy 405.610231 18.780875) (xy 405.56509 18.853781) (xy 405.526868 18.930541) (xy 405.495892 19.0105)
			(xy 405.472425 19.092976) (xy 405.456669 19.177266) (xy 405.448757 19.262649) (xy 400.953491 19.262649)
			(xy 400.945579 19.177266) (xy 400.929823 19.092976) (xy 400.906356 19.0105) (xy 400.87538 18.930541)
			(xy 400.837158 18.853781) (xy 400.792017 18.780875) (xy 400.740341 18.712446) (xy 400.682572 18.649076)
			(xy 400.619202 18.591307) (xy 400.550773 18.539631) (xy 400.477867 18.49449) (xy 400.401107 18.456268)
			(xy 400.321148 18.425292) (xy 400.238672 18.401825) (xy 400.154382 18.386069) (xy 400.068999 18.378157)
			(xy 399.983249 18.378157) (xy 399.897866 18.386069) (xy 399.813576 18.401825) (xy 399.7311 18.425292)
			(xy 399.651141 18.456268) (xy 399.574381 18.49449) (xy 399.501475 18.539631) (xy 399.433046 18.591307)
			(xy 399.369676 18.649076) (xy 399.311907 18.712446) (xy 399.260231 18.780875) (xy 399.21509 18.853781)
			(xy 399.176868 18.930541) (xy 399.145892 19.0105) (xy 399.122425 19.092976) (xy 399.106669 19.177266)
			(xy 399.098757 19.262649) (xy 381.720693 19.262649) (xy 381.720611 19.255537) (xy 381.712699 19.170154)
			(xy 381.696943 19.085864) (xy 381.673476 19.003388) (xy 381.6425 18.923429) (xy 381.604278 18.846669)
			(xy 381.559137 18.773763) (xy 381.507461 18.705334) (xy 381.449692 18.641964) (xy 381.386322 18.584195)
			(xy 381.317893 18.532519) (xy 381.244987 18.487378) (xy 381.168227 18.449156) (xy 381.088268 18.41818)
			(xy 381.005792 18.394713) (xy 380.921502 18.378957) (xy 380.836119 18.371045) (xy 380.750369 18.371045)
			(xy 380.664986 18.378957) (xy 380.580696 18.394713) (xy 380.49822 18.41818) (xy 380.418261 18.449156)
			(xy 380.341501 18.487378) (xy 380.268595 18.532519) (xy 380.200166 18.584195) (xy 380.136796 18.641964)
			(xy 380.079027 18.705334) (xy 380.027351 18.773763) (xy 379.98221 18.846669) (xy 379.943988 18.923429)
			(xy 379.913012 19.003388) (xy 379.889545 19.085864) (xy 379.873789 19.170154) (xy 379.865877 19.255537)
			(xy 375.370611 19.255537) (xy 375.362699 19.170154) (xy 375.346943 19.085864) (xy 375.323476 19.003388)
			(xy 375.2925 18.923429) (xy 375.254278 18.846669) (xy 375.209137 18.773763) (xy 375.157461 18.705334)
			(xy 375.099692 18.641964) (xy 375.036322 18.584195) (xy 374.967893 18.532519) (xy 374.894987 18.487378)
			(xy 374.818227 18.449156) (xy 374.738268 18.41818) (xy 374.655792 18.394713) (xy 374.571502 18.378957)
			(xy 374.486119 18.371045) (xy 374.400369 18.371045) (xy 374.314986 18.378957) (xy 374.230696 18.394713)
			(xy 374.14822 18.41818) (xy 374.068261 18.449156) (xy 373.991501 18.487378) (xy 373.918595 18.532519)
			(xy 373.850166 18.584195) (xy 373.786796 18.641964) (xy 373.729027 18.705334) (xy 373.677351 18.773763)
			(xy 373.63221 18.846669) (xy 373.593988 18.923429) (xy 373.563012 19.003388) (xy 373.539545 19.085864)
			(xy 373.523789 19.170154) (xy 373.515877 19.255537) (xy 342.659832 19.255537) (xy 342.652579 19.177266)
			(xy 342.636823 19.092976) (xy 342.613356 19.0105) (xy 342.58238 18.930541) (xy 342.544158 18.853781)
			(xy 342.499017 18.780875) (xy 342.447341 18.712446) (xy 342.389572 18.649076) (xy 342.326202 18.591307)
			(xy 342.257773 18.539631) (xy 342.184867 18.49449) (xy 342.108107 18.456268) (xy 342.028148 18.425292)
			(xy 341.945672 18.401825) (xy 341.861382 18.386069) (xy 341.775999 18.378157) (xy 341.690249 18.378157)
			(xy 341.604866 18.386069) (xy 341.520576 18.401825) (xy 341.4381 18.425292) (xy 341.358141 18.456268)
			(xy 341.281381 18.49449) (xy 341.208475 18.539631) (xy 341.140046 18.591307) (xy 341.076676 18.649076)
			(xy 341.018907 18.712446) (xy 340.967231 18.780875) (xy 340.92209 18.853781) (xy 340.883868 18.930541)
			(xy 340.852892 19.0105) (xy 340.829425 19.092976) (xy 340.813669 19.177266) (xy 340.805757 19.262649)
			(xy 336.310491 19.262649) (xy 336.302579 19.177266) (xy 336.286823 19.092976) (xy 336.263356 19.0105)
			(xy 336.23238 18.930541) (xy 336.194158 18.853781) (xy 336.149017 18.780875) (xy 336.097341 18.712446)
			(xy 336.039572 18.649076) (xy 335.976202 18.591307) (xy 335.907773 18.539631) (xy 335.834867 18.49449)
			(xy 335.758107 18.456268) (xy 335.678148 18.425292) (xy 335.595672 18.401825) (xy 335.511382 18.386069)
			(xy 335.425999 18.378157) (xy 335.340249 18.378157) (xy 335.254866 18.386069) (xy 335.170576 18.401825)
			(xy 335.0881 18.425292) (xy 335.008141 18.456268) (xy 334.931381 18.49449) (xy 334.858475 18.539631)
			(xy 334.790046 18.591307) (xy 334.726676 18.649076) (xy 334.668907 18.712446) (xy 334.617231 18.780875)
			(xy 334.57209 18.853781) (xy 334.533868 18.930541) (xy 334.502892 19.0105) (xy 334.479425 19.092976)
			(xy 334.463669 19.177266) (xy 334.455757 19.262649) (xy 316.569693 19.262649) (xy 316.569611 19.255537)
			(xy 316.561699 19.170154) (xy 316.545943 19.085864) (xy 316.522476 19.003388) (xy 316.4915 18.923429)
			(xy 316.453278 18.846669) (xy 316.408137 18.773763) (xy 316.356461 18.705334) (xy 316.298692 18.641964)
			(xy 316.235322 18.584195) (xy 316.166893 18.532519) (xy 316.093987 18.487378) (xy 316.017227 18.449156)
			(xy 315.937268 18.41818) (xy 315.854792 18.394713) (xy 315.770502 18.378957) (xy 315.685119 18.371045)
			(xy 315.599369 18.371045) (xy 315.513986 18.378957) (xy 315.429696 18.394713) (xy 315.34722 18.41818)
			(xy 315.267261 18.449156) (xy 315.190501 18.487378) (xy 315.117595 18.532519) (xy 315.049166 18.584195)
			(xy 314.985796 18.641964) (xy 314.928027 18.705334) (xy 314.876351 18.773763) (xy 314.83121 18.846669)
			(xy 314.792988 18.923429) (xy 314.762012 19.003388) (xy 314.738545 19.085864) (xy 314.722789 19.170154)
			(xy 314.714877 19.255537) (xy 310.219611 19.255537) (xy 310.211699 19.170154) (xy 310.195943 19.085864)
			(xy 310.172476 19.003388) (xy 310.1415 18.923429) (xy 310.103278 18.846669) (xy 310.058137 18.773763)
			(xy 310.006461 18.705334) (xy 309.948692 18.641964) (xy 309.885322 18.584195) (xy 309.816893 18.532519)
			(xy 309.743987 18.487378) (xy 309.667227 18.449156) (xy 309.587268 18.41818) (xy 309.504792 18.394713)
			(xy 309.420502 18.378957) (xy 309.335119 18.371045) (xy 309.249369 18.371045) (xy 309.163986 18.378957)
			(xy 309.079696 18.394713) (xy 308.99722 18.41818) (xy 308.917261 18.449156) (xy 308.840501 18.487378)
			(xy 308.767595 18.532519) (xy 308.699166 18.584195) (xy 308.635796 18.641964) (xy 308.578027 18.705334)
			(xy 308.526351 18.773763) (xy 308.48121 18.846669) (xy 308.442988 18.923429) (xy 308.412012 19.003388)
			(xy 308.388545 19.085864) (xy 308.372789 19.170154) (xy 308.364877 19.255537) (xy 277.508832 19.255537)
			(xy 277.501579 19.177266) (xy 277.485823 19.092976) (xy 277.462356 19.0105) (xy 277.43138 18.930541)
			(xy 277.393158 18.853781) (xy 277.348017 18.780875) (xy 277.296341 18.712446) (xy 277.238572 18.649076)
			(xy 277.175202 18.591307) (xy 277.106773 18.539631) (xy 277.033867 18.49449) (xy 276.957107 18.456268)
			(xy 276.877148 18.425292) (xy 276.794672 18.401825) (xy 276.710382 18.386069) (xy 276.624999 18.378157)
			(xy 276.539249 18.378157) (xy 276.453866 18.386069) (xy 276.369576 18.401825) (xy 276.2871 18.425292)
			(xy 276.207141 18.456268) (xy 276.130381 18.49449) (xy 276.057475 18.539631) (xy 275.989046 18.591307)
			(xy 275.925676 18.649076) (xy 275.867907 18.712446) (xy 275.816231 18.780875) (xy 275.77109 18.853781)
			(xy 275.732868 18.930541) (xy 275.701892 19.0105) (xy 275.678425 19.092976) (xy 275.662669 19.177266)
			(xy 275.654757 19.262649) (xy 271.159491 19.262649) (xy 271.151579 19.177266) (xy 271.135823 19.092976)
			(xy 271.112356 19.0105) (xy 271.08138 18.930541) (xy 271.043158 18.853781) (xy 270.998017 18.780875)
			(xy 270.946341 18.712446) (xy 270.888572 18.649076) (xy 270.825202 18.591307) (xy 270.756773 18.539631)
			(xy 270.683867 18.49449) (xy 270.607107 18.456268) (xy 270.527148 18.425292) (xy 270.444672 18.401825)
			(xy 270.360382 18.386069) (xy 270.274999 18.378157) (xy 270.189249 18.378157) (xy 270.103866 18.386069)
			(xy 270.019576 18.401825) (xy 269.9371 18.425292) (xy 269.857141 18.456268) (xy 269.780381 18.49449)
			(xy 269.707475 18.539631) (xy 269.639046 18.591307) (xy 269.575676 18.649076) (xy 269.517907 18.712446)
			(xy 269.466231 18.780875) (xy 269.42109 18.853781) (xy 269.382868 18.930541) (xy 269.351892 19.0105)
			(xy 269.328425 19.092976) (xy 269.312669 19.177266) (xy 269.304757 19.262649) (xy 252.231493 19.262649)
			(xy 252.231411 19.255537) (xy 252.223499 19.170154) (xy 252.207743 19.085864) (xy 252.184276 19.003388)
			(xy 252.1533 18.923429) (xy 252.115078 18.846669) (xy 252.069937 18.773763) (xy 252.018261 18.705334)
			(xy 251.960492 18.641964) (xy 251.897122 18.584195) (xy 251.828693 18.532519) (xy 251.755787 18.487378)
			(xy 251.679027 18.449156) (xy 251.599068 18.41818) (xy 251.516592 18.394713) (xy 251.432302 18.378957)
			(xy 251.346919 18.371045) (xy 251.261169 18.371045) (xy 251.175786 18.378957) (xy 251.091496 18.394713)
			(xy 251.00902 18.41818) (xy 250.929061 18.449156) (xy 250.852301 18.487378) (xy 250.779395 18.532519)
			(xy 250.710966 18.584195) (xy 250.647596 18.641964) (xy 250.589827 18.705334) (xy 250.538151 18.773763)
			(xy 250.49301 18.846669) (xy 250.454788 18.923429) (xy 250.423812 19.003388) (xy 250.400345 19.085864)
			(xy 250.384589 19.170154) (xy 250.376677 19.255537) (xy 245.881411 19.255537) (xy 245.873499 19.170154)
			(xy 245.857743 19.085864) (xy 245.834276 19.003388) (xy 245.8033 18.923429) (xy 245.765078 18.846669)
			(xy 245.719937 18.773763) (xy 245.668261 18.705334) (xy 245.610492 18.641964) (xy 245.547122 18.584195)
			(xy 245.478693 18.532519) (xy 245.405787 18.487378) (xy 245.329027 18.449156) (xy 245.249068 18.41818)
			(xy 245.166592 18.394713) (xy 245.082302 18.378957) (xy 244.996919 18.371045) (xy 244.911169 18.371045)
			(xy 244.825786 18.378957) (xy 244.741496 18.394713) (xy 244.65902 18.41818) (xy 244.579061 18.449156)
			(xy 244.502301 18.487378) (xy 244.429395 18.532519) (xy 244.360966 18.584195) (xy 244.297596 18.641964)
			(xy 244.239827 18.705334) (xy 244.188151 18.773763) (xy 244.14301 18.846669) (xy 244.104788 18.923429)
			(xy 244.073812 19.003388) (xy 244.050345 19.085864) (xy 244.034589 19.170154) (xy 244.026677 19.255537)
			(xy 218.199832 19.255537) (xy 218.192579 19.177266) (xy 218.176823 19.092976) (xy 218.153356 19.0105)
			(xy 218.12238 18.930541) (xy 218.084158 18.853781) (xy 218.039017 18.780875) (xy 217.987341 18.712446)
			(xy 217.929572 18.649076) (xy 217.866202 18.591307) (xy 217.797773 18.539631) (xy 217.724867 18.49449)
			(xy 217.648107 18.456268) (xy 217.568148 18.425292) (xy 217.485672 18.401825) (xy 217.401382 18.386069)
			(xy 217.315999 18.378157) (xy 217.230249 18.378157) (xy 217.144866 18.386069) (xy 217.060576 18.401825)
			(xy 216.9781 18.425292) (xy 216.898141 18.456268) (xy 216.821381 18.49449) (xy 216.748475 18.539631)
			(xy 216.680046 18.591307) (xy 216.616676 18.649076) (xy 216.558907 18.712446) (xy 216.507231 18.780875)
			(xy 216.46209 18.853781) (xy 216.423868 18.930541) (xy 216.392892 19.0105) (xy 216.369425 19.092976)
			(xy 216.353669 19.177266) (xy 216.345757 19.262649) (xy 211.850491 19.262649) (xy 211.842579 19.177266)
			(xy 211.826823 19.092976) (xy 211.803356 19.0105) (xy 211.77238 18.930541) (xy 211.734158 18.853781)
			(xy 211.689017 18.780875) (xy 211.637341 18.712446) (xy 211.579572 18.649076) (xy 211.516202 18.591307)
			(xy 211.447773 18.539631) (xy 211.374867 18.49449) (xy 211.298107 18.456268) (xy 211.218148 18.425292)
			(xy 211.135672 18.401825) (xy 211.051382 18.386069) (xy 210.965999 18.378157) (xy 210.880249 18.378157)
			(xy 210.794866 18.386069) (xy 210.710576 18.401825) (xy 210.6281 18.425292) (xy 210.548141 18.456268)
			(xy 210.471381 18.49449) (xy 210.398475 18.539631) (xy 210.330046 18.591307) (xy 210.266676 18.649076)
			(xy 210.208907 18.712446) (xy 210.157231 18.780875) (xy 210.11209 18.853781) (xy 210.073868 18.930541)
			(xy 210.042892 19.0105) (xy 210.019425 19.092976) (xy 210.003669 19.177266) (xy 209.995757 19.262649)
			(xy 158.621984 19.262649) (xy 158.621984 16.722649) (xy 209.995757 16.722649) (xy 209.995757 16.808399)
			(xy 210.003669 16.893782) (xy 210.019425 16.978072) (xy 210.042892 17.060548) (xy 210.073868 17.140507)
			(xy 210.11209 17.217267) (xy 210.157231 17.290173) (xy 210.208907 17.358602) (xy 210.266676 17.421972)
			(xy 210.330046 17.479741) (xy 210.398475 17.531417) (xy 210.471381 17.576558) (xy 210.548141 17.61478)
			(xy 210.6281 17.645756) (xy 210.710576 17.669223) (xy 210.794866 17.684979) (xy 210.880249 17.692891)
			(xy 210.965999 17.692891) (xy 211.051382 17.684979) (xy 211.135672 17.669223) (xy 211.218148 17.645756)
			(xy 211.298107 17.61478) (xy 211.374867 17.576558) (xy 211.447773 17.531417) (xy 211.516202 17.479741)
			(xy 211.579572 17.421972) (xy 211.637341 17.358602) (xy 211.689017 17.290173) (xy 211.734158 17.217267)
			(xy 211.77238 17.140507) (xy 211.803356 17.060548) (xy 211.826823 16.978072) (xy 211.842579 16.893782)
			(xy 211.850491 16.808399) (xy 211.850986 16.765524) (xy 211.850491 16.722649) (xy 216.345757 16.722649)
			(xy 216.345757 16.808399) (xy 216.353669 16.893782) (xy 216.369425 16.978072) (xy 216.392892 17.060548)
			(xy 216.423868 17.140507) (xy 216.46209 17.217267) (xy 216.507231 17.290173) (xy 216.558907 17.358602)
			(xy 216.616676 17.421972) (xy 216.680046 17.479741) (xy 216.748475 17.531417) (xy 216.821381 17.576558)
			(xy 216.898141 17.61478) (xy 216.9781 17.645756) (xy 217.060576 17.669223) (xy 217.144866 17.684979)
			(xy 217.230249 17.692891) (xy 217.315999 17.692891) (xy 217.401382 17.684979) (xy 217.485672 17.669223)
			(xy 217.568148 17.645756) (xy 217.648107 17.61478) (xy 217.724867 17.576558) (xy 217.797773 17.531417)
			(xy 217.866202 17.479741) (xy 217.929572 17.421972) (xy 217.987341 17.358602) (xy 218.039017 17.290173)
			(xy 218.084158 17.217267) (xy 218.12238 17.140507) (xy 218.153356 17.060548) (xy 218.176823 16.978072)
			(xy 218.192579 16.893782) (xy 218.200491 16.808399) (xy 218.200986 16.765524) (xy 218.200491 16.722649)
			(xy 218.199832 16.715537) (xy 244.026677 16.715537) (xy 244.026677 16.801287) (xy 244.034589 16.88667)
			(xy 244.050345 16.97096) (xy 244.073812 17.053436) (xy 244.104788 17.133395) (xy 244.14301 17.210155)
			(xy 244.188151 17.283061) (xy 244.239827 17.35149) (xy 244.297596 17.41486) (xy 244.360966 17.472629)
			(xy 244.429395 17.524305) (xy 244.502301 17.569446) (xy 244.579061 17.607668) (xy 244.65902 17.638644)
			(xy 244.741496 17.662111) (xy 244.825786 17.677867) (xy 244.911169 17.685779) (xy 244.996919 17.685779)
			(xy 245.082302 17.677867) (xy 245.166592 17.662111) (xy 245.249068 17.638644) (xy 245.329027 17.607668)
			(xy 245.405787 17.569446) (xy 245.478693 17.524305) (xy 245.547122 17.472629) (xy 245.610492 17.41486)
			(xy 245.668261 17.35149) (xy 245.719937 17.283061) (xy 245.765078 17.210155) (xy 245.8033 17.133395)
			(xy 245.834276 17.053436) (xy 245.857743 16.97096) (xy 245.873499 16.88667) (xy 245.881411 16.801287)
			(xy 245.881906 16.758412) (xy 245.881411 16.715537) (xy 250.376677 16.715537) (xy 250.376677 16.801287)
			(xy 250.384589 16.88667) (xy 250.400345 16.97096) (xy 250.423812 17.053436) (xy 250.454788 17.133395)
			(xy 250.49301 17.210155) (xy 250.538151 17.283061) (xy 250.589827 17.35149) (xy 250.647596 17.41486)
			(xy 250.710966 17.472629) (xy 250.779395 17.524305) (xy 250.852301 17.569446) (xy 250.929061 17.607668)
			(xy 251.00902 17.638644) (xy 251.091496 17.662111) (xy 251.175786 17.677867) (xy 251.261169 17.685779)
			(xy 251.346919 17.685779) (xy 251.432302 17.677867) (xy 251.516592 17.662111) (xy 251.599068 17.638644)
			(xy 251.679027 17.607668) (xy 251.755787 17.569446) (xy 251.828693 17.524305) (xy 251.897122 17.472629)
			(xy 251.960492 17.41486) (xy 252.018261 17.35149) (xy 252.069937 17.283061) (xy 252.115078 17.210155)
			(xy 252.1533 17.133395) (xy 252.184276 17.053436) (xy 252.207743 16.97096) (xy 252.223499 16.88667)
			(xy 252.231411 16.801287) (xy 252.231906 16.758412) (xy 252.231493 16.722649) (xy 269.304757 16.722649)
			(xy 269.304757 16.808399) (xy 269.312669 16.893782) (xy 269.328425 16.978072) (xy 269.351892 17.060548)
			(xy 269.382868 17.140507) (xy 269.42109 17.217267) (xy 269.466231 17.290173) (xy 269.517907 17.358602)
			(xy 269.575676 17.421972) (xy 269.639046 17.479741) (xy 269.707475 17.531417) (xy 269.780381 17.576558)
			(xy 269.857141 17.61478) (xy 269.9371 17.645756) (xy 270.019576 17.669223) (xy 270.103866 17.684979)
			(xy 270.189249 17.692891) (xy 270.274999 17.692891) (xy 270.360382 17.684979) (xy 270.444672 17.669223)
			(xy 270.527148 17.645756) (xy 270.607107 17.61478) (xy 270.62931 17.603724) (xy 274.239736 17.603724)
			(xy 274.239736 18.467324) (xy 274.240222 18.494593) (xy 274.247984 18.548577) (xy 274.263349 18.600907)
			(xy 274.286006 18.650517) (xy 274.315492 18.696398) (xy 274.351207 18.737615) (xy 274.392424 18.77333)
			(xy 274.438305 18.802816) (xy 274.487915 18.825473) (xy 274.540245 18.840838) (xy 274.594229 18.8486)
			(xy 274.648767 18.8486) (xy 274.702751 18.840838) (xy 274.755081 18.825473) (xy 274.804691 18.802816)
			(xy 274.850572 18.77333) (xy 274.891789 18.737615) (xy 274.927504 18.696398) (xy 274.95699 18.650517)
			(xy 274.979647 18.600907) (xy 274.995012 18.548577) (xy 275.002774 18.494593) (xy 275.00326 18.467324)
			(xy 275.00326 17.603724) (xy 275.002774 17.576455) (xy 274.995012 17.522471) (xy 274.979647 17.470141)
			(xy 274.95699 17.420531) (xy 274.927504 17.37465) (xy 274.891789 17.333433) (xy 274.850572 17.297718)
			(xy 274.804691 17.268232) (xy 274.755081 17.245575) (xy 274.702751 17.23021) (xy 274.648767 17.222448)
			(xy 274.594229 17.222448) (xy 274.540245 17.23021) (xy 274.487915 17.245575) (xy 274.438305 17.268232)
			(xy 274.392424 17.297718) (xy 274.351207 17.333433) (xy 274.315492 17.37465) (xy 274.286006 17.420531)
			(xy 274.263349 17.470141) (xy 274.247984 17.522471) (xy 274.240222 17.576455) (xy 274.239736 17.603724)
			(xy 270.62931 17.603724) (xy 270.683867 17.576558) (xy 270.756773 17.531417) (xy 270.825202 17.479741)
			(xy 270.888572 17.421972) (xy 270.946341 17.358602) (xy 270.998017 17.290173) (xy 271.043158 17.217267)
			(xy 271.08138 17.140507) (xy 271.112356 17.060548) (xy 271.135823 16.978072) (xy 271.151579 16.893782)
			(xy 271.159491 16.808399) (xy 271.159986 16.765524) (xy 271.159491 16.722649) (xy 275.654757 16.722649)
			(xy 275.654757 16.808399) (xy 275.662669 16.893782) (xy 275.678425 16.978072) (xy 275.701892 17.060548)
			(xy 275.732868 17.140507) (xy 275.77109 17.217267) (xy 275.816231 17.290173) (xy 275.867907 17.358602)
			(xy 275.925676 17.421972) (xy 275.989046 17.479741) (xy 276.057475 17.531417) (xy 276.130381 17.576558)
			(xy 276.207141 17.61478) (xy 276.2871 17.645756) (xy 276.369576 17.669223) (xy 276.453866 17.684979)
			(xy 276.539249 17.692891) (xy 276.624999 17.692891) (xy 276.710382 17.684979) (xy 276.794672 17.669223)
			(xy 276.877148 17.645756) (xy 276.957107 17.61478) (xy 277.033867 17.576558) (xy 277.106773 17.531417)
			(xy 277.175202 17.479741) (xy 277.238572 17.421972) (xy 277.296341 17.358602) (xy 277.348017 17.290173)
			(xy 277.393158 17.217267) (xy 277.43138 17.140507) (xy 277.462356 17.060548) (xy 277.485823 16.978072)
			(xy 277.501579 16.893782) (xy 277.509491 16.808399) (xy 277.509986 16.765524) (xy 277.509491 16.722649)
			(xy 277.508832 16.715537) (xy 308.364877 16.715537) (xy 308.364877 16.801287) (xy 308.372789 16.88667)
			(xy 308.388545 16.97096) (xy 308.412012 17.053436) (xy 308.442988 17.133395) (xy 308.48121 17.210155)
			(xy 308.526351 17.283061) (xy 308.578027 17.35149) (xy 308.635796 17.41486) (xy 308.699166 17.472629)
			(xy 308.767595 17.524305) (xy 308.840501 17.569446) (xy 308.917261 17.607668) (xy 308.99722 17.638644)
			(xy 309.079696 17.662111) (xy 309.163986 17.677867) (xy 309.249369 17.685779) (xy 309.335119 17.685779)
			(xy 309.420502 17.677867) (xy 309.504792 17.662111) (xy 309.587268 17.638644) (xy 309.667227 17.607668)
			(xy 309.68943 17.596612) (xy 310.871108 17.596612) (xy 310.871108 18.460212) (xy 310.871594 18.487481)
			(xy 310.879356 18.541465) (xy 310.894721 18.593795) (xy 310.917378 18.643405) (xy 310.946864 18.689286)
			(xy 310.982579 18.730503) (xy 311.023796 18.766218) (xy 311.069677 18.795704) (xy 311.119287 18.818361)
			(xy 311.171617 18.833726) (xy 311.225601 18.841488) (xy 311.280139 18.841488) (xy 311.334123 18.833726)
			(xy 311.386453 18.818361) (xy 311.436063 18.795704) (xy 311.481944 18.766218) (xy 311.523161 18.730503)
			(xy 311.558876 18.689286) (xy 311.588362 18.643405) (xy 311.611019 18.593795) (xy 311.626384 18.541465)
			(xy 311.634146 18.487481) (xy 311.634632 18.460212) (xy 311.634632 17.596612) (xy 311.634146 17.569343)
			(xy 311.626384 17.515359) (xy 311.611019 17.463029) (xy 311.588362 17.413419) (xy 311.558876 17.367538)
			(xy 311.523161 17.326321) (xy 311.481944 17.290606) (xy 311.436063 17.26112) (xy 311.386453 17.238463)
			(xy 311.334123 17.223098) (xy 311.280139 17.215336) (xy 311.225601 17.215336) (xy 311.171617 17.223098)
			(xy 311.119287 17.238463) (xy 311.069677 17.26112) (xy 311.023796 17.290606) (xy 310.982579 17.326321)
			(xy 310.946864 17.367538) (xy 310.917378 17.413419) (xy 310.894721 17.463029) (xy 310.879356 17.515359)
			(xy 310.871594 17.569343) (xy 310.871108 17.596612) (xy 309.68943 17.596612) (xy 309.743987 17.569446)
			(xy 309.816893 17.524305) (xy 309.885322 17.472629) (xy 309.948692 17.41486) (xy 310.006461 17.35149)
			(xy 310.058137 17.283061) (xy 310.103278 17.210155) (xy 310.1415 17.133395) (xy 310.172476 17.053436)
			(xy 310.195943 16.97096) (xy 310.211699 16.88667) (xy 310.219611 16.801287) (xy 310.220106 16.758412)
			(xy 310.219611 16.715537) (xy 314.714877 16.715537) (xy 314.714877 16.801287) (xy 314.722789 16.88667)
			(xy 314.738545 16.97096) (xy 314.762012 17.053436) (xy 314.792988 17.133395) (xy 314.83121 17.210155)
			(xy 314.876351 17.283061) (xy 314.928027 17.35149) (xy 314.985796 17.41486) (xy 315.049166 17.472629)
			(xy 315.117595 17.524305) (xy 315.190501 17.569446) (xy 315.267261 17.607668) (xy 315.34722 17.638644)
			(xy 315.429696 17.662111) (xy 315.513986 17.677867) (xy 315.599369 17.685779) (xy 315.685119 17.685779)
			(xy 315.770502 17.677867) (xy 315.854792 17.662111) (xy 315.937268 17.638644) (xy 316.017227 17.607668)
			(xy 316.093987 17.569446) (xy 316.166893 17.524305) (xy 316.235322 17.472629) (xy 316.298692 17.41486)
			(xy 316.356461 17.35149) (xy 316.408137 17.283061) (xy 316.453278 17.210155) (xy 316.4915 17.133395)
			(xy 316.522476 17.053436) (xy 316.545943 16.97096) (xy 316.561699 16.88667) (xy 316.569611 16.801287)
			(xy 316.570106 16.758412) (xy 316.569693 16.722649) (xy 334.455757 16.722649) (xy 334.455757 16.808399)
			(xy 334.463669 16.893782) (xy 334.479425 16.978072) (xy 334.502892 17.060548) (xy 334.533868 17.140507)
			(xy 334.57209 17.217267) (xy 334.617231 17.290173) (xy 334.668907 17.358602) (xy 334.726676 17.421972)
			(xy 334.790046 17.479741) (xy 334.858475 17.531417) (xy 334.931381 17.576558) (xy 335.008141 17.61478)
			(xy 335.0881 17.645756) (xy 335.170576 17.669223) (xy 335.254866 17.684979) (xy 335.340249 17.692891)
			(xy 335.425999 17.692891) (xy 335.511382 17.684979) (xy 335.595672 17.669223) (xy 335.678148 17.645756)
			(xy 335.758107 17.61478) (xy 335.78031 17.603724) (xy 339.390736 17.603724) (xy 339.390736 18.467324)
			(xy 339.391222 18.494593) (xy 339.398984 18.548577) (xy 339.414349 18.600907) (xy 339.437006 18.650517)
			(xy 339.466492 18.696398) (xy 339.502207 18.737615) (xy 339.543424 18.77333) (xy 339.589305 18.802816)
			(xy 339.638915 18.825473) (xy 339.691245 18.840838) (xy 339.745229 18.8486) (xy 339.799767 18.8486)
			(xy 339.853751 18.840838) (xy 339.906081 18.825473) (xy 339.955691 18.802816) (xy 340.001572 18.77333)
			(xy 340.042789 18.737615) (xy 340.078504 18.696398) (xy 340.10799 18.650517) (xy 340.130647 18.600907)
			(xy 340.146012 18.548577) (xy 340.153774 18.494593) (xy 340.15426 18.467324) (xy 340.15426 17.603724)
			(xy 340.153774 17.576455) (xy 340.146012 17.522471) (xy 340.130647 17.470141) (xy 340.10799 17.420531)
			(xy 340.078504 17.37465) (xy 340.042789 17.333433) (xy 340.001572 17.297718) (xy 339.955691 17.268232)
			(xy 339.906081 17.245575) (xy 339.853751 17.23021) (xy 339.799767 17.222448) (xy 339.745229 17.222448)
			(xy 339.691245 17.23021) (xy 339.638915 17.245575) (xy 339.589305 17.268232) (xy 339.543424 17.297718)
			(xy 339.502207 17.333433) (xy 339.466492 17.37465) (xy 339.437006 17.420531) (xy 339.414349 17.470141)
			(xy 339.398984 17.522471) (xy 339.391222 17.576455) (xy 339.390736 17.603724) (xy 335.78031 17.603724)
			(xy 335.834867 17.576558) (xy 335.907773 17.531417) (xy 335.976202 17.479741) (xy 336.039572 17.421972)
			(xy 336.097341 17.358602) (xy 336.149017 17.290173) (xy 336.194158 17.217267) (xy 336.23238 17.140507)
			(xy 336.263356 17.060548) (xy 336.286823 16.978072) (xy 336.302579 16.893782) (xy 336.310491 16.808399)
			(xy 336.310986 16.765524) (xy 336.310491 16.722649) (xy 340.805757 16.722649) (xy 340.805757 16.808399)
			(xy 340.813669 16.893782) (xy 340.829425 16.978072) (xy 340.852892 17.060548) (xy 340.883868 17.140507)
			(xy 340.92209 17.217267) (xy 340.967231 17.290173) (xy 341.018907 17.358602) (xy 341.076676 17.421972)
			(xy 341.140046 17.479741) (xy 341.208475 17.531417) (xy 341.281381 17.576558) (xy 341.358141 17.61478)
			(xy 341.4381 17.645756) (xy 341.520576 17.669223) (xy 341.604866 17.684979) (xy 341.690249 17.692891)
			(xy 341.775999 17.692891) (xy 341.861382 17.684979) (xy 341.945672 17.669223) (xy 342.028148 17.645756)
			(xy 342.108107 17.61478) (xy 342.184867 17.576558) (xy 342.257773 17.531417) (xy 342.326202 17.479741)
			(xy 342.389572 17.421972) (xy 342.447341 17.358602) (xy 342.499017 17.290173) (xy 342.544158 17.217267)
			(xy 342.58238 17.140507) (xy 342.613356 17.060548) (xy 342.636823 16.978072) (xy 342.652579 16.893782)
			(xy 342.660491 16.808399) (xy 342.660986 16.765524) (xy 342.660491 16.722649) (xy 342.659832 16.715537)
			(xy 373.515877 16.715537) (xy 373.515877 16.801287) (xy 373.523789 16.88667) (xy 373.539545 16.97096)
			(xy 373.563012 17.053436) (xy 373.593988 17.133395) (xy 373.63221 17.210155) (xy 373.677351 17.283061)
			(xy 373.729027 17.35149) (xy 373.786796 17.41486) (xy 373.850166 17.472629) (xy 373.918595 17.524305)
			(xy 373.991501 17.569446) (xy 374.068261 17.607668) (xy 374.14822 17.638644) (xy 374.230696 17.662111)
			(xy 374.314986 17.677867) (xy 374.400369 17.685779) (xy 374.486119 17.685779) (xy 374.571502 17.677867)
			(xy 374.655792 17.662111) (xy 374.738268 17.638644) (xy 374.818227 17.607668) (xy 374.84043 17.596612)
			(xy 376.022108 17.596612) (xy 376.022108 18.460212) (xy 376.022594 18.487481) (xy 376.030356 18.541465)
			(xy 376.045721 18.593795) (xy 376.068378 18.643405) (xy 376.097864 18.689286) (xy 376.133579 18.730503)
			(xy 376.174796 18.766218) (xy 376.220677 18.795704) (xy 376.270287 18.818361) (xy 376.322617 18.833726)
			(xy 376.376601 18.841488) (xy 376.431139 18.841488) (xy 376.485123 18.833726) (xy 376.537453 18.818361)
			(xy 376.587063 18.795704) (xy 376.632944 18.766218) (xy 376.674161 18.730503) (xy 376.709876 18.689286)
			(xy 376.739362 18.643405) (xy 376.762019 18.593795) (xy 376.777384 18.541465) (xy 376.785146 18.487481)
			(xy 376.785632 18.460212) (xy 376.785632 17.596612) (xy 376.785146 17.569343) (xy 376.777384 17.515359)
			(xy 376.762019 17.463029) (xy 376.739362 17.413419) (xy 376.709876 17.367538) (xy 376.674161 17.326321)
			(xy 376.632944 17.290606) (xy 376.587063 17.26112) (xy 376.537453 17.238463) (xy 376.485123 17.223098)
			(xy 376.431139 17.215336) (xy 376.376601 17.215336) (xy 376.322617 17.223098) (xy 376.270287 17.238463)
			(xy 376.220677 17.26112) (xy 376.174796 17.290606) (xy 376.133579 17.326321) (xy 376.097864 17.367538)
			(xy 376.068378 17.413419) (xy 376.045721 17.463029) (xy 376.030356 17.515359) (xy 376.022594 17.569343)
			(xy 376.022108 17.596612) (xy 374.84043 17.596612) (xy 374.894987 17.569446) (xy 374.967893 17.524305)
			(xy 375.036322 17.472629) (xy 375.099692 17.41486) (xy 375.157461 17.35149) (xy 375.209137 17.283061)
			(xy 375.254278 17.210155) (xy 375.2925 17.133395) (xy 375.323476 17.053436) (xy 375.346943 16.97096)
			(xy 375.362699 16.88667) (xy 375.370611 16.801287) (xy 375.371106 16.758412) (xy 375.370611 16.715537)
			(xy 379.865877 16.715537) (xy 379.865877 16.801287) (xy 379.873789 16.88667) (xy 379.889545 16.97096)
			(xy 379.913012 17.053436) (xy 379.943988 17.133395) (xy 379.98221 17.210155) (xy 380.027351 17.283061)
			(xy 380.079027 17.35149) (xy 380.136796 17.41486) (xy 380.200166 17.472629) (xy 380.268595 17.524305)
			(xy 380.341501 17.569446) (xy 380.418261 17.607668) (xy 380.49822 17.638644) (xy 380.580696 17.662111)
			(xy 380.664986 17.677867) (xy 380.750369 17.685779) (xy 380.836119 17.685779) (xy 380.921502 17.677867)
			(xy 381.005792 17.662111) (xy 381.088268 17.638644) (xy 381.168227 17.607668) (xy 381.244987 17.569446)
			(xy 381.317893 17.524305) (xy 381.386322 17.472629) (xy 381.449692 17.41486) (xy 381.507461 17.35149)
			(xy 381.559137 17.283061) (xy 381.604278 17.210155) (xy 381.6425 17.133395) (xy 381.673476 17.053436)
			(xy 381.696943 16.97096) (xy 381.712699 16.88667) (xy 381.720611 16.801287) (xy 381.721106 16.758412)
			(xy 381.720693 16.722649) (xy 399.098757 16.722649) (xy 399.098757 16.808399) (xy 399.106669 16.893782)
			(xy 399.122425 16.978072) (xy 399.145892 17.060548) (xy 399.176868 17.140507) (xy 399.21509 17.217267)
			(xy 399.260231 17.290173) (xy 399.311907 17.358602) (xy 399.369676 17.421972) (xy 399.433046 17.479741)
			(xy 399.501475 17.531417) (xy 399.574381 17.576558) (xy 399.651141 17.61478) (xy 399.7311 17.645756)
			(xy 399.813576 17.669223) (xy 399.897866 17.684979) (xy 399.983249 17.692891) (xy 400.068999 17.692891)
			(xy 400.154382 17.684979) (xy 400.238672 17.669223) (xy 400.321148 17.645756) (xy 400.401107 17.61478)
			(xy 400.42331 17.603724) (xy 404.033736 17.603724) (xy 404.033736 18.467324) (xy 404.034222 18.494593)
			(xy 404.041984 18.548577) (xy 404.057349 18.600907) (xy 404.080006 18.650517) (xy 404.109492 18.696398)
			(xy 404.145207 18.737615) (xy 404.186424 18.77333) (xy 404.232305 18.802816) (xy 404.281915 18.825473)
			(xy 404.334245 18.840838) (xy 404.388229 18.8486) (xy 404.442767 18.8486) (xy 404.496751 18.840838)
			(xy 404.549081 18.825473) (xy 404.598691 18.802816) (xy 404.644572 18.77333) (xy 404.685789 18.737615)
			(xy 404.721504 18.696398) (xy 404.75099 18.650517) (xy 404.773647 18.600907) (xy 404.789012 18.548577)
			(xy 404.796774 18.494593) (xy 404.79726 18.467324) (xy 404.79726 17.603724) (xy 404.796774 17.576455)
			(xy 404.789012 17.522471) (xy 404.773647 17.470141) (xy 404.75099 17.420531) (xy 404.721504 17.37465)
			(xy 404.685789 17.333433) (xy 404.644572 17.297718) (xy 404.598691 17.268232) (xy 404.549081 17.245575)
			(xy 404.496751 17.23021) (xy 404.442767 17.222448) (xy 404.388229 17.222448) (xy 404.334245 17.23021)
			(xy 404.281915 17.245575) (xy 404.232305 17.268232) (xy 404.186424 17.297718) (xy 404.145207 17.333433)
			(xy 404.109492 17.37465) (xy 404.080006 17.420531) (xy 404.057349 17.470141) (xy 404.041984 17.522471)
			(xy 404.034222 17.576455) (xy 404.033736 17.603724) (xy 400.42331 17.603724) (xy 400.477867 17.576558)
			(xy 400.550773 17.531417) (xy 400.619202 17.479741) (xy 400.682572 17.421972) (xy 400.740341 17.358602)
			(xy 400.792017 17.290173) (xy 400.837158 17.217267) (xy 400.87538 17.140507) (xy 400.906356 17.060548)
			(xy 400.929823 16.978072) (xy 400.945579 16.893782) (xy 400.953491 16.808399) (xy 400.953986 16.765524)
			(xy 400.953491 16.722649) (xy 405.448757 16.722649) (xy 405.448757 16.808399) (xy 405.456669 16.893782)
			(xy 405.472425 16.978072) (xy 405.495892 17.060548) (xy 405.526868 17.140507) (xy 405.56509 17.217267)
			(xy 405.610231 17.290173) (xy 405.661907 17.358602) (xy 405.719676 17.421972) (xy 405.783046 17.479741)
			(xy 405.851475 17.531417) (xy 405.924381 17.576558) (xy 406.001141 17.61478) (xy 406.0811 17.645756)
			(xy 406.163576 17.669223) (xy 406.247866 17.684979) (xy 406.333249 17.692891) (xy 406.418999 17.692891)
			(xy 406.504382 17.684979) (xy 406.588672 17.669223) (xy 406.671148 17.645756) (xy 406.751107 17.61478)
			(xy 406.827867 17.576558) (xy 406.900773 17.531417) (xy 406.969202 17.479741) (xy 407.032572 17.421972)
			(xy 407.090341 17.358602) (xy 407.142017 17.290173) (xy 407.187158 17.217267) (xy 407.22538 17.140507)
			(xy 407.256356 17.060548) (xy 407.279823 16.978072) (xy 407.295579 16.893782) (xy 407.303491 16.808399)
			(xy 407.303986 16.765524) (xy 407.303491 16.722649) (xy 407.302832 16.715537) (xy 438.158877 16.715537)
			(xy 438.158877 16.801287) (xy 438.166789 16.88667) (xy 438.182545 16.97096) (xy 438.206012 17.053436)
			(xy 438.236988 17.133395) (xy 438.27521 17.210155) (xy 438.320351 17.283061) (xy 438.372027 17.35149)
			(xy 438.429796 17.41486) (xy 438.493166 17.472629) (xy 438.561595 17.524305) (xy 438.634501 17.569446)
			(xy 438.711261 17.607668) (xy 438.79122 17.638644) (xy 438.873696 17.662111) (xy 438.957986 17.677867)
			(xy 439.043369 17.685779) (xy 439.129119 17.685779) (xy 439.214502 17.677867) (xy 439.298792 17.662111)
			(xy 439.381268 17.638644) (xy 439.461227 17.607668) (xy 439.48343 17.596612) (xy 440.665108 17.596612)
			(xy 440.665108 18.460212) (xy 440.665594 18.487481) (xy 440.673356 18.541465) (xy 440.688721 18.593795)
			(xy 440.711378 18.643405) (xy 440.740864 18.689286) (xy 440.776579 18.730503) (xy 440.817796 18.766218)
			(xy 440.863677 18.795704) (xy 440.913287 18.818361) (xy 440.965617 18.833726) (xy 441.019601 18.841488)
			(xy 441.074139 18.841488) (xy 441.128123 18.833726) (xy 441.180453 18.818361) (xy 441.230063 18.795704)
			(xy 441.275944 18.766218) (xy 441.317161 18.730503) (xy 441.352876 18.689286) (xy 441.382362 18.643405)
			(xy 441.405019 18.593795) (xy 441.420384 18.541465) (xy 441.428146 18.487481) (xy 441.428632 18.460212)
			(xy 441.428632 17.596612) (xy 441.428146 17.569343) (xy 441.420384 17.515359) (xy 441.405019 17.463029)
			(xy 441.382362 17.413419) (xy 441.352876 17.367538) (xy 441.317161 17.326321) (xy 441.275944 17.290606)
			(xy 441.230063 17.26112) (xy 441.180453 17.238463) (xy 441.128123 17.223098) (xy 441.074139 17.215336)
			(xy 441.019601 17.215336) (xy 440.965617 17.223098) (xy 440.913287 17.238463) (xy 440.863677 17.26112)
			(xy 440.817796 17.290606) (xy 440.776579 17.326321) (xy 440.740864 17.367538) (xy 440.711378 17.413419)
			(xy 440.688721 17.463029) (xy 440.673356 17.515359) (xy 440.665594 17.569343) (xy 440.665108 17.596612)
			(xy 439.48343 17.596612) (xy 439.537987 17.569446) (xy 439.610893 17.524305) (xy 439.679322 17.472629)
			(xy 439.742692 17.41486) (xy 439.800461 17.35149) (xy 439.852137 17.283061) (xy 439.897278 17.210155)
			(xy 439.9355 17.133395) (xy 439.966476 17.053436) (xy 439.989943 16.97096) (xy 440.005699 16.88667)
			(xy 440.013611 16.801287) (xy 440.014106 16.758412) (xy 440.013611 16.715537) (xy 444.508877 16.715537)
			(xy 444.508877 16.801287) (xy 444.516789 16.88667) (xy 444.532545 16.97096) (xy 444.556012 17.053436)
			(xy 444.586988 17.133395) (xy 444.62521 17.210155) (xy 444.670351 17.283061) (xy 444.722027 17.35149)
			(xy 444.779796 17.41486) (xy 444.843166 17.472629) (xy 444.911595 17.524305) (xy 444.984501 17.569446)
			(xy 445.061261 17.607668) (xy 445.14122 17.638644) (xy 445.223696 17.662111) (xy 445.307986 17.677867)
			(xy 445.393369 17.685779) (xy 445.479119 17.685779) (xy 445.564502 17.677867) (xy 445.648792 17.662111)
			(xy 445.731268 17.638644) (xy 445.811227 17.607668) (xy 445.887987 17.569446) (xy 445.960893 17.524305)
			(xy 446.029322 17.472629) (xy 446.092692 17.41486) (xy 446.150461 17.35149) (xy 446.202137 17.283061)
			(xy 446.247278 17.210155) (xy 446.2855 17.133395) (xy 446.316476 17.053436) (xy 446.339943 16.97096)
			(xy 446.355699 16.88667) (xy 446.363611 16.801287) (xy 446.364106 16.758412) (xy 446.363611 16.715537)
			(xy 446.355699 16.630154) (xy 446.339943 16.545864) (xy 446.316476 16.463388) (xy 446.2855 16.383429)
			(xy 446.247278 16.306669) (xy 446.202137 16.233763) (xy 446.150461 16.165334) (xy 446.092692 16.101964)
			(xy 446.029322 16.044195) (xy 445.960893 15.992519) (xy 445.887987 15.947378) (xy 445.811227 15.909156)
			(xy 445.731268 15.87818) (xy 445.648792 15.854713) (xy 445.564502 15.838957) (xy 445.479119 15.831045)
			(xy 445.393369 15.831045) (xy 445.307986 15.838957) (xy 445.223696 15.854713) (xy 445.14122 15.87818)
			(xy 445.061261 15.909156) (xy 444.984501 15.947378) (xy 444.911595 15.992519) (xy 444.843166 16.044195)
			(xy 444.779796 16.101964) (xy 444.722027 16.165334) (xy 444.670351 16.233763) (xy 444.62521 16.306669)
			(xy 444.586988 16.383429) (xy 444.556012 16.463388) (xy 444.532545 16.545864) (xy 444.516789 16.630154)
			(xy 444.508877 16.715537) (xy 440.013611 16.715537) (xy 440.005699 16.630154) (xy 439.989943 16.545864)
			(xy 439.966476 16.463388) (xy 439.9355 16.383429) (xy 439.897278 16.306669) (xy 439.852137 16.233763)
			(xy 439.800461 16.165334) (xy 439.742692 16.101964) (xy 439.679322 16.044195) (xy 439.610893 15.992519)
			(xy 439.537987 15.947378) (xy 439.461227 15.909156) (xy 439.381268 15.87818) (xy 439.298792 15.854713)
			(xy 439.214502 15.838957) (xy 439.129119 15.831045) (xy 439.043369 15.831045) (xy 438.957986 15.838957)
			(xy 438.873696 15.854713) (xy 438.79122 15.87818) (xy 438.711261 15.909156) (xy 438.634501 15.947378)
			(xy 438.561595 15.992519) (xy 438.493166 16.044195) (xy 438.429796 16.101964) (xy 438.372027 16.165334)
			(xy 438.320351 16.233763) (xy 438.27521 16.306669) (xy 438.236988 16.383429) (xy 438.206012 16.463388)
			(xy 438.182545 16.545864) (xy 438.166789 16.630154) (xy 438.158877 16.715537) (xy 407.302832 16.715537)
			(xy 407.295579 16.637266) (xy 407.279823 16.552976) (xy 407.256356 16.4705) (xy 407.22538 16.390541)
			(xy 407.187158 16.313781) (xy 407.142017 16.240875) (xy 407.090341 16.172446) (xy 407.032572 16.109076)
			(xy 406.969202 16.051307) (xy 406.900773 15.999631) (xy 406.827867 15.95449) (xy 406.751107 15.916268)
			(xy 406.671148 15.885292) (xy 406.588672 15.861825) (xy 406.504382 15.846069) (xy 406.418999 15.838157)
			(xy 406.333249 15.838157) (xy 406.247866 15.846069) (xy 406.163576 15.861825) (xy 406.0811 15.885292)
			(xy 406.001141 15.916268) (xy 405.924381 15.95449) (xy 405.851475 15.999631) (xy 405.783046 16.051307)
			(xy 405.719676 16.109076) (xy 405.661907 16.172446) (xy 405.610231 16.240875) (xy 405.56509 16.313781)
			(xy 405.526868 16.390541) (xy 405.495892 16.4705) (xy 405.472425 16.552976) (xy 405.456669 16.637266)
			(xy 405.448757 16.722649) (xy 400.953491 16.722649) (xy 400.945579 16.637266) (xy 400.929823 16.552976)
			(xy 400.906356 16.4705) (xy 400.87538 16.390541) (xy 400.837158 16.313781) (xy 400.792017 16.240875)
			(xy 400.740341 16.172446) (xy 400.682572 16.109076) (xy 400.619202 16.051307) (xy 400.550773 15.999631)
			(xy 400.477867 15.95449) (xy 400.401107 15.916268) (xy 400.321148 15.885292) (xy 400.238672 15.861825)
			(xy 400.154382 15.846069) (xy 400.068999 15.838157) (xy 399.983249 15.838157) (xy 399.897866 15.846069)
			(xy 399.813576 15.861825) (xy 399.7311 15.885292) (xy 399.651141 15.916268) (xy 399.574381 15.95449)
			(xy 399.501475 15.999631) (xy 399.433046 16.051307) (xy 399.369676 16.109076) (xy 399.311907 16.172446)
			(xy 399.260231 16.240875) (xy 399.21509 16.313781) (xy 399.176868 16.390541) (xy 399.145892 16.4705)
			(xy 399.122425 16.552976) (xy 399.106669 16.637266) (xy 399.098757 16.722649) (xy 381.720693 16.722649)
			(xy 381.720611 16.715537) (xy 381.712699 16.630154) (xy 381.696943 16.545864) (xy 381.673476 16.463388)
			(xy 381.6425 16.383429) (xy 381.604278 16.306669) (xy 381.559137 16.233763) (xy 381.507461 16.165334)
			(xy 381.449692 16.101964) (xy 381.386322 16.044195) (xy 381.317893 15.992519) (xy 381.244987 15.947378)
			(xy 381.168227 15.909156) (xy 381.088268 15.87818) (xy 381.005792 15.854713) (xy 380.921502 15.838957)
			(xy 380.836119 15.831045) (xy 380.750369 15.831045) (xy 380.664986 15.838957) (xy 380.580696 15.854713)
			(xy 380.49822 15.87818) (xy 380.418261 15.909156) (xy 380.341501 15.947378) (xy 380.268595 15.992519)
			(xy 380.200166 16.044195) (xy 380.136796 16.101964) (xy 380.079027 16.165334) (xy 380.027351 16.233763)
			(xy 379.98221 16.306669) (xy 379.943988 16.383429) (xy 379.913012 16.463388) (xy 379.889545 16.545864)
			(xy 379.873789 16.630154) (xy 379.865877 16.715537) (xy 375.370611 16.715537) (xy 375.362699 16.630154)
			(xy 375.346943 16.545864) (xy 375.323476 16.463388) (xy 375.2925 16.383429) (xy 375.254278 16.306669)
			(xy 375.209137 16.233763) (xy 375.157461 16.165334) (xy 375.099692 16.101964) (xy 375.036322 16.044195)
			(xy 374.967893 15.992519) (xy 374.894987 15.947378) (xy 374.818227 15.909156) (xy 374.738268 15.87818)
			(xy 374.655792 15.854713) (xy 374.571502 15.838957) (xy 374.486119 15.831045) (xy 374.400369 15.831045)
			(xy 374.314986 15.838957) (xy 374.230696 15.854713) (xy 374.14822 15.87818) (xy 374.068261 15.909156)
			(xy 373.991501 15.947378) (xy 373.918595 15.992519) (xy 373.850166 16.044195) (xy 373.786796 16.101964)
			(xy 373.729027 16.165334) (xy 373.677351 16.233763) (xy 373.63221 16.306669) (xy 373.593988 16.383429)
			(xy 373.563012 16.463388) (xy 373.539545 16.545864) (xy 373.523789 16.630154) (xy 373.515877 16.715537)
			(xy 342.659832 16.715537) (xy 342.652579 16.637266) (xy 342.636823 16.552976) (xy 342.613356 16.4705)
			(xy 342.58238 16.390541) (xy 342.544158 16.313781) (xy 342.499017 16.240875) (xy 342.447341 16.172446)
			(xy 342.389572 16.109076) (xy 342.326202 16.051307) (xy 342.257773 15.999631) (xy 342.184867 15.95449)
			(xy 342.108107 15.916268) (xy 342.028148 15.885292) (xy 341.945672 15.861825) (xy 341.861382 15.846069)
			(xy 341.775999 15.838157) (xy 341.690249 15.838157) (xy 341.604866 15.846069) (xy 341.520576 15.861825)
			(xy 341.4381 15.885292) (xy 341.358141 15.916268) (xy 341.281381 15.95449) (xy 341.208475 15.999631)
			(xy 341.140046 16.051307) (xy 341.076676 16.109076) (xy 341.018907 16.172446) (xy 340.967231 16.240875)
			(xy 340.92209 16.313781) (xy 340.883868 16.390541) (xy 340.852892 16.4705) (xy 340.829425 16.552976)
			(xy 340.813669 16.637266) (xy 340.805757 16.722649) (xy 336.310491 16.722649) (xy 336.302579 16.637266)
			(xy 336.286823 16.552976) (xy 336.263356 16.4705) (xy 336.23238 16.390541) (xy 336.194158 16.313781)
			(xy 336.149017 16.240875) (xy 336.097341 16.172446) (xy 336.039572 16.109076) (xy 335.976202 16.051307)
			(xy 335.907773 15.999631) (xy 335.834867 15.95449) (xy 335.758107 15.916268) (xy 335.678148 15.885292)
			(xy 335.595672 15.861825) (xy 335.511382 15.846069) (xy 335.425999 15.838157) (xy 335.340249 15.838157)
			(xy 335.254866 15.846069) (xy 335.170576 15.861825) (xy 335.0881 15.885292) (xy 335.008141 15.916268)
			(xy 334.931381 15.95449) (xy 334.858475 15.999631) (xy 334.790046 16.051307) (xy 334.726676 16.109076)
			(xy 334.668907 16.172446) (xy 334.617231 16.240875) (xy 334.57209 16.313781) (xy 334.533868 16.390541)
			(xy 334.502892 16.4705) (xy 334.479425 16.552976) (xy 334.463669 16.637266) (xy 334.455757 16.722649)
			(xy 316.569693 16.722649) (xy 316.569611 16.715537) (xy 316.561699 16.630154) (xy 316.545943 16.545864)
			(xy 316.522476 16.463388) (xy 316.4915 16.383429) (xy 316.453278 16.306669) (xy 316.408137 16.233763)
			(xy 316.356461 16.165334) (xy 316.298692 16.101964) (xy 316.235322 16.044195) (xy 316.166893 15.992519)
			(xy 316.093987 15.947378) (xy 316.017227 15.909156) (xy 315.937268 15.87818) (xy 315.854792 15.854713)
			(xy 315.770502 15.838957) (xy 315.685119 15.831045) (xy 315.599369 15.831045) (xy 315.513986 15.838957)
			(xy 315.429696 15.854713) (xy 315.34722 15.87818) (xy 315.267261 15.909156) (xy 315.190501 15.947378)
			(xy 315.117595 15.992519) (xy 315.049166 16.044195) (xy 314.985796 16.101964) (xy 314.928027 16.165334)
			(xy 314.876351 16.233763) (xy 314.83121 16.306669) (xy 314.792988 16.383429) (xy 314.762012 16.463388)
			(xy 314.738545 16.545864) (xy 314.722789 16.630154) (xy 314.714877 16.715537) (xy 310.219611 16.715537)
			(xy 310.211699 16.630154) (xy 310.195943 16.545864) (xy 310.172476 16.463388) (xy 310.1415 16.383429)
			(xy 310.103278 16.306669) (xy 310.058137 16.233763) (xy 310.006461 16.165334) (xy 309.948692 16.101964)
			(xy 309.885322 16.044195) (xy 309.816893 15.992519) (xy 309.743987 15.947378) (xy 309.667227 15.909156)
			(xy 309.587268 15.87818) (xy 309.504792 15.854713) (xy 309.420502 15.838957) (xy 309.335119 15.831045)
			(xy 309.249369 15.831045) (xy 309.163986 15.838957) (xy 309.079696 15.854713) (xy 308.99722 15.87818)
			(xy 308.917261 15.909156) (xy 308.840501 15.947378) (xy 308.767595 15.992519) (xy 308.699166 16.044195)
			(xy 308.635796 16.101964) (xy 308.578027 16.165334) (xy 308.526351 16.233763) (xy 308.48121 16.306669)
			(xy 308.442988 16.383429) (xy 308.412012 16.463388) (xy 308.388545 16.545864) (xy 308.372789 16.630154)
			(xy 308.364877 16.715537) (xy 277.508832 16.715537) (xy 277.501579 16.637266) (xy 277.485823 16.552976)
			(xy 277.462356 16.4705) (xy 277.43138 16.390541) (xy 277.393158 16.313781) (xy 277.348017 16.240875)
			(xy 277.296341 16.172446) (xy 277.238572 16.109076) (xy 277.175202 16.051307) (xy 277.106773 15.999631)
			(xy 277.033867 15.95449) (xy 276.957107 15.916268) (xy 276.877148 15.885292) (xy 276.794672 15.861825)
			(xy 276.710382 15.846069) (xy 276.624999 15.838157) (xy 276.539249 15.838157) (xy 276.453866 15.846069)
			(xy 276.369576 15.861825) (xy 276.2871 15.885292) (xy 276.207141 15.916268) (xy 276.130381 15.95449)
			(xy 276.057475 15.999631) (xy 275.989046 16.051307) (xy 275.925676 16.109076) (xy 275.867907 16.172446)
			(xy 275.816231 16.240875) (xy 275.77109 16.313781) (xy 275.732868 16.390541) (xy 275.701892 16.4705)
			(xy 275.678425 16.552976) (xy 275.662669 16.637266) (xy 275.654757 16.722649) (xy 271.159491 16.722649)
			(xy 271.151579 16.637266) (xy 271.135823 16.552976) (xy 271.112356 16.4705) (xy 271.08138 16.390541)
			(xy 271.043158 16.313781) (xy 270.998017 16.240875) (xy 270.946341 16.172446) (xy 270.888572 16.109076)
			(xy 270.825202 16.051307) (xy 270.756773 15.999631) (xy 270.683867 15.95449) (xy 270.607107 15.916268)
			(xy 270.527148 15.885292) (xy 270.444672 15.861825) (xy 270.360382 15.846069) (xy 270.274999 15.838157)
			(xy 270.189249 15.838157) (xy 270.103866 15.846069) (xy 270.019576 15.861825) (xy 269.9371 15.885292)
			(xy 269.857141 15.916268) (xy 269.780381 15.95449) (xy 269.707475 15.999631) (xy 269.639046 16.051307)
			(xy 269.575676 16.109076) (xy 269.517907 16.172446) (xy 269.466231 16.240875) (xy 269.42109 16.313781)
			(xy 269.382868 16.390541) (xy 269.351892 16.4705) (xy 269.328425 16.552976) (xy 269.312669 16.637266)
			(xy 269.304757 16.722649) (xy 252.231493 16.722649) (xy 252.231411 16.715537) (xy 252.223499 16.630154)
			(xy 252.207743 16.545864) (xy 252.184276 16.463388) (xy 252.1533 16.383429) (xy 252.115078 16.306669)
			(xy 252.069937 16.233763) (xy 252.018261 16.165334) (xy 251.960492 16.101964) (xy 251.897122 16.044195)
			(xy 251.828693 15.992519) (xy 251.755787 15.947378) (xy 251.679027 15.909156) (xy 251.599068 15.87818)
			(xy 251.516592 15.854713) (xy 251.432302 15.838957) (xy 251.346919 15.831045) (xy 251.261169 15.831045)
			(xy 251.175786 15.838957) (xy 251.091496 15.854713) (xy 251.00902 15.87818) (xy 250.929061 15.909156)
			(xy 250.852301 15.947378) (xy 250.779395 15.992519) (xy 250.710966 16.044195) (xy 250.647596 16.101964)
			(xy 250.589827 16.165334) (xy 250.538151 16.233763) (xy 250.49301 16.306669) (xy 250.454788 16.383429)
			(xy 250.423812 16.463388) (xy 250.400345 16.545864) (xy 250.384589 16.630154) (xy 250.376677 16.715537)
			(xy 245.881411 16.715537) (xy 245.873499 16.630154) (xy 245.857743 16.545864) (xy 245.834276 16.463388)
			(xy 245.8033 16.383429) (xy 245.765078 16.306669) (xy 245.719937 16.233763) (xy 245.668261 16.165334)
			(xy 245.610492 16.101964) (xy 245.547122 16.044195) (xy 245.478693 15.992519) (xy 245.405787 15.947378)
			(xy 245.329027 15.909156) (xy 245.249068 15.87818) (xy 245.166592 15.854713) (xy 245.082302 15.838957)
			(xy 244.996919 15.831045) (xy 244.911169 15.831045) (xy 244.825786 15.838957) (xy 244.741496 15.854713)
			(xy 244.65902 15.87818) (xy 244.579061 15.909156) (xy 244.502301 15.947378) (xy 244.429395 15.992519)
			(xy 244.360966 16.044195) (xy 244.297596 16.101964) (xy 244.239827 16.165334) (xy 244.188151 16.233763)
			(xy 244.14301 16.306669) (xy 244.104788 16.383429) (xy 244.073812 16.463388) (xy 244.050345 16.545864)
			(xy 244.034589 16.630154) (xy 244.026677 16.715537) (xy 218.199832 16.715537) (xy 218.192579 16.637266)
			(xy 218.176823 16.552976) (xy 218.153356 16.4705) (xy 218.12238 16.390541) (xy 218.084158 16.313781)
			(xy 218.039017 16.240875) (xy 217.987341 16.172446) (xy 217.929572 16.109076) (xy 217.866202 16.051307)
			(xy 217.797773 15.999631) (xy 217.724867 15.95449) (xy 217.648107 15.916268) (xy 217.568148 15.885292)
			(xy 217.485672 15.861825) (xy 217.401382 15.846069) (xy 217.315999 15.838157) (xy 217.230249 15.838157)
			(xy 217.144866 15.846069) (xy 217.060576 15.861825) (xy 216.9781 15.885292) (xy 216.898141 15.916268)
			(xy 216.821381 15.95449) (xy 216.748475 15.999631) (xy 216.680046 16.051307) (xy 216.616676 16.109076)
			(xy 216.558907 16.172446) (xy 216.507231 16.240875) (xy 216.46209 16.313781) (xy 216.423868 16.390541)
			(xy 216.392892 16.4705) (xy 216.369425 16.552976) (xy 216.353669 16.637266) (xy 216.345757 16.722649)
			(xy 211.850491 16.722649) (xy 211.842579 16.637266) (xy 211.826823 16.552976) (xy 211.803356 16.4705)
			(xy 211.77238 16.390541) (xy 211.734158 16.313781) (xy 211.689017 16.240875) (xy 211.637341 16.172446)
			(xy 211.579572 16.109076) (xy 211.516202 16.051307) (xy 211.447773 15.999631) (xy 211.374867 15.95449)
			(xy 211.298107 15.916268) (xy 211.218148 15.885292) (xy 211.135672 15.861825) (xy 211.051382 15.846069)
			(xy 210.965999 15.838157) (xy 210.880249 15.838157) (xy 210.794866 15.846069) (xy 210.710576 15.861825)
			(xy 210.6281 15.885292) (xy 210.548141 15.916268) (xy 210.471381 15.95449) (xy 210.398475 15.999631)
			(xy 210.330046 16.051307) (xy 210.266676 16.109076) (xy 210.208907 16.172446) (xy 210.157231 16.240875)
			(xy 210.11209 16.313781) (xy 210.073868 16.390541) (xy 210.042892 16.4705) (xy 210.019425 16.552976)
			(xy 210.003669 16.637266) (xy 209.995757 16.722649) (xy 158.621984 16.722649) (xy 158.621984 11.850929)
			(xy 251.524757 11.850929) (xy 251.524757 11.936679) (xy 251.532669 12.022062) (xy 251.548425 12.106352)
			(xy 251.571892 12.188828) (xy 251.602868 12.268787) (xy 251.64109 12.345547) (xy 251.686231 12.418453)
			(xy 251.737907 12.486882) (xy 251.795676 12.550252) (xy 251.859046 12.608021) (xy 251.927475 12.659697)
			(xy 252.000381 12.704838) (xy 252.077141 12.74306) (xy 252.1571 12.774036) (xy 252.239576 12.797503)
			(xy 252.323866 12.813259) (xy 252.409249 12.821171) (xy 252.494999 12.821171) (xy 252.580382 12.813259)
			(xy 252.664672 12.797503) (xy 252.747148 12.774036) (xy 252.827107 12.74306) (xy 252.903867 12.704838)
			(xy 252.976773 12.659697) (xy 253.045202 12.608021) (xy 253.108572 12.550252) (xy 253.166341 12.486882)
			(xy 253.218017 12.418453) (xy 253.263158 12.345547) (xy 253.30138 12.268787) (xy 253.332356 12.188828)
			(xy 253.355823 12.106352) (xy 253.371579 12.022062) (xy 253.379491 11.936679) (xy 253.379986 11.893804)
			(xy 253.379491 11.850929) (xy 257.874757 11.850929) (xy 257.874757 11.936679) (xy 257.882669 12.022062)
			(xy 257.898425 12.106352) (xy 257.921892 12.188828) (xy 257.952868 12.268787) (xy 257.99109 12.345547)
			(xy 258.036231 12.418453) (xy 258.087907 12.486882) (xy 258.145676 12.550252) (xy 258.209046 12.608021)
			(xy 258.277475 12.659697) (xy 258.350381 12.704838) (xy 258.427141 12.74306) (xy 258.5071 12.774036)
			(xy 258.589576 12.797503) (xy 258.673866 12.813259) (xy 258.759249 12.821171) (xy 258.844999 12.821171)
			(xy 258.930382 12.813259) (xy 259.014672 12.797503) (xy 259.097148 12.774036) (xy 259.177107 12.74306)
			(xy 259.253867 12.704838) (xy 259.326773 12.659697) (xy 259.395202 12.608021) (xy 259.458572 12.550252)
			(xy 259.516341 12.486882) (xy 259.568017 12.418453) (xy 259.613158 12.345547) (xy 259.65138 12.268787)
			(xy 259.682356 12.188828) (xy 259.705823 12.106352) (xy 259.721579 12.022062) (xy 259.729491 11.936679)
			(xy 259.729986 11.893804) (xy 259.72979 11.876837) (xy 309.725301 11.876837) (xy 309.725301 11.962587)
			(xy 309.733213 12.04797) (xy 309.748969 12.13226) (xy 309.772436 12.214736) (xy 309.803412 12.294695)
			(xy 309.841634 12.371455) (xy 309.886775 12.444361) (xy 309.938451 12.51279) (xy 309.99622 12.57616)
			(xy 310.05959 12.633929) (xy 310.128019 12.685605) (xy 310.200925 12.730746) (xy 310.277685 12.768968)
			(xy 310.357644 12.799944) (xy 310.44012 12.823411) (xy 310.52441 12.839167) (xy 310.609793 12.847079)
			(xy 310.695543 12.847079) (xy 310.780926 12.839167) (xy 310.865216 12.823411) (xy 310.947692 12.799944)
			(xy 311.027651 12.768968) (xy 311.104411 12.730746) (xy 311.177317 12.685605) (xy 311.245746 12.633929)
			(xy 311.309116 12.57616) (xy 311.366885 12.51279) (xy 311.418561 12.444361) (xy 311.463702 12.371455)
			(xy 311.501924 12.294695) (xy 311.5329 12.214736) (xy 311.556367 12.13226) (xy 311.572123 12.04797)
			(xy 311.580035 11.962587) (xy 311.58053 11.919712) (xy 311.580035 11.876837) (xy 316.075301 11.876837)
			(xy 316.075301 11.962587) (xy 316.083213 12.04797) (xy 316.098969 12.13226) (xy 316.122436 12.214736)
			(xy 316.153412 12.294695) (xy 316.191634 12.371455) (xy 316.236775 12.444361) (xy 316.288451 12.51279)
			(xy 316.34622 12.57616) (xy 316.40959 12.633929) (xy 316.478019 12.685605) (xy 316.550925 12.730746)
			(xy 316.627685 12.768968) (xy 316.707644 12.799944) (xy 316.79012 12.823411) (xy 316.87441 12.839167)
			(xy 316.959793 12.847079) (xy 317.045543 12.847079) (xy 317.130926 12.839167) (xy 317.215216 12.823411)
			(xy 317.297692 12.799944) (xy 317.377651 12.768968) (xy 317.454411 12.730746) (xy 317.527317 12.685605)
			(xy 317.595746 12.633929) (xy 317.659116 12.57616) (xy 317.716885 12.51279) (xy 317.768561 12.444361)
			(xy 317.813702 12.371455) (xy 317.851924 12.294695) (xy 317.8829 12.214736) (xy 317.906367 12.13226)
			(xy 317.922123 12.04797) (xy 317.930035 11.962587) (xy 317.93053 11.919712) (xy 317.930117 11.883949)
			(xy 324.295757 11.883949) (xy 324.295757 11.969699) (xy 324.303669 12.055082) (xy 324.319425 12.139372)
			(xy 324.342892 12.221848) (xy 324.373868 12.301807) (xy 324.41209 12.378567) (xy 324.457231 12.451473)
			(xy 324.508907 12.519902) (xy 324.566676 12.583272) (xy 324.630046 12.641041) (xy 324.698475 12.692717)
			(xy 324.771381 12.737858) (xy 324.848141 12.77608) (xy 324.9281 12.807056) (xy 325.010576 12.830523)
			(xy 325.094866 12.846279) (xy 325.180249 12.854191) (xy 325.265999 12.854191) (xy 325.351382 12.846279)
			(xy 325.435672 12.830523) (xy 325.518148 12.807056) (xy 325.598107 12.77608) (xy 325.674867 12.737858)
			(xy 325.747773 12.692717) (xy 325.816202 12.641041) (xy 325.879572 12.583272) (xy 325.937341 12.519902)
			(xy 325.989017 12.451473) (xy 326.034158 12.378567) (xy 326.07238 12.301807) (xy 326.103356 12.221848)
			(xy 326.126823 12.139372) (xy 326.142579 12.055082) (xy 326.150491 11.969699) (xy 326.150986 11.926824)
			(xy 326.150491 11.883949) (xy 330.645757 11.883949) (xy 330.645757 11.969699) (xy 330.653669 12.055082)
			(xy 330.669425 12.139372) (xy 330.692892 12.221848) (xy 330.723868 12.301807) (xy 330.76209 12.378567)
			(xy 330.807231 12.451473) (xy 330.858907 12.519902) (xy 330.916676 12.583272) (xy 330.980046 12.641041)
			(xy 331.048475 12.692717) (xy 331.121381 12.737858) (xy 331.198141 12.77608) (xy 331.2781 12.807056)
			(xy 331.360576 12.830523) (xy 331.444866 12.846279) (xy 331.530249 12.854191) (xy 331.615999 12.854191)
			(xy 331.701382 12.846279) (xy 331.785672 12.830523) (xy 331.868148 12.807056) (xy 331.948107 12.77608)
			(xy 332.024867 12.737858) (xy 332.097773 12.692717) (xy 332.166202 12.641041) (xy 332.229572 12.583272)
			(xy 332.287341 12.519902) (xy 332.339017 12.451473) (xy 332.384158 12.378567) (xy 332.42238 12.301807)
			(xy 332.453356 12.221848) (xy 332.476823 12.139372) (xy 332.492579 12.055082) (xy 332.500491 11.969699)
			(xy 332.500986 11.926824) (xy 332.50079 11.909857) (xy 382.496301 11.909857) (xy 382.496301 11.995607)
			(xy 382.504213 12.08099) (xy 382.519969 12.16528) (xy 382.543436 12.247756) (xy 382.574412 12.327715)
			(xy 382.612634 12.404475) (xy 382.657775 12.477381) (xy 382.709451 12.54581) (xy 382.76722 12.60918)
			(xy 382.83059 12.666949) (xy 382.899019 12.718625) (xy 382.971925 12.763766) (xy 383.048685 12.801988)
			(xy 383.128644 12.832964) (xy 383.21112 12.856431) (xy 383.29541 12.872187) (xy 383.380793 12.880099)
			(xy 383.466543 12.880099) (xy 383.551926 12.872187) (xy 383.636216 12.856431) (xy 383.718692 12.832964)
			(xy 383.798651 12.801988) (xy 383.875411 12.763766) (xy 383.948317 12.718625) (xy 384.016746 12.666949)
			(xy 384.080116 12.60918) (xy 384.137885 12.54581) (xy 384.189561 12.477381) (xy 384.234702 12.404475)
			(xy 384.272924 12.327715) (xy 384.3039 12.247756) (xy 384.327367 12.16528) (xy 384.343123 12.08099)
			(xy 384.351035 11.995607) (xy 384.35153 11.952732) (xy 384.351035 11.909857) (xy 388.846301 11.909857)
			(xy 388.846301 11.995607) (xy 388.854213 12.08099) (xy 388.869969 12.16528) (xy 388.893436 12.247756)
			(xy 388.924412 12.327715) (xy 388.962634 12.404475) (xy 389.007775 12.477381) (xy 389.059451 12.54581)
			(xy 389.11722 12.60918) (xy 389.18059 12.666949) (xy 389.249019 12.718625) (xy 389.321925 12.763766)
			(xy 389.398685 12.801988) (xy 389.478644 12.832964) (xy 389.56112 12.856431) (xy 389.64541 12.872187)
			(xy 389.730793 12.880099) (xy 389.816543 12.880099) (xy 389.901926 12.872187) (xy 389.986216 12.856431)
			(xy 390.068692 12.832964) (xy 390.148651 12.801988) (xy 390.225411 12.763766) (xy 390.298317 12.718625)
			(xy 390.366746 12.666949) (xy 390.430116 12.60918) (xy 390.487885 12.54581) (xy 390.539561 12.477381)
			(xy 390.584702 12.404475) (xy 390.622924 12.327715) (xy 390.6539 12.247756) (xy 390.677367 12.16528)
			(xy 390.693123 12.08099) (xy 390.701035 11.995607) (xy 390.70153 11.952732) (xy 390.701117 11.916969)
			(xy 396.558757 11.916969) (xy 396.558757 12.002719) (xy 396.566669 12.088102) (xy 396.582425 12.172392)
			(xy 396.605892 12.254868) (xy 396.636868 12.334827) (xy 396.67509 12.411587) (xy 396.720231 12.484493)
			(xy 396.771907 12.552922) (xy 396.829676 12.616292) (xy 396.893046 12.674061) (xy 396.961475 12.725737)
			(xy 397.034381 12.770878) (xy 397.111141 12.8091) (xy 397.1911 12.840076) (xy 397.273576 12.863543)
			(xy 397.357866 12.879299) (xy 397.443249 12.887211) (xy 397.528999 12.887211) (xy 397.614382 12.879299)
			(xy 397.698672 12.863543) (xy 397.781148 12.840076) (xy 397.861107 12.8091) (xy 397.937867 12.770878)
			(xy 398.010773 12.725737) (xy 398.079202 12.674061) (xy 398.142572 12.616292) (xy 398.200341 12.552922)
			(xy 398.252017 12.484493) (xy 398.297158 12.411587) (xy 398.33538 12.334827) (xy 398.366356 12.254868)
			(xy 398.389823 12.172392) (xy 398.405579 12.088102) (xy 398.413491 12.002719) (xy 398.413986 11.959844)
			(xy 398.413491 11.916969) (xy 402.908757 11.916969) (xy 402.908757 12.002719) (xy 402.916669 12.088102)
			(xy 402.932425 12.172392) (xy 402.955892 12.254868) (xy 402.986868 12.334827) (xy 403.02509 12.411587)
			(xy 403.070231 12.484493) (xy 403.121907 12.552922) (xy 403.179676 12.616292) (xy 403.243046 12.674061)
			(xy 403.311475 12.725737) (xy 403.384381 12.770878) (xy 403.461141 12.8091) (xy 403.5411 12.840076)
			(xy 403.623576 12.863543) (xy 403.707866 12.879299) (xy 403.793249 12.887211) (xy 403.878999 12.887211)
			(xy 403.964382 12.879299) (xy 404.048672 12.863543) (xy 404.131148 12.840076) (xy 404.211107 12.8091)
			(xy 404.287867 12.770878) (xy 404.360773 12.725737) (xy 404.429202 12.674061) (xy 404.492572 12.616292)
			(xy 404.550341 12.552922) (xy 404.602017 12.484493) (xy 404.647158 12.411587) (xy 404.68538 12.334827)
			(xy 404.716356 12.254868) (xy 404.739823 12.172392) (xy 404.755579 12.088102) (xy 404.763491 12.002719)
			(xy 404.763986 11.959844) (xy 404.76379 11.942877) (xy 454.759301 11.942877) (xy 454.759301 12.028627)
			(xy 454.767213 12.11401) (xy 454.782969 12.1983) (xy 454.806436 12.280776) (xy 454.837412 12.360735)
			(xy 454.875634 12.437495) (xy 454.920775 12.510401) (xy 454.972451 12.57883) (xy 455.03022 12.6422)
			(xy 455.09359 12.699969) (xy 455.162019 12.751645) (xy 455.234925 12.796786) (xy 455.311685 12.835008)
			(xy 455.391644 12.865984) (xy 455.47412 12.889451) (xy 455.55841 12.905207) (xy 455.643793 12.913119)
			(xy 455.729543 12.913119) (xy 455.814926 12.905207) (xy 455.899216 12.889451) (xy 455.981692 12.865984)
			(xy 456.061651 12.835008) (xy 456.138411 12.796786) (xy 456.211317 12.751645) (xy 456.279746 12.699969)
			(xy 456.343116 12.6422) (xy 456.400885 12.57883) (xy 456.452561 12.510401) (xy 456.497702 12.437495)
			(xy 456.535924 12.360735) (xy 456.5669 12.280776) (xy 456.590367 12.1983) (xy 456.606123 12.11401)
			(xy 456.614035 12.028627) (xy 456.61453 11.985752) (xy 456.614035 11.942877) (xy 461.109301 11.942877)
			(xy 461.109301 12.028627) (xy 461.117213 12.11401) (xy 461.132969 12.1983) (xy 461.156436 12.280776)
			(xy 461.187412 12.360735) (xy 461.225634 12.437495) (xy 461.270775 12.510401) (xy 461.322451 12.57883)
			(xy 461.38022 12.6422) (xy 461.44359 12.699969) (xy 461.512019 12.751645) (xy 461.584925 12.796786)
			(xy 461.661685 12.835008) (xy 461.741644 12.865984) (xy 461.82412 12.889451) (xy 461.90841 12.905207)
			(xy 461.993793 12.913119) (xy 462.079543 12.913119) (xy 462.164926 12.905207) (xy 462.249216 12.889451)
			(xy 462.331692 12.865984) (xy 462.411651 12.835008) (xy 462.488411 12.796786) (xy 462.561317 12.751645)
			(xy 462.629746 12.699969) (xy 462.693116 12.6422) (xy 462.750885 12.57883) (xy 462.802561 12.510401)
			(xy 462.847702 12.437495) (xy 462.885924 12.360735) (xy 462.9169 12.280776) (xy 462.940367 12.1983)
			(xy 462.956123 12.11401) (xy 462.964035 12.028627) (xy 462.96453 11.985752) (xy 462.964035 11.942877)
			(xy 462.956123 11.857494) (xy 462.940367 11.773204) (xy 462.9169 11.690728) (xy 462.885924 11.610769)
			(xy 462.847702 11.534009) (xy 462.802561 11.461103) (xy 462.750885 11.392674) (xy 462.693116 11.329304)
			(xy 462.629746 11.271535) (xy 462.561317 11.219859) (xy 462.488411 11.174718) (xy 462.411651 11.136496)
			(xy 462.331692 11.10552) (xy 462.249216 11.082053) (xy 462.164926 11.066297) (xy 462.079543 11.058385)
			(xy 461.993793 11.058385) (xy 461.90841 11.066297) (xy 461.82412 11.082053) (xy 461.741644 11.10552)
			(xy 461.661685 11.136496) (xy 461.584925 11.174718) (xy 461.512019 11.219859) (xy 461.44359 11.271535)
			(xy 461.38022 11.329304) (xy 461.322451 11.392674) (xy 461.270775 11.461103) (xy 461.225634 11.534009)
			(xy 461.187412 11.610769) (xy 461.156436 11.690728) (xy 461.132969 11.773204) (xy 461.117213 11.857494)
			(xy 461.109301 11.942877) (xy 456.614035 11.942877) (xy 456.606123 11.857494) (xy 456.590367 11.773204)
			(xy 456.5669 11.690728) (xy 456.535924 11.610769) (xy 456.497702 11.534009) (xy 456.452561 11.461103)
			(xy 456.400885 11.392674) (xy 456.343116 11.329304) (xy 456.279746 11.271535) (xy 456.211317 11.219859)
			(xy 456.138411 11.174718) (xy 456.061651 11.136496) (xy 455.981692 11.10552) (xy 455.899216 11.082053)
			(xy 455.814926 11.066297) (xy 455.729543 11.058385) (xy 455.643793 11.058385) (xy 455.55841 11.066297)
			(xy 455.47412 11.082053) (xy 455.391644 11.10552) (xy 455.311685 11.136496) (xy 455.234925 11.174718)
			(xy 455.162019 11.219859) (xy 455.09359 11.271535) (xy 455.03022 11.329304) (xy 454.972451 11.392674)
			(xy 454.920775 11.461103) (xy 454.875634 11.534009) (xy 454.837412 11.610769) (xy 454.806436 11.690728)
			(xy 454.782969 11.773204) (xy 454.767213 11.857494) (xy 454.759301 11.942877) (xy 404.76379 11.942877)
			(xy 404.763491 11.916969) (xy 404.755579 11.831586) (xy 404.739823 11.747296) (xy 404.716356 11.66482)
			(xy 404.68538 11.584861) (xy 404.647158 11.508101) (xy 404.602017 11.435195) (xy 404.550341 11.366766)
			(xy 404.492572 11.303396) (xy 404.429202 11.245627) (xy 404.360773 11.193951) (xy 404.287867 11.14881)
			(xy 404.211107 11.110588) (xy 404.131148 11.079612) (xy 404.048672 11.056145) (xy 403.964382 11.040389)
			(xy 403.878999 11.032477) (xy 403.793249 11.032477) (xy 403.707866 11.040389) (xy 403.623576 11.056145)
			(xy 403.5411 11.079612) (xy 403.461141 11.110588) (xy 403.384381 11.14881) (xy 403.311475 11.193951)
			(xy 403.243046 11.245627) (xy 403.179676 11.303396) (xy 403.121907 11.366766) (xy 403.070231 11.435195)
			(xy 403.02509 11.508101) (xy 402.986868 11.584861) (xy 402.955892 11.66482) (xy 402.932425 11.747296)
			(xy 402.916669 11.831586) (xy 402.908757 11.916969) (xy 398.413491 11.916969) (xy 398.405579 11.831586)
			(xy 398.389823 11.747296) (xy 398.366356 11.66482) (xy 398.33538 11.584861) (xy 398.297158 11.508101)
			(xy 398.252017 11.435195) (xy 398.200341 11.366766) (xy 398.142572 11.303396) (xy 398.079202 11.245627)
			(xy 398.010773 11.193951) (xy 397.937867 11.14881) (xy 397.861107 11.110588) (xy 397.781148 11.079612)
			(xy 397.698672 11.056145) (xy 397.614382 11.040389) (xy 397.528999 11.032477) (xy 397.443249 11.032477)
			(xy 397.357866 11.040389) (xy 397.273576 11.056145) (xy 397.1911 11.079612) (xy 397.111141 11.110588)
			(xy 397.034381 11.14881) (xy 396.961475 11.193951) (xy 396.893046 11.245627) (xy 396.829676 11.303396)
			(xy 396.771907 11.366766) (xy 396.720231 11.435195) (xy 396.67509 11.508101) (xy 396.636868 11.584861)
			(xy 396.605892 11.66482) (xy 396.582425 11.747296) (xy 396.566669 11.831586) (xy 396.558757 11.916969)
			(xy 390.701117 11.916969) (xy 390.701035 11.909857) (xy 390.693123 11.824474) (xy 390.677367 11.740184)
			(xy 390.6539 11.657708) (xy 390.622924 11.577749) (xy 390.584702 11.500989) (xy 390.539561 11.428083)
			(xy 390.487885 11.359654) (xy 390.430116 11.296284) (xy 390.366746 11.238515) (xy 390.298317 11.186839)
			(xy 390.225411 11.141698) (xy 390.148651 11.103476) (xy 390.068692 11.0725) (xy 389.986216 11.049033)
			(xy 389.901926 11.033277) (xy 389.816543 11.025365) (xy 389.730793 11.025365) (xy 389.64541 11.033277)
			(xy 389.56112 11.049033) (xy 389.478644 11.0725) (xy 389.398685 11.103476) (xy 389.321925 11.141698)
			(xy 389.249019 11.186839) (xy 389.18059 11.238515) (xy 389.11722 11.296284) (xy 389.059451 11.359654)
			(xy 389.007775 11.428083) (xy 388.962634 11.500989) (xy 388.924412 11.577749) (xy 388.893436 11.657708)
			(xy 388.869969 11.740184) (xy 388.854213 11.824474) (xy 388.846301 11.909857) (xy 384.351035 11.909857)
			(xy 384.343123 11.824474) (xy 384.327367 11.740184) (xy 384.3039 11.657708) (xy 384.272924 11.577749)
			(xy 384.234702 11.500989) (xy 384.189561 11.428083) (xy 384.137885 11.359654) (xy 384.080116 11.296284)
			(xy 384.016746 11.238515) (xy 383.948317 11.186839) (xy 383.875411 11.141698) (xy 383.798651 11.103476)
			(xy 383.718692 11.0725) (xy 383.636216 11.049033) (xy 383.551926 11.033277) (xy 383.466543 11.025365)
			(xy 383.380793 11.025365) (xy 383.29541 11.033277) (xy 383.21112 11.049033) (xy 383.128644 11.0725)
			(xy 383.048685 11.103476) (xy 382.971925 11.141698) (xy 382.899019 11.186839) (xy 382.83059 11.238515)
			(xy 382.76722 11.296284) (xy 382.709451 11.359654) (xy 382.657775 11.428083) (xy 382.612634 11.500989)
			(xy 382.574412 11.577749) (xy 382.543436 11.657708) (xy 382.519969 11.740184) (xy 382.504213 11.824474)
			(xy 382.496301 11.909857) (xy 332.50079 11.909857) (xy 332.500491 11.883949) (xy 332.492579 11.798566)
			(xy 332.476823 11.714276) (xy 332.453356 11.6318) (xy 332.42238 11.551841) (xy 332.384158 11.475081)
			(xy 332.339017 11.402175) (xy 332.287341 11.333746) (xy 332.229572 11.270376) (xy 332.166202 11.212607)
			(xy 332.097773 11.160931) (xy 332.024867 11.11579) (xy 331.948107 11.077568) (xy 331.868148 11.046592)
			(xy 331.785672 11.023125) (xy 331.701382 11.007369) (xy 331.615999 10.999457) (xy 331.530249 10.999457)
			(xy 331.444866 11.007369) (xy 331.360576 11.023125) (xy 331.2781 11.046592) (xy 331.198141 11.077568)
			(xy 331.121381 11.11579) (xy 331.048475 11.160931) (xy 330.980046 11.212607) (xy 330.916676 11.270376)
			(xy 330.858907 11.333746) (xy 330.807231 11.402175) (xy 330.76209 11.475081) (xy 330.723868 11.551841)
			(xy 330.692892 11.6318) (xy 330.669425 11.714276) (xy 330.653669 11.798566) (xy 330.645757 11.883949)
			(xy 326.150491 11.883949) (xy 326.142579 11.798566) (xy 326.126823 11.714276) (xy 326.103356 11.6318)
			(xy 326.07238 11.551841) (xy 326.034158 11.475081) (xy 325.989017 11.402175) (xy 325.937341 11.333746)
			(xy 325.879572 11.270376) (xy 325.816202 11.212607) (xy 325.747773 11.160931) (xy 325.674867 11.11579)
			(xy 325.598107 11.077568) (xy 325.518148 11.046592) (xy 325.435672 11.023125) (xy 325.351382 11.007369)
			(xy 325.265999 10.999457) (xy 325.180249 10.999457) (xy 325.094866 11.007369) (xy 325.010576 11.023125)
			(xy 324.9281 11.046592) (xy 324.848141 11.077568) (xy 324.771381 11.11579) (xy 324.698475 11.160931)
			(xy 324.630046 11.212607) (xy 324.566676 11.270376) (xy 324.508907 11.333746) (xy 324.457231 11.402175)
			(xy 324.41209 11.475081) (xy 324.373868 11.551841) (xy 324.342892 11.6318) (xy 324.319425 11.714276)
			(xy 324.303669 11.798566) (xy 324.295757 11.883949) (xy 317.930117 11.883949) (xy 317.930035 11.876837)
			(xy 317.922123 11.791454) (xy 317.906367 11.707164) (xy 317.8829 11.624688) (xy 317.851924 11.544729)
			(xy 317.813702 11.467969) (xy 317.768561 11.395063) (xy 317.716885 11.326634) (xy 317.659116 11.263264)
			(xy 317.595746 11.205495) (xy 317.527317 11.153819) (xy 317.454411 11.108678) (xy 317.377651 11.070456)
			(xy 317.297692 11.03948) (xy 317.215216 11.016013) (xy 317.130926 11.000257) (xy 317.045543 10.992345)
			(xy 316.959793 10.992345) (xy 316.87441 11.000257) (xy 316.79012 11.016013) (xy 316.707644 11.03948)
			(xy 316.627685 11.070456) (xy 316.550925 11.108678) (xy 316.478019 11.153819) (xy 316.40959 11.205495)
			(xy 316.34622 11.263264) (xy 316.288451 11.326634) (xy 316.236775 11.395063) (xy 316.191634 11.467969)
			(xy 316.153412 11.544729) (xy 316.122436 11.624688) (xy 316.098969 11.707164) (xy 316.083213 11.791454)
			(xy 316.075301 11.876837) (xy 311.580035 11.876837) (xy 311.572123 11.791454) (xy 311.556367 11.707164)
			(xy 311.5329 11.624688) (xy 311.501924 11.544729) (xy 311.463702 11.467969) (xy 311.418561 11.395063)
			(xy 311.366885 11.326634) (xy 311.309116 11.263264) (xy 311.245746 11.205495) (xy 311.177317 11.153819)
			(xy 311.104411 11.108678) (xy 311.027651 11.070456) (xy 310.947692 11.03948) (xy 310.865216 11.016013)
			(xy 310.780926 11.000257) (xy 310.695543 10.992345) (xy 310.609793 10.992345) (xy 310.52441 11.000257)
			(xy 310.44012 11.016013) (xy 310.357644 11.03948) (xy 310.277685 11.070456) (xy 310.200925 11.108678)
			(xy 310.128019 11.153819) (xy 310.05959 11.205495) (xy 309.99622 11.263264) (xy 309.938451 11.326634)
			(xy 309.886775 11.395063) (xy 309.841634 11.467969) (xy 309.803412 11.544729) (xy 309.772436 11.624688)
			(xy 309.748969 11.707164) (xy 309.733213 11.791454) (xy 309.725301 11.876837) (xy 259.72979 11.876837)
			(xy 259.729491 11.850929) (xy 259.721579 11.765546) (xy 259.705823 11.681256) (xy 259.682356 11.59878)
			(xy 259.65138 11.518821) (xy 259.613158 11.442061) (xy 259.568017 11.369155) (xy 259.516341 11.300726)
			(xy 259.458572 11.237356) (xy 259.395202 11.179587) (xy 259.326773 11.127911) (xy 259.253867 11.08277)
			(xy 259.177107 11.044548) (xy 259.097148 11.013572) (xy 259.014672 10.990105) (xy 258.930382 10.974349)
			(xy 258.844999 10.966437) (xy 258.759249 10.966437) (xy 258.673866 10.974349) (xy 258.589576 10.990105)
			(xy 258.5071 11.013572) (xy 258.427141 11.044548) (xy 258.350381 11.08277) (xy 258.277475 11.127911)
			(xy 258.209046 11.179587) (xy 258.145676 11.237356) (xy 258.087907 11.300726) (xy 258.036231 11.369155)
			(xy 257.99109 11.442061) (xy 257.952868 11.518821) (xy 257.921892 11.59878) (xy 257.898425 11.681256)
			(xy 257.882669 11.765546) (xy 257.874757 11.850929) (xy 253.379491 11.850929) (xy 253.371579 11.765546)
			(xy 253.355823 11.681256) (xy 253.332356 11.59878) (xy 253.30138 11.518821) (xy 253.263158 11.442061)
			(xy 253.218017 11.369155) (xy 253.166341 11.300726) (xy 253.108572 11.237356) (xy 253.045202 11.179587)
			(xy 252.976773 11.127911) (xy 252.903867 11.08277) (xy 252.827107 11.044548) (xy 252.747148 11.013572)
			(xy 252.664672 10.990105) (xy 252.580382 10.974349) (xy 252.494999 10.966437) (xy 252.409249 10.966437)
			(xy 252.323866 10.974349) (xy 252.239576 10.990105) (xy 252.1571 11.013572) (xy 252.077141 11.044548)
			(xy 252.000381 11.08277) (xy 251.927475 11.127911) (xy 251.859046 11.179587) (xy 251.795676 11.237356)
			(xy 251.737907 11.300726) (xy 251.686231 11.369155) (xy 251.64109 11.442061) (xy 251.602868 11.518821)
			(xy 251.571892 11.59878) (xy 251.548425 11.681256) (xy 251.532669 11.765546) (xy 251.524757 11.850929)
			(xy 158.621984 11.850929) (xy 158.621984 9.310929) (xy 179.515757 9.310929) (xy 179.515757 9.396679)
			(xy 179.523669 9.482062) (xy 179.539425 9.566352) (xy 179.562892 9.648828) (xy 179.593868 9.728787)
			(xy 179.63209 9.805547) (xy 179.677231 9.878453) (xy 179.728907 9.946882) (xy 179.786676 10.010252)
			(xy 179.850046 10.068021) (xy 179.918475 10.119697) (xy 179.991381 10.164838) (xy 180.068141 10.20306)
			(xy 180.1481 10.234036) (xy 180.230576 10.257503) (xy 180.314866 10.273259) (xy 180.400249 10.281171)
			(xy 180.485999 10.281171) (xy 180.571382 10.273259) (xy 180.655672 10.257503) (xy 180.738148 10.234036)
			(xy 180.818107 10.20306) (xy 180.894867 10.164838) (xy 180.967773 10.119697) (xy 181.036202 10.068021)
			(xy 181.099572 10.010252) (xy 181.157341 9.946882) (xy 181.209017 9.878453) (xy 181.254158 9.805547)
			(xy 181.29238 9.728787) (xy 181.323356 9.648828) (xy 181.346823 9.566352) (xy 181.362579 9.482062)
			(xy 181.370491 9.396679) (xy 181.370986 9.353804) (xy 181.370491 9.310929) (xy 185.865757 9.310929)
			(xy 185.865757 9.396679) (xy 185.873669 9.482062) (xy 185.889425 9.566352) (xy 185.912892 9.648828)
			(xy 185.943868 9.728787) (xy 185.98209 9.805547) (xy 186.027231 9.878453) (xy 186.078907 9.946882)
			(xy 186.136676 10.010252) (xy 186.200046 10.068021) (xy 186.268475 10.119697) (xy 186.341381 10.164838)
			(xy 186.418141 10.20306) (xy 186.4981 10.234036) (xy 186.580576 10.257503) (xy 186.664866 10.273259)
			(xy 186.750249 10.281171) (xy 186.835999 10.281171) (xy 186.921382 10.273259) (xy 187.005672 10.257503)
			(xy 187.088148 10.234036) (xy 187.168107 10.20306) (xy 187.244867 10.164838) (xy 187.317773 10.119697)
			(xy 187.386202 10.068021) (xy 187.449572 10.010252) (xy 187.507341 9.946882) (xy 187.559017 9.878453)
			(xy 187.604158 9.805547) (xy 187.64238 9.728787) (xy 187.673356 9.648828) (xy 187.696823 9.566352)
			(xy 187.712579 9.482062) (xy 187.720491 9.396679) (xy 187.720986 9.353804) (xy 187.720491 9.310929)
			(xy 187.719832 9.303817) (xy 237.716301 9.303817) (xy 237.716301 9.389567) (xy 237.724213 9.47495)
			(xy 237.739969 9.55924) (xy 237.763436 9.641716) (xy 237.794412 9.721675) (xy 237.832634 9.798435)
			(xy 237.877775 9.871341) (xy 237.929451 9.93977) (xy 237.98722 10.00314) (xy 238.05059 10.060909)
			(xy 238.119019 10.112585) (xy 238.191925 10.157726) (xy 238.268685 10.195948) (xy 238.348644 10.226924)
			(xy 238.43112 10.250391) (xy 238.51541 10.266147) (xy 238.600793 10.274059) (xy 238.686543 10.274059)
			(xy 238.771926 10.266147) (xy 238.856216 10.250391) (xy 238.938692 10.226924) (xy 239.018651 10.195948)
			(xy 239.095411 10.157726) (xy 239.168317 10.112585) (xy 239.236746 10.060909) (xy 239.300116 10.00314)
			(xy 239.357885 9.93977) (xy 239.409561 9.871341) (xy 239.454702 9.798435) (xy 239.492924 9.721675)
			(xy 239.5239 9.641716) (xy 239.547367 9.55924) (xy 239.563123 9.47495) (xy 239.571035 9.389567) (xy 239.57153 9.346692)
			(xy 239.571035 9.303817) (xy 244.066301 9.303817) (xy 244.066301 9.389567) (xy 244.074213 9.47495)
			(xy 244.089969 9.55924) (xy 244.113436 9.641716) (xy 244.144412 9.721675) (xy 244.182634 9.798435)
			(xy 244.227775 9.871341) (xy 244.279451 9.93977) (xy 244.33722 10.00314) (xy 244.40059 10.060909)
			(xy 244.469019 10.112585) (xy 244.541925 10.157726) (xy 244.618685 10.195948) (xy 244.698644 10.226924)
			(xy 244.78112 10.250391) (xy 244.86541 10.266147) (xy 244.950793 10.274059) (xy 245.036543 10.274059)
			(xy 245.121926 10.266147) (xy 245.206216 10.250391) (xy 245.288692 10.226924) (xy 245.368651 10.195948)
			(xy 245.445411 10.157726) (xy 245.518317 10.112585) (xy 245.586746 10.060909) (xy 245.650116 10.00314)
			(xy 245.707885 9.93977) (xy 245.759561 9.871341) (xy 245.804702 9.798435) (xy 245.842924 9.721675)
			(xy 245.8739 9.641716) (xy 245.897367 9.55924) (xy 245.913123 9.47495) (xy 245.921035 9.389567) (xy 245.92153 9.346692)
			(xy 245.921117 9.310929) (xy 251.524757 9.310929) (xy 251.524757 9.396679) (xy 251.532669 9.482062)
			(xy 251.548425 9.566352) (xy 251.571892 9.648828) (xy 251.602868 9.728787) (xy 251.64109 9.805547)
			(xy 251.686231 9.878453) (xy 251.737907 9.946882) (xy 251.795676 10.010252) (xy 251.859046 10.068021)
			(xy 251.927475 10.119697) (xy 252.000381 10.164838) (xy 252.077141 10.20306) (xy 252.1571 10.234036)
			(xy 252.239576 10.257503) (xy 252.323866 10.273259) (xy 252.409249 10.281171) (xy 252.494999 10.281171)
			(xy 252.580382 10.273259) (xy 252.664672 10.257503) (xy 252.747148 10.234036) (xy 252.827107 10.20306)
			(xy 252.84931 10.192004) (xy 256.459736 10.192004) (xy 256.459736 11.055604) (xy 256.460222 11.082873)
			(xy 256.467984 11.136857) (xy 256.483349 11.189187) (xy 256.506006 11.238797) (xy 256.535492 11.284678)
			(xy 256.571207 11.325895) (xy 256.612424 11.36161) (xy 256.658305 11.391096) (xy 256.707915 11.413753)
			(xy 256.760245 11.429118) (xy 256.814229 11.43688) (xy 256.868767 11.43688) (xy 256.922751 11.429118)
			(xy 256.975081 11.413753) (xy 257.024691 11.391096) (xy 257.070572 11.36161) (xy 257.111789 11.325895)
			(xy 257.147504 11.284678) (xy 257.17699 11.238797) (xy 257.199647 11.189187) (xy 257.215012 11.136857)
			(xy 257.222774 11.082873) (xy 257.22326 11.055604) (xy 257.22326 10.192004) (xy 257.222774 10.164735)
			(xy 257.215012 10.110751) (xy 257.199647 10.058421) (xy 257.17699 10.008811) (xy 257.147504 9.96293)
			(xy 257.111789 9.921713) (xy 257.070572 9.885998) (xy 257.024691 9.856512) (xy 256.975081 9.833855)
			(xy 256.922751 9.81849) (xy 256.868767 9.810728) (xy 256.814229 9.810728) (xy 256.760245 9.81849)
			(xy 256.707915 9.833855) (xy 256.658305 9.856512) (xy 256.612424 9.885998) (xy 256.571207 9.921713)
			(xy 256.535492 9.96293) (xy 256.506006 10.008811) (xy 256.483349 10.058421) (xy 256.467984 10.110751)
			(xy 256.460222 10.164735) (xy 256.459736 10.192004) (xy 252.84931 10.192004) (xy 252.903867 10.164838)
			(xy 252.976773 10.119697) (xy 253.045202 10.068021) (xy 253.108572 10.010252) (xy 253.166341 9.946882)
			(xy 253.218017 9.878453) (xy 253.263158 9.805547) (xy 253.30138 9.728787) (xy 253.332356 9.648828)
			(xy 253.355823 9.566352) (xy 253.371579 9.482062) (xy 253.379491 9.396679) (xy 253.379986 9.353804)
			(xy 253.379491 9.310929) (xy 257.874757 9.310929) (xy 257.874757 9.396679) (xy 257.882669 9.482062)
			(xy 257.898425 9.566352) (xy 257.921892 9.648828) (xy 257.952868 9.728787) (xy 257.99109 9.805547)
			(xy 258.036231 9.878453) (xy 258.087907 9.946882) (xy 258.145676 10.010252) (xy 258.209046 10.068021)
			(xy 258.277475 10.119697) (xy 258.350381 10.164838) (xy 258.427141 10.20306) (xy 258.5071 10.234036)
			(xy 258.589576 10.257503) (xy 258.673866 10.273259) (xy 258.759249 10.281171) (xy 258.844999 10.281171)
			(xy 258.930382 10.273259) (xy 259.014672 10.257503) (xy 259.097148 10.234036) (xy 259.177107 10.20306)
			(xy 259.253867 10.164838) (xy 259.326773 10.119697) (xy 259.395202 10.068021) (xy 259.458572 10.010252)
			(xy 259.516341 9.946882) (xy 259.568017 9.878453) (xy 259.613158 9.805547) (xy 259.65138 9.728787)
			(xy 259.682356 9.648828) (xy 259.705823 9.566352) (xy 259.721579 9.482062) (xy 259.729491 9.396679)
			(xy 259.729986 9.353804) (xy 259.72979 9.336837) (xy 309.725301 9.336837) (xy 309.725301 9.422587)
			(xy 309.733213 9.50797) (xy 309.748969 9.59226) (xy 309.772436 9.674736) (xy 309.803412 9.754695)
			(xy 309.841634 9.831455) (xy 309.886775 9.904361) (xy 309.938451 9.97279) (xy 309.99622 10.03616)
			(xy 310.05959 10.093929) (xy 310.128019 10.145605) (xy 310.200925 10.190746) (xy 310.277685 10.228968)
			(xy 310.357644 10.259944) (xy 310.44012 10.283411) (xy 310.52441 10.299167) (xy 310.609793 10.307079)
			(xy 310.695543 10.307079) (xy 310.780926 10.299167) (xy 310.865216 10.283411) (xy 310.947692 10.259944)
			(xy 311.027651 10.228968) (xy 311.049854 10.217912) (xy 312.231532 10.217912) (xy 312.231532 11.081512)
			(xy 312.232018 11.108781) (xy 312.23978 11.162765) (xy 312.255145 11.215095) (xy 312.277802 11.264705)
			(xy 312.307288 11.310586) (xy 312.343003 11.351803) (xy 312.38422 11.387518) (xy 312.430101 11.417004)
			(xy 312.479711 11.439661) (xy 312.532041 11.455026) (xy 312.586025 11.462788) (xy 312.640563 11.462788)
			(xy 312.694547 11.455026) (xy 312.746877 11.439661) (xy 312.796487 11.417004) (xy 312.842368 11.387518)
			(xy 312.883585 11.351803) (xy 312.9193 11.310586) (xy 312.948786 11.264705) (xy 312.971443 11.215095)
			(xy 312.986808 11.162765) (xy 312.99457 11.108781) (xy 312.995056 11.081512) (xy 312.995056 10.217912)
			(xy 312.99457 10.190643) (xy 312.986808 10.136659) (xy 312.971443 10.084329) (xy 312.948786 10.034719)
			(xy 312.9193 9.988838) (xy 312.883585 9.947621) (xy 312.842368 9.911906) (xy 312.796487 9.88242)
			(xy 312.746877 9.859763) (xy 312.694547 9.844398) (xy 312.640563 9.836636) (xy 312.586025 9.836636)
			(xy 312.532041 9.844398) (xy 312.479711 9.859763) (xy 312.430101 9.88242) (xy 312.38422 9.911906)
			(xy 312.343003 9.947621) (xy 312.307288 9.988838) (xy 312.277802 10.034719) (xy 312.255145 10.084329)
			(xy 312.23978 10.136659) (xy 312.232018 10.190643) (xy 312.231532 10.217912) (xy 311.049854 10.217912)
			(xy 311.104411 10.190746) (xy 311.177317 10.145605) (xy 311.245746 10.093929) (xy 311.309116 10.03616)
			(xy 311.366885 9.97279) (xy 311.418561 9.904361) (xy 311.463702 9.831455) (xy 311.501924 9.754695)
			(xy 311.5329 9.674736) (xy 311.556367 9.59226) (xy 311.572123 9.50797) (xy 311.580035 9.422587) (xy 311.58053 9.379712)
			(xy 311.580035 9.336837) (xy 316.075301 9.336837) (xy 316.075301 9.422587) (xy 316.083213 9.50797)
			(xy 316.098969 9.59226) (xy 316.122436 9.674736) (xy 316.153412 9.754695) (xy 316.191634 9.831455)
			(xy 316.236775 9.904361) (xy 316.288451 9.97279) (xy 316.34622 10.03616) (xy 316.40959 10.093929)
			(xy 316.478019 10.145605) (xy 316.550925 10.190746) (xy 316.627685 10.228968) (xy 316.707644 10.259944)
			(xy 316.79012 10.283411) (xy 316.87441 10.299167) (xy 316.959793 10.307079) (xy 317.045543 10.307079)
			(xy 317.130926 10.299167) (xy 317.215216 10.283411) (xy 317.297692 10.259944) (xy 317.377651 10.228968)
			(xy 317.454411 10.190746) (xy 317.527317 10.145605) (xy 317.595746 10.093929) (xy 317.659116 10.03616)
			(xy 317.716885 9.97279) (xy 317.768561 9.904361) (xy 317.813702 9.831455) (xy 317.851924 9.754695)
			(xy 317.8829 9.674736) (xy 317.906367 9.59226) (xy 317.922123 9.50797) (xy 317.930035 9.422587) (xy 317.93053 9.379712)
			(xy 317.930117 9.343949) (xy 324.295757 9.343949) (xy 324.295757 9.429699) (xy 324.303669 9.515082)
			(xy 324.319425 9.599372) (xy 324.342892 9.681848) (xy 324.373868 9.761807) (xy 324.41209 9.838567)
			(xy 324.457231 9.911473) (xy 324.508907 9.979902) (xy 324.566676 10.043272) (xy 324.630046 10.101041)
			(xy 324.698475 10.152717) (xy 324.771381 10.197858) (xy 324.848141 10.23608) (xy 324.9281 10.267056)
			(xy 325.010576 10.290523) (xy 325.094866 10.306279) (xy 325.180249 10.314191) (xy 325.265999 10.314191)
			(xy 325.351382 10.306279) (xy 325.435672 10.290523) (xy 325.518148 10.267056) (xy 325.598107 10.23608)
			(xy 325.62031 10.225024) (xy 329.230736 10.225024) (xy 329.230736 11.088624) (xy 329.231222 11.115893)
			(xy 329.238984 11.169877) (xy 329.254349 11.222207) (xy 329.277006 11.271817) (xy 329.306492 11.317698)
			(xy 329.342207 11.358915) (xy 329.383424 11.39463) (xy 329.429305 11.424116) (xy 329.478915 11.446773)
			(xy 329.531245 11.462138) (xy 329.585229 11.4699) (xy 329.639767 11.4699) (xy 329.693751 11.462138)
			(xy 329.746081 11.446773) (xy 329.795691 11.424116) (xy 329.841572 11.39463) (xy 329.882789 11.358915)
			(xy 329.918504 11.317698) (xy 329.94799 11.271817) (xy 329.970647 11.222207) (xy 329.986012 11.169877)
			(xy 329.993774 11.115893) (xy 329.99426 11.088624) (xy 329.99426 10.225024) (xy 329.993774 10.197755)
			(xy 329.986012 10.143771) (xy 329.970647 10.091441) (xy 329.94799 10.041831) (xy 329.918504 9.99595)
			(xy 329.882789 9.954733) (xy 329.841572 9.919018) (xy 329.795691 9.889532) (xy 329.746081 9.866875)
			(xy 329.693751 9.85151) (xy 329.639767 9.843748) (xy 329.585229 9.843748) (xy 329.531245 9.85151)
			(xy 329.478915 9.866875) (xy 329.429305 9.889532) (xy 329.383424 9.919018) (xy 329.342207 9.954733)
			(xy 329.306492 9.99595) (xy 329.277006 10.041831) (xy 329.254349 10.091441) (xy 329.238984 10.143771)
			(xy 329.231222 10.197755) (xy 329.230736 10.225024) (xy 325.62031 10.225024) (xy 325.674867 10.197858)
			(xy 325.747773 10.152717) (xy 325.816202 10.101041) (xy 325.879572 10.043272) (xy 325.937341 9.979902)
			(xy 325.989017 9.911473) (xy 326.034158 9.838567) (xy 326.07238 9.761807) (xy 326.103356 9.681848)
			(xy 326.126823 9.599372) (xy 326.142579 9.515082) (xy 326.150491 9.429699) (xy 326.150986 9.386824)
			(xy 326.150491 9.343949) (xy 330.645757 9.343949) (xy 330.645757 9.429699) (xy 330.653669 9.515082)
			(xy 330.669425 9.599372) (xy 330.692892 9.681848) (xy 330.723868 9.761807) (xy 330.76209 9.838567)
			(xy 330.807231 9.911473) (xy 330.858907 9.979902) (xy 330.916676 10.043272) (xy 330.980046 10.101041)
			(xy 331.048475 10.152717) (xy 331.121381 10.197858) (xy 331.198141 10.23608) (xy 331.2781 10.267056)
			(xy 331.360576 10.290523) (xy 331.444866 10.306279) (xy 331.530249 10.314191) (xy 331.615999 10.314191)
			(xy 331.701382 10.306279) (xy 331.785672 10.290523) (xy 331.868148 10.267056) (xy 331.948107 10.23608)
			(xy 332.024867 10.197858) (xy 332.097773 10.152717) (xy 332.166202 10.101041) (xy 332.229572 10.043272)
			(xy 332.287341 9.979902) (xy 332.339017 9.911473) (xy 332.384158 9.838567) (xy 332.42238 9.761807)
			(xy 332.453356 9.681848) (xy 332.476823 9.599372) (xy 332.492579 9.515082) (xy 332.500491 9.429699)
			(xy 332.500986 9.386824) (xy 332.50079 9.369857) (xy 382.496301 9.369857) (xy 382.496301 9.455607)
			(xy 382.504213 9.54099) (xy 382.519969 9.62528) (xy 382.543436 9.707756) (xy 382.574412 9.787715)
			(xy 382.612634 9.864475) (xy 382.657775 9.937381) (xy 382.709451 10.00581) (xy 382.76722 10.06918)
			(xy 382.83059 10.126949) (xy 382.899019 10.178625) (xy 382.971925 10.223766) (xy 383.048685 10.261988)
			(xy 383.128644 10.292964) (xy 383.21112 10.316431) (xy 383.29541 10.332187) (xy 383.380793 10.340099)
			(xy 383.466543 10.340099) (xy 383.551926 10.332187) (xy 383.636216 10.316431) (xy 383.718692 10.292964)
			(xy 383.798651 10.261988) (xy 383.820854 10.250932) (xy 385.002532 10.250932) (xy 385.002532 11.114532)
			(xy 385.003018 11.141801) (xy 385.01078 11.195785) (xy 385.026145 11.248115) (xy 385.048802 11.297725)
			(xy 385.078288 11.343606) (xy 385.114003 11.384823) (xy 385.15522 11.420538) (xy 385.201101 11.450024)
			(xy 385.250711 11.472681) (xy 385.303041 11.488046) (xy 385.357025 11.495808) (xy 385.411563 11.495808)
			(xy 385.465547 11.488046) (xy 385.517877 11.472681) (xy 385.567487 11.450024) (xy 385.613368 11.420538)
			(xy 385.654585 11.384823) (xy 385.6903 11.343606) (xy 385.719786 11.297725) (xy 385.742443 11.248115)
			(xy 385.757808 11.195785) (xy 385.76557 11.141801) (xy 385.766056 11.114532) (xy 385.766056 10.250932)
			(xy 385.76557 10.223663) (xy 385.757808 10.169679) (xy 385.742443 10.117349) (xy 385.719786 10.067739)
			(xy 385.6903 10.021858) (xy 385.654585 9.980641) (xy 385.613368 9.944926) (xy 385.567487 9.91544)
			(xy 385.517877 9.892783) (xy 385.465547 9.877418) (xy 385.411563 9.869656) (xy 385.357025 9.869656)
			(xy 385.303041 9.877418) (xy 385.250711 9.892783) (xy 385.201101 9.91544) (xy 385.15522 9.944926)
			(xy 385.114003 9.980641) (xy 385.078288 10.021858) (xy 385.048802 10.067739) (xy 385.026145 10.117349)
			(xy 385.01078 10.169679) (xy 385.003018 10.223663) (xy 385.002532 10.250932) (xy 383.820854 10.250932)
			(xy 383.875411 10.223766) (xy 383.948317 10.178625) (xy 384.016746 10.126949) (xy 384.080116 10.06918)
			(xy 384.137885 10.00581) (xy 384.189561 9.937381) (xy 384.234702 9.864475) (xy 384.272924 9.787715)
			(xy 384.3039 9.707756) (xy 384.327367 9.62528) (xy 384.343123 9.54099) (xy 384.351035 9.455607) (xy 384.35153 9.412732)
			(xy 384.351035 9.369857) (xy 388.846301 9.369857) (xy 388.846301 9.455607) (xy 388.854213 9.54099)
			(xy 388.869969 9.62528) (xy 388.893436 9.707756) (xy 388.924412 9.787715) (xy 388.962634 9.864475)
			(xy 389.007775 9.937381) (xy 389.059451 10.00581) (xy 389.11722 10.06918) (xy 389.18059 10.126949)
			(xy 389.249019 10.178625) (xy 389.321925 10.223766) (xy 389.398685 10.261988) (xy 389.478644 10.292964)
			(xy 389.56112 10.316431) (xy 389.64541 10.332187) (xy 389.730793 10.340099) (xy 389.816543 10.340099)
			(xy 389.901926 10.332187) (xy 389.986216 10.316431) (xy 390.068692 10.292964) (xy 390.148651 10.261988)
			(xy 390.225411 10.223766) (xy 390.298317 10.178625) (xy 390.366746 10.126949) (xy 390.430116 10.06918)
			(xy 390.487885 10.00581) (xy 390.539561 9.937381) (xy 390.584702 9.864475) (xy 390.622924 9.787715)
			(xy 390.6539 9.707756) (xy 390.677367 9.62528) (xy 390.693123 9.54099) (xy 390.701035 9.455607) (xy 390.70153 9.412732)
			(xy 390.701117 9.376969) (xy 396.558757 9.376969) (xy 396.558757 9.462719) (xy 396.566669 9.548102)
			(xy 396.582425 9.632392) (xy 396.605892 9.714868) (xy 396.636868 9.794827) (xy 396.67509 9.871587)
			(xy 396.720231 9.944493) (xy 396.771907 10.012922) (xy 396.829676 10.076292) (xy 396.893046 10.134061)
			(xy 396.961475 10.185737) (xy 397.034381 10.230878) (xy 397.111141 10.2691) (xy 397.1911 10.300076)
			(xy 397.273576 10.323543) (xy 397.357866 10.339299) (xy 397.443249 10.347211) (xy 397.528999 10.347211)
			(xy 397.614382 10.339299) (xy 397.698672 10.323543) (xy 397.781148 10.300076) (xy 397.861107 10.2691)
			(xy 397.88331 10.258044) (xy 401.493736 10.258044) (xy 401.493736 11.121644) (xy 401.494222 11.148913)
			(xy 401.501984 11.202897) (xy 401.517349 11.255227) (xy 401.540006 11.304837) (xy 401.569492 11.350718)
			(xy 401.605207 11.391935) (xy 401.646424 11.42765) (xy 401.692305 11.457136) (xy 401.741915 11.479793)
			(xy 401.794245 11.495158) (xy 401.848229 11.50292) (xy 401.902767 11.50292) (xy 401.956751 11.495158)
			(xy 402.009081 11.479793) (xy 402.058691 11.457136) (xy 402.104572 11.42765) (xy 402.145789 11.391935)
			(xy 402.181504 11.350718) (xy 402.21099 11.304837) (xy 402.233647 11.255227) (xy 402.249012 11.202897)
			(xy 402.256774 11.148913) (xy 402.25726 11.121644) (xy 402.25726 10.258044) (xy 402.256774 10.230775)
			(xy 402.249012 10.176791) (xy 402.233647 10.124461) (xy 402.21099 10.074851) (xy 402.181504 10.02897)
			(xy 402.145789 9.987753) (xy 402.104572 9.952038) (xy 402.058691 9.922552) (xy 402.009081 9.899895)
			(xy 401.956751 9.88453) (xy 401.902767 9.876768) (xy 401.848229 9.876768) (xy 401.794245 9.88453)
			(xy 401.741915 9.899895) (xy 401.692305 9.922552) (xy 401.646424 9.952038) (xy 401.605207 9.987753)
			(xy 401.569492 10.02897) (xy 401.540006 10.074851) (xy 401.517349 10.124461) (xy 401.501984 10.176791)
			(xy 401.494222 10.230775) (xy 401.493736 10.258044) (xy 397.88331 10.258044) (xy 397.937867 10.230878)
			(xy 398.010773 10.185737) (xy 398.079202 10.134061) (xy 398.142572 10.076292) (xy 398.200341 10.012922)
			(xy 398.252017 9.944493) (xy 398.297158 9.871587) (xy 398.33538 9.794827) (xy 398.366356 9.714868)
			(xy 398.389823 9.632392) (xy 398.405579 9.548102) (xy 398.413491 9.462719) (xy 398.413986 9.419844)
			(xy 398.413491 9.376969) (xy 402.908757 9.376969) (xy 402.908757 9.462719) (xy 402.916669 9.548102)
			(xy 402.932425 9.632392) (xy 402.955892 9.714868) (xy 402.986868 9.794827) (xy 403.02509 9.871587)
			(xy 403.070231 9.944493) (xy 403.121907 10.012922) (xy 403.179676 10.076292) (xy 403.243046 10.134061)
			(xy 403.311475 10.185737) (xy 403.384381 10.230878) (xy 403.461141 10.2691) (xy 403.5411 10.300076)
			(xy 403.623576 10.323543) (xy 403.707866 10.339299) (xy 403.793249 10.347211) (xy 403.878999 10.347211)
			(xy 403.964382 10.339299) (xy 404.048672 10.323543) (xy 404.131148 10.300076) (xy 404.211107 10.2691)
			(xy 404.287867 10.230878) (xy 404.360773 10.185737) (xy 404.429202 10.134061) (xy 404.492572 10.076292)
			(xy 404.550341 10.012922) (xy 404.602017 9.944493) (xy 404.647158 9.871587) (xy 404.68538 9.794827)
			(xy 404.716356 9.714868) (xy 404.739823 9.632392) (xy 404.755579 9.548102) (xy 404.763491 9.462719)
			(xy 404.763986 9.419844) (xy 404.76379 9.402877) (xy 454.759301 9.402877) (xy 454.759301 9.488627)
			(xy 454.767213 9.57401) (xy 454.782969 9.6583) (xy 454.806436 9.740776) (xy 454.837412 9.820735)
			(xy 454.875634 9.897495) (xy 454.920775 9.970401) (xy 454.972451 10.03883) (xy 455.03022 10.1022)
			(xy 455.09359 10.159969) (xy 455.162019 10.211645) (xy 455.234925 10.256786) (xy 455.311685 10.295008)
			(xy 455.391644 10.325984) (xy 455.47412 10.349451) (xy 455.55841 10.365207) (xy 455.643793 10.373119)
			(xy 455.729543 10.373119) (xy 455.814926 10.365207) (xy 455.899216 10.349451) (xy 455.981692 10.325984)
			(xy 456.061651 10.295008) (xy 456.083854 10.283952) (xy 457.265532 10.283952) (xy 457.265532 11.147552)
			(xy 457.266018 11.174821) (xy 457.27378 11.228805) (xy 457.289145 11.281135) (xy 457.311802 11.330745)
			(xy 457.341288 11.376626) (xy 457.377003 11.417843) (xy 457.41822 11.453558) (xy 457.464101 11.483044)
			(xy 457.513711 11.505701) (xy 457.566041 11.521066) (xy 457.620025 11.528828) (xy 457.674563 11.528828)
			(xy 457.728547 11.521066) (xy 457.780877 11.505701) (xy 457.830487 11.483044) (xy 457.876368 11.453558)
			(xy 457.917585 11.417843) (xy 457.9533 11.376626) (xy 457.982786 11.330745) (xy 458.005443 11.281135)
			(xy 458.020808 11.228805) (xy 458.02857 11.174821) (xy 458.029056 11.147552) (xy 458.029056 10.283952)
			(xy 458.02857 10.256683) (xy 458.020808 10.202699) (xy 458.005443 10.150369) (xy 457.982786 10.100759)
			(xy 457.9533 10.054878) (xy 457.917585 10.013661) (xy 457.876368 9.977946) (xy 457.830487 9.94846)
			(xy 457.780877 9.925803) (xy 457.728547 9.910438) (xy 457.674563 9.902676) (xy 457.620025 9.902676)
			(xy 457.566041 9.910438) (xy 457.513711 9.925803) (xy 457.464101 9.94846) (xy 457.41822 9.977946)
			(xy 457.377003 10.013661) (xy 457.341288 10.054878) (xy 457.311802 10.100759) (xy 457.289145 10.150369)
			(xy 457.27378 10.202699) (xy 457.266018 10.256683) (xy 457.265532 10.283952) (xy 456.083854 10.283952)
			(xy 456.138411 10.256786) (xy 456.211317 10.211645) (xy 456.279746 10.159969) (xy 456.343116 10.1022)
			(xy 456.400885 10.03883) (xy 456.452561 9.970401) (xy 456.497702 9.897495) (xy 456.535924 9.820735)
			(xy 456.5669 9.740776) (xy 456.590367 9.6583) (xy 456.606123 9.57401) (xy 456.614035 9.488627) (xy 456.61453 9.445752)
			(xy 456.614035 9.402877) (xy 461.109301 9.402877) (xy 461.109301 9.488627) (xy 461.117213 9.57401)
			(xy 461.132969 9.6583) (xy 461.156436 9.740776) (xy 461.187412 9.820735) (xy 461.225634 9.897495)
			(xy 461.270775 9.970401) (xy 461.322451 10.03883) (xy 461.38022 10.1022) (xy 461.44359 10.159969)
			(xy 461.512019 10.211645) (xy 461.584925 10.256786) (xy 461.661685 10.295008) (xy 461.741644 10.325984)
			(xy 461.82412 10.349451) (xy 461.90841 10.365207) (xy 461.993793 10.373119) (xy 462.079543 10.373119)
			(xy 462.164926 10.365207) (xy 462.249216 10.349451) (xy 462.331692 10.325984) (xy 462.411651 10.295008)
			(xy 462.488411 10.256786) (xy 462.561317 10.211645) (xy 462.629746 10.159969) (xy 462.693116 10.1022)
			(xy 462.750885 10.03883) (xy 462.802561 9.970401) (xy 462.847702 9.897495) (xy 462.885924 9.820735)
			(xy 462.9169 9.740776) (xy 462.940367 9.6583) (xy 462.956123 9.57401) (xy 462.964035 9.488627) (xy 462.96453 9.445752)
			(xy 462.964035 9.402877) (xy 462.956123 9.317494) (xy 462.940367 9.233204) (xy 462.9169 9.150728)
			(xy 462.885924 9.070769) (xy 462.847702 8.994009) (xy 462.802561 8.921103) (xy 462.750885 8.852674)
			(xy 462.693116 8.789304) (xy 462.629746 8.731535) (xy 462.561317 8.679859) (xy 462.488411 8.634718)
			(xy 462.411651 8.596496) (xy 462.331692 8.56552) (xy 462.249216 8.542053) (xy 462.164926 8.526297)
			(xy 462.079543 8.518385) (xy 461.993793 8.518385) (xy 461.90841 8.526297) (xy 461.82412 8.542053)
			(xy 461.741644 8.56552) (xy 461.661685 8.596496) (xy 461.584925 8.634718) (xy 461.512019 8.679859)
			(xy 461.44359 8.731535) (xy 461.38022 8.789304) (xy 461.322451 8.852674) (xy 461.270775 8.921103)
			(xy 461.225634 8.994009) (xy 461.187412 9.070769) (xy 461.156436 9.150728) (xy 461.132969 9.233204)
			(xy 461.117213 9.317494) (xy 461.109301 9.402877) (xy 456.614035 9.402877) (xy 456.606123 9.317494)
			(xy 456.590367 9.233204) (xy 456.5669 9.150728) (xy 456.535924 9.070769) (xy 456.497702 8.994009)
			(xy 456.452561 8.921103) (xy 456.400885 8.852674) (xy 456.343116 8.789304) (xy 456.279746 8.731535)
			(xy 456.211317 8.679859) (xy 456.138411 8.634718) (xy 456.061651 8.596496) (xy 455.981692 8.56552)
			(xy 455.899216 8.542053) (xy 455.814926 8.526297) (xy 455.729543 8.518385) (xy 455.643793 8.518385)
			(xy 455.55841 8.526297) (xy 455.47412 8.542053) (xy 455.391644 8.56552) (xy 455.311685 8.596496)
			(xy 455.234925 8.634718) (xy 455.162019 8.679859) (xy 455.09359 8.731535) (xy 455.03022 8.789304)
			(xy 454.972451 8.852674) (xy 454.920775 8.921103) (xy 454.875634 8.994009) (xy 454.837412 9.070769)
			(xy 454.806436 9.150728) (xy 454.782969 9.233204) (xy 454.767213 9.317494) (xy 454.759301 9.402877)
			(xy 404.76379 9.402877) (xy 404.763491 9.376969) (xy 404.755579 9.291586) (xy 404.739823 9.207296)
			(xy 404.716356 9.12482) (xy 404.68538 9.044861) (xy 404.647158 8.968101) (xy 404.602017 8.895195)
			(xy 404.550341 8.826766) (xy 404.492572 8.763396) (xy 404.429202 8.705627) (xy 404.360773 8.653951)
			(xy 404.287867 8.60881) (xy 404.211107 8.570588) (xy 404.131148 8.539612) (xy 404.048672 8.516145)
			(xy 403.964382 8.500389) (xy 403.878999 8.492477) (xy 403.793249 8.492477) (xy 403.707866 8.500389)
			(xy 403.623576 8.516145) (xy 403.5411 8.539612) (xy 403.461141 8.570588) (xy 403.384381 8.60881)
			(xy 403.311475 8.653951) (xy 403.243046 8.705627) (xy 403.179676 8.763396) (xy 403.121907 8.826766)
			(xy 403.070231 8.895195) (xy 403.02509 8.968101) (xy 402.986868 9.044861) (xy 402.955892 9.12482)
			(xy 402.932425 9.207296) (xy 402.916669 9.291586) (xy 402.908757 9.376969) (xy 398.413491 9.376969)
			(xy 398.405579 9.291586) (xy 398.389823 9.207296) (xy 398.366356 9.12482) (xy 398.33538 9.044861)
			(xy 398.297158 8.968101) (xy 398.252017 8.895195) (xy 398.200341 8.826766) (xy 398.142572 8.763396)
			(xy 398.079202 8.705627) (xy 398.010773 8.653951) (xy 397.937867 8.60881) (xy 397.861107 8.570588)
			(xy 397.781148 8.539612) (xy 397.698672 8.516145) (xy 397.614382 8.500389) (xy 397.528999 8.492477)
			(xy 397.443249 8.492477) (xy 397.357866 8.500389) (xy 397.273576 8.516145) (xy 397.1911 8.539612)
			(xy 397.111141 8.570588) (xy 397.034381 8.60881) (xy 396.961475 8.653951) (xy 396.893046 8.705627)
			(xy 396.829676 8.763396) (xy 396.771907 8.826766) (xy 396.720231 8.895195) (xy 396.67509 8.968101)
			(xy 396.636868 9.044861) (xy 396.605892 9.12482) (xy 396.582425 9.207296) (xy 396.566669 9.291586)
			(xy 396.558757 9.376969) (xy 390.701117 9.376969) (xy 390.701035 9.369857) (xy 390.693123 9.284474)
			(xy 390.677367 9.200184) (xy 390.6539 9.117708) (xy 390.622924 9.037749) (xy 390.584702 8.960989)
			(xy 390.539561 8.888083) (xy 390.487885 8.819654) (xy 390.430116 8.756284) (xy 390.366746 8.698515)
			(xy 390.298317 8.646839) (xy 390.225411 8.601698) (xy 390.148651 8.563476) (xy 390.068692 8.5325)
			(xy 389.986216 8.509033) (xy 389.901926 8.493277) (xy 389.816543 8.485365) (xy 389.730793 8.485365)
			(xy 389.64541 8.493277) (xy 389.56112 8.509033) (xy 389.478644 8.5325) (xy 389.398685 8.563476) (xy 389.321925 8.601698)
			(xy 389.249019 8.646839) (xy 389.18059 8.698515) (xy 389.11722 8.756284) (xy 389.059451 8.819654)
			(xy 389.007775 8.888083) (xy 388.962634 8.960989) (xy 388.924412 9.037749) (xy 388.893436 9.117708)
			(xy 388.869969 9.200184) (xy 388.854213 9.284474) (xy 388.846301 9.369857) (xy 384.351035 9.369857)
			(xy 384.343123 9.284474) (xy 384.327367 9.200184) (xy 384.3039 9.117708) (xy 384.272924 9.037749)
			(xy 384.234702 8.960989) (xy 384.189561 8.888083) (xy 384.137885 8.819654) (xy 384.080116 8.756284)
			(xy 384.016746 8.698515) (xy 383.948317 8.646839) (xy 383.875411 8.601698) (xy 383.798651 8.563476)
			(xy 383.718692 8.5325) (xy 383.636216 8.509033) (xy 383.551926 8.493277) (xy 383.466543 8.485365)
			(xy 383.380793 8.485365) (xy 383.29541 8.493277) (xy 383.21112 8.509033) (xy 383.128644 8.5325) (xy 383.048685 8.563476)
			(xy 382.971925 8.601698) (xy 382.899019 8.646839) (xy 382.83059 8.698515) (xy 382.76722 8.756284)
			(xy 382.709451 8.819654) (xy 382.657775 8.888083) (xy 382.612634 8.960989) (xy 382.574412 9.037749)
			(xy 382.543436 9.117708) (xy 382.519969 9.200184) (xy 382.504213 9.284474) (xy 382.496301 9.369857)
			(xy 332.50079 9.369857) (xy 332.500491 9.343949) (xy 332.492579 9.258566) (xy 332.476823 9.174276)
			(xy 332.453356 9.0918) (xy 332.42238 9.011841) (xy 332.384158 8.935081) (xy 332.339017 8.862175)
			(xy 332.287341 8.793746) (xy 332.229572 8.730376) (xy 332.166202 8.672607) (xy 332.097773 8.620931)
			(xy 332.024867 8.57579) (xy 331.948107 8.537568) (xy 331.868148 8.506592) (xy 331.785672 8.483125)
			(xy 331.701382 8.467369) (xy 331.615999 8.459457) (xy 331.530249 8.459457) (xy 331.444866 8.467369)
			(xy 331.360576 8.483125) (xy 331.2781 8.506592) (xy 331.198141 8.537568) (xy 331.121381 8.57579)
			(xy 331.048475 8.620931) (xy 330.980046 8.672607) (xy 330.916676 8.730376) (xy 330.858907 8.793746)
			(xy 330.807231 8.862175) (xy 330.76209 8.935081) (xy 330.723868 9.011841) (xy 330.692892 9.0918)
			(xy 330.669425 9.174276) (xy 330.653669 9.258566) (xy 330.645757 9.343949) (xy 326.150491 9.343949)
			(xy 326.142579 9.258566) (xy 326.126823 9.174276) (xy 326.103356 9.0918) (xy 326.07238 9.011841)
			(xy 326.034158 8.935081) (xy 325.989017 8.862175) (xy 325.937341 8.793746) (xy 325.879572 8.730376)
			(xy 325.816202 8.672607) (xy 325.747773 8.620931) (xy 325.674867 8.57579) (xy 325.598107 8.537568)
			(xy 325.518148 8.506592) (xy 325.435672 8.483125) (xy 325.351382 8.467369) (xy 325.265999 8.459457)
			(xy 325.180249 8.459457) (xy 325.094866 8.467369) (xy 325.010576 8.483125) (xy 324.9281 8.506592)
			(xy 324.848141 8.537568) (xy 324.771381 8.57579) (xy 324.698475 8.620931) (xy 324.630046 8.672607)
			(xy 324.566676 8.730376) (xy 324.508907 8.793746) (xy 324.457231 8.862175) (xy 324.41209 8.935081)
			(xy 324.373868 9.011841) (xy 324.342892 9.0918) (xy 324.319425 9.174276) (xy 324.303669 9.258566)
			(xy 324.295757 9.343949) (xy 317.930117 9.343949) (xy 317.930035 9.336837) (xy 317.922123 9.251454)
			(xy 317.906367 9.167164) (xy 317.8829 9.084688) (xy 317.851924 9.004729) (xy 317.813702 8.927969)
			(xy 317.768561 8.855063) (xy 317.716885 8.786634) (xy 317.659116 8.723264) (xy 317.595746 8.665495)
			(xy 317.527317 8.613819) (xy 317.454411 8.568678) (xy 317.377651 8.530456) (xy 317.297692 8.49948)
			(xy 317.215216 8.476013) (xy 317.130926 8.460257) (xy 317.045543 8.452345) (xy 316.959793 8.452345)
			(xy 316.87441 8.460257) (xy 316.79012 8.476013) (xy 316.707644 8.49948) (xy 316.627685 8.530456)
			(xy 316.550925 8.568678) (xy 316.478019 8.613819) (xy 316.40959 8.665495) (xy 316.34622 8.723264)
			(xy 316.288451 8.786634) (xy 316.236775 8.855063) (xy 316.191634 8.927969) (xy 316.153412 9.004729)
			(xy 316.122436 9.084688) (xy 316.098969 9.167164) (xy 316.083213 9.251454) (xy 316.075301 9.336837)
			(xy 311.580035 9.336837) (xy 311.572123 9.251454) (xy 311.556367 9.167164) (xy 311.5329 9.084688)
			(xy 311.501924 9.004729) (xy 311.463702 8.927969) (xy 311.418561 8.855063) (xy 311.366885 8.786634)
			(xy 311.309116 8.723264) (xy 311.245746 8.665495) (xy 311.177317 8.613819) (xy 311.104411 8.568678)
			(xy 311.027651 8.530456) (xy 310.947692 8.49948) (xy 310.865216 8.476013) (xy 310.780926 8.460257)
			(xy 310.695543 8.452345) (xy 310.609793 8.452345) (xy 310.52441 8.460257) (xy 310.44012 8.476013)
			(xy 310.357644 8.49948) (xy 310.277685 8.530456) (xy 310.200925 8.568678) (xy 310.128019 8.613819)
			(xy 310.05959 8.665495) (xy 309.99622 8.723264) (xy 309.938451 8.786634) (xy 309.886775 8.855063)
			(xy 309.841634 8.927969) (xy 309.803412 9.004729) (xy 309.772436 9.084688) (xy 309.748969 9.167164)
			(xy 309.733213 9.251454) (xy 309.725301 9.336837) (xy 259.72979 9.336837) (xy 259.729491 9.310929)
			(xy 259.721579 9.225546) (xy 259.705823 9.141256) (xy 259.682356 9.05878) (xy 259.65138 8.978821)
			(xy 259.613158 8.902061) (xy 259.568017 8.829155) (xy 259.516341 8.760726) (xy 259.458572 8.697356)
			(xy 259.395202 8.639587) (xy 259.326773 8.587911) (xy 259.253867 8.54277) (xy 259.177107 8.504548)
			(xy 259.097148 8.473572) (xy 259.014672 8.450105) (xy 258.930382 8.434349) (xy 258.844999 8.426437)
			(xy 258.759249 8.426437) (xy 258.673866 8.434349) (xy 258.589576 8.450105) (xy 258.5071 8.473572)
			(xy 258.427141 8.504548) (xy 258.350381 8.54277) (xy 258.277475 8.587911) (xy 258.209046 8.639587)
			(xy 258.145676 8.697356) (xy 258.087907 8.760726) (xy 258.036231 8.829155) (xy 257.99109 8.902061)
			(xy 257.952868 8.978821) (xy 257.921892 9.05878) (xy 257.898425 9.141256) (xy 257.882669 9.225546)
			(xy 257.874757 9.310929) (xy 253.379491 9.310929) (xy 253.371579 9.225546) (xy 253.355823 9.141256)
			(xy 253.332356 9.05878) (xy 253.30138 8.978821) (xy 253.263158 8.902061) (xy 253.218017 8.829155)
			(xy 253.166341 8.760726) (xy 253.108572 8.697356) (xy 253.045202 8.639587) (xy 252.976773 8.587911)
			(xy 252.903867 8.54277) (xy 252.827107 8.504548) (xy 252.747148 8.473572) (xy 252.664672 8.450105)
			(xy 252.580382 8.434349) (xy 252.494999 8.426437) (xy 252.409249 8.426437) (xy 252.323866 8.434349)
			(xy 252.239576 8.450105) (xy 252.1571 8.473572) (xy 252.077141 8.504548) (xy 252.000381 8.54277)
			(xy 251.927475 8.587911) (xy 251.859046 8.639587) (xy 251.795676 8.697356) (xy 251.737907 8.760726)
			(xy 251.686231 8.829155) (xy 251.64109 8.902061) (xy 251.602868 8.978821) (xy 251.571892 9.05878)
			(xy 251.548425 9.141256) (xy 251.532669 9.225546) (xy 251.524757 9.310929) (xy 245.921117 9.310929)
			(xy 245.921035 9.303817) (xy 245.913123 9.218434) (xy 245.897367 9.134144) (xy 245.8739 9.051668)
			(xy 245.842924 8.971709) (xy 245.804702 8.894949) (xy 245.759561 8.822043) (xy 245.707885 8.753614)
			(xy 245.650116 8.690244) (xy 245.586746 8.632475) (xy 245.518317 8.580799) (xy 245.445411 8.535658)
			(xy 245.368651 8.497436) (xy 245.288692 8.46646) (xy 245.206216 8.442993) (xy 245.121926 8.427237)
			(xy 245.036543 8.419325) (xy 244.950793 8.419325) (xy 244.86541 8.427237) (xy 244.78112 8.442993)
			(xy 244.698644 8.46646) (xy 244.618685 8.497436) (xy 244.541925 8.535658) (xy 244.469019 8.580799)
			(xy 244.40059 8.632475) (xy 244.33722 8.690244) (xy 244.279451 8.753614) (xy 244.227775 8.822043)
			(xy 244.182634 8.894949) (xy 244.144412 8.971709) (xy 244.113436 9.051668) (xy 244.089969 9.134144)
			(xy 244.074213 9.218434) (xy 244.066301 9.303817) (xy 239.571035 9.303817) (xy 239.563123 9.218434)
			(xy 239.547367 9.134144) (xy 239.5239 9.051668) (xy 239.492924 8.971709) (xy 239.454702 8.894949)
			(xy 239.409561 8.822043) (xy 239.357885 8.753614) (xy 239.300116 8.690244) (xy 239.236746 8.632475)
			(xy 239.168317 8.580799) (xy 239.095411 8.535658) (xy 239.018651 8.497436) (xy 238.938692 8.46646)
			(xy 238.856216 8.442993) (xy 238.771926 8.427237) (xy 238.686543 8.419325) (xy 238.600793 8.419325)
			(xy 238.51541 8.427237) (xy 238.43112 8.442993) (xy 238.348644 8.46646) (xy 238.268685 8.497436)
			(xy 238.191925 8.535658) (xy 238.119019 8.580799) (xy 238.05059 8.632475) (xy 237.98722 8.690244)
			(xy 237.929451 8.753614) (xy 237.877775 8.822043) (xy 237.832634 8.894949) (xy 237.794412 8.971709)
			(xy 237.763436 9.051668) (xy 237.739969 9.134144) (xy 237.724213 9.218434) (xy 237.716301 9.303817)
			(xy 187.719832 9.303817) (xy 187.712579 9.225546) (xy 187.696823 9.141256) (xy 187.673356 9.05878)
			(xy 187.64238 8.978821) (xy 187.604158 8.902061) (xy 187.559017 8.829155) (xy 187.507341 8.760726)
			(xy 187.449572 8.697356) (xy 187.386202 8.639587) (xy 187.317773 8.587911) (xy 187.244867 8.54277)
			(xy 187.168107 8.504548) (xy 187.088148 8.473572) (xy 187.005672 8.450105) (xy 186.921382 8.434349)
			(xy 186.835999 8.426437) (xy 186.750249 8.426437) (xy 186.664866 8.434349) (xy 186.580576 8.450105)
			(xy 186.4981 8.473572) (xy 186.418141 8.504548) (xy 186.341381 8.54277) (xy 186.268475 8.587911)
			(xy 186.200046 8.639587) (xy 186.136676 8.697356) (xy 186.078907 8.760726) (xy 186.027231 8.829155)
			(xy 185.98209 8.902061) (xy 185.943868 8.978821) (xy 185.912892 9.05878) (xy 185.889425 9.141256)
			(xy 185.873669 9.225546) (xy 185.865757 9.310929) (xy 181.370491 9.310929) (xy 181.362579 9.225546)
			(xy 181.346823 9.141256) (xy 181.323356 9.05878) (xy 181.29238 8.978821) (xy 181.254158 8.902061)
			(xy 181.209017 8.829155) (xy 181.157341 8.760726) (xy 181.099572 8.697356) (xy 181.036202 8.639587)
			(xy 180.967773 8.587911) (xy 180.894867 8.54277) (xy 180.818107 8.504548) (xy 180.738148 8.473572)
			(xy 180.655672 8.450105) (xy 180.571382 8.434349) (xy 180.485999 8.426437) (xy 180.400249 8.426437)
			(xy 180.314866 8.434349) (xy 180.230576 8.450105) (xy 180.1481 8.473572) (xy 180.068141 8.504548)
			(xy 179.991381 8.54277) (xy 179.918475 8.587911) (xy 179.850046 8.639587) (xy 179.786676 8.697356)
			(xy 179.728907 8.760726) (xy 179.677231 8.829155) (xy 179.63209 8.902061) (xy 179.593868 8.978821)
			(xy 179.562892 9.05878) (xy 179.539425 9.141256) (xy 179.523669 9.225546) (xy 179.515757 9.310929)
			(xy 158.621984 9.310929) (xy 158.621984 8.377682) (xy 158.62149 8.307329) (xy 158.6136 8.166844)
			(xy 158.597845 8.027022) (xy 158.574274 7.888303) (xy 158.542963 7.751125) (xy 158.50401 7.615918)
			(xy 158.457537 7.483107) (xy 158.40369 7.353112) (xy 158.342638 7.22634) (xy 158.274575 7.103191)
			(xy 158.199714 6.984051) (xy 158.11829 6.869297) (xy 158.039844 6.770929) (xy 179.515757 6.770929)
			(xy 179.515757 6.856679) (xy 179.523669 6.942062) (xy 179.539425 7.026352) (xy 179.562892 7.108828)
			(xy 179.593868 7.188787) (xy 179.63209 7.265547) (xy 179.677231 7.338453) (xy 179.728907 7.406882)
			(xy 179.786676 7.470252) (xy 179.850046 7.528021) (xy 179.918475 7.579697) (xy 179.991381 7.624838)
			(xy 180.068141 7.66306) (xy 180.1481 7.694036) (xy 180.230576 7.717503) (xy 180.314866 7.733259)
			(xy 180.400249 7.741171) (xy 180.485999 7.741171) (xy 180.571382 7.733259) (xy 180.655672 7.717503)
			(xy 180.738148 7.694036) (xy 180.818107 7.66306) (xy 180.894867 7.624838) (xy 180.967773 7.579697)
			(xy 181.036202 7.528021) (xy 181.099572 7.470252) (xy 181.157341 7.406882) (xy 181.209017 7.338453)
			(xy 181.254158 7.265547) (xy 181.29238 7.188787) (xy 181.323356 7.108828) (xy 181.346823 7.026352)
			(xy 181.362579 6.942062) (xy 181.370491 6.856679) (xy 181.370986 6.813804) (xy 181.370491 6.770929)
			(xy 185.865757 6.770929) (xy 185.865757 6.856679) (xy 185.873669 6.942062) (xy 185.889425 7.026352)
			(xy 185.912892 7.108828) (xy 185.943868 7.188787) (xy 185.98209 7.265547) (xy 186.027231 7.338453)
			(xy 186.078907 7.406882) (xy 186.136676 7.470252) (xy 186.200046 7.528021) (xy 186.268475 7.579697)
			(xy 186.341381 7.624838) (xy 186.418141 7.66306) (xy 186.4981 7.694036) (xy 186.580576 7.717503)
			(xy 186.664866 7.733259) (xy 186.750249 7.741171) (xy 186.835999 7.741171) (xy 186.921382 7.733259)
			(xy 187.005672 7.717503) (xy 187.088148 7.694036) (xy 187.168107 7.66306) (xy 187.244867 7.624838)
			(xy 187.317773 7.579697) (xy 187.386202 7.528021) (xy 187.449572 7.470252) (xy 187.507341 7.406882)
			(xy 187.559017 7.338453) (xy 187.604158 7.265547) (xy 187.64238 7.188787) (xy 187.673356 7.108828)
			(xy 187.696823 7.026352) (xy 187.712579 6.942062) (xy 187.720491 6.856679) (xy 187.720986 6.813804)
			(xy 187.720491 6.770929) (xy 187.719832 6.763817) (xy 237.716301 6.763817) (xy 237.716301 6.849567)
			(xy 237.724213 6.93495) (xy 237.739969 7.01924) (xy 237.763436 7.101716) (xy 237.794412 7.181675)
			(xy 237.832634 7.258435) (xy 237.877775 7.331341) (xy 237.929451 7.39977) (xy 237.98722 7.46314)
			(xy 238.05059 7.520909) (xy 238.119019 7.572585) (xy 238.191925 7.617726) (xy 238.268685 7.655948)
			(xy 238.348644 7.686924) (xy 238.43112 7.710391) (xy 238.51541 7.726147) (xy 238.600793 7.734059)
			(xy 238.686543 7.734059) (xy 238.771926 7.726147) (xy 238.856216 7.710391) (xy 238.938692 7.686924)
			(xy 239.018651 7.655948) (xy 239.095411 7.617726) (xy 239.168317 7.572585) (xy 239.236746 7.520909)
			(xy 239.300116 7.46314) (xy 239.357885 7.39977) (xy 239.409561 7.331341) (xy 239.454702 7.258435)
			(xy 239.492924 7.181675) (xy 239.5239 7.101716) (xy 239.547367 7.01924) (xy 239.563123 6.93495) (xy 239.571035 6.849567)
			(xy 239.57153 6.806692) (xy 239.571035 6.763817) (xy 244.066301 6.763817) (xy 244.066301 6.849567)
			(xy 244.074213 6.93495) (xy 244.089969 7.01924) (xy 244.113436 7.101716) (xy 244.144412 7.181675)
			(xy 244.182634 7.258435) (xy 244.227775 7.331341) (xy 244.279451 7.39977) (xy 244.33722 7.46314)
			(xy 244.40059 7.520909) (xy 244.469019 7.572585) (xy 244.541925 7.617726) (xy 244.618685 7.655948)
			(xy 244.698644 7.686924) (xy 244.78112 7.710391) (xy 244.86541 7.726147) (xy 244.950793 7.734059)
			(xy 245.036543 7.734059) (xy 245.121926 7.726147) (xy 245.206216 7.710391) (xy 245.288692 7.686924)
			(xy 245.368651 7.655948) (xy 245.445411 7.617726) (xy 245.518317 7.572585) (xy 245.586746 7.520909)
			(xy 245.650116 7.46314) (xy 245.707885 7.39977) (xy 245.759561 7.331341) (xy 245.804702 7.258435)
			(xy 245.842924 7.181675) (xy 245.8739 7.101716) (xy 245.897367 7.01924) (xy 245.913123 6.93495) (xy 245.921035 6.849567)
			(xy 245.92153 6.806692) (xy 245.921117 6.770929) (xy 251.524757 6.770929) (xy 251.524757 6.856679)
			(xy 251.532669 6.942062) (xy 251.548425 7.026352) (xy 251.571892 7.108828) (xy 251.602868 7.188787)
			(xy 251.64109 7.265547) (xy 251.686231 7.338453) (xy 251.737907 7.406882) (xy 251.795676 7.470252)
			(xy 251.859046 7.528021) (xy 251.927475 7.579697) (xy 252.000381 7.624838) (xy 252.077141 7.66306)
			(xy 252.1571 7.694036) (xy 252.239576 7.717503) (xy 252.323866 7.733259) (xy 252.409249 7.741171)
			(xy 252.494999 7.741171) (xy 252.580382 7.733259) (xy 252.664672 7.717503) (xy 252.747148 7.694036)
			(xy 252.827107 7.66306) (xy 252.84931 7.652004) (xy 256.459736 7.652004) (xy 256.459736 8.515604)
			(xy 256.460222 8.542873) (xy 256.467984 8.596857) (xy 256.483349 8.649187) (xy 256.506006 8.698797)
			(xy 256.535492 8.744678) (xy 256.571207 8.785895) (xy 256.612424 8.82161) (xy 256.658305 8.851096)
			(xy 256.707915 8.873753) (xy 256.760245 8.889118) (xy 256.814229 8.89688) (xy 256.868767 8.89688)
			(xy 256.922751 8.889118) (xy 256.975081 8.873753) (xy 257.024691 8.851096) (xy 257.070572 8.82161)
			(xy 257.111789 8.785895) (xy 257.147504 8.744678) (xy 257.17699 8.698797) (xy 257.199647 8.649187)
			(xy 257.215012 8.596857) (xy 257.222774 8.542873) (xy 257.22326 8.515604) (xy 257.22326 7.652004)
			(xy 257.222774 7.624735) (xy 257.215012 7.570751) (xy 257.199647 7.518421) (xy 257.17699 7.468811)
			(xy 257.147504 7.42293) (xy 257.111789 7.381713) (xy 257.070572 7.345998) (xy 257.024691 7.316512)
			(xy 256.975081 7.293855) (xy 256.922751 7.27849) (xy 256.868767 7.270728) (xy 256.814229 7.270728)
			(xy 256.760245 7.27849) (xy 256.707915 7.293855) (xy 256.658305 7.316512) (xy 256.612424 7.345998)
			(xy 256.571207 7.381713) (xy 256.535492 7.42293) (xy 256.506006 7.468811) (xy 256.483349 7.518421)
			(xy 256.467984 7.570751) (xy 256.460222 7.624735) (xy 256.459736 7.652004) (xy 252.84931 7.652004)
			(xy 252.903867 7.624838) (xy 252.976773 7.579697) (xy 253.045202 7.528021) (xy 253.108572 7.470252)
			(xy 253.166341 7.406882) (xy 253.218017 7.338453) (xy 253.263158 7.265547) (xy 253.30138 7.188787)
			(xy 253.332356 7.108828) (xy 253.355823 7.026352) (xy 253.371579 6.942062) (xy 253.379491 6.856679)
			(xy 253.379986 6.813804) (xy 253.379491 6.770929) (xy 257.874757 6.770929) (xy 257.874757 6.856679)
			(xy 257.882669 6.942062) (xy 257.898425 7.026352) (xy 257.921892 7.108828) (xy 257.952868 7.188787)
			(xy 257.99109 7.265547) (xy 258.036231 7.338453) (xy 258.087907 7.406882) (xy 258.145676 7.470252)
			(xy 258.209046 7.528021) (xy 258.277475 7.579697) (xy 258.350381 7.624838) (xy 258.427141 7.66306)
			(xy 258.5071 7.694036) (xy 258.589576 7.717503) (xy 258.673866 7.733259) (xy 258.759249 7.741171)
			(xy 258.844999 7.741171) (xy 258.930382 7.733259) (xy 259.014672 7.717503) (xy 259.097148 7.694036)
			(xy 259.177107 7.66306) (xy 259.253867 7.624838) (xy 259.326773 7.579697) (xy 259.395202 7.528021)
			(xy 259.458572 7.470252) (xy 259.516341 7.406882) (xy 259.568017 7.338453) (xy 259.613158 7.265547)
			(xy 259.65138 7.188787) (xy 259.682356 7.108828) (xy 259.705823 7.026352) (xy 259.721579 6.942062)
			(xy 259.729491 6.856679) (xy 259.729986 6.813804) (xy 259.72979 6.796837) (xy 309.725301 6.796837)
			(xy 309.725301 6.882587) (xy 309.733213 6.96797) (xy 309.748969 7.05226) (xy 309.772436 7.134736)
			(xy 309.803412 7.214695) (xy 309.841634 7.291455) (xy 309.886775 7.364361) (xy 309.938451 7.43279)
			(xy 309.99622 7.49616) (xy 310.05959 7.553929) (xy 310.128019 7.605605) (xy 310.200925 7.650746)
			(xy 310.277685 7.688968) (xy 310.357644 7.719944) (xy 310.44012 7.743411) (xy 310.52441 7.759167)
			(xy 310.609793 7.767079) (xy 310.695543 7.767079) (xy 310.780926 7.759167) (xy 310.865216 7.743411)
			(xy 310.947692 7.719944) (xy 311.027651 7.688968) (xy 311.049854 7.677912) (xy 312.231532 7.677912)
			(xy 312.231532 8.541512) (xy 312.232018 8.568781) (xy 312.23978 8.622765) (xy 312.255145 8.675095)
			(xy 312.277802 8.724705) (xy 312.307288 8.770586) (xy 312.343003 8.811803) (xy 312.38422 8.847518)
			(xy 312.430101 8.877004) (xy 312.479711 8.899661) (xy 312.532041 8.915026) (xy 312.586025 8.922788)
			(xy 312.640563 8.922788) (xy 312.694547 8.915026) (xy 312.746877 8.899661) (xy 312.796487 8.877004)
			(xy 312.842368 8.847518) (xy 312.883585 8.811803) (xy 312.9193 8.770586) (xy 312.948786 8.724705)
			(xy 312.971443 8.675095) (xy 312.986808 8.622765) (xy 312.99457 8.568781) (xy 312.995056 8.541512)
			(xy 312.995056 7.677912) (xy 312.99457 7.650643) (xy 312.986808 7.596659) (xy 312.971443 7.544329)
			(xy 312.948786 7.494719) (xy 312.9193 7.448838) (xy 312.883585 7.407621) (xy 312.842368 7.371906)
			(xy 312.796487 7.34242) (xy 312.746877 7.319763) (xy 312.694547 7.304398) (xy 312.640563 7.296636)
			(xy 312.586025 7.296636) (xy 312.532041 7.304398) (xy 312.479711 7.319763) (xy 312.430101 7.34242)
			(xy 312.38422 7.371906) (xy 312.343003 7.407621) (xy 312.307288 7.448838) (xy 312.277802 7.494719)
			(xy 312.255145 7.544329) (xy 312.23978 7.596659) (xy 312.232018 7.650643) (xy 312.231532 7.677912)
			(xy 311.049854 7.677912) (xy 311.104411 7.650746) (xy 311.177317 7.605605) (xy 311.245746 7.553929)
			(xy 311.309116 7.49616) (xy 311.366885 7.43279) (xy 311.418561 7.364361) (xy 311.463702 7.291455)
			(xy 311.501924 7.214695) (xy 311.5329 7.134736) (xy 311.556367 7.05226) (xy 311.572123 6.96797) (xy 311.580035 6.882587)
			(xy 311.58053 6.839712) (xy 311.580035 6.796837) (xy 316.075301 6.796837) (xy 316.075301 6.882587)
			(xy 316.083213 6.96797) (xy 316.098969 7.05226) (xy 316.122436 7.134736) (xy 316.153412 7.214695)
			(xy 316.191634 7.291455) (xy 316.236775 7.364361) (xy 316.288451 7.43279) (xy 316.34622 7.49616)
			(xy 316.40959 7.553929) (xy 316.478019 7.605605) (xy 316.550925 7.650746) (xy 316.627685 7.688968)
			(xy 316.707644 7.719944) (xy 316.79012 7.743411) (xy 316.87441 7.759167) (xy 316.959793 7.767079)
			(xy 317.045543 7.767079) (xy 317.130926 7.759167) (xy 317.215216 7.743411) (xy 317.297692 7.719944)
			(xy 317.377651 7.688968) (xy 317.454411 7.650746) (xy 317.527317 7.605605) (xy 317.595746 7.553929)
			(xy 317.659116 7.49616) (xy 317.716885 7.43279) (xy 317.768561 7.364361) (xy 317.813702 7.291455)
			(xy 317.851924 7.214695) (xy 317.8829 7.134736) (xy 317.906367 7.05226) (xy 317.922123 6.96797) (xy 317.930035 6.882587)
			(xy 317.93053 6.839712) (xy 317.930117 6.803949) (xy 324.295757 6.803949) (xy 324.295757 6.889699)
			(xy 324.303669 6.975082) (xy 324.319425 7.059372) (xy 324.342892 7.141848) (xy 324.373868 7.221807)
			(xy 324.41209 7.298567) (xy 324.457231 7.371473) (xy 324.508907 7.439902) (xy 324.566676 7.503272)
			(xy 324.630046 7.561041) (xy 324.698475 7.612717) (xy 324.771381 7.657858) (xy 324.848141 7.69608)
			(xy 324.9281 7.727056) (xy 325.010576 7.750523) (xy 325.094866 7.766279) (xy 325.180249 7.774191)
			(xy 325.265999 7.774191) (xy 325.351382 7.766279) (xy 325.435672 7.750523) (xy 325.518148 7.727056)
			(xy 325.598107 7.69608) (xy 325.62031 7.685024) (xy 329.230736 7.685024) (xy 329.230736 8.548624)
			(xy 329.231222 8.575893) (xy 329.238984 8.629877) (xy 329.254349 8.682207) (xy 329.277006 8.731817)
			(xy 329.306492 8.777698) (xy 329.342207 8.818915) (xy 329.383424 8.85463) (xy 329.429305 8.884116)
			(xy 329.478915 8.906773) (xy 329.531245 8.922138) (xy 329.585229 8.9299) (xy 329.639767 8.9299) (xy 329.693751 8.922138)
			(xy 329.746081 8.906773) (xy 329.795691 8.884116) (xy 329.841572 8.85463) (xy 329.882789 8.818915)
			(xy 329.918504 8.777698) (xy 329.94799 8.731817) (xy 329.970647 8.682207) (xy 329.986012 8.629877)
			(xy 329.993774 8.575893) (xy 329.99426 8.548624) (xy 329.99426 7.685024) (xy 329.993774 7.657755)
			(xy 329.986012 7.603771) (xy 329.970647 7.551441) (xy 329.94799 7.501831) (xy 329.918504 7.45595)
			(xy 329.882789 7.414733) (xy 329.841572 7.379018) (xy 329.795691 7.349532) (xy 329.746081 7.326875)
			(xy 329.693751 7.31151) (xy 329.639767 7.303748) (xy 329.585229 7.303748) (xy 329.531245 7.31151)
			(xy 329.478915 7.326875) (xy 329.429305 7.349532) (xy 329.383424 7.379018) (xy 329.342207 7.414733)
			(xy 329.306492 7.45595) (xy 329.277006 7.501831) (xy 329.254349 7.551441) (xy 329.238984 7.603771)
			(xy 329.231222 7.657755) (xy 329.230736 7.685024) (xy 325.62031 7.685024) (xy 325.674867 7.657858)
			(xy 325.747773 7.612717) (xy 325.816202 7.561041) (xy 325.879572 7.503272) (xy 325.937341 7.439902)
			(xy 325.989017 7.371473) (xy 326.034158 7.298567) (xy 326.07238 7.221807) (xy 326.103356 7.141848)
			(xy 326.126823 7.059372) (xy 326.142579 6.975082) (xy 326.150491 6.889699) (xy 326.150986 6.846824)
			(xy 326.150491 6.803949) (xy 330.645757 6.803949) (xy 330.645757 6.889699) (xy 330.653669 6.975082)
			(xy 330.669425 7.059372) (xy 330.692892 7.141848) (xy 330.723868 7.221807) (xy 330.76209 7.298567)
			(xy 330.807231 7.371473) (xy 330.858907 7.439902) (xy 330.916676 7.503272) (xy 330.980046 7.561041)
			(xy 331.048475 7.612717) (xy 331.121381 7.657858) (xy 331.198141 7.69608) (xy 331.2781 7.727056)
			(xy 331.360576 7.750523) (xy 331.444866 7.766279) (xy 331.530249 7.774191) (xy 331.615999 7.774191)
			(xy 331.701382 7.766279) (xy 331.785672 7.750523) (xy 331.868148 7.727056) (xy 331.948107 7.69608)
			(xy 332.024867 7.657858) (xy 332.097773 7.612717) (xy 332.166202 7.561041) (xy 332.229572 7.503272)
			(xy 332.287341 7.439902) (xy 332.339017 7.371473) (xy 332.384158 7.298567) (xy 332.42238 7.221807)
			(xy 332.453356 7.141848) (xy 332.476823 7.059372) (xy 332.492579 6.975082) (xy 332.500491 6.889699)
			(xy 332.500986 6.846824) (xy 332.50079 6.829857) (xy 382.496301 6.829857) (xy 382.496301 6.915607)
			(xy 382.504213 7.00099) (xy 382.519969 7.08528) (xy 382.543436 7.167756) (xy 382.574412 7.247715)
			(xy 382.612634 7.324475) (xy 382.657775 7.397381) (xy 382.709451 7.46581) (xy 382.76722 7.52918)
			(xy 382.83059 7.586949) (xy 382.899019 7.638625) (xy 382.971925 7.683766) (xy 383.048685 7.721988)
			(xy 383.128644 7.752964) (xy 383.21112 7.776431) (xy 383.29541 7.792187) (xy 383.380793 7.800099)
			(xy 383.466543 7.800099) (xy 383.551926 7.792187) (xy 383.636216 7.776431) (xy 383.718692 7.752964)
			(xy 383.798651 7.721988) (xy 383.820854 7.710932) (xy 385.002532 7.710932) (xy 385.002532 8.574532)
			(xy 385.003018 8.601801) (xy 385.01078 8.655785) (xy 385.026145 8.708115) (xy 385.048802 8.757725)
			(xy 385.078288 8.803606) (xy 385.114003 8.844823) (xy 385.15522 8.880538) (xy 385.201101 8.910024)
			(xy 385.250711 8.932681) (xy 385.303041 8.948046) (xy 385.357025 8.955808) (xy 385.411563 8.955808)
			(xy 385.465547 8.948046) (xy 385.517877 8.932681) (xy 385.567487 8.910024) (xy 385.613368 8.880538)
			(xy 385.654585 8.844823) (xy 385.6903 8.803606) (xy 385.719786 8.757725) (xy 385.742443 8.708115)
			(xy 385.757808 8.655785) (xy 385.76557 8.601801) (xy 385.766056 8.574532) (xy 385.766056 7.710932)
			(xy 385.76557 7.683663) (xy 385.757808 7.629679) (xy 385.742443 7.577349) (xy 385.719786 7.527739)
			(xy 385.6903 7.481858) (xy 385.654585 7.440641) (xy 385.613368 7.404926) (xy 385.567487 7.37544)
			(xy 385.517877 7.352783) (xy 385.465547 7.337418) (xy 385.411563 7.329656) (xy 385.357025 7.329656)
			(xy 385.303041 7.337418) (xy 385.250711 7.352783) (xy 385.201101 7.37544) (xy 385.15522 7.404926)
			(xy 385.114003 7.440641) (xy 385.078288 7.481858) (xy 385.048802 7.527739) (xy 385.026145 7.577349)
			(xy 385.01078 7.629679) (xy 385.003018 7.683663) (xy 385.002532 7.710932) (xy 383.820854 7.710932)
			(xy 383.875411 7.683766) (xy 383.948317 7.638625) (xy 384.016746 7.586949) (xy 384.080116 7.52918)
			(xy 384.137885 7.46581) (xy 384.189561 7.397381) (xy 384.234702 7.324475) (xy 384.272924 7.247715)
			(xy 384.3039 7.167756) (xy 384.327367 7.08528) (xy 384.343123 7.00099) (xy 384.351035 6.915607) (xy 384.35153 6.872732)
			(xy 384.351035 6.829857) (xy 388.846301 6.829857) (xy 388.846301 6.915607) (xy 388.854213 7.00099)
			(xy 388.869969 7.08528) (xy 388.893436 7.167756) (xy 388.924412 7.247715) (xy 388.962634 7.324475)
			(xy 389.007775 7.397381) (xy 389.059451 7.46581) (xy 389.11722 7.52918) (xy 389.18059 7.586949) (xy 389.249019 7.638625)
			(xy 389.321925 7.683766) (xy 389.398685 7.721988) (xy 389.478644 7.752964) (xy 389.56112 7.776431)
			(xy 389.64541 7.792187) (xy 389.730793 7.800099) (xy 389.816543 7.800099) (xy 389.901926 7.792187)
			(xy 389.986216 7.776431) (xy 390.068692 7.752964) (xy 390.148651 7.721988) (xy 390.225411 7.683766)
			(xy 390.298317 7.638625) (xy 390.366746 7.586949) (xy 390.430116 7.52918) (xy 390.487885 7.46581)
			(xy 390.539561 7.397381) (xy 390.584702 7.324475) (xy 390.622924 7.247715) (xy 390.6539 7.167756)
			(xy 390.677367 7.08528) (xy 390.693123 7.00099) (xy 390.701035 6.915607) (xy 390.70153 6.872732)
			(xy 390.701117 6.836969) (xy 396.558757 6.836969) (xy 396.558757 6.922719) (xy 396.566669 7.008102)
			(xy 396.582425 7.092392) (xy 396.605892 7.174868) (xy 396.636868 7.254827) (xy 396.67509 7.331587)
			(xy 396.720231 7.404493) (xy 396.771907 7.472922) (xy 396.829676 7.536292) (xy 396.893046 7.594061)
			(xy 396.961475 7.645737) (xy 397.034381 7.690878) (xy 397.111141 7.7291) (xy 397.1911 7.760076) (xy 397.273576 7.783543)
			(xy 397.357866 7.799299) (xy 397.443249 7.807211) (xy 397.528999 7.807211) (xy 397.614382 7.799299)
			(xy 397.698672 7.783543) (xy 397.781148 7.760076) (xy 397.861107 7.7291) (xy 397.88331 7.718044)
			(xy 401.493736 7.718044) (xy 401.493736 8.581644) (xy 401.494222 8.608913) (xy 401.501984 8.662897)
			(xy 401.517349 8.715227) (xy 401.540006 8.764837) (xy 401.569492 8.810718) (xy 401.605207 8.851935)
			(xy 401.646424 8.88765) (xy 401.692305 8.917136) (xy 401.741915 8.939793) (xy 401.794245 8.955158)
			(xy 401.848229 8.96292) (xy 401.902767 8.96292) (xy 401.956751 8.955158) (xy 402.009081 8.939793)
			(xy 402.058691 8.917136) (xy 402.104572 8.88765) (xy 402.145789 8.851935) (xy 402.181504 8.810718)
			(xy 402.21099 8.764837) (xy 402.233647 8.715227) (xy 402.249012 8.662897) (xy 402.256774 8.608913)
			(xy 402.25726 8.581644) (xy 402.25726 7.718044) (xy 402.256774 7.690775) (xy 402.249012 7.636791)
			(xy 402.233647 7.584461) (xy 402.21099 7.534851) (xy 402.181504 7.48897) (xy 402.145789 7.447753)
			(xy 402.104572 7.412038) (xy 402.058691 7.382552) (xy 402.009081 7.359895) (xy 401.956751 7.34453)
			(xy 401.902767 7.336768) (xy 401.848229 7.336768) (xy 401.794245 7.34453) (xy 401.741915 7.359895)
			(xy 401.692305 7.382552) (xy 401.646424 7.412038) (xy 401.605207 7.447753) (xy 401.569492 7.48897)
			(xy 401.540006 7.534851) (xy 401.517349 7.584461) (xy 401.501984 7.636791) (xy 401.494222 7.690775)
			(xy 401.493736 7.718044) (xy 397.88331 7.718044) (xy 397.937867 7.690878) (xy 398.010773 7.645737)
			(xy 398.079202 7.594061) (xy 398.142572 7.536292) (xy 398.200341 7.472922) (xy 398.252017 7.404493)
			(xy 398.297158 7.331587) (xy 398.33538 7.254827) (xy 398.366356 7.174868) (xy 398.389823 7.092392)
			(xy 398.405579 7.008102) (xy 398.413491 6.922719) (xy 398.413986 6.879844) (xy 398.413491 6.836969)
			(xy 402.908757 6.836969) (xy 402.908757 6.922719) (xy 402.916669 7.008102) (xy 402.932425 7.092392)
			(xy 402.955892 7.174868) (xy 402.986868 7.254827) (xy 403.02509 7.331587) (xy 403.070231 7.404493)
			(xy 403.121907 7.472922) (xy 403.179676 7.536292) (xy 403.243046 7.594061) (xy 403.311475 7.645737)
			(xy 403.384381 7.690878) (xy 403.461141 7.7291) (xy 403.5411 7.760076) (xy 403.623576 7.783543) (xy 403.707866 7.799299)
			(xy 403.793249 7.807211) (xy 403.878999 7.807211) (xy 403.964382 7.799299) (xy 404.048672 7.783543)
			(xy 404.131148 7.760076) (xy 404.211107 7.7291) (xy 404.287867 7.690878) (xy 404.360773 7.645737)
			(xy 404.429202 7.594061) (xy 404.492572 7.536292) (xy 404.550341 7.472922) (xy 404.602017 7.404493)
			(xy 404.647158 7.331587) (xy 404.68538 7.254827) (xy 404.716356 7.174868) (xy 404.739823 7.092392)
			(xy 404.755579 7.008102) (xy 404.763491 6.922719) (xy 404.763986 6.879844) (xy 404.76379 6.862877)
			(xy 454.759301 6.862877) (xy 454.759301 6.948627) (xy 454.767213 7.03401) (xy 454.782969 7.1183)
			(xy 454.806436 7.200776) (xy 454.837412 7.280735) (xy 454.875634 7.357495) (xy 454.920775 7.430401)
			(xy 454.972451 7.49883) (xy 455.03022 7.5622) (xy 455.09359 7.619969) (xy 455.162019 7.671645) (xy 455.234925 7.716786)
			(xy 455.311685 7.755008) (xy 455.391644 7.785984) (xy 455.47412 7.809451) (xy 455.55841 7.825207)
			(xy 455.643793 7.833119) (xy 455.729543 7.833119) (xy 455.814926 7.825207) (xy 455.899216 7.809451)
			(xy 455.981692 7.785984) (xy 456.061651 7.755008) (xy 456.083854 7.743952) (xy 457.265532 7.743952)
			(xy 457.265532 8.607552) (xy 457.266018 8.634821) (xy 457.27378 8.688805) (xy 457.289145 8.741135)
			(xy 457.311802 8.790745) (xy 457.341288 8.836626) (xy 457.377003 8.877843) (xy 457.41822 8.913558)
			(xy 457.464101 8.943044) (xy 457.513711 8.965701) (xy 457.566041 8.981066) (xy 457.620025 8.988828)
			(xy 457.674563 8.988828) (xy 457.728547 8.981066) (xy 457.780877 8.965701) (xy 457.830487 8.943044)
			(xy 457.876368 8.913558) (xy 457.917585 8.877843) (xy 457.9533 8.836626) (xy 457.982786 8.790745)
			(xy 458.005443 8.741135) (xy 458.020808 8.688805) (xy 458.02857 8.634821) (xy 458.029056 8.607552)
			(xy 458.029056 7.743952) (xy 458.02857 7.716683) (xy 458.020808 7.662699) (xy 458.005443 7.610369)
			(xy 457.982786 7.560759) (xy 457.9533 7.514878) (xy 457.917585 7.473661) (xy 457.876368 7.437946)
			(xy 457.830487 7.40846) (xy 457.780877 7.385803) (xy 457.728547 7.370438) (xy 457.674563 7.362676)
			(xy 457.620025 7.362676) (xy 457.566041 7.370438) (xy 457.513711 7.385803) (xy 457.464101 7.40846)
			(xy 457.41822 7.437946) (xy 457.377003 7.473661) (xy 457.341288 7.514878) (xy 457.311802 7.560759)
			(xy 457.289145 7.610369) (xy 457.27378 7.662699) (xy 457.266018 7.716683) (xy 457.265532 7.743952)
			(xy 456.083854 7.743952) (xy 456.138411 7.716786) (xy 456.211317 7.671645) (xy 456.279746 7.619969)
			(xy 456.343116 7.5622) (xy 456.400885 7.49883) (xy 456.452561 7.430401) (xy 456.497702 7.357495)
			(xy 456.535924 7.280735) (xy 456.5669 7.200776) (xy 456.590367 7.1183) (xy 456.606123 7.03401) (xy 456.614035 6.948627)
			(xy 456.61453 6.905752) (xy 456.614035 6.862877) (xy 461.109301 6.862877) (xy 461.109301 6.948627)
			(xy 461.117213 7.03401) (xy 461.132969 7.1183) (xy 461.156436 7.200776) (xy 461.187412 7.280735)
			(xy 461.225634 7.357495) (xy 461.270775 7.430401) (xy 461.322451 7.49883) (xy 461.38022 7.5622) (xy 461.44359 7.619969)
			(xy 461.512019 7.671645) (xy 461.584925 7.716786) (xy 461.661685 7.755008) (xy 461.741644 7.785984)
			(xy 461.82412 7.809451) (xy 461.90841 7.825207) (xy 461.993793 7.833119) (xy 462.079543 7.833119)
			(xy 462.164926 7.825207) (xy 462.249216 7.809451) (xy 462.331692 7.785984) (xy 462.411651 7.755008)
			(xy 462.488411 7.716786) (xy 462.561317 7.671645) (xy 462.629746 7.619969) (xy 462.693116 7.5622)
			(xy 462.750885 7.49883) (xy 462.802561 7.430401) (xy 462.847702 7.357495) (xy 462.885924 7.280735)
			(xy 462.9169 7.200776) (xy 462.940367 7.1183) (xy 462.956123 7.03401) (xy 462.964035 6.948627) (xy 462.96453 6.905752)
			(xy 462.964035 6.862877) (xy 462.956123 6.777494) (xy 462.940367 6.693204) (xy 462.9169 6.610728)
			(xy 462.885924 6.530769) (xy 462.847702 6.454009) (xy 462.802561 6.381103) (xy 462.750885 6.312674)
			(xy 462.693116 6.249304) (xy 462.629746 6.191535) (xy 462.561317 6.139859) (xy 462.488411 6.094718)
			(xy 462.411651 6.056496) (xy 462.331692 6.02552) (xy 462.249216 6.002053) (xy 462.164926 5.986297)
			(xy 462.079543 5.978385) (xy 461.993793 5.978385) (xy 461.90841 5.986297) (xy 461.82412 6.002053)
			(xy 461.741644 6.02552) (xy 461.661685 6.056496) (xy 461.584925 6.094718) (xy 461.512019 6.139859)
			(xy 461.44359 6.191535) (xy 461.38022 6.249304) (xy 461.322451 6.312674) (xy 461.270775 6.381103)
			(xy 461.225634 6.454009) (xy 461.187412 6.530769) (xy 461.156436 6.610728) (xy 461.132969 6.693204)
			(xy 461.117213 6.777494) (xy 461.109301 6.862877) (xy 456.614035 6.862877) (xy 456.606123 6.777494)
			(xy 456.590367 6.693204) (xy 456.5669 6.610728) (xy 456.535924 6.530769) (xy 456.497702 6.454009)
			(xy 456.452561 6.381103) (xy 456.400885 6.312674) (xy 456.343116 6.249304) (xy 456.279746 6.191535)
			(xy 456.211317 6.139859) (xy 456.138411 6.094718) (xy 456.061651 6.056496) (xy 455.981692 6.02552)
			(xy 455.899216 6.002053) (xy 455.814926 5.986297) (xy 455.729543 5.978385) (xy 455.643793 5.978385)
			(xy 455.55841 5.986297) (xy 455.47412 6.002053) (xy 455.391644 6.02552) (xy 455.311685 6.056496)
			(xy 455.234925 6.094718) (xy 455.162019 6.139859) (xy 455.09359 6.191535) (xy 455.03022 6.249304)
			(xy 454.972451 6.312674) (xy 454.920775 6.381103) (xy 454.875634 6.454009) (xy 454.837412 6.530769)
			(xy 454.806436 6.610728) (xy 454.782969 6.693204) (xy 454.767213 6.777494) (xy 454.759301 6.862877)
			(xy 404.76379 6.862877) (xy 404.763491 6.836969) (xy 404.755579 6.751586) (xy 404.739823 6.667296)
			(xy 404.716356 6.58482) (xy 404.68538 6.504861) (xy 404.647158 6.428101) (xy 404.602017 6.355195)
			(xy 404.550341 6.286766) (xy 404.492572 6.223396) (xy 404.429202 6.165627) (xy 404.360773 6.113951)
			(xy 404.287867 6.06881) (xy 404.211107 6.030588) (xy 404.131148 5.999612) (xy 404.048672 5.976145)
			(xy 403.964382 5.960389) (xy 403.878999 5.952477) (xy 403.793249 5.952477) (xy 403.707866 5.960389)
			(xy 403.623576 5.976145) (xy 403.5411 5.999612) (xy 403.461141 6.030588) (xy 403.384381 6.06881)
			(xy 403.311475 6.113951) (xy 403.243046 6.165627) (xy 403.179676 6.223396) (xy 403.121907 6.286766)
			(xy 403.070231 6.355195) (xy 403.02509 6.428101) (xy 402.986868 6.504861) (xy 402.955892 6.58482)
			(xy 402.932425 6.667296) (xy 402.916669 6.751586) (xy 402.908757 6.836969) (xy 398.413491 6.836969)
			(xy 398.405579 6.751586) (xy 398.389823 6.667296) (xy 398.366356 6.58482) (xy 398.33538 6.504861)
			(xy 398.297158 6.428101) (xy 398.252017 6.355195) (xy 398.200341 6.286766) (xy 398.142572 6.223396)
			(xy 398.079202 6.165627) (xy 398.010773 6.113951) (xy 397.937867 6.06881) (xy 397.861107 6.030588)
			(xy 397.781148 5.999612) (xy 397.698672 5.976145) (xy 397.614382 5.960389) (xy 397.528999 5.952477)
			(xy 397.443249 5.952477) (xy 397.357866 5.960389) (xy 397.273576 5.976145) (xy 397.1911 5.999612)
			(xy 397.111141 6.030588) (xy 397.034381 6.06881) (xy 396.961475 6.113951) (xy 396.893046 6.165627)
			(xy 396.829676 6.223396) (xy 396.771907 6.286766) (xy 396.720231 6.355195) (xy 396.67509 6.428101)
			(xy 396.636868 6.504861) (xy 396.605892 6.58482) (xy 396.582425 6.667296) (xy 396.566669 6.751586)
			(xy 396.558757 6.836969) (xy 390.701117 6.836969) (xy 390.701035 6.829857) (xy 390.693123 6.744474)
			(xy 390.677367 6.660184) (xy 390.6539 6.577708) (xy 390.622924 6.497749) (xy 390.584702 6.420989)
			(xy 390.539561 6.348083) (xy 390.487885 6.279654) (xy 390.430116 6.216284) (xy 390.366746 6.158515)
			(xy 390.298317 6.106839) (xy 390.225411 6.061698) (xy 390.148651 6.023476) (xy 390.068692 5.9925)
			(xy 389.986216 5.969033) (xy 389.901926 5.953277) (xy 389.816543 5.945365) (xy 389.730793 5.945365)
			(xy 389.64541 5.953277) (xy 389.56112 5.969033) (xy 389.478644 5.9925) (xy 389.398685 6.023476) (xy 389.321925 6.061698)
			(xy 389.249019 6.106839) (xy 389.18059 6.158515) (xy 389.11722 6.216284) (xy 389.059451 6.279654)
			(xy 389.007775 6.348083) (xy 388.962634 6.420989) (xy 388.924412 6.497749) (xy 388.893436 6.577708)
			(xy 388.869969 6.660184) (xy 388.854213 6.744474) (xy 388.846301 6.829857) (xy 384.351035 6.829857)
			(xy 384.343123 6.744474) (xy 384.327367 6.660184) (xy 384.3039 6.577708) (xy 384.272924 6.497749)
			(xy 384.234702 6.420989) (xy 384.189561 6.348083) (xy 384.137885 6.279654) (xy 384.080116 6.216284)
			(xy 384.016746 6.158515) (xy 383.948317 6.106839) (xy 383.875411 6.061698) (xy 383.798651 6.023476)
			(xy 383.718692 5.9925) (xy 383.636216 5.969033) (xy 383.551926 5.953277) (xy 383.466543 5.945365)
			(xy 383.380793 5.945365) (xy 383.29541 5.953277) (xy 383.21112 5.969033) (xy 383.128644 5.9925) (xy 383.048685 6.023476)
			(xy 382.971925 6.061698) (xy 382.899019 6.106839) (xy 382.83059 6.158515) (xy 382.76722 6.216284)
			(xy 382.709451 6.279654) (xy 382.657775 6.348083) (xy 382.612634 6.420989) (xy 382.574412 6.497749)
			(xy 382.543436 6.577708) (xy 382.519969 6.660184) (xy 382.504213 6.744474) (xy 382.496301 6.829857)
			(xy 332.50079 6.829857) (xy 332.500491 6.803949) (xy 332.492579 6.718566) (xy 332.476823 6.634276)
			(xy 332.453356 6.5518) (xy 332.42238 6.471841) (xy 332.384158 6.395081) (xy 332.339017 6.322175)
			(xy 332.287341 6.253746) (xy 332.229572 6.190376) (xy 332.166202 6.132607) (xy 332.097773 6.080931)
			(xy 332.024867 6.03579) (xy 331.948107 5.997568) (xy 331.868148 5.966592) (xy 331.785672 5.943125)
			(xy 331.701382 5.927369) (xy 331.615999 5.919457) (xy 331.530249 5.919457) (xy 331.444866 5.927369)
			(xy 331.360576 5.943125) (xy 331.2781 5.966592) (xy 331.198141 5.997568) (xy 331.121381 6.03579)
			(xy 331.048475 6.080931) (xy 330.980046 6.132607) (xy 330.916676 6.190376) (xy 330.858907 6.253746)
			(xy 330.807231 6.322175) (xy 330.76209 6.395081) (xy 330.723868 6.471841) (xy 330.692892 6.5518)
			(xy 330.669425 6.634276) (xy 330.653669 6.718566) (xy 330.645757 6.803949) (xy 326.150491 6.803949)
			(xy 326.142579 6.718566) (xy 326.126823 6.634276) (xy 326.103356 6.5518) (xy 326.07238 6.471841)
			(xy 326.034158 6.395081) (xy 325.989017 6.322175) (xy 325.937341 6.253746) (xy 325.879572 6.190376)
			(xy 325.816202 6.132607) (xy 325.747773 6.080931) (xy 325.674867 6.03579) (xy 325.598107 5.997568)
			(xy 325.518148 5.966592) (xy 325.435672 5.943125) (xy 325.351382 5.927369) (xy 325.265999 5.919457)
			(xy 325.180249 5.919457) (xy 325.094866 5.927369) (xy 325.010576 5.943125) (xy 324.9281 5.966592)
			(xy 324.848141 5.997568) (xy 324.771381 6.03579) (xy 324.698475 6.080931) (xy 324.630046 6.132607)
			(xy 324.566676 6.190376) (xy 324.508907 6.253746) (xy 324.457231 6.322175) (xy 324.41209 6.395081)
			(xy 324.373868 6.471841) (xy 324.342892 6.5518) (xy 324.319425 6.634276) (xy 324.303669 6.718566)
			(xy 324.295757 6.803949) (xy 317.930117 6.803949) (xy 317.930035 6.796837) (xy 317.922123 6.711454)
			(xy 317.906367 6.627164) (xy 317.8829 6.544688) (xy 317.851924 6.464729) (xy 317.813702 6.387969)
			(xy 317.768561 6.315063) (xy 317.716885 6.246634) (xy 317.659116 6.183264) (xy 317.595746 6.125495)
			(xy 317.527317 6.073819) (xy 317.454411 6.028678) (xy 317.377651 5.990456) (xy 317.297692 5.95948)
			(xy 317.215216 5.936013) (xy 317.130926 5.920257) (xy 317.045543 5.912345) (xy 316.959793 5.912345)
			(xy 316.87441 5.920257) (xy 316.79012 5.936013) (xy 316.707644 5.95948) (xy 316.627685 5.990456)
			(xy 316.550925 6.028678) (xy 316.478019 6.073819) (xy 316.40959 6.125495) (xy 316.34622 6.183264)
			(xy 316.288451 6.246634) (xy 316.236775 6.315063) (xy 316.191634 6.387969) (xy 316.153412 6.464729)
			(xy 316.122436 6.544688) (xy 316.098969 6.627164) (xy 316.083213 6.711454) (xy 316.075301 6.796837)
			(xy 311.580035 6.796837) (xy 311.572123 6.711454) (xy 311.556367 6.627164) (xy 311.5329 6.544688)
			(xy 311.501924 6.464729) (xy 311.463702 6.387969) (xy 311.418561 6.315063) (xy 311.366885 6.246634)
			(xy 311.309116 6.183264) (xy 311.245746 6.125495) (xy 311.177317 6.073819) (xy 311.104411 6.028678)
			(xy 311.027651 5.990456) (xy 310.947692 5.95948) (xy 310.865216 5.936013) (xy 310.780926 5.920257)
			(xy 310.695543 5.912345) (xy 310.609793 5.912345) (xy 310.52441 5.920257) (xy 310.44012 5.936013)
			(xy 310.357644 5.95948) (xy 310.277685 5.990456) (xy 310.200925 6.028678) (xy 310.128019 6.073819)
			(xy 310.05959 6.125495) (xy 309.99622 6.183264) (xy 309.938451 6.246634) (xy 309.886775 6.315063)
			(xy 309.841634 6.387969) (xy 309.803412 6.464729) (xy 309.772436 6.544688) (xy 309.748969 6.627164)
			(xy 309.733213 6.711454) (xy 309.725301 6.796837) (xy 259.72979 6.796837) (xy 259.729491 6.770929)
			(xy 259.721579 6.685546) (xy 259.705823 6.601256) (xy 259.682356 6.51878) (xy 259.65138 6.438821)
			(xy 259.613158 6.362061) (xy 259.568017 6.289155) (xy 259.516341 6.220726) (xy 259.458572 6.157356)
			(xy 259.395202 6.099587) (xy 259.326773 6.047911) (xy 259.253867 6.00277) (xy 259.177107 5.964548)
			(xy 259.097148 5.933572) (xy 259.014672 5.910105) (xy 258.930382 5.894349) (xy 258.844999 5.886437)
			(xy 258.759249 5.886437) (xy 258.673866 5.894349) (xy 258.589576 5.910105) (xy 258.5071 5.933572)
			(xy 258.427141 5.964548) (xy 258.350381 6.00277) (xy 258.277475 6.047911) (xy 258.209046 6.099587)
			(xy 258.145676 6.157356) (xy 258.087907 6.220726) (xy 258.036231 6.289155) (xy 257.99109 6.362061)
			(xy 257.952868 6.438821) (xy 257.921892 6.51878) (xy 257.898425 6.601256) (xy 257.882669 6.685546)
			(xy 257.874757 6.770929) (xy 253.379491 6.770929) (xy 253.371579 6.685546) (xy 253.355823 6.601256)
			(xy 253.332356 6.51878) (xy 253.30138 6.438821) (xy 253.263158 6.362061) (xy 253.218017 6.289155)
			(xy 253.166341 6.220726) (xy 253.108572 6.157356) (xy 253.045202 6.099587) (xy 252.976773 6.047911)
			(xy 252.903867 6.00277) (xy 252.827107 5.964548) (xy 252.747148 5.933572) (xy 252.664672 5.910105)
			(xy 252.580382 5.894349) (xy 252.494999 5.886437) (xy 252.409249 5.886437) (xy 252.323866 5.894349)
			(xy 252.239576 5.910105) (xy 252.1571 5.933572) (xy 252.077141 5.964548) (xy 252.000381 6.00277)
			(xy 251.927475 6.047911) (xy 251.859046 6.099587) (xy 251.795676 6.157356) (xy 251.737907 6.220726)
			(xy 251.686231 6.289155) (xy 251.64109 6.362061) (xy 251.602868 6.438821) (xy 251.571892 6.51878)
			(xy 251.548425 6.601256) (xy 251.532669 6.685546) (xy 251.524757 6.770929) (xy 245.921117 6.770929)
			(xy 245.921035 6.763817) (xy 245.913123 6.678434) (xy 245.897367 6.594144) (xy 245.8739 6.511668)
			(xy 245.842924 6.431709) (xy 245.804702 6.354949) (xy 245.759561 6.282043) (xy 245.707885 6.213614)
			(xy 245.650116 6.150244) (xy 245.586746 6.092475) (xy 245.518317 6.040799) (xy 245.445411 5.995658)
			(xy 245.368651 5.957436) (xy 245.288692 5.92646) (xy 245.206216 5.902993) (xy 245.121926 5.887237)
			(xy 245.036543 5.879325) (xy 244.950793 5.879325) (xy 244.86541 5.887237) (xy 244.78112 5.902993)
			(xy 244.698644 5.92646) (xy 244.618685 5.957436) (xy 244.541925 5.995658) (xy 244.469019 6.040799)
			(xy 244.40059 6.092475) (xy 244.33722 6.150244) (xy 244.279451 6.213614) (xy 244.227775 6.282043)
			(xy 244.182634 6.354949) (xy 244.144412 6.431709) (xy 244.113436 6.511668) (xy 244.089969 6.594144)
			(xy 244.074213 6.678434) (xy 244.066301 6.763817) (xy 239.571035 6.763817) (xy 239.563123 6.678434)
			(xy 239.547367 6.594144) (xy 239.5239 6.511668) (xy 239.492924 6.431709) (xy 239.454702 6.354949)
			(xy 239.409561 6.282043) (xy 239.357885 6.213614) (xy 239.300116 6.150244) (xy 239.236746 6.092475)
			(xy 239.168317 6.040799) (xy 239.095411 5.995658) (xy 239.018651 5.957436) (xy 238.938692 5.92646)
			(xy 238.856216 5.902993) (xy 238.771926 5.887237) (xy 238.686543 5.879325) (xy 238.600793 5.879325)
			(xy 238.51541 5.887237) (xy 238.43112 5.902993) (xy 238.348644 5.92646) (xy 238.268685 5.957436)
			(xy 238.191925 5.995658) (xy 238.119019 6.040799) (xy 238.05059 6.092475) (xy 237.98722 6.150244)
			(xy 237.929451 6.213614) (xy 237.877775 6.282043) (xy 237.832634 6.354949) (xy 237.794412 6.431709)
			(xy 237.763436 6.511668) (xy 237.739969 6.594144) (xy 237.724213 6.678434) (xy 237.716301 6.763817)
			(xy 187.719832 6.763817) (xy 187.712579 6.685546) (xy 187.696823 6.601256) (xy 187.673356 6.51878)
			(xy 187.64238 6.438821) (xy 187.604158 6.362061) (xy 187.559017 6.289155) (xy 187.507341 6.220726)
			(xy 187.449572 6.157356) (xy 187.386202 6.099587) (xy 187.317773 6.047911) (xy 187.244867 6.00277)
			(xy 187.168107 5.964548) (xy 187.088148 5.933572) (xy 187.005672 5.910105) (xy 186.921382 5.894349)
			(xy 186.835999 5.886437) (xy 186.750249 5.886437) (xy 186.664866 5.894349) (xy 186.580576 5.910105)
			(xy 186.4981 5.933572) (xy 186.418141 5.964548) (xy 186.341381 6.00277) (xy 186.268475 6.047911)
			(xy 186.200046 6.099587) (xy 186.136676 6.157356) (xy 186.078907 6.220726) (xy 186.027231 6.289155)
			(xy 185.98209 6.362061) (xy 185.943868 6.438821) (xy 185.912892 6.51878) (xy 185.889425 6.601256)
			(xy 185.873669 6.685546) (xy 185.865757 6.770929) (xy 181.370491 6.770929) (xy 181.362579 6.685546)
			(xy 181.346823 6.601256) (xy 181.323356 6.51878) (xy 181.29238 6.438821) (xy 181.254158 6.362061)
			(xy 181.209017 6.289155) (xy 181.157341 6.220726) (xy 181.099572 6.157356) (xy 181.036202 6.099587)
			(xy 180.967773 6.047911) (xy 180.894867 6.00277) (xy 180.818107 5.964548) (xy 180.738148 5.933572)
			(xy 180.655672 5.910105) (xy 180.571382 5.894349) (xy 180.485999 5.886437) (xy 180.400249 5.886437)
			(xy 180.314866 5.894349) (xy 180.230576 5.910105) (xy 180.1481 5.933572) (xy 180.068141 5.964548)
			(xy 179.991381 6.00277) (xy 179.918475 6.047911) (xy 179.850046 6.099587) (xy 179.786676 6.157356)
			(xy 179.728907 6.220726) (xy 179.677231 6.289155) (xy 179.63209 6.362061) (xy 179.593868 6.438821)
			(xy 179.562892 6.51878) (xy 179.539425 6.601256) (xy 179.523669 6.685546) (xy 179.515757 6.770929)
			(xy 158.039844 6.770929) (xy 158.030561 6.759289) (xy 157.936801 6.654373) (xy 157.837306 6.554879)
			(xy 157.732388 6.46112) (xy 157.622379 6.373391) (xy 157.507624 6.291969) (xy 157.388483 6.21711)
			(xy 157.265333 6.149048) (xy 157.138561 6.087998) (xy 157.008565 6.034153) (xy 156.875754 5.987681)
			(xy 156.740546 5.948729) (xy 156.603367 5.91742) (xy 156.464649 5.893851) (xy 156.324827 5.878098)
			(xy 156.184341 5.870209) (xy 156.113988 5.869686) (xy 17.493996 5.869686) (xy 17.423642 5.870179)
			(xy 17.283156 5.878069) (xy 17.143333 5.893824) (xy 17.004613 5.917393) (xy 16.867433 5.948703) (xy 16.732225 5.987656)
			(xy 16.599413 6.034129) (xy 16.469416 6.087976) (xy 16.342643 6.149026) (xy 16.219492 6.217089) (xy 16.100351 6.29195)
			(xy 15.985596 6.373373) (xy 15.875586 6.461103) (xy 15.770668 6.554863) (xy 15.671172 6.654358) (xy 15.577412 6.759275)
			(xy 15.489682 6.869284) (xy 15.408258 6.98404) (xy 15.333396 7.10318) (xy 15.265333 7.22633) (xy 15.204281 7.353103)
			(xy 15.150434 7.4831) (xy 15.103961 7.615912) (xy 15.065007 7.75112) (xy 15.033696 7.8883) (xy 15.010125 8.027019)
			(xy 14.99437 8.166842) (xy 14.98648 8.307328) (xy 14.986 8.377682) (xy 14.986 24.157686) (xy 14.985478 24.213493)
			(xy 14.977137 24.324795) (xy 14.960501 24.435162) (xy 14.935664 24.543977) (xy 14.902765 24.650632)
			(xy 14.861988 24.754531) (xy 14.81356 24.855091) (xy 14.757753 24.951752) (xy 14.694879 25.043971)
			(xy 14.625289 25.131234) (xy 14.549372 25.213053) (xy 14.467553 25.28897) (xy 14.38029 25.35856)
			(xy 14.28807 25.421434) (xy 14.19141 25.477241) (xy 14.090849 25.525669) (xy 13.986951 25.566446)
			(xy 13.880295 25.599345) (xy 13.77148 25.624182) (xy 13.661113 25.640817) (xy 13.549811 25.649158)
			(xy 13.494004 25.649682) (xy 1.999996 25.649682) (xy 1.944189 25.64916) (xy 1.832887 25.640819) (xy 1.72252 25.624184)
			(xy 1.613704 25.599347) (xy 1.507049 25.566448) (xy 1.40315 25.525671) (xy 1.30259 25.477243) (xy 1.205929 25.421436)
			(xy 1.113709 25.358562) (xy 1.026446 25.288971) (xy 0.944627 25.213055) (xy 0.86871 25.131236) (xy 0.79912 25.043972)
			(xy 0.736245 24.951753) (xy 0.680438 24.855092) (xy 0.63201 24.754532) (xy 0.591233 24.650633) (xy 0.558334 24.543978)
			(xy 0.533497 24.435162) (xy 0.516861 24.324795) (xy 0.50852 24.213493) (xy 0.508 24.157686) (xy 0.508 21.093122)
			(xy 2.904225 21.093122) (xy 2.904225 21.222262) (xy 2.912175 21.351157) (xy 2.928045 21.479317) (xy 2.951774 21.606258)
			(xy 2.983273 21.731497) (xy 3.022422 21.85456) (xy 3.069073 21.974979) (xy 3.123048 22.092298) (xy 3.184143 22.206072)
			(xy 3.252126 22.315869) (xy 3.32674 22.421272) (xy 3.407701 22.521882) (xy 3.494701 22.617317) (xy 3.587412 22.707216)
			(xy 3.685482 22.791237) (xy 3.788537 22.869061) (xy 3.896188 22.940393) (xy 4.008027 23.004963) (xy 4.123628 23.062525)
			(xy 4.242553 23.112862) (xy 4.364352 23.155782) (xy 4.488562 23.191123) (xy 4.614711 23.21875) (xy 4.742323 23.238559)
			(xy 4.870912 23.250475) (xy 4.99999 23.254452) (xy 5.129068 23.250475) (xy 5.257657 23.238559) (xy 5.385269 23.21875)
			(xy 5.511418 23.191123) (xy 5.635628 23.155782) (xy 5.757427 23.112862) (xy 5.876352 23.062525) (xy 5.991953 23.004963)
			(xy 6.103792 22.940393) (xy 6.211443 22.869061) (xy 6.314498 22.791237) (xy 6.412568 22.707216) (xy 6.505279 22.617317)
			(xy 6.592279 22.521882) (xy 6.67324 22.421272) (xy 6.747854 22.315869) (xy 6.815837 22.206072) (xy 6.876932 22.092298)
			(xy 6.930907 21.974979) (xy 6.977558 21.85456) (xy 7.016707 21.731497) (xy 7.048206 21.606258) (xy 7.071935 21.479317)
			(xy 7.087805 21.351157) (xy 7.095755 21.222262) (xy 7.096252 21.157692) (xy 7.095755 21.093122) (xy 7.087805 20.964227)
			(xy 7.071935 20.836067) (xy 7.048206 20.709126) (xy 7.016707 20.583887) (xy 6.977558 20.460824) (xy 6.930907 20.340405)
			(xy 6.876932 20.223086) (xy 6.815837 20.109312) (xy 6.747854 19.999515) (xy 6.67324 19.894112) (xy 6.592279 19.793502)
			(xy 6.505279 19.698067) (xy 6.412568 19.608168) (xy 6.314498 19.524147) (xy 6.211443 19.446323) (xy 6.103792 19.374991)
			(xy 5.991953 19.310421) (xy 5.876352 19.252859) (xy 5.757427 19.202522) (xy 5.635628 19.159602) (xy 5.511418 19.124261)
			(xy 5.385269 19.096634) (xy 5.257657 19.076825) (xy 5.129068 19.064909) (xy 4.99999 19.060933) (xy 4.870912 19.064909)
			(xy 4.742323 19.076825) (xy 4.614711 19.096634) (xy 4.488562 19.124261) (xy 4.364352 19.159602) (xy 4.242553 19.202522)
			(xy 4.123628 19.252859) (xy 4.008027 19.310421) (xy 3.896188 19.374991) (xy 3.788537 19.446323) (xy 3.685482 19.524147)
			(xy 3.587412 19.608168) (xy 3.494701 19.698067) (xy 3.407701 19.793502) (xy 3.32674 19.894112) (xy 3.252126 19.999515)
			(xy 3.184143 20.109312) (xy 3.123048 20.223086) (xy 3.069073 20.340405) (xy 3.022422 20.460824) (xy 2.983273 20.583887)
			(xy 2.951774 20.709126) (xy 2.928045 20.836067) (xy 2.912175 20.964227) (xy 2.904225 21.093122) (xy 0.508 21.093122)
			(xy 0.508 3.999992) (xy 0.508522 3.944185) (xy 0.516863 3.832883) (xy 0.533498 3.722516) (xy 0.558335 3.6137)
			(xy 0.591234 3.507045) (xy 0.632011 3.403146) (xy 0.680438 3.302586) (xy 0.736246 3.205925) (xy 0.79912 3.113705)
			(xy 0.86871 3.026442) (xy 0.944627 2.944623) (xy 1.026446 2.868706) (xy 1.113709 2.799116) (xy 1.205929 2.736242)
			(xy 1.30259 2.680434) (xy 1.40315 2.632007) (xy 1.507049 2.59123) (xy 1.613704 2.558331) (xy 1.72252 2.533494)
			(xy 1.832887 2.516859) (xy 1.944189 2.508518) (xy 1.999996 2.507996) (xy 7.964932 2.507996) (xy 8.035286 2.507503)
			(xy 8.175772 2.499613) (xy 8.315594 2.483859) (xy 8.454314 2.460289) (xy 8.591493 2.428979) (xy 8.726701 2.390026)
			(xy 8.859513 2.343553) (xy 8.989509 2.289707) (xy 9.116282 2.228656) (xy 9.239433 2.160593) (xy 9.358573 2.085732)
			(xy 9.473329 2.004309) (xy 9.583338 1.916579) (xy 9.688255 1.822819) (xy 9.78775 1.723324) (xy 9.88151 1.618406)
			(xy 9.96924 1.508397) (xy 10.050663 1.393641) (xy 10.125524 1.274501) (xy 10.193587 1.151351) (xy 10.254637 1.024578)
			(xy 10.308484 0.894581) (xy 10.354957 0.76177) (xy 10.393909 0.626561) (xy 10.42522 0.489382) (xy 10.448789 0.350662)
			(xy 10.464543 0.21084) (xy 10.472433 0.070354) (xy 10.472928 0) (xy 10.472928 -8.850122) (xy 10.47345 -8.905929)
			(xy 10.481791 -9.017231) (xy 10.498426 -9.127599) (xy 10.523263 -9.236414) (xy 10.556162 -9.34307)
			(xy 10.596939 -9.446968) (xy 10.645366 -9.547529) (xy 10.701173 -9.64419) (xy 10.764048 -9.73641)
			(xy 10.833638 -9.823673) (xy 10.909555 -9.905492) (xy 10.991374 -9.981409) (xy 11.078637 -10.051)
			(xy 11.170857 -10.113875) (xy 11.267517 -10.169682) (xy 11.368078 -10.21811) (xy 11.471977 -10.258887)
			(xy 11.578632 -10.291786) (xy 11.687448 -10.316623) (xy 11.797815 -10.333259) (xy 11.909117 -10.3416)
			(xy 11.964924 -10.342118)
		)
		(stroke
			(width 0)
			(type solid)
		)
		(fill yes)
		(layer "In10.Cu")
		(net "COUPON_GND2")
	)
	(gr_poly
		(pts
			(xy 200.481692 -418.081968) (xy 200.538276 -418.081432) (xy 200.651116 -418.072836) (xy 200.76298 -418.055715)
			(xy 200.873227 -418.030169) (xy 200.98122 -417.996343) (xy 201.086341 -417.954433) (xy 201.187984 -417.904678)
			(xy 201.285565 -417.847366) (xy 201.378524 -417.782825) (xy 201.466326 -417.711427) (xy 201.548466 -417.633582)
			(xy 201.586846 -417.592002) (xy 201.634058 -417.54062) (xy 201.733379 -417.442584) (xy 201.837997 -417.350223)
			(xy 201.947589 -417.26382) (xy 202.061814 -417.183644) (xy 202.18032 -417.109943) (xy 202.302741 -417.042944)
			(xy 202.428697 -416.982855) (xy 202.557798 -416.929861) (xy 202.689647 -416.884127) (xy 202.823834 -416.845794)
			(xy 202.959945 -416.81498) (xy 203.097558 -416.791782) (xy 203.236248 -416.77627) (xy 203.375587 -416.768492)
			(xy 203.445364 -416.768026) (xy 271.794732 -416.768026) (xy 271.864502 -416.768512) (xy 272.003824 -416.776289)
			(xy 272.142499 -416.791801) (xy 272.280097 -416.814999) (xy 272.416192 -416.845812) (xy 272.550363 -416.884144)
			(xy 272.682195 -416.929877) (xy 272.811281 -416.982869) (xy 272.937221 -417.042957) (xy 273.059624 -417.109954)
			(xy 273.178113 -417.183654) (xy 273.292321 -417.263827) (xy 273.401895 -417.350227) (xy 273.434939 -417.379404)
			(xy 313.073796 -417.379404) (xy 313.073796 -394.27912) (xy 326.479662 -394.27912) (xy 326.525636 -394.325094)
			(xy 326.525636 -397.823826) (xy 330.929171 -397.823826) (xy 330.929175 -397.756517) (xy 330.937223 -397.689692)
			(xy 330.953201 -397.624307) (xy 330.976879 -397.561301) (xy 331.007918 -397.501576) (xy 331.045873 -397.44599)
			(xy 331.067664 -397.420338) (xy 331.073477 -397.413205) (xy 331.07998 -397.396005) (xy 331.080364 -397.38681)
			(xy 331.080364 -396.893542) (xy 331.079919 -396.884359) (xy 331.073428 -396.867175) (xy 331.067664 -396.860014)
			(xy 331.045866 -396.83437) (xy 331.007916 -396.778783) (xy 330.976881 -396.719059) (xy 330.953208 -396.656053)
			(xy 330.937235 -396.59067) (xy 330.929191 -396.523846) (xy 330.929192 -396.456539) (xy 330.937238 -396.389716)
			(xy 330.953213 -396.324333) (xy 330.976888 -396.261328) (xy 331.007923 -396.201604) (xy 331.045875 -396.146018)
			(xy 331.067664 -396.120366) (xy 331.073465 -396.113225) (xy 331.079975 -396.096031) (xy 331.080364 -396.086838)
			(xy 331.080364 -395.92885) (xy 331.080805 -395.918678) (xy 331.088579 -395.89988) (xy 331.10296 -395.885492)
			(xy 331.121755 -395.87771) (xy 331.131926 -395.877288) (xy 331.848206 -395.877288) (xy 331.858384 -395.87766)
			(xy 331.877189 -395.885456) (xy 331.891575 -395.899859) (xy 331.899351 -395.918671) (xy 331.899768 -395.92885)
			(xy 331.899768 -396.086838) (xy 331.900167 -396.096026) (xy 331.906689 -396.11321) (xy 331.912468 -396.120366)
			(xy 331.934246 -396.146026) (xy 331.972195 -396.201612) (xy 332.003228 -396.261334) (xy 332.026901 -396.324338)
			(xy 332.042874 -396.389719) (xy 332.050919 -396.45654) (xy 332.05092 -396.523845) (xy 332.042877 -396.590666)
			(xy 332.026905 -396.656048) (xy 332.003234 -396.719052) (xy 331.972202 -396.778775) (xy 331.934255 -396.834362)
			(xy 331.912468 -396.860014) (xy 331.906679 -396.867164) (xy 331.90016 -396.884351) (xy 331.899768 -396.893542)
			(xy 331.899768 -397.38681) (xy 331.90018 -397.395997) (xy 331.906693 -397.413181) (xy 331.912468 -397.420338)
			(xy 331.934218 -397.446021) (xy 331.972167 -397.501603) (xy 332.00059 -397.556296) (xy 333.128836 -397.556296)
			(xy 333.136911 -397.489358) (xy 333.152946 -397.423869) (xy 333.17671 -397.360773) (xy 333.20786 -397.300977)
			(xy 333.245948 -397.245343) (xy 333.267812 -397.219678) (xy 333.273602 -397.212528) (xy 333.28012 -397.195341)
			(xy 333.280512 -397.18615) (xy 333.280512 -397.028924) (xy 333.280936 -397.018802) (xy 333.288678 -397.000096)
			(xy 333.302993 -396.985781) (xy 333.321698 -396.978037) (xy 333.33182 -396.977616) (xy 334.0481 -396.977616)
			(xy 334.058224 -396.978016) (xy 334.076931 -396.985768) (xy 334.091246 -397.000089) (xy 334.098988 -397.018799)
			(xy 334.099408 -397.028924) (xy 334.099408 -397.18615) (xy 334.09984 -397.195335) (xy 334.106338 -397.21252)
			(xy 334.112108 -397.219678) (xy 334.133982 -397.245335) (xy 334.172069 -397.300971) (xy 334.203219 -397.360769)
			(xy 334.226982 -397.423866) (xy 334.243017 -397.489356) (xy 334.251092 -397.556295) (xy 334.251091 -397.62372)
			(xy 334.243014 -397.690658) (xy 334.226978 -397.756148) (xy 334.203213 -397.819245) (xy 334.200796 -397.823884)
			(xy 335.328964 -397.823884) (xy 335.328968 -397.756459) (xy 335.337047 -397.689518) (xy 335.353085 -397.624028)
			(xy 335.376852 -397.560929) (xy 335.408005 -397.501132) (xy 335.446095 -397.445496) (xy 335.46796 -397.41983)
			(xy 335.473776 -397.412699) (xy 335.480277 -397.395497) (xy 335.48066 -397.386302) (xy 335.48066 -396.89405)
			(xy 335.480213 -396.884867) (xy 335.473723 -396.867683) (xy 335.46796 -396.860522) (xy 335.446088 -396.834864)
			(xy 335.408002 -396.779228) (xy 335.376854 -396.71943) (xy 335.353092 -396.656332) (xy 335.337058 -396.590843)
			(xy 335.328984 -396.523904) (xy 335.328985 -396.456481) (xy 335.337061 -396.389542) (xy 335.353096 -396.324053)
			(xy 335.37686 -396.260956) (xy 335.40801 -396.201159) (xy 335.446097 -396.145524) (xy 335.46796 -396.119858)
			(xy 335.473764 -396.112719) (xy 335.480273 -396.095523) (xy 335.48066 -396.08633) (xy 335.48066 -395.92885)
			(xy 335.481168 -395.918724) (xy 335.488883 -395.9) (xy 335.503164 -395.885642) (xy 335.521845 -395.877824)
			(xy 335.531968 -395.877288) (xy 336.248248 -395.877288) (xy 336.258404 -395.877682) (xy 336.277155 -395.885491)
			(xy 336.291476 -395.899896) (xy 336.299176 -395.918692) (xy 336.299556 -395.92885) (xy 336.299556 -396.08633)
			(xy 336.299962 -396.095517) (xy 336.30648 -396.112701) (xy 336.312256 -396.119858) (xy 336.334112 -396.145531)
			(xy 336.372204 -396.201163) (xy 336.403357 -396.260958) (xy 336.427124 -396.324054) (xy 336.443161 -396.389542)
			(xy 336.451239 -396.456481) (xy 336.45124 -396.523904) (xy 336.443164 -396.590843) (xy 336.427128 -396.656332)
			(xy 336.403363 -396.719428) (xy 336.372211 -396.779224) (xy 336.334121 -396.834858) (xy 336.312256 -396.860522)
			(xy 336.306462 -396.867669) (xy 336.299947 -396.884858) (xy 336.299556 -396.89405) (xy 336.299556 -397.386302)
			(xy 336.299975 -397.395488) (xy 336.306484 -397.412672) (xy 336.312256 -397.41983) (xy 336.334084 -397.445525)
			(xy 336.372177 -397.501154) (xy 336.40094 -397.556356) (xy 337.529156 -397.556356) (xy 337.537198 -397.489535)
			(xy 337.553169 -397.424153) (xy 337.576839 -397.361149) (xy 337.607869 -397.301426) (xy 337.645814 -397.245839)
			(xy 337.6676 -397.220186) (xy 337.673385 -397.213033) (xy 337.679907 -397.195848) (xy 337.6803 -397.186658)
			(xy 337.6803 -397.028924) (xy 337.680741 -397.018771) (xy 337.688529 -397.000019) (xy 337.70292 -396.985695)
			(xy 337.721708 -396.977995) (xy 337.731862 -396.977616) (xy 338.448142 -396.977616) (xy 338.458268 -396.978091)
			(xy 338.476986 -396.985829) (xy 338.49134 -397.000118) (xy 338.499162 -397.0188) (xy 338.499704 -397.028924)
			(xy 338.499704 -397.186658) (xy 338.500133 -397.195843) (xy 338.506634 -397.213028) (xy 338.512404 -397.220186)
			(xy 338.5342 -397.245831) (xy 338.572146 -397.301419) (xy 338.603176 -397.361144) (xy 338.626847 -397.42415)
			(xy 338.642818 -397.489532) (xy 338.65086 -397.556355) (xy 338.650859 -397.62366) (xy 338.642815 -397.690483)
			(xy 338.626842 -397.755865) (xy 338.60317 -397.81887) (xy 338.600595 -397.823826) (xy 339.729259 -397.823826)
			(xy 339.729263 -397.756517) (xy 339.737311 -397.689692) (xy 339.753288 -397.624308) (xy 339.776965 -397.561301)
			(xy 339.808004 -397.501577) (xy 339.845958 -397.44599) (xy 339.867748 -397.420338) (xy 339.873559 -397.413204)
			(xy 339.880064 -397.396005) (xy 339.880448 -397.38681) (xy 339.880448 -396.893542) (xy 339.880007 -396.884358)
			(xy 339.873513 -396.867174) (xy 339.867748 -396.860014) (xy 339.84595 -396.83437) (xy 339.808001 -396.778783)
			(xy 339.776968 -396.719058) (xy 339.753295 -396.656052) (xy 339.737322 -396.590669) (xy 339.729279 -396.523845)
			(xy 339.72928 -396.456539) (xy 339.737325 -396.389716) (xy 339.753299 -396.324333) (xy 339.776974 -396.261328)
			(xy 339.808009 -396.201604) (xy 339.845959 -396.146018) (xy 339.867748 -396.120366) (xy 339.873547 -396.113223)
			(xy 339.880059 -396.096031) (xy 339.880448 -396.086838) (xy 339.880448 -395.92885) (xy 339.880905 -395.91868)
			(xy 339.888675 -395.899885) (xy 339.903051 -395.885498) (xy 339.921841 -395.877713) (xy 339.93201 -395.877288)
			(xy 340.64829 -395.877288) (xy 340.658467 -395.877673) (xy 340.677271 -395.885464) (xy 340.691658 -395.899862)
			(xy 340.699435 -395.918672) (xy 340.699852 -395.92885) (xy 340.699852 -396.086838) (xy 340.700255 -396.096026)
			(xy 340.706775 -396.113209) (xy 340.712552 -396.120366) (xy 340.73433 -396.146026) (xy 340.77228 -396.201611)
			(xy 340.803314 -396.261334) (xy 340.826988 -396.324337) (xy 340.842962 -396.389718) (xy 340.851007 -396.45654)
			(xy 340.851007 -396.523845) (xy 340.842964 -396.590667) (xy 340.826992 -396.656048) (xy 340.80332 -396.719053)
			(xy 340.772287 -396.778776) (xy 340.734339 -396.834362) (xy 340.712552 -396.860014) (xy 340.706761 -396.867163)
			(xy 340.700244 -396.884351) (xy 340.699852 -396.893542) (xy 340.699852 -397.38681) (xy 340.700268 -397.395996)
			(xy 340.706779 -397.41318) (xy 340.712552 -397.420338) (xy 340.734302 -397.446021) (xy 340.772253 -397.501603)
			(xy 340.800676 -397.556296) (xy 341.928924 -397.556296) (xy 341.936999 -397.489359) (xy 341.953033 -397.42387)
			(xy 341.976796 -397.360774) (xy 342.007946 -397.300978) (xy 342.046033 -397.245343) (xy 342.067896 -397.219678)
			(xy 342.073684 -397.212527) (xy 342.080204 -397.195341) (xy 342.080596 -397.18615) (xy 342.080596 -397.028924)
			(xy 342.081035 -397.018804) (xy 342.088775 -397.000101) (xy 342.103084 -396.985786) (xy 342.121784 -396.978039)
			(xy 342.131904 -396.977616) (xy 342.848184 -396.977616) (xy 342.858307 -396.978029) (xy 342.877014 -396.985775)
			(xy 342.891329 -397.000093) (xy 342.899072 -397.0188) (xy 342.899492 -397.028924) (xy 342.899492 -397.18615)
			(xy 342.899928 -397.195334) (xy 342.906424 -397.212519) (xy 342.912192 -397.219678) (xy 342.934066 -397.245335)
			(xy 342.972155 -397.300971) (xy 343.003306 -397.360768) (xy 343.02707 -397.423866) (xy 343.043105 -397.489356)
			(xy 343.05118 -397.556295) (xy 343.051179 -397.62372) (xy 343.043102 -397.690659) (xy 343.027065 -397.756149)
			(xy 343.0033 -397.819246) (xy 343.000914 -397.823825) (xy 344.12905 -397.823825) (xy 344.129054 -397.756517)
			(xy 344.137101 -397.689692) (xy 344.153078 -397.624308) (xy 344.176755 -397.561302) (xy 344.207793 -397.501577)
			(xy 344.245746 -397.44599) (xy 344.267536 -397.420338) (xy 344.273346 -397.413202) (xy 344.279852 -397.396004)
			(xy 344.280236 -397.38681) (xy 344.280236 -396.893542) (xy 344.279797 -396.884358) (xy 344.273303 -396.867174)
			(xy 344.267536 -396.860014) (xy 344.245738 -396.83437) (xy 344.20779 -396.778782) (xy 344.176757 -396.719058)
			(xy 344.153085 -396.656052) (xy 344.137113 -396.590669) (xy 344.12907 -396.523845) (xy 344.129071 -396.45654)
			(xy 344.137116 -396.389716) (xy 344.15309 -396.324334) (xy 344.176764 -396.261329) (xy 344.207798 -396.201605)
			(xy 344.245748 -396.146018) (xy 344.267536 -396.120366) (xy 344.273334 -396.113222) (xy 344.279847 -396.09603)
			(xy 344.280236 -396.086838) (xy 344.280236 -395.92885) (xy 344.280705 -395.918682) (xy 344.288473 -395.899889)
			(xy 344.302845 -395.885502) (xy 344.32163 -395.877715) (xy 344.331798 -395.877288) (xy 345.048078 -395.877288)
			(xy 345.058254 -395.877683) (xy 345.077058 -395.88547) (xy 345.091445 -395.899866) (xy 345.099222 -395.918673)
			(xy 345.09964 -395.92885) (xy 345.09964 -396.086838) (xy 345.100045 -396.096025) (xy 345.106564 -396.113209)
			(xy 345.11234 -396.120366) (xy 345.134118 -396.146026) (xy 345.172069 -396.201611) (xy 345.203104 -396.261333)
			(xy 345.226778 -396.324337) (xy 345.242752 -396.389718) (xy 345.250798 -396.45654) (xy 345.250798 -396.523845)
			(xy 345.242755 -396.590667) (xy 345.226782 -396.656049) (xy 345.20311 -396.719053) (xy 345.172077 -396.778776)
			(xy 345.134128 -396.834362) (xy 345.11234 -396.860014) (xy 345.106548 -396.867162) (xy 345.100032 -396.884351)
			(xy 345.09964 -396.893542) (xy 345.09964 -397.38681) (xy 345.100059 -397.395996) (xy 345.106568 -397.41318)
			(xy 345.11234 -397.420338) (xy 345.134091 -397.446021) (xy 345.172042 -397.501602) (xy 345.200497 -397.556355)
			(xy 346.32922 -397.556355) (xy 346.337264 -397.489532) (xy 346.353237 -397.42415) (xy 346.37691 -397.361146)
			(xy 346.407945 -397.301423) (xy 346.445896 -397.245838) (xy 346.467684 -397.220186) (xy 346.473467 -397.213031)
			(xy 346.47999 -397.195848) (xy 346.480384 -397.186658) (xy 346.480384 -397.028924) (xy 346.480841 -397.018773)
			(xy 346.488625 -397.000025) (xy 346.503011 -396.985701) (xy 346.521794 -396.977997) (xy 346.531946 -396.977616)
			(xy 347.248226 -396.977616) (xy 347.258351 -396.978104) (xy 347.277069 -396.985836) (xy 347.291423 -397.000121)
			(xy 347.299246 -397.018801) (xy 347.299788 -397.028924) (xy 347.299788 -397.186658) (xy 347.300221 -397.195843)
			(xy 347.306719 -397.213027) (xy 347.312488 -397.220186) (xy 347.334285 -397.24583) (xy 347.372232 -397.301419)
			(xy 347.403263 -397.361143) (xy 347.426934 -397.424149) (xy 347.442905 -397.489532) (xy 347.450948 -397.556355)
			(xy 347.450947 -397.62366) (xy 347.442903 -397.690483) (xy 347.426929 -397.755865) (xy 347.403257 -397.81887)
			(xy 347.400682 -397.823826) (xy 374.92908 -397.823826) (xy 374.929084 -397.756517) (xy 374.937132 -397.689691)
			(xy 374.95311 -397.624306) (xy 374.976789 -397.5613) (xy 375.007829 -397.501576) (xy 375.045785 -397.445989)
			(xy 375.067576 -397.420338) (xy 375.073379 -397.413197) (xy 375.07989 -397.396003) (xy 375.080276 -397.38681)
			(xy 375.080276 -396.893542) (xy 375.079851 -396.884356) (xy 375.073348 -396.867171) (xy 375.067576 -396.860014)
			(xy 375.045777 -396.83437) (xy 375.007826 -396.778784) (xy 374.976792 -396.719059) (xy 374.953118 -396.656053)
			(xy 374.937144 -396.59067) (xy 374.9291 -396.523846) (xy 374.929101 -396.456539) (xy 374.937147 -396.389715)
			(xy 374.953122 -396.324332) (xy 374.976798 -396.261327) (xy 375.007834 -396.201604) (xy 375.045787 -396.146018)
			(xy 375.067576 -396.120366) (xy 375.073367 -396.113216) (xy 375.079886 -396.096029) (xy 375.080276 -396.086838)
			(xy 375.080276 -395.92885) (xy 375.080706 -395.918677) (xy 375.088481 -395.899876) (xy 375.102866 -395.885488)
			(xy 375.121665 -395.877708) (xy 375.131838 -395.877288) (xy 375.848118 -395.877288) (xy 375.858297 -395.87765)
			(xy 375.877102 -395.885451) (xy 375.891487 -395.899856) (xy 375.899263 -395.91867) (xy 375.89968 -395.92885)
			(xy 375.89968 -396.086838) (xy 375.900076 -396.096027) (xy 375.9066 -396.113211) (xy 375.91238 -396.120366)
			(xy 375.934157 -396.146026) (xy 375.972105 -396.201612) (xy 376.003138 -396.261335) (xy 376.02681 -396.324338)
			(xy 376.042784 -396.389719) (xy 376.050828 -396.456541) (xy 376.050829 -396.523844) (xy 376.042786 -396.590666)
			(xy 376.026815 -396.656047) (xy 376.003144 -396.719051) (xy 375.972113 -396.778775) (xy 375.934167 -396.834362)
			(xy 375.91238 -396.860014) (xy 375.906593 -396.867166) (xy 375.900073 -396.884351) (xy 375.89968 -396.893542)
			(xy 375.89968 -397.38681) (xy 375.90009 -397.395997) (xy 375.906604 -397.413181) (xy 375.91238 -397.420338)
			(xy 375.93413 -397.446021) (xy 375.972078 -397.501604) (xy 376.0005 -397.556296) (xy 377.128745 -397.556296)
			(xy 377.136821 -397.489358) (xy 377.152856 -397.423869) (xy 377.17662 -397.360772) (xy 377.207771 -397.300977)
			(xy 377.24586 -397.245343) (xy 377.267724 -397.219678) (xy 377.273515 -397.212529) (xy 377.280032 -397.195341)
			(xy 377.280424 -397.18615) (xy 377.280424 -397.028924) (xy 377.280836 -397.0188) (xy 377.288581 -397.000092)
			(xy 377.302899 -396.985776) (xy 377.321608 -396.978034) (xy 377.331732 -396.977616) (xy 378.048012 -396.977616)
			(xy 378.058137 -396.978006) (xy 378.076844 -396.985761) (xy 378.091159 -397.000086) (xy 378.098901 -397.018798)
			(xy 378.09932 -397.028924) (xy 378.09932 -397.18615) (xy 378.09975 -397.195335) (xy 378.10625 -397.21252)
			(xy 378.11202 -397.219678) (xy 378.133893 -397.245335) (xy 378.17198 -397.300972) (xy 378.203129 -397.360769)
			(xy 378.226892 -397.423867) (xy 378.242926 -397.489357) (xy 378.251001 -397.556295) (xy 378.251 -397.62372)
			(xy 378.242924 -397.690658) (xy 378.226888 -397.756147) (xy 378.203123 -397.819245) (xy 378.200706 -397.823885)
			(xy 379.328873 -397.823885) (xy 379.328877 -397.756458) (xy 379.336956 -397.689518) (xy 379.352995 -397.624027)
			(xy 379.376762 -397.560929) (xy 379.407915 -397.501131) (xy 379.446007 -397.445496) (xy 379.467872 -397.41983)
			(xy 379.47369 -397.4127) (xy 379.48019 -397.395498) (xy 379.480572 -397.386302) (xy 379.480572 -396.89405)
			(xy 379.480144 -396.884865) (xy 379.473643 -396.86768) (xy 379.467872 -396.860522) (xy 379.445999 -396.834864)
			(xy 379.407913 -396.779228) (xy 379.376764 -396.719431) (xy 379.353002 -396.656333) (xy 379.336968 -396.590843)
			(xy 379.328893 -396.523904) (xy 379.328894 -396.456481) (xy 379.33697 -396.389542) (xy 379.353006 -396.324053)
			(xy 379.37677 -396.260956) (xy 379.40792 -396.201159) (xy 379.446008 -396.145524) (xy 379.467872 -396.119858)
			(xy 379.473678 -396.11272) (xy 379.480185 -396.095524) (xy 379.480572 -396.08633) (xy 379.480572 -395.92885)
			(xy 379.481069 -395.918723) (xy 379.488786 -395.899996) (xy 379.50307 -395.885637) (xy 379.521755 -395.877822)
			(xy 379.53188 -395.877288) (xy 380.24816 -395.877288) (xy 380.258278 -395.877749) (xy 380.276979 -395.885481)
			(xy 380.291294 -395.899784) (xy 380.299043 -395.918478) (xy 380.299468 -395.928596) (xy 380.299468 -396.08633)
			(xy 380.299871 -396.095518) (xy 380.30639 -396.112702) (xy 380.312168 -396.119858) (xy 380.334023 -396.145531)
			(xy 380.372114 -396.201163) (xy 380.403267 -396.260958) (xy 380.427033 -396.324054) (xy 380.443071 -396.389543)
			(xy 380.451148 -396.456481) (xy 380.451149 -396.523904) (xy 380.443073 -396.590842) (xy 380.427038 -396.656331)
			(xy 380.403273 -396.719428) (xy 380.372122 -396.779224) (xy 380.334032 -396.834857) (xy 380.312168 -396.860522)
			(xy 380.306375 -396.86767) (xy 380.299859 -396.884858) (xy 380.299468 -396.89405) (xy 380.299468 -397.386302)
			(xy 380.299884 -397.395488) (xy 380.306394 -397.412672) (xy 380.312168 -397.41983) (xy 380.333996 -397.445525)
			(xy 380.372088 -397.501155) (xy 380.40085 -397.556356) (xy 381.529065 -397.556356) (xy 381.537108 -397.489534)
			(xy 381.553079 -397.424153) (xy 381.576749 -397.361149) (xy 381.60778 -397.301425) (xy 381.645726 -397.245838)
			(xy 381.667512 -397.220186) (xy 381.673298 -397.213034) (xy 381.679819 -397.195849) (xy 381.680212 -397.186658)
			(xy 381.680212 -397.028924) (xy 381.680636 -397.018802) (xy 381.688378 -397.000096) (xy 381.702693 -396.985781)
			(xy 381.721398 -396.978037) (xy 381.73152 -396.977616) (xy 382.448054 -396.977616) (xy 382.458175 -396.978164)
			(xy 382.47689 -396.985872) (xy 382.491247 -397.000139) (xy 382.499072 -397.018806) (xy 382.499616 -397.028924)
			(xy 382.499616 -397.186658) (xy 382.500043 -397.195844) (xy 382.506544 -397.213028) (xy 382.512316 -397.220186)
			(xy 382.534115 -397.245829) (xy 382.572066 -397.301416) (xy 382.603102 -397.36114) (xy 382.626776 -397.424146)
			(xy 382.642749 -397.48953) (xy 382.650793 -397.556354) (xy 382.650793 -397.623661) (xy 382.642747 -397.690485)
			(xy 382.626771 -397.755868) (xy 382.603096 -397.818873) (xy 382.600522 -397.823826) (xy 383.729168 -397.823826)
			(xy 383.729172 -397.756517) (xy 383.73722 -397.689692) (xy 383.753198 -397.624307) (xy 383.776876 -397.561301)
			(xy 383.807914 -397.501576) (xy 383.845869 -397.44599) (xy 383.86766 -397.420338) (xy 383.873473 -397.413205)
			(xy 383.879976 -397.396005) (xy 383.88036 -397.38681) (xy 383.88036 -396.893542) (xy 383.879916 -396.884359)
			(xy 383.873425 -396.867175) (xy 383.86766 -396.860014) (xy 383.845862 -396.83437) (xy 383.807912 -396.778783)
			(xy 383.776878 -396.719058) (xy 383.753205 -396.656053) (xy 383.737232 -396.590669) (xy 383.729188 -396.523846)
			(xy 383.729189 -396.456539) (xy 383.737235 -396.389716) (xy 383.753209 -396.324333) (xy 383.776884 -396.261328)
			(xy 383.80792 -396.201604) (xy 383.845871 -396.146018) (xy 383.86766 -396.120366) (xy 383.873461 -396.113224)
			(xy 383.879971 -396.096031) (xy 383.88036 -396.086838) (xy 383.88036 -395.92885) (xy 383.880805 -395.918679)
			(xy 383.888578 -395.899881) (xy 383.902958 -395.885494) (xy 383.921751 -395.877711) (xy 383.931922 -395.877288)
			(xy 384.648202 -395.877288) (xy 384.65838 -395.877663) (xy 384.677184 -395.885458) (xy 384.691571 -395.899859)
			(xy 384.699347 -395.918672) (xy 384.699764 -395.92885) (xy 384.699764 -396.086838) (xy 384.700164 -396.096026)
			(xy 384.706686 -396.11321) (xy 384.712464 -396.120366) (xy 384.734242 -396.146026) (xy 384.772191 -396.201612)
			(xy 384.803224 -396.261334) (xy 384.826898 -396.324337) (xy 384.842871 -396.389719) (xy 384.850916 -396.45654)
			(xy 384.850917 -396.523845) (xy 384.842874 -396.590666) (xy 384.826902 -396.656048) (xy 384.803231 -396.719052)
			(xy 384.772199 -396.778776) (xy 384.734251 -396.834362) (xy 384.712464 -396.860014) (xy 384.706674 -396.867164)
			(xy 384.700156 -396.884351) (xy 384.699764 -396.893542) (xy 384.699764 -397.38681) (xy 384.700177 -397.395997)
			(xy 384.70669 -397.413181) (xy 384.712464 -397.420338) (xy 384.734214 -397.446021) (xy 384.772164 -397.501603)
			(xy 384.800587 -397.556296) (xy 385.928833 -397.556296) (xy 385.936908 -397.489358) (xy 385.952943 -397.42387)
			(xy 385.976706 -397.360773) (xy 386.007856 -397.300977) (xy 386.045944 -397.245343) (xy 386.067808 -397.219678)
			(xy 386.073597 -397.212528) (xy 386.080116 -397.195341) (xy 386.080508 -397.18615) (xy 386.080508 -397.028924)
			(xy 386.080936 -397.018802) (xy 386.088677 -397.000097) (xy 386.102991 -396.985782) (xy 386.121694 -396.978037)
			(xy 386.131816 -396.977616) (xy 386.848096 -396.977616) (xy 386.85822 -396.97802) (xy 386.876927 -396.985769)
			(xy 386.891242 -397.00009) (xy 386.898984 -397.0188) (xy 386.899404 -397.028924) (xy 386.899404 -397.18615)
			(xy 386.899837 -397.195335) (xy 386.906335 -397.212519) (xy 386.912104 -397.219678) (xy 386.933978 -397.245335)
			(xy 386.972066 -397.300971) (xy 387.003216 -397.360768) (xy 387.026979 -397.423866) (xy 387.043014 -397.489356)
			(xy 387.051089 -397.556295) (xy 387.051088 -397.62372) (xy 387.043011 -397.690659) (xy 387.026975 -397.756148)
			(xy 387.00321 -397.819245) (xy 387.000823 -397.823826) (xy 388.128959 -397.823826) (xy 388.128963 -397.756517)
			(xy 388.137011 -397.689692) (xy 388.152988 -397.624308) (xy 388.176665 -397.561301) (xy 388.207704 -397.501577)
			(xy 388.245658 -397.44599) (xy 388.267448 -397.420338) (xy 388.273259 -397.413204) (xy 388.279764 -397.396005)
			(xy 388.280148 -397.38681) (xy 388.280148 -396.893542) (xy 388.279707 -396.884358) (xy 388.273213 -396.867174)
			(xy 388.267448 -396.860014) (xy 388.24565 -396.83437) (xy 388.207701 -396.778783) (xy 388.176668 -396.719058)
			(xy 388.152995 -396.656052) (xy 388.137022 -396.590669) (xy 388.128979 -396.523845) (xy 388.12898 -396.456539)
			(xy 388.137025 -396.389716) (xy 388.152999 -396.324333) (xy 388.176674 -396.261328) (xy 388.207709 -396.201604)
			(xy 388.245659 -396.146018) (xy 388.267448 -396.120366) (xy 388.273247 -396.113223) (xy 388.279759 -396.096031)
			(xy 388.280148 -396.086838) (xy 388.280148 -395.92885) (xy 388.280605 -395.91868) (xy 388.288375 -395.899885)
			(xy 388.302751 -395.885498) (xy 388.321541 -395.877713) (xy 388.33171 -395.877288) (xy 389.04799 -395.877288)
			(xy 389.058167 -395.877673) (xy 389.076971 -395.885464) (xy 389.091358 -395.899862) (xy 389.099135 -395.918672)
			(xy 389.099552 -395.92885) (xy 389.099552 -396.086838) (xy 389.099955 -396.096026) (xy 389.106475 -396.113209)
			(xy 389.112252 -396.120366) (xy 389.13403 -396.146026) (xy 389.17198 -396.201611) (xy 389.203014 -396.261334)
			(xy 389.226688 -396.324337) (xy 389.242662 -396.389718) (xy 389.250707 -396.45654) (xy 389.250707 -396.523845)
			(xy 389.242664 -396.590667) (xy 389.226692 -396.656048) (xy 389.20302 -396.719053) (xy 389.171987 -396.778776)
			(xy 389.134039 -396.834362) (xy 389.112252 -396.860014) (xy 389.106461 -396.867163) (xy 389.099944 -396.884351)
			(xy 389.099552 -396.893542) (xy 389.099552 -397.38681) (xy 389.099968 -397.395996) (xy 389.106479 -397.41318)
			(xy 389.112252 -397.420338) (xy 389.134002 -397.446021) (xy 389.171953 -397.501603) (xy 389.200407 -397.556356)
			(xy 390.329153 -397.556356) (xy 390.337195 -397.489535) (xy 390.353166 -397.424153) (xy 390.376836 -397.36115)
			(xy 390.407865 -397.301426) (xy 390.44581 -397.245839) (xy 390.467596 -397.220186) (xy 390.473381 -397.213032)
			(xy 390.479903 -397.195848) (xy 390.480296 -397.186658) (xy 390.480296 -397.028924) (xy 390.480735 -397.018804)
			(xy 390.488475 -397.000101) (xy 390.502784 -396.985786) (xy 390.521484 -396.978039) (xy 390.531604 -396.977616)
			(xy 391.248138 -396.977616) (xy 391.258264 -396.978095) (xy 391.276982 -396.985831) (xy 391.291336 -397.000119)
			(xy 391.299158 -397.0188) (xy 391.2997 -397.028924) (xy 391.2997 -397.186658) (xy 391.30013 -397.195843)
			(xy 391.30663 -397.213028) (xy 391.3124 -397.220186) (xy 391.334196 -397.245831) (xy 391.372142 -397.301419)
			(xy 391.403173 -397.361144) (xy 391.426844 -397.424149) (xy 391.442815 -397.489532) (xy 391.450857 -397.556355)
			(xy 391.450856 -397.62366) (xy 391.442812 -397.690483) (xy 391.426839 -397.755865) (xy 391.403167 -397.81887)
			(xy 391.372135 -397.878594) (xy 391.334187 -397.934181) (xy 391.3124 -397.959834) (xy 391.306606 -397.966981)
			(xy 391.30009 -397.98417) (xy 391.2997 -397.993362) (xy 391.2997 -398.486884) (xy 391.300118 -398.49607)
			(xy 391.306626 -398.513255) (xy 391.3124 -398.520412) (xy 391.334222 -398.546036) (xy 391.372167 -398.601627)
			(xy 391.403197 -398.661355) (xy 391.426866 -398.724363) (xy 391.442835 -398.789748) (xy 391.450876 -398.856574)
			(xy 391.450872 -398.923881) (xy 391.442825 -398.990705) (xy 391.42685 -399.056089) (xy 391.403175 -399.119095)
			(xy 391.372139 -399.178819) (xy 391.334189 -399.234407) (xy 391.3124 -399.26006) (xy 391.306595 -399.2672)
			(xy 391.300086 -399.284394) (xy 391.2997 -399.293588) (xy 391.2997 -399.451576) (xy 391.299265 -399.461697)
			(xy 391.291524 -399.4804) (xy 391.277214 -399.494715) (xy 391.258513 -399.502461) (xy 391.248392 -399.502884)
			(xy 390.531858 -399.502884) (xy 390.521732 -399.502409) (xy 390.503014 -399.494671) (xy 390.48866 -399.480382)
			(xy 390.480838 -399.4617) (xy 390.480296 -399.451576) (xy 390.480296 -399.293588) (xy 390.479892 -399.2844)
			(xy 390.473374 -399.267216) (xy 390.467596 -399.26006) (xy 390.445845 -399.234378) (xy 390.407898 -399.178795)
			(xy 390.376865 -399.119075) (xy 390.353192 -399.056075) (xy 390.337218 -398.990696) (xy 390.329172 -398.923878)
			(xy 390.329169 -398.856576) (xy 390.337209 -398.789757) (xy 390.353176 -398.724377) (xy 390.376843 -398.661374)
			(xy 390.40787 -398.601652) (xy 390.445812 -398.546065) (xy 390.467596 -398.520412) (xy 390.473412 -398.51328)
			(xy 390.479915 -398.49608) (xy 390.480296 -398.486884) (xy 390.480296 -397.993362) (xy 390.479905 -397.984173)
			(xy 390.473378 -397.966988) (xy 390.467596 -397.959834) (xy 390.445819 -397.934173) (xy 390.407873 -397.878587)
			(xy 390.376842 -397.818864) (xy 390.35317 -397.755861) (xy 390.337198 -397.69048) (xy 390.329154 -397.623659)
			(xy 390.329153 -397.556356) (xy 389.200407 -397.556356) (xy 389.202988 -397.561322) (xy 389.226664 -397.624322)
			(xy 389.24264 -397.689701) (xy 389.250687 -397.75652) (xy 389.25069 -397.823823) (xy 389.24265 -397.890643)
			(xy 389.226681 -397.956023) (xy 389.203012 -398.019026) (xy 389.171982 -398.078748) (xy 389.134038 -398.134334)
			(xy 389.112252 -398.159986) (xy 389.10643 -398.167113) (xy 389.099932 -398.184318) (xy 389.099552 -398.193514)
			(xy 389.099552 -398.351502) (xy 389.099138 -398.361675) (xy 389.09135 -398.380472) (xy 389.076962 -398.394857)
			(xy 389.058163 -398.40264) (xy 389.04799 -398.403064) (xy 388.33171 -398.403064) (xy 388.321539 -398.402628)
			(xy 388.302745 -398.394847) (xy 388.28836 -398.380465) (xy 388.280574 -398.361673) (xy 388.280148 -398.351502)
			(xy 388.280148 -398.193514) (xy 388.27972 -398.184329) (xy 388.273218 -398.167145) (xy 388.267448 -398.159986)
			(xy 388.245622 -398.134365) (xy 388.207674 -398.078774) (xy 388.176642 -398.019046) (xy 388.152971 -397.956038)
			(xy 388.137 -397.890652) (xy 388.128959 -397.823826) (xy 387.000823 -397.823826) (xy 386.972058 -397.879042)
			(xy 386.933968 -397.934677) (xy 386.912104 -397.960342) (xy 386.906308 -397.967487) (xy 386.899793 -397.984678)
			(xy 386.899404 -397.99387) (xy 386.899404 -398.486376) (xy 386.899825 -398.495562) (xy 386.906331 -398.512747)
			(xy 386.912104 -398.519904) (xy 386.934003 -398.54554) (xy 386.972091 -398.601179) (xy 387.003239 -398.660979)
			(xy 387.027001 -398.72408) (xy 387.043034 -398.789572) (xy 387.051107 -398.856514) (xy 387.051104 -398.92394)
			(xy 387.043025 -398.990881) (xy 387.026985 -399.056372) (xy 387.003217 -399.11947) (xy 386.972063 -399.179268)
			(xy 386.93397 -399.234903) (xy 386.912104 -399.260568) (xy 386.906297 -399.267706) (xy 386.899788 -399.284902)
			(xy 386.899404 -399.294096) (xy 386.899404 -399.451576) (xy 386.898965 -399.461696) (xy 386.891225 -399.480399)
			(xy 386.876916 -399.494714) (xy 386.858216 -399.502461) (xy 386.848096 -399.502884) (xy 386.131816 -399.502884)
			(xy 386.121693 -399.502471) (xy 386.102986 -399.494725) (xy 386.088671 -399.480407) (xy 386.080928 -399.4617)
			(xy 386.080508 -399.451576) (xy 386.080508 -399.294096) (xy 386.080098 -399.284909) (xy 386.073584 -399.267725)
			(xy 386.067808 -399.260568) (xy 386.045979 -399.234874) (xy 386.007889 -399.179244) (xy 385.976736 -399.119451)
			(xy 385.95297 -399.056358) (xy 385.936931 -398.990873) (xy 385.928852 -398.923938) (xy 385.928849 -398.856517)
			(xy 385.936922 -398.789581) (xy 385.952954 -398.724093) (xy 385.976714 -398.660998) (xy 386.007861 -398.601203)
			(xy 386.045946 -398.545569) (xy 386.067808 -398.519904) (xy 386.073586 -398.512746) (xy 386.080112 -398.495565)
			(xy 386.080508 -398.486376) (xy 386.080508 -397.99387) (xy 386.080111 -397.984681) (xy 386.073588 -397.967497)
			(xy 386.067808 -397.960342) (xy 386.045954 -397.934669) (xy 386.007864 -397.879036) (xy 385.976712 -397.819241)
			(xy 385.952947 -397.756145) (xy 385.936911 -397.690657) (xy 385.928834 -397.623719) (xy 385.928833 -397.556296)
			(xy 384.800587 -397.556296) (xy 384.803199 -397.561322) (xy 384.826873 -397.624323) (xy 384.842849 -397.689701)
			(xy 384.850896 -397.75652) (xy 384.850899 -397.823822) (xy 384.842859 -397.890642) (xy 384.82689 -397.956022)
			(xy 384.803222 -398.019025) (xy 384.772193 -398.078748) (xy 384.734249 -398.134334) (xy 384.712464 -398.159986)
			(xy 384.706644 -398.167114) (xy 384.700144 -398.184318) (xy 384.699764 -398.193514) (xy 384.699764 -398.351502)
			(xy 384.699268 -398.36166) (xy 384.691494 -398.380428) (xy 384.677128 -398.394794) (xy 384.65836 -398.402568)
			(xy 384.648202 -398.403064) (xy 383.931922 -398.403064) (xy 383.921752 -398.402618) (xy 383.902958 -398.394841)
			(xy 383.888573 -398.380462) (xy 383.880787 -398.361672) (xy 383.88036 -398.351502) (xy 383.88036 -398.193514)
			(xy 383.87993 -398.184329) (xy 383.873429 -398.167145) (xy 383.86766 -398.159986) (xy 383.845834 -398.134365)
			(xy 383.807885 -398.078775) (xy 383.776852 -398.019047) (xy 383.753181 -397.956038) (xy 383.73721 -397.890652)
			(xy 383.729168 -397.823826) (xy 382.600522 -397.823826) (xy 382.572059 -397.878597) (xy 382.534106 -397.934182)
			(xy 382.512316 -397.959834) (xy 382.506524 -397.966983) (xy 382.500006 -397.98417) (xy 382.499616 -397.993362)
			(xy 382.499616 -398.486884) (xy 382.50003 -398.496071) (xy 382.506541 -398.513255) (xy 382.512316 -398.520412)
			(xy 382.53414 -398.546034) (xy 382.572091 -398.601624) (xy 382.603125 -398.661351) (xy 382.626798 -398.72436)
			(xy 382.64277 -398.789746) (xy 382.650812 -398.856573) (xy 382.650808 -398.923881) (xy 382.64276 -398.990707)
			(xy 382.626782 -399.056092) (xy 382.603103 -399.119098) (xy 382.572063 -399.178822) (xy 382.534107 -399.234408)
			(xy 382.512316 -399.26006) (xy 382.506513 -399.267201) (xy 382.500002 -399.284395) (xy 382.499616 -399.293588)
			(xy 382.499616 -399.451576) (xy 382.499165 -399.461695) (xy 382.491428 -399.480395) (xy 382.477122 -399.49471)
			(xy 382.458427 -399.502459) (xy 382.448308 -399.502884) (xy 381.731774 -399.502884) (xy 381.721649 -399.502396)
			(xy 381.702931 -399.494664) (xy 381.688577 -399.480379) (xy 381.680754 -399.461699) (xy 381.680212 -399.451576)
			(xy 381.680212 -399.293588) (xy 381.679805 -399.284401) (xy 381.673289 -399.267216) (xy 381.667512 -399.26006)
			(xy 381.64576 -399.234378) (xy 381.607812 -399.178796) (xy 381.576779 -399.119076) (xy 381.553105 -399.056075)
			(xy 381.537131 -398.990697) (xy 381.529084 -398.923878) (xy 381.529081 -398.856576) (xy 381.537121 -398.789757)
			(xy 381.553089 -398.724377) (xy 381.576757 -398.661374) (xy 381.607784 -398.601651) (xy 381.645727 -398.546064)
			(xy 381.667512 -398.520412) (xy 381.67333 -398.513282) (xy 381.679831 -398.49608) (xy 381.680212 -398.486884)
			(xy 381.680212 -397.993362) (xy 381.679818 -397.984173) (xy 381.673293 -397.966989) (xy 381.667512 -397.959834)
			(xy 381.645735 -397.934173) (xy 381.607788 -397.878588) (xy 381.576755 -397.818865) (xy 381.553083 -397.755862)
			(xy 381.53711 -397.690481) (xy 381.529066 -397.623659) (xy 381.529065 -397.556356) (xy 380.40085 -397.556356)
			(xy 380.403242 -397.560947) (xy 380.42701 -397.62404) (xy 380.443049 -397.689525) (xy 380.451128 -397.756461)
			(xy 380.451131 -397.823882) (xy 380.443059 -397.890818) (xy 380.427026 -397.956306) (xy 380.403265 -398.019401)
			(xy 380.372117 -398.079196) (xy 380.334031 -398.134829) (xy 380.312168 -398.160494) (xy 380.306387 -398.16765)
			(xy 380.299864 -398.184832) (xy 380.299468 -398.194022) (xy 380.299468 -398.351502) (xy 380.298975 -398.361628)
			(xy 380.291248 -398.380347) (xy 380.276964 -398.394703) (xy 380.258283 -398.402524) (xy 380.24816 -398.403064)
			(xy 379.53188 -398.403064) (xy 379.521752 -398.4027) (xy 379.503041 -398.394938) (xy 379.488726 -398.380605)
			(xy 379.480988 -398.361885) (xy 379.480572 -398.351756) (xy 379.480572 -398.194022) (xy 379.480158 -398.184835)
			(xy 379.473648 -398.16765) (xy 379.467872 -398.160494) (xy 379.445972 -398.134859) (xy 379.407886 -398.07922)
			(xy 379.376738 -398.019419) (xy 379.352978 -397.956318) (xy 379.336946 -397.890826) (xy 379.328873 -397.823885)
			(xy 378.200706 -397.823885) (xy 378.171972 -397.879041) (xy 378.133884 -397.934676) (xy 378.11202 -397.960342)
			(xy 378.106225 -397.967489) (xy 378.099709 -397.984678) (xy 378.09932 -397.99387) (xy 378.09932 -398.486376)
			(xy 378.099737 -398.495563) (xy 378.106245 -398.512747) (xy 378.11202 -398.519904) (xy 378.133919 -398.54554)
			(xy 378.172005 -398.60118) (xy 378.203153 -398.66098) (xy 378.226914 -398.724081) (xy 378.242947 -398.789573)
			(xy 378.251019 -398.856514) (xy 378.251016 -398.92394) (xy 378.242937 -398.99088) (xy 378.226898 -399.056371)
			(xy 378.203131 -399.11947) (xy 378.171977 -399.179267) (xy 378.133885 -399.234902) (xy 378.11202 -399.260568)
			(xy 378.106214 -399.267707) (xy 378.099704 -399.284902) (xy 378.09932 -399.294096) (xy 378.09932 -399.451576)
			(xy 378.098865 -399.461694) (xy 378.091128 -399.480394) (xy 378.076824 -399.494708) (xy 378.05813 -399.502458)
			(xy 378.048012 -399.502884) (xy 377.331732 -399.502884) (xy 377.32161 -399.502458) (xy 377.302903 -399.494717)
			(xy 377.288587 -399.480403) (xy 377.280844 -399.461698) (xy 377.280424 -399.451576) (xy 377.280424 -399.294096)
			(xy 377.280011 -399.284909) (xy 377.273499 -399.267725) (xy 377.267724 -399.260568) (xy 377.245895 -399.234874)
			(xy 377.207803 -399.179244) (xy 377.17665 -399.119452) (xy 377.152882 -399.056359) (xy 377.136844 -398.990873)
			(xy 377.128765 -398.923938) (xy 377.128761 -398.856516) (xy 377.136834 -398.78958) (xy 377.152866 -398.724093)
			(xy 377.176627 -398.660997) (xy 377.207775 -398.601202) (xy 377.245861 -398.545569) (xy 377.267724 -398.519904)
			(xy 377.273504 -398.512747) (xy 377.280028 -398.495565) (xy 377.280424 -398.486376) (xy 377.280424 -397.99387)
			(xy 377.280023 -397.984682) (xy 377.273502 -397.967498) (xy 377.267724 -397.960342) (xy 377.245869 -397.934669)
			(xy 377.207778 -397.879036) (xy 377.176626 -397.819241) (xy 377.15286 -397.756145) (xy 377.136823 -397.690657)
			(xy 377.128746 -397.623719) (xy 377.128745 -397.556296) (xy 376.0005 -397.556296) (xy 376.003112 -397.561323)
			(xy 376.026786 -397.624324) (xy 376.042761 -397.689702) (xy 376.050808 -397.756521) (xy 376.050811 -397.823822)
			(xy 376.042771 -397.890642) (xy 376.026803 -397.956022) (xy 376.003135 -398.019025) (xy 375.972108 -398.078747)
			(xy 375.934165 -398.134333) (xy 375.91238 -398.159986) (xy 375.906562 -398.167116) (xy 375.900061 -398.184318)
			(xy 375.89968 -398.193514) (xy 375.89968 -398.351502) (xy 375.899169 -398.361658) (xy 375.891397 -398.380423)
			(xy 375.877037 -398.394788) (xy 375.858274 -398.402565) (xy 375.848118 -398.403064) (xy 375.131838 -398.403064)
			(xy 375.121669 -398.402605) (xy 375.102876 -398.394833) (xy 375.08849 -398.380458) (xy 375.080703 -398.361671)
			(xy 375.080276 -398.351502) (xy 375.080276 -398.193514) (xy 375.079865 -398.184327) (xy 375.073352 -398.167142)
			(xy 375.067576 -398.159986) (xy 375.04575 -398.134365) (xy 375.007799 -398.078775) (xy 374.976766 -398.019048)
			(xy 374.953093 -397.956039) (xy 374.937122 -397.890652) (xy 374.92908 -397.823826) (xy 347.400682 -397.823826)
			(xy 347.372224 -397.878594) (xy 347.334276 -397.934182) (xy 347.312488 -397.959834) (xy 347.306693 -397.96698)
			(xy 347.300178 -397.98417) (xy 347.299788 -397.993362) (xy 347.299788 -398.486884) (xy 347.300209 -398.49607)
			(xy 347.306715 -398.513254) (xy 347.312488 -398.520412) (xy 347.33431 -398.546035) (xy 347.372256 -398.601627)
			(xy 347.403286 -398.661354) (xy 347.426956 -398.724363) (xy 347.442926 -398.789748) (xy 347.450967 -398.856573)
			(xy 347.450963 -398.923881) (xy 347.442916 -398.990705) (xy 347.42694 -399.056089) (xy 347.403264 -399.119095)
			(xy 347.372228 -399.17882) (xy 347.334277 -399.234407) (xy 347.312488 -399.26006) (xy 347.306682 -399.267199)
			(xy 347.300173 -399.284394) (xy 347.299788 -399.293588) (xy 347.299788 -399.451576) (xy 347.299359 -399.46173)
			(xy 347.291569 -399.480484) (xy 347.277174 -399.494809) (xy 347.258382 -399.502507) (xy 347.248226 -399.502884)
			(xy 346.531946 -399.502884) (xy 346.521825 -399.502336) (xy 346.50311 -399.494628) (xy 346.488753 -399.480361)
			(xy 346.480928 -399.461694) (xy 346.480384 -399.451576) (xy 346.480384 -399.293588) (xy 346.479983 -399.2844)
			(xy 346.473463 -399.267215) (xy 346.467684 -399.26006) (xy 346.44593 -399.234379) (xy 346.407977 -399.178798)
			(xy 346.37694 -399.119079) (xy 346.353263 -399.056078) (xy 346.337287 -398.990699) (xy 346.329239 -398.923879)
			(xy 346.329236 -398.856576) (xy 346.337277 -398.789755) (xy 346.353247 -398.724374) (xy 346.376918 -398.661371)
			(xy 346.40795 -398.601648) (xy 346.445897 -398.546064) (xy 346.467684 -398.520412) (xy 346.473499 -398.513279)
			(xy 346.480003 -398.496079) (xy 346.480384 -398.486884) (xy 346.480384 -397.993362) (xy 346.479996 -397.984172)
			(xy 346.473467 -397.966988) (xy 346.467684 -397.959834) (xy 346.445905 -397.934174) (xy 346.407953 -397.87859)
			(xy 346.376917 -397.818868) (xy 346.353241 -397.755864) (xy 346.337266 -397.690483) (xy 346.329221 -397.62366)
			(xy 346.32922 -397.556355) (xy 345.200497 -397.556355) (xy 345.203078 -397.561321) (xy 345.226754 -397.624322)
			(xy 345.24273 -397.689701) (xy 345.250778 -397.75652) (xy 345.250781 -397.823823) (xy 345.242741 -397.890643)
			(xy 345.226771 -397.956023) (xy 345.203102 -398.019026) (xy 345.172072 -398.078749) (xy 345.134126 -398.134334)
			(xy 345.11234 -398.159986) (xy 345.106517 -398.167112) (xy 345.10002 -398.184318) (xy 345.09964 -398.193514)
			(xy 345.09964 -398.351502) (xy 345.099237 -398.361676) (xy 345.091447 -398.380475) (xy 345.077055 -398.394861)
			(xy 345.058253 -398.402642) (xy 345.048078 -398.403064) (xy 344.331798 -398.403064) (xy 344.32164 -398.402568)
			(xy 344.302872 -398.394794) (xy 344.288506 -398.380428) (xy 344.280732 -398.36166) (xy 344.280236 -398.351502)
			(xy 344.280236 -398.193514) (xy 344.279811 -398.184329) (xy 344.273307 -398.167144) (xy 344.267536 -398.159986)
			(xy 344.245711 -398.134365) (xy 344.207763 -398.078774) (xy 344.176732 -398.019046) (xy 344.153061 -397.956037)
			(xy 344.137091 -397.890651) (xy 344.12905 -397.823825) (xy 343.000914 -397.823825) (xy 342.972147 -397.879042)
			(xy 342.934057 -397.934677) (xy 342.912192 -397.960342) (xy 342.906394 -397.967486) (xy 342.899881 -397.984678)
			(xy 342.899492 -397.99387) (xy 342.899492 -398.486376) (xy 342.899916 -398.495562) (xy 342.90642 -398.512746)
			(xy 342.912192 -398.519904) (xy 342.934092 -398.54554) (xy 342.97218 -398.601178) (xy 343.003329 -398.660979)
			(xy 343.027092 -398.724079) (xy 343.043125 -398.789572) (xy 343.051198 -398.856514) (xy 343.051195 -398.92394)
			(xy 343.043115 -398.990881) (xy 343.027076 -399.056372) (xy 343.003307 -399.119471) (xy 342.972152 -399.179268)
			(xy 342.934058 -399.234903) (xy 342.912192 -399.260568) (xy 342.906383 -399.267704) (xy 342.899876 -399.284902)
			(xy 342.899492 -399.294096) (xy 342.899492 -399.451576) (xy 342.899064 -399.461698) (xy 342.891323 -399.480403)
			(xy 342.877009 -399.494718) (xy 342.858306 -399.502463) (xy 342.848184 -399.502884) (xy 342.131904 -399.502884)
			(xy 342.12178 -399.50248) (xy 342.103073 -399.494731) (xy 342.088758 -399.48041) (xy 342.081016 -399.4617)
			(xy 342.080596 -399.451576) (xy 342.080596 -399.294096) (xy 342.080189 -399.284909) (xy 342.073673 -399.267724)
			(xy 342.067896 -399.260568) (xy 342.046068 -399.234874) (xy 342.007978 -399.179243) (xy 341.976826 -399.119451)
			(xy 341.95306 -399.056358) (xy 341.937022 -398.990872) (xy 341.928943 -398.923937) (xy 341.92894 -398.856517)
			(xy 341.937012 -398.789581) (xy 341.953044 -398.724094) (xy 341.976804 -398.660999) (xy 342.00795 -398.601203)
			(xy 342.046034 -398.545569) (xy 342.067896 -398.519904) (xy 342.073673 -398.512745) (xy 342.080199 -398.495565)
			(xy 342.080596 -398.486376) (xy 342.080596 -397.99387) (xy 342.080201 -397.984681) (xy 342.073677 -397.967497)
			(xy 342.067896 -397.960342) (xy 342.046042 -397.934669) (xy 342.007953 -397.879035) (xy 341.976802 -397.81924)
			(xy 341.953038 -397.756144) (xy 341.937002 -397.690656) (xy 341.928925 -397.623719) (xy 341.928924 -397.556296)
			(xy 340.800676 -397.556296) (xy 340.803288 -397.561322) (xy 340.826964 -397.624322) (xy 340.84294 -397.689701)
			(xy 340.850987 -397.75652) (xy 340.85099 -397.823823) (xy 340.84295 -397.890643) (xy 340.826981 -397.956023)
			(xy 340.803312 -398.019026) (xy 340.772282 -398.078748) (xy 340.734338 -398.134334) (xy 340.712552 -398.159986)
			(xy 340.70673 -398.167113) (xy 340.700232 -398.184318) (xy 340.699852 -398.193514) (xy 340.699852 -398.351502)
			(xy 340.699438 -398.361675) (xy 340.69165 -398.380472) (xy 340.677262 -398.394857) (xy 340.658463 -398.40264)
			(xy 340.64829 -398.403064) (xy 339.93201 -398.403064) (xy 339.921839 -398.402628) (xy 339.903045 -398.394847)
			(xy 339.88866 -398.380465) (xy 339.880874 -398.361673) (xy 339.880448 -398.351502) (xy 339.880448 -398.193514)
			(xy 339.88002 -398.184329) (xy 339.873518 -398.167145) (xy 339.867748 -398.159986) (xy 339.845922 -398.134365)
			(xy 339.807974 -398.078774) (xy 339.776942 -398.019046) (xy 339.753271 -397.956038) (xy 339.7373 -397.890652)
			(xy 339.729259 -397.823826) (xy 338.600595 -397.823826) (xy 338.572138 -397.878594) (xy 338.534191 -397.934181)
			(xy 338.512404 -397.959834) (xy 338.506611 -397.966982) (xy 338.500094 -397.98417) (xy 338.499704 -397.993362)
			(xy 338.499704 -398.486884) (xy 338.500121 -398.49607) (xy 338.50663 -398.513255) (xy 338.512404 -398.520412)
			(xy 338.534226 -398.546036) (xy 338.572171 -398.601627) (xy 338.6032 -398.661355) (xy 338.626869 -398.724363)
			(xy 338.642838 -398.789748) (xy 338.650879 -398.856574) (xy 338.650875 -398.923881) (xy 338.642828 -398.990705)
			(xy 338.626853 -399.056089) (xy 338.603178 -399.119094) (xy 338.572143 -399.178819) (xy 338.534193 -399.234407)
			(xy 338.512404 -399.26006) (xy 338.5066 -399.2672) (xy 338.50009 -399.284394) (xy 338.499704 -399.293588)
			(xy 338.499704 -399.451576) (xy 338.499259 -399.461728) (xy 338.491472 -399.480479) (xy 338.477082 -399.494803)
			(xy 338.458296 -399.502505) (xy 338.448142 -399.502884) (xy 337.731862 -399.502884) (xy 337.721736 -399.502405)
			(xy 337.703018 -399.494669) (xy 337.688664 -399.480381) (xy 337.680842 -399.4617) (xy 337.6803 -399.451576)
			(xy 337.6803 -399.293588) (xy 337.679895 -399.2844) (xy 337.673378 -399.267216) (xy 337.6676 -399.26006)
			(xy 337.645849 -399.234378) (xy 337.607901 -399.178795) (xy 337.576869 -399.119075) (xy 337.553196 -399.056075)
			(xy 337.537221 -398.990697) (xy 337.529175 -398.923878) (xy 337.529172 -398.856576) (xy 337.537212 -398.789757)
			(xy 337.55318 -398.724377) (xy 337.576847 -398.661374) (xy 337.607874 -398.601651) (xy 337.645816 -398.546065)
			(xy 337.6676 -398.520412) (xy 337.673416 -398.513281) (xy 337.679919 -398.49608) (xy 337.6803 -398.486884)
			(xy 337.6803 -397.993362) (xy 337.679908 -397.984173) (xy 337.673382 -397.966989) (xy 337.6676 -397.959834)
			(xy 337.645823 -397.934173) (xy 337.607877 -397.878587) (xy 337.576845 -397.818864) (xy 337.553174 -397.755861)
			(xy 337.537201 -397.69048) (xy 337.529157 -397.623659) (xy 337.529156 -397.556356) (xy 336.40094 -397.556356)
			(xy 336.403332 -397.560946) (xy 336.4271 -397.624039) (xy 336.443139 -397.689525) (xy 336.451219 -397.756461)
			(xy 336.451222 -397.823882) (xy 336.44315 -397.890819) (xy 336.427117 -397.956306) (xy 336.403355 -398.019402)
			(xy 336.372206 -398.079196) (xy 336.334119 -398.13483) (xy 336.312256 -398.160494) (xy 336.306474 -398.167649)
			(xy 336.299952 -398.184832) (xy 336.299556 -398.194022) (xy 336.299556 -398.351502) (xy 336.299075 -398.361629)
			(xy 336.291346 -398.380351) (xy 336.277058 -398.394708) (xy 336.258373 -398.402526) (xy 336.248248 -398.403064)
			(xy 335.531968 -398.403064) (xy 335.521807 -398.402704) (xy 335.503047 -398.394891) (xy 335.488724 -398.380475)
			(xy 335.481032 -398.361665) (xy 335.48066 -398.351502) (xy 335.48066 -398.194022) (xy 335.480226 -398.184838)
			(xy 335.473727 -398.167654) (xy 335.46796 -398.160494) (xy 335.44606 -398.134859) (xy 335.407975 -398.079219)
			(xy 335.376828 -398.019418) (xy 335.353068 -397.956318) (xy 335.337036 -397.890825) (xy 335.328964 -397.823884)
			(xy 334.200796 -397.823884) (xy 334.172062 -397.879042) (xy 334.133972 -397.934677) (xy 334.112108 -397.960342)
			(xy 334.106312 -397.967488) (xy 334.099797 -397.984678) (xy 334.099408 -397.99387) (xy 334.099408 -398.486376)
			(xy 334.099828 -398.495562) (xy 334.106335 -398.512747) (xy 334.112108 -398.519904) (xy 334.134007 -398.54554)
			(xy 334.172094 -398.601179) (xy 334.203243 -398.660979) (xy 334.227005 -398.72408) (xy 334.243037 -398.789573)
			(xy 334.25111 -398.856514) (xy 334.251107 -398.92394) (xy 334.243028 -398.990881) (xy 334.226989 -399.056372)
			(xy 334.203221 -399.11947) (xy 334.172066 -399.179267) (xy 334.133974 -399.234903) (xy 334.112108 -399.260568)
			(xy 334.106301 -399.267706) (xy 334.099792 -399.284902) (xy 334.099408 -399.294096) (xy 334.099408 -399.451576)
			(xy 334.098965 -399.461696) (xy 334.091226 -399.480398) (xy 334.076918 -399.494712) (xy 334.05822 -399.50246)
			(xy 334.0481 -399.502884) (xy 333.33182 -399.502884) (xy 333.321697 -399.502467) (xy 333.302991 -399.494723)
			(xy 333.288675 -399.480406) (xy 333.280932 -399.461699) (xy 333.280512 -399.451576) (xy 333.280512 -399.294096)
			(xy 333.280101 -399.284909) (xy 333.273587 -399.267725) (xy 333.267812 -399.260568) (xy 333.245983 -399.234874)
			(xy 333.207892 -399.179244) (xy 333.176739 -399.119452) (xy 333.152973 -399.056358) (xy 333.136934 -398.990873)
			(xy 333.128855 -398.923938) (xy 333.128852 -398.856516) (xy 333.136925 -398.78958) (xy 333.152957 -398.724093)
			(xy 333.176717 -398.660998) (xy 333.207865 -398.601203) (xy 333.24595 -398.545569) (xy 333.267812 -398.519904)
			(xy 333.273591 -398.512746) (xy 333.280116 -398.495565) (xy 333.280512 -398.486376) (xy 333.280512 -397.99387)
			(xy 333.280114 -397.984682) (xy 333.273592 -397.967497) (xy 333.267812 -397.960342) (xy 333.245957 -397.934669)
			(xy 333.207868 -397.879036) (xy 333.176716 -397.819241) (xy 333.152951 -397.756145) (xy 333.136914 -397.690657)
			(xy 333.128837 -397.623719) (xy 333.128836 -397.556296) (xy 332.00059 -397.556296) (xy 332.003202 -397.561323)
			(xy 332.026877 -397.624323) (xy 332.042852 -397.689701) (xy 332.050899 -397.75652) (xy 332.050902 -397.823822)
			(xy 332.042862 -397.890642) (xy 332.026893 -397.956022) (xy 332.003225 -398.019025) (xy 331.972197 -398.078748)
			(xy 331.934253 -398.134334) (xy 331.912468 -398.159986) (xy 331.906648 -398.167115) (xy 331.900148 -398.184318)
			(xy 331.899768 -398.193514) (xy 331.899768 -398.351502) (xy 331.899268 -398.361659) (xy 331.891494 -398.380427)
			(xy 331.877131 -398.394792) (xy 331.858363 -398.402568) (xy 331.848206 -398.403064) (xy 331.131926 -398.403064)
			(xy 331.121756 -398.402615) (xy 331.102963 -398.394839) (xy 331.088577 -398.380461) (xy 331.080791 -398.361671)
			(xy 331.080364 -398.351502) (xy 331.080364 -398.193514) (xy 331.079933 -398.184329) (xy 331.073432 -398.167146)
			(xy 331.067664 -398.159986) (xy 331.045838 -398.134365) (xy 331.007889 -398.078775) (xy 330.976856 -398.019047)
			(xy 330.953184 -397.956038) (xy 330.937213 -397.890652) (xy 330.929171 -397.823826) (xy 326.525636 -397.823826)
			(xy 326.525636 -401.723737) (xy 330.929183 -401.723737) (xy 330.929184 -401.65643) (xy 330.937231 -401.589605)
			(xy 330.953207 -401.524221) (xy 330.976884 -401.461216) (xy 331.007921 -401.401492) (xy 331.045874 -401.345906)
			(xy 331.067664 -401.320254) (xy 331.07347 -401.313116) (xy 331.079977 -401.29592) (xy 331.080364 -401.286726)
			(xy 331.080364 -400.793458) (xy 331.07996 -400.78427) (xy 331.073441 -400.767087) (xy 331.067664 -400.75993)
			(xy 331.045882 -400.734273) (xy 331.007931 -400.678688) (xy 330.976896 -400.618965) (xy 330.953222 -400.555961)
			(xy 330.937248 -400.490579) (xy 330.929203 -400.423757) (xy 330.929202 -400.356452) (xy 330.937246 -400.289629)
			(xy 330.953219 -400.224247) (xy 330.976892 -400.161243) (xy 331.007926 -400.10152) (xy 331.045876 -400.045934)
			(xy 331.067664 -400.020282) (xy 331.073459 -400.013136) (xy 331.079973 -399.995946) (xy 331.080364 -399.986754)
			(xy 331.080364 -399.828766) (xy 331.080806 -399.818603) (xy 331.088597 -399.799828) (xy 331.102978 -399.785463)
			(xy 331.121762 -399.777694) (xy 331.131926 -399.777204) (xy 331.848206 -399.777204) (xy 331.85836 -399.777728)
			(xy 331.877123 -399.785498) (xy 331.891486 -399.799854) (xy 331.899267 -399.818612) (xy 331.899768 -399.828766)
			(xy 331.899768 -399.986754) (xy 331.900208 -399.995938) (xy 331.906702 -400.013122) (xy 331.912468 -400.020282)
			(xy 331.934262 -400.045929) (xy 331.97221 -400.101517) (xy 332.003242 -400.161241) (xy 332.026915 -400.224246)
			(xy 332.042887 -400.289629) (xy 332.05093 -400.356452) (xy 332.05093 -400.423757) (xy 332.042885 -400.49058)
			(xy 332.026912 -400.555963) (xy 332.003239 -400.618967) (xy 331.972205 -400.678691) (xy 331.934256 -400.734278)
			(xy 331.912468 -400.75993) (xy 331.906672 -400.767076) (xy 331.900158 -400.784266) (xy 331.899768 -400.793458)
			(xy 331.899768 -401.286726) (xy 331.900173 -401.295914) (xy 331.906691 -401.313098) (xy 331.912468 -401.320254)
			(xy 331.934234 -401.345924) (xy 331.972183 -401.401508) (xy 332.003216 -401.461229) (xy 332.02689 -401.524231)
			(xy 332.042864 -401.589611) (xy 332.05091 -401.656432) (xy 332.050912 -401.723735) (xy 332.04287 -401.790556)
			(xy 332.0269 -401.855937) (xy 332.00323 -401.91894) (xy 331.9722 -401.978663) (xy 331.934254 -402.03425)
			(xy 331.912468 -402.059902) (xy 331.906684 -402.067056) (xy 331.900163 -402.08424) (xy 331.899768 -402.09343)
			(xy 331.899768 -402.251418) (xy 331.899282 -402.261576) (xy 331.891502 -402.280345) (xy 331.877135 -402.294709)
			(xy 331.858364 -402.302484) (xy 331.848206 -402.30298) (xy 331.131926 -402.30298) (xy 331.121758 -402.302515)
			(xy 331.102968 -402.294742) (xy 331.088583 -402.280369) (xy 331.080794 -402.261585) (xy 331.080364 -402.251418)
			(xy 331.080364 -402.09343) (xy 331.079925 -402.084246) (xy 331.07343 -402.067062) (xy 331.067664 -402.059902)
			(xy 331.045854 -402.034268) (xy 331.007904 -401.97868) (xy 330.97687 -401.918954) (xy 330.953197 -401.855947)
			(xy 330.937225 -401.790562) (xy 330.929183 -401.723737) (xy 326.525636 -401.723737) (xy 326.525636 -402.823878)
			(xy 333.128796 -402.823878) (xy 333.128801 -402.75645) (xy 333.136882 -402.689508) (xy 333.152922 -402.624016)
			(xy 333.176693 -402.560918) (xy 333.20785 -402.50112) (xy 333.245945 -402.445485) (xy 333.267812 -402.41982)
			(xy 333.273626 -402.412687) (xy 333.28013 -402.395487) (xy 333.280512 -402.386292) (xy 333.280512 -401.89404)
			(xy 333.28008 -401.884855) (xy 333.273581 -401.867671) (xy 333.267812 -401.860512) (xy 333.245928 -401.834863)
			(xy 333.207839 -401.779227) (xy 333.176689 -401.719428) (xy 333.152925 -401.656329) (xy 333.136891 -401.590838)
			(xy 333.128816 -401.523898) (xy 333.128818 -401.456472) (xy 333.136896 -401.389532) (xy 333.152934 -401.324042)
			(xy 333.176701 -401.260944) (xy 333.207855 -401.201148) (xy 333.245946 -401.145513) (xy 333.267812 -401.119848)
			(xy 333.273615 -401.112707) (xy 333.280125 -401.095513) (xy 333.280512 -401.08632) (xy 333.280512 -400.92884)
			(xy 333.280949 -400.918719) (xy 333.288686 -400.900014) (xy 333.302997 -400.885698) (xy 333.321699 -400.877953)
			(xy 333.33182 -400.877532) (xy 334.0481 -400.877532) (xy 334.058226 -400.877917) (xy 334.076936 -400.885671)
			(xy 334.091252 -400.899997) (xy 334.098991 -400.918713) (xy 334.099408 -400.92884) (xy 334.099408 -401.08632)
			(xy 334.099807 -401.095508) (xy 334.106328 -401.112693) (xy 334.112108 -401.119848) (xy 334.133952 -401.14553)
			(xy 334.172041 -401.201162) (xy 334.203192 -401.260956) (xy 334.226957 -401.324051) (xy 334.242994 -401.389538)
			(xy 334.251071 -401.456474) (xy 334.251073 -401.523896) (xy 334.242999 -401.590833) (xy 334.226966 -401.656321)
			(xy 334.203204 -401.719417) (xy 334.200923 -401.723796) (xy 335.328975 -401.723796) (xy 335.328977 -401.656371)
			(xy 335.337055 -401.589432) (xy 335.353091 -401.523942) (xy 335.376856 -401.460845) (xy 335.408007 -401.401048)
			(xy 335.446096 -401.345412) (xy 335.46796 -401.319746) (xy 335.473769 -401.31261) (xy 335.480275 -401.295412)
			(xy 335.48066 -401.286218) (xy 335.48066 -400.793966) (xy 335.480253 -400.784779) (xy 335.473735 -400.767595)
			(xy 335.46796 -400.760438) (xy 335.446103 -400.734767) (xy 335.408017 -400.679133) (xy 335.376868 -400.619337)
			(xy 335.353106 -400.556241) (xy 335.337071 -400.490753) (xy 335.328995 -400.423816) (xy 335.328995 -400.356393)
			(xy 335.337069 -400.289456) (xy 335.353103 -400.223968) (xy 335.376865 -400.160872) (xy 335.408012 -400.101075)
			(xy 335.446098 -400.04544) (xy 335.46796 -400.019774) (xy 335.473757 -400.01263) (xy 335.48027 -399.995438)
			(xy 335.48066 -399.986246) (xy 335.48066 -399.828766) (xy 335.481099 -399.818635) (xy 335.488842 -399.799909)
			(xy 335.503143 -399.785553) (xy 335.521839 -399.777739) (xy 335.531968 -399.777204) (xy 336.248248 -399.777204)
			(xy 336.258406 -399.777583) (xy 336.27716 -399.785395) (xy 336.291482 -399.799804) (xy 336.299179 -399.818606)
			(xy 336.299556 -399.828766) (xy 336.299556 -399.986246) (xy 336.300002 -399.995429) (xy 336.306492 -400.012613)
			(xy 336.312256 -400.019774) (xy 336.334127 -400.045434) (xy 336.372219 -400.101068) (xy 336.403372 -400.160864)
			(xy 336.427138 -400.223962) (xy 336.443174 -400.289452) (xy 336.45125 -400.356392) (xy 336.451249 -400.423817)
			(xy 336.443172 -400.490756) (xy 336.427135 -400.556246) (xy 336.403368 -400.619344) (xy 336.372214 -400.67914)
			(xy 336.334122 -400.734774) (xy 336.312256 -400.760438) (xy 336.306455 -400.76758) (xy 336.299944 -400.784773)
			(xy 336.299556 -400.793966) (xy 336.299556 -401.286218) (xy 336.299967 -401.295405) (xy 336.306481 -401.312589)
			(xy 336.312256 -401.319746) (xy 336.3341 -401.345428) (xy 336.372192 -401.401059) (xy 336.403346 -401.460853)
			(xy 336.427114 -401.523948) (xy 336.443152 -401.589435) (xy 336.45123 -401.656372) (xy 336.451232 -401.723795)
			(xy 336.443158 -401.790732) (xy 336.427123 -401.856221) (xy 336.40336 -401.919317) (xy 336.372209 -401.979112)
			(xy 336.33412 -402.034746) (xy 336.312256 -402.06041) (xy 336.306467 -402.06756) (xy 336.299949 -402.084747)
			(xy 336.299556 -402.093938) (xy 336.299556 -402.251418) (xy 336.299088 -402.261546) (xy 336.291354 -402.280269)
			(xy 336.277062 -402.294625) (xy 336.258374 -402.302443) (xy 336.248248 -402.30298) (xy 335.531968 -402.30298)
			(xy 335.521809 -402.302604) (xy 335.503052 -402.294794) (xy 335.488729 -402.280384) (xy 335.481034 -402.261579)
			(xy 335.48066 -402.251418) (xy 335.48066 -402.093938) (xy 335.480218 -402.084754) (xy 335.473725 -402.06757)
			(xy 335.46796 -402.06041) (xy 335.446076 -402.034762) (xy 335.40799 -401.979124) (xy 335.376843 -401.919325)
			(xy 335.353082 -401.856226) (xy 335.337049 -401.790735) (xy 335.328975 -401.723796) (xy 334.200923 -401.723796)
			(xy 334.172056 -401.779212) (xy 334.13397 -401.834847) (xy 334.112108 -401.860512) (xy 334.106325 -401.867667)
			(xy 334.099802 -401.88485) (xy 334.099408 -401.89404) (xy 334.099408 -402.386292) (xy 334.09982 -402.395479)
			(xy 334.106332 -402.412663) (xy 334.112108 -402.41982) (xy 334.133925 -402.445524) (xy 334.172014 -402.501153)
			(xy 334.203166 -402.560944) (xy 334.226933 -402.624036) (xy 334.242972 -402.68952) (xy 334.251051 -402.756454)
			(xy 334.251055 -402.823818) (xy 337.529116 -402.823818) (xy 337.52912 -402.75651) (xy 337.537169 -402.689685)
			(xy 337.553145 -402.6243) (xy 337.576822 -402.561294) (xy 337.607859 -402.501569) (xy 337.645811 -402.445981)
			(xy 337.6676 -402.420328) (xy 337.67341 -402.413192) (xy 337.679917 -402.395994) (xy 337.6803 -402.3868)
			(xy 337.6803 -401.893532) (xy 337.679874 -401.884346) (xy 337.673371 -401.867162) (xy 337.6676 -401.860004)
			(xy 337.645794 -401.834367) (xy 337.607848 -401.778778) (xy 337.576818 -401.719052) (xy 337.553148 -401.656045)
			(xy 337.537178 -401.590662) (xy 337.529136 -401.523838) (xy 337.529137 -401.456532) (xy 337.537183 -401.389709)
			(xy 337.553157 -401.324326) (xy 337.57683 -401.261321) (xy 337.607864 -401.201596) (xy 337.645812 -401.146009)
			(xy 337.6676 -401.120356) (xy 337.673398 -401.113212) (xy 337.679912 -401.09602) (xy 337.6803 -401.086828)
			(xy 337.6803 -400.92884) (xy 337.680755 -400.918688) (xy 337.688537 -400.899937) (xy 337.702924 -400.885612)
			(xy 337.721709 -400.877911) (xy 337.731862 -400.877532) (xy 338.448142 -400.877532) (xy 338.45827 -400.877992)
			(xy 338.476991 -400.885732) (xy 338.491346 -400.900026) (xy 338.499165 -400.918714) (xy 338.499704 -400.92884)
			(xy 338.499704 -401.086828) (xy 338.5001 -401.096017) (xy 338.506623 -401.113201) (xy 338.512404 -401.120356)
			(xy 338.534171 -401.146025) (xy 338.572117 -401.20161) (xy 338.603149 -401.261332) (xy 338.626821 -401.324334)
			(xy 338.642794 -401.389714) (xy 338.650839 -401.456534) (xy 338.650841 -401.523836) (xy 338.6428 -401.590657)
			(xy 338.62683 -401.656037) (xy 338.603161 -401.719041) (xy 338.600721 -401.723737) (xy 339.72927 -401.723737)
			(xy 339.729272 -401.65643) (xy 339.737319 -401.589606) (xy 339.753294 -401.524222) (xy 339.77697 -401.461217)
			(xy 339.808006 -401.401492) (xy 339.845959 -401.345906) (xy 339.867748 -401.320254) (xy 339.873553 -401.313115)
			(xy 339.880061 -401.295919) (xy 339.880448 -401.286726) (xy 339.880448 -400.793458) (xy 339.880047 -400.78427)
			(xy 339.873526 -400.767086) (xy 339.867748 -400.75993) (xy 339.845966 -400.734273) (xy 339.808017 -400.678687)
			(xy 339.776983 -400.618965) (xy 339.753309 -400.555961) (xy 339.737335 -400.490579) (xy 339.729291 -400.423757)
			(xy 339.72929 -400.356452) (xy 339.737334 -400.28963) (xy 339.753306 -400.224248) (xy 339.776979 -400.161244)
			(xy 339.808012 -400.10152) (xy 339.845961 -400.045934) (xy 339.867748 -400.020282) (xy 339.873541 -400.013134)
			(xy 339.880056 -399.995946) (xy 339.880448 -399.986754) (xy 339.880448 -399.828766) (xy 339.880906 -399.818605)
			(xy 339.888693 -399.799833) (xy 339.90307 -399.785469) (xy 339.921848 -399.777697) (xy 339.93201 -399.777204)
			(xy 340.64829 -399.777204) (xy 340.658443 -399.777741) (xy 340.677205 -399.785506) (xy 340.69157 -399.799858)
			(xy 340.699351 -399.818613) (xy 340.699852 -399.828766) (xy 340.699852 -399.986754) (xy 340.700295 -399.995937)
			(xy 340.706787 -400.013121) (xy 340.712552 -400.020282) (xy 340.734346 -400.045929) (xy 340.772295 -400.101516)
			(xy 340.803329 -400.16124) (xy 340.827002 -400.224245) (xy 340.842975 -400.289628) (xy 340.851018 -400.356452)
			(xy 340.851018 -400.423757) (xy 340.842973 -400.490581) (xy 340.826999 -400.555963) (xy 340.803325 -400.618968)
			(xy 340.772291 -400.678692) (xy 340.734341 -400.734278) (xy 340.712552 -400.75993) (xy 340.706754 -400.767074)
			(xy 340.700242 -400.784266) (xy 340.699852 -400.793458) (xy 340.699852 -401.286726) (xy 340.70026 -401.295913)
			(xy 340.706777 -401.313097) (xy 340.712552 -401.320254) (xy 340.734318 -401.345924) (xy 340.772268 -401.401508)
			(xy 340.803303 -401.461229) (xy 340.826977 -401.524231) (xy 340.842952 -401.589611) (xy 340.850998 -401.656432)
			(xy 340.851 -401.723735) (xy 340.842958 -401.790556) (xy 340.826987 -401.855937) (xy 340.803316 -401.918941)
			(xy 340.772285 -401.978664) (xy 340.734338 -402.03425) (xy 340.712552 -402.059902) (xy 340.706766 -402.067055)
			(xy 340.700246 -402.08424) (xy 340.699852 -402.09343) (xy 340.699852 -402.251418) (xy 340.699381 -402.261578)
			(xy 340.691599 -402.28035) (xy 340.677226 -402.294715) (xy 340.65845 -402.302487) (xy 340.64829 -402.30298)
			(xy 339.93201 -402.30298) (xy 339.921855 -402.302459) (xy 339.90309 -402.294691) (xy 339.888725 -402.280334)
			(xy 339.880947 -402.261573) (xy 339.880448 -402.251418) (xy 339.880448 -402.09343) (xy 339.880013 -402.084246)
			(xy 339.873515 -402.067062) (xy 339.867748 -402.059902) (xy 339.845938 -402.034268) (xy 339.807989 -401.978679)
			(xy 339.776957 -401.918953) (xy 339.753285 -401.855946) (xy 339.737313 -401.790562) (xy 339.72927 -401.723737)
			(xy 338.600721 -401.723737) (xy 338.572133 -401.778764) (xy 338.534189 -401.834351) (xy 338.512404 -401.860004)
			(xy 338.506624 -401.867161) (xy 338.500099 -401.884342) (xy 338.499704 -401.893532) (xy 338.499704 -402.3868)
			(xy 338.500113 -402.395987) (xy 338.506628 -402.413172) (xy 338.512404 -402.420328) (xy 338.534143 -402.44602)
			(xy 338.572091 -402.501601) (xy 338.603124 -402.56132) (xy 338.626797 -402.624319) (xy 338.642772 -402.689696)
			(xy 338.65082 -402.756514) (xy 338.650824 -402.823814) (xy 338.650816 -402.823878) (xy 341.928884 -402.823878)
			(xy 341.928889 -402.75645) (xy 341.936969 -402.689509) (xy 341.95301 -402.624017) (xy 341.976779 -402.560918)
			(xy 342.007935 -402.501121) (xy 342.046029 -402.445485) (xy 342.067896 -402.41982) (xy 342.073709 -402.412686)
			(xy 342.080214 -402.395487) (xy 342.080596 -402.386292) (xy 342.080596 -401.89404) (xy 342.080168 -401.884855)
			(xy 342.073667 -401.86767) (xy 342.067896 -401.860512) (xy 342.046013 -401.834863) (xy 342.007925 -401.779226)
			(xy 341.976775 -401.719428) (xy 341.953012 -401.656329) (xy 341.936978 -401.590838) (xy 341.928904 -401.523898)
			(xy 341.928906 -401.456472) (xy 341.936984 -401.389533) (xy 341.953021 -401.324043) (xy 341.976787 -401.260945)
			(xy 342.00794 -401.201148) (xy 342.046031 -401.145513) (xy 342.067896 -401.119848) (xy 342.073697 -401.112706)
			(xy 342.080209 -401.095513) (xy 342.080596 -401.08632) (xy 342.080596 -400.92884) (xy 342.081049 -400.918721)
			(xy 342.088783 -400.900019) (xy 342.103088 -400.885703) (xy 342.121785 -400.877956) (xy 342.131904 -400.877532)
			(xy 342.848184 -400.877532) (xy 342.858309 -400.87793) (xy 342.877019 -400.885679) (xy 342.891335 -400.900001)
			(xy 342.899075 -400.918714) (xy 342.899492 -400.92884) (xy 342.899492 -401.08632) (xy 342.899894 -401.095508)
			(xy 342.906413 -401.112692) (xy 342.912192 -401.119848) (xy 342.934037 -401.145529) (xy 342.972126 -401.201161)
			(xy 343.003278 -401.260955) (xy 343.027044 -401.32405) (xy 343.043081 -401.389537) (xy 343.051159 -401.456474)
			(xy 343.051161 -401.523896) (xy 343.043087 -401.590833) (xy 343.027053 -401.656321) (xy 343.003291 -401.719417)
			(xy 343.001041 -401.723737) (xy 344.129061 -401.723737) (xy 344.129063 -401.65643) (xy 344.13711 -401.589606)
			(xy 344.153085 -401.524223) (xy 344.17676 -401.461217) (xy 344.207796 -401.401493) (xy 344.245747 -401.345906)
			(xy 344.267536 -401.320254) (xy 344.273339 -401.313114) (xy 344.279849 -401.295919) (xy 344.280236 -401.286726)
			(xy 344.280236 -400.793458) (xy 344.279838 -400.78427) (xy 344.273315 -400.767086) (xy 344.267536 -400.75993)
			(xy 344.245754 -400.734273) (xy 344.207805 -400.678687) (xy 344.176772 -400.618964) (xy 344.153099 -400.55596)
			(xy 344.137126 -400.490579) (xy 344.129081 -400.423757) (xy 344.129081 -400.356452) (xy 344.137124 -400.28963)
			(xy 344.153096 -400.224248) (xy 344.176768 -400.161244) (xy 344.207801 -400.101521) (xy 344.245749 -400.045934)
			(xy 344.267536 -400.020282) (xy 344.273327 -400.013133) (xy 344.279844 -399.995945) (xy 344.280236 -399.986754)
			(xy 344.280236 -399.828766) (xy 344.280705 -399.818606) (xy 344.288491 -399.799837) (xy 344.302864 -399.785473)
			(xy 344.321638 -399.777699) (xy 344.331798 -399.777204) (xy 345.048078 -399.777204) (xy 345.05823 -399.77775)
			(xy 345.076992 -399.785511) (xy 345.091357 -399.799861) (xy 345.099139 -399.818614) (xy 345.09964 -399.828766)
			(xy 345.09964 -399.986754) (xy 345.100086 -399.995937) (xy 345.106576 -400.013121) (xy 345.11234 -400.020282)
			(xy 345.134134 -400.045929) (xy 345.172084 -400.101516) (xy 345.203118 -400.16124) (xy 345.226792 -400.224245)
			(xy 345.242765 -400.289628) (xy 345.250809 -400.356452) (xy 345.250808 -400.423757) (xy 345.242763 -400.490581)
			(xy 345.226789 -400.555964) (xy 345.203115 -400.618968) (xy 345.172079 -400.678692) (xy 345.134129 -400.734278)
			(xy 345.11234 -400.75993) (xy 345.106541 -400.767073) (xy 345.100029 -400.784265) (xy 345.09964 -400.793458)
			(xy 345.09964 -401.286726) (xy 345.100051 -401.295913) (xy 345.106566 -401.313096) (xy 345.11234 -401.320254)
			(xy 345.134107 -401.345924) (xy 345.172057 -401.401507) (xy 345.203093 -401.461228) (xy 345.226768 -401.52423)
			(xy 345.242743 -401.589611) (xy 345.250789 -401.656432) (xy 345.250791 -401.723735) (xy 345.242749 -401.790557)
			(xy 345.226778 -401.855938) (xy 345.203106 -401.918942) (xy 345.172074 -401.978664) (xy 345.134127 -402.03425)
			(xy 345.11234 -402.059902) (xy 345.106553 -402.067053) (xy 345.100034 -402.084239) (xy 345.09964 -402.09343)
			(xy 345.09964 -402.251418) (xy 345.09925 -402.261593) (xy 345.091455 -402.280393) (xy 345.077059 -402.294778)
			(xy 345.058254 -402.302558) (xy 345.048078 -402.30298) (xy 344.331798 -402.30298) (xy 344.321642 -402.302469)
			(xy 344.302877 -402.294697) (xy 344.288512 -402.280337) (xy 344.280735 -402.261574) (xy 344.280236 -402.251418)
			(xy 344.280236 -402.09343) (xy 344.279803 -402.084245) (xy 344.273304 -402.067061) (xy 344.267536 -402.059902)
			(xy 344.245727 -402.034268) (xy 344.207779 -401.978679) (xy 344.176746 -401.918953) (xy 344.153075 -401.855946)
			(xy 344.137104 -401.790561) (xy 344.129061 -401.723737) (xy 343.001041 -401.723737) (xy 342.972142 -401.779213)
			(xy 342.934055 -401.834847) (xy 342.912192 -401.860512) (xy 342.906407 -401.867665) (xy 342.899886 -401.88485)
			(xy 342.899492 -401.89404) (xy 342.899492 -402.386292) (xy 342.899908 -402.395479) (xy 342.906418 -402.412663)
			(xy 342.912192 -402.41982) (xy 342.934009 -402.445524) (xy 342.9721 -402.501153) (xy 343.003253 -402.560944)
			(xy 343.02702 -402.624035) (xy 343.043059 -402.68952) (xy 343.051139 -402.756454) (xy 343.051143 -402.823819)
			(xy 346.329179 -402.823819) (xy 346.329184 -402.756509) (xy 346.337233 -402.689682) (xy 346.353213 -402.624297)
			(xy 346.376893 -402.56129) (xy 346.407934 -402.501566) (xy 346.445892 -402.445979) (xy 346.467684 -402.420328)
			(xy 346.473492 -402.413191) (xy 346.48 -402.395994) (xy 346.480384 -402.3868) (xy 346.480384 -401.893532)
			(xy 346.479962 -401.884346) (xy 346.473457 -401.867161) (xy 346.467684 -401.860004) (xy 346.445875 -401.834369)
			(xy 346.407924 -401.778781) (xy 346.376889 -401.719055) (xy 346.353216 -401.656049) (xy 346.337243 -401.590664)
			(xy 346.3292 -401.523839) (xy 346.329201 -401.456531) (xy 346.337248 -401.389707) (xy 346.353225 -401.324323)
			(xy 346.376902 -401.261317) (xy 346.40794 -401.201593) (xy 346.445894 -401.146008) (xy 346.467684 -401.120356)
			(xy 346.47348 -401.11321) (xy 346.479995 -401.09602) (xy 346.480384 -401.086828) (xy 346.480384 -400.92884)
			(xy 346.480854 -400.91869) (xy 346.488634 -400.899942) (xy 346.503015 -400.885618) (xy 346.521795 -400.877914)
			(xy 346.531946 -400.877532) (xy 347.248226 -400.877532) (xy 347.258353 -400.878005) (xy 347.277074 -400.88574)
			(xy 347.291429 -400.90003) (xy 347.299249 -400.918715) (xy 347.299788 -400.92884) (xy 347.299788 -401.086828)
			(xy 347.300187 -401.096016) (xy 347.306709 -401.1132) (xy 347.312488 -401.120356) (xy 347.334255 -401.146025)
			(xy 347.372203 -401.201609) (xy 347.403236 -401.261331) (xy 347.426908 -401.324333) (xy 347.442882 -401.389713)
			(xy 347.450927 -401.456533) (xy 347.450929 -401.523836) (xy 347.442887 -401.590657) (xy 347.426917 -401.656038)
			(xy 347.403248 -401.719042) (xy 347.400809 -401.723737) (xy 374.929092 -401.723737) (xy 374.929094 -401.65643)
			(xy 374.937141 -401.589605) (xy 374.953117 -401.524221) (xy 374.976794 -401.461216) (xy 375.007832 -401.401492)
			(xy 375.045786 -401.345906) (xy 375.067576 -401.320254) (xy 375.073372 -401.313108) (xy 375.079888 -401.295918)
			(xy 375.080276 -401.286726) (xy 375.080276 -400.793458) (xy 375.079891 -400.784268) (xy 375.07336 -400.767084)
			(xy 375.067576 -400.75993) (xy 375.045793 -400.734273) (xy 375.007842 -400.678688) (xy 374.976806 -400.618966)
			(xy 374.953131 -400.555962) (xy 374.937157 -400.49058) (xy 374.929112 -400.423757) (xy 374.929111 -400.356452)
			(xy 374.937155 -400.289629) (xy 374.953129 -400.224247) (xy 374.976802 -400.161242) (xy 375.007837 -400.101519)
			(xy 375.045788 -400.045934) (xy 375.067576 -400.020282) (xy 375.07336 -400.013128) (xy 375.079883 -399.995944)
			(xy 375.080276 -399.986754) (xy 375.080276 -399.828766) (xy 375.080637 -399.818587) (xy 375.08844 -399.799785)
			(xy 375.102845 -399.7854) (xy 375.121659 -399.777623) (xy 375.131838 -399.777204) (xy 375.848118 -399.777204)
			(xy 375.858273 -399.777718) (xy 375.877036 -399.785492) (xy 375.891399 -399.799851) (xy 375.899179 -399.818611)
			(xy 375.89968 -399.828766) (xy 375.89968 -399.986754) (xy 375.900117 -399.995938) (xy 375.906612 -400.013123)
			(xy 375.91238 -400.020282) (xy 375.934173 -400.045929) (xy 375.972121 -400.101517) (xy 376.003152 -400.161241)
			(xy 376.026824 -400.224247) (xy 376.042796 -400.289629) (xy 376.050839 -400.356452) (xy 376.050839 -400.423757)
			(xy 376.042794 -400.49058) (xy 376.026821 -400.555962) (xy 376.003149 -400.618967) (xy 375.972116 -400.678691)
			(xy 375.934168 -400.734278) (xy 375.91238 -400.75993) (xy 375.906586 -400.767077) (xy 375.90007 -400.784266)
			(xy 375.89968 -400.793458) (xy 375.89968 -401.286726) (xy 375.900082 -401.295914) (xy 375.906602 -401.313098)
			(xy 375.91238 -401.320254) (xy 375.934146 -401.345924) (xy 375.972094 -401.401508) (xy 376.003127 -401.46123)
			(xy 376.0268 -401.524232) (xy 376.042774 -401.589612) (xy 376.05082 -401.656432) (xy 376.050822 -401.723735)
			(xy 376.04278 -401.790556) (xy 376.02681 -401.855937) (xy 376.003141 -401.91894) (xy 375.972111 -401.978663)
			(xy 375.934166 -402.03425) (xy 375.91238 -402.059902) (xy 375.906598 -402.067057) (xy 375.900075 -402.08424)
			(xy 375.89968 -402.09343) (xy 375.89968 -402.251418) (xy 375.899182 -402.261575) (xy 375.891405 -402.280341)
			(xy 375.877041 -402.294705) (xy 375.858275 -402.302482) (xy 375.848118 -402.30298) (xy 375.131838 -402.30298)
			(xy 375.121671 -402.302505) (xy 375.102881 -402.294736) (xy 375.088495 -402.280366) (xy 375.080706 -402.261584)
			(xy 375.080276 -402.251418) (xy 375.080276 -402.09343) (xy 375.079857 -402.084244) (xy 375.07335 -402.067059)
			(xy 375.067576 -402.059902) (xy 375.045766 -402.034268) (xy 375.007815 -401.97868) (xy 374.976781 -401.918954)
			(xy 374.953108 -401.855947) (xy 374.937135 -401.790562) (xy 374.929092 -401.723737) (xy 347.400809 -401.723737)
			(xy 347.372218 -401.778765) (xy 347.334274 -401.834352) (xy 347.312488 -401.860004) (xy 347.306706 -401.867159)
			(xy 347.300183 -401.884342) (xy 347.299788 -401.893532) (xy 347.299788 -402.3868) (xy 347.300201 -402.395987)
			(xy 347.306713 -402.413171) (xy 347.312488 -402.420328) (xy 347.334227 -402.44602) (xy 347.372176 -402.501601)
			(xy 347.40321 -402.561319) (xy 347.426884 -402.624319) (xy 347.442859 -402.689696) (xy 347.450907 -402.756514)
			(xy 347.450911 -402.823814) (xy 347.450903 -402.823878) (xy 377.128705 -402.823878) (xy 377.12871 -402.75645)
			(xy 377.136791 -402.689508) (xy 377.152832 -402.624016) (xy 377.176603 -402.560917) (xy 377.20776 -402.50112)
			(xy 377.245856 -402.445485) (xy 377.267724 -402.41982) (xy 377.27354 -402.412689) (xy 377.280042 -402.395487)
			(xy 377.280424 -402.386292) (xy 377.280424 -401.89404) (xy 377.279989 -401.884856) (xy 377.273492 -401.867671)
			(xy 377.267724 -401.860512) (xy 377.24584 -401.834863) (xy 377.20775 -401.779227) (xy 377.176599 -401.719429)
			(xy 377.152835 -401.65633) (xy 377.1368 -401.590838) (xy 377.128725 -401.523898) (xy 377.128727 -401.456472)
			(xy 377.136805 -401.389532) (xy 377.152843 -401.324042) (xy 377.176611 -401.260944) (xy 377.207765 -401.201147)
			(xy 377.245858 -401.145513) (xy 377.267724 -401.119848) (xy 377.273528 -401.112708) (xy 377.280037 -401.095513)
			(xy 377.280424 -401.08632) (xy 377.280424 -400.92884) (xy 377.280849 -400.918717) (xy 377.288589 -400.90001)
			(xy 377.302903 -400.885693) (xy 377.321609 -400.877951) (xy 377.331732 -400.877532) (xy 378.048012 -400.877532)
			(xy 378.058139 -400.877907) (xy 378.076849 -400.885665) (xy 378.091164 -400.899994) (xy 378.098904 -400.918712)
			(xy 378.09932 -400.92884) (xy 378.09932 -401.08632) (xy 378.099716 -401.095509) (xy 378.106239 -401.112693)
			(xy 378.11202 -401.119848) (xy 378.133864 -401.14553) (xy 378.171952 -401.201162) (xy 378.203102 -401.260957)
			(xy 378.226866 -401.324051) (xy 378.242903 -401.389538) (xy 378.25098 -401.456474) (xy 378.250982 -401.523896)
			(xy 378.242908 -401.590832) (xy 378.226875 -401.65632) (xy 378.203114 -401.719416) (xy 378.200833 -401.723796)
			(xy 379.328885 -401.723796) (xy 379.328887 -401.656371) (xy 379.336964 -401.589432) (xy 379.353001 -401.523942)
			(xy 379.376766 -401.460844) (xy 379.407918 -401.401047) (xy 379.446008 -401.345412) (xy 379.467872 -401.319746)
			(xy 379.473683 -401.312611) (xy 379.480187 -401.295412) (xy 379.480572 -401.286218) (xy 379.480572 -400.793966)
			(xy 379.480184 -400.784776) (xy 379.473656 -400.767592) (xy 379.467872 -400.760438) (xy 379.446015 -400.734767)
			(xy 379.407928 -400.679133) (xy 379.376778 -400.619337) (xy 379.353015 -400.556241) (xy 379.33698 -400.490753)
			(xy 379.328904 -400.423816) (xy 379.328904 -400.356393) (xy 379.336979 -400.289456) (xy 379.353013 -400.223967)
			(xy 379.376775 -400.160871) (xy 379.407923 -400.101075) (xy 379.446009 -400.04544) (xy 379.467872 -400.019774)
			(xy 379.473671 -400.012631) (xy 379.480182 -399.995438) (xy 379.480572 -399.986246) (xy 379.480572 -399.828766)
			(xy 379.481 -399.818633) (xy 379.488744 -399.799905) (xy 379.503049 -399.785549) (xy 379.521749 -399.777737)
			(xy 379.53188 -399.777204) (xy 380.24816 -399.777204) (xy 380.25828 -399.777649) (xy 380.276984 -399.785385)
			(xy 380.2913 -399.799693) (xy 380.299045 -399.818392) (xy 380.299468 -399.828512) (xy 380.299468 -399.986246)
			(xy 380.299911 -399.99543) (xy 380.306403 -400.012614) (xy 380.312168 -400.019774) (xy 380.334039 -400.045434)
			(xy 380.37213 -400.101068) (xy 380.403282 -400.160865) (xy 380.427047 -400.223963) (xy 380.443083 -400.289453)
			(xy 380.451159 -400.356392) (xy 380.451158 -400.423817) (xy 380.443082 -400.490756) (xy 380.427044 -400.556246)
			(xy 380.403278 -400.619343) (xy 380.372125 -400.679139) (xy 380.334033 -400.734773) (xy 380.312168 -400.760438)
			(xy 380.306369 -400.767581) (xy 380.299856 -400.784773) (xy 380.299468 -400.793966) (xy 380.299468 -401.286218)
			(xy 380.299877 -401.295405) (xy 380.306392 -401.312589) (xy 380.312168 -401.319746) (xy 380.334011 -401.345429)
			(xy 380.372103 -401.40106) (xy 380.403256 -401.460853) (xy 380.427023 -401.523948) (xy 380.443061 -401.589435)
			(xy 380.451139 -401.656372) (xy 380.451141 -401.723795) (xy 380.443067 -401.790732) (xy 380.427033 -401.85622)
			(xy 380.40327 -401.919316) (xy 380.37212 -401.979112) (xy 380.334032 -402.034745) (xy 380.312168 -402.06041)
			(xy 380.306381 -402.067562) (xy 380.299861 -402.084747) (xy 380.299468 -402.093938) (xy 380.299468 -402.251418)
			(xy 380.298989 -402.261545) (xy 380.291256 -402.280265) (xy 380.276968 -402.29462) (xy 380.258284 -402.30244)
			(xy 380.24816 -402.30298) (xy 379.53188 -402.30298) (xy 379.521754 -402.3026) (xy 379.503046 -402.294842)
			(xy 379.488731 -402.280514) (xy 379.48099 -402.261799) (xy 379.480572 -402.251672) (xy 379.480572 -402.093938)
			(xy 379.48015 -402.084752) (xy 379.473645 -402.067567) (xy 379.467872 -402.06041) (xy 379.445987 -402.034762)
			(xy 379.407901 -401.979124) (xy 379.376753 -401.919326) (xy 379.352991 -401.856227) (xy 379.336958 -401.790736)
			(xy 379.328885 -401.723796) (xy 378.200833 -401.723796) (xy 378.171967 -401.779212) (xy 378.133882 -401.834846)
			(xy 378.11202 -401.860512) (xy 378.106238 -401.867668) (xy 378.099714 -401.88485) (xy 378.09932 -401.89404)
			(xy 378.09932 -402.386292) (xy 378.099729 -402.395479) (xy 378.106243 -402.412664) (xy 378.11202 -402.41982)
			(xy 378.133836 -402.445524) (xy 378.171925 -402.501154) (xy 378.203077 -402.560945) (xy 378.226843 -402.624037)
			(xy 378.242881 -402.689521) (xy 378.25096 -402.756454) (xy 378.250965 -402.823818) (xy 381.529025 -402.823818)
			(xy 381.529029 -402.75651) (xy 381.537078 -402.689684) (xy 381.553055 -402.6243) (xy 381.576732 -402.561293)
			(xy 381.607769 -402.501568) (xy 381.645722 -402.445981) (xy 381.667512 -402.420328) (xy 381.673323 -402.413193)
			(xy 381.679829 -402.395995) (xy 381.680212 -402.3868) (xy 381.680212 -401.893532) (xy 381.679784 -401.884347)
			(xy 381.673282 -401.867162) (xy 381.667512 -401.860004) (xy 381.645705 -401.834368) (xy 381.607759 -401.778778)
			(xy 381.576728 -401.719052) (xy 381.553058 -401.656046) (xy 381.537087 -401.590662) (xy 381.529045 -401.523838)
			(xy 381.529046 -401.456532) (xy 381.537092 -401.389708) (xy 381.553066 -401.324325) (xy 381.57674 -401.26132)
			(xy 381.607774 -401.201596) (xy 381.645724 -401.146009) (xy 381.667512 -401.120356) (xy 381.673311 -401.113213)
			(xy 381.679824 -401.096021) (xy 381.680212 -401.086828) (xy 381.680212 -400.92884) (xy 381.680649 -400.918719)
			(xy 381.688386 -400.900014) (xy 381.702697 -400.885698) (xy 381.721399 -400.877953) (xy 381.73152 -400.877532)
			(xy 382.448054 -400.877532) (xy 382.458177 -400.878064) (xy 382.476895 -400.885775) (xy 382.491253 -400.900048)
			(xy 382.499075 -400.91872) (xy 382.499616 -400.92884) (xy 382.499616 -401.086828) (xy 382.500009 -401.096017)
			(xy 382.506534 -401.113201) (xy 382.512316 -401.120356) (xy 382.534085 -401.146024) (xy 382.572038 -401.201607)
			(xy 382.603074 -401.261328) (xy 382.62675 -401.32433) (xy 382.642726 -401.389711) (xy 382.650772 -401.456533)
			(xy 382.650774 -401.523837) (xy 382.642731 -401.590659) (xy 382.626759 -401.656041) (xy 382.603087 -401.719045)
			(xy 382.600649 -401.723737) (xy 383.729179 -401.723737) (xy 383.729181 -401.65643) (xy 383.737228 -401.589605)
			(xy 383.753204 -401.524222) (xy 383.77688 -401.461216) (xy 383.807917 -401.401492) (xy 383.84587 -401.345906)
			(xy 383.86766 -401.320254) (xy 383.873466 -401.313116) (xy 383.879973 -401.29592) (xy 383.88036 -401.286726)
			(xy 383.88036 -400.793458) (xy 383.879957 -400.78427) (xy 383.873437 -400.767087) (xy 383.86766 -400.75993)
			(xy 383.845878 -400.734273) (xy 383.807927 -400.678688) (xy 383.776893 -400.618965) (xy 383.753219 -400.555961)
			(xy 383.737245 -400.490579) (xy 383.7292 -400.423757) (xy 383.729199 -400.356452) (xy 383.737243 -400.28963)
			(xy 383.753216 -400.224247) (xy 383.776889 -400.161243) (xy 383.807923 -400.10152) (xy 383.845872 -400.045934)
			(xy 383.86766 -400.020282) (xy 383.873454 -400.013135) (xy 383.879969 -399.995946) (xy 383.88036 -399.986754)
			(xy 383.88036 -399.828766) (xy 383.880806 -399.818603) (xy 383.888596 -399.799829) (xy 383.902976 -399.785464)
			(xy 383.921759 -399.777695) (xy 383.931922 -399.777204) (xy 384.648202 -399.777204) (xy 384.658356 -399.777731)
			(xy 384.677118 -399.7855) (xy 384.691482 -399.799855) (xy 384.699263 -399.818613) (xy 384.699764 -399.828766)
			(xy 384.699764 -399.986754) (xy 384.700205 -399.995938) (xy 384.706698 -400.013122) (xy 384.712464 -400.020282)
			(xy 384.734258 -400.045929) (xy 384.772206 -400.101516) (xy 384.803239 -400.161241) (xy 384.826911 -400.224246)
			(xy 384.842884 -400.289629) (xy 384.850927 -400.356452) (xy 384.850927 -400.423757) (xy 384.842882 -400.49058)
			(xy 384.826909 -400.555963) (xy 384.803235 -400.618968) (xy 384.772201 -400.678691) (xy 384.734252 -400.734278)
			(xy 384.712464 -400.75993) (xy 384.706668 -400.767075) (xy 384.700154 -400.784266) (xy 384.699764 -400.793458)
			(xy 384.699764 -401.286726) (xy 384.70017 -401.295913) (xy 384.706687 -401.313097) (xy 384.712464 -401.320254)
			(xy 384.73423 -401.345924) (xy 384.772179 -401.401508) (xy 384.803213 -401.461229) (xy 384.826887 -401.524231)
			(xy 384.842861 -401.589611) (xy 384.850907 -401.656432) (xy 384.850909 -401.723735) (xy 384.842867 -401.790556)
			(xy 384.826897 -401.855937) (xy 384.803227 -401.918941) (xy 384.772196 -401.978663) (xy 384.73425 -402.03425)
			(xy 384.712464 -402.059902) (xy 384.706679 -402.067056) (xy 384.700158 -402.08424) (xy 384.699764 -402.09343)
			(xy 384.699764 -402.251418) (xy 384.699282 -402.261577) (xy 384.691502 -402.280346) (xy 384.677133 -402.294711)
			(xy 384.658361 -402.302485) (xy 384.648202 -402.30298) (xy 383.931922 -402.30298) (xy 383.921754 -402.302518)
			(xy 383.902963 -402.294744) (xy 383.888578 -402.28037) (xy 383.88079 -402.261586) (xy 383.88036 -402.251418)
			(xy 383.88036 -402.09343) (xy 383.879922 -402.084246) (xy 383.873426 -402.067062) (xy 383.86766 -402.059902)
			(xy 383.84585 -402.034268) (xy 383.8079 -401.97868) (xy 383.776867 -401.918954) (xy 383.753194 -401.855947)
			(xy 383.737222 -401.790562) (xy 383.729179 -401.723737) (xy 382.600649 -401.723737) (xy 382.572053 -401.778767)
			(xy 382.534104 -401.834352) (xy 382.512316 -401.860004) (xy 382.506537 -401.867162) (xy 382.500011 -401.884343)
			(xy 382.499616 -401.893532) (xy 382.499616 -402.3868) (xy 382.500023 -402.395988) (xy 382.506538 -402.413172)
			(xy 382.512316 -402.420328) (xy 382.534058 -402.446018) (xy 382.572011 -402.501598) (xy 382.603049 -402.561316)
			(xy 382.626726 -402.624316) (xy 382.642704 -402.689694) (xy 382.650753 -402.756513) (xy 382.650757 -402.823815)
			(xy 382.650749 -402.823878) (xy 385.928793 -402.823878) (xy 385.928798 -402.75645) (xy 385.936878 -402.689508)
			(xy 385.952919 -402.624017) (xy 385.976689 -402.560918) (xy 386.007846 -402.50112) (xy 386.045941 -402.445485)
			(xy 386.067808 -402.41982) (xy 386.073622 -402.412687) (xy 386.080126 -402.395487) (xy 386.080508 -402.386292)
			(xy 386.080508 -401.89404) (xy 386.080077 -401.884855) (xy 386.073578 -401.867671) (xy 386.067808 -401.860512)
			(xy 386.045924 -401.834863) (xy 386.007835 -401.779226) (xy 385.976685 -401.719428) (xy 385.952922 -401.656329)
			(xy 385.936887 -401.590838) (xy 385.928813 -401.523898) (xy 385.928815 -401.456472) (xy 385.936893 -401.389533)
			(xy 385.952931 -401.324042) (xy 385.976697 -401.260944) (xy 386.007851 -401.201148) (xy 386.045943 -401.145513)
			(xy 386.067808 -401.119848) (xy 386.07361 -401.112707) (xy 386.080121 -401.095513) (xy 386.080508 -401.08632)
			(xy 386.080508 -400.92884) (xy 386.080949 -400.918719) (xy 386.088686 -400.900015) (xy 386.102995 -400.885699)
			(xy 386.121695 -400.877954) (xy 386.131816 -400.877532) (xy 386.848096 -400.877532) (xy 386.858222 -400.87792)
			(xy 386.876932 -400.885673) (xy 386.891247 -400.899998) (xy 386.898987 -400.918714) (xy 386.899404 -400.92884)
			(xy 386.899404 -401.08632) (xy 386.899804 -401.095508) (xy 386.906325 -401.112692) (xy 386.912104 -401.119848)
			(xy 386.933948 -401.14553) (xy 386.972037 -401.201162) (xy 387.003189 -401.260956) (xy 387.026954 -401.324051)
			(xy 387.04299 -401.389538) (xy 387.051068 -401.456474) (xy 387.05107 -401.523896) (xy 387.042996 -401.590833)
			(xy 387.026963 -401.656321) (xy 387.003201 -401.719417) (xy 387.000951 -401.723737) (xy 388.12897 -401.723737)
			(xy 388.128972 -401.65643) (xy 388.137019 -401.589606) (xy 388.152994 -401.524222) (xy 388.17667 -401.461217)
			(xy 388.207706 -401.401492) (xy 388.245659 -401.345906) (xy 388.267448 -401.320254) (xy 388.273253 -401.313115)
			(xy 388.279761 -401.295919) (xy 388.280148 -401.286726) (xy 388.280148 -400.793458) (xy 388.279747 -400.78427)
			(xy 388.273226 -400.767086) (xy 388.267448 -400.75993) (xy 388.245666 -400.734273) (xy 388.207717 -400.678687)
			(xy 388.176683 -400.618965) (xy 388.153009 -400.555961) (xy 388.137035 -400.490579) (xy 388.128991 -400.423757)
			(xy 388.12899 -400.356452) (xy 388.137034 -400.28963) (xy 388.153006 -400.224248) (xy 388.176679 -400.161244)
			(xy 388.207712 -400.10152) (xy 388.245661 -400.045934) (xy 388.267448 -400.020282) (xy 388.273241 -400.013134)
			(xy 388.279756 -399.995946) (xy 388.280148 -399.986754) (xy 388.280148 -399.828766) (xy 388.280606 -399.818605)
			(xy 388.288393 -399.799833) (xy 388.30277 -399.785469) (xy 388.321548 -399.777697) (xy 388.33171 -399.777204)
			(xy 389.04799 -399.777204) (xy 389.058143 -399.777741) (xy 389.076905 -399.785506) (xy 389.09127 -399.799858)
			(xy 389.099051 -399.818613) (xy 389.099552 -399.828766) (xy 389.099552 -399.986754) (xy 389.099995 -399.995937)
			(xy 389.106487 -400.013121) (xy 389.112252 -400.020282) (xy 389.134046 -400.045929) (xy 389.171995 -400.101516)
			(xy 389.203029 -400.16124) (xy 389.226702 -400.224245) (xy 389.242675 -400.289628) (xy 389.250718 -400.356452)
			(xy 389.250718 -400.423757) (xy 389.242673 -400.490581) (xy 389.226699 -400.555963) (xy 389.203025 -400.618968)
			(xy 389.171991 -400.678692) (xy 389.134041 -400.734278) (xy 389.112252 -400.75993) (xy 389.106454 -400.767074)
			(xy 389.099942 -400.784266) (xy 389.099552 -400.793458) (xy 389.099552 -401.286726) (xy 389.09996 -401.295913)
			(xy 389.106477 -401.313097) (xy 389.112252 -401.320254) (xy 389.134018 -401.345924) (xy 389.171968 -401.401508)
			(xy 389.203003 -401.461229) (xy 389.226677 -401.524231) (xy 389.242652 -401.589611) (xy 389.250698 -401.656432)
			(xy 389.2507 -401.723735) (xy 389.242658 -401.790556) (xy 389.226687 -401.855937) (xy 389.203016 -401.918941)
			(xy 389.171985 -401.978664) (xy 389.134038 -402.03425) (xy 389.112252 -402.059902) (xy 389.106466 -402.067055)
			(xy 389.099946 -402.08424) (xy 389.099552 -402.09343) (xy 389.099552 -402.251418) (xy 389.099081 -402.261578)
			(xy 389.091299 -402.28035) (xy 389.076926 -402.294715) (xy 389.05815 -402.302487) (xy 389.04799 -402.30298)
			(xy 388.33171 -402.30298) (xy 388.321555 -402.302459) (xy 388.30279 -402.294691) (xy 388.288425 -402.280334)
			(xy 388.280647 -402.261573) (xy 388.280148 -402.251418) (xy 388.280148 -402.09343) (xy 388.279713 -402.084246)
			(xy 388.273215 -402.067062) (xy 388.267448 -402.059902) (xy 388.245638 -402.034268) (xy 388.207689 -401.978679)
			(xy 388.176657 -401.918953) (xy 388.152985 -401.855946) (xy 388.137013 -401.790562) (xy 388.12897 -401.723737)
			(xy 387.000951 -401.723737) (xy 386.972053 -401.779212) (xy 386.933967 -401.834847) (xy 386.912104 -401.860512)
			(xy 386.90632 -401.867666) (xy 386.899798 -401.88485) (xy 386.899404 -401.89404) (xy 386.899404 -402.386292)
			(xy 386.899817 -402.395479) (xy 386.906329 -402.412663) (xy 386.912104 -402.41982) (xy 386.933921 -402.445524)
			(xy 386.972011 -402.501153) (xy 387.003163 -402.560944) (xy 387.02693 -402.624036) (xy 387.042968 -402.68952)
			(xy 387.051048 -402.756454) (xy 387.051052 -402.823818) (xy 390.329113 -402.823818) (xy 390.329117 -402.75651)
			(xy 390.337166 -402.689685) (xy 390.353142 -402.6243) (xy 390.376819 -402.561294) (xy 390.407855 -402.501569)
			(xy 390.445807 -402.445981) (xy 390.467596 -402.420328) (xy 390.473405 -402.413192) (xy 390.479912 -402.395994)
			(xy 390.480296 -402.3868) (xy 390.480296 -401.893532) (xy 390.479871 -401.884346) (xy 390.473368 -401.867162)
			(xy 390.467596 -401.860004) (xy 390.44579 -401.834367) (xy 390.407845 -401.778778) (xy 390.376815 -401.719052)
			(xy 390.353145 -401.656045) (xy 390.337174 -401.590661) (xy 390.329133 -401.523838) (xy 390.329134 -401.456532)
			(xy 390.33718 -401.389709) (xy 390.353154 -401.324326) (xy 390.376827 -401.261321) (xy 390.40786 -401.201596)
			(xy 390.445808 -401.146009) (xy 390.467596 -401.120356) (xy 390.473393 -401.113211) (xy 390.479908 -401.09602)
			(xy 390.480296 -401.086828) (xy 390.480296 -400.92884) (xy 390.480749 -400.918721) (xy 390.488483 -400.900019)
			(xy 390.502788 -400.885703) (xy 390.521485 -400.877956) (xy 390.531604 -400.877532) (xy 391.248138 -400.877532)
			(xy 391.258266 -400.877995) (xy 391.276987 -400.885734) (xy 391.291341 -400.900027) (xy 391.299161 -400.918714)
			(xy 391.2997 -400.92884) (xy 391.2997 -401.086828) (xy 391.300096 -401.096017) (xy 391.30662 -401.113201)
			(xy 391.3124 -401.120356) (xy 391.334167 -401.146025) (xy 391.372114 -401.20161) (xy 391.403146 -401.261331)
			(xy 391.426818 -401.324334) (xy 391.442791 -401.389713) (xy 391.450836 -401.456534) (xy 391.450838 -401.523836)
			(xy 391.442797 -401.590657) (xy 391.426827 -401.656038) (xy 391.403158 -401.719041) (xy 391.372129 -401.778764)
			(xy 391.334185 -401.834351) (xy 391.3124 -401.860004) (xy 391.306619 -401.86716) (xy 391.300095 -401.884342)
			(xy 391.2997 -401.893532) (xy 391.2997 -402.3868) (xy 391.30011 -402.395987) (xy 391.306624 -402.413171)
			(xy 391.3124 -402.420328) (xy 391.334139 -402.446019) (xy 391.372087 -402.501601) (xy 391.40312 -402.56132)
			(xy 391.426794 -402.624319) (xy 391.442769 -402.689696) (xy 391.450817 -402.756514) (xy 391.450821 -402.823814)
			(xy 391.442782 -402.890633) (xy 391.426815 -402.956012) (xy 391.40315 -403.019014) (xy 391.372124 -403.078737)
			(xy 391.334184 -403.134323) (xy 391.3124 -403.159976) (xy 391.306589 -403.167111) (xy 391.300083 -403.184309)
			(xy 391.2997 -403.193504) (xy 391.2997 -403.351492) (xy 391.299277 -403.361614) (xy 391.291532 -403.380317)
			(xy 391.277217 -403.394632) (xy 391.258514 -403.402377) (xy 391.248392 -403.4028) (xy 390.531858 -403.4028)
			(xy 390.521734 -403.402309) (xy 390.503019 -403.394575) (xy 390.488666 -403.380291) (xy 390.480841 -403.361614)
			(xy 390.480296 -403.351492) (xy 390.480296 -403.193504) (xy 390.479885 -403.184317) (xy 390.473372 -403.167133)
			(xy 390.467596 -403.159976) (xy 390.445763 -403.134362) (xy 390.407818 -403.078769) (xy 390.376789 -403.01904)
			(xy 390.353121 -402.95603) (xy 390.337153 -402.890644) (xy 390.329113 -402.823818) (xy 387.051052 -402.823818)
			(xy 387.051052 -402.823874) (xy 387.042981 -402.890809) (xy 387.026951 -402.956295) (xy 387.003193 -403.01939)
			(xy 386.972048 -403.079185) (xy 386.933965 -403.134819) (xy 386.912104 -403.160484) (xy 386.90629 -403.167617)
			(xy 386.899785 -403.184817) (xy 386.899404 -403.194012) (xy 386.899404 -403.351492) (xy 386.898978 -403.361613)
			(xy 386.891233 -403.380316) (xy 386.87692 -403.394631) (xy 386.858217 -403.402377) (xy 386.848096 -403.4028)
			(xy 386.131816 -403.4028) (xy 386.121695 -403.402371) (xy 386.102991 -403.394628) (xy 386.088676 -403.380315)
			(xy 386.080931 -403.361613) (xy 386.080508 -403.351492) (xy 386.080508 -403.194012) (xy 386.08009 -403.184826)
			(xy 386.073582 -403.167641) (xy 386.067808 -403.160484) (xy 386.045897 -403.134858) (xy 386.007809 -403.079218)
			(xy 385.97666 -403.019416) (xy 385.952898 -402.956314) (xy 385.936865 -402.89082) (xy 385.928793 -402.823878)
			(xy 382.650749 -402.823878) (xy 382.642717 -402.890635) (xy 382.626748 -402.956015) (xy 382.603078 -403.019018)
			(xy 382.572048 -403.07874) (xy 382.534102 -403.134324) (xy 382.512316 -403.159976) (xy 382.506507 -403.167112)
			(xy 382.499999 -403.18431) (xy 382.499616 -403.193504) (xy 382.499616 -403.351492) (xy 382.499109 -403.361598)
			(xy 382.491377 -403.380273) (xy 382.477087 -403.394568) (xy 382.458414 -403.402306) (xy 382.448308 -403.4028)
			(xy 381.731774 -403.4028) (xy 381.721651 -403.402296) (xy 381.702936 -403.394567) (xy 381.688582 -403.380287)
			(xy 381.680757 -403.361613) (xy 381.680212 -403.351492) (xy 381.680212 -403.193504) (xy 381.679797 -403.184317)
			(xy 381.673286 -403.167133) (xy 381.667512 -403.159976) (xy 381.645678 -403.134362) (xy 381.607732 -403.07877)
			(xy 381.576703 -403.019041) (xy 381.553034 -402.956031) (xy 381.537065 -402.890644) (xy 381.529025 -402.823818)
			(xy 378.250965 -402.823818) (xy 378.250965 -402.823874) (xy 378.242894 -402.890808) (xy 378.226864 -402.956294)
			(xy 378.203106 -403.019389) (xy 378.171962 -403.079184) (xy 378.13388 -403.134818) (xy 378.11202 -403.160484)
			(xy 378.106208 -403.167618) (xy 378.099702 -403.184817) (xy 378.09932 -403.194012) (xy 378.09932 -403.351492)
			(xy 378.098809 -403.361598) (xy 378.091078 -403.380272) (xy 378.076789 -403.394566) (xy 378.058118 -403.402305)
			(xy 378.048012 -403.4028) (xy 377.331732 -403.4028) (xy 377.321612 -403.402358) (xy 377.302909 -403.39462)
			(xy 377.288593 -403.380312) (xy 377.280847 -403.361612) (xy 377.280424 -403.351492) (xy 377.280424 -403.194012)
			(xy 377.280002 -403.184826) (xy 377.273496 -403.167642) (xy 377.267724 -403.160484) (xy 377.245812 -403.134858)
			(xy 377.207723 -403.079218) (xy 377.176573 -403.019417) (xy 377.152811 -402.956315) (xy 377.136778 -402.890821)
			(xy 377.128705 -402.823878) (xy 347.450903 -402.823878) (xy 347.442872 -402.890633) (xy 347.426905 -402.956012)
			(xy 347.403239 -403.019015) (xy 347.372213 -403.078737) (xy 347.334272 -403.134323) (xy 347.312488 -403.159976)
			(xy 347.306675 -403.16711) (xy 347.300171 -403.184309) (xy 347.299788 -403.193504) (xy 347.299788 -403.351492)
			(xy 347.299372 -403.361647) (xy 347.291576 -403.380402) (xy 347.277178 -403.394726) (xy 347.258383 -403.402424)
			(xy 347.248226 -403.4028) (xy 346.531946 -403.4028) (xy 346.521827 -403.402237) (xy 346.503115 -403.394532)
			(xy 346.488758 -403.380269) (xy 346.48093 -403.361607) (xy 346.480384 -403.351492) (xy 346.480384 -403.193504)
			(xy 346.479975 -403.184317) (xy 346.473461 -403.167132) (xy 346.467684 -403.159976) (xy 346.445847 -403.134364)
			(xy 346.407897 -403.078772) (xy 346.376863 -403.019044) (xy 346.353191 -402.956034) (xy 346.33722 -402.890646)
			(xy 346.329179 -402.823819) (xy 343.051143 -402.823819) (xy 343.051143 -402.823874) (xy 343.043072 -402.890809)
			(xy 343.027042 -402.956296) (xy 343.003282 -403.019391) (xy 342.972137 -403.079185) (xy 342.934053 -403.134819)
			(xy 342.912192 -403.160484) (xy 342.906376 -403.167616) (xy 342.899873 -403.184817) (xy 342.899492 -403.194012)
			(xy 342.899492 -403.351492) (xy 342.899077 -403.361615) (xy 342.89133 -403.38032) (xy 342.877013 -403.394635)
			(xy 342.858307 -403.402379) (xy 342.848184 -403.4028) (xy 342.131904 -403.4028) (xy 342.121782 -403.402381)
			(xy 342.103078 -403.394634) (xy 342.088764 -403.380318) (xy 342.081019 -403.361614) (xy 342.080596 -403.351492)
			(xy 342.080596 -403.194012) (xy 342.080181 -403.184825) (xy 342.073671 -403.167641) (xy 342.067896 -403.160484)
			(xy 342.045985 -403.134858) (xy 342.007898 -403.079217) (xy 341.97675 -403.019416) (xy 341.952988 -402.956314)
			(xy 341.936956 -402.89082) (xy 341.928884 -402.823878) (xy 338.650816 -402.823878) (xy 338.642785 -402.890633)
			(xy 338.626819 -402.956012) (xy 338.603153 -403.019014) (xy 338.572128 -403.078737) (xy 338.534188 -403.134323)
			(xy 338.512404 -403.159976) (xy 338.506593 -403.167111) (xy 338.500087 -403.184309) (xy 338.499704 -403.193504)
			(xy 338.499704 -403.351492) (xy 338.499272 -403.361645) (xy 338.49148 -403.380397) (xy 338.477086 -403.39472)
			(xy 338.458297 -403.402421) (xy 338.448142 -403.4028) (xy 337.731862 -403.4028) (xy 337.721738 -403.402306)
			(xy 337.703023 -403.394573) (xy 337.68867 -403.38029) (xy 337.680845 -403.361614) (xy 337.6803 -403.351492)
			(xy 337.6803 -403.193504) (xy 337.679888 -403.184317) (xy 337.673375 -403.167133) (xy 337.6676 -403.159976)
			(xy 337.645766 -403.134362) (xy 337.607822 -403.078769) (xy 337.576793 -403.01904) (xy 337.553124 -402.956031)
			(xy 337.537156 -402.890644) (xy 337.529116 -402.823818) (xy 334.251055 -402.823818) (xy 334.251055 -402.823874)
			(xy 334.242984 -402.890809) (xy 334.226954 -402.956295) (xy 334.203196 -403.01939) (xy 334.172051 -403.079185)
			(xy 334.133969 -403.134819) (xy 334.112108 -403.160484) (xy 334.106294 -403.167617) (xy 334.09979 -403.184817)
			(xy 334.099408 -403.194012) (xy 334.099408 -403.351492) (xy 334.098978 -403.361613) (xy 334.091234 -403.380315)
			(xy 334.076922 -403.394629) (xy 334.058221 -403.402376) (xy 334.0481 -403.4028) (xy 333.33182 -403.4028)
			(xy 333.321699 -403.402368) (xy 333.302996 -403.394626) (xy 333.288681 -403.380315) (xy 333.280935 -403.361613)
			(xy 333.280512 -403.351492) (xy 333.280512 -403.194012) (xy 333.280093 -403.184826) (xy 333.273585 -403.167642)
			(xy 333.267812 -403.160484) (xy 333.2459 -403.134858) (xy 333.207812 -403.079218) (xy 333.176663 -403.019417)
			(xy 333.152901 -402.956315) (xy 333.136869 -402.890821) (xy 333.128796 -402.823878) (xy 326.525636 -402.823878)
			(xy 326.525636 -405.623648) (xy 330.929194 -405.623648) (xy 330.929195 -405.556343) (xy 330.93724 -405.489519)
			(xy 330.953214 -405.424136) (xy 330.976889 -405.361131) (xy 331.007924 -405.301408) (xy 331.045875 -405.245822)
			(xy 331.067664 -405.22017) (xy 331.073464 -405.213027) (xy 331.079975 -405.195835) (xy 331.080364 -405.186642)
			(xy 331.080364 -404.693374) (xy 331.079952 -404.684187) (xy 331.073438 -404.667004) (xy 331.067664 -404.659846)
			(xy 331.045897 -404.634176) (xy 331.007946 -404.578593) (xy 330.976911 -404.518872) (xy 330.953235 -404.45587)
			(xy 330.93726 -404.390489) (xy 330.929214 -404.323668) (xy 330.929212 -404.256365) (xy 330.937254 -404.189543)
			(xy 330.953226 -404.124162) (xy 330.976897 -404.061158) (xy 331.007929 -404.001435) (xy 331.045877 -403.94585)
			(xy 331.067664 -403.920198) (xy 331.073452 -403.913047) (xy 331.07997 -403.895861) (xy 331.080364 -403.88667)
			(xy 331.080364 -403.728682) (xy 331.08075 -403.718506) (xy 331.088546 -403.699706) (xy 331.102943 -403.685321)
			(xy 331.12175 -403.677541) (xy 331.131926 -403.67712) (xy 331.848206 -403.67712) (xy 331.858362 -403.677628)
			(xy 331.877128 -403.685401) (xy 331.891492 -403.699762) (xy 331.899269 -403.718526) (xy 331.899768 -403.728682)
			(xy 331.899768 -403.88667) (xy 331.9002 -403.895855) (xy 331.906699 -403.913039) (xy 331.912468 -403.920198)
			(xy 331.934277 -403.945832) (xy 331.972225 -404.001422) (xy 332.003257 -404.061148) (xy 332.026928 -404.124154)
			(xy 332.042899 -404.189539) (xy 332.050942 -404.256363) (xy 332.05094 -404.32367) (xy 332.042893 -404.390494)
			(xy 332.026918 -404.455877) (xy 332.003243 -404.518883) (xy 331.972208 -404.578607) (xy 331.934257 -404.634194)
			(xy 331.912468 -404.659846) (xy 331.906665 -404.666987) (xy 331.900155 -404.684181) (xy 331.899768 -404.693374)
			(xy 331.899768 -405.186642) (xy 331.900165 -405.19583) (xy 331.906689 -405.213014) (xy 331.912468 -405.22017)
			(xy 331.93425 -405.245827) (xy 331.972198 -405.301413) (xy 332.003231 -405.361136) (xy 332.026904 -405.42414)
			(xy 332.042877 -405.489521) (xy 332.050922 -405.556343) (xy 332.050923 -405.623648) (xy 332.042879 -405.69047)
			(xy 332.026907 -405.755852) (xy 332.003235 -405.818856) (xy 331.972203 -405.878579) (xy 331.934255 -405.934166)
			(xy 331.912468 -405.959818) (xy 331.906677 -405.966967) (xy 331.90016 -405.984155) (xy 331.899768 -405.993346)
			(xy 331.899768 -406.151334) (xy 331.899295 -406.161493) (xy 331.89151 -406.180262) (xy 331.877138 -406.194626)
			(xy 331.858365 -406.2024) (xy 331.848206 -406.202896) (xy 331.131926 -406.202896) (xy 331.121774 -406.202346)
			(xy 331.103012 -406.194587) (xy 331.088647 -406.180238) (xy 331.080865 -406.161485) (xy 331.080364 -406.151334)
			(xy 331.080364 -405.993346) (xy 331.079918 -405.984163) (xy 331.073428 -405.966979) (xy 331.067664 -405.959818)
			(xy 331.04587 -405.934171) (xy 331.007919 -405.878584) (xy 330.976885 -405.81886) (xy 330.953212 -405.755855)
			(xy 330.937238 -405.690472) (xy 330.929194 -405.623648) (xy 326.525636 -405.623648) (xy 326.525636 -406.723789)
			(xy 333.128808 -406.723789) (xy 333.128811 -406.656363) (xy 333.13689 -406.589422) (xy 333.152929 -406.523931)
			(xy 333.176697 -406.460833) (xy 333.207852 -406.401036) (xy 333.245946 -406.345401) (xy 333.267812 -406.319736)
			(xy 333.27362 -406.312599) (xy 333.280127 -406.295402) (xy 333.280512 -406.286208) (xy 333.280512 -405.793956)
			(xy 333.28012 -405.784767) (xy 333.273594 -405.767583) (xy 333.267812 -405.760428) (xy 333.245944 -405.734766)
			(xy 333.207854 -405.679131) (xy 333.176703 -405.619335) (xy 333.152939 -405.556238) (xy 333.136903 -405.490748)
			(xy 333.128827 -405.423809) (xy 333.128828 -405.356385) (xy 333.136904 -405.289446) (xy 333.15294 -405.223957)
			(xy 333.176706 -405.16086) (xy 333.207857 -405.101063) (xy 333.245947 -405.045429) (xy 333.267812 -405.019764)
			(xy 333.273608 -405.012618) (xy 333.280123 -404.995428) (xy 333.280512 -404.986236) (xy 333.280512 -404.828756)
			(xy 333.280949 -404.818643) (xy 333.288704 -404.799961) (xy 333.303015 -404.785668) (xy 333.321706 -404.777937)
			(xy 333.33182 -404.777448) (xy 334.0481 -404.777448) (xy 334.058202 -404.777984) (xy 334.076871 -404.785712)
			(xy 334.091163 -404.799993) (xy 334.098907 -404.818654) (xy 334.099408 -404.828756) (xy 334.099408 -404.986236)
			(xy 334.099799 -404.995425) (xy 334.106326 -405.01261) (xy 334.112108 -405.019764) (xy 334.133968 -405.045433)
			(xy 334.172056 -405.101067) (xy 334.203206 -405.160863) (xy 334.226971 -405.223959) (xy 334.243006 -405.289448)
			(xy 334.251082 -405.356385) (xy 334.251082 -405.423809) (xy 334.243007 -405.490746) (xy 334.226972 -405.556235)
			(xy 334.203209 -405.619332) (xy 334.20093 -405.623707) (xy 335.328987 -405.623707) (xy 335.328987 -405.556284)
			(xy 335.337063 -405.489346) (xy 335.353098 -405.423857) (xy 335.376861 -405.36076) (xy 335.40801 -405.300963)
			(xy 335.446097 -405.245328) (xy 335.46796 -405.219662) (xy 335.473763 -405.212521) (xy 335.480272 -405.195327)
			(xy 335.48066 -405.186134) (xy 335.48066 -404.693882) (xy 335.480245 -404.684696) (xy 335.473733 -404.667512)
			(xy 335.46796 -404.660354) (xy 335.446119 -404.63467) (xy 335.408032 -404.579037) (xy 335.376883 -404.519243)
			(xy 335.353119 -404.456149) (xy 335.337083 -404.390663) (xy 335.329006 -404.323727) (xy 335.329004 -404.256306)
			(xy 335.337078 -404.18937) (xy 335.353109 -404.123883) (xy 335.376869 -404.060787) (xy 335.408015 -404.000991)
			(xy 335.446099 -403.945356) (xy 335.46796 -403.91969) (xy 335.473751 -403.912541) (xy 335.480267 -403.895353)
			(xy 335.48066 -403.886162) (xy 335.48066 -403.728682) (xy 335.481112 -403.718552) (xy 335.48885 -403.699826)
			(xy 335.503147 -403.68547) (xy 335.52184 -403.677655) (xy 335.531968 -403.67712) (xy 336.248248 -403.67712)
			(xy 336.258408 -403.677483) (xy 336.277165 -403.685298) (xy 336.291487 -403.699713) (xy 336.299182 -403.71852)
			(xy 336.299556 -403.728682) (xy 336.299556 -403.886162) (xy 336.299995 -403.895346) (xy 336.30649 -403.91253)
			(xy 336.312256 -403.91969) (xy 336.334143 -403.945337) (xy 336.372234 -404.000973) (xy 336.403386 -404.060771)
			(xy 336.427151 -404.123871) (xy 336.443186 -404.189362) (xy 336.451261 -404.256303) (xy 336.451259 -404.32373)
			(xy 336.443181 -404.39067) (xy 336.427141 -404.456161) (xy 336.403373 -404.519259) (xy 336.372217 -404.579056)
			(xy 336.334123 -404.634689) (xy 336.312256 -404.660354) (xy 336.306449 -404.667491) (xy 336.299941 -404.684688)
			(xy 336.299556 -404.693882) (xy 336.299556 -405.186134) (xy 336.29996 -405.195322) (xy 336.306479 -405.212505)
			(xy 336.312256 -405.219662) (xy 336.334116 -405.245331) (xy 336.372207 -405.300964) (xy 336.403361 -405.360759)
			(xy 336.427127 -405.423856) (xy 336.443164 -405.489345) (xy 336.451242 -405.556283) (xy 336.451242 -405.623708)
			(xy 336.443166 -405.690646) (xy 336.42713 -405.756135) (xy 336.403365 -405.819232) (xy 336.372212 -405.879028)
			(xy 336.334121 -405.934662) (xy 336.312256 -405.960326) (xy 336.30646 -405.967472) (xy 336.299946 -405.984662)
			(xy 336.299556 -405.993854) (xy 336.299556 -406.151334) (xy 336.299101 -406.161463) (xy 336.291362 -406.180186)
			(xy 336.277066 -406.194541) (xy 336.258375 -406.202359) (xy 336.248248 -406.202896) (xy 335.531968 -406.202896)
			(xy 335.521811 -406.202505) (xy 335.503057 -406.194698) (xy 335.488735 -406.180292) (xy 335.481037 -406.161493)
			(xy 335.48066 -406.151334) (xy 335.48066 -405.993854) (xy 335.48021 -405.984671) (xy 335.473722 -405.967487)
			(xy 335.46796 -405.960326) (xy 335.446092 -405.934665) (xy 335.408006 -405.879029) (xy 335.376857 -405.819232)
			(xy 335.353095 -405.756134) (xy 335.337062 -405.690645) (xy 335.328987 -405.623707) (xy 334.20093 -405.623707)
			(xy 334.172059 -405.679128) (xy 334.133971 -405.734763) (xy 334.112108 -405.760428) (xy 334.106318 -405.767578)
			(xy 334.099799 -405.784765) (xy 334.099408 -405.793956) (xy 334.099408 -406.286208) (xy 334.099813 -406.295396)
			(xy 334.10633 -406.31258) (xy 334.112108 -406.319736) (xy 334.13394 -406.345427) (xy 334.172029 -406.401058)
			(xy 334.203181 -406.460851) (xy 334.226947 -406.523944) (xy 334.242984 -406.58943) (xy 334.251062 -406.656365)
			(xy 334.251065 -406.723729) (xy 337.529127 -406.723729) (xy 337.52913 -406.656423) (xy 337.537177 -406.589598)
			(xy 337.553152 -406.524215) (xy 337.576827 -406.461209) (xy 337.607861 -406.401484) (xy 337.645812 -406.345897)
			(xy 337.6676 -406.320244) (xy 337.673403 -406.313103) (xy 337.679914 -406.295909) (xy 337.6803 -406.286716)
			(xy 337.6803 -405.793448) (xy 337.679867 -405.784263) (xy 337.673369 -405.767079) (xy 337.6676 -405.75992)
			(xy 337.64581 -405.734271) (xy 337.607863 -405.678683) (xy 337.576832 -405.618958) (xy 337.553162 -405.555954)
			(xy 337.53719 -405.490572) (xy 337.529147 -405.423749) (xy 337.529147 -405.356445) (xy 337.537191 -405.289622)
			(xy 337.553163 -405.224241) (xy 337.576835 -405.161236) (xy 337.607866 -405.101512) (xy 337.645813 -405.045925)
			(xy 337.6676 -405.020272) (xy 337.673391 -405.013123) (xy 337.679909 -404.995935) (xy 337.6803 -404.986744)
			(xy 337.6803 -404.828756) (xy 337.680686 -404.818599) (xy 337.688496 -404.799846) (xy 337.702903 -404.785524)
			(xy 337.721703 -404.777826) (xy 337.731862 -404.777448) (xy 338.448142 -404.777448) (xy 338.458272 -404.777892)
			(xy 338.476996 -404.785635) (xy 338.491351 -404.799934) (xy 338.499167 -404.818628) (xy 338.499704 -404.828756)
			(xy 338.499704 -404.986744) (xy 338.500092 -404.995934) (xy 338.506621 -405.013118) (xy 338.512404 -405.020272)
			(xy 338.534186 -405.045928) (xy 338.572133 -405.101515) (xy 338.603164 -405.161238) (xy 338.626835 -405.224242)
			(xy 338.642807 -405.289624) (xy 338.650851 -405.356445) (xy 338.650851 -405.423749) (xy 338.642808 -405.490571)
			(xy 338.626837 -405.555952) (xy 338.603166 -405.618956) (xy 338.600728 -405.623648) (xy 339.729282 -405.623648)
			(xy 339.729282 -405.556343) (xy 339.737327 -405.489519) (xy 339.753301 -405.424137) (xy 339.776975 -405.361132)
			(xy 339.808009 -405.301408) (xy 339.845959 -405.245822) (xy 339.867748 -405.22017) (xy 339.873546 -405.213026)
			(xy 339.880058 -405.195834) (xy 339.880448 -405.186642) (xy 339.880448 -404.693374) (xy 339.88004 -404.684187)
			(xy 339.873523 -404.667003) (xy 339.867748 -404.659846) (xy 339.845982 -404.634176) (xy 339.808032 -404.578592)
			(xy 339.776997 -404.518871) (xy 339.753323 -404.455869) (xy 339.737348 -404.390489) (xy 339.729302 -404.323668)
			(xy 339.7293 -404.256365) (xy 339.737342 -404.189544) (xy 339.753313 -404.124163) (xy 339.776984 -404.061159)
			(xy 339.808015 -404.001436) (xy 339.845962 -403.94585) (xy 339.867748 -403.920198) (xy 339.873534 -403.913045)
			(xy 339.880054 -403.89586) (xy 339.880448 -403.88667) (xy 339.880448 -403.728682) (xy 339.880919 -403.718522)
			(xy 339.888701 -403.69975) (xy 339.903074 -403.685385) (xy 339.92185 -403.677613) (xy 339.93201 -403.67712)
			(xy 340.64829 -403.67712) (xy 340.658445 -403.677641) (xy 340.67721 -403.685409) (xy 340.691575 -403.699766)
			(xy 340.699353 -403.718527) (xy 340.699852 -403.728682) (xy 340.699852 -403.88667) (xy 340.700287 -403.895854)
			(xy 340.706785 -403.913038) (xy 340.712552 -403.920198) (xy 340.734362 -403.945832) (xy 340.772311 -404.001421)
			(xy 340.803343 -404.061147) (xy 340.827015 -404.124154) (xy 340.842987 -404.189538) (xy 340.85103 -404.256363)
			(xy 340.851028 -404.32367) (xy 340.842981 -404.390494) (xy 340.827006 -404.455878) (xy 340.80333 -404.518883)
			(xy 340.772294 -404.578608) (xy 340.734341 -404.634194) (xy 340.712552 -404.659846) (xy 340.706747 -404.666985)
			(xy 340.700239 -404.684181) (xy 340.699852 -404.693374) (xy 340.699852 -405.186642) (xy 340.700253 -405.19583)
			(xy 340.706774 -405.213014) (xy 340.712552 -405.22017) (xy 340.734334 -405.245827) (xy 340.772283 -405.301413)
			(xy 340.803317 -405.361135) (xy 340.826991 -405.424139) (xy 340.842965 -405.489521) (xy 340.851009 -405.556343)
			(xy 340.85101 -405.623648) (xy 340.842966 -405.69047) (xy 340.826994 -405.755852) (xy 340.803321 -405.818856)
			(xy 340.772288 -405.87858) (xy 340.734339 -405.934166) (xy 340.712552 -405.959818) (xy 340.706759 -405.966966)
			(xy 340.700244 -405.984154) (xy 340.699852 -405.993346) (xy 340.699852 -406.151334) (xy 340.699394 -406.161495)
			(xy 340.691607 -406.180267) (xy 340.67723 -406.194631) (xy 340.658452 -406.202403) (xy 340.64829 -406.202896)
			(xy 339.93201 -406.202896) (xy 339.921857 -406.202359) (xy 339.903095 -406.194594) (xy 339.88873 -406.180242)
			(xy 339.880949 -406.161487) (xy 339.880448 -406.151334) (xy 339.880448 -405.993346) (xy 339.880005 -405.984163)
			(xy 339.873513 -405.966979) (xy 339.867748 -405.959818) (xy 339.845954 -405.934171) (xy 339.808005 -405.878584)
			(xy 339.776971 -405.81886) (xy 339.753298 -405.755855) (xy 339.737325 -405.690472) (xy 339.729282 -405.623648)
			(xy 338.600728 -405.623648) (xy 338.572136 -405.67868) (xy 338.53419 -405.734267) (xy 338.512404 -405.75992)
			(xy 338.506617 -405.767072) (xy 338.500096 -405.784257) (xy 338.499704 -405.793448) (xy 338.499704 -406.286716)
			(xy 338.500106 -406.295904) (xy 338.506625 -406.313088) (xy 338.512404 -406.320244) (xy 338.534159 -406.345923)
			(xy 338.572106 -406.401506) (xy 338.603138 -406.461227) (xy 338.626811 -406.524228) (xy 338.642785 -406.589606)
			(xy 338.650831 -406.656425) (xy 338.650834 -406.723727) (xy 338.650827 -406.723789) (xy 341.928896 -406.723789)
			(xy 341.928898 -406.656363) (xy 341.936977 -406.589423) (xy 341.953016 -406.523932) (xy 341.976784 -406.460834)
			(xy 342.007938 -406.401036) (xy 342.04603 -406.345401) (xy 342.067896 -406.319736) (xy 342.073702 -406.312597)
			(xy 342.080211 -406.295402) (xy 342.080596 -406.286208) (xy 342.080596 -405.793956) (xy 342.080208 -405.784766)
			(xy 342.073679 -405.767582) (xy 342.067896 -405.760428) (xy 342.046028 -405.734766) (xy 342.00794 -405.679131)
			(xy 341.97679 -405.619334) (xy 341.953026 -405.556237) (xy 341.936991 -405.490748) (xy 341.928915 -405.423809)
			(xy 341.928916 -405.356385) (xy 341.936992 -405.289447) (xy 341.953028 -405.223957) (xy 341.976792 -405.16086)
			(xy 342.007943 -405.101064) (xy 342.046032 -405.045429) (xy 342.067896 -405.019764) (xy 342.07369 -405.012617)
			(xy 342.080206 -404.995428) (xy 342.080596 -404.986236) (xy 342.080596 -404.828756) (xy 342.081049 -404.818645)
			(xy 342.0888 -404.799967) (xy 342.103107 -404.785673) (xy 342.121793 -404.77794) (xy 342.131904 -404.777448)
			(xy 342.848184 -404.777448) (xy 342.858285 -404.777997) (xy 342.876953 -404.78572) (xy 342.891247 -404.799996)
			(xy 342.898991 -404.818655) (xy 342.899492 -404.828756) (xy 342.899492 -404.986236) (xy 342.899886 -404.995425)
			(xy 342.906411 -405.012609) (xy 342.912192 -405.019764) (xy 342.934052 -405.045432) (xy 342.972142 -405.101066)
			(xy 343.003293 -405.160862) (xy 343.027058 -405.223958) (xy 343.043094 -405.289447) (xy 343.05117 -405.356385)
			(xy 343.05117 -405.423809) (xy 343.043095 -405.490747) (xy 343.02706 -405.556236) (xy 343.003295 -405.619333)
			(xy 343.001047 -405.623648) (xy 344.129073 -405.623648) (xy 344.129073 -405.556343) (xy 344.137118 -405.48952)
			(xy 344.153091 -405.424137) (xy 344.176765 -405.361132) (xy 344.207799 -405.301409) (xy 344.245748 -405.245822)
			(xy 344.267536 -405.22017) (xy 344.273332 -405.213025) (xy 344.279846 -405.195834) (xy 344.280236 -405.186642)
			(xy 344.280236 -404.693374) (xy 344.27983 -404.684187) (xy 344.273313 -404.667003) (xy 344.267536 -404.659846)
			(xy 344.24577 -404.634176) (xy 344.207821 -404.578592) (xy 344.176787 -404.518871) (xy 344.153113 -404.455869)
			(xy 344.137139 -404.390489) (xy 344.129093 -404.323668) (xy 344.129091 -404.256365) (xy 344.137133 -404.189544)
			(xy 344.153103 -404.124163) (xy 344.176773 -404.061159) (xy 344.207804 -404.001437) (xy 344.24575 -403.94585)
			(xy 344.267536 -403.920198) (xy 344.273321 -403.913044) (xy 344.279842 -403.89586) (xy 344.280236 -403.88667)
			(xy 344.280236 -403.728682) (xy 344.280718 -403.718523) (xy 344.288498 -403.699754) (xy 344.302867 -403.685389)
			(xy 344.321639 -403.677615) (xy 344.331798 -403.67712) (xy 345.048078 -403.67712) (xy 345.058246 -403.677582)
			(xy 345.077037 -403.685356) (xy 345.091422 -403.69973) (xy 345.09921 -403.718514) (xy 345.09964 -403.728682)
			(xy 345.09964 -403.88667) (xy 345.100078 -403.895854) (xy 345.106574 -403.913038) (xy 345.11234 -403.920198)
			(xy 345.13415 -403.945832) (xy 345.1721 -404.00142) (xy 345.203133 -404.061146) (xy 345.226806 -404.124153)
			(xy 345.242778 -404.189538) (xy 345.250821 -404.256363) (xy 345.250819 -404.32367) (xy 345.242772 -404.390495)
			(xy 345.226796 -404.455878) (xy 345.20312 -404.518884) (xy 345.172083 -404.578608) (xy 345.13413 -404.634194)
			(xy 345.11234 -404.659846) (xy 345.106534 -404.666984) (xy 345.100027 -404.68418) (xy 345.09964 -404.693374)
			(xy 345.09964 -405.186642) (xy 345.100043 -405.19583) (xy 345.106563 -405.213013) (xy 345.11234 -405.22017)
			(xy 345.134122 -405.245827) (xy 345.172073 -405.301412) (xy 345.203107 -405.361135) (xy 345.226781 -405.424139)
			(xy 345.242755 -405.489521) (xy 345.2508 -405.556343) (xy 345.250801 -405.623648) (xy 345.242757 -405.69047)
			(xy 345.226784 -405.755853) (xy 345.203111 -405.818857) (xy 345.172077 -405.87858) (xy 345.134128 -405.934166)
			(xy 345.11234 -405.959818) (xy 345.106546 -405.966965) (xy 345.100031 -405.984154) (xy 345.09964 -405.993346)
			(xy 345.09964 -406.151334) (xy 345.099194 -406.161497) (xy 345.091404 -406.180271) (xy 345.077024 -406.194636)
			(xy 345.058241 -406.202405) (xy 345.048078 -406.202896) (xy 344.331798 -406.202896) (xy 344.321644 -406.202369)
			(xy 344.302882 -406.1946) (xy 344.288518 -406.180245) (xy 344.280737 -406.161487) (xy 344.280236 -406.151334)
			(xy 344.280236 -405.993346) (xy 344.279795 -405.984162) (xy 344.273302 -405.966978) (xy 344.267536 -405.959818)
			(xy 344.245742 -405.934171) (xy 344.207794 -405.878584) (xy 344.176761 -405.818859) (xy 344.153089 -405.755854)
			(xy 344.137116 -405.690471) (xy 344.129073 -405.623648) (xy 343.001047 -405.623648) (xy 342.972145 -405.679129)
			(xy 342.934056 -405.734763) (xy 342.912192 -405.760428) (xy 342.9064 -405.767576) (xy 342.899883 -405.784765)
			(xy 342.899492 -405.793956) (xy 342.899492 -406.286208) (xy 342.8999 -406.295395) (xy 342.906416 -406.312579)
			(xy 342.912192 -406.319736) (xy 342.934025 -406.345427) (xy 342.972115 -406.401058) (xy 343.003268 -406.46085)
			(xy 343.027034 -406.523944) (xy 343.043072 -406.58943) (xy 343.05115 -406.656365) (xy 343.051153 -406.72373)
			(xy 346.329191 -406.72373) (xy 346.329194 -406.656422) (xy 346.337242 -406.589596) (xy 346.35322 -406.524212)
			(xy 346.376898 -406.461206) (xy 346.407937 -406.401482) (xy 346.445893 -406.345896) (xy 346.467684 -406.320244)
			(xy 346.473485 -406.313102) (xy 346.479998 -406.295909) (xy 346.480384 -406.286716) (xy 346.480384 -405.793448)
			(xy 346.479955 -405.784263) (xy 346.473455 -405.767078) (xy 346.467684 -405.75992) (xy 346.445891 -405.734272)
			(xy 346.407939 -405.678686) (xy 346.376904 -405.618962) (xy 346.353229 -405.555957) (xy 346.337255 -405.490574)
			(xy 346.329211 -405.42375) (xy 346.329211 -405.356444) (xy 346.337256 -405.28962) (xy 346.353231 -405.224237)
			(xy 346.376906 -405.161232) (xy 346.407942 -405.101509) (xy 346.445895 -405.045924) (xy 346.467684 -405.020272)
			(xy 346.473473 -405.013121) (xy 346.479993 -404.995935) (xy 346.480384 -404.986744) (xy 346.480384 -404.828756)
			(xy 346.480785 -404.818601) (xy 346.488592 -404.799851) (xy 346.502995 -404.78553) (xy 346.521789 -404.777829)
			(xy 346.531946 -404.777448) (xy 347.248226 -404.777448) (xy 347.258355 -404.777905) (xy 347.277079 -404.785643)
			(xy 347.291434 -404.799938) (xy 347.299251 -404.818629) (xy 347.299788 -404.828756) (xy 347.299788 -404.986744)
			(xy 347.30018 -404.995933) (xy 347.306706 -405.013117) (xy 347.312488 -405.020272) (xy 347.334271 -405.045928)
			(xy 347.372218 -405.101514) (xy 347.40325 -405.161238) (xy 347.426922 -405.224242) (xy 347.442894 -405.289623)
			(xy 347.450938 -405.356445) (xy 347.450939 -405.423749) (xy 347.442895 -405.490571) (xy 347.426924 -405.555953)
			(xy 347.403253 -405.618957) (xy 347.400815 -405.623649) (xy 374.929103 -405.623649) (xy 374.929104 -405.556342)
			(xy 374.937149 -405.489519) (xy 374.953124 -405.424136) (xy 374.976799 -405.361131) (xy 375.007835 -405.301407)
			(xy 375.045787 -405.245822) (xy 375.067576 -405.22017) (xy 375.073365 -405.213019) (xy 375.079885 -405.195833)
			(xy 375.080276 -405.186642) (xy 375.080276 -404.693374) (xy 375.079884 -404.684185) (xy 375.073358 -404.667)
			(xy 375.067576 -404.659846) (xy 375.045809 -404.634177) (xy 375.007857 -404.578593) (xy 374.976821 -404.518873)
			(xy 374.953145 -404.45587) (xy 374.937169 -404.39049) (xy 374.929123 -404.323669) (xy 374.929121 -404.256365)
			(xy 374.937164 -404.189543) (xy 374.953135 -404.124161) (xy 374.976807 -404.061158) (xy 375.00784 -404.001435)
			(xy 375.045789 -403.94585) (xy 375.067576 -403.920198) (xy 375.073353 -403.913039) (xy 375.07988 -403.895859)
			(xy 375.080276 -403.88667) (xy 375.080276 -403.728682) (xy 375.08065 -403.718505) (xy 375.088448 -403.699702)
			(xy 375.102849 -403.685317) (xy 375.12166 -403.677539) (xy 375.131838 -403.67712) (xy 375.848118 -403.67712)
			(xy 375.858275 -403.677618) (xy 375.877041 -403.685395) (xy 375.891405 -403.699759) (xy 375.899182 -403.718525)
			(xy 375.89968 -403.728682) (xy 375.89968 -403.88667) (xy 375.900109 -403.895855) (xy 375.90661 -403.913039)
			(xy 375.91238 -403.920198) (xy 375.934189 -403.945833) (xy 375.972136 -404.001422) (xy 376.003167 -404.061148)
			(xy 376.026838 -404.124155) (xy 376.042809 -404.189539) (xy 376.050851 -404.256363) (xy 376.050849 -404.32367)
			(xy 376.042803 -404.390494) (xy 376.026828 -404.455877) (xy 376.003154 -404.518882) (xy 375.972119 -404.578606)
			(xy 375.934169 -404.634194) (xy 375.91238 -404.659846) (xy 375.906579 -404.666988) (xy 375.900068 -404.684181)
			(xy 375.89968 -404.693374) (xy 375.89968 -405.186642) (xy 375.900074 -405.195831) (xy 375.9066 -405.213015)
			(xy 375.91238 -405.22017) (xy 375.934161 -405.245827) (xy 375.972109 -405.301413) (xy 376.003142 -405.361136)
			(xy 376.026814 -405.42414) (xy 376.042787 -405.489522) (xy 376.050831 -405.556343) (xy 376.050832 -405.623648)
			(xy 376.042788 -405.690469) (xy 376.026817 -405.755851) (xy 376.003145 -405.818855) (xy 375.972114 -405.878579)
			(xy 375.934167 -405.934166) (xy 375.91238 -405.959818) (xy 375.906591 -405.966968) (xy 375.900072 -405.984155)
			(xy 375.89968 -405.993346) (xy 375.89968 -406.151334) (xy 375.899195 -406.161492) (xy 375.891413 -406.180258)
			(xy 375.877045 -406.194622) (xy 375.858276 -406.202398) (xy 375.848118 -406.202896) (xy 375.131838 -406.202896)
			(xy 375.121673 -406.202406) (xy 375.102886 -406.19464) (xy 375.088501 -406.180275) (xy 375.080708 -406.161498)
			(xy 375.080276 -406.151334) (xy 375.080276 -405.993346) (xy 375.079849 -405.984161) (xy 375.073347 -405.966976)
			(xy 375.067576 -405.959818) (xy 375.045781 -405.934171) (xy 375.00783 -405.878585) (xy 374.976795 -405.818861)
			(xy 374.953121 -405.755856) (xy 374.937148 -405.690472) (xy 374.929103 -405.623649) (xy 347.400815 -405.623649)
			(xy 347.372221 -405.678681) (xy 347.334275 -405.734268) (xy 347.312488 -405.75992) (xy 347.306699 -405.767071)
			(xy 347.30018 -405.784257) (xy 347.299788 -405.793448) (xy 347.299788 -406.286716) (xy 347.300193 -406.295904)
			(xy 347.30671 -406.313088) (xy 347.312488 -406.320244) (xy 347.334244 -406.345922) (xy 347.372192 -406.401506)
			(xy 347.403225 -406.461226) (xy 347.426898 -406.524227) (xy 347.442873 -406.589606) (xy 347.450919 -406.656425)
			(xy 347.450922 -406.723727) (xy 347.450915 -406.723789) (xy 377.128717 -406.723789) (xy 377.12872 -406.656363)
			(xy 377.136799 -406.589422) (xy 377.152839 -406.523931) (xy 377.176607 -406.460832) (xy 377.207763 -406.401035)
			(xy 377.245857 -406.345401) (xy 377.267724 -406.319736) (xy 377.273533 -406.3126) (xy 377.280039 -406.295402)
			(xy 377.280424 -406.286208) (xy 377.280424 -405.793956) (xy 377.28003 -405.784767) (xy 377.273504 -405.767583)
			(xy 377.267724 -405.760428) (xy 377.245855 -405.734766) (xy 377.207765 -405.679132) (xy 377.176613 -405.619335)
			(xy 377.152848 -405.556238) (xy 377.136812 -405.490748) (xy 377.128736 -405.423809) (xy 377.128737 -405.356385)
			(xy 377.136813 -405.289446) (xy 377.15285 -405.223956) (xy 377.176616 -405.160859) (xy 377.207768 -405.101063)
			(xy 377.245859 -405.045429) (xy 377.267724 -405.019764) (xy 377.273521 -405.012619) (xy 377.280035 -404.995428)
			(xy 377.280424 -404.986236) (xy 377.280424 -404.828756) (xy 377.28085 -404.818641) (xy 377.288606 -404.799958)
			(xy 377.302922 -404.785664) (xy 377.321617 -404.777935) (xy 377.331732 -404.777448) (xy 378.048012 -404.777448)
			(xy 378.058115 -404.777974) (xy 378.076783 -404.785706) (xy 378.091076 -404.79999) (xy 378.098819 -404.818653)
			(xy 378.09932 -404.828756) (xy 378.09932 -404.986236) (xy 378.099709 -404.995426) (xy 378.106237 -405.01261)
			(xy 378.11202 -405.019764) (xy 378.133879 -405.045433) (xy 378.171967 -405.101067) (xy 378.203117 -405.160863)
			(xy 378.22688 -405.22396) (xy 378.242915 -405.289448) (xy 378.250991 -405.356386) (xy 378.250992 -405.423808)
			(xy 378.242916 -405.490746) (xy 378.226882 -405.556235) (xy 378.203119 -405.619331) (xy 378.200839 -405.623707)
			(xy 379.328896 -405.623707) (xy 379.328896 -405.556284) (xy 379.336972 -405.489346) (xy 379.353008 -405.423856)
			(xy 379.376771 -405.360759) (xy 379.407921 -405.300963) (xy 379.446009 -405.245328) (xy 379.467872 -405.219662)
			(xy 379.473676 -405.212522) (xy 379.480184 -405.195327) (xy 379.480572 -405.186134) (xy 379.480572 -404.693882)
			(xy 379.480177 -404.684693) (xy 379.473653 -404.667509) (xy 379.467872 -404.660354) (xy 379.446031 -404.63467)
			(xy 379.407943 -404.579038) (xy 379.376793 -404.519244) (xy 379.353029 -404.45615) (xy 379.336993 -404.390663)
			(xy 379.328915 -404.323727) (xy 379.328913 -404.256306) (xy 379.336987 -404.18937) (xy 379.353019 -404.123882)
			(xy 379.376779 -404.060786) (xy 379.407926 -404.00099) (xy 379.44601 -403.945356) (xy 379.467872 -403.91969)
			(xy 379.473664 -403.912542) (xy 379.480179 -403.895353) (xy 379.480572 -403.886162) (xy 379.480572 -403.728682)
			(xy 379.481013 -403.71855) (xy 379.488752 -403.699822) (xy 379.503053 -403.685466) (xy 379.52175 -403.677653)
			(xy 379.53188 -403.67712) (xy 380.24816 -403.67712) (xy 380.258282 -403.677549) (xy 380.276989 -403.685288)
			(xy 380.291305 -403.699601) (xy 380.299048 -403.718306) (xy 380.299468 -403.728428) (xy 380.299468 -403.886162)
			(xy 380.299904 -403.895346) (xy 380.306401 -403.91253) (xy 380.312168 -403.91969) (xy 380.334055 -403.945337)
			(xy 380.372145 -404.000973) (xy 380.403296 -404.060772) (xy 380.427061 -404.123871) (xy 380.443096 -404.189363)
			(xy 380.45117 -404.256303) (xy 380.451168 -404.32373) (xy 380.44309 -404.39067) (xy 380.427051 -404.456161)
			(xy 380.403283 -404.519259) (xy 380.372128 -404.579055) (xy 380.334034 -404.634689) (xy 380.312168 -404.660354)
			(xy 380.306362 -404.667492) (xy 380.299854 -404.684688) (xy 380.299468 -404.693882) (xy 380.299468 -405.186134)
			(xy 380.299869 -405.195322) (xy 380.30639 -405.212506) (xy 380.312168 -405.219662) (xy 380.334027 -405.245332)
			(xy 380.372118 -405.300965) (xy 380.403271 -405.36076) (xy 380.427037 -405.423856) (xy 380.443074 -405.489345)
			(xy 380.451151 -405.556284) (xy 380.451151 -405.623707) (xy 380.443075 -405.690646) (xy 380.42704 -405.756135)
			(xy 380.403275 -405.819232) (xy 380.372123 -405.879028) (xy 380.334033 -405.934661) (xy 380.312168 -405.960326)
			(xy 380.306374 -405.967473) (xy 380.299858 -405.984662) (xy 380.299468 -405.993854) (xy 380.299468 -406.151334)
			(xy 380.299002 -406.161462) (xy 380.291264 -406.180182) (xy 380.276972 -406.194537) (xy 380.258286 -406.202357)
			(xy 380.24816 -406.202896) (xy 379.53188 -406.202896) (xy 379.521769 -406.202431) (xy 379.50309 -406.194686)
			(xy 379.488796 -406.180383) (xy 379.481062 -406.161699) (xy 379.480572 -406.151588) (xy 379.480572 -405.993854)
			(xy 379.480142 -405.984669) (xy 379.473643 -405.967484) (xy 379.467872 -405.960326) (xy 379.446003 -405.934665)
			(xy 379.407916 -405.879029) (xy 379.376768 -405.819232) (xy 379.353005 -405.756135) (xy 379.336971 -405.690646)
			(xy 379.328896 -405.623707) (xy 378.200839 -405.623707) (xy 378.17197 -405.679128) (xy 378.133883 -405.734762)
			(xy 378.11202 -405.760428) (xy 378.106231 -405.767579) (xy 378.099711 -405.784765) (xy 378.09932 -405.793956)
			(xy 378.09932 -406.286208) (xy 378.099722 -406.295396) (xy 378.106241 -406.312581) (xy 378.11202 -406.319736)
			(xy 378.133852 -406.345428) (xy 378.17194 -406.401059) (xy 378.203091 -406.460852) (xy 378.226856 -406.523945)
			(xy 378.242893 -406.589431) (xy 378.250971 -406.656366) (xy 378.250974 -406.723729) (xy 381.529036 -406.723729)
			(xy 381.529039 -406.656422) (xy 381.537086 -406.589598) (xy 381.553062 -406.524214) (xy 381.576737 -406.461209)
			(xy 381.607772 -406.401484) (xy 381.645723 -406.345897) (xy 381.667512 -406.320244) (xy 381.673316 -406.313104)
			(xy 381.679826 -406.29591) (xy 381.680212 -406.286716) (xy 381.680212 -405.793448) (xy 381.679776 -405.784264)
			(xy 381.67328 -405.767079) (xy 381.667512 -405.75992) (xy 381.645721 -405.734271) (xy 381.607774 -405.678683)
			(xy 381.576743 -405.618959) (xy 381.553071 -405.555954) (xy 381.537099 -405.490572) (xy 381.529056 -405.423749)
			(xy 381.529056 -405.356445) (xy 381.5371 -405.289622) (xy 381.553073 -405.22424) (xy 381.576745 -405.161235)
			(xy 381.607777 -405.101512) (xy 381.645725 -405.045924) (xy 381.667512 -405.020272) (xy 381.673304 -405.013124)
			(xy 381.679821 -404.995936) (xy 381.680212 -404.986744) (xy 381.680212 -404.828756) (xy 381.680649 -404.818643)
			(xy 381.688404 -404.799961) (xy 381.702715 -404.785668) (xy 381.721406 -404.777937) (xy 381.73152 -404.777448)
			(xy 382.448054 -404.777448) (xy 382.458179 -404.777965) (xy 382.4769 -404.785679) (xy 382.491258 -404.799956)
			(xy 382.499078 -404.818634) (xy 382.499616 -404.828756) (xy 382.499616 -404.986744) (xy 382.500001 -404.995934)
			(xy 382.506532 -405.013118) (xy 382.512316 -405.020272) (xy 382.534101 -405.045927) (xy 382.572053 -405.101512)
			(xy 382.603089 -405.161235) (xy 382.626764 -405.224239) (xy 382.642738 -405.289621) (xy 382.650784 -405.356444)
			(xy 382.650784 -405.42375) (xy 382.64274 -405.490573) (xy 382.626766 -405.555955) (xy 382.603091 -405.61896)
			(xy 382.600655 -405.623648) (xy 383.729191 -405.623648) (xy 383.729192 -405.556343) (xy 383.737237 -405.489519)
			(xy 383.753211 -405.424136) (xy 383.776885 -405.361132) (xy 383.807921 -405.301408) (xy 383.845871 -405.245822)
			(xy 383.86766 -405.22017) (xy 383.873459 -405.213027) (xy 383.879971 -405.195835) (xy 383.88036 -405.186642)
			(xy 383.88036 -404.693374) (xy 383.879949 -404.684187) (xy 383.873434 -404.667004) (xy 383.86766 -404.659846)
			(xy 383.845893 -404.634176) (xy 383.807943 -404.578593) (xy 383.776907 -404.518872) (xy 383.753232 -404.45587)
			(xy 383.737257 -404.390489) (xy 383.729211 -404.323668) (xy 383.729209 -404.256365) (xy 383.737251 -404.189543)
			(xy 383.753222 -404.124162) (xy 383.776894 -404.061158) (xy 383.807926 -404.001436) (xy 383.845873 -403.94585)
			(xy 383.86766 -403.920198) (xy 383.873447 -403.913047) (xy 383.879966 -403.895861) (xy 383.88036 -403.88667)
			(xy 383.88036 -403.728682) (xy 383.88075 -403.718507) (xy 383.888545 -403.699707) (xy 383.902941 -403.685322)
			(xy 383.921746 -403.677542) (xy 383.931922 -403.67712) (xy 384.648202 -403.67712) (xy 384.658358 -403.677631)
			(xy 384.677123 -403.685403) (xy 384.691488 -403.699763) (xy 384.699265 -403.718526) (xy 384.699764 -403.728682)
			(xy 384.699764 -403.88667) (xy 384.700197 -403.895855) (xy 384.706696 -403.913039) (xy 384.712464 -403.920198)
			(xy 384.734273 -403.945832) (xy 384.772221 -404.001421) (xy 384.803254 -404.061147) (xy 384.826925 -404.124154)
			(xy 384.842896 -404.189539) (xy 384.850939 -404.256363) (xy 384.850937 -404.32367) (xy 384.84289 -404.390494)
			(xy 384.826915 -404.455877) (xy 384.80324 -404.518883) (xy 384.772204 -404.578607) (xy 384.734253 -404.634194)
			(xy 384.712464 -404.659846) (xy 384.706661 -404.666986) (xy 384.700151 -404.684181) (xy 384.699764 -404.693374)
			(xy 384.699764 -405.186642) (xy 384.700162 -405.19583) (xy 384.706685 -405.213014) (xy 384.712464 -405.22017)
			(xy 384.734246 -405.245827) (xy 384.772195 -405.301413) (xy 384.803228 -405.361136) (xy 384.826901 -405.42414)
			(xy 384.842874 -405.489521) (xy 384.850919 -405.556343) (xy 384.850919 -405.623648) (xy 384.842876 -405.69047)
			(xy 384.826904 -405.755852) (xy 384.803232 -405.818856) (xy 384.772199 -405.878579) (xy 384.734251 -405.934166)
			(xy 384.712464 -405.959818) (xy 384.706673 -405.966967) (xy 384.700156 -405.984155) (xy 384.699764 -405.993346)
			(xy 384.699764 -406.151334) (xy 384.699295 -406.161494) (xy 384.691509 -406.180263) (xy 384.677136 -406.194627)
			(xy 384.658362 -406.202401) (xy 384.648202 -406.202896) (xy 383.931922 -406.202896) (xy 383.92177 -406.20235)
			(xy 383.903008 -406.194589) (xy 383.888643 -406.180239) (xy 383.880861 -406.161486) (xy 383.88036 -406.151334)
			(xy 383.88036 -405.993346) (xy 383.879914 -405.984163) (xy 383.873424 -405.966979) (xy 383.86766 -405.959818)
			(xy 383.845866 -405.934171) (xy 383.807916 -405.878584) (xy 383.776882 -405.81886) (xy 383.753208 -405.755855)
			(xy 383.737235 -405.690472) (xy 383.729191 -405.623648) (xy 382.600655 -405.623648) (xy 382.572056 -405.678683)
			(xy 382.534105 -405.734268) (xy 382.512316 -405.75992) (xy 382.50653 -405.767073) (xy 382.500009 -405.784257)
			(xy 382.499616 -405.793448) (xy 382.499616 -406.286716) (xy 382.500015 -406.295904) (xy 382.506536 -406.313089)
			(xy 382.512316 -406.320244) (xy 382.534074 -406.345921) (xy 382.572026 -406.401503) (xy 382.603063 -406.461223)
			(xy 382.62674 -406.524224) (xy 382.642717 -406.589604) (xy 382.650764 -406.656424) (xy 382.650767 -406.723728)
			(xy 382.65076 -406.723789) (xy 385.928805 -406.723789) (xy 385.928807 -406.656363) (xy 385.936887 -406.589422)
			(xy 385.952926 -406.523931) (xy 385.976694 -406.460833) (xy 386.007849 -406.401036) (xy 386.045942 -406.345401)
			(xy 386.067808 -406.319736) (xy 386.073615 -406.312598) (xy 386.080123 -406.295402) (xy 386.080508 -406.286208)
			(xy 386.080508 -405.793956) (xy 386.080117 -405.784767) (xy 386.07359 -405.767583) (xy 386.067808 -405.760428)
			(xy 386.04594 -405.734766) (xy 386.007851 -405.679131) (xy 385.9767 -405.619335) (xy 385.952935 -405.556237)
			(xy 385.9369 -405.490748) (xy 385.928824 -405.423809) (xy 385.928825 -405.356385) (xy 385.936901 -405.289446)
			(xy 385.952937 -405.223957) (xy 385.976702 -405.16086) (xy 386.007854 -405.101064) (xy 386.045944 -405.045429)
			(xy 386.067808 -405.019764) (xy 386.073603 -405.012618) (xy 386.080118 -404.995428) (xy 386.080508 -404.986236)
			(xy 386.080508 -404.828756) (xy 386.080949 -404.818643) (xy 386.088703 -404.799963) (xy 386.103013 -404.785669)
			(xy 386.121703 -404.777938) (xy 386.131816 -404.777448) (xy 386.848096 -404.777448) (xy 386.858198 -404.777987)
			(xy 386.876866 -404.785714) (xy 386.891159 -404.799993) (xy 386.898903 -404.818654) (xy 386.899404 -404.828756)
			(xy 386.899404 -404.986236) (xy 386.899796 -404.995425) (xy 386.906322 -405.012609) (xy 386.912104 -405.019764)
			(xy 386.933964 -405.045433) (xy 386.972052 -405.101067) (xy 387.003203 -405.160862) (xy 387.026967 -405.223959)
			(xy 387.043003 -405.289448) (xy 387.051079 -405.356385) (xy 387.051079 -405.423809) (xy 387.043004 -405.490747)
			(xy 387.026969 -405.556235) (xy 387.003206 -405.619332) (xy 387.000958 -405.623648) (xy 388.128982 -405.623648)
			(xy 388.128982 -405.556343) (xy 388.137027 -405.489519) (xy 388.153001 -405.424137) (xy 388.176675 -405.361132)
			(xy 388.207709 -405.301408) (xy 388.245659 -405.245822) (xy 388.267448 -405.22017) (xy 388.273246 -405.213026)
			(xy 388.279758 -405.195834) (xy 388.280148 -405.186642) (xy 388.280148 -404.693374) (xy 388.27974 -404.684187)
			(xy 388.273223 -404.667003) (xy 388.267448 -404.659846) (xy 388.245682 -404.634176) (xy 388.207732 -404.578592)
			(xy 388.176697 -404.518871) (xy 388.153023 -404.455869) (xy 388.137048 -404.390489) (xy 388.129002 -404.323668)
			(xy 388.129 -404.256365) (xy 388.137042 -404.189544) (xy 388.153013 -404.124163) (xy 388.176684 -404.061159)
			(xy 388.207715 -404.001436) (xy 388.245662 -403.94585) (xy 388.267448 -403.920198) (xy 388.273234 -403.913045)
			(xy 388.279754 -403.89586) (xy 388.280148 -403.88667) (xy 388.280148 -403.728682) (xy 388.280619 -403.718522)
			(xy 388.288401 -403.69975) (xy 388.302774 -403.685385) (xy 388.32155 -403.677613) (xy 388.33171 -403.67712)
			(xy 389.04799 -403.67712) (xy 389.058145 -403.677641) (xy 389.07691 -403.685409) (xy 389.091275 -403.699766)
			(xy 389.099053 -403.718527) (xy 389.099552 -403.728682) (xy 389.099552 -403.88667) (xy 389.099987 -403.895854)
			(xy 389.106485 -403.913038) (xy 389.112252 -403.920198) (xy 389.134062 -403.945832) (xy 389.172011 -404.001421)
			(xy 389.203043 -404.061147) (xy 389.226715 -404.124154) (xy 389.242687 -404.189538) (xy 389.25073 -404.256363)
			(xy 389.250728 -404.32367) (xy 389.242681 -404.390494) (xy 389.226706 -404.455878) (xy 389.20303 -404.518883)
			(xy 389.171994 -404.578608) (xy 389.134041 -404.634194) (xy 389.112252 -404.659846) (xy 389.106447 -404.666985)
			(xy 389.099939 -404.684181) (xy 389.099552 -404.693374) (xy 389.099552 -405.186642) (xy 389.099953 -405.19583)
			(xy 389.106474 -405.213014) (xy 389.112252 -405.22017) (xy 389.134034 -405.245827) (xy 389.171983 -405.301413)
			(xy 389.203017 -405.361135) (xy 389.226691 -405.424139) (xy 389.242665 -405.489521) (xy 389.250709 -405.556343)
			(xy 389.25071 -405.623648) (xy 389.242666 -405.69047) (xy 389.226694 -405.755852) (xy 389.203021 -405.818856)
			(xy 389.171988 -405.87858) (xy 389.134039 -405.934166) (xy 389.112252 -405.959818) (xy 389.106459 -405.966966)
			(xy 389.099944 -405.984154) (xy 389.099552 -405.993346) (xy 389.099552 -406.151334) (xy 389.099094 -406.161495)
			(xy 389.091307 -406.180267) (xy 389.07693 -406.194631) (xy 389.058152 -406.202403) (xy 389.04799 -406.202896)
			(xy 388.33171 -406.202896) (xy 388.321557 -406.202359) (xy 388.302795 -406.194594) (xy 388.28843 -406.180242)
			(xy 388.280649 -406.161487) (xy 388.280148 -406.151334) (xy 388.280148 -405.993346) (xy 388.279705 -405.984163)
			(xy 388.273213 -405.966979) (xy 388.267448 -405.959818) (xy 388.245654 -405.934171) (xy 388.207705 -405.878584)
			(xy 388.176671 -405.81886) (xy 388.152998 -405.755855) (xy 388.137025 -405.690472) (xy 388.128982 -405.623648)
			(xy 387.000958 -405.623648) (xy 386.972056 -405.679128) (xy 386.933968 -405.734763) (xy 386.912104 -405.760428)
			(xy 386.906314 -405.767578) (xy 386.899795 -405.784765) (xy 386.899404 -405.793956) (xy 386.899404 -406.286208)
			(xy 386.89981 -406.295396) (xy 386.906326 -406.31258) (xy 386.912104 -406.319736) (xy 386.933936 -406.345427)
			(xy 386.972026 -406.401058) (xy 387.003178 -406.460851) (xy 387.026943 -406.523944) (xy 387.042981 -406.58943)
			(xy 387.051059 -406.656365) (xy 387.051062 -406.723729) (xy 390.329124 -406.723729) (xy 390.329127 -406.656423)
			(xy 390.337174 -406.589599) (xy 390.353149 -406.524215) (xy 390.376823 -406.461209) (xy 390.407858 -406.401485)
			(xy 390.445808 -406.345897) (xy 390.467596 -406.320244) (xy 390.473398 -406.313103) (xy 390.47991 -406.295909)
			(xy 390.480296 -406.286716) (xy 390.480296 -405.793448) (xy 390.479864 -405.784263) (xy 390.473366 -405.767078)
			(xy 390.467596 -405.75992) (xy 390.445806 -405.73427) (xy 390.40786 -405.678683) (xy 390.376829 -405.618958)
			(xy 390.353158 -405.555954) (xy 390.337187 -405.490571) (xy 390.329144 -405.423749) (xy 390.329144 -405.356445)
			(xy 390.337188 -405.289623) (xy 390.35316 -405.224241) (xy 390.376832 -405.161236) (xy 390.407863 -405.101512)
			(xy 390.445809 -405.045925) (xy 390.467596 -405.020272) (xy 390.473386 -405.013122) (xy 390.479905 -404.995935)
			(xy 390.480296 -404.986744) (xy 390.480296 -404.828756) (xy 390.480749 -404.818645) (xy 390.4885 -404.799967)
			(xy 390.502807 -404.785673) (xy 390.521493 -404.77794) (xy 390.531604 -404.777448) (xy 391.248138 -404.777448)
			(xy 391.258268 -404.777896) (xy 391.276992 -404.785637) (xy 391.291347 -404.799935) (xy 391.299163 -404.818628)
			(xy 391.2997 -404.828756) (xy 391.2997 -404.986744) (xy 391.300089 -404.995933) (xy 391.306617 -405.013118)
			(xy 391.3124 -405.020272) (xy 391.334183 -405.045928) (xy 391.372129 -405.101515) (xy 391.40316 -405.161238)
			(xy 391.426832 -405.224242) (xy 391.442804 -405.289623) (xy 391.450848 -405.356445) (xy 391.450848 -405.423749)
			(xy 391.442805 -405.490571) (xy 391.426833 -405.555952) (xy 391.403163 -405.618956) (xy 391.372132 -405.67868)
			(xy 391.334186 -405.734267) (xy 391.3124 -405.75992) (xy 391.306612 -405.767072) (xy 391.300092 -405.784257)
			(xy 391.2997 -405.793448) (xy 391.2997 -406.286716) (xy 391.300103 -406.295904) (xy 391.306622 -406.313088)
			(xy 391.3124 -406.320244) (xy 391.334155 -406.345923) (xy 391.372102 -406.401506) (xy 391.403135 -406.461226)
			(xy 391.426808 -406.524227) (xy 391.442782 -406.589606) (xy 391.450828 -406.656425) (xy 391.450831 -406.723727)
			(xy 391.44279 -406.790547) (xy 391.426822 -406.855927) (xy 391.403154 -406.91893) (xy 391.372127 -406.978653)
			(xy 391.334185 -407.034239) (xy 391.3124 -407.059892) (xy 391.306624 -407.067052) (xy 391.300097 -407.084231)
			(xy 391.2997 -407.09342) (xy 391.2997 -407.251408) (xy 391.299221 -407.261517) (xy 391.291481 -407.280196)
			(xy 391.277182 -407.29449) (xy 391.258501 -407.302224) (xy 391.248392 -407.302716) (xy 390.531858 -407.302716)
			(xy 390.521723 -407.302307) (xy 390.502993 -407.294557) (xy 390.488636 -407.280247) (xy 390.480826 -407.261541)
			(xy 390.480296 -407.251408) (xy 390.480296 -407.09342) (xy 390.479877 -407.084234) (xy 390.47337 -407.067049)
			(xy 390.467596 -407.059892) (xy 390.445778 -407.034265) (xy 390.407833 -406.978674) (xy 390.376804 -406.918947)
			(xy 390.353135 -406.855939) (xy 390.337165 -406.790554) (xy 390.329124 -406.723729) (xy 387.051062 -406.723729)
			(xy 387.051062 -406.723787) (xy 387.04299 -406.790723) (xy 387.026958 -406.85621) (xy 387.003197 -406.919305)
			(xy 386.972051 -406.979101) (xy 386.933966 -407.034735) (xy 386.912104 -407.0604) (xy 386.906325 -407.067558)
			(xy 386.8998 -407.084739) (xy 386.899404 -407.093928) (xy 386.899404 -407.251408) (xy 386.898921 -407.261517)
			(xy 386.891182 -407.280194) (xy 386.876884 -407.294489) (xy 386.858205 -407.302224) (xy 386.848096 -407.302716)
			(xy 386.131816 -407.302716) (xy 386.121697 -407.302271) (xy 386.102996 -407.294531) (xy 386.088682 -407.280224)
			(xy 386.080933 -407.261527) (xy 386.080508 -407.251408) (xy 386.080508 -407.093928) (xy 386.080083 -407.084742)
			(xy 386.073579 -407.067558) (xy 386.067808 -407.0604) (xy 386.045912 -407.034761) (xy 386.007824 -406.979123)
			(xy 385.976674 -406.919323) (xy 385.952912 -406.856223) (xy 385.936878 -406.79073) (xy 385.928805 -406.723789)
			(xy 382.65076 -406.723789) (xy 382.642725 -406.790549) (xy 382.626754 -406.85593) (xy 382.603083 -406.918933)
			(xy 382.572051 -406.978655) (xy 382.534103 -407.03424) (xy 382.512316 -407.059892) (xy 382.506542 -407.067053)
			(xy 382.500013 -407.084231) (xy 382.499616 -407.09342) (xy 382.499616 -407.251408) (xy 382.499122 -407.261515)
			(xy 382.491384 -407.28019) (xy 382.47709 -407.294484) (xy 382.458415 -407.302222) (xy 382.448308 -407.302716)
			(xy 381.731774 -407.302716) (xy 381.72164 -407.302294) (xy 381.70291 -407.294549) (xy 381.688553 -407.280243)
			(xy 381.680743 -407.26154) (xy 381.680212 -407.251408) (xy 381.680212 -407.09342) (xy 381.679789 -407.084234)
			(xy 381.673284 -407.06705) (xy 381.667512 -407.059892) (xy 381.645694 -407.034265) (xy 381.607748 -406.978675)
			(xy 381.576717 -406.918947) (xy 381.553047 -406.855939) (xy 381.537077 -406.790554) (xy 381.529036 -406.723729)
			(xy 378.250974 -406.723729) (xy 378.250974 -406.723786) (xy 378.242902 -406.790722) (xy 378.226871 -406.856209)
			(xy 378.203111 -406.919305) (xy 378.171965 -406.9791) (xy 378.133881 -407.034734) (xy 378.11202 -407.0604)
			(xy 378.106243 -407.067559) (xy 378.099716 -407.084739) (xy 378.09932 -407.093928) (xy 378.09932 -407.251408)
			(xy 378.098822 -407.261515) (xy 378.091085 -407.280189) (xy 378.076793 -407.294483) (xy 378.058119 -407.302221)
			(xy 378.048012 -407.302716) (xy 377.331732 -407.302716) (xy 377.321614 -407.302258) (xy 377.302914 -407.294524)
			(xy 377.288599 -407.28022) (xy 377.280849 -407.261526) (xy 377.280424 -407.251408) (xy 377.280424 -407.093928)
			(xy 377.279995 -407.084743) (xy 377.273494 -407.067559) (xy 377.267724 -407.0604) (xy 377.245828 -407.034761)
			(xy 377.207738 -406.979123) (xy 377.176588 -406.919324) (xy 377.152824 -406.856223) (xy 377.13679 -406.790731)
			(xy 377.128717 -406.723789) (xy 347.450915 -406.723789) (xy 347.442881 -406.790547) (xy 347.426912 -406.855927)
			(xy 347.403244 -406.91893) (xy 347.372216 -406.978653) (xy 347.334273 -407.03424) (xy 347.312488 -407.059892)
			(xy 347.306711 -407.067051) (xy 347.300185 -407.084231) (xy 347.299788 -407.09342) (xy 347.299788 -407.251408)
			(xy 347.299385 -407.261564) (xy 347.291584 -407.280319) (xy 347.277182 -407.294642) (xy 347.258384 -407.30234)
			(xy 347.248226 -407.302716) (xy 346.531946 -407.302716) (xy 346.521817 -407.302234) (xy 346.503088 -407.294514)
			(xy 346.488729 -407.280225) (xy 346.480916 -407.261535) (xy 346.480384 -407.251408) (xy 346.480384 -407.09342)
			(xy 346.479968 -407.084233) (xy 346.473459 -407.067049) (xy 346.467684 -407.059892) (xy 346.445864 -407.034266)
			(xy 346.407913 -406.978677) (xy 346.376878 -406.91895) (xy 346.353205 -406.855942) (xy 346.337233 -406.790556)
			(xy 346.329191 -406.72373) (xy 343.051153 -406.72373) (xy 343.051153 -406.723787) (xy 343.04308 -406.790723)
			(xy 343.027048 -406.85621) (xy 343.003287 -406.919306) (xy 342.97214 -406.979101) (xy 342.934054 -407.034735)
			(xy 342.912192 -407.0604) (xy 342.906412 -407.067557) (xy 342.899888 -407.084738) (xy 342.899492 -407.093928)
			(xy 342.899492 -407.251408) (xy 342.89909 -407.261532) (xy 342.891338 -407.280237) (xy 342.877017 -407.294551)
			(xy 342.858308 -407.302295) (xy 342.848184 -407.302716) (xy 342.131904 -407.302716) (xy 342.121798 -407.302212)
			(xy 342.103122 -407.294479) (xy 342.088828 -407.280188) (xy 342.08109 -407.261514) (xy 342.080596 -407.251408)
			(xy 342.080596 -407.093928) (xy 342.080173 -407.084742) (xy 342.073668 -407.067558) (xy 342.067896 -407.0604)
			(xy 342.046001 -407.034761) (xy 342.007913 -406.979122) (xy 341.976764 -406.919322) (xy 341.953002 -406.856222)
			(xy 341.936969 -406.79073) (xy 341.928896 -406.723789) (xy 338.650827 -406.723789) (xy 338.642793 -406.790546)
			(xy 338.626825 -406.855926) (xy 338.603158 -406.918929) (xy 338.572131 -406.978652) (xy 338.534188 -407.034239)
			(xy 338.512404 -407.059892) (xy 338.506629 -407.067052) (xy 338.500101 -407.084231) (xy 338.499704 -407.09342)
			(xy 338.499704 -407.251408) (xy 338.499285 -407.261562) (xy 338.491487 -407.280314) (xy 338.47709 -407.294637)
			(xy 338.458298 -407.302337) (xy 338.448142 -407.302716) (xy 337.731862 -407.302716) (xy 337.721727 -407.302303)
			(xy 337.702997 -407.294555) (xy 337.688641 -407.280246) (xy 337.68083 -407.261541) (xy 337.6803 -407.251408)
			(xy 337.6803 -407.09342) (xy 337.67988 -407.084234) (xy 337.673373 -407.067049) (xy 337.6676 -407.059892)
			(xy 337.645782 -407.034265) (xy 337.607837 -406.978674) (xy 337.576807 -406.918947) (xy 337.553138 -406.855939)
			(xy 337.537168 -406.790554) (xy 337.529127 -406.723729) (xy 334.251065 -406.723729) (xy 334.251065 -406.723786)
			(xy 334.242993 -406.790722) (xy 334.226961 -406.85621) (xy 334.203201 -406.919305) (xy 334.172054 -406.9791)
			(xy 334.13397 -407.034735) (xy 334.112108 -407.0604) (xy 334.10633 -407.067558) (xy 334.099804 -407.084739)
			(xy 334.099408 -407.093928) (xy 334.099408 -407.251408) (xy 334.098921 -407.261516) (xy 334.091183 -407.280193)
			(xy 334.076886 -407.294487) (xy 334.058208 -407.302223) (xy 334.0481 -407.302716) (xy 333.33182 -407.302716)
			(xy 333.321701 -407.302268) (xy 333.303001 -407.29453) (xy 333.288686 -407.280223) (xy 333.280937 -407.261527)
			(xy 333.280512 -407.251408) (xy 333.280512 -407.093928) (xy 333.280086 -407.084743) (xy 333.273583 -407.067558)
			(xy 333.267812 -407.0604) (xy 333.245916 -407.034761) (xy 333.207828 -406.979123) (xy 333.176678 -406.919323)
			(xy 333.152915 -406.856223) (xy 333.136881 -406.790731) (xy 333.128808 -406.723789) (xy 326.525636 -406.723789)
			(xy 326.525636 -409.523827) (xy 330.929173 -409.523827) (xy 330.929176 -409.456519) (xy 330.937224 -409.389693)
			(xy 330.953202 -409.324309) (xy 330.976879 -409.261303) (xy 331.007918 -409.201578) (xy 331.045873 -409.145992)
			(xy 331.067664 -409.12034) (xy 331.073476 -409.113206) (xy 331.07998 -409.096007) (xy 331.080364 -409.086812)
			(xy 331.080364 -408.593544) (xy 331.079919 -408.584361) (xy 331.073428 -408.567177) (xy 331.067664 -408.560016)
			(xy 331.045868 -408.534371) (xy 331.007918 -408.478784) (xy 330.976883 -408.419059) (xy 330.95321 -408.356054)
			(xy 330.937237 -408.290671) (xy 330.929193 -408.223847) (xy 330.929194 -408.156541) (xy 330.937239 -408.089717)
			(xy 330.953213 -408.024334) (xy 330.976888 -407.96133) (xy 331.007924 -407.901606) (xy 331.045875 -407.84602)
			(xy 331.067664 -407.820368) (xy 331.073464 -407.813226) (xy 331.079975 -407.796033) (xy 331.080364 -407.78684)
			(xy 331.080364 -407.628852) (xy 331.080782 -407.618699) (xy 331.088586 -407.599953) (xy 331.102983 -407.585633)
			(xy 331.121771 -407.577928) (xy 331.131926 -407.577544) (xy 331.848206 -407.577544) (xy 331.858334 -407.578022)
			(xy 331.877056 -407.585752) (xy 331.891412 -407.600041) (xy 331.89923 -407.618727) (xy 331.899768 -407.628852)
			(xy 331.899768 -407.78684) (xy 331.900166 -407.796028) (xy 331.906689 -407.813212) (xy 331.912468 -407.820368)
			(xy 331.934248 -407.846027) (xy 331.972196 -407.901612) (xy 332.00323 -407.961335) (xy 332.026903 -408.024339)
			(xy 332.042876 -408.08972) (xy 332.050921 -408.156542) (xy 332.050921 -408.223846) (xy 332.042878 -408.290668)
			(xy 332.026906 -408.35605) (xy 332.003235 -408.419054) (xy 331.972203 -408.478777) (xy 331.934255 -408.534364)
			(xy 331.912468 -408.560016) (xy 331.906678 -408.567166) (xy 331.90016 -408.584353) (xy 331.899768 -408.593544)
			(xy 331.899768 -409.086812) (xy 331.900179 -409.095999) (xy 331.906693 -409.113183) (xy 331.912468 -409.12034)
			(xy 331.93422 -409.146022) (xy 331.972169 -409.201604) (xy 332.003204 -409.261323) (xy 332.026878 -409.324324)
			(xy 332.042853 -409.389703) (xy 332.0509 -409.456522) (xy 332.050904 -409.523824) (xy 332.042863 -409.590644)
			(xy 332.026894 -409.656024) (xy 332.003226 -409.719027) (xy 331.972197 -409.77875) (xy 331.934253 -409.834336)
			(xy 331.912468 -409.859988) (xy 331.906647 -409.867116) (xy 331.900148 -409.88432) (xy 331.899768 -409.893516)
			(xy 331.899768 -410.051504) (xy 331.899381 -410.061662) (xy 331.891578 -410.080421) (xy 331.87717 -410.094745)
			(xy 331.858367 -410.102439) (xy 331.848206 -410.102812) (xy 331.131926 -410.102812) (xy 331.121807 -410.102254)
			(xy 331.103097 -410.094544) (xy 331.088741 -410.08028) (xy 331.080912 -410.061619) (xy 331.080364 -410.051504)
			(xy 331.080364 -409.893516) (xy 331.079932 -409.884331) (xy 331.073432 -409.867148) (xy 331.067664 -409.859988)
			(xy 331.04584 -409.834365) (xy 331.007891 -409.778775) (xy 330.976857 -409.719048) (xy 330.953186 -409.656039)
			(xy 330.937214 -409.590653) (xy 330.929173 -409.523827) (xy 326.525636 -409.523827) (xy 326.525636 -410.623701)
			(xy 333.128819 -410.623701) (xy 333.12882 -410.556275) (xy 333.136898 -410.489336) (xy 333.152936 -410.423846)
			(xy 333.176702 -410.360748) (xy 333.207855 -410.300952) (xy 333.245947 -410.245317) (xy 333.267812 -410.219652)
			(xy 333.273613 -410.21251) (xy 333.280125 -410.195317) (xy 333.280512 -410.186124) (xy 333.280512 -409.693872)
			(xy 333.280113 -409.684684) (xy 333.273591 -409.6675) (xy 333.267812 -409.660344) (xy 333.245959 -409.634669)
			(xy 333.20787 -409.579036) (xy 333.176718 -409.519242) (xy 333.152952 -409.456146) (xy 333.136916 -409.390658)
			(xy 333.128839 -409.32372) (xy 333.128837 -409.256298) (xy 333.136912 -409.18936) (xy 333.152947 -409.123871)
			(xy 333.17671 -409.060775) (xy 333.20786 -409.000979) (xy 333.245948 -408.945345) (xy 333.267812 -408.91968)
			(xy 333.273601 -408.912529) (xy 333.28012 -408.895343) (xy 333.280512 -408.886152) (xy 333.280512 -408.728672)
			(xy 333.280962 -408.71856) (xy 333.288711 -408.699879) (xy 333.303019 -408.685585) (xy 333.321708 -408.677853)
			(xy 333.33182 -408.677364) (xy 334.0481 -408.677364) (xy 334.058204 -408.677884) (xy 334.076876 -408.685615)
			(xy 334.091169 -408.699901) (xy 334.09891 -408.718568) (xy 334.099408 -408.728672) (xy 334.099408 -408.886152)
			(xy 334.099839 -408.895337) (xy 334.106338 -408.912522) (xy 334.112108 -408.91968) (xy 334.133983 -408.945336)
			(xy 334.172071 -409.000972) (xy 334.203221 -409.060769) (xy 334.226984 -409.123867) (xy 334.243019 -409.189358)
			(xy 334.251093 -409.256297) (xy 334.251092 -409.323721) (xy 334.243015 -409.39066) (xy 334.226979 -409.45615)
			(xy 334.203214 -409.519247) (xy 334.200797 -409.523886) (xy 335.328966 -409.523886) (xy 335.328969 -409.45646)
			(xy 335.337048 -409.38952) (xy 335.353086 -409.32403) (xy 335.376852 -409.260931) (xy 335.408005 -409.201134)
			(xy 335.446095 -409.145498) (xy 335.46796 -409.119832) (xy 335.473775 -409.1127) (xy 335.480277 -409.095499)
			(xy 335.48066 -409.086304) (xy 335.48066 -408.594052) (xy 335.480211 -408.584869) (xy 335.473723 -408.567685)
			(xy 335.46796 -408.560524) (xy 335.44609 -408.534865) (xy 335.408004 -408.479228) (xy 335.376856 -408.419431)
			(xy 335.353094 -408.356333) (xy 335.33706 -408.290844) (xy 335.328985 -408.223906) (xy 335.328986 -408.156482)
			(xy 335.337062 -408.089544) (xy 335.353097 -408.024055) (xy 335.376861 -407.960958) (xy 335.40801 -407.901161)
			(xy 335.446097 -407.845526) (xy 335.46796 -407.81986) (xy 335.473763 -407.81272) (xy 335.480272 -407.795525)
			(xy 335.48066 -407.786332) (xy 335.48066 -407.628852) (xy 335.481145 -407.618745) (xy 335.488891 -407.600074)
			(xy 335.503187 -407.585782) (xy 335.521861 -407.578042) (xy 335.531968 -407.577544) (xy 336.248248 -407.577544)
			(xy 336.258353 -407.578045) (xy 336.277021 -407.585788) (xy 336.291312 -407.600079) (xy 336.299055 -407.618747)
			(xy 336.299556 -407.628852) (xy 336.299556 -407.786332) (xy 336.299961 -407.79552) (xy 336.306479 -407.812703)
			(xy 336.312256 -407.81986) (xy 336.334114 -407.845531) (xy 336.372205 -407.901164) (xy 336.403359 -407.960959)
			(xy 336.427126 -408.024055) (xy 336.443163 -408.089544) (xy 336.45124 -408.156482) (xy 336.451241 -408.223906)
			(xy 336.443165 -408.290844) (xy 336.427129 -408.356334) (xy 336.403364 -408.41943) (xy 336.372212 -408.479226)
			(xy 336.334121 -408.53486) (xy 336.312256 -408.560524) (xy 336.306461 -408.56767) (xy 336.299947 -408.58486)
			(xy 336.299556 -408.594052) (xy 336.299556 -409.086304) (xy 336.299974 -409.09549) (xy 336.306483 -409.112674)
			(xy 336.312256 -409.119832) (xy 336.334086 -409.145526) (xy 336.372179 -409.201155) (xy 336.403334 -409.260947)
			(xy 336.427102 -409.32404) (xy 336.443141 -409.389526) (xy 336.45122 -409.456462) (xy 336.451224 -409.523884)
			(xy 336.443151 -409.59082) (xy 336.427118 -409.656308) (xy 336.403356 -409.719404) (xy 336.372207 -409.779198)
			(xy 336.334119 -409.834832) (xy 336.312256 -409.860496) (xy 336.306473 -409.867651) (xy 336.299951 -409.884834)
			(xy 336.299556 -409.894024) (xy 336.299556 -410.051504) (xy 336.299019 -410.061606) (xy 336.291291 -410.080274)
			(xy 336.277011 -410.094566) (xy 336.25835 -410.102311) (xy 336.248248 -410.102812) (xy 335.531968 -410.102812)
			(xy 335.521859 -410.102341) (xy 335.503182 -410.094595) (xy 335.488889 -410.080294) (xy 335.481153 -410.061614)
			(xy 335.48066 -410.051504) (xy 335.48066 -409.894024) (xy 335.480225 -409.88484) (xy 335.473727 -409.867656)
			(xy 335.46796 -409.860496) (xy 335.446062 -409.834859) (xy 335.407977 -409.77922) (xy 335.37683 -409.719419)
			(xy 335.35307 -409.656319) (xy 335.337038 -409.590827) (xy 335.328966 -409.523886) (xy 334.200797 -409.523886)
			(xy 334.172062 -409.579044) (xy 334.133972 -409.634679) (xy 334.112108 -409.660344) (xy 334.106311 -409.667489)
			(xy 334.099796 -409.68468) (xy 334.099408 -409.693872) (xy 334.099408 -410.186124) (xy 334.099805 -410.195313)
			(xy 334.106328 -410.212497) (xy 334.112108 -410.219652) (xy 334.133956 -410.24533) (xy 334.172045 -410.300963)
			(xy 334.203196 -410.360758) (xy 334.22696 -410.423853) (xy 334.242997 -410.48934) (xy 334.251074 -410.556277)
			(xy 334.251075 -410.623641) (xy 337.529138 -410.623641) (xy 337.52914 -410.556335) (xy 337.537185 -410.489512)
			(xy 337.553158 -410.42413) (xy 337.576831 -410.361125) (xy 337.607864 -410.3014) (xy 337.645813 -410.245813)
			(xy 337.6676 -410.22016) (xy 337.673396 -410.213014) (xy 337.679911 -410.195824) (xy 337.6803 -410.186632)
			(xy 337.6803 -409.693364) (xy 337.679907 -409.684175) (xy 337.673382 -409.666991) (xy 337.6676 -409.659836)
			(xy 337.645825 -409.634174) (xy 337.607879 -409.578588) (xy 337.576847 -409.518865) (xy 337.553175 -409.455862)
			(xy 337.537203 -409.390482) (xy 337.529158 -409.323661) (xy 337.529157 -409.256357) (xy 337.537199 -409.189536)
			(xy 337.55317 -409.124155) (xy 337.57684 -409.061151) (xy 337.607869 -409.001428) (xy 337.645814 -408.945841)
			(xy 337.6676 -408.920188) (xy 337.673384 -408.913034) (xy 337.679906 -408.89585) (xy 337.6803 -408.88666)
			(xy 337.6803 -408.728672) (xy 337.680699 -408.718516) (xy 337.688503 -408.699763) (xy 337.702907 -408.685441)
			(xy 337.721704 -408.677742) (xy 337.731862 -408.677364) (xy 338.448142 -408.677364) (xy 338.458274 -408.677793)
			(xy 338.477001 -408.685539) (xy 338.491357 -408.699843) (xy 338.49917 -408.718542) (xy 338.499704 -408.728672)
			(xy 338.499704 -408.88666) (xy 338.500132 -408.895845) (xy 338.506633 -408.91303) (xy 338.512404 -408.920188)
			(xy 338.534202 -408.945831) (xy 338.572148 -409.00142) (xy 338.603178 -409.061145) (xy 338.626848 -409.124151)
			(xy 338.642819 -409.189534) (xy 338.650862 -409.256356) (xy 338.650861 -409.323662) (xy 338.642816 -409.390484)
			(xy 338.626843 -409.455867) (xy 338.603171 -409.518871) (xy 338.600596 -409.523827) (xy 339.729261 -409.523827)
			(xy 339.729264 -409.456519) (xy 339.737312 -409.389694) (xy 339.753289 -409.324309) (xy 339.776966 -409.261303)
			(xy 339.808004 -409.201579) (xy 339.845958 -409.145992) (xy 339.867748 -409.12034) (xy 339.873559 -409.113205)
			(xy 339.880064 -409.096006) (xy 339.880448 -409.086812) (xy 339.880448 -408.593544) (xy 339.880006 -408.58436)
			(xy 339.873513 -408.567176) (xy 339.867748 -408.560016) (xy 339.845952 -408.534371) (xy 339.808003 -408.478783)
			(xy 339.776969 -408.419059) (xy 339.753297 -408.356054) (xy 339.737324 -408.29067) (xy 339.72928 -408.223847)
			(xy 339.729281 -408.156541) (xy 339.737326 -408.089718) (xy 339.7533 -408.024335) (xy 339.776974 -407.96133)
			(xy 339.808009 -407.901606) (xy 339.845959 -407.84602) (xy 339.867748 -407.820368) (xy 339.873547 -407.813224)
			(xy 339.880059 -407.796032) (xy 339.880448 -407.78684) (xy 339.880448 -407.628852) (xy 339.880881 -407.618701)
			(xy 339.888683 -407.599958) (xy 339.903075 -407.585638) (xy 339.921857 -407.577931) (xy 339.93201 -407.577544)
			(xy 340.64829 -407.577544) (xy 340.658417 -407.578035) (xy 340.677138 -407.58576) (xy 340.691495 -407.600045)
			(xy 340.699314 -407.618728) (xy 340.699852 -407.628852) (xy 340.699852 -407.78684) (xy 340.700254 -407.796028)
			(xy 340.706775 -407.813211) (xy 340.712552 -407.820368) (xy 340.734332 -407.846027) (xy 340.772282 -407.901612)
			(xy 340.803316 -407.961335) (xy 340.826989 -408.024338) (xy 340.842963 -408.08972) (xy 340.851008 -408.156542)
			(xy 340.851009 -408.223846) (xy 340.842965 -408.290668) (xy 340.826993 -408.35605) (xy 340.803321 -408.419054)
			(xy 340.772288 -408.478778) (xy 340.734339 -408.534364) (xy 340.712552 -408.560016) (xy 340.70676 -408.567164)
			(xy 340.700244 -408.584353) (xy 340.699852 -408.593544) (xy 340.699852 -409.086812) (xy 340.700267 -409.095998)
			(xy 340.706779 -409.113182) (xy 340.712552 -409.12034) (xy 340.734304 -409.146021) (xy 340.772255 -409.201603)
			(xy 340.80329 -409.261323) (xy 340.826965 -409.324323) (xy 340.842941 -409.389702) (xy 340.850988 -409.456522)
			(xy 340.850992 -409.523824) (xy 340.842951 -409.590644) (xy 340.826981 -409.656025) (xy 340.803312 -409.719028)
			(xy 340.772283 -409.77875) (xy 340.734338 -409.834336) (xy 340.712552 -409.859988) (xy 340.70673 -409.867115)
			(xy 340.700232 -409.88432) (xy 340.699852 -409.893516) (xy 340.699852 -410.051504) (xy 340.699383 -410.061652)
			(xy 340.691595 -410.080394) (xy 340.677214 -410.094716) (xy 340.65844 -410.102424) (xy 340.64829 -410.102812)
			(xy 339.93201 -410.102812) (xy 339.92189 -410.102267) (xy 339.903179 -410.094552) (xy 339.888824 -410.080284)
			(xy 339.880996 -410.061621) (xy 339.880448 -410.051504) (xy 339.880448 -409.893516) (xy 339.88002 -409.884331)
			(xy 339.873517 -409.867147) (xy 339.867748 -409.859988) (xy 339.845924 -409.834365) (xy 339.807976 -409.778775)
			(xy 339.776944 -409.719047) (xy 339.753273 -409.656039) (xy 339.737302 -409.590653) (xy 339.729261 -409.523827)
			(xy 338.600596 -409.523827) (xy 338.572139 -409.578596) (xy 338.534191 -409.634183) (xy 338.512404 -409.659836)
			(xy 338.50661 -409.666983) (xy 338.500094 -409.684172) (xy 338.499704 -409.693364) (xy 338.499704 -410.186632)
			(xy 338.500098 -410.195821) (xy 338.506623 -410.213005) (xy 338.512404 -410.22016) (xy 338.534175 -410.245826)
			(xy 338.572121 -410.301411) (xy 338.603153 -410.361133) (xy 338.626825 -410.424136) (xy 338.642797 -410.489516)
			(xy 338.650842 -410.556336) (xy 338.650844 -410.623639) (xy 338.650837 -410.6237) (xy 341.928907 -410.6237)
			(xy 341.928908 -410.556276) (xy 341.936986 -410.489336) (xy 341.953023 -410.423846) (xy 341.976789 -410.360749)
			(xy 342.007941 -410.300952) (xy 342.046031 -410.245317) (xy 342.067896 -410.219652) (xy 342.073695 -410.212508)
			(xy 342.080208 -410.195317) (xy 342.080596 -410.186124) (xy 342.080596 -409.693872) (xy 342.0802 -409.684683)
			(xy 342.073677 -409.667499) (xy 342.067896 -409.660344) (xy 342.046044 -409.634669) (xy 342.007955 -409.579036)
			(xy 341.976804 -409.519241) (xy 341.953039 -409.456145) (xy 341.937003 -409.390657) (xy 341.928927 -409.32372)
			(xy 341.928925 -409.256298) (xy 341.937 -409.18936) (xy 341.953034 -409.123872) (xy 341.976797 -409.060776)
			(xy 342.007946 -409.00098) (xy 342.046033 -408.945345) (xy 342.067896 -408.91968) (xy 342.073683 -408.912528)
			(xy 342.080204 -408.895343) (xy 342.080596 -408.886152) (xy 342.080596 -408.728672) (xy 342.081062 -408.718562)
			(xy 342.088808 -408.699884) (xy 342.103111 -408.68559) (xy 342.121794 -408.677856) (xy 342.131904 -408.677364)
			(xy 342.848184 -408.677364) (xy 342.858287 -408.677897) (xy 342.876958 -408.685623) (xy 342.891252 -408.699905)
			(xy 342.898994 -408.718569) (xy 342.899492 -408.728672) (xy 342.899492 -408.886152) (xy 342.899927 -408.895337)
			(xy 342.906424 -408.912521) (xy 342.912192 -408.91968) (xy 342.934068 -408.945335) (xy 342.972157 -409.000971)
			(xy 343.003308 -409.060769) (xy 343.027071 -409.123867) (xy 343.043106 -409.189357) (xy 343.051181 -409.256297)
			(xy 343.05118 -409.323721) (xy 343.043103 -409.390661) (xy 343.027066 -409.45615) (xy 343.0033 -409.519248)
			(xy 343.000914 -409.523827) (xy 344.129052 -409.523827) (xy 344.129055 -409.456519) (xy 344.137102 -409.389694)
			(xy 344.153079 -409.32431) (xy 344.176756 -409.261304) (xy 344.207793 -409.201579) (xy 344.245746 -409.145992)
			(xy 344.267536 -409.12034) (xy 344.273345 -409.113204) (xy 344.279851 -409.096006) (xy 344.280236 -409.086812)
			(xy 344.280236 -408.593544) (xy 344.279796 -408.58436) (xy 344.273302 -408.567176) (xy 344.267536 -408.560016)
			(xy 344.24574 -408.53437) (xy 344.207792 -408.478783) (xy 344.176759 -408.419058) (xy 344.153087 -408.356053)
			(xy 344.137115 -408.29067) (xy 344.129071 -408.223847) (xy 344.129072 -408.156541) (xy 344.137117 -408.089718)
			(xy 344.153091 -408.024335) (xy 344.176764 -407.961331) (xy 344.207798 -407.901607) (xy 344.245748 -407.84602)
			(xy 344.267536 -407.820368) (xy 344.273333 -407.813223) (xy 344.279847 -407.796032) (xy 344.280236 -407.78684)
			(xy 344.280236 -407.628852) (xy 344.280583 -407.61869) (xy 344.288401 -407.59993) (xy 344.302821 -407.585607)
			(xy 344.321634 -407.577916) (xy 344.331798 -407.577544) (xy 345.048078 -407.577544) (xy 345.058204 -407.578045)
			(xy 345.076925 -407.585766) (xy 345.091283 -407.600048) (xy 345.099102 -407.618729) (xy 345.09964 -407.628852)
			(xy 345.09964 -407.78684) (xy 345.100044 -407.796028) (xy 345.106563 -407.813211) (xy 345.11234 -407.820368)
			(xy 345.13412 -407.846026) (xy 345.172071 -407.901611) (xy 345.203106 -407.961334) (xy 345.22678 -408.024338)
			(xy 345.242754 -408.089719) (xy 345.250799 -408.156542) (xy 345.2508 -408.223846) (xy 345.242756 -408.290669)
			(xy 345.226783 -408.356051) (xy 345.20311 -408.419055) (xy 345.172077 -408.478778) (xy 345.134128 -408.534364)
			(xy 345.11234 -408.560016) (xy 345.106547 -408.567163) (xy 345.100032 -408.584352) (xy 345.09964 -408.593544)
			(xy 345.09964 -409.086812) (xy 345.100058 -409.095998) (xy 345.106568 -409.113182) (xy 345.11234 -409.12034)
			(xy 345.134093 -409.146021) (xy 345.172044 -409.201603) (xy 345.20308 -409.261322) (xy 345.226756 -409.324323)
			(xy 345.242732 -409.389702) (xy 345.250779 -409.456522) (xy 345.250783 -409.523824) (xy 345.242742 -409.590645)
			(xy 345.226772 -409.656025) (xy 345.203102 -409.719028) (xy 345.172072 -409.778751) (xy 345.134126 -409.834336)
			(xy 345.11234 -409.859988) (xy 345.106516 -409.867114) (xy 345.100019 -409.884319) (xy 345.09964 -409.893516)
			(xy 345.09964 -410.051504) (xy 345.099182 -410.061653) (xy 345.091393 -410.080398) (xy 345.077008 -410.09472)
			(xy 345.058229 -410.102427) (xy 345.048078 -410.102812) (xy 344.331798 -410.102812) (xy 344.321678 -410.102277)
			(xy 344.302966 -410.094558) (xy 344.288612 -410.080287) (xy 344.280784 -410.061621) (xy 344.280236 -410.051504)
			(xy 344.280236 -409.893516) (xy 344.27981 -409.884331) (xy 344.273307 -409.867146) (xy 344.267536 -409.859988)
			(xy 344.245713 -409.834365) (xy 344.207765 -409.778774) (xy 344.176734 -409.719047) (xy 344.153063 -409.656038)
			(xy 344.137093 -409.590653) (xy 344.129052 -409.523827) (xy 343.000914 -409.523827) (xy 342.972148 -409.579044)
			(xy 342.934057 -409.634679) (xy 342.912192 -409.660344) (xy 342.906393 -409.667488) (xy 342.89988 -409.684679)
			(xy 342.899492 -409.693872) (xy 342.899492 -410.186124) (xy 342.899892 -410.195312) (xy 342.906413 -410.212496)
			(xy 342.912192 -410.219652) (xy 342.934041 -410.24533) (xy 342.97213 -410.300963) (xy 343.003282 -410.360757)
			(xy 343.027048 -410.423852) (xy 343.043084 -410.48934) (xy 343.051162 -410.556277) (xy 343.051163 -410.623642)
			(xy 346.329202 -410.623642) (xy 346.329204 -410.556334) (xy 346.33725 -410.48951) (xy 346.353226 -410.424126)
			(xy 346.376903 -410.361121) (xy 346.40794 -410.301397) (xy 346.445894 -410.245812) (xy 346.467684 -410.22016)
			(xy 346.473478 -410.213013) (xy 346.479995 -410.195824) (xy 346.480384 -410.186632) (xy 346.480384 -409.693364)
			(xy 346.479995 -409.684175) (xy 346.473467 -409.66699) (xy 346.467684 -409.659836) (xy 346.445907 -409.634175)
			(xy 346.407955 -409.578591) (xy 346.376918 -409.518869) (xy 346.353243 -409.455865) (xy 346.337268 -409.390484)
			(xy 346.329222 -409.323661) (xy 346.329221 -409.256357) (xy 346.337265 -409.189534) (xy 346.353238 -409.124152)
			(xy 346.376911 -409.061148) (xy 346.407945 -409.001425) (xy 346.445896 -408.94584) (xy 346.467684 -408.920188)
			(xy 346.473466 -408.913033) (xy 346.47999 -408.89585) (xy 346.480384 -408.88666) (xy 346.480384 -408.728672)
			(xy 346.480798 -408.718518) (xy 346.4886 -408.699768) (xy 346.502999 -408.685446) (xy 346.52179 -408.677745)
			(xy 346.531946 -408.677364) (xy 347.248226 -408.677364) (xy 347.258357 -408.677806) (xy 347.277084 -408.685547)
			(xy 347.29144 -408.699847) (xy 347.299254 -408.718543) (xy 347.299788 -408.728672) (xy 347.299788 -408.88666)
			(xy 347.30022 -408.895845) (xy 347.306719 -408.913029) (xy 347.312488 -408.920188) (xy 347.334287 -408.945831)
			(xy 347.372233 -409.001419) (xy 347.403265 -409.061144) (xy 347.426936 -409.12415) (xy 347.442907 -409.189533)
			(xy 347.45095 -409.256356) (xy 347.450949 -409.323662) (xy 347.442904 -409.390485) (xy 347.42693 -409.455867)
			(xy 347.403257 -409.518872) (xy 347.400682 -409.523827) (xy 374.929082 -409.523827) (xy 374.929085 -409.456519)
			(xy 374.937133 -409.389693) (xy 374.953111 -409.324308) (xy 374.97679 -409.261302) (xy 375.007829 -409.201578)
			(xy 375.045785 -409.145991) (xy 375.067576 -409.12034) (xy 375.073378 -409.113198) (xy 375.07989 -409.096005)
			(xy 375.080276 -409.086812) (xy 375.080276 -408.593544) (xy 375.07985 -408.584358) (xy 375.073348 -408.567174)
			(xy 375.067576 -408.560016) (xy 375.045779 -408.534371) (xy 375.007828 -408.478784) (xy 374.976793 -408.41906)
			(xy 374.953119 -408.356055) (xy 374.937146 -408.290671) (xy 374.929102 -408.223847) (xy 374.929103 -408.156541)
			(xy 374.937148 -408.089717) (xy 374.953123 -408.024334) (xy 374.976798 -407.961329) (xy 375.007835 -407.901605)
			(xy 375.045787 -407.84602) (xy 375.067576 -407.820368) (xy 375.073366 -407.813218) (xy 375.079885 -407.796031)
			(xy 375.080276 -407.78684) (xy 375.080276 -407.628852) (xy 375.080682 -407.618698) (xy 375.088489 -407.599949)
			(xy 375.10289 -407.585628) (xy 375.121682 -407.577926) (xy 375.131838 -407.577544) (xy 375.848118 -407.577544)
			(xy 375.858246 -407.578012) (xy 375.876969 -407.585746) (xy 375.891325 -407.600038) (xy 375.899143 -407.618726)
			(xy 375.89968 -407.628852) (xy 375.89968 -407.78684) (xy 375.900075 -407.796029) (xy 375.9066 -407.813213)
			(xy 375.91238 -407.820368) (xy 375.934159 -407.846027) (xy 375.972107 -407.901613) (xy 376.00314 -407.961336)
			(xy 376.026812 -408.024339) (xy 376.042785 -408.08972) (xy 376.05083 -408.156542) (xy 376.05083 -408.223846)
			(xy 376.042787 -408.290668) (xy 376.026816 -408.356049) (xy 376.003145 -408.419053) (xy 375.972113 -408.478777)
			(xy 375.934167 -408.534364) (xy 375.91238 -408.560016) (xy 375.906592 -408.567167) (xy 375.900073 -408.584353)
			(xy 375.89968 -408.593544) (xy 375.89968 -409.086812) (xy 375.900089 -409.095999) (xy 375.906604 -409.113183)
			(xy 375.91238 -409.12034) (xy 375.934131 -409.146022) (xy 375.97208 -409.201604) (xy 376.003114 -409.261324)
			(xy 376.026788 -409.324325) (xy 376.042763 -409.389703) (xy 376.050809 -409.456522) (xy 376.050813 -409.523824)
			(xy 376.042772 -409.590644) (xy 376.026804 -409.656024) (xy 376.003136 -409.719026) (xy 375.972108 -409.778749)
			(xy 375.934165 -409.834335) (xy 375.91238 -409.859988) (xy 375.906561 -409.867117) (xy 375.90006 -409.88432)
			(xy 375.89968 -409.893516) (xy 375.89968 -410.051504) (xy 375.899281 -410.061661) (xy 375.891481 -410.080417)
			(xy 375.877077 -410.094741) (xy 375.858277 -410.102437) (xy 375.848118 -410.102812) (xy 375.131838 -410.102812)
			(xy 375.12172 -410.102244) (xy 375.10301 -410.094538) (xy 375.088654 -410.080277) (xy 375.080824 -410.061618)
			(xy 375.080276 -410.051504) (xy 375.080276 -409.893516) (xy 375.079864 -409.884329) (xy 375.073352 -409.867144)
			(xy 375.067576 -409.859988) (xy 375.045751 -409.834366) (xy 375.007801 -409.778776) (xy 374.976768 -409.719048)
			(xy 374.953095 -409.65604) (xy 374.937124 -409.590654) (xy 374.929082 -409.523827) (xy 347.400682 -409.523827)
			(xy 347.372224 -409.578596) (xy 347.334276 -409.634184) (xy 347.312488 -409.659836) (xy 347.306692 -409.666982)
			(xy 347.300177 -409.684172) (xy 347.299788 -409.693364) (xy 347.299788 -410.186632) (xy 347.300185 -410.195821)
			(xy 347.306708 -410.213005) (xy 347.312488 -410.22016) (xy 347.334259 -410.245825) (xy 347.372207 -410.301411)
			(xy 347.403239 -410.361133) (xy 347.426912 -410.424135) (xy 347.442885 -410.489516) (xy 347.45093 -410.556336)
			(xy 347.450931 -410.62364) (xy 347.450924 -410.623701) (xy 377.128728 -410.623701) (xy 377.128729 -410.556275)
			(xy 377.136807 -410.489335) (xy 377.152845 -410.423845) (xy 377.176612 -410.360748) (xy 377.207766 -410.300951)
			(xy 377.245858 -410.245317) (xy 377.267724 -410.219652) (xy 377.273526 -410.212511) (xy 377.280037 -410.195317)
			(xy 377.280424 -410.186124) (xy 377.280424 -409.693872) (xy 377.280022 -409.684684) (xy 377.273502 -409.6675)
			(xy 377.267724 -409.660344) (xy 377.245871 -409.634669) (xy 377.20778 -409.579037) (xy 377.176628 -409.519242)
			(xy 377.152862 -409.456146) (xy 377.136825 -409.390658) (xy 377.128748 -409.323721) (xy 377.128747 -409.256297)
			(xy 377.136822 -409.18936) (xy 377.152857 -409.123871) (xy 377.17662 -409.060774) (xy 377.207771 -409.000979)
			(xy 377.24586 -408.945345) (xy 377.267724 -408.91968) (xy 377.273514 -408.912531) (xy 377.280032 -408.895343)
			(xy 377.280424 -408.886152) (xy 377.280424 -408.728672) (xy 377.280794 -408.718545) (xy 377.288555 -408.699836)
			(xy 377.302886 -408.685522) (xy 377.321604 -408.677782) (xy 377.331732 -408.677364) (xy 378.048012 -408.677364)
			(xy 378.058117 -408.677875) (xy 378.076789 -408.685609) (xy 378.091082 -408.699898) (xy 378.098822 -408.718567)
			(xy 378.09932 -408.728672) (xy 378.09932 -408.886152) (xy 378.099749 -408.895337) (xy 378.106249 -408.912522)
			(xy 378.11202 -408.91968) (xy 378.133895 -408.945336) (xy 378.171982 -409.000972) (xy 378.203131 -409.06077)
			(xy 378.226894 -409.123868) (xy 378.242928 -409.189358) (xy 378.251002 -409.256297) (xy 378.251001 -409.323721)
			(xy 378.242925 -409.39066) (xy 378.226888 -409.456149) (xy 378.203124 -409.519247) (xy 378.200707 -409.523886)
			(xy 379.328875 -409.523886) (xy 379.328878 -409.45646) (xy 379.336957 -409.38952) (xy 379.352995 -409.324029)
			(xy 379.376762 -409.260931) (xy 379.407916 -409.201133) (xy 379.446007 -409.145498) (xy 379.467872 -409.119832)
			(xy 379.473689 -409.112701) (xy 379.480189 -409.095499) (xy 379.480572 -409.086304) (xy 379.480572 -408.594052)
			(xy 379.480143 -408.584867) (xy 379.473643 -408.567682) (xy 379.467872 -408.560524) (xy 379.446001 -408.534865)
			(xy 379.407915 -408.479229) (xy 379.376766 -408.419431) (xy 379.353003 -408.356334) (xy 379.336969 -408.290844)
			(xy 379.328894 -408.223906) (xy 379.328895 -408.156482) (xy 379.336971 -408.089544) (xy 379.353007 -408.024055)
			(xy 379.376771 -407.960958) (xy 379.407921 -407.901161) (xy 379.446009 -407.845526) (xy 379.467872 -407.81986)
			(xy 379.473677 -407.812721) (xy 379.480185 -407.795525) (xy 379.480572 -407.786332) (xy 379.480572 -407.628852)
			(xy 379.481045 -407.618744) (xy 379.488793 -407.60007) (xy 379.503093 -407.585778) (xy 379.521771 -407.57804)
			(xy 379.53188 -407.577544) (xy 380.24816 -407.577544) (xy 380.258259 -407.578117) (xy 380.276926 -407.585831)
			(xy 380.29122 -407.6001) (xy 380.298966 -407.618754) (xy 380.299468 -407.628852) (xy 380.299468 -407.786332)
			(xy 380.29987 -407.79552) (xy 380.30639 -407.812704) (xy 380.312168 -407.81986) (xy 380.334025 -407.845531)
			(xy 380.372116 -407.901164) (xy 380.403269 -407.960959) (xy 380.427035 -408.024055) (xy 380.443072 -408.089544)
			(xy 380.451149 -408.156482) (xy 380.45115 -408.223906) (xy 380.443074 -408.290844) (xy 380.427039 -408.356333)
			(xy 380.403274 -408.41943) (xy 380.372122 -408.479226) (xy 380.334033 -408.534859) (xy 380.312168 -408.560524)
			(xy 380.306375 -408.567671) (xy 380.299859 -408.58486) (xy 380.299468 -408.594052) (xy 380.299468 -409.086304)
			(xy 380.299883 -409.09549) (xy 380.306394 -409.112675) (xy 380.312168 -409.119832) (xy 380.333998 -409.145526)
			(xy 380.37209 -409.201156) (xy 380.403244 -409.260947) (xy 380.427011 -409.324041) (xy 380.44305 -409.389527)
			(xy 380.451129 -409.456462) (xy 380.451133 -409.523884) (xy 380.44306 -409.59082) (xy 380.427027 -409.656308)
			(xy 380.403266 -409.719403) (xy 380.372117 -409.779198) (xy 380.334031 -409.834831) (xy 380.312168 -409.860496)
			(xy 380.306386 -409.867652) (xy 380.299864 -409.884834) (xy 380.299468 -409.894024) (xy 380.299468 -410.051504)
			(xy 380.299086 -410.061631) (xy 380.291331 -410.08034) (xy 380.277003 -410.094656) (xy 380.258287 -410.102395)
			(xy 380.24816 -410.102812) (xy 379.53188 -410.102812) (xy 379.521771 -410.102332) (xy 379.503095 -410.09459)
			(xy 379.488801 -410.080292) (xy 379.481065 -410.061613) (xy 379.480572 -410.051504) (xy 379.480572 -409.894024)
			(xy 379.480157 -409.884837) (xy 379.473647 -409.867652) (xy 379.467872 -409.860496) (xy 379.445974 -409.834859)
			(xy 379.407888 -409.77922) (xy 379.37674 -409.71942) (xy 379.352979 -409.656319) (xy 379.336947 -409.590827)
			(xy 379.328875 -409.523886) (xy 378.200707 -409.523886) (xy 378.171973 -409.579043) (xy 378.133884 -409.634678)
			(xy 378.11202 -409.660344) (xy 378.106225 -409.66749) (xy 378.099709 -409.68468) (xy 378.09932 -409.693872)
			(xy 378.09932 -410.186124) (xy 378.099714 -410.195313) (xy 378.106239 -410.212497) (xy 378.11202 -410.219652)
			(xy 378.133868 -410.245331) (xy 378.171955 -410.300964) (xy 378.203106 -410.360758) (xy 378.22687 -410.423853)
			(xy 378.242906 -410.48934) (xy 378.250983 -410.556277) (xy 378.250984 -410.623641) (xy 381.529047 -410.623641)
			(xy 381.529049 -410.556335) (xy 381.537094 -410.489512) (xy 381.553068 -410.424129) (xy 381.576742 -410.361124)
			(xy 381.607775 -410.3014) (xy 381.645724 -410.245812) (xy 381.667512 -410.22016) (xy 381.673309 -410.213015)
			(xy 381.679823 -410.195824) (xy 381.680212 -410.186632) (xy 381.680212 -409.693364) (xy 381.679817 -409.684175)
			(xy 381.673292 -409.666991) (xy 381.667512 -409.659836) (xy 381.645737 -409.634174) (xy 381.607789 -409.578588)
			(xy 381.576757 -409.518866) (xy 381.553085 -409.455863) (xy 381.537112 -409.390482) (xy 381.529067 -409.323661)
			(xy 381.529066 -409.256357) (xy 381.537109 -409.189536) (xy 381.553079 -409.124155) (xy 381.57675 -409.061151)
			(xy 381.60778 -409.001427) (xy 381.645726 -408.94584) (xy 381.667512 -408.920188) (xy 381.673298 -408.913035)
			(xy 381.679818 -408.89585) (xy 381.680212 -408.88666) (xy 381.680212 -408.728672) (xy 381.680662 -408.71856)
			(xy 381.688411 -408.699879) (xy 381.702719 -408.685585) (xy 381.721408 -408.677853) (xy 381.73152 -408.677364)
			(xy 382.448054 -408.677364) (xy 382.458181 -408.677865) (xy 382.476905 -408.685582) (xy 382.491264 -408.699865)
			(xy 382.499081 -408.718548) (xy 382.499616 -408.728672) (xy 382.499616 -408.88666) (xy 382.500042 -408.895846)
			(xy 382.506544 -408.91303) (xy 382.512316 -408.920188) (xy 382.534117 -408.94583) (xy 382.572068 -409.001417)
			(xy 382.603103 -409.061141) (xy 382.626778 -409.124147) (xy 382.642751 -409.189531) (xy 382.650795 -409.256356)
			(xy 382.650794 -409.323662) (xy 382.642748 -409.390487) (xy 382.626772 -409.45587) (xy 382.603096 -409.518875)
			(xy 382.600523 -409.523827) (xy 383.72917 -409.523827) (xy 383.729173 -409.456519) (xy 383.737221 -409.389693)
			(xy 383.753198 -409.324309) (xy 383.776876 -409.261303) (xy 383.807915 -409.201578) (xy 383.845869 -409.145992)
			(xy 383.86766 -409.12034) (xy 383.873472 -409.113206) (xy 383.879976 -409.096007) (xy 383.88036 -409.086812)
			(xy 383.88036 -408.593544) (xy 383.879915 -408.584361) (xy 383.873424 -408.567177) (xy 383.86766 -408.560016)
			(xy 383.845864 -408.53437) (xy 383.807914 -408.478784) (xy 383.77688 -408.419059) (xy 383.753207 -408.356054)
			(xy 383.737234 -408.290671) (xy 383.72919 -408.223847) (xy 383.729191 -408.156541) (xy 383.737236 -408.089717)
			(xy 383.75321 -408.024335) (xy 383.776885 -407.96133) (xy 383.80792 -407.901606) (xy 383.845871 -407.84602)
			(xy 383.86766 -407.820368) (xy 383.87346 -407.813226) (xy 383.879971 -407.796033) (xy 383.88036 -407.78684)
			(xy 383.88036 -407.628852) (xy 383.880845 -407.618745) (xy 383.888591 -407.600074) (xy 383.902887 -407.585782)
			(xy 383.921561 -407.578042) (xy 383.931668 -407.577544) (xy 384.648202 -407.577544) (xy 384.658329 -407.578025)
			(xy 384.677051 -407.585754) (xy 384.691408 -407.600042) (xy 384.699226 -407.618727) (xy 384.699764 -407.628852)
			(xy 384.699764 -407.78684) (xy 384.700163 -407.796028) (xy 384.706685 -407.813212) (xy 384.712464 -407.820368)
			(xy 384.734244 -407.846027) (xy 384.772193 -407.901612) (xy 384.803226 -407.961335) (xy 384.826899 -408.024339)
			(xy 384.842873 -408.08972) (xy 384.850918 -408.156542) (xy 384.850918 -408.223846) (xy 384.842875 -408.290668)
			(xy 384.826903 -408.35605) (xy 384.803231 -408.419054) (xy 384.772199 -408.478778) (xy 384.734251 -408.534364)
			(xy 384.712464 -408.560016) (xy 384.706674 -408.567165) (xy 384.700156 -408.584353) (xy 384.699764 -408.593544)
			(xy 384.699764 -409.086812) (xy 384.700176 -409.095999) (xy 384.706689 -409.113183) (xy 384.712464 -409.12034)
			(xy 384.734216 -409.146021) (xy 384.772166 -409.201604) (xy 384.8032 -409.261323) (xy 384.826875 -409.324324)
			(xy 384.84285 -409.389703) (xy 384.850897 -409.456522) (xy 384.850901 -409.523824) (xy 384.84286 -409.590644)
			(xy 384.826891 -409.656024) (xy 384.803222 -409.719027) (xy 384.772194 -409.77875) (xy 384.734249 -409.834336)
			(xy 384.712464 -409.859988) (xy 384.706643 -409.867116) (xy 384.700144 -409.88432) (xy 384.699764 -409.893516)
			(xy 384.699764 -410.051504) (xy 384.699386 -410.061631) (xy 384.69163 -410.080342) (xy 384.677301 -410.094657)
			(xy 384.658584 -410.102396) (xy 384.648456 -410.102812) (xy 383.931922 -410.102812) (xy 383.921803 -410.102257)
			(xy 383.903092 -410.094546) (xy 383.888737 -410.080281) (xy 383.880908 -410.06162) (xy 383.88036 -410.051504)
			(xy 383.88036 -409.893516) (xy 383.879929 -409.884331) (xy 383.873428 -409.867147) (xy 383.86766 -409.859988)
			(xy 383.845836 -409.834365) (xy 383.807887 -409.778775) (xy 383.776854 -409.719048) (xy 383.753182 -409.656039)
			(xy 383.737211 -409.590653) (xy 383.72917 -409.523827) (xy 382.600523 -409.523827) (xy 382.572059 -409.578599)
			(xy 382.534106 -409.634184) (xy 382.512316 -409.659836) (xy 382.506523 -409.666984) (xy 382.500006 -409.684172)
			(xy 382.499616 -409.693364) (xy 382.499616 -410.186632) (xy 382.500007 -410.195821) (xy 382.506534 -410.213006)
			(xy 382.512316 -410.22016) (xy 382.534089 -410.245824) (xy 382.572042 -410.301408) (xy 382.603078 -410.36113)
			(xy 382.626754 -410.424133) (xy 382.642729 -410.489514) (xy 382.650775 -410.556336) (xy 382.650777 -410.62364)
			(xy 382.65077 -410.623701) (xy 385.928816 -410.623701) (xy 385.928817 -410.556275) (xy 385.936895 -410.489336)
			(xy 385.952932 -410.423846) (xy 385.976699 -410.360748) (xy 386.007852 -410.300952) (xy 386.045943 -410.245317)
			(xy 386.067808 -410.219652) (xy 386.073608 -410.21251) (xy 386.080121 -410.195317) (xy 386.080508 -410.186124)
			(xy 386.080508 -409.693872) (xy 386.08011 -409.684684) (xy 386.073588 -409.667499) (xy 386.067808 -409.660344)
			(xy 386.045956 -409.634669) (xy 386.007866 -409.579036) (xy 385.976714 -409.519241) (xy 385.952949 -409.456146)
			(xy 385.936913 -409.390658) (xy 385.928836 -409.32372) (xy 385.928834 -409.256298) (xy 385.936909 -409.18936)
			(xy 385.952944 -409.123871) (xy 385.976707 -409.060775) (xy 386.007857 -409.000979) (xy 386.045944 -408.945345)
			(xy 386.067808 -408.91968) (xy 386.073596 -408.912529) (xy 386.080116 -408.895343) (xy 386.080508 -408.886152)
			(xy 386.080508 -408.728672) (xy 386.080962 -408.71856) (xy 386.088711 -408.69988) (xy 386.103017 -408.685586)
			(xy 386.121704 -408.677854) (xy 386.131816 -408.677364) (xy 386.848096 -408.677364) (xy 386.8582 -408.677888)
			(xy 386.876871 -408.685617) (xy 386.891165 -408.699902) (xy 386.898906 -408.718568) (xy 386.899404 -408.728672)
			(xy 386.899404 -408.886152) (xy 386.899836 -408.895337) (xy 386.906334 -408.912522) (xy 386.912104 -408.91968)
			(xy 386.93398 -408.945336) (xy 386.972068 -409.000972) (xy 387.003218 -409.060769) (xy 387.026981 -409.123867)
			(xy 387.043016 -409.189357) (xy 387.05109 -409.256297) (xy 387.051089 -409.323721) (xy 387.043012 -409.39066)
			(xy 387.026976 -409.45615) (xy 387.00321 -409.519247) (xy 387.000824 -409.523827) (xy 388.128961 -409.523827)
			(xy 388.128964 -409.456519) (xy 388.137012 -409.389694) (xy 388.152989 -409.324309) (xy 388.176666 -409.261303)
			(xy 388.207704 -409.201579) (xy 388.245658 -409.145992) (xy 388.267448 -409.12034) (xy 388.273259 -409.113205)
			(xy 388.279764 -409.096006) (xy 388.280148 -409.086812) (xy 388.280148 -408.593544) (xy 388.279706 -408.58436)
			(xy 388.273213 -408.567176) (xy 388.267448 -408.560016) (xy 388.245652 -408.534371) (xy 388.207703 -408.478783)
			(xy 388.176669 -408.419059) (xy 388.152997 -408.356054) (xy 388.137024 -408.29067) (xy 388.12898 -408.223847)
			(xy 388.128981 -408.156541) (xy 388.137026 -408.089718) (xy 388.153 -408.024335) (xy 388.176674 -407.96133)
			(xy 388.207709 -407.901606) (xy 388.245659 -407.84602) (xy 388.267448 -407.820368) (xy 388.273247 -407.813224)
			(xy 388.279759 -407.796032) (xy 388.280148 -407.78684) (xy 388.280148 -407.628852) (xy 388.280645 -407.618747)
			(xy 388.288388 -407.600077) (xy 388.302681 -407.585786) (xy 388.321351 -407.578044) (xy 388.331456 -407.577544)
			(xy 389.04799 -407.577544) (xy 389.058117 -407.578035) (xy 389.076838 -407.58576) (xy 389.091195 -407.600045)
			(xy 389.099014 -407.618728) (xy 389.099552 -407.628852) (xy 389.099552 -407.78684) (xy 389.099954 -407.796028)
			(xy 389.106475 -407.813211) (xy 389.112252 -407.820368) (xy 389.134032 -407.846027) (xy 389.171982 -407.901612)
			(xy 389.203016 -407.961335) (xy 389.226689 -408.024338) (xy 389.242663 -408.08972) (xy 389.250708 -408.156542)
			(xy 389.250709 -408.223846) (xy 389.242665 -408.290668) (xy 389.226693 -408.35605) (xy 389.203021 -408.419054)
			(xy 389.171988 -408.478778) (xy 389.134039 -408.534364) (xy 389.112252 -408.560016) (xy 389.10646 -408.567164)
			(xy 389.099944 -408.584353) (xy 389.099552 -408.593544) (xy 389.099552 -409.086812) (xy 389.099967 -409.095998)
			(xy 389.106479 -409.113182) (xy 389.112252 -409.12034) (xy 389.134004 -409.146021) (xy 389.171955 -409.201603)
			(xy 389.20299 -409.261323) (xy 389.226665 -409.324323) (xy 389.242641 -409.389702) (xy 389.250688 -409.456522)
			(xy 389.250692 -409.523824) (xy 389.242651 -409.590644) (xy 389.226681 -409.656025) (xy 389.203012 -409.719028)
			(xy 389.171983 -409.77875) (xy 389.134038 -409.834336) (xy 389.112252 -409.859988) (xy 389.10643 -409.867115)
			(xy 389.099932 -409.88432) (xy 389.099552 -409.893516) (xy 389.099552 -410.051504) (xy 389.099019 -410.061607)
			(xy 389.09129 -410.080275) (xy 389.077008 -410.094568) (xy 389.058346 -410.102311) (xy 389.048244 -410.102812)
			(xy 388.33171 -410.102812) (xy 388.32159 -410.102267) (xy 388.302879 -410.094552) (xy 388.288524 -410.080284)
			(xy 388.280696 -410.061621) (xy 388.280148 -410.051504) (xy 388.280148 -409.893516) (xy 388.27972 -409.884331)
			(xy 388.273217 -409.867147) (xy 388.267448 -409.859988) (xy 388.245624 -409.834365) (xy 388.207676 -409.778775)
			(xy 388.176644 -409.719047) (xy 388.152973 -409.656039) (xy 388.137002 -409.590653) (xy 388.128961 -409.523827)
			(xy 387.000824 -409.523827) (xy 386.972058 -409.579044) (xy 386.933969 -409.634679) (xy 386.912104 -409.660344)
			(xy 386.906307 -409.667489) (xy 386.899792 -409.68468) (xy 386.899404 -409.693872) (xy 386.899404 -410.186124)
			(xy 386.899801 -410.195313) (xy 386.906324 -410.212497) (xy 386.912104 -410.219652) (xy 386.933952 -410.24533)
			(xy 386.972041 -410.300963) (xy 387.003192 -410.360757) (xy 387.026957 -410.423853) (xy 387.042994 -410.48934)
			(xy 387.051071 -410.556277) (xy 387.051072 -410.623641) (xy 390.329135 -410.623641) (xy 390.329137 -410.556335)
			(xy 390.337182 -410.489512) (xy 390.353155 -410.42413) (xy 390.376828 -410.361125) (xy 390.407861 -410.3014)
			(xy 390.445809 -410.245813) (xy 390.467596 -410.22016) (xy 390.473392 -410.213014) (xy 390.479907 -410.195824)
			(xy 390.480296 -410.186632) (xy 390.480296 -409.693364) (xy 390.479904 -409.684175) (xy 390.473378 -409.666991)
			(xy 390.467596 -409.659836) (xy 390.445821 -409.634174) (xy 390.407875 -409.578588) (xy 390.376844 -409.518865)
			(xy 390.353172 -409.455862) (xy 390.3372 -409.390481) (xy 390.329155 -409.323661) (xy 390.329154 -409.256357)
			(xy 390.337196 -409.189536) (xy 390.353167 -409.124155) (xy 390.376836 -409.061151) (xy 390.407866 -409.001428)
			(xy 390.44581 -408.945841) (xy 390.467596 -408.920188) (xy 390.47338 -408.913034) (xy 390.479902 -408.89585)
			(xy 390.480296 -408.88666) (xy 390.480296 -408.728672) (xy 390.480762 -408.718562) (xy 390.488508 -408.699884)
			(xy 390.502811 -408.68559) (xy 390.521494 -408.677856) (xy 390.531604 -408.677364) (xy 391.248138 -408.677364)
			(xy 391.25827 -408.677796) (xy 391.276997 -408.685541) (xy 391.291352 -408.699844) (xy 391.299166 -408.718542)
			(xy 391.2997 -408.728672) (xy 391.2997 -408.88666) (xy 391.300129 -408.895845) (xy 391.30663 -408.91303)
			(xy 391.3124 -408.920188) (xy 391.334198 -408.945831) (xy 391.372144 -409.00142) (xy 391.403175 -409.061145)
			(xy 391.426845 -409.12415) (xy 391.442816 -409.189533) (xy 391.450859 -409.256356) (xy 391.450858 -409.323662)
			(xy 391.442813 -409.390484) (xy 391.42684 -409.455867) (xy 391.403167 -409.518872) (xy 391.372135 -409.578596)
			(xy 391.334187 -409.634183) (xy 391.3124 -409.659836) (xy 391.306606 -409.666983) (xy 391.30009 -409.684172)
			(xy 391.2997 -409.693364) (xy 391.2997 -410.186632) (xy 391.300095 -410.195821) (xy 391.306619 -410.213005)
			(xy 391.3124 -410.22016) (xy 391.334171 -410.245826) (xy 391.372118 -410.301411) (xy 391.403149 -410.361133)
			(xy 391.426821 -410.424136) (xy 391.442794 -410.489516) (xy 391.450839 -410.556336) (xy 391.450841 -410.623639)
			(xy 391.442799 -410.69046) (xy 391.426828 -410.755841) (xy 391.403159 -410.818845) (xy 391.37213 -410.878568)
			(xy 391.334186 -410.934155) (xy 391.3124 -410.959808) (xy 391.306618 -410.966963) (xy 391.300094 -410.984146)
			(xy 391.2997 -410.993336) (xy 391.2997 -411.151324) (xy 391.299235 -411.161434) (xy 391.291489 -411.180113)
			(xy 391.277186 -411.194407) (xy 391.258503 -411.202141) (xy 391.248392 -411.202632) (xy 390.531858 -411.202632)
			(xy 390.521725 -411.202207) (xy 390.502998 -411.19446) (xy 390.488642 -411.180155) (xy 390.480829 -411.161455)
			(xy 390.480296 -411.151324) (xy 390.480296 -410.993336) (xy 390.479869 -410.984151) (xy 390.473367 -410.966966)
			(xy 390.467596 -410.959808) (xy 390.445794 -410.934168) (xy 390.407848 -410.878579) (xy 390.376818 -410.818853)
			(xy 390.353148 -410.755847) (xy 390.337178 -410.690464) (xy 390.329135 -410.623641) (xy 387.051072 -410.623641)
			(xy 387.051072 -410.623699) (xy 387.042998 -410.690636) (xy 387.026964 -410.756124) (xy 387.003202 -410.819221)
			(xy 386.972053 -410.879016) (xy 386.933967 -410.934651) (xy 386.912104 -410.960316) (xy 386.906319 -410.967469)
			(xy 386.899797 -410.984654) (xy 386.899404 -410.993844) (xy 386.899404 -411.151324) (xy 386.898935 -411.161434)
			(xy 386.89119 -411.180112) (xy 386.876888 -411.194406) (xy 386.858206 -411.20214) (xy 386.848096 -411.202632)
			(xy 386.131816 -411.202632) (xy 386.121712 -411.202103) (xy 386.10304 -411.194376) (xy 386.088746 -411.180093)
			(xy 386.081005 -411.161427) (xy 386.080508 -411.151324) (xy 386.080508 -410.993844) (xy 386.080075 -410.984659)
			(xy 386.073577 -410.967475) (xy 386.067808 -410.960316) (xy 386.045928 -410.934664) (xy 386.007839 -410.879028)
			(xy 385.976689 -410.81923) (xy 385.952925 -410.756131) (xy 385.936891 -410.69064) (xy 385.928816 -410.623701)
			(xy 382.65077 -410.623701) (xy 382.642733 -410.690463) (xy 382.626761 -410.755844) (xy 382.603088 -410.818848)
			(xy 382.572054 -410.878571) (xy 382.534104 -410.934156) (xy 382.512316 -410.959808) (xy 382.506535 -410.966965)
			(xy 382.500011 -410.984146) (xy 382.499616 -410.993336) (xy 382.499616 -411.151324) (xy 382.499135 -411.161432)
			(xy 382.491392 -411.180108) (xy 382.477095 -411.194401) (xy 382.458416 -411.202138) (xy 382.448308 -411.202632)
			(xy 381.731774 -411.202632) (xy 381.721642 -411.202194) (xy 381.702915 -411.194453) (xy 381.688559 -411.180151)
			(xy 381.680745 -411.161454) (xy 381.680212 -411.151324) (xy 381.680212 -410.993336) (xy 381.679782 -410.984151)
			(xy 381.673282 -410.966967) (xy 381.667512 -410.959808) (xy 381.645709 -410.934168) (xy 381.607763 -410.87858)
			(xy 381.576732 -410.818854) (xy 381.553061 -410.755848) (xy 381.53709 -410.690464) (xy 381.529047 -410.623641)
			(xy 378.250984 -410.623641) (xy 378.250984 -410.623699) (xy 378.24291 -410.690636) (xy 378.226877 -410.756124)
			(xy 378.203116 -410.81922) (xy 378.171968 -410.879016) (xy 378.133882 -410.93465) (xy 378.11202 -410.960316)
			(xy 378.106236 -410.967471) (xy 378.099713 -410.984654) (xy 378.09932 -410.993844) (xy 378.09932 -411.151324)
			(xy 378.098835 -411.161432) (xy 378.091093 -411.180107) (xy 378.076797 -411.1944) (xy 378.05812 -411.202138)
			(xy 378.048012 -411.202632) (xy 377.331732 -411.202632) (xy 377.321615 -411.202159) (xy 377.302919 -411.194427)
			(xy 377.288604 -411.180128) (xy 377.280852 -411.16144) (xy 377.280424 -411.151324) (xy 377.280424 -410.993844)
			(xy 377.279987 -410.98466) (xy 377.273491 -410.967475) (xy 377.267724 -410.960316) (xy 377.245843 -410.934664)
			(xy 377.207754 -410.879028) (xy 377.176602 -410.81923) (xy 377.152838 -410.756132) (xy 377.136803 -410.690641)
			(xy 377.128728 -410.623701) (xy 347.450924 -410.623701) (xy 347.442889 -410.690461) (xy 347.426919 -410.755842)
			(xy 347.403249 -410.818845) (xy 347.372219 -410.878569) (xy 347.334274 -410.934156) (xy 347.312488 -410.959808)
			(xy 347.306704 -410.966962) (xy 347.300182 -410.984146) (xy 347.299788 -410.993336) (xy 347.299788 -411.151324)
			(xy 347.299398 -411.161481) (xy 347.291592 -411.180236) (xy 347.277186 -411.194559) (xy 347.258386 -411.202256)
			(xy 347.248226 -411.202632) (xy 346.531946 -411.202632) (xy 346.521819 -411.202135) (xy 346.503093 -411.194417)
			(xy 346.488735 -411.180133) (xy 346.480919 -411.161449) (xy 346.480384 -411.151324) (xy 346.480384 -410.993336)
			(xy 346.47996 -410.98415) (xy 346.473456 -410.966965) (xy 346.467684 -410.959808) (xy 346.445879 -410.934169)
			(xy 346.407928 -410.878582) (xy 346.376893 -410.818857) (xy 346.353219 -410.755851) (xy 346.337246 -410.690466)
			(xy 346.329202 -410.623642) (xy 343.051163 -410.623642) (xy 343.051163 -410.623699) (xy 343.043089 -410.690637)
			(xy 343.027055 -410.756125) (xy 343.003292 -410.819221) (xy 342.972143 -410.879017) (xy 342.934055 -410.934651)
			(xy 342.912192 -410.960316) (xy 342.906405 -410.967468) (xy 342.899885 -410.984653) (xy 342.899492 -410.993844)
			(xy 342.899492 -411.151324) (xy 342.899034 -411.161435) (xy 342.891287 -411.180116) (xy 342.876982 -411.19441)
			(xy 342.858296 -411.202142) (xy 342.848184 -411.202632) (xy 342.131904 -411.202632) (xy 342.121799 -411.202112)
			(xy 342.103128 -411.194382) (xy 342.088834 -411.180096) (xy 342.081093 -411.161428) (xy 342.080596 -411.151324)
			(xy 342.080596 -410.993844) (xy 342.080166 -410.984659) (xy 342.073666 -410.967474) (xy 342.067896 -410.960316)
			(xy 342.046016 -410.934664) (xy 342.007928 -410.879027) (xy 341.976779 -410.819229) (xy 341.953016 -410.756131)
			(xy 341.936981 -410.69064) (xy 341.928907 -410.6237) (xy 338.650837 -410.6237) (xy 338.642802 -410.69046)
			(xy 338.626832 -410.755841) (xy 338.603163 -410.818845) (xy 338.572134 -410.878568) (xy 338.534189 -410.934155)
			(xy 338.512404 -410.959808) (xy 338.506622 -410.966964) (xy 338.500098 -410.984146) (xy 338.499704 -410.993336)
			(xy 338.499704 -411.151324) (xy 338.499298 -411.161479) (xy 338.491495 -411.180231) (xy 338.477094 -411.194554)
			(xy 338.458299 -411.202253) (xy 338.448142 -411.202632) (xy 337.731862 -411.202632) (xy 337.721729 -411.202204)
			(xy 337.703002 -411.194458) (xy 337.688646 -411.180154) (xy 337.680833 -411.161455) (xy 337.6803 -411.151324)
			(xy 337.6803 -410.993336) (xy 337.679873 -410.984151) (xy 337.673371 -410.966966) (xy 337.6676 -410.959808)
			(xy 337.645798 -410.934168) (xy 337.607852 -410.878579) (xy 337.576822 -410.818853) (xy 337.553151 -410.755847)
			(xy 337.537181 -410.690464) (xy 337.529138 -410.623641) (xy 334.251075 -410.623641) (xy 334.251075 -410.623699)
			(xy 334.243001 -410.690636) (xy 334.226967 -410.756124) (xy 334.203205 -410.81922) (xy 334.172057 -410.879016)
			(xy 334.133971 -410.934651) (xy 334.112108 -410.960316) (xy 334.106323 -410.96747) (xy 334.099801 -410.984654)
			(xy 334.099408 -410.993844) (xy 334.099408 -411.151324) (xy 334.098935 -411.161433) (xy 334.091191 -411.180111)
			(xy 334.07689 -411.194404) (xy 334.05821 -411.20214) (xy 334.0481 -411.202632) (xy 333.33182 -411.202632)
			(xy 333.321716 -411.202099) (xy 333.303045 -411.194374) (xy 333.28875 -411.180092) (xy 333.281009 -411.161427)
			(xy 333.280512 -411.151324) (xy 333.280512 -410.993844) (xy 333.280078 -410.984659) (xy 333.273581 -410.967475)
			(xy 333.267812 -410.960316) (xy 333.245932 -410.934664) (xy 333.207843 -410.879028) (xy 333.176692 -410.81923)
			(xy 333.152928 -410.756131) (xy 333.136894 -410.69064) (xy 333.128819 -410.623701) (xy 326.525636 -410.623701)
			(xy 326.525636 -417.379404) (xy 326.525636 -417.533836) (xy 401.074128 -417.533836) (xy 401.074128 -417.366196)
			(xy 401.074128 -394.27912) (xy 414.451292 -394.27912) (xy 414.525968 -394.353542) (xy 414.525968 -397.823826)
			(xy 418.92899 -397.823826) (xy 418.928993 -397.756517) (xy 418.937042 -397.689691) (xy 418.95302 -397.624306)
			(xy 418.9767 -397.5613) (xy 419.00774 -397.501575) (xy 419.045697 -397.44599) (xy 419.067488 -397.420338)
			(xy 419.073292 -397.413198) (xy 419.079803 -397.396004) (xy 419.080188 -397.38681) (xy 419.080188 -396.893542)
			(xy 419.07976 -396.884357) (xy 419.073259 -396.867172) (xy 419.067488 -396.860014) (xy 419.045689 -396.834371)
			(xy 419.007737 -396.778784) (xy 418.976702 -396.71906) (xy 418.953027 -396.656054) (xy 418.937054 -396.59067)
			(xy 418.92901 -396.523846) (xy 418.92901 -396.456539) (xy 418.937056 -396.389715) (xy 418.953032 -396.324332)
			(xy 418.976708 -396.261327) (xy 419.007745 -396.201603) (xy 419.045698 -396.146018) (xy 419.067488 -396.120366)
			(xy 419.07328 -396.113218) (xy 419.079798 -396.09603) (xy 419.080188 -396.086838) (xy 419.080188 -395.92885)
			(xy 419.080606 -395.918675) (xy 419.088384 -395.899872) (xy 419.102772 -395.885484) (xy 419.121575 -395.877706)
			(xy 419.13175 -395.877288) (xy 419.84803 -395.877288) (xy 419.85821 -395.87764) (xy 419.877015 -395.885445)
			(xy 419.8914 -395.899852) (xy 419.899175 -395.91867) (xy 419.899592 -395.92885) (xy 419.899592 -396.086838)
			(xy 419.899986 -396.096027) (xy 419.906511 -396.113211) (xy 419.912292 -396.120366) (xy 419.934069 -396.146027)
			(xy 419.972016 -396.201613) (xy 420.003048 -396.261335) (xy 420.02672 -396.324339) (xy 420.042693 -396.389719)
			(xy 420.050737 -396.456541) (xy 420.050738 -396.523844) (xy 420.042695 -396.590666) (xy 420.026725 -396.656047)
			(xy 420.003054 -396.719051) (xy 419.972024 -396.778774) (xy 419.934078 -396.834361) (xy 419.912292 -396.860014)
			(xy 419.906506 -396.867167) (xy 419.899985 -396.884351) (xy 419.899592 -396.893542) (xy 419.899592 -397.38681)
			(xy 419.899999 -397.395998) (xy 419.906515 -397.413182) (xy 419.912292 -397.420338) (xy 419.934041 -397.446021)
			(xy 419.971989 -397.501604) (xy 420.00041 -397.556296) (xy 421.128654 -397.556296) (xy 421.13673 -397.489357)
			(xy 421.152765 -397.423869) (xy 421.17653 -397.360772) (xy 421.207681 -397.300976) (xy 421.245771 -397.245343)
			(xy 421.267636 -397.219678) (xy 421.273429 -397.21253) (xy 421.279945 -397.195342) (xy 421.280336 -397.18615)
			(xy 421.280336 -397.028924) (xy 421.280736 -397.018799) (xy 421.288483 -397.000089) (xy 421.302805 -396.985772)
			(xy 421.321518 -396.978032) (xy 421.331644 -396.977616) (xy 422.047924 -396.977616) (xy 422.058036 -396.978066)
			(xy 422.076718 -396.985814) (xy 422.091013 -397.000122) (xy 422.098744 -397.018811) (xy 422.099232 -397.028924)
			(xy 422.099232 -397.18615) (xy 422.099681 -397.195333) (xy 422.106169 -397.212517) (xy 422.111932 -397.219678)
			(xy 422.133805 -397.245336) (xy 422.171891 -397.300972) (xy 422.203039 -397.36077) (xy 422.226802 -397.423867)
			(xy 422.242835 -397.489357) (xy 422.25091 -397.556296) (xy 422.250909 -397.623719) (xy 422.242833 -397.690658)
			(xy 422.226797 -397.756147) (xy 422.203033 -397.819244) (xy 422.200615 -397.823885) (xy 423.328782 -397.823885)
			(xy 423.328786 -397.756458) (xy 423.336865 -397.689518) (xy 423.352904 -397.624027) (xy 423.376672 -397.560928)
			(xy 423.407826 -397.501131) (xy 423.445918 -397.445496) (xy 423.467784 -397.41983) (xy 423.473591 -397.412692)
			(xy 423.4801 -397.395496) (xy 423.480484 -397.386302) (xy 423.480484 -396.89405) (xy 423.480054 -396.884865)
			(xy 423.473554 -396.86768) (xy 423.467784 -396.860522) (xy 423.445911 -396.834865) (xy 423.407823 -396.779229)
			(xy 423.376674 -396.719431) (xy 423.352911 -396.656333) (xy 423.336877 -396.590843) (xy 423.328802 -396.523905)
			(xy 423.328803 -396.45648) (xy 423.33688 -396.389542) (xy 423.352916 -396.324052) (xy 423.37668 -396.260955)
			(xy 423.407831 -396.201159) (xy 423.44592 -396.145524) (xy 423.467784 -396.119858) (xy 423.473579 -396.112712)
			(xy 423.480095 -396.095522) (xy 423.480484 -396.08633) (xy 423.480484 -395.92885) (xy 423.480969 -395.918721)
			(xy 423.488688 -395.899993) (xy 423.502976 -395.885633) (xy 423.521666 -395.87782) (xy 423.531792 -395.877288)
			(xy 424.248072 -395.877288) (xy 424.258223 -395.877744) (xy 424.276972 -395.885528) (xy 424.291296 -395.899914)
			(xy 424.298999 -395.918697) (xy 424.29938 -395.92885) (xy 424.29938 -396.08633) (xy 424.29978 -396.095518)
			(xy 424.306301 -396.112702) (xy 424.31208 -396.119858) (xy 424.333935 -396.145531) (xy 424.372025 -396.201164)
			(xy 424.403177 -396.260959) (xy 424.426943 -396.324055) (xy 424.44298 -396.389543) (xy 424.451057 -396.456481)
			(xy 424.451058 -396.523904) (xy 424.442983 -396.590842) (xy 424.426948 -396.656331) (xy 424.403184 -396.719427)
			(xy 424.372033 -396.779223) (xy 424.333944 -396.834857) (xy 424.31208 -396.860522) (xy 424.306289 -396.867671)
			(xy 424.299772 -396.884859) (xy 424.29938 -396.89405) (xy 424.29938 -397.386302) (xy 424.299793 -397.395489)
			(xy 424.306305 -397.412673) (xy 424.31208 -397.41983) (xy 424.333907 -397.445526) (xy 424.371998 -397.501155)
			(xy 424.40076 -397.556356) (xy 425.528974 -397.556356) (xy 425.537017 -397.489534) (xy 425.552988 -397.424152)
			(xy 425.576659 -397.361148) (xy 425.607691 -397.301425) (xy 425.645637 -397.245838) (xy 425.667424 -397.220186)
			(xy 425.673212 -397.213035) (xy 425.679731 -397.195849) (xy 425.680124 -397.186658) (xy 425.680124 -397.028924)
			(xy 425.680542 -397.018768) (xy 425.688334 -397.000012) (xy 425.702732 -396.985687) (xy 425.721528 -396.97799)
			(xy 425.731686 -396.977616) (xy 426.447966 -396.977616) (xy 426.458088 -396.978154) (xy 426.476803 -396.985866)
			(xy 426.49116 -397.000137) (xy 426.498984 -397.018806) (xy 426.499528 -397.028924) (xy 426.499528 -397.186658)
			(xy 426.499952 -397.195844) (xy 426.506456 -397.213029) (xy 426.512228 -397.220186) (xy 426.534026 -397.24583)
			(xy 426.571977 -397.301417) (xy 426.603012 -397.361141) (xy 426.626685 -397.424147) (xy 426.642659 -397.48953)
			(xy 426.650703 -397.556354) (xy 426.650702 -397.623661) (xy 426.642656 -397.690485) (xy 426.626681 -397.755868)
			(xy 426.603006 -397.818873) (xy 426.600432 -397.823826) (xy 427.729077 -397.823826) (xy 427.729081 -397.756517)
			(xy 427.737129 -397.689691) (xy 427.753107 -397.624307) (xy 427.776786 -397.5613) (xy 427.807825 -397.501576)
			(xy 427.845781 -397.44599) (xy 427.867572 -397.420338) (xy 427.873386 -397.413206) (xy 427.879888 -397.396005)
			(xy 427.880272 -397.38681) (xy 427.880272 -396.893542) (xy 427.879848 -396.884356) (xy 427.873344 -396.867171)
			(xy 427.867572 -396.860014) (xy 427.845774 -396.83437) (xy 427.807823 -396.778783) (xy 427.776788 -396.719059)
			(xy 427.753115 -396.656053) (xy 427.737141 -396.59067) (xy 427.729097 -396.523846) (xy 427.729098 -396.456539)
			(xy 427.737144 -396.389715) (xy 427.753119 -396.324332) (xy 427.776794 -396.261327) (xy 427.807831 -396.201604)
			(xy 427.845783 -396.146018) (xy 427.867572 -396.120366) (xy 427.873374 -396.113225) (xy 427.879883 -396.096031)
			(xy 427.880272 -396.086838) (xy 427.880272 -395.92885) (xy 427.880706 -395.918677) (xy 427.88848 -395.899877)
			(xy 427.902864 -395.885489) (xy 427.921662 -395.877709) (xy 427.931834 -395.877288) (xy 428.648114 -395.877288)
			(xy 428.658293 -395.877654) (xy 428.677097 -395.885453) (xy 428.691483 -395.899857) (xy 428.699259 -395.918671)
			(xy 428.699676 -395.92885) (xy 428.699676 -396.086838) (xy 428.700073 -396.096026) (xy 428.706596 -396.11321)
			(xy 428.712376 -396.120366) (xy 428.734154 -396.146026) (xy 428.772102 -396.201612) (xy 428.803135 -396.261335)
			(xy 428.826807 -396.324338) (xy 428.84278 -396.389719) (xy 428.850825 -396.45654) (xy 428.850826 -396.523844)
			(xy 428.842783 -396.590666) (xy 428.826812 -396.656048) (xy 428.803141 -396.719052) (xy 428.772109 -396.778775)
			(xy 428.734163 -396.834362) (xy 428.712376 -396.860014) (xy 428.706588 -396.867165) (xy 428.700069 -396.884351)
			(xy 428.699676 -396.893542) (xy 428.699676 -397.38681) (xy 428.700087 -397.395997) (xy 428.7066 -397.413181)
			(xy 428.712376 -397.420338) (xy 428.734126 -397.446021) (xy 428.772075 -397.501604) (xy 428.800497 -397.556296)
			(xy 429.928742 -397.556296) (xy 429.936817 -397.489358) (xy 429.952852 -397.423869) (xy 429.976616 -397.360773)
			(xy 430.007767 -397.300977) (xy 430.045856 -397.245343) (xy 430.06772 -397.219678) (xy 430.073511 -397.212529)
			(xy 430.080028 -397.195341) (xy 430.08042 -397.18615) (xy 430.08042 -397.028924) (xy 430.080836 -397.018801)
			(xy 430.08858 -397.000094) (xy 430.102897 -396.985778) (xy 430.121605 -396.978035) (xy 430.131728 -396.977616)
			(xy 430.848008 -396.977616) (xy 430.858133 -396.97801) (xy 430.87684 -396.985764) (xy 430.891154 -397.000087)
			(xy 430.898896 -397.018799) (xy 430.899316 -397.028924) (xy 430.899316 -397.18615) (xy 430.899746 -397.195335)
			(xy 430.906246 -397.21252) (xy 430.912016 -397.219678) (xy 430.933889 -397.245335) (xy 430.971977 -397.300971)
			(xy 431.003126 -397.360769) (xy 431.026889 -397.423867) (xy 431.042923 -397.489357) (xy 431.050998 -397.556295)
			(xy 431.050997 -397.62372) (xy 431.04292 -397.690658) (xy 431.026884 -397.756148) (xy 431.00312 -397.819245)
			(xy 431.000734 -397.823826) (xy 432.128868 -397.823826) (xy 432.128872 -397.756517) (xy 432.13692 -397.689692)
			(xy 432.152898 -397.624307) (xy 432.176576 -397.561301) (xy 432.207614 -397.501576) (xy 432.245569 -397.44599)
			(xy 432.26736 -397.420338) (xy 432.273173 -397.413205) (xy 432.279676 -397.396005) (xy 432.28006 -397.38681)
			(xy 432.28006 -396.893542) (xy 432.279616 -396.884359) (xy 432.273125 -396.867175) (xy 432.26736 -396.860014)
			(xy 432.245562 -396.83437) (xy 432.207612 -396.778783) (xy 432.176578 -396.719058) (xy 432.152905 -396.656053)
			(xy 432.136932 -396.590669) (xy 432.128888 -396.523846) (xy 432.128889 -396.456539) (xy 432.136935 -396.389716)
			(xy 432.152909 -396.324333) (xy 432.176584 -396.261328) (xy 432.20762 -396.201604) (xy 432.245571 -396.146018)
			(xy 432.26736 -396.120366) (xy 432.273161 -396.113224) (xy 432.279671 -396.096031) (xy 432.28006 -396.086838)
			(xy 432.28006 -395.92885) (xy 432.280505 -395.918679) (xy 432.288278 -395.899881) (xy 432.302658 -395.885494)
			(xy 432.321451 -395.877711) (xy 432.331622 -395.877288) (xy 433.047902 -395.877288) (xy 433.05808 -395.877663)
			(xy 433.076884 -395.885458) (xy 433.091271 -395.899859) (xy 433.099047 -395.918672) (xy 433.099464 -395.92885)
			(xy 433.099464 -396.086838) (xy 433.099864 -396.096026) (xy 433.106386 -396.11321) (xy 433.112164 -396.120366)
			(xy 433.133942 -396.146026) (xy 433.171891 -396.201612) (xy 433.202924 -396.261334) (xy 433.226598 -396.324337)
			(xy 433.242571 -396.389719) (xy 433.250616 -396.45654) (xy 433.250617 -396.523845) (xy 433.242574 -396.590666)
			(xy 433.226602 -396.656048) (xy 433.202931 -396.719052) (xy 433.171899 -396.778776) (xy 433.133951 -396.834362)
			(xy 433.112164 -396.860014) (xy 433.106374 -396.867164) (xy 433.099856 -396.884351) (xy 433.099464 -396.893542)
			(xy 433.099464 -397.38681) (xy 433.099877 -397.395997) (xy 433.10639 -397.413181) (xy 433.112164 -397.420338)
			(xy 433.133914 -397.446021) (xy 433.171864 -397.501603) (xy 433.200318 -397.556356) (xy 434.329062 -397.556356)
			(xy 434.337105 -397.489534) (xy 434.353075 -397.424153) (xy 434.376746 -397.361149) (xy 434.407776 -397.301426)
			(xy 434.445722 -397.245839) (xy 434.467508 -397.220186) (xy 434.473294 -397.213033) (xy 434.479815 -397.195849)
			(xy 434.480208 -397.186658) (xy 434.480208 -397.028924) (xy 434.480641 -397.01877) (xy 434.48843 -397.000017)
			(xy 434.502824 -396.985692) (xy 434.521614 -396.977993) (xy 434.53177 -396.977616) (xy 435.24805 -396.977616)
			(xy 435.258171 -396.978167) (xy 435.276886 -396.985874) (xy 435.291243 -397.00014) (xy 435.299068 -397.018807)
			(xy 435.299612 -397.028924) (xy 435.299612 -397.186658) (xy 435.30004 -397.195843) (xy 435.306541 -397.213028)
			(xy 435.312312 -397.220186) (xy 435.334111 -397.245829) (xy 435.372063 -397.301416) (xy 435.403098 -397.36114)
			(xy 435.426773 -397.424146) (xy 435.442746 -397.48953) (xy 435.45079 -397.556354) (xy 435.45079 -397.623661)
			(xy 435.442744 -397.690485) (xy 435.426768 -397.755868) (xy 435.403092 -397.818873) (xy 435.372055 -397.878597)
			(xy 435.334102 -397.934182) (xy 435.312312 -397.959834) (xy 435.30652 -397.966982) (xy 435.300002 -397.98417)
			(xy 435.299612 -397.993362) (xy 435.299612 -398.100042) (xy 459.541382 -398.100042) (xy 459.545364 -397.972056)
			(xy 459.557296 -397.844565) (xy 459.57713 -397.718062) (xy 459.604791 -397.593037) (xy 459.640171 -397.469974)
			(xy 459.683133 -397.349348) (xy 459.733511 -397.231627) (xy 459.791111 -397.117265) (xy 459.855709 -397.006706)
			(xy 459.927056 -396.900376) (xy 460.004875 -396.798688) (xy 460.088865 -396.702034) (xy 460.178702 -396.610789)
			(xy 460.274038 -396.525306) (xy 460.374503 -396.445915) (xy 460.479711 -396.372923) (xy 460.589252 -396.306614)
			(xy 460.702704 -396.247243) (xy 460.819628 -396.195039) (xy 460.939571 -396.150206) (xy 461.062069 -396.112917)
			(xy 461.186649 -396.083315) (xy 461.312827 -396.061516) (xy 461.440117 -396.047603) (xy 461.568026 -396.041631)
			(xy 461.696059 -396.043622) (xy 461.82372 -396.05357) (xy 461.950516 -396.071434) (xy 462.075955 -396.097147)
			(xy 462.199554 -396.130609) (xy 462.320833 -396.17169) (xy 462.439324 -396.220232) (xy 462.554568 -396.276046)
			(xy 462.666118 -396.338917) (xy 462.773545 -396.408601) (xy 462.876431 -396.484829) (xy 462.974379 -396.567306)
			(xy 463.06701 -396.655713) (xy 463.153966 -396.749708) (xy 463.23491 -396.848927) (xy 463.309529 -396.952986)
			(xy 463.377534 -397.061483) (xy 463.438662 -397.173998) (xy 463.492677 -397.290096) (xy 463.53937 -397.409327)
			(xy 463.57856 -397.531231) (xy 463.610096 -397.655335) (xy 463.633855 -397.781159) (xy 463.649745 -397.908218)
			(xy 463.657706 -398.036018) (xy 463.658204 -398.100042) (xy 463.657706 -398.164066) (xy 463.649745 -398.291866)
			(xy 463.633855 -398.418925) (xy 463.610096 -398.544749) (xy 463.57856 -398.668853) (xy 463.53937 -398.790757)
			(xy 463.492677 -398.909988) (xy 463.438662 -399.026086) (xy 463.377534 -399.138601) (xy 463.309529 -399.247098)
			(xy 463.23491 -399.351157) (xy 463.153966 -399.450376) (xy 463.06701 -399.544371) (xy 462.974379 -399.632778)
			(xy 462.876431 -399.715255) (xy 462.773545 -399.791483) (xy 462.666118 -399.861167) (xy 462.554568 -399.924038)
			(xy 462.439324 -399.979852) (xy 462.320833 -400.028394) (xy 462.199554 -400.069475) (xy 462.075955 -400.102937)
			(xy 461.950516 -400.12865) (xy 461.82372 -400.146514) (xy 461.696059 -400.156462) (xy 461.568026 -400.158453)
			(xy 461.440117 -400.152481) (xy 461.312827 -400.138568) (xy 461.186649 -400.116769) (xy 461.062069 -400.087167)
			(xy 460.939571 -400.049878) (xy 460.819628 -400.005045) (xy 460.702704 -399.952841) (xy 460.589252 -399.89347)
			(xy 460.479711 -399.827161) (xy 460.374503 -399.754169) (xy 460.274038 -399.674778) (xy 460.178702 -399.589295)
			(xy 460.088865 -399.49805) (xy 460.004875 -399.401396) (xy 459.927056 -399.299708) (xy 459.855709 -399.193378)
			(xy 459.791111 -399.082819) (xy 459.733511 -398.968457) (xy 459.683133 -398.850736) (xy 459.640171 -398.73011)
			(xy 459.604791 -398.607047) (xy 459.57713 -398.482022) (xy 459.557296 -398.355519) (xy 459.545364 -398.228028)
			(xy 459.541382 -398.100042) (xy 435.299612 -398.100042) (xy 435.299612 -398.486884) (xy 435.300027 -398.496071)
			(xy 435.306537 -398.513255) (xy 435.312312 -398.520412) (xy 435.334137 -398.546034) (xy 435.372087 -398.601624)
			(xy 435.403122 -398.661351) (xy 435.426795 -398.72436) (xy 435.442767 -398.789746) (xy 435.450809 -398.856573)
			(xy 435.450805 -398.923881) (xy 435.442757 -398.990707) (xy 435.426779 -399.056092) (xy 435.4031 -399.119098)
			(xy 435.37206 -399.178823) (xy 435.334103 -399.234408) (xy 435.312312 -399.26006) (xy 435.306509 -399.267201)
			(xy 435.299998 -399.284395) (xy 435.299612 -399.293588) (xy 435.299612 -399.451576) (xy 435.299159 -399.461727)
			(xy 435.291374 -399.480477) (xy 435.276987 -399.494801) (xy 435.258203 -399.502503) (xy 435.24805 -399.502884)
			(xy 434.53177 -399.502884) (xy 434.521644 -399.502399) (xy 434.502927 -399.494666) (xy 434.488573 -399.480379)
			(xy 434.48075 -399.461699) (xy 434.480208 -399.451576) (xy 434.480208 -399.293588) (xy 434.479802 -399.2844)
			(xy 434.473285 -399.267216) (xy 434.467508 -399.26006) (xy 434.445757 -399.234378) (xy 434.407809 -399.178795)
			(xy 434.376776 -399.119076) (xy 434.353102 -399.056075) (xy 434.337128 -398.990697) (xy 434.329081 -398.923878)
			(xy 434.329078 -398.856576) (xy 434.337118 -398.789757) (xy 434.353086 -398.724377) (xy 434.376753 -398.661374)
			(xy 434.407781 -398.601651) (xy 434.445723 -398.546064) (xy 434.467508 -398.520412) (xy 434.473325 -398.513282)
			(xy 434.479827 -398.49608) (xy 434.480208 -398.486884) (xy 434.480208 -397.993362) (xy 434.479814 -397.984173)
			(xy 434.473289 -397.966989) (xy 434.467508 -397.959834) (xy 434.445731 -397.934173) (xy 434.407784 -397.878587)
			(xy 434.376752 -397.818865) (xy 434.35308 -397.755861) (xy 434.337107 -397.690481) (xy 434.329063 -397.623659)
			(xy 434.329062 -397.556356) (xy 433.200318 -397.556356) (xy 433.202899 -397.561322) (xy 433.226573 -397.624323)
			(xy 433.242549 -397.689701) (xy 433.250596 -397.75652) (xy 433.250599 -397.823822) (xy 433.242559 -397.890642)
			(xy 433.22659 -397.956022) (xy 433.202922 -398.019025) (xy 433.171893 -398.078748) (xy 433.133949 -398.134334)
			(xy 433.112164 -398.159986) (xy 433.106344 -398.167114) (xy 433.099844 -398.184318) (xy 433.099464 -398.193514)
			(xy 433.099464 -398.351502) (xy 433.098968 -398.36166) (xy 433.091194 -398.380428) (xy 433.076828 -398.394794)
			(xy 433.05806 -398.402568) (xy 433.047902 -398.403064) (xy 432.331622 -398.403064) (xy 432.321452 -398.402618)
			(xy 432.302658 -398.394841) (xy 432.288273 -398.380462) (xy 432.280487 -398.361672) (xy 432.28006 -398.351502)
			(xy 432.28006 -398.193514) (xy 432.27963 -398.184329) (xy 432.273129 -398.167145) (xy 432.26736 -398.159986)
			(xy 432.245534 -398.134365) (xy 432.207585 -398.078775) (xy 432.176552 -398.019047) (xy 432.152881 -397.956038)
			(xy 432.13691 -397.890652) (xy 432.128868 -397.823826) (xy 431.000734 -397.823826) (xy 430.971969 -397.879041)
			(xy 430.93388 -397.934676) (xy 430.912016 -397.960342) (xy 430.906221 -397.967488) (xy 430.899705 -397.984678)
			(xy 430.899316 -397.99387) (xy 430.899316 -398.486376) (xy 430.899734 -398.495562) (xy 430.906242 -398.512747)
			(xy 430.912016 -398.519904) (xy 430.933915 -398.54554) (xy 430.972001 -398.601179) (xy 431.00315 -398.66098)
			(xy 431.026911 -398.72408) (xy 431.042944 -398.789573) (xy 431.051016 -398.856514) (xy 431.051013 -398.92394)
			(xy 431.042934 -398.990881) (xy 431.026895 -399.056371) (xy 431.003128 -399.11947) (xy 430.971974 -399.179267)
			(xy 430.933882 -399.234902) (xy 430.912016 -399.260568) (xy 430.90621 -399.267707) (xy 430.8997 -399.284902)
			(xy 430.899316 -399.294096) (xy 430.899316 -399.451576) (xy 430.898865 -399.461695) (xy 430.891128 -399.480395)
			(xy 430.876822 -399.49471) (xy 430.858127 -399.502459) (xy 430.848008 -399.502884) (xy 430.131728 -399.502884)
			(xy 430.121605 -399.502461) (xy 430.102899 -399.494719) (xy 430.088583 -399.480404) (xy 430.08084 -399.461699)
			(xy 430.08042 -399.451576) (xy 430.08042 -399.294096) (xy 430.080008 -399.284909) (xy 430.073495 -399.267725)
			(xy 430.06772 -399.260568) (xy 430.045891 -399.234874) (xy 430.0078 -399.179244) (xy 429.976646 -399.119452)
			(xy 429.952879 -399.056359) (xy 429.936841 -398.990873) (xy 429.928761 -398.923938) (xy 429.928758 -398.856516)
			(xy 429.936831 -398.78958) (xy 429.952863 -398.724093) (xy 429.976624 -398.660997) (xy 430.007772 -398.601202)
			(xy 430.045857 -398.545569) (xy 430.06772 -398.519904) (xy 430.0735 -398.512747) (xy 430.080024 -398.495565)
			(xy 430.08042 -398.486376) (xy 430.08042 -397.99387) (xy 430.08002 -397.984682) (xy 430.073499 -397.967498)
			(xy 430.06772 -397.960342) (xy 430.045865 -397.934669) (xy 430.007775 -397.879036) (xy 429.976623 -397.819241)
			(xy 429.952857 -397.756145) (xy 429.93682 -397.690657) (xy 429.928743 -397.623719) (xy 429.928742 -397.556296)
			(xy 428.800497 -397.556296) (xy 428.803109 -397.561323) (xy 428.826783 -397.624323) (xy 428.842758 -397.689702)
			(xy 428.850805 -397.756521) (xy 428.850808 -397.823822) (xy 428.842768 -397.890642) (xy 428.8268 -397.956022)
			(xy 428.803132 -398.019025) (xy 428.772104 -398.078747) (xy 428.734161 -398.134333) (xy 428.712376 -398.159986)
			(xy 428.706558 -398.167116) (xy 428.700057 -398.184318) (xy 428.699676 -398.193514) (xy 428.699676 -398.351502)
			(xy 428.699169 -398.361658) (xy 428.691396 -398.380425) (xy 428.677035 -398.394789) (xy 428.65827 -398.402566)
			(xy 428.648114 -398.403064) (xy 427.931834 -398.403064) (xy 427.921665 -398.402608) (xy 427.902871 -398.394835)
			(xy 427.888485 -398.380459) (xy 427.880699 -398.361671) (xy 427.880272 -398.351502) (xy 427.880272 -398.193514)
			(xy 427.879861 -398.184327) (xy 427.873349 -398.167142) (xy 427.867572 -398.159986) (xy 427.845746 -398.134365)
			(xy 427.807796 -398.078775) (xy 427.776762 -398.019047) (xy 427.75309 -397.956039) (xy 427.737119 -397.890652)
			(xy 427.729077 -397.823826) (xy 426.600432 -397.823826) (xy 426.571969 -397.878596) (xy 426.534017 -397.934182)
			(xy 426.512228 -397.959834) (xy 426.506426 -397.966975) (xy 426.499917 -397.984169) (xy 426.499528 -397.993362)
			(xy 426.499528 -398.486884) (xy 426.499939 -398.496071) (xy 426.506451 -398.513256) (xy 426.512228 -398.520412)
			(xy 426.534052 -398.546034) (xy 426.572002 -398.601624) (xy 426.603036 -398.661352) (xy 426.626708 -398.72436)
			(xy 426.64268 -398.789746) (xy 426.650721 -398.856573) (xy 426.650718 -398.923881) (xy 426.64267 -398.990707)
			(xy 426.626692 -399.056092) (xy 426.603014 -399.119098) (xy 426.571974 -399.178822) (xy 426.534019 -399.234408)
			(xy 426.512228 -399.26006) (xy 426.506415 -399.267193) (xy 426.499912 -399.284393) (xy 426.499528 -399.293588)
			(xy 426.499528 -399.451576) (xy 426.499059 -399.461725) (xy 426.491277 -399.480472) (xy 426.476895 -399.494795)
			(xy 426.458117 -399.502501) (xy 426.447966 -399.502884) (xy 425.731686 -399.502884) (xy 425.721561 -399.502385)
			(xy 425.702845 -399.494657) (xy 425.68849 -399.480375) (xy 425.680667 -399.461698) (xy 425.680124 -399.451576)
			(xy 425.680124 -399.293588) (xy 425.679714 -399.284401) (xy 425.6732 -399.267217) (xy 425.667424 -399.26006)
			(xy 425.645672 -399.234378) (xy 425.607723 -399.178796) (xy 425.576689 -399.119076) (xy 425.553015 -399.056076)
			(xy 425.53704 -398.990697) (xy 425.528994 -398.923878) (xy 425.52899 -398.856576) (xy 425.537031 -398.789756)
			(xy 425.552999 -398.724376) (xy 425.576667 -398.661373) (xy 425.607696 -398.601651) (xy 425.645639 -398.546065)
			(xy 425.667424 -398.520412) (xy 425.673243 -398.513283) (xy 425.679744 -398.49608) (xy 425.680124 -398.486884)
			(xy 425.680124 -397.993362) (xy 425.679727 -397.984174) (xy 425.673204 -397.96699) (xy 425.667424 -397.959834)
			(xy 425.645646 -397.934174) (xy 425.607698 -397.878588) (xy 425.576665 -397.818865) (xy 425.552993 -397.755862)
			(xy 425.53702 -397.690481) (xy 425.528975 -397.62366) (xy 425.528974 -397.556356) (xy 424.40076 -397.556356)
			(xy 424.403152 -397.560947) (xy 424.426919 -397.62404) (xy 424.442958 -397.689526) (xy 424.451037 -397.756461)
			(xy 424.451041 -397.823882) (xy 424.442968 -397.890818) (xy 424.426936 -397.956305) (xy 424.403175 -398.019401)
			(xy 424.372028 -398.079196) (xy 424.333942 -398.134829) (xy 424.31208 -398.160494) (xy 424.306301 -398.167652)
			(xy 424.299777 -398.184833) (xy 424.29938 -398.194022) (xy 424.29938 -398.351502) (xy 424.298876 -398.361626)
			(xy 424.291151 -398.380344) (xy 424.27687 -398.394699) (xy 424.258194 -398.402522) (xy 424.248072 -398.403064)
			(xy 423.531792 -398.403064) (xy 423.521633 -398.402684) (xy 423.502873 -398.394879) (xy 423.488549 -398.380469)
			(xy 423.480856 -398.361663) (xy 423.480484 -398.351502) (xy 423.480484 -398.194022) (xy 423.480067 -398.184835)
			(xy 423.473558 -398.167651) (xy 423.467784 -398.160494) (xy 423.445883 -398.134859) (xy 423.407797 -398.07922)
			(xy 423.376649 -398.019419) (xy 423.352887 -397.956319) (xy 423.336855 -397.890826) (xy 423.328782 -397.823885)
			(xy 422.200615 -397.823885) (xy 422.171883 -397.879041) (xy 422.133795 -397.934676) (xy 422.111932 -397.960342)
			(xy 422.106127 -397.967481) (xy 422.099619 -397.984676) (xy 422.099232 -397.99387) (xy 422.099232 -398.486376)
			(xy 422.099669 -398.49556) (xy 422.106166 -398.512744) (xy 422.111932 -398.519904) (xy 422.13383 -398.545541)
			(xy 422.171916 -398.60118) (xy 422.203063 -398.66098) (xy 422.226824 -398.724081) (xy 422.242856 -398.789573)
			(xy 422.250928 -398.856514) (xy 422.250925 -398.92394) (xy 422.242846 -398.99088) (xy 422.226808 -399.056371)
			(xy 422.203041 -399.119469) (xy 422.171888 -399.179266) (xy 422.133797 -399.234902) (xy 422.111932 -399.260568)
			(xy 422.106116 -399.267699) (xy 422.099615 -399.284901) (xy 422.099232 -399.294096) (xy 422.099232 -399.451576)
			(xy 422.098696 -399.461679) (xy 422.090972 -399.480351) (xy 422.076691 -399.494645) (xy 422.058027 -399.502387)
			(xy 422.047924 -399.502884) (xy 421.331644 -399.502884) (xy 421.321522 -399.502447) (xy 421.302817 -399.494711)
			(xy 421.2885 -399.4804) (xy 421.280756 -399.461697) (xy 421.280336 -399.451576) (xy 421.280336 -399.294096)
			(xy 421.27992 -399.28491) (xy 421.27341 -399.267726) (xy 421.267636 -399.260568) (xy 421.245806 -399.234874)
			(xy 421.207714 -399.179245) (xy 421.17656 -399.119453) (xy 421.152792 -399.056359) (xy 421.136753 -398.990873)
			(xy 421.128674 -398.923938) (xy 421.12867 -398.856516) (xy 421.136743 -398.78958) (xy 421.152776 -398.724092)
			(xy 421.176538 -398.660997) (xy 421.207686 -398.601202) (xy 421.245773 -398.545569) (xy 421.267636 -398.519904)
			(xy 421.273418 -398.512749) (xy 421.27994 -398.495566) (xy 421.280336 -398.486376) (xy 421.280336 -397.99387)
			(xy 421.279932 -397.984682) (xy 421.273413 -397.967498) (xy 421.267636 -397.960342) (xy 421.245781 -397.934669)
			(xy 421.207689 -397.879037) (xy 421.176536 -397.819242) (xy 421.15277 -397.756146) (xy 421.136732 -397.690657)
			(xy 421.128655 -397.623719) (xy 421.128654 -397.556296) (xy 420.00041 -397.556296) (xy 420.003023 -397.561324)
			(xy 420.026696 -397.624324) (xy 420.042671 -397.689702) (xy 420.050718 -397.756521) (xy 420.050721 -397.823822)
			(xy 420.042681 -397.890642) (xy 420.026713 -397.956021) (xy 420.003046 -398.019024) (xy 419.972019 -398.078747)
			(xy 419.934077 -398.134334) (xy 419.912292 -398.159986) (xy 419.906475 -398.167117) (xy 419.899973 -398.184318)
			(xy 419.899592 -398.193514) (xy 419.899592 -398.351502) (xy 419.899069 -398.361656) (xy 419.891299 -398.38042)
			(xy 419.876943 -398.394784) (xy 419.858184 -398.402563) (xy 419.84803 -398.403064) (xy 419.13175 -398.403064)
			(xy 419.121582 -398.402595) (xy 419.102789 -398.394827) (xy 419.088402 -398.380455) (xy 419.080615 -398.36167)
			(xy 419.080188 -398.351502) (xy 419.080188 -398.193514) (xy 419.079774 -398.184327) (xy 419.073263 -398.167143)
			(xy 419.067488 -398.159986) (xy 419.045661 -398.134365) (xy 419.007711 -398.078775) (xy 418.976676 -398.019048)
			(xy 418.953004 -397.956039) (xy 418.937032 -397.890653) (xy 418.92899 -397.823826) (xy 414.525968 -397.823826)
			(xy 414.525968 -401.723737) (xy 418.929001 -401.723737) (xy 418.929003 -401.65643) (xy 418.93705 -401.589605)
			(xy 418.953027 -401.524221) (xy 418.976704 -401.461215) (xy 419.007743 -401.401491) (xy 419.045697 -401.345906)
			(xy 419.067488 -401.320254) (xy 419.073285 -401.313109) (xy 419.0798 -401.295918) (xy 419.080188 -401.286726)
			(xy 419.080188 -400.793458) (xy 419.079801 -400.784268) (xy 419.073272 -400.767084) (xy 419.067488 -400.75993)
			(xy 419.045705 -400.734274) (xy 419.007752 -400.678689) (xy 418.976716 -400.618966) (xy 418.953041 -400.555962)
			(xy 418.937066 -400.49058) (xy 418.929021 -400.423757) (xy 418.92902 -400.356452) (xy 418.937065 -400.289629)
			(xy 418.953038 -400.224246) (xy 418.976713 -400.161242) (xy 419.007748 -400.101519) (xy 419.045699 -400.045933)
			(xy 419.067488 -400.020282) (xy 419.073273 -400.013129) (xy 419.079795 -399.995944) (xy 419.080188 -399.986754)
			(xy 419.080188 -399.828766) (xy 419.080537 -399.818586) (xy 419.088343 -399.799781) (xy 419.102752 -399.785395)
			(xy 419.121569 -399.777621) (xy 419.13175 -399.777204) (xy 419.84803 -399.777204) (xy 419.858186 -399.777708)
			(xy 419.876949 -399.785486) (xy 419.891312 -399.799848) (xy 419.899091 -399.818611) (xy 419.899592 -399.828766)
			(xy 419.899592 -399.986754) (xy 419.900026 -399.995939) (xy 419.906523 -400.013123) (xy 419.912292 -400.020282)
			(xy 419.934085 -400.04593) (xy 419.972031 -400.101518) (xy 420.003063 -400.161242) (xy 420.026734 -400.224247)
			(xy 420.042705 -400.289629) (xy 420.050749 -400.356452) (xy 420.050748 -400.423757) (xy 420.042704 -400.490579)
			(xy 420.026731 -400.555962) (xy 420.003059 -400.618966) (xy 419.972027 -400.67869) (xy 419.934079 -400.734277)
			(xy 419.912292 -400.75993) (xy 419.906499 -400.767078) (xy 419.899983 -400.784266) (xy 419.899592 -400.793458)
			(xy 419.899592 -401.286726) (xy 419.899991 -401.295914) (xy 419.906513 -401.313099) (xy 419.912292 -401.320254)
			(xy 419.934057 -401.345924) (xy 419.972005 -401.401509) (xy 420.003037 -401.46123) (xy 420.02671 -401.524232)
			(xy 420.042683 -401.589612) (xy 420.050729 -401.656432) (xy 420.050731 -401.723735) (xy 420.042689 -401.790555)
			(xy 420.02672 -401.855936) (xy 420.003051 -401.918939) (xy 419.972022 -401.978663) (xy 419.934077 -402.034249)
			(xy 419.912292 -402.059902) (xy 419.906511 -402.067058) (xy 419.899987 -402.08424) (xy 419.899592 -402.09343)
			(xy 419.899592 -402.251418) (xy 419.899082 -402.261573) (xy 419.891308 -402.280337) (xy 419.876947 -402.294701)
			(xy 419.858185 -402.30248) (xy 419.84803 -402.30298) (xy 419.13175 -402.30298) (xy 419.121584 -402.302496)
			(xy 419.102794 -402.29473) (xy 419.088408 -402.280363) (xy 419.080618 -402.261584) (xy 419.080188 -402.251418)
			(xy 419.080188 -402.09343) (xy 419.079766 -402.084244) (xy 419.073261 -402.067059) (xy 419.067488 -402.059902)
			(xy 419.045677 -402.034268) (xy 419.007726 -401.97868) (xy 418.976691 -401.918955) (xy 418.953017 -401.855948)
			(xy 418.937044 -401.790563) (xy 418.929001 -401.723737) (xy 414.525968 -401.723737) (xy 414.525968 -402.823878)
			(xy 421.128614 -402.823878) (xy 421.128619 -402.75645) (xy 421.1367 -402.689508) (xy 421.152742 -402.624016)
			(xy 421.176513 -402.560916) (xy 421.207671 -402.501119) (xy 421.245768 -402.445485) (xy 421.267636 -402.41982)
			(xy 421.273454 -402.41269) (xy 421.279955 -402.395488) (xy 421.280336 -402.386292) (xy 421.280336 -401.89404)
			(xy 421.279898 -401.884856) (xy 421.273403 -401.867672) (xy 421.267636 -401.860512) (xy 421.245751 -401.834864)
			(xy 421.207661 -401.779227) (xy 421.176509 -401.719429) (xy 421.152744 -401.65633) (xy 421.136709 -401.590839)
			(xy 421.128634 -401.523898) (xy 421.128636 -401.456472) (xy 421.136714 -401.389532) (xy 421.152753 -401.324041)
			(xy 421.176521 -401.260943) (xy 421.207676 -401.201147) (xy 421.24577 -401.145513) (xy 421.267636 -401.119848)
			(xy 421.273442 -401.112709) (xy 421.27995 -401.095514) (xy 421.280336 -401.08632) (xy 421.280336 -400.92884)
			(xy 421.28075 -400.918716) (xy 421.288491 -400.900006) (xy 421.302809 -400.885689) (xy 421.32152 -400.877949)
			(xy 421.331644 -400.877532) (xy 422.047924 -400.877532) (xy 422.058052 -400.877897) (xy 422.076762 -400.885659)
			(xy 422.091077 -400.899991) (xy 422.098816 -400.918711) (xy 422.099232 -400.92884) (xy 422.099232 -401.08632)
			(xy 422.099648 -401.095506) (xy 422.106159 -401.11269) (xy 422.111932 -401.119848) (xy 422.133775 -401.14553)
			(xy 422.171862 -401.201163) (xy 422.203012 -401.260957) (xy 422.226776 -401.324052) (xy 422.242812 -401.389538)
			(xy 422.250889 -401.456474) (xy 422.250891 -401.523896) (xy 422.242817 -401.590832) (xy 422.226785 -401.65632)
			(xy 422.203024 -401.719415) (xy 422.200742 -401.723796) (xy 423.328794 -401.723796) (xy 423.328796 -401.656371)
			(xy 423.336873 -401.589431) (xy 423.352911 -401.523941) (xy 423.376677 -401.460844) (xy 423.407829 -401.401047)
			(xy 423.445919 -401.345412) (xy 423.467784 -401.319746) (xy 423.473584 -401.312603) (xy 423.480097 -401.295411)
			(xy 423.480484 -401.286218) (xy 423.480484 -400.793966) (xy 423.480094 -400.784777) (xy 423.473566 -400.767592)
			(xy 423.467784 -400.760438) (xy 423.445926 -400.734768) (xy 423.407839 -400.679133) (xy 423.376689 -400.619338)
			(xy 423.352925 -400.556242) (xy 423.336889 -400.490753) (xy 423.328813 -400.423816) (xy 423.328813 -400.356393)
			(xy 423.336888 -400.289455) (xy 423.352922 -400.223967) (xy 423.376685 -400.16087) (xy 423.407834 -400.101074)
			(xy 423.445921 -400.045439) (xy 423.467784 -400.019774) (xy 423.473572 -400.012623) (xy 423.480092 -399.995437)
			(xy 423.480484 -399.986246) (xy 423.480484 -399.828766) (xy 423.4809 -399.818632) (xy 423.488647 -399.799901)
			(xy 423.502955 -399.785545) (xy 423.521659 -399.777735) (xy 423.531792 -399.777204) (xy 424.248072 -399.777204)
			(xy 424.258225 -399.777644) (xy 424.276977 -399.785431) (xy 424.291302 -399.799823) (xy 424.299002 -399.818611)
			(xy 424.29938 -399.828766) (xy 424.29938 -399.986246) (xy 424.299821 -399.99543) (xy 424.306314 -400.012614)
			(xy 424.31208 -400.019774) (xy 424.333951 -400.045434) (xy 424.37204 -400.101069) (xy 424.403192 -400.160866)
			(xy 424.426957 -400.223963) (xy 424.442992 -400.289453) (xy 424.451068 -400.356392) (xy 424.451068 -400.423817)
			(xy 424.442991 -400.490756) (xy 424.426954 -400.556245) (xy 424.403188 -400.619343) (xy 424.372036 -400.679139)
			(xy 424.333945 -400.734773) (xy 424.31208 -400.760438) (xy 424.306282 -400.767582) (xy 424.299769 -400.784774)
			(xy 424.29938 -400.793966) (xy 424.29938 -401.286218) (xy 424.299786 -401.295406) (xy 424.306303 -401.31259)
			(xy 424.31208 -401.319746) (xy 424.333923 -401.345429) (xy 424.372014 -401.40106) (xy 424.403167 -401.460854)
			(xy 424.426933 -401.523949) (xy 424.44297 -401.589436) (xy 424.451048 -401.656372) (xy 424.45105 -401.723795)
			(xy 424.442976 -401.790732) (xy 424.426943 -401.85622) (xy 424.40318 -401.919316) (xy 424.372031 -401.979111)
			(xy 424.333943 -402.034745) (xy 424.31208 -402.06041) (xy 424.306294 -402.067563) (xy 424.299774 -402.084748)
			(xy 424.29938 -402.093938) (xy 424.29938 -402.251418) (xy 424.298889 -402.261543) (xy 424.291159 -402.280261)
			(xy 424.276874 -402.294616) (xy 424.258195 -402.302438) (xy 424.248072 -402.30298) (xy 423.531792 -402.30298)
			(xy 423.521635 -402.302584) (xy 423.502879 -402.294782) (xy 423.488555 -402.280378) (xy 423.480859 -402.261577)
			(xy 423.480484 -402.251418) (xy 423.480484 -402.093938) (xy 423.480059 -402.084752) (xy 423.473556 -402.067568)
			(xy 423.467784 -402.06041) (xy 423.445899 -402.034762) (xy 423.407812 -401.979125) (xy 423.376663 -401.919326)
			(xy 423.352901 -401.856227) (xy 423.336867 -401.790736) (xy 423.328794 -401.723796) (xy 422.200742 -401.723796)
			(xy 422.171878 -401.779211) (xy 422.133794 -401.834846) (xy 422.111932 -401.860512) (xy 422.10614 -401.86766)
			(xy 422.099624 -401.884849) (xy 422.099232 -401.89404) (xy 422.099232 -402.386292) (xy 422.099661 -402.395477)
			(xy 422.106163 -402.412661) (xy 422.111932 -402.41982) (xy 422.133748 -402.445525) (xy 422.171836 -402.501154)
			(xy 422.202987 -402.560945) (xy 422.226752 -402.624037) (xy 422.24279 -402.689521) (xy 422.250869 -402.756454)
			(xy 422.250874 -402.823818) (xy 425.528934 -402.823818) (xy 425.528938 -402.75651) (xy 425.536987 -402.689684)
			(xy 425.552965 -402.624299) (xy 425.576642 -402.561293) (xy 425.60768 -402.501568) (xy 425.645634 -402.44598)
			(xy 425.667424 -402.420328) (xy 425.673236 -402.413194) (xy 425.679741 -402.395995) (xy 425.680124 -402.3868)
			(xy 425.680124 -401.893532) (xy 425.679693 -401.884347) (xy 425.673193 -401.867163) (xy 425.667424 -401.860004)
			(xy 425.645617 -401.834368) (xy 425.60767 -401.778779) (xy 425.576638 -401.719053) (xy 425.552967 -401.656046)
			(xy 425.536996 -401.590662) (xy 425.528954 -401.523838) (xy 425.528956 -401.456532) (xy 425.537001 -401.389708)
			(xy 425.552976 -401.324325) (xy 425.57665 -401.26132) (xy 425.607685 -401.201595) (xy 425.645635 -401.146008)
			(xy 425.667424 -401.120356) (xy 425.673225 -401.113214) (xy 425.679736 -401.096021) (xy 425.680124 -401.086828)
			(xy 425.680124 -400.92884) (xy 425.680555 -400.918686) (xy 425.688342 -400.899929) (xy 425.702736 -400.885604)
			(xy 425.72153 -400.877907) (xy 425.731686 -400.877532) (xy 426.447966 -400.877532) (xy 426.45809 -400.878054)
			(xy 426.476808 -400.88577) (xy 426.491165 -400.900045) (xy 426.498987 -400.918719) (xy 426.499528 -400.92884)
			(xy 426.499528 -401.086828) (xy 426.499918 -401.096017) (xy 426.506445 -401.113202) (xy 426.512228 -401.120356)
			(xy 426.533997 -401.146024) (xy 426.571949 -401.201607) (xy 426.602985 -401.261328) (xy 426.62666 -401.324331)
			(xy 426.642635 -401.389712) (xy 426.650681 -401.456533) (xy 426.650683 -401.523837) (xy 426.642641 -401.590659)
			(xy 426.626669 -401.65604) (xy 426.602997 -401.719044) (xy 426.600558 -401.723737) (xy 427.729089 -401.723737)
			(xy 427.729091 -401.65643) (xy 427.737138 -401.589605) (xy 427.753114 -401.524221) (xy 427.776791 -401.461216)
			(xy 427.807828 -401.401492) (xy 427.845782 -401.345906) (xy 427.867572 -401.320254) (xy 427.873379 -401.313117)
			(xy 427.879886 -401.29592) (xy 427.880272 -401.286726) (xy 427.880272 -400.793458) (xy 427.879888 -400.784268)
			(xy 427.873357 -400.767084) (xy 427.867572 -400.75993) (xy 427.845789 -400.734273) (xy 427.807838 -400.678688)
			(xy 427.776803 -400.618966) (xy 427.753128 -400.555962) (xy 427.737154 -400.49058) (xy 427.729109 -400.423757)
			(xy 427.729108 -400.356452) (xy 427.737152 -400.289629) (xy 427.753126 -400.224247) (xy 427.776799 -400.161243)
			(xy 427.807833 -400.101519) (xy 427.845784 -400.045934) (xy 427.867572 -400.020282) (xy 427.873367 -400.013136)
			(xy 427.879881 -399.995946) (xy 427.880272 -399.986754) (xy 427.880272 -399.828766) (xy 427.880706 -399.818602)
			(xy 427.888498 -399.799825) (xy 427.902883 -399.78546) (xy 427.921669 -399.777693) (xy 427.931834 -399.777204)
			(xy 428.648114 -399.777204) (xy 428.658268 -399.777721) (xy 428.677031 -399.785494) (xy 428.691395 -399.799852)
			(xy 428.699175 -399.818612) (xy 428.699676 -399.828766) (xy 428.699676 -399.986754) (xy 428.700114 -399.995938)
			(xy 428.706609 -400.013122) (xy 428.712376 -400.020282) (xy 428.734169 -400.045929) (xy 428.772117 -400.101517)
			(xy 428.803149 -400.161241) (xy 428.826821 -400.224246) (xy 428.842793 -400.289629) (xy 428.850836 -400.356452)
			(xy 428.850836 -400.423757) (xy 428.842791 -400.49058) (xy 428.826818 -400.555962) (xy 428.803145 -400.618967)
			(xy 428.772112 -400.678691) (xy 428.734164 -400.734278) (xy 428.712376 -400.75993) (xy 428.706581 -400.767076)
			(xy 428.700066 -400.784266) (xy 428.699676 -400.793458) (xy 428.699676 -401.286726) (xy 428.700079 -401.295914)
			(xy 428.706598 -401.313098) (xy 428.712376 -401.320254) (xy 428.734142 -401.345924) (xy 428.77209 -401.401508)
			(xy 428.803124 -401.46123) (xy 428.826797 -401.524232) (xy 428.842771 -401.589612) (xy 428.850817 -401.656432)
			(xy 428.850819 -401.723735) (xy 428.842777 -401.790556) (xy 428.826807 -401.855937) (xy 428.803137 -401.91894)
			(xy 428.772107 -401.978663) (xy 428.734162 -402.03425) (xy 428.712376 -402.059902) (xy 428.706593 -402.067057)
			(xy 428.700071 -402.08424) (xy 428.699676 -402.09343) (xy 428.699676 -402.251418) (xy 428.699182 -402.261575)
			(xy 428.691404 -402.280342) (xy 428.677039 -402.294706) (xy 428.658271 -402.302483) (xy 428.648114 -402.30298)
			(xy 427.931834 -402.30298) (xy 427.921667 -402.302509) (xy 427.902876 -402.294738) (xy 427.888491 -402.280367)
			(xy 427.880702 -402.261585) (xy 427.880272 -402.251418) (xy 427.880272 -402.09343) (xy 427.879854 -402.084244)
			(xy 427.873347 -402.067059) (xy 427.867572 -402.059902) (xy 427.845762 -402.034268) (xy 427.807811 -401.97868)
			(xy 427.776777 -401.918954) (xy 427.753104 -401.855947) (xy 427.737132 -401.790562) (xy 427.729089 -401.723737)
			(xy 426.600558 -401.723737) (xy 426.571964 -401.778767) (xy 426.534015 -401.834352) (xy 426.512228 -401.860004)
			(xy 426.506438 -401.867154) (xy 426.499922 -401.884341) (xy 426.499528 -401.893532) (xy 426.499528 -402.3868)
			(xy 426.499932 -402.395988) (xy 426.506449 -402.413173) (xy 426.512228 -402.420328) (xy 426.53397 -402.446019)
			(xy 426.571922 -402.501599) (xy 426.602959 -402.561317) (xy 426.626636 -402.624316) (xy 426.642613 -402.689694)
			(xy 426.650662 -402.756513) (xy 426.650666 -402.823815) (xy 426.650658 -402.823878) (xy 429.928702 -402.823878)
			(xy 429.928707 -402.75645) (xy 429.936788 -402.689508) (xy 429.952829 -402.624016) (xy 429.976599 -402.560917)
			(xy 430.007757 -402.50112) (xy 430.045852 -402.445485) (xy 430.06772 -402.41982) (xy 430.073535 -402.412688)
			(xy 430.080038 -402.395487) (xy 430.08042 -402.386292) (xy 430.08042 -401.89404) (xy 430.079986 -401.884855)
			(xy 430.073488 -401.867671) (xy 430.06772 -401.860512) (xy 430.045836 -401.834863) (xy 430.007746 -401.779227)
			(xy 429.976595 -401.719429) (xy 429.952831 -401.656329) (xy 429.936797 -401.590838) (xy 429.928722 -401.523898)
			(xy 429.928724 -401.456472) (xy 429.936802 -401.389532) (xy 429.95284 -401.324042) (xy 429.976608 -401.260944)
			(xy 430.007762 -401.201147) (xy 430.045854 -401.145513) (xy 430.06772 -401.119848) (xy 430.073523 -401.112708)
			(xy 430.080033 -401.095513) (xy 430.08042 -401.08632) (xy 430.08042 -400.92884) (xy 430.080849 -400.918718)
			(xy 430.088588 -400.900011) (xy 430.102901 -400.885695) (xy 430.121606 -400.877952) (xy 430.131728 -400.877532)
			(xy 430.848008 -400.877532) (xy 430.858135 -400.87791) (xy 430.876845 -400.885667) (xy 430.89116 -400.899996)
			(xy 430.898899 -400.918713) (xy 430.899316 -400.92884) (xy 430.899316 -401.08632) (xy 430.899713 -401.095509)
			(xy 430.906236 -401.112693) (xy 430.912016 -401.119848) (xy 430.93386 -401.14553) (xy 430.971948 -401.201162)
			(xy 431.003099 -401.260956) (xy 431.026863 -401.324051) (xy 431.0429 -401.389538) (xy 431.050977 -401.456474)
			(xy 431.050979 -401.523896) (xy 431.042905 -401.590832) (xy 431.026872 -401.65632) (xy 431.003111 -401.719416)
			(xy 431.00086 -401.723737) (xy 432.128879 -401.723737) (xy 432.128881 -401.65643) (xy 432.136928 -401.589605)
			(xy 432.152904 -401.524222) (xy 432.17658 -401.461216) (xy 432.207617 -401.401492) (xy 432.24557 -401.345906)
			(xy 432.26736 -401.320254) (xy 432.273166 -401.313116) (xy 432.279673 -401.29592) (xy 432.28006 -401.286726)
			(xy 432.28006 -400.793458) (xy 432.279657 -400.78427) (xy 432.273137 -400.767087) (xy 432.26736 -400.75993)
			(xy 432.245578 -400.734273) (xy 432.207627 -400.678688) (xy 432.176593 -400.618965) (xy 432.152919 -400.555961)
			(xy 432.136945 -400.490579) (xy 432.1289 -400.423757) (xy 432.128899 -400.356452) (xy 432.136943 -400.28963)
			(xy 432.152916 -400.224247) (xy 432.176589 -400.161243) (xy 432.207623 -400.10152) (xy 432.245572 -400.045934)
			(xy 432.26736 -400.020282) (xy 432.273154 -400.013135) (xy 432.279669 -399.995946) (xy 432.28006 -399.986754)
			(xy 432.28006 -399.828766) (xy 432.280506 -399.818603) (xy 432.288296 -399.799829) (xy 432.302676 -399.785464)
			(xy 432.321459 -399.777695) (xy 432.331622 -399.777204) (xy 433.047902 -399.777204) (xy 433.058056 -399.777731)
			(xy 433.076818 -399.7855) (xy 433.091182 -399.799855) (xy 433.098963 -399.818613) (xy 433.099464 -399.828766)
			(xy 433.099464 -399.986754) (xy 433.099905 -399.995938) (xy 433.106398 -400.013122) (xy 433.112164 -400.020282)
			(xy 433.133958 -400.045929) (xy 433.171906 -400.101516) (xy 433.202939 -400.161241) (xy 433.226611 -400.224246)
			(xy 433.242584 -400.289629) (xy 433.250627 -400.356452) (xy 433.250627 -400.423757) (xy 433.242582 -400.49058)
			(xy 433.226609 -400.555963) (xy 433.202935 -400.618968) (xy 433.171901 -400.678691) (xy 433.133952 -400.734278)
			(xy 433.112164 -400.75993) (xy 433.106368 -400.767075) (xy 433.099854 -400.784266) (xy 433.099464 -400.793458)
			(xy 433.099464 -401.286726) (xy 433.09987 -401.295913) (xy 433.106387 -401.313097) (xy 433.112164 -401.320254)
			(xy 433.13393 -401.345924) (xy 433.171879 -401.401508) (xy 433.202913 -401.461229) (xy 433.226587 -401.524231)
			(xy 433.242561 -401.589611) (xy 433.250607 -401.656432) (xy 433.250609 -401.723735) (xy 433.242567 -401.790556)
			(xy 433.226597 -401.855937) (xy 433.202927 -401.918941) (xy 433.171896 -401.978663) (xy 433.13395 -402.03425)
			(xy 433.112164 -402.059902) (xy 433.106379 -402.067056) (xy 433.099858 -402.08424) (xy 433.099464 -402.09343)
			(xy 433.099464 -402.251418) (xy 433.098982 -402.261577) (xy 433.091202 -402.280346) (xy 433.076833 -402.294711)
			(xy 433.058061 -402.302485) (xy 433.047902 -402.30298) (xy 432.331622 -402.30298) (xy 432.321454 -402.302518)
			(xy 432.302663 -402.294744) (xy 432.288278 -402.28037) (xy 432.28049 -402.261586) (xy 432.28006 -402.251418)
			(xy 432.28006 -402.09343) (xy 432.279622 -402.084246) (xy 432.273126 -402.067062) (xy 432.26736 -402.059902)
			(xy 432.24555 -402.034268) (xy 432.2076 -401.97868) (xy 432.176567 -401.918954) (xy 432.152894 -401.855947)
			(xy 432.136922 -401.790562) (xy 432.128879 -401.723737) (xy 431.00086 -401.723737) (xy 430.971963 -401.779212)
			(xy 430.933878 -401.834847) (xy 430.912016 -401.860512) (xy 430.906234 -401.867667) (xy 430.89971 -401.88485)
			(xy 430.899316 -401.89404) (xy 430.899316 -402.386292) (xy 430.899726 -402.395479) (xy 430.90624 -402.412664)
			(xy 430.912016 -402.41982) (xy 430.933832 -402.445524) (xy 430.971921 -402.501154) (xy 431.003073 -402.560945)
			(xy 431.026839 -402.624036) (xy 431.042878 -402.68952) (xy 431.050957 -402.756454) (xy 431.050962 -402.823818)
			(xy 434.329022 -402.823818) (xy 434.329026 -402.75651) (xy 434.337075 -402.689684) (xy 434.353052 -402.6243)
			(xy 434.376729 -402.561294) (xy 434.407766 -402.501568) (xy 434.445718 -402.445981) (xy 434.467508 -402.420328)
			(xy 434.473319 -402.413193) (xy 434.479825 -402.395995) (xy 434.480208 -402.3868) (xy 434.480208 -401.893532)
			(xy 434.479781 -401.884347) (xy 434.473279 -401.867162) (xy 434.467508 -401.860004) (xy 434.445702 -401.834368)
			(xy 434.407755 -401.778778) (xy 434.376725 -401.719052) (xy 434.353054 -401.656046) (xy 434.337084 -401.590662)
			(xy 434.329042 -401.523838) (xy 434.329043 -401.456532) (xy 434.337089 -401.389709) (xy 434.353063 -401.324326)
			(xy 434.376737 -401.26132) (xy 434.407771 -401.201596) (xy 434.44572 -401.146009) (xy 434.467508 -401.120356)
			(xy 434.473307 -401.113212) (xy 434.47982 -401.096021) (xy 434.480208 -401.086828) (xy 434.480208 -400.92884)
			(xy 434.480655 -400.918688) (xy 434.488438 -400.899934) (xy 434.502828 -400.885609) (xy 434.521616 -400.87791)
			(xy 434.53177 -400.877532) (xy 435.24805 -400.877532) (xy 435.258173 -400.878067) (xy 435.276891 -400.885777)
			(xy 435.291249 -400.900049) (xy 435.299071 -400.918721) (xy 435.299612 -400.92884) (xy 435.299612 -401.086828)
			(xy 435.300006 -401.096017) (xy 435.306531 -401.113201) (xy 435.312312 -401.120356) (xy 435.334082 -401.146024)
			(xy 435.372034 -401.201607) (xy 435.403071 -401.261328) (xy 435.426747 -401.32433) (xy 435.442723 -401.389711)
			(xy 435.450769 -401.456533) (xy 435.450771 -401.523837) (xy 435.442728 -401.590659) (xy 435.426756 -401.656041)
			(xy 435.403083 -401.719045) (xy 435.37205 -401.778767) (xy 435.3341 -401.834353) (xy 435.312312 -401.860004)
			(xy 435.306533 -401.867161) (xy 435.300007 -401.884343) (xy 435.299612 -401.893532) (xy 435.299612 -402.3868)
			(xy 435.30002 -402.395988) (xy 435.306535 -402.413172) (xy 435.312312 -402.420328) (xy 435.334054 -402.446018)
			(xy 435.372008 -402.501598) (xy 435.403046 -402.561316) (xy 435.426723 -402.624316) (xy 435.442701 -402.689694)
			(xy 435.45075 -402.756513) (xy 435.450754 -402.823815) (xy 435.442714 -402.890635) (xy 435.426745 -402.956015)
			(xy 435.403075 -403.019018) (xy 435.372045 -403.07874) (xy 435.334098 -403.134325) (xy 435.312312 -403.159976)
			(xy 435.306502 -403.167112) (xy 435.299995 -403.184309) (xy 435.299612 -403.193504) (xy 435.299612 -403.351492)
			(xy 435.299172 -403.361644) (xy 435.291381 -403.380394) (xy 435.27699 -403.394717) (xy 435.258204 -403.402419)
			(xy 435.24805 -403.4028) (xy 434.53177 -403.4028) (xy 434.521646 -403.402299) (xy 434.502932 -403.394569)
			(xy 434.488578 -403.380288) (xy 434.480753 -403.361613) (xy 434.480208 -403.351492) (xy 434.480208 -403.193504)
			(xy 434.479794 -403.184317) (xy 434.473283 -403.167133) (xy 434.467508 -403.159976) (xy 434.445674 -403.134362)
			(xy 434.407729 -403.07877) (xy 434.376699 -403.01904) (xy 434.353031 -402.956031) (xy 434.337062 -402.890644)
			(xy 434.329022 -402.823818) (xy 431.050962 -402.823818) (xy 431.050962 -402.823874) (xy 431.042891 -402.890808)
			(xy 431.026861 -402.956295) (xy 431.003103 -403.019389) (xy 430.971958 -403.079184) (xy 430.933877 -403.134819)
			(xy 430.912016 -403.160484) (xy 430.906203 -403.167618) (xy 430.899698 -403.184817) (xy 430.899316 -403.194012)
			(xy 430.899316 -403.351492) (xy 430.898809 -403.361598) (xy 430.891077 -403.380273) (xy 430.876787 -403.394568)
			(xy 430.858114 -403.402306) (xy 430.848008 -403.4028) (xy 430.131728 -403.4028) (xy 430.121607 -403.402361)
			(xy 430.102904 -403.394622) (xy 430.088589 -403.380313) (xy 430.080843 -403.361613) (xy 430.08042 -403.351492)
			(xy 430.08042 -403.194012) (xy 430.079999 -403.184826) (xy 430.073492 -403.167642) (xy 430.06772 -403.160484)
			(xy 430.045808 -403.134858) (xy 430.00772 -403.079218) (xy 429.97657 -403.019417) (xy 429.952807 -402.956315)
			(xy 429.936775 -402.890821) (xy 429.928702 -402.823878) (xy 426.650658 -402.823878) (xy 426.642626 -402.890635)
			(xy 426.626657 -402.956015) (xy 426.602989 -403.019017) (xy 426.571959 -403.078739) (xy 426.534014 -403.134324)
			(xy 426.512228 -403.159976) (xy 426.506408 -403.167104) (xy 426.499909 -403.184308) (xy 426.499528 -403.193504)
			(xy 426.499528 -403.351492) (xy 426.499072 -403.361642) (xy 426.491285 -403.380389) (xy 426.476899 -403.394712)
			(xy 426.458118 -403.402417) (xy 426.447966 -403.4028) (xy 425.731686 -403.4028) (xy 425.721563 -403.402286)
			(xy 425.70285 -403.394561) (xy 425.688495 -403.380284) (xy 425.68067 -403.361612) (xy 425.680124 -403.351492)
			(xy 425.680124 -403.193504) (xy 425.679707 -403.184318) (xy 425.673198 -403.167133) (xy 425.667424 -403.159976)
			(xy 425.64559 -403.134362) (xy 425.607643 -403.07877) (xy 425.576613 -403.019041) (xy 425.552943 -402.956032)
			(xy 425.536974 -402.890645) (xy 425.528934 -402.823818) (xy 422.250874 -402.823818) (xy 422.250874 -402.823874)
			(xy 422.242803 -402.890808) (xy 422.226774 -402.956294) (xy 422.203016 -403.019389) (xy 422.171873 -403.079184)
			(xy 422.133792 -403.134818) (xy 422.111932 -403.160484) (xy 422.106109 -403.16761) (xy 422.099612 -403.184816)
			(xy 422.099232 -403.194012) (xy 422.099232 -403.351492) (xy 422.098709 -403.361596) (xy 422.09098 -403.380268)
			(xy 422.076695 -403.394562) (xy 422.058028 -403.402303) (xy 422.047924 -403.4028) (xy 421.331644 -403.4028)
			(xy 421.321524 -403.402348) (xy 421.302822 -403.394614) (xy 421.288506 -403.380308) (xy 421.280759 -403.361611)
			(xy 421.280336 -403.351492) (xy 421.280336 -403.194012) (xy 421.279912 -403.184826) (xy 421.273407 -403.167642)
			(xy 421.267636 -403.160484) (xy 421.245724 -403.134858) (xy 421.207634 -403.079219) (xy 421.176483 -403.019418)
			(xy 421.15272 -402.956315) (xy 421.136687 -402.890821) (xy 421.128614 -402.823878) (xy 414.525968 -402.823878)
			(xy 414.525968 -405.623649) (xy 418.929012 -405.623649) (xy 418.929013 -405.556342) (xy 418.937058 -405.489518)
			(xy 418.953033 -405.424135) (xy 418.976709 -405.36113) (xy 419.007746 -405.301407) (xy 419.045698 -405.245822)
			(xy 419.067488 -405.22017) (xy 419.073278 -405.21302) (xy 419.079797 -405.195833) (xy 419.080188 -405.186642)
			(xy 419.080188 -404.693374) (xy 419.079793 -404.684185) (xy 419.073269 -404.667001) (xy 419.067488 -404.659846)
			(xy 419.04572 -404.634177) (xy 419.007768 -404.578594) (xy 418.976731 -404.518873) (xy 418.953055 -404.455871)
			(xy 418.937079 -404.39049) (xy 418.929032 -404.323669) (xy 418.92903 -404.256364) (xy 418.937073 -404.189542)
			(xy 418.953045 -404.124161) (xy 418.976717 -404.061157) (xy 419.007751 -404.001435) (xy 419.0457 -403.945849)
			(xy 419.067488 -403.920198) (xy 419.073267 -403.91304) (xy 419.079792 -403.895859) (xy 419.080188 -403.88667)
			(xy 419.080188 -403.728682) (xy 419.08055 -403.718503) (xy 419.088351 -403.699698) (xy 419.102756 -403.685313)
			(xy 419.12157 -403.677537) (xy 419.13175 -403.67712) (xy 419.84803 -403.67712) (xy 419.858187 -403.677608)
			(xy 419.876954 -403.685389) (xy 419.891317 -403.699756) (xy 419.899094 -403.718524) (xy 419.899592 -403.728682)
			(xy 419.899592 -403.88667) (xy 419.900018 -403.895855) (xy 419.906521 -403.91304) (xy 419.912292 -403.920198)
			(xy 419.9341 -403.945833) (xy 419.972047 -404.001422) (xy 420.003077 -404.061149) (xy 420.026747 -404.124155)
			(xy 420.042718 -404.189539) (xy 420.05076 -404.256363) (xy 420.050758 -404.32367) (xy 420.042712 -404.390493)
			(xy 420.026738 -404.455876) (xy 420.003064 -404.518882) (xy 419.97203 -404.578606) (xy 419.93408 -404.634193)
			(xy 419.912292 -404.659846) (xy 419.906492 -404.666989) (xy 419.89998 -404.684181) (xy 419.899592 -404.693374)
			(xy 419.899592 -405.186642) (xy 419.899984 -405.195831) (xy 419.90651 -405.213015) (xy 419.912292 -405.22017)
			(xy 419.934073 -405.245827) (xy 419.97202 -405.301414) (xy 420.003052 -405.361137) (xy 420.026723 -405.424141)
			(xy 420.042696 -405.489522) (xy 420.05074 -405.556343) (xy 420.050741 -405.623647) (xy 420.042698 -405.690469)
			(xy 420.026726 -405.755851) (xy 420.003055 -405.818855) (xy 419.972025 -405.878578) (xy 419.934078 -405.934165)
			(xy 419.912292 -405.959818) (xy 419.906504 -405.96697) (xy 419.899985 -405.984155) (xy 419.899592 -405.993346)
			(xy 419.899592 -406.151334) (xy 419.899095 -406.16149) (xy 419.891315 -406.180254) (xy 419.876951 -406.194617)
			(xy 419.858186 -406.202396) (xy 419.84803 -406.202896) (xy 419.13175 -406.202896) (xy 419.121586 -406.202396)
			(xy 419.102799 -406.194634) (xy 419.088413 -406.180272) (xy 419.08062 -406.161497) (xy 419.080188 -406.151334)
			(xy 419.080188 -405.993346) (xy 419.079759 -405.984161) (xy 419.073259 -405.966976) (xy 419.067488 -405.959818)
			(xy 419.045693 -405.934171) (xy 419.007741 -405.878585) (xy 418.976705 -405.818861) (xy 418.953031 -405.755856)
			(xy 418.937057 -405.690473) (xy 418.929012 -405.623649) (xy 414.525968 -405.623649) (xy 414.525968 -406.723789)
			(xy 421.128626 -406.723789) (xy 421.128629 -406.656363) (xy 421.136708 -406.589421) (xy 421.152748 -406.52393)
			(xy 421.176518 -406.460832) (xy 421.207674 -406.401035) (xy 421.245769 -406.345401) (xy 421.267636 -406.319736)
			(xy 421.273447 -406.312601) (xy 421.279952 -406.295403) (xy 421.280336 -406.286208) (xy 421.280336 -405.793956)
			(xy 421.279939 -405.784768) (xy 421.273415 -405.767584) (xy 421.267636 -405.760428) (xy 421.245767 -405.734767)
			(xy 421.207676 -405.679132) (xy 421.176523 -405.619336) (xy 421.152758 -405.556239) (xy 421.136722 -405.490749)
			(xy 421.128645 -405.423809) (xy 421.128646 -405.356385) (xy 421.136723 -405.289445) (xy 421.15276 -405.223956)
			(xy 421.176526 -405.160859) (xy 421.207679 -405.101062) (xy 421.245771 -405.045429) (xy 421.267636 -405.019764)
			(xy 421.273435 -405.012621) (xy 421.279947 -404.995429) (xy 421.280336 -404.986236) (xy 421.280336 -404.828756)
			(xy 421.28075 -404.81864) (xy 421.288509 -404.799954) (xy 421.302828 -404.785659) (xy 421.321527 -404.777933)
			(xy 421.331644 -404.777448) (xy 422.047924 -404.777448) (xy 422.058028 -404.777964) (xy 422.076697 -404.7857)
			(xy 422.090989 -404.799986) (xy 422.098732 -404.818652) (xy 422.099232 -404.828756) (xy 422.099232 -404.986236)
			(xy 422.09964 -404.995423) (xy 422.106157 -405.012607) (xy 422.111932 -405.019764) (xy 422.133791 -405.045433)
			(xy 422.171878 -405.101068) (xy 422.203027 -405.160864) (xy 422.22679 -405.22396) (xy 422.242825 -405.289448)
			(xy 422.2509 -405.356386) (xy 422.250901 -405.423808) (xy 422.242826 -405.490746) (xy 422.226792 -405.556234)
			(xy 422.203029 -405.619331) (xy 422.20075 -405.623707) (xy 423.328805 -405.623707) (xy 423.328805 -405.556284)
			(xy 423.336882 -405.489345) (xy 423.352917 -405.423856) (xy 423.376681 -405.360759) (xy 423.407832 -405.300962)
			(xy 423.44592 -405.245328) (xy 423.467784 -405.219662) (xy 423.473577 -405.212514) (xy 423.480094 -405.195326)
			(xy 423.480484 -405.186134) (xy 423.480484 -404.693882) (xy 423.480086 -404.684693) (xy 423.473564 -404.667509)
			(xy 423.467784 -404.660354) (xy 423.445942 -404.634671) (xy 423.407854 -404.579038) (xy 423.376703 -404.519245)
			(xy 423.352938 -404.45615) (xy 423.336902 -404.390663) (xy 423.328825 -404.323727) (xy 423.328823 -404.256306)
			(xy 423.336896 -404.189369) (xy 423.352929 -404.123882) (xy 423.37669 -404.060786) (xy 423.407837 -404.00099)
			(xy 423.445922 -403.945355) (xy 423.467784 -403.91969) (xy 423.473565 -403.912534) (xy 423.48009 -403.895352)
			(xy 423.480484 -403.886162) (xy 423.480484 -403.728682) (xy 423.480913 -403.718549) (xy 423.488655 -403.699819)
			(xy 423.502959 -403.685461) (xy 423.521661 -403.677651) (xy 423.531792 -403.67712) (xy 424.248072 -403.67712)
			(xy 424.258227 -403.677545) (xy 424.276983 -403.685335) (xy 424.291308 -403.699731) (xy 424.299005 -403.718525)
			(xy 424.29938 -403.728682) (xy 424.29938 -403.886162) (xy 424.299813 -403.895347) (xy 424.306311 -403.912531)
			(xy 424.31208 -403.91969) (xy 424.333966 -403.945337) (xy 424.372056 -404.000974) (xy 424.403207 -404.060772)
			(xy 424.42697 -404.123872) (xy 424.443005 -404.189363) (xy 424.451079 -404.256304) (xy 424.451077 -404.323729)
			(xy 424.442999 -404.39067) (xy 424.426961 -404.45616) (xy 424.403193 -404.519258) (xy 424.372039 -404.579055)
			(xy 424.333946 -404.634689) (xy 424.31208 -404.660354) (xy 424.306276 -404.667494) (xy 424.299766 -404.684688)
			(xy 424.29938 -404.693882) (xy 424.29938 -405.186134) (xy 424.299778 -405.195322) (xy 424.306301 -405.212506)
			(xy 424.31208 -405.219662) (xy 424.333939 -405.245332) (xy 424.372029 -405.300965) (xy 424.403181 -405.360761)
			(xy 424.426946 -405.423857) (xy 424.442983 -405.489346) (xy 424.45106 -405.556284) (xy 424.45106 -405.623707)
			(xy 424.442985 -405.690646) (xy 424.426949 -405.756134) (xy 424.403185 -405.819231) (xy 424.372034 -405.879027)
			(xy 424.333944 -405.934661) (xy 424.31208 -405.960326) (xy 424.306288 -405.967474) (xy 424.299771 -405.984662)
			(xy 424.29938 -405.993854) (xy 424.29938 -406.151334) (xy 424.298902 -406.16146) (xy 424.291167 -406.180179)
			(xy 424.276878 -406.194533) (xy 424.258196 -406.202355) (xy 424.248072 -406.202896) (xy 423.531792 -406.202896)
			(xy 423.521637 -406.202485) (xy 423.502884 -406.194686) (xy 423.48856 -406.180286) (xy 423.480862 -406.161491)
			(xy 423.480484 -406.151334) (xy 423.480484 -405.993854) (xy 423.480051 -405.984669) (xy 423.473553 -405.967484)
			(xy 423.467784 -405.960326) (xy 423.445915 -405.934665) (xy 423.407827 -405.87903) (xy 423.376678 -405.819233)
			(xy 423.352915 -405.756135) (xy 423.33688 -405.690646) (xy 423.328805 -405.623707) (xy 422.20075 -405.623707)
			(xy 422.171881 -405.679127) (xy 422.133795 -405.734762) (xy 422.111932 -405.760428) (xy 422.106133 -405.767571)
			(xy 422.099622 -405.784763) (xy 422.099232 -405.793956) (xy 422.099232 -406.286208) (xy 422.099654 -406.295394)
			(xy 422.106161 -406.312577) (xy 422.111932 -406.319736) (xy 422.133763 -406.345428) (xy 422.171851 -406.401059)
			(xy 422.203001 -406.460852) (xy 422.226766 -406.523945) (xy 422.242803 -406.589431) (xy 422.250881 -406.656366)
			(xy 422.250883 -406.72373) (xy 425.528945 -406.72373) (xy 425.528948 -406.656422) (xy 425.536995 -406.589598)
			(xy 425.552971 -406.524214) (xy 425.576647 -406.461208) (xy 425.607683 -406.401484) (xy 425.645635 -406.345896)
			(xy 425.667424 -406.320244) (xy 425.67323 -406.313105) (xy 425.679738 -406.29591) (xy 425.680124 -406.286716)
			(xy 425.680124 -405.793448) (xy 425.679685 -405.784264) (xy 425.673191 -405.76708) (xy 425.667424 -405.75992)
			(xy 425.645633 -405.734271) (xy 425.607685 -405.678684) (xy 425.576653 -405.61896) (xy 425.552981 -405.555955)
			(xy 425.537009 -405.490572) (xy 425.528965 -405.42375) (xy 425.528965 -405.356444) (xy 425.53701 -405.289622)
			(xy 425.552983 -405.22424) (xy 425.576655 -405.161235) (xy 425.607688 -405.101511) (xy 425.645636 -405.045924)
			(xy 425.667424 -405.020272) (xy 425.673218 -405.013125) (xy 425.679733 -404.995936) (xy 425.680124 -404.986744)
			(xy 425.680124 -404.828756) (xy 425.680486 -404.818596) (xy 425.688301 -404.799838) (xy 425.702716 -404.785515)
			(xy 425.721523 -404.777822) (xy 425.731686 -404.777448) (xy 426.447966 -404.777448) (xy 426.458091 -404.777955)
			(xy 426.476813 -404.785673) (xy 426.491171 -404.799953) (xy 426.49899 -404.818633) (xy 426.499528 -404.828756)
			(xy 426.499528 -404.986744) (xy 426.499911 -404.995934) (xy 426.506443 -405.013119) (xy 426.512228 -405.020272)
			(xy 426.534013 -405.045927) (xy 426.571964 -405.101512) (xy 426.602999 -405.161235) (xy 426.626674 -405.224239)
			(xy 426.642648 -405.289622) (xy 426.650693 -405.356444) (xy 426.650693 -405.42375) (xy 426.642649 -405.490573)
			(xy 426.626675 -405.555955) (xy 426.603002 -405.618959) (xy 426.600565 -405.623649) (xy 427.7291 -405.623649)
			(xy 427.729101 -405.556342) (xy 427.737146 -405.489519) (xy 427.753121 -405.424136) (xy 427.776796 -405.361131)
			(xy 427.807831 -405.301408) (xy 427.845783 -405.245822) (xy 427.867572 -405.22017) (xy 427.873373 -405.213028)
			(xy 427.879883 -405.195835) (xy 427.880272 -405.186642) (xy 427.880272 -404.693374) (xy 427.879881 -404.684185)
			(xy 427.873355 -404.667) (xy 427.867572 -404.659846) (xy 427.845805 -404.634176) (xy 427.807853 -404.578593)
			(xy 427.776817 -404.518872) (xy 427.753142 -404.45587) (xy 427.737166 -404.39049) (xy 427.72912 -404.323668)
			(xy 427.729118 -404.256365) (xy 427.73716 -404.189543) (xy 427.753132 -404.124162) (xy 427.776804 -404.061158)
			(xy 427.807836 -404.001435) (xy 427.845785 -403.94585) (xy 427.867572 -403.920198) (xy 427.873361 -403.913048)
			(xy 427.879878 -403.895861) (xy 427.880272 -403.88667) (xy 427.880272 -403.728682) (xy 427.88065 -403.718505)
			(xy 427.888447 -403.699703) (xy 427.902847 -403.685318) (xy 427.921657 -403.67754) (xy 427.931834 -403.67712)
			(xy 428.648114 -403.67712) (xy 428.65827 -403.677622) (xy 428.677036 -403.685397) (xy 428.6914 -403.69976)
			(xy 428.699178 -403.718526) (xy 428.699676 -403.728682) (xy 428.699676 -403.88667) (xy 428.700106 -403.895855)
			(xy 428.706607 -403.913039) (xy 428.712376 -403.920198) (xy 428.734185 -403.945833) (xy 428.772132 -404.001422)
			(xy 428.803164 -404.061148) (xy 428.826835 -404.124155) (xy 428.842806 -404.189539) (xy 428.850848 -404.256363)
			(xy 428.850846 -404.32367) (xy 428.8428 -404.390494) (xy 428.826825 -404.455877) (xy 428.80315 -404.518882)
			(xy 428.772115 -404.578607) (xy 428.734165 -404.634194) (xy 428.712376 -404.659846) (xy 428.706575 -404.666988)
			(xy 428.700064 -404.684181) (xy 428.699676 -404.693374) (xy 428.699676 -405.186642) (xy 428.700071 -405.195831)
			(xy 428.706596 -405.213015) (xy 428.712376 -405.22017) (xy 428.734157 -405.245827) (xy 428.772106 -405.301413)
			(xy 428.803138 -405.361136) (xy 428.826811 -405.42414) (xy 428.842784 -405.489522) (xy 428.850828 -405.556343)
			(xy 428.850829 -405.623648) (xy 428.842785 -405.69047) (xy 428.826813 -405.755851) (xy 428.803142 -405.818856)
			(xy 428.77211 -405.878579) (xy 428.734163 -405.934166) (xy 428.712376 -405.959818) (xy 428.706587 -405.966968)
			(xy 428.700068 -405.984155) (xy 428.699676 -405.993346) (xy 428.699676 -406.151334) (xy 428.699195 -406.161492)
			(xy 428.691412 -406.180259) (xy 428.677043 -406.194623) (xy 428.658272 -406.202399) (xy 428.648114 -406.202896)
			(xy 427.931834 -406.202896) (xy 427.921683 -406.202339) (xy 427.902921 -406.194583) (xy 427.888556 -406.180236)
			(xy 427.880774 -406.161485) (xy 427.880272 -406.151334) (xy 427.880272 -405.993346) (xy 427.879846 -405.98416)
			(xy 427.873344 -405.966976) (xy 427.867572 -405.959818) (xy 427.845777 -405.934171) (xy 427.807827 -405.878585)
			(xy 427.776792 -405.818861) (xy 427.753118 -405.755855) (xy 427.737144 -405.690472) (xy 427.7291 -405.623649)
			(xy 426.600565 -405.623649) (xy 426.571967 -405.678683) (xy 426.534016 -405.734268) (xy 426.512228 -405.75992)
			(xy 426.506432 -405.767065) (xy 426.499919 -405.784256) (xy 426.499528 -405.793448) (xy 426.499528 -406.286716)
			(xy 426.499924 -406.295905) (xy 426.506447 -406.313089) (xy 426.512228 -406.320244) (xy 426.533985 -406.345922)
			(xy 426.571937 -406.401504) (xy 426.602974 -406.461223) (xy 426.62665 -406.524225) (xy 426.642626 -406.589604)
			(xy 426.650673 -406.656424) (xy 426.650676 -406.723728) (xy 426.650669 -406.723789) (xy 429.928714 -406.723789)
			(xy 429.928717 -406.656363) (xy 429.936796 -406.589422) (xy 429.952835 -406.523931) (xy 429.976604 -406.460832)
			(xy 430.00776 -406.401036) (xy 430.045853 -406.345401) (xy 430.06772 -406.319736) (xy 430.073529 -406.312599)
			(xy 430.080035 -406.295402) (xy 430.08042 -406.286208) (xy 430.08042 -405.793956) (xy 430.080027 -405.784767)
			(xy 430.073501 -405.767583) (xy 430.06772 -405.760428) (xy 430.045851 -405.734766) (xy 430.007761 -405.679132)
			(xy 429.97661 -405.619335) (xy 429.952845 -405.556238) (xy 429.936809 -405.490748) (xy 429.928733 -405.423809)
			(xy 429.928734 -405.356385) (xy 429.93681 -405.289446) (xy 429.952847 -405.223956) (xy 429.976612 -405.160859)
			(xy 430.007765 -405.101063) (xy 430.045855 -405.045429) (xy 430.06772 -405.019764) (xy 430.073517 -405.012619)
			(xy 430.080031 -404.995428) (xy 430.08042 -404.986236) (xy 430.08042 -404.828756) (xy 430.08085 -404.818642)
			(xy 430.088605 -404.799959) (xy 430.102919 -404.785665) (xy 430.121613 -404.777935) (xy 430.131728 -404.777448)
			(xy 430.848008 -404.777448) (xy 430.858111 -404.777977) (xy 430.876779 -404.785708) (xy 430.891072 -404.799991)
			(xy 430.898815 -404.818654) (xy 430.899316 -404.828756) (xy 430.899316 -404.986236) (xy 430.899705 -404.995425)
			(xy 430.906233 -405.01261) (xy 430.912016 -405.019764) (xy 430.933875 -405.045433) (xy 430.971963 -405.101067)
			(xy 431.003113 -405.160863) (xy 431.026877 -405.223959) (xy 431.042912 -405.289448) (xy 431.050988 -405.356385)
			(xy 431.050989 -405.423809) (xy 431.042913 -405.490746) (xy 431.026879 -405.556235) (xy 431.003116 -405.619331)
			(xy 431.000867 -405.623648) (xy 432.128891 -405.623648) (xy 432.128892 -405.556343) (xy 432.136937 -405.489519)
			(xy 432.152911 -405.424136) (xy 432.176585 -405.361132) (xy 432.207621 -405.301408) (xy 432.245571 -405.245822)
			(xy 432.26736 -405.22017) (xy 432.273159 -405.213027) (xy 432.279671 -405.195835) (xy 432.28006 -405.186642)
			(xy 432.28006 -404.693374) (xy 432.279649 -404.684187) (xy 432.273134 -404.667004) (xy 432.26736 -404.659846)
			(xy 432.245593 -404.634176) (xy 432.207643 -404.578593) (xy 432.176607 -404.518872) (xy 432.152932 -404.45587)
			(xy 432.136957 -404.390489) (xy 432.128911 -404.323668) (xy 432.128909 -404.256365) (xy 432.136951 -404.189543)
			(xy 432.152922 -404.124162) (xy 432.176594 -404.061158) (xy 432.207626 -404.001436) (xy 432.245573 -403.94585)
			(xy 432.26736 -403.920198) (xy 432.273147 -403.913047) (xy 432.279666 -403.895861) (xy 432.28006 -403.88667)
			(xy 432.28006 -403.728682) (xy 432.28045 -403.718507) (xy 432.288245 -403.699707) (xy 432.302641 -403.685322)
			(xy 432.321446 -403.677542) (xy 432.331622 -403.67712) (xy 433.047902 -403.67712) (xy 433.058058 -403.677631)
			(xy 433.076823 -403.685403) (xy 433.091188 -403.699763) (xy 433.098965 -403.718526) (xy 433.099464 -403.728682)
			(xy 433.099464 -403.88667) (xy 433.099897 -403.895855) (xy 433.106396 -403.913039) (xy 433.112164 -403.920198)
			(xy 433.133973 -403.945832) (xy 433.171921 -404.001421) (xy 433.202954 -404.061147) (xy 433.226625 -404.124154)
			(xy 433.242596 -404.189539) (xy 433.250639 -404.256363) (xy 433.250637 -404.32367) (xy 433.24259 -404.390494)
			(xy 433.226615 -404.455877) (xy 433.20294 -404.518883) (xy 433.171904 -404.578607) (xy 433.133953 -404.634194)
			(xy 433.112164 -404.659846) (xy 433.106361 -404.666986) (xy 433.099851 -404.684181) (xy 433.099464 -404.693374)
			(xy 433.099464 -405.186642) (xy 433.099862 -405.19583) (xy 433.106385 -405.213014) (xy 433.112164 -405.22017)
			(xy 433.133946 -405.245827) (xy 433.171895 -405.301413) (xy 433.202928 -405.361136) (xy 433.226601 -405.42414)
			(xy 433.242574 -405.489521) (xy 433.250619 -405.556343) (xy 433.250619 -405.623648) (xy 433.242576 -405.69047)
			(xy 433.226604 -405.755852) (xy 433.202932 -405.818856) (xy 433.171899 -405.878579) (xy 433.133951 -405.934166)
			(xy 433.112164 -405.959818) (xy 433.106373 -405.966967) (xy 433.099856 -405.984155) (xy 433.099464 -405.993346)
			(xy 433.099464 -406.151334) (xy 433.098995 -406.161494) (xy 433.091209 -406.180263) (xy 433.076836 -406.194627)
			(xy 433.058062 -406.202401) (xy 433.047902 -406.202896) (xy 432.331622 -406.202896) (xy 432.32147 -406.20235)
			(xy 432.302708 -406.194589) (xy 432.288343 -406.180239) (xy 432.280561 -406.161486) (xy 432.28006 -406.151334)
			(xy 432.28006 -405.993346) (xy 432.279614 -405.984163) (xy 432.273124 -405.966979) (xy 432.26736 -405.959818)
			(xy 432.245566 -405.934171) (xy 432.207616 -405.878584) (xy 432.176582 -405.81886) (xy 432.152908 -405.755855)
			(xy 432.136935 -405.690472) (xy 432.128891 -405.623648) (xy 431.000867 -405.623648) (xy 430.971966 -405.679128)
			(xy 430.933879 -405.734762) (xy 430.912016 -405.760428) (xy 430.906227 -405.767579) (xy 430.899707 -405.784765)
			(xy 430.899316 -405.793956) (xy 430.899316 -406.286208) (xy 430.899719 -406.295396) (xy 430.906237 -406.31258)
			(xy 430.912016 -406.319736) (xy 430.933848 -406.345427) (xy 430.971937 -406.401059) (xy 431.003088 -406.460851)
			(xy 431.026853 -406.523945) (xy 431.04289 -406.58943) (xy 431.050968 -406.656366) (xy 431.050971 -406.723729)
			(xy 434.329033 -406.723729) (xy 434.329036 -406.656422) (xy 434.337083 -406.589598) (xy 434.353058 -406.524215)
			(xy 434.376733 -406.461209) (xy 434.407769 -406.401484) (xy 434.445719 -406.345897) (xy 434.467508 -406.320244)
			(xy 434.473312 -406.313104) (xy 434.479822 -406.295909) (xy 434.480208 -406.286716) (xy 434.480208 -405.793448)
			(xy 434.479773 -405.784263) (xy 434.473276 -405.767079) (xy 434.467508 -405.75992) (xy 434.445717 -405.734271)
			(xy 434.407771 -405.678683) (xy 434.376739 -405.618959) (xy 434.353068 -405.555954) (xy 434.337096 -405.490572)
			(xy 434.329053 -405.423749) (xy 434.329053 -405.356445) (xy 434.337097 -405.289622) (xy 434.35307 -405.22424)
			(xy 434.376742 -405.161236) (xy 434.407774 -405.101512) (xy 434.445721 -405.045925) (xy 434.467508 -405.020272)
			(xy 434.4733 -405.013124) (xy 434.479817 -404.995935) (xy 434.480208 -404.986744) (xy 434.480208 -404.828756)
			(xy 434.480586 -404.818598) (xy 434.488397 -404.799843) (xy 434.502807 -404.785521) (xy 434.52161 -404.777824)
			(xy 434.53177 -404.777448) (xy 435.24805 -404.777448) (xy 435.258175 -404.777968) (xy 435.276896 -404.785681)
			(xy 435.291254 -404.799957) (xy 435.299074 -404.818634) (xy 435.299612 -404.828756) (xy 435.299612 -404.986744)
			(xy 435.299998 -404.995934) (xy 435.306528 -405.013118) (xy 435.312312 -405.020272) (xy 435.334097 -405.045927)
			(xy 435.372049 -405.101512) (xy 435.403086 -405.161234) (xy 435.426761 -405.224239) (xy 435.442735 -405.289621)
			(xy 435.450781 -405.356444) (xy 435.450781 -405.42375) (xy 435.442736 -405.490573) (xy 435.426762 -405.555956)
			(xy 435.403088 -405.61896) (xy 435.372052 -405.678683) (xy 435.334101 -405.734269) (xy 435.312312 -405.75992)
			(xy 435.306526 -405.767073) (xy 435.300005 -405.784257) (xy 435.299612 -405.793448) (xy 435.299612 -406.286716)
			(xy 435.300012 -406.295904) (xy 435.306532 -406.313089) (xy 435.312312 -406.320244) (xy 435.33407 -406.345921)
			(xy 435.372023 -406.401503) (xy 435.40306 -406.461223) (xy 435.426737 -406.524224) (xy 435.442713 -406.589604)
			(xy 435.450761 -406.656424) (xy 435.450764 -406.723728) (xy 435.442722 -406.790549) (xy 435.426751 -406.85593)
			(xy 435.40308 -406.918933) (xy 435.372048 -406.978656) (xy 435.334099 -407.034241) (xy 435.312312 -407.059892)
			(xy 435.306538 -407.067053) (xy 435.300009 -407.084231) (xy 435.299612 -407.09342) (xy 435.299612 -407.251408)
			(xy 435.299185 -407.261561) (xy 435.291389 -407.280311) (xy 435.276994 -407.294634) (xy 435.258205 -407.302335)
			(xy 435.24805 -407.302716) (xy 434.53177 -407.302716) (xy 434.521636 -407.302297) (xy 434.502906 -407.294551)
			(xy 434.488549 -407.280244) (xy 434.480739 -407.26154) (xy 434.480208 -407.251408) (xy 434.480208 -407.09342)
			(xy 434.479786 -407.084234) (xy 434.47328 -407.06705) (xy 434.467508 -407.059892) (xy 434.44569 -407.034265)
			(xy 434.407744 -406.978674) (xy 434.376714 -406.918947) (xy 434.353044 -406.855939) (xy 434.337074 -406.790554)
			(xy 434.329033 -406.723729) (xy 431.050971 -406.723729) (xy 431.050971 -406.723786) (xy 431.042899 -406.790722)
			(xy 431.026867 -406.856209) (xy 431.003107 -406.919305) (xy 430.971961 -406.9791) (xy 430.933877 -407.034735)
			(xy 430.912016 -407.0604) (xy 430.906239 -407.067559) (xy 430.899712 -407.084739) (xy 430.899316 -407.093928)
			(xy 430.899316 -407.251408) (xy 430.898822 -407.261515) (xy 430.891084 -407.28019) (xy 430.87679 -407.294484)
			(xy 430.858115 -407.302222) (xy 430.848008 -407.302716) (xy 430.131728 -407.302716) (xy 430.121609 -407.302262)
			(xy 430.102909 -407.294526) (xy 430.088595 -407.280221) (xy 430.080845 -407.261526) (xy 430.08042 -407.251408)
			(xy 430.08042 -407.093928) (xy 430.079992 -407.084743) (xy 430.07349 -407.067559) (xy 430.06772 -407.0604)
			(xy 430.045824 -407.034761) (xy 430.007735 -406.979123) (xy 429.976584 -406.919324) (xy 429.952821 -406.856223)
			(xy 429.936787 -406.790731) (xy 429.928714 -406.723789) (xy 426.650669 -406.723789) (xy 426.642634 -406.790548)
			(xy 426.626664 -406.855929) (xy 426.602993 -406.918933) (xy 426.571962 -406.978655) (xy 426.534015 -407.03424)
			(xy 426.512228 -407.059892) (xy 426.506444 -407.067045) (xy 426.499924 -407.08423) (xy 426.499528 -407.09342)
			(xy 426.499528 -407.251408) (xy 426.499085 -407.261559) (xy 426.491292 -407.280306) (xy 426.476903 -407.294628)
			(xy 426.458119 -407.302333) (xy 426.447966 -407.302716) (xy 425.731686 -407.302716) (xy 425.721553 -407.302283)
			(xy 425.702823 -407.294543) (xy 425.688466 -407.28024) (xy 425.680655 -407.261539) (xy 425.680124 -407.251408)
			(xy 425.680124 -407.09342) (xy 425.679699 -407.084235) (xy 425.673195 -407.06705) (xy 425.667424 -407.059892)
			(xy 425.645605 -407.034266) (xy 425.607658 -406.978675) (xy 425.576627 -406.918948) (xy 425.552957 -406.85594)
			(xy 425.536987 -406.790555) (xy 425.528945 -406.72373) (xy 422.250883 -406.72373) (xy 422.250883 -406.723786)
			(xy 422.242811 -406.790722) (xy 422.22678 -406.856209) (xy 422.203021 -406.919304) (xy 422.171876 -406.9791)
			(xy 422.133793 -407.034734) (xy 422.111932 -407.0604) (xy 422.106145 -407.067551) (xy 422.099626 -407.084737)
			(xy 422.099232 -407.093928) (xy 422.099232 -407.251408) (xy 422.098722 -407.261513) (xy 422.090988 -407.280185)
			(xy 422.076699 -407.294479) (xy 422.058029 -407.302219) (xy 422.047924 -407.302716) (xy 421.331644 -407.302716)
			(xy 421.321526 -407.302248) (xy 421.302827 -407.294518) (xy 421.288512 -407.280217) (xy 421.280762 -407.261525)
			(xy 421.280336 -407.251408) (xy 421.280336 -407.093928) (xy 421.279904 -407.084743) (xy 421.273405 -407.067559)
			(xy 421.267636 -407.0604) (xy 421.245739 -407.034761) (xy 421.207649 -406.979124) (xy 421.176498 -406.919324)
			(xy 421.152734 -406.856224) (xy 421.1367 -406.790731) (xy 421.128626 -406.723789) (xy 414.525968 -406.723789)
			(xy 414.525968 -409.523827) (xy 418.928991 -409.523827) (xy 418.928995 -409.456519) (xy 418.937043 -409.389693)
			(xy 418.953021 -409.324308) (xy 418.9767 -409.261302) (xy 419.00774 -409.201577) (xy 419.045697 -409.145992)
			(xy 419.067488 -409.12034) (xy 419.073291 -409.113199) (xy 419.079802 -409.096005) (xy 419.080188 -409.086812)
			(xy 419.080188 -408.593544) (xy 419.079759 -408.584359) (xy 419.073259 -408.567174) (xy 419.067488 -408.560016)
			(xy 419.045691 -408.534371) (xy 419.007739 -408.478785) (xy 418.976704 -408.419061) (xy 418.953029 -408.356055)
			(xy 418.937055 -408.290671) (xy 418.929011 -408.223847) (xy 418.929012 -408.156541) (xy 418.937057 -408.089717)
			(xy 418.953033 -408.024333) (xy 418.976708 -407.961328) (xy 419.007745 -407.901605) (xy 419.045698 -407.84602)
			(xy 419.067488 -407.820368) (xy 419.073279 -407.813219) (xy 419.079797 -407.796031) (xy 419.080188 -407.78684)
			(xy 419.080188 -407.628852) (xy 419.080582 -407.618696) (xy 419.088391 -407.599945) (xy 419.102796 -407.585624)
			(xy 419.121592 -407.577924) (xy 419.13175 -407.577544) (xy 419.84803 -407.577544) (xy 419.858159 -407.578002)
			(xy 419.876882 -407.58574) (xy 419.891237 -407.600035) (xy 419.899055 -407.618725) (xy 419.899592 -407.628852)
			(xy 419.899592 -407.78684) (xy 419.899985 -407.796029) (xy 419.906511 -407.813213) (xy 419.912292 -407.820368)
			(xy 419.934071 -407.846027) (xy 419.972018 -407.901613) (xy 420.00305 -407.961336) (xy 420.026722 -408.02434)
			(xy 420.042694 -408.089721) (xy 420.050739 -408.156542) (xy 420.050739 -408.223846) (xy 420.042697 -408.290667)
			(xy 420.026725 -408.356049) (xy 420.003055 -408.419053) (xy 419.972024 -408.478776) (xy 419.934078 -408.534363)
			(xy 419.912292 -408.560016) (xy 419.906505 -408.567168) (xy 419.899985 -408.584353) (xy 419.899592 -408.593544)
			(xy 419.899592 -409.086812) (xy 419.899998 -409.096) (xy 419.906515 -409.113184) (xy 419.912292 -409.12034)
			(xy 419.934043 -409.146022) (xy 419.971991 -409.201605) (xy 420.003024 -409.261324) (xy 420.026698 -409.324325)
			(xy 420.042672 -409.389703) (xy 420.050719 -409.456522) (xy 420.050722 -409.523824) (xy 420.042682 -409.590643)
			(xy 420.026714 -409.656023) (xy 420.003047 -409.719026) (xy 419.972019 -409.778749) (xy 419.934077 -409.834336)
			(xy 419.912292 -409.859988) (xy 419.906475 -409.867118) (xy 419.899973 -409.88432) (xy 419.899592 -409.893516)
			(xy 419.899592 -410.051504) (xy 419.899181 -410.061659) (xy 419.891383 -410.080413) (xy 419.876983 -410.094737)
			(xy 419.858187 -410.102435) (xy 419.84803 -410.102812) (xy 419.13175 -410.102812) (xy 419.121633 -410.102234)
			(xy 419.102923 -410.094532) (xy 419.088567 -410.080274) (xy 419.080736 -410.061618) (xy 419.080188 -410.051504)
			(xy 419.080188 -409.893516) (xy 419.079773 -409.884329) (xy 419.073263 -409.867145) (xy 419.067488 -409.859988)
			(xy 419.045663 -409.834366) (xy 419.007713 -409.778776) (xy 418.976678 -409.719049) (xy 418.953005 -409.65604)
			(xy 418.937033 -409.590654) (xy 418.928991 -409.523827) (xy 414.525968 -409.523827) (xy 414.525968 -410.623701)
			(xy 421.128637 -410.623701) (xy 421.128638 -410.556275) (xy 421.136716 -410.489335) (xy 421.152755 -410.423845)
			(xy 421.176522 -410.360747) (xy 421.207677 -410.300951) (xy 421.24577 -410.245317) (xy 421.267636 -410.219652)
			(xy 421.27344 -410.212512) (xy 421.279949 -410.195317) (xy 421.280336 -410.186124) (xy 421.280336 -409.693872)
			(xy 421.279931 -409.684684) (xy 421.273413 -409.667501) (xy 421.267636 -409.660344) (xy 421.245783 -409.63467)
			(xy 421.207691 -409.579037) (xy 421.176538 -409.519243) (xy 421.152771 -409.456147) (xy 421.136734 -409.390659)
			(xy 421.128657 -409.323721) (xy 421.128656 -409.256297) (xy 421.136731 -409.189359) (xy 421.152766 -409.12387)
			(xy 421.176531 -409.060774) (xy 421.207682 -409.000978) (xy 421.245771 -408.945345) (xy 421.267636 -408.91968)
			(xy 421.273428 -408.912532) (xy 421.279945 -408.895343) (xy 421.280336 -408.886152) (xy 421.280336 -408.728672)
			(xy 421.280694 -408.718543) (xy 421.288458 -408.699832) (xy 421.302793 -408.685517) (xy 421.321515 -408.67778)
			(xy 421.331644 -408.677364) (xy 422.047924 -408.677364) (xy 422.05803 -408.677864) (xy 422.076702 -408.685603)
			(xy 422.090994 -408.699895) (xy 422.098735 -408.718566) (xy 422.099232 -408.728672) (xy 422.099232 -408.886152)
			(xy 422.09968 -408.895335) (xy 422.106169 -408.912519) (xy 422.111932 -408.91968) (xy 422.133807 -408.945336)
			(xy 422.171893 -409.000973) (xy 422.203041 -409.06077) (xy 422.226803 -409.123868) (xy 422.242837 -409.189358)
			(xy 422.250911 -409.256297) (xy 422.25091 -409.323721) (xy 422.242834 -409.39066) (xy 422.226798 -409.456149)
			(xy 422.203034 -409.519246) (xy 422.200617 -409.523886) (xy 423.328784 -409.523886) (xy 423.328787 -409.45646)
			(xy 423.336866 -409.389519) (xy 423.352905 -409.324029) (xy 423.376672 -409.26093) (xy 423.407826 -409.201133)
			(xy 423.445918 -409.145498) (xy 423.467784 -409.119832) (xy 423.47359 -409.112693) (xy 423.4801 -409.095498)
			(xy 423.480484 -409.086304) (xy 423.480484 -408.594052) (xy 423.480052 -408.584867) (xy 423.473554 -408.567682)
			(xy 423.467784 -408.560524) (xy 423.445913 -408.534865) (xy 423.407825 -408.479229) (xy 423.376676 -408.419432)
			(xy 423.352913 -408.356334) (xy 423.336878 -408.290845) (xy 423.328803 -408.223906) (xy 423.328804 -408.156482)
			(xy 423.336881 -408.089543) (xy 423.352916 -408.024054) (xy 423.376681 -407.960957) (xy 423.407832 -407.901161)
			(xy 423.44592 -407.845526) (xy 423.467784 -407.81986) (xy 423.473578 -407.812713) (xy 423.480095 -407.795524)
			(xy 423.480484 -407.786332) (xy 423.480484 -407.628852) (xy 423.480946 -407.618742) (xy 423.488696 -407.600066)
			(xy 423.503 -407.585774) (xy 423.521682 -407.578038) (xy 423.531792 -407.577544) (xy 424.248072 -407.577544)
			(xy 424.258172 -407.578106) (xy 424.276839 -407.585825) (xy 424.291133 -407.600097) (xy 424.298879 -407.618753)
			(xy 424.29938 -407.628852) (xy 424.29938 -407.786332) (xy 424.299779 -407.79552) (xy 424.306301 -407.812704)
			(xy 424.31208 -407.81986) (xy 424.333937 -407.845531) (xy 424.372027 -407.901165) (xy 424.403179 -407.96096)
			(xy 424.426945 -408.024056) (xy 424.442981 -408.089544) (xy 424.451058 -408.156482) (xy 424.451059 -408.223906)
			(xy 424.442984 -408.290844) (xy 424.426948 -408.356333) (xy 424.403184 -408.419429) (xy 424.372033 -408.479225)
			(xy 424.333944 -408.534859) (xy 424.31208 -408.560524) (xy 424.306288 -408.567673) (xy 424.299771 -408.584861)
			(xy 424.29938 -408.594052) (xy 424.29938 -409.086304) (xy 424.299792 -409.095491) (xy 424.306305 -409.112675)
			(xy 424.31208 -409.119832) (xy 424.333909 -409.145526) (xy 424.372 -409.201156) (xy 424.403154 -409.260948)
			(xy 424.426921 -409.324041) (xy 424.442959 -409.389527) (xy 424.451039 -409.456462) (xy 424.451042 -409.523884)
			(xy 424.442969 -409.59082) (xy 424.426937 -409.656307) (xy 424.403176 -409.719403) (xy 424.372028 -409.779198)
			(xy 424.333943 -409.834831) (xy 424.31208 -409.860496) (xy 424.3063 -409.867653) (xy 424.299776 -409.884835)
			(xy 424.29938 -409.894024) (xy 424.29938 -410.051504) (xy 424.298987 -410.061629) (xy 424.291234 -410.080337)
			(xy 424.27691 -410.094651) (xy 424.258197 -410.102393) (xy 424.248072 -410.102812) (xy 423.531792 -410.102812)
			(xy 423.521684 -410.102322) (xy 423.503008 -410.094584) (xy 423.488714 -410.080288) (xy 423.480978 -410.061612)
			(xy 423.480484 -410.051504) (xy 423.480484 -409.894024) (xy 423.480066 -409.884838) (xy 423.473558 -409.867653)
			(xy 423.467784 -409.860496) (xy 423.445885 -409.83486) (xy 423.407799 -409.779221) (xy 423.37665 -409.71942)
			(xy 423.352889 -409.65632) (xy 423.336856 -409.590827) (xy 423.328784 -409.523886) (xy 422.200617 -409.523886)
			(xy 422.171884 -409.579043) (xy 422.133796 -409.634678) (xy 422.111932 -409.660344) (xy 422.106126 -409.667482)
			(xy 422.099619 -409.684678) (xy 422.099232 -409.693872) (xy 422.099232 -410.186124) (xy 422.099646 -410.19531)
			(xy 422.106159 -410.212494) (xy 422.111932 -410.219652) (xy 422.133779 -410.245331) (xy 422.171866 -410.300964)
			(xy 422.203016 -410.360759) (xy 422.22678 -410.423854) (xy 422.242815 -410.489341) (xy 422.250892 -410.556277)
			(xy 422.250893 -410.623641) (xy 425.528957 -410.623641) (xy 425.528958 -410.556335) (xy 425.537003 -410.489512)
			(xy 425.552978 -410.424129) (xy 425.576652 -410.361123) (xy 425.607686 -410.301399) (xy 425.645636 -410.245812)
			(xy 425.667424 -410.22016) (xy 425.673223 -410.213017) (xy 425.679735 -410.195825) (xy 425.680124 -410.186632)
			(xy 425.680124 -409.693364) (xy 425.679726 -409.684176) (xy 425.673203 -409.666992) (xy 425.667424 -409.659836)
			(xy 425.645648 -409.634174) (xy 425.6077 -409.578589) (xy 425.576667 -409.518866) (xy 425.552994 -409.455863)
			(xy 425.537021 -409.390482) (xy 425.528976 -409.323661) (xy 425.528975 -409.256357) (xy 425.537018 -409.189536)
			(xy 425.552989 -409.124154) (xy 425.57666 -409.06115) (xy 425.607691 -409.001427) (xy 425.645637 -408.94584)
			(xy 425.667424 -408.920188) (xy 425.673211 -408.913036) (xy 425.679731 -408.895851) (xy 425.680124 -408.88666)
			(xy 425.680124 -408.728672) (xy 425.680499 -408.718513) (xy 425.688308 -408.699755) (xy 425.70272 -408.685432)
			(xy 425.721525 -408.677738) (xy 425.731686 -408.677364) (xy 426.447966 -408.677364) (xy 426.458093 -408.677855)
			(xy 426.476818 -408.685576) (xy 426.491177 -408.699862) (xy 426.498993 -408.718547) (xy 426.499528 -408.728672)
			(xy 426.499528 -408.88666) (xy 426.499951 -408.895846) (xy 426.506455 -408.913031) (xy 426.512228 -408.920188)
			(xy 426.534028 -408.94583) (xy 426.571979 -409.001417) (xy 426.603014 -409.061142) (xy 426.626687 -409.124148)
			(xy 426.64266 -409.189532) (xy 426.650704 -409.256356) (xy 426.650703 -409.323662) (xy 426.642657 -409.390486)
			(xy 426.626682 -409.45587) (xy 426.603006 -409.518875) (xy 426.600433 -409.523827) (xy 427.729079 -409.523827)
			(xy 427.729082 -409.456519) (xy 427.73713 -409.389693) (xy 427.753108 -409.324308) (xy 427.776786 -409.261302)
			(xy 427.807826 -409.201578) (xy 427.845781 -409.145992) (xy 427.867572 -409.12034) (xy 427.873385 -409.113207)
			(xy 427.879888 -409.096007) (xy 427.880272 -409.086812) (xy 427.880272 -408.593544) (xy 427.879847 -408.584358)
			(xy 427.873344 -408.567174) (xy 427.867572 -408.560016) (xy 427.845776 -408.534371) (xy 427.807825 -408.478784)
			(xy 427.77679 -408.41906) (xy 427.753116 -408.356054) (xy 427.737143 -408.290671) (xy 427.729099 -408.223847)
			(xy 427.7291 -408.156541) (xy 427.737145 -408.089717) (xy 427.75312 -408.024334) (xy 427.776795 -407.961329)
			(xy 427.807831 -407.901606) (xy 427.845783 -407.84602) (xy 427.867572 -407.820368) (xy 427.873373 -407.813227)
			(xy 427.879883 -407.796033) (xy 427.880272 -407.78684) (xy 427.880272 -407.628852) (xy 427.880682 -407.618698)
			(xy 427.888488 -407.59995) (xy 427.902887 -407.58563) (xy 427.921678 -407.577927) (xy 427.931834 -407.577544)
			(xy 428.648114 -407.577544) (xy 428.658242 -407.578015) (xy 428.676964 -407.585749) (xy 428.69132 -407.600039)
			(xy 428.699138 -407.618726) (xy 428.699676 -407.628852) (xy 428.699676 -407.78684) (xy 428.700072 -407.796029)
			(xy 428.706596 -407.813212) (xy 428.712376 -407.820368) (xy 428.734155 -407.846027) (xy 428.772104 -407.901613)
			(xy 428.803136 -407.961335) (xy 428.826809 -408.024339) (xy 428.842782 -408.08972) (xy 428.850827 -408.156542)
			(xy 428.850827 -408.223846) (xy 428.842784 -408.290668) (xy 428.826813 -408.356049) (xy 428.803141 -408.419054)
			(xy 428.77211 -408.478777) (xy 428.734163 -408.534364) (xy 428.712376 -408.560016) (xy 428.706587 -408.567167)
			(xy 428.700069 -408.584353) (xy 428.699676 -408.593544) (xy 428.699676 -409.086812) (xy 428.700086 -409.095999)
			(xy 428.7066 -409.113183) (xy 428.712376 -409.12034) (xy 428.734128 -409.146022) (xy 428.772077 -409.201604)
			(xy 428.803111 -409.261324) (xy 428.826785 -409.324324) (xy 428.84276 -409.389703) (xy 428.850806 -409.456522)
			(xy 428.85081 -409.523824) (xy 428.842769 -409.590644) (xy 428.826801 -409.656024) (xy 428.803133 -409.719027)
			(xy 428.772104 -409.778749) (xy 428.734161 -409.834335) (xy 428.712376 -409.859988) (xy 428.706557 -409.867117)
			(xy 428.700056 -409.88432) (xy 428.699676 -409.893516) (xy 428.699676 -410.051504) (xy 428.699281 -410.061661)
			(xy 428.69148 -410.080418) (xy 428.677074 -410.094742) (xy 428.658274 -410.102438) (xy 428.648114 -410.102812)
			(xy 427.931834 -410.102812) (xy 427.921716 -410.102247) (xy 427.903005 -410.09454) (xy 427.88865 -410.080278)
			(xy 427.88082 -410.061619) (xy 427.880272 -410.051504) (xy 427.880272 -409.893516) (xy 427.879861 -409.884329)
			(xy 427.873349 -409.867144) (xy 427.867572 -409.859988) (xy 427.845748 -409.834366) (xy 427.807798 -409.778776)
			(xy 427.776764 -409.719048) (xy 427.753092 -409.65604) (xy 427.73712 -409.590654) (xy 427.729079 -409.523827)
			(xy 426.600433 -409.523827) (xy 426.57197 -409.578598) (xy 426.534017 -409.634184) (xy 426.512228 -409.659836)
			(xy 426.506425 -409.666976) (xy 426.499916 -409.684171) (xy 426.499528 -409.693364) (xy 426.499528 -410.186632)
			(xy 426.499917 -410.195822) (xy 426.506445 -410.213006) (xy 426.512228 -410.22016) (xy 426.534001 -410.245825)
			(xy 426.571952 -410.301409) (xy 426.602988 -410.36113) (xy 426.626663 -410.424133) (xy 426.642638 -410.489514)
			(xy 426.650684 -410.556336) (xy 426.650686 -410.62364) (xy 426.650679 -410.623701) (xy 429.928725 -410.623701)
			(xy 429.928726 -410.556275) (xy 429.936804 -410.489336) (xy 429.952842 -410.423845) (xy 429.976609 -410.360748)
			(xy 430.007762 -410.300951) (xy 430.045854 -410.245317) (xy 430.06772 -410.219652) (xy 430.073522 -410.212511)
			(xy 430.080033 -410.195317) (xy 430.08042 -410.186124) (xy 430.08042 -409.693872) (xy 430.080019 -409.684684)
			(xy 430.073498 -409.6675) (xy 430.06772 -409.660344) (xy 430.045867 -409.634669) (xy 430.007777 -409.579037)
			(xy 429.976624 -409.519242) (xy 429.952859 -409.456146) (xy 429.936822 -409.390658) (xy 429.928745 -409.323721)
			(xy 429.928744 -409.256297) (xy 429.936819 -409.18936) (xy 429.952853 -409.123871) (xy 429.976617 -409.060775)
			(xy 430.007767 -409.000979) (xy 430.045856 -408.945345) (xy 430.06772 -408.91968) (xy 430.07351 -408.91253)
			(xy 430.080028 -408.895343) (xy 430.08042 -408.886152) (xy 430.08042 -408.728672) (xy 430.080863 -408.718559)
			(xy 430.088613 -408.699876) (xy 430.102923 -408.685582) (xy 430.121614 -408.677852) (xy 430.131728 -408.677364)
			(xy 430.848008 -408.677364) (xy 430.858113 -408.677878) (xy 430.876784 -408.685611) (xy 430.891077 -408.699899)
			(xy 430.898818 -408.718567) (xy 430.899316 -408.728672) (xy 430.899316 -408.886152) (xy 430.899745 -408.895337)
			(xy 430.906245 -408.912522) (xy 430.912016 -408.91968) (xy 430.933891 -408.945336) (xy 430.971979 -409.000972)
			(xy 431.003128 -409.06077) (xy 431.026891 -409.123868) (xy 431.042925 -409.189358) (xy 431.050999 -409.256297)
			(xy 431.050998 -409.323721) (xy 431.042922 -409.39066) (xy 431.026885 -409.456149) (xy 431.00312 -409.519247)
			(xy 431.000734 -409.523827) (xy 432.12887 -409.523827) (xy 432.128873 -409.456519) (xy 432.136921 -409.389693)
			(xy 432.152898 -409.324309) (xy 432.176576 -409.261303) (xy 432.207615 -409.201578) (xy 432.245569 -409.145992)
			(xy 432.26736 -409.12034) (xy 432.273172 -409.113206) (xy 432.279676 -409.096007) (xy 432.28006 -409.086812)
			(xy 432.28006 -408.593544) (xy 432.279615 -408.584361) (xy 432.273124 -408.567177) (xy 432.26736 -408.560016)
			(xy 432.245564 -408.53437) (xy 432.207614 -408.478784) (xy 432.17658 -408.419059) (xy 432.152907 -408.356054)
			(xy 432.136934 -408.290671) (xy 432.12889 -408.223847) (xy 432.128891 -408.156541) (xy 432.136936 -408.089717)
			(xy 432.15291 -408.024335) (xy 432.176585 -407.96133) (xy 432.20762 -407.901606) (xy 432.245571 -407.84602)
			(xy 432.26736 -407.820368) (xy 432.27316 -407.813226) (xy 432.279671 -407.796033) (xy 432.28006 -407.78684)
			(xy 432.28006 -407.628852) (xy 432.280482 -407.6187) (xy 432.288286 -407.599954) (xy 432.302681 -407.585634)
			(xy 432.321468 -407.577929) (xy 432.331622 -407.577544) (xy 433.047902 -407.577544) (xy 433.058029 -407.578025)
			(xy 433.076751 -407.585754) (xy 433.091108 -407.600042) (xy 433.098926 -407.618727) (xy 433.099464 -407.628852)
			(xy 433.099464 -407.78684) (xy 433.099863 -407.796028) (xy 433.106385 -407.813212) (xy 433.112164 -407.820368)
			(xy 433.133944 -407.846027) (xy 433.171893 -407.901612) (xy 433.202926 -407.961335) (xy 433.226599 -408.024339)
			(xy 433.242573 -408.08972) (xy 433.250618 -408.156542) (xy 433.250618 -408.223846) (xy 433.242575 -408.290668)
			(xy 433.226603 -408.35605) (xy 433.202931 -408.419054) (xy 433.171899 -408.478778) (xy 433.133951 -408.534364)
			(xy 433.112164 -408.560016) (xy 433.106374 -408.567165) (xy 433.099856 -408.584353) (xy 433.099464 -408.593544)
			(xy 433.099464 -409.086812) (xy 433.099876 -409.095999) (xy 433.106389 -409.113183) (xy 433.112164 -409.12034)
			(xy 433.133916 -409.146021) (xy 433.171866 -409.201604) (xy 433.2029 -409.261323) (xy 433.226575 -409.324324)
			(xy 433.24255 -409.389703) (xy 433.250597 -409.456522) (xy 433.250601 -409.523824) (xy 433.24256 -409.590644)
			(xy 433.226591 -409.656024) (xy 433.202922 -409.719027) (xy 433.171894 -409.77875) (xy 433.133949 -409.834336)
			(xy 433.112164 -409.859988) (xy 433.106343 -409.867116) (xy 433.099844 -409.88432) (xy 433.099464 -409.893516)
			(xy 433.099464 -410.051504) (xy 433.099081 -410.061663) (xy 433.091277 -410.080422) (xy 433.076868 -410.094747)
			(xy 433.058063 -410.10244) (xy 433.047902 -410.102812) (xy 432.331622 -410.102812) (xy 432.321503 -410.102257)
			(xy 432.302792 -410.094546) (xy 432.288437 -410.080281) (xy 432.280608 -410.06162) (xy 432.28006 -410.051504)
			(xy 432.28006 -409.893516) (xy 432.279629 -409.884331) (xy 432.273128 -409.867147) (xy 432.26736 -409.859988)
			(xy 432.245536 -409.834365) (xy 432.207587 -409.778775) (xy 432.176554 -409.719048) (xy 432.152882 -409.656039)
			(xy 432.136911 -409.590653) (xy 432.12887 -409.523827) (xy 431.000734 -409.523827) (xy 430.971969 -409.579043)
			(xy 430.93388 -409.634678) (xy 430.912016 -409.660344) (xy 430.90622 -409.66749) (xy 430.899705 -409.68468)
			(xy 430.899316 -409.693872) (xy 430.899316 -410.186124) (xy 430.899711 -410.195313) (xy 430.906235 -410.212497)
			(xy 430.912016 -410.219652) (xy 430.933864 -410.24533) (xy 430.971952 -410.300963) (xy 431.003102 -410.360758)
			(xy 431.026867 -410.423853) (xy 431.042903 -410.48934) (xy 431.05098 -410.556277) (xy 431.050981 -410.623641)
			(xy 434.329044 -410.623641) (xy 434.329046 -410.556335) (xy 434.337091 -410.489512) (xy 434.353065 -410.424129)
			(xy 434.376738 -410.361124) (xy 434.407772 -410.3014) (xy 434.44572 -410.245813) (xy 434.467508 -410.22016)
			(xy 434.473305 -410.213015) (xy 434.479819 -410.195824) (xy 434.480208 -410.186632) (xy 434.480208 -409.693364)
			(xy 434.479814 -409.684175) (xy 434.473289 -409.666991) (xy 434.467508 -409.659836) (xy 434.445733 -409.634174)
			(xy 434.407786 -409.578588) (xy 434.376754 -409.518866) (xy 434.353082 -409.455862) (xy 434.337109 -409.390482)
			(xy 434.329064 -409.323661) (xy 434.329063 -409.256357) (xy 434.337106 -409.189536) (xy 434.353076 -409.124155)
			(xy 434.376746 -409.061151) (xy 434.407777 -409.001427) (xy 434.445722 -408.945841) (xy 434.467508 -408.920188)
			(xy 434.473293 -408.913035) (xy 434.479814 -408.89585) (xy 434.480208 -408.88666) (xy 434.480208 -408.728672)
			(xy 434.480599 -408.718515) (xy 434.488405 -408.69976) (xy 434.502811 -408.685438) (xy 434.521611 -408.67774)
			(xy 434.53177 -408.677364) (xy 435.24805 -408.677364) (xy 435.258176 -408.677868) (xy 435.276901 -408.685584)
			(xy 435.29126 -408.699866) (xy 435.299077 -408.718548) (xy 435.299612 -408.728672) (xy 435.299612 -408.88666)
			(xy 435.300039 -408.895846) (xy 435.30654 -408.91303) (xy 435.312312 -408.920188) (xy 435.334113 -408.94583)
			(xy 435.372065 -409.001417) (xy 435.4031 -409.061141) (xy 435.426774 -409.124147) (xy 435.442748 -409.189531)
			(xy 435.450792 -409.256356) (xy 435.450791 -409.323662) (xy 435.442745 -409.390487) (xy 435.426769 -409.45587)
			(xy 435.403093 -409.518875) (xy 435.372055 -409.578599) (xy 435.334102 -409.634184) (xy 435.312312 -409.659836)
			(xy 435.306519 -409.666984) (xy 435.300002 -409.684172) (xy 435.299612 -409.693364) (xy 435.299612 -410.186632)
			(xy 435.300004 -410.195821) (xy 435.30653 -410.213006) (xy 435.312312 -410.22016) (xy 435.334085 -410.245824)
			(xy 435.372038 -410.301408) (xy 435.403075 -410.361129) (xy 435.42675 -410.424132) (xy 435.442726 -410.489514)
			(xy 435.450772 -410.556336) (xy 435.450774 -410.62364) (xy 435.44273 -410.690463) (xy 435.426758 -410.755845)
			(xy 435.403084 -410.818849) (xy 435.37205 -410.878571) (xy 435.3341 -410.934157) (xy 435.312312 -410.959808)
			(xy 435.306531 -410.966964) (xy 435.300007 -410.984146) (xy 435.299612 -410.993336) (xy 435.299612 -411.151324)
			(xy 435.299198 -411.161478) (xy 435.291397 -411.180229) (xy 435.276998 -411.194551) (xy 435.258206 -411.202252)
			(xy 435.24805 -411.202632) (xy 434.53177 -411.202632) (xy 434.521638 -411.202197) (xy 434.502911 -411.194454)
			(xy 434.488554 -411.180152) (xy 434.480741 -411.161454) (xy 434.480208 -411.151324) (xy 434.480208 -410.993336)
			(xy 434.479779 -410.984151) (xy 434.473278 -410.966966) (xy 434.467508 -410.959808) (xy 434.445706 -410.934168)
			(xy 434.407759 -410.878579) (xy 434.376728 -410.818854) (xy 434.353058 -410.755848) (xy 434.337087 -410.690464)
			(xy 434.329044 -410.623641) (xy 431.050981 -410.623641) (xy 431.050981 -410.623699) (xy 431.042907 -410.690636)
			(xy 431.026874 -410.756124) (xy 431.003112 -410.81922) (xy 430.971964 -410.879016) (xy 430.933878 -410.934651)
			(xy 430.912016 -410.960316) (xy 430.906232 -410.96747) (xy 430.899709 -410.984654) (xy 430.899316 -410.993844)
			(xy 430.899316 -411.151324) (xy 430.898835 -411.161432) (xy 430.891092 -411.180108) (xy 430.876795 -411.194401)
			(xy 430.858116 -411.202138) (xy 430.848008 -411.202632) (xy 430.131728 -411.202632) (xy 430.121611 -411.202162)
			(xy 430.102914 -411.194429) (xy 430.0886 -411.180129) (xy 430.080848 -411.16144) (xy 430.08042 -411.151324)
			(xy 430.08042 -410.993844) (xy 430.079984 -410.98466) (xy 430.073488 -410.967475) (xy 430.06772 -410.960316)
			(xy 430.04584 -410.934664) (xy 430.00775 -410.879028) (xy 429.976599 -410.81923) (xy 429.952835 -410.756132)
			(xy 429.9368 -410.690641) (xy 429.928725 -410.623701) (xy 426.650679 -410.623701) (xy 426.642643 -410.690462)
			(xy 426.62667 -410.755844) (xy 426.602998 -410.818848) (xy 426.571965 -410.878571) (xy 426.534016 -410.934156)
			(xy 426.512228 -410.959808) (xy 426.506437 -410.966957) (xy 426.499921 -410.984145) (xy 426.499528 -410.993336)
			(xy 426.499528 -411.151324) (xy 426.499099 -411.161476) (xy 426.4913 -411.180224) (xy 426.476907 -411.194545)
			(xy 426.45812 -411.202249) (xy 426.447966 -411.202632) (xy 425.731686 -411.202632) (xy 425.721555 -411.202184)
			(xy 425.702828 -411.194446) (xy 425.688472 -411.180148) (xy 425.680658 -411.161453) (xy 425.680124 -411.151324)
			(xy 425.680124 -410.993336) (xy 425.679691 -410.984151) (xy 425.673193 -410.966967) (xy 425.667424 -410.959808)
			(xy 425.645621 -410.934169) (xy 425.607674 -410.87858) (xy 425.576642 -410.818855) (xy 425.552971 -410.755848)
			(xy 425.536999 -410.690465) (xy 425.528957 -410.623641) (xy 422.250893 -410.623641) (xy 422.250893 -410.623699)
			(xy 422.242819 -410.690635) (xy 422.226787 -410.756123) (xy 422.203026 -410.819219) (xy 422.171879 -410.879015)
			(xy 422.133794 -410.93465) (xy 422.111932 -410.960316) (xy 422.106138 -410.967463) (xy 422.099624 -410.984652)
			(xy 422.099232 -410.993844) (xy 422.099232 -411.151324) (xy 422.098735 -411.16143) (xy 422.090996 -411.180103)
			(xy 422.076703 -411.194396) (xy 422.05803 -411.202135) (xy 422.047924 -411.202632) (xy 421.331644 -411.202632)
			(xy 421.321528 -411.202149) (xy 421.302832 -411.194421) (xy 421.288517 -411.180125) (xy 421.280765 -411.161439)
			(xy 421.280336 -411.151324) (xy 421.280336 -410.993844) (xy 421.279896 -410.98466) (xy 421.273402 -410.967476)
			(xy 421.267636 -410.960316) (xy 421.245755 -410.934664) (xy 421.207664 -410.879029) (xy 421.176512 -410.819231)
			(xy 421.152748 -410.756132) (xy 421.136712 -410.690641) (xy 421.128637 -410.623701) (xy 414.525968 -410.623701)
			(xy 414.525968 -417.366196) (xy 414.52546 -417.366196) (xy 414.52546 -417.533836) (xy 414.525117 -417.545925)
			(xy 414.517634 -417.568917) (xy 414.503411 -417.588471) (xy 414.483842 -417.602672) (xy 414.460842 -417.61013)
			(xy 414.448752 -417.610544) (xy 401.15109 -417.610544) (xy 401.138998 -417.610101) (xy 401.115995 -417.602639)
			(xy 401.096414 -417.588447) (xy 401.082164 -417.568908) (xy 401.074635 -417.545926) (xy 401.074128 -417.533836)
			(xy 326.525636 -417.533836) (xy 326.525172 -417.545885) (xy 326.517733 -417.568805) (xy 326.503592 -417.588317)
			(xy 326.484126 -417.602521) (xy 326.461229 -417.610032) (xy 326.449182 -417.610544) (xy 313.151012 -417.610544)
			(xy 313.138942 -417.610026) (xy 313.115981 -417.602571) (xy 313.096447 -417.588387) (xy 313.082251 -417.568862)
			(xy 313.074781 -417.545906) (xy 313.074304 -417.533836) (xy 313.074304 -417.379404) (xy 313.073796 -417.379404)
			(xy 273.434939 -417.379404) (xy 273.506495 -417.442585) (xy 273.605798 -417.540617) (xy 273.652996 -417.592002)
			(xy 273.691387 -417.633573) (xy 273.773525 -417.71142) (xy 273.861325 -417.782821) (xy 273.954282 -417.847364)
			(xy 274.051862 -417.90468) (xy 274.153504 -417.954438) (xy 274.258623 -417.996352) (xy 274.366616 -418.030181)
			(xy 274.476862 -418.055732) (xy 274.588726 -418.072856) (xy 274.701566 -418.081457) (xy 274.75815 -418.081968)
			(xy 465.600034 -418.081968) (xy 465.65584 -418.081445) (xy 465.767139 -418.073102) (xy 465.877504 -418.056464)
			(xy 465.986317 -418.031626) (xy 466.092969 -417.998726) (xy 466.196865 -417.957947) (xy 466.297422 -417.909518)
			(xy 466.39408 -417.85371) (xy 466.486296 -417.790835) (xy 466.573556 -417.721245) (xy 466.655372 -417.645328)
			(xy 466.731285 -417.563509) (xy 466.800872 -417.476246) (xy 466.863743 -417.384027) (xy 466.919547 -417.287367)
			(xy 466.967972 -417.186808) (xy 467.008746 -417.082911) (xy 467.041642 -416.976257) (xy 467.066476 -416.867443)
			(xy 467.083109 -416.757078) (xy 467.091447 -416.645778) (xy 467.09203 -416.589972) (xy 467.09203 -246.48795)
			(xy 467.091546 -246.4347) (xy 467.083933 -246.328473) (xy 467.068764 -246.223059) (xy 467.046116 -246.118995)
			(xy 467.016104 -246.016811) (xy 466.978881 -245.917028) (xy 466.934637 -245.820154) (xy 466.883597 -245.726681)
			(xy 466.82602 -245.637087) (xy 466.762201 -245.551827) (xy 466.692464 -245.471335) (xy 466.65515 -245.433342)
			(xy 464.026504 -242.80495) (xy 463.9771 -242.754859) (xy 463.883341 -242.649941) (xy 463.795613 -242.53993)
			(xy 463.714192 -242.425173) (xy 463.639333 -242.306031) (xy 463.571273 -242.182879) (xy 463.510225 -242.056105)
			(xy 463.456381 -241.926107) (xy 463.409911 -241.793295) (xy 463.370962 -241.658086) (xy 463.339655 -241.520905)
			(xy 463.31609 -241.382185) (xy 463.300339 -241.242362) (xy 463.292454 -241.101876) (xy 463.291936 -241.031522)
			(xy 463.291936 -87.588344) (xy 463.292417 -87.517998) (xy 463.3003 -87.377526) (xy 463.316048 -87.237717)
			(xy 463.339614 -87.099011) (xy 463.370921 -86.961846) (xy 463.409872 -86.826652) (xy 463.456344 -86.693856)
			(xy 463.510191 -86.563875) (xy 463.571243 -86.437119) (xy 463.639308 -86.313987) (xy 463.714172 -86.194865)
			(xy 463.7956 -86.08013) (xy 463.883333 -85.970143) (xy 463.977098 -85.865249) (xy 464.026504 -85.81517)
			(xy 466.65515 -83.186524) (xy 466.692477 -83.148543) (xy 466.762224 -83.068056) (xy 466.826051 -82.982799)
			(xy 466.883632 -82.893206) (xy 466.934676 -82.799733) (xy 466.978921 -82.702856) (xy 467.016141 -82.60307)
			(xy 467.046149 -82.500883) (xy 467.068789 -82.396815) (xy 467.083947 -82.291397) (xy 467.091547 -82.185167)
			(xy 467.09203 -82.131916) (xy 467.09203 -1.999996) (xy 467.091508 -1.944189) (xy 467.083167 -1.832886)
			(xy 467.066532 -1.722518) (xy 467.041695 -1.613701) (xy 467.008796 -1.507045) (xy 466.968019 -1.403146)
			(xy 466.919592 -1.302584) (xy 466.863785 -1.205923) (xy 466.800911 -1.113702) (xy 466.731321 -1.026437)
			(xy 466.655404 -0.944617) (xy 466.573586 -0.868699) (xy 466.486322 -0.799107) (xy 466.394103 -0.736231)
			(xy 466.297442 -0.680422) (xy 466.196882 -0.631993) (xy 466.092983 -0.591214) (xy 465.986328 -0.558313)
			(xy 465.877512 -0.533474) (xy 465.767144 -0.516836) (xy 465.655841 -0.508493) (xy 465.600034 -0.508)
			(xy 446.265046 -0.508) (xy 446.209237 -0.508508) (xy 446.097932 -0.516845) (xy 445.987561 -0.533478)
			(xy 445.878741 -0.558312) (xy 445.772082 -0.591209) (xy 445.668179 -0.631985) (xy 445.567615 -0.680412)
			(xy 445.47095 -0.736218) (xy 445.378726 -0.799093) (xy 445.291459 -0.868683) (xy 445.209636 -0.944601)
			(xy 445.133716 -1.026421) (xy 445.064123 -1.113686) (xy 445.001245 -1.205908) (xy 444.945435 -1.30257)
			(xy 444.897005 -1.403134) (xy 444.856226 -1.507035) (xy 444.823325 -1.613693) (xy 444.798487 -1.722512)
			(xy 444.781851 -1.832882) (xy 444.773509 -1.944187) (xy 444.77305 -1.999996) (xy 444.77305 -11.850116)
			(xy 444.77258 -11.903957) (xy 444.764897 -12.011363) (xy 444.749571 -12.117948) (xy 444.726681 -12.223168)
			(xy 444.696342 -12.326487) (xy 444.65871 -12.427378) (xy 444.613976 -12.525327) (xy 444.562368 -12.619836)
			(xy 444.504149 -12.710422) (xy 444.439617 -12.796624) (xy 444.369099 -12.878002) (xy 444.292955 -12.954143)
			(xy 444.211574 -13.024657) (xy 444.125369 -13.089186) (xy 444.034781 -13.147401) (xy 443.94027 -13.199004)
			(xy 443.842319 -13.243734) (xy 443.741426 -13.281362) (xy 443.638106 -13.311696) (xy 443.532885 -13.334583)
			(xy 443.4263 -13.349904) (xy 443.318893 -13.357583) (xy 443.265052 -13.358114) (xy 435.265068 -13.358114)
			(xy 435.211227 -13.357632) (xy 435.103821 -13.349948) (xy 434.997236 -13.334622) (xy 434.892016 -13.311731)
			(xy 434.788697 -13.281392) (xy 434.687806 -13.24376) (xy 434.589856 -13.199026) (xy 434.495347 -13.147419)
			(xy 434.40476 -13.089201) (xy 434.318558 -13.024669) (xy 434.237178 -12.954153) (xy 434.161036 -12.87801)
			(xy 434.090521 -12.79663) (xy 434.02599 -12.710426) (xy 433.967773 -12.619839) (xy 433.916167 -12.52533)
			(xy 433.871434 -12.42738) (xy 433.833803 -12.326488) (xy 433.803465 -12.223169) (xy 433.780576 -12.117948)
			(xy 433.76525 -12.011363) (xy 433.757567 -11.903957) (xy 433.75707 -11.850116) (xy 433.75707 -1.999996)
			(xy 433.756561 -1.944189) (xy 433.748219 -1.832887) (xy 433.731584 -1.72252) (xy 433.706747 -1.613704)
			(xy 433.673847 -1.507049) (xy 433.633069 -1.40315) (xy 433.584641 -1.30259) (xy 433.528833 -1.20593)
			(xy 433.465958 -1.11371) (xy 433.396367 -1.026448) (xy 433.320449 -0.944629) (xy 433.23863 -0.868713)
			(xy 433.151366 -0.799124) (xy 433.059145 -0.736251) (xy 432.962484 -0.680445) (xy 432.861922 -0.632019)
			(xy 432.758023 -0.591243) (xy 432.651367 -0.558346) (xy 432.542551 -0.533511) (xy 432.432183 -0.516877)
			(xy 432.320881 -0.508538) (xy 432.265074 -0.508) (xy 420.265098 -0.508) (xy 420.209291 -0.508522)
			(xy 420.097989 -0.516863) (xy 419.987622 -0.533498) (xy 419.878806 -0.558335) (xy 419.772151 -0.591234)
			(xy 419.668252 -0.632011) (xy 419.567691 -0.680438) (xy 419.471031 -0.736245) (xy 419.378811 -0.79912)
			(xy 419.291547 -0.86871) (xy 419.209728 -0.944627) (xy 419.133811 -1.026446) (xy 419.064221 -1.113709)
			(xy 419.001346 -1.205929) (xy 418.945539 -1.302589) (xy 418.897112 -1.40315) (xy 418.856334 -1.507049)
			(xy 418.823435 -1.613704) (xy 418.798599 -1.72252) (xy 418.781963 -1.832887) (xy 418.773622 -1.944189)
			(xy 418.773102 -1.999996) (xy 418.773102 -11.850116) (xy 418.772621 -11.903957) (xy 418.764938 -12.011364)
			(xy 418.749612 -12.117949) (xy 418.726722 -12.22317) (xy 418.696384 -12.326489) (xy 418.658752 -12.427381)
			(xy 418.614019 -12.525332) (xy 418.562412 -12.619841) (xy 418.504194 -12.710429) (xy 418.439663 -12.796632)
			(xy 418.369146 -12.878012) (xy 418.293003 -12.954154) (xy 418.211622 -13.02467) (xy 418.125419 -13.089201)
			(xy 418.034831 -13.147418) (xy 417.940321 -13.199024) (xy 417.84237 -13.243756) (xy 417.741478 -13.281387)
			(xy 417.638158 -13.311725) (xy 417.532938 -13.334614) (xy 417.426352 -13.349939) (xy 417.318945 -13.357621)
			(xy 417.265104 -13.358114) (xy 409.26512 -13.358114) (xy 409.211278 -13.357646) (xy 409.103868 -13.349965)
			(xy 408.997279 -13.334641) (xy 408.892055 -13.311753) (xy 408.788733 -13.281416) (xy 408.687837 -13.243785)
			(xy 408.589884 -13.199053) (xy 408.495371 -13.147446) (xy 408.40478 -13.089229) (xy 408.318573 -13.024697)
			(xy 408.23719 -12.95418) (xy 408.161045 -12.878036) (xy 408.090526 -12.796655) (xy 408.025992 -12.71045)
			(xy 407.967772 -12.61986) (xy 407.916164 -12.525349) (xy 407.871429 -12.427396) (xy 407.833796 -12.326502)
			(xy 407.803456 -12.223179) (xy 407.780565 -12.117956) (xy 407.765239 -12.011368) (xy 407.757556 -11.903958)
			(xy 407.757122 -11.850116) (xy 407.757122 -1.999996) (xy 407.7566 -1.944189) (xy 407.748259 -1.832886)
			(xy 407.731624 -1.722518) (xy 407.706787 -1.613702) (xy 407.673888 -1.507046) (xy 407.633111 -1.403147)
			(xy 407.584684 -1.302586) (xy 407.528877 -1.205924) (xy 407.466002 -1.113704) (xy 407.396412 -1.02644)
			(xy 407.320496 -0.94462) (xy 407.238677 -0.868702) (xy 407.151414 -0.799111) (xy 407.059194 -0.736235)
			(xy 406.962534 -0.680427) (xy 406.861973 -0.631998) (xy 406.758075 -0.591219) (xy 406.651419 -0.558319)
			(xy 406.542603 -0.53348) (xy 406.432236 -0.516843) (xy 406.320933 -0.508501) (xy 406.265126 -0.508)
			(xy 394.264896 -0.508) (xy 394.209089 -0.508522) (xy 394.097787 -0.516863) (xy 393.98742 -0.533498)
			(xy 393.878604 -0.558335) (xy 393.771949 -0.591234) (xy 393.668051 -0.632011) (xy 393.56749 -0.680439)
			(xy 393.470829 -0.736246) (xy 393.37861 -0.799121) (xy 393.291346 -0.868711) (xy 393.209528 -0.944628)
			(xy 393.133611 -1.026446) (xy 393.064021 -1.11371) (xy 393.001146 -1.205929) (xy 392.945339 -1.30259)
			(xy 392.896911 -1.403151) (xy 392.856134 -1.507049) (xy 392.823235 -1.613704) (xy 392.798398 -1.72252)
			(xy 392.781763 -1.832887) (xy 392.773422 -1.944189) (xy 392.7729 -1.999996) (xy 392.7729 -11.850116)
			(xy 392.772419 -11.903957) (xy 392.764736 -12.011364) (xy 392.74941 -12.117949) (xy 392.72652 -12.22317)
			(xy 392.696182 -12.326489) (xy 392.65855 -12.427381) (xy 392.613817 -12.525331) (xy 392.56221 -12.619841)
			(xy 392.503992 -12.710428) (xy 392.43946 -12.796631) (xy 392.368944 -12.878011) (xy 392.292801 -12.954153)
			(xy 392.21142 -13.024669) (xy 392.125217 -13.0892) (xy 392.034629 -13.147417) (xy 391.940119 -13.199023)
			(xy 391.842168 -13.243755) (xy 391.741276 -13.281386) (xy 391.637956 -13.311723) (xy 391.532735 -13.334613)
			(xy 391.42615 -13.349937) (xy 391.318743 -13.357619) (xy 391.264902 -13.358114) (xy 383.264918 -13.358114)
			(xy 383.211076 -13.357645) (xy 383.103666 -13.349965) (xy 382.997077 -13.334641) (xy 382.891854 -13.311752)
			(xy 382.788531 -13.281415) (xy 382.687636 -13.243785) (xy 382.589682 -13.199052) (xy 382.495169 -13.147445)
			(xy 382.404579 -13.089228) (xy 382.318373 -13.024696) (xy 382.236989 -12.954179) (xy 382.160844 -12.878035)
			(xy 382.090325 -12.796654) (xy 382.025791 -12.710449) (xy 381.967572 -12.61986) (xy 381.915963 -12.525348)
			(xy 381.871228 -12.427396) (xy 381.833596 -12.326501) (xy 381.803256 -12.223179) (xy 381.780365 -12.117956)
			(xy 381.765039 -12.011368) (xy 381.757356 -11.903958) (xy 381.75692 -11.850116) (xy 381.75692 -1.999996)
			(xy 381.756398 -1.944189) (xy 381.748057 -1.832886) (xy 381.731422 -1.722518) (xy 381.706585 -1.613702)
			(xy 381.673686 -1.507047) (xy 381.632909 -1.403147) (xy 381.584482 -1.302586) (xy 381.528675 -1.205925)
			(xy 381.4658 -1.113704) (xy 381.39621 -1.02644) (xy 381.320294 -0.944621) (xy 381.238475 -0.868703)
			(xy 381.151212 -0.799112) (xy 381.058992 -0.736236) (xy 380.962332 -0.680428) (xy 380.861771 -0.631999)
			(xy 380.757872 -0.59122) (xy 380.651217 -0.55832) (xy 380.542401 -0.533482) (xy 380.432034 -0.516845)
			(xy 380.320731 -0.508503) (xy 380.264924 -0.508) (xy 368.264948 -0.508) (xy 368.209139 -0.508507)
			(xy 368.097834 -0.516845) (xy 367.987463 -0.533478) (xy 367.878643 -0.558312) (xy 367.771984 -0.591209)
			(xy 367.668081 -0.631985) (xy 367.567516 -0.680411) (xy 367.470851 -0.736218) (xy 367.378627 -0.799092)
			(xy 367.29136 -0.868683) (xy 367.209537 -0.9446) (xy 367.133617 -1.02642) (xy 367.064023 -1.113685)
			(xy 367.001145 -1.205907) (xy 366.945336 -1.30257) (xy 366.896905 -1.403133) (xy 366.856126 -1.507034)
			(xy 366.823225 -1.613693) (xy 366.798387 -1.722511) (xy 366.781751 -1.832882) (xy 366.773409 -1.944187)
			(xy 366.772952 -1.999996) (xy 366.772952 -11.850116) (xy 366.772482 -11.903957) (xy 366.764799 -12.011363)
			(xy 366.749473 -12.117948) (xy 366.726583 -12.223168) (xy 366.696244 -12.326487) (xy 366.658612 -12.427378)
			(xy 366.613878 -12.525328) (xy 366.56227 -12.619836) (xy 366.504051 -12.710422) (xy 366.439519 -12.796624)
			(xy 366.369001 -12.878003) (xy 366.292858 -12.954143) (xy 366.211476 -13.024658) (xy 366.125271 -13.089187)
			(xy 366.034683 -13.147402) (xy 365.940172 -13.199005) (xy 365.842221 -13.243735) (xy 365.741328 -13.281363)
			(xy 365.638008 -13.311698) (xy 365.532787 -13.334584) (xy 365.426202 -13.349906) (xy 365.318795 -13.357584)
			(xy 365.264954 -13.358114) (xy 357.26497 -13.358114) (xy 357.211129 -13.357632) (xy 357.103723 -13.349948)
			(xy 356.997138 -13.334622) (xy 356.891918 -13.311731) (xy 356.788599 -13.281392) (xy 356.687707 -13.24376)
			(xy 356.589757 -13.199027) (xy 356.495248 -13.147419) (xy 356.404661 -13.089202) (xy 356.318459 -13.02467)
			(xy 356.237079 -12.954153) (xy 356.160937 -12.878011) (xy 356.090421 -12.796631) (xy 356.02589 -12.710427)
			(xy 355.967673 -12.61984) (xy 355.916067 -12.52533) (xy 355.871335 -12.42738) (xy 355.833703 -12.326488)
			(xy 355.803366 -12.223169) (xy 355.780476 -12.117949) (xy 355.76515 -12.011363) (xy 355.757467 -11.903957)
			(xy 355.756972 -11.850116) (xy 355.756972 -1.999996) (xy 355.756463 -1.944189) (xy 355.748121 -1.832887)
			(xy 355.731486 -1.722519) (xy 355.706649 -1.613704) (xy 355.673749 -1.507049) (xy 355.632971 -1.40315)
			(xy 355.584543 -1.30259) (xy 355.528735 -1.205929) (xy 355.46586 -1.11371) (xy 355.396269 -1.026447)
			(xy 355.320352 -0.944629) (xy 355.238532 -0.868713) (xy 355.151268 -0.799123) (xy 355.059047 -0.73625)
			(xy 354.962386 -0.680444) (xy 354.861824 -0.632017) (xy 354.757925 -0.591241) (xy 354.651269 -0.558344)
			(xy 354.542453 -0.533509) (xy 354.432085 -0.516876) (xy 354.320783 -0.508536) (xy 354.264976 -0.508)
			(xy 330.164948 -0.508) (xy 330.109139 -0.508507) (xy 329.997834 -0.516845) (xy 329.887463 -0.533478)
			(xy 329.778643 -0.558312) (xy 329.671984 -0.591209) (xy 329.568081 -0.631985) (xy 329.467516 -0.680411)
			(xy 329.370851 -0.736218) (xy 329.278627 -0.799092) (xy 329.19136 -0.868683) (xy 329.109537 -0.9446)
			(xy 329.033617 -1.02642) (xy 328.964023 -1.113685) (xy 328.901145 -1.205907) (xy 328.845336 -1.30257)
			(xy 328.796905 -1.403133) (xy 328.756126 -1.507034) (xy 328.723225 -1.613693) (xy 328.698387 -1.722511)
			(xy 328.681751 -1.832882) (xy 328.673409 -1.944187) (xy 328.672952 -1.999996) (xy 328.672952 -11.850116)
			(xy 328.672482 -11.903957) (xy 328.664799 -12.011363) (xy 328.649473 -12.117948) (xy 328.626583 -12.223168)
			(xy 328.596244 -12.326487) (xy 328.558612 -12.427378) (xy 328.513878 -12.525328) (xy 328.46227 -12.619836)
			(xy 328.404051 -12.710422) (xy 328.339519 -12.796624) (xy 328.269001 -12.878003) (xy 328.192858 -12.954143)
			(xy 328.111476 -13.024658) (xy 328.025271 -13.089187) (xy 327.934683 -13.147402) (xy 327.840172 -13.199005)
			(xy 327.742221 -13.243735) (xy 327.641328 -13.281363) (xy 327.538008 -13.311698) (xy 327.432787 -13.334584)
			(xy 327.326202 -13.349906) (xy 327.218795 -13.357584) (xy 327.164954 -13.358114) (xy 319.16497 -13.358114)
			(xy 319.111129 -13.357632) (xy 319.003723 -13.349948) (xy 318.897138 -13.334622) (xy 318.791918 -13.311731)
			(xy 318.688599 -13.281392) (xy 318.587707 -13.24376) (xy 318.489757 -13.199027) (xy 318.395248 -13.147419)
			(xy 318.304661 -13.089202) (xy 318.218459 -13.02467) (xy 318.137079 -12.954153) (xy 318.060937 -12.878011)
			(xy 317.990421 -12.796631) (xy 317.92589 -12.710427) (xy 317.867673 -12.61984) (xy 317.816067 -12.52533)
			(xy 317.771335 -12.42738) (xy 317.733703 -12.326488) (xy 317.703366 -12.223169) (xy 317.680476 -12.117949)
			(xy 317.66515 -12.011363) (xy 317.657467 -11.903957) (xy 317.656972 -11.850116) (xy 317.656972 -1.999996)
			(xy 317.656463 -1.944189) (xy 317.648121 -1.832887) (xy 317.631486 -1.722519) (xy 317.606649 -1.613704)
			(xy 317.573749 -1.507049) (xy 317.532971 -1.40315) (xy 317.484543 -1.30259) (xy 317.428735 -1.205929)
			(xy 317.36586 -1.11371) (xy 317.296269 -1.026447) (xy 317.220352 -0.944629) (xy 317.138532 -0.868713)
			(xy 317.051268 -0.799123) (xy 316.959047 -0.73625) (xy 316.862386 -0.680444) (xy 316.761824 -0.632017)
			(xy 316.657925 -0.591241) (xy 316.551269 -0.558344) (xy 316.442453 -0.533509) (xy 316.332085 -0.516876)
			(xy 316.220783 -0.508536) (xy 316.164976 -0.508) (xy 304.165 -0.508) (xy 304.109193 -0.508522) (xy 303.997891 -0.516863)
			(xy 303.887523 -0.533498) (xy 303.778708 -0.558334) (xy 303.672052 -0.591233) (xy 303.568153 -0.63201)
			(xy 303.467592 -0.680438) (xy 303.370932 -0.736245) (xy 303.278712 -0.799119) (xy 303.191448 -0.868709)
			(xy 303.109629 -0.944626) (xy 303.033712 -1.026445) (xy 302.964122 -1.113708) (xy 302.901247 -1.205928)
			(xy 302.84544 -1.302589) (xy 302.797012 -1.40315) (xy 302.756234 -1.507048) (xy 302.723335 -1.613704)
			(xy 302.698499 -1.722519) (xy 302.681863 -1.832887) (xy 302.673522 -1.944189) (xy 302.673004 -1.999996)
			(xy 302.673004 -11.850116) (xy 302.672523 -11.903957) (xy 302.66484 -12.011364) (xy 302.649514 -12.11795)
			(xy 302.626624 -12.22317) (xy 302.596286 -12.32649) (xy 302.558654 -12.427382) (xy 302.513921 -12.525332)
			(xy 302.462314 -12.619842) (xy 302.404096 -12.710429) (xy 302.339565 -12.796632) (xy 302.269048 -12.878012)
			(xy 302.192905 -12.954155) (xy 302.111525 -13.024671) (xy 302.025321 -13.089202) (xy 301.934733 -13.147419)
			(xy 301.840223 -13.199025) (xy 301.742272 -13.243758) (xy 301.64138 -13.281389) (xy 301.53806 -13.311726)
			(xy 301.43284 -13.334616) (xy 301.326254 -13.349941) (xy 301.218847 -13.357623) (xy 301.165006 -13.358114)
			(xy 293.165022 -13.358114) (xy 293.11118 -13.357646) (xy 293.00377 -13.349965) (xy 292.897181 -13.334641)
			(xy 292.791957 -13.311753) (xy 292.688634 -13.281416) (xy 292.587739 -13.243786) (xy 292.489785 -13.199053)
			(xy 292.395272 -13.147447) (xy 292.304681 -13.089229) (xy 292.218474 -13.024698) (xy 292.137091 -12.95418)
			(xy 292.060946 -12.878037) (xy 291.990426 -12.796655) (xy 291.925892 -12.71045) (xy 291.867673 -12.619861)
			(xy 291.816064 -12.525349) (xy 291.771329 -12.427396) (xy 291.733696 -12.326502) (xy 291.703356 -12.22318)
			(xy 291.680465 -12.117956) (xy 291.665139 -12.011368) (xy 291.657456 -11.903958) (xy 291.657024 -11.850116)
			(xy 291.657024 -1.999996) (xy 291.656502 -1.944189) (xy 291.648161 -1.832886) (xy 291.631526 -1.722518)
			(xy 291.606689 -1.613702) (xy 291.57379 -1.507046) (xy 291.533013 -1.403147) (xy 291.484586 -1.302585)
			(xy 291.428779 -1.205924) (xy 291.365905 -1.113703) (xy 291.296314 -1.026439) (xy 291.220398 -0.944619)
			(xy 291.138579 -0.868701) (xy 291.051316 -0.79911) (xy 290.959096 -0.736234) (xy 290.862436 -0.680426)
			(xy 290.761875 -0.631997) (xy 290.657977 -0.591218) (xy 290.551321 -0.558317) (xy 290.442505 -0.533479)
			(xy 290.332138 -0.516842) (xy 290.220835 -0.508499) (xy 290.165028 -0.508) (xy 278.165052 -0.508)
			(xy 278.109246 -0.508523) (xy 277.997947 -0.516868) (xy 277.887582 -0.533506) (xy 277.778769 -0.558345)
			(xy 277.672116 -0.591246) (xy 277.568221 -0.632024) (xy 277.467663 -0.680453) (xy 277.371005 -0.736261)
			(xy 277.278789 -0.799136) (xy 277.191528 -0.868726) (xy 277.109712 -0.944643) (xy 277.033798 -1.026461)
			(xy 276.96421 -1.113724) (xy 276.901338 -1.205943) (xy 276.845533 -1.302602) (xy 276.797107 -1.403161)
			(xy 276.756331 -1.507058) (xy 276.723433 -1.613711) (xy 276.698598 -1.722525) (xy 276.681963 -1.83289)
			(xy 276.673622 -1.94419) (xy 276.673056 -1.999996) (xy 276.673056 -11.850116) (xy 276.672586 -11.903957)
			(xy 276.664903 -12.011363) (xy 276.649577 -12.117948) (xy 276.626687 -12.223169) (xy 276.596348 -12.326487)
			(xy 276.558716 -12.427379) (xy 276.513982 -12.525328) (xy 276.462374 -12.619837) (xy 276.404156 -12.710423)
			(xy 276.339623 -12.796626) (xy 276.269105 -12.878004) (xy 276.192962 -12.954145) (xy 276.11158 -13.02466)
			(xy 276.025376 -13.089189) (xy 275.934787 -13.147404) (xy 275.840277 -13.199008) (xy 275.742325 -13.243738)
			(xy 275.641432 -13.281366) (xy 275.538112 -13.311701) (xy 275.432891 -13.334588) (xy 275.326306 -13.349909)
			(xy 275.218899 -13.357588) (xy 275.165058 -13.358114) (xy 267.165074 -13.358114) (xy 267.111233 -13.357632)
			(xy 267.003826 -13.349949) (xy 266.897241 -13.334623) (xy 266.792021 -13.311732) (xy 266.688702 -13.281393)
			(xy 266.58781 -13.243761) (xy 266.48986 -13.199028) (xy 266.39535 -13.147421) (xy 266.304763 -13.089203)
			(xy 266.21856 -13.024672) (xy 266.13718 -12.954155) (xy 266.061038 -12.878012) (xy 265.990522 -12.796632)
			(xy 265.925991 -12.710428) (xy 265.867774 -12.619841) (xy 265.816168 -12.525331) (xy 265.771435 -12.427381)
			(xy 265.733804 -12.326489) (xy 265.703466 -12.22317) (xy 265.680576 -12.117949) (xy 265.66525 -12.011364)
			(xy 265.657567 -11.903957) (xy 265.657076 -11.850116) (xy 265.657076 -1.999996) (xy 265.656567 -1.944189)
			(xy 265.648225 -1.832887) (xy 265.63159 -1.722519) (xy 265.606753 -1.613703) (xy 265.573853 -1.507048)
			(xy 265.533076 -1.403149) (xy 265.484647 -1.302589) (xy 265.42884 -1.205928) (xy 265.365964 -1.113709)
			(xy 265.296373 -1.026446) (xy 265.220456 -0.944627) (xy 265.138636 -0.868711) (xy 265.051372 -0.799121)
			(xy 264.959151 -0.736248) (xy 264.86249 -0.680441) (xy 264.761929 -0.632015) (xy 264.658029 -0.591239)
			(xy 264.551373 -0.558341) (xy 264.442557 -0.533506) (xy 264.332189 -0.516872) (xy 264.220887 -0.508532)
			(xy 264.16508 -0.508) (xy 252.165104 -0.508) (xy 252.109297 -0.508522) (xy 251.997995 -0.516862)
			(xy 251.887627 -0.533497) (xy 251.778811 -0.558333) (xy 251.672155 -0.591232) (xy 251.568256 -0.632009)
			(xy 251.467695 -0.680436) (xy 251.371034 -0.736243) (xy 251.278814 -0.799118) (xy 251.19155 -0.868708)
			(xy 251.10973 -0.944625) (xy 251.033813 -1.026444) (xy 250.964222 -1.113707) (xy 250.901348 -1.205927)
			(xy 250.84554 -1.302588) (xy 250.797112 -1.403149) (xy 250.756335 -1.507047) (xy 250.723435 -1.613703)
			(xy 250.698599 -1.722519) (xy 250.681963 -1.832887) (xy 250.673622 -1.944189) (xy 250.673108 -1.999996)
			(xy 250.673108 -11.850116) (xy 250.672627 -11.903957) (xy 250.664944 -12.011364) (xy 250.649618 -12.11795)
			(xy 250.626728 -12.223171) (xy 250.59639 -12.32649) (xy 250.558758 -12.427382) (xy 250.514025 -12.525333)
			(xy 250.462418 -12.619843) (xy 250.4042 -12.71043) (xy 250.339669 -12.796633) (xy 250.269152 -12.878014)
			(xy 250.193009 -12.954156) (xy 250.111629 -13.024673) (xy 250.025425 -13.089204) (xy 249.934837 -13.147421)
			(xy 249.840327 -13.199027) (xy 249.742377 -13.24376) (xy 249.641484 -13.281392) (xy 249.538165 -13.311729)
			(xy 249.432944 -13.334619) (xy 249.326358 -13.349944) (xy 249.218951 -13.357627) (xy 249.16511 -13.358114)
			(xy 241.164872 -13.358114) (xy 241.111035 -13.357619) (xy 241.003638 -13.34991) (xy 240.897064 -13.334562)
			(xy 240.791856 -13.311652) (xy 240.688549 -13.281298) (xy 240.58767 -13.243654) (xy 240.489733 -13.198912)
			(xy 240.395235 -13.1473) (xy 240.304659 -13.08908) (xy 240.218466 -13.024548) (xy 240.137093 -12.954035)
			(xy 240.060957 -12.877898) (xy 239.990444 -12.796525) (xy 239.925914 -12.710331) (xy 239.867694 -12.619754)
			(xy 239.816083 -12.525256) (xy 239.771341 -12.427319) (xy 239.733698 -12.326439) (xy 239.703345 -12.223133)
			(xy 239.680436 -12.117924) (xy 239.665089 -12.01135) (xy 239.657381 -11.903953) (xy 239.656874 -11.850116)
			(xy 239.656874 -1.999996) (xy 239.656365 -1.944189) (xy 239.648023 -1.832887) (xy 239.631388 -1.722519)
			(xy 239.606551 -1.613704) (xy 239.573651 -1.507048) (xy 239.532873 -1.40315) (xy 239.484445 -1.302589)
			(xy 239.428638 -1.205929) (xy 239.365762 -1.113709) (xy 239.296171 -1.026446) (xy 239.220254 -0.944628)
			(xy 239.138434 -0.868712) (xy 239.05117 -0.799122) (xy 238.958949 -0.736249) (xy 238.862288 -0.680443)
			(xy 238.761726 -0.632016) (xy 238.657827 -0.59124) (xy 238.551171 -0.558343) (xy 238.442355 -0.533507)
			(xy 238.331987 -0.516874) (xy 238.220685 -0.508534) (xy 238.164878 -0.508) (xy 214.065104 -0.508)
			(xy 214.009297 -0.508522) (xy 213.897995 -0.516862) (xy 213.787627 -0.533497) (xy 213.678811 -0.558333)
			(xy 213.572155 -0.591232) (xy 213.468256 -0.632009) (xy 213.367695 -0.680436) (xy 213.271034 -0.736243)
			(xy 213.178814 -0.799118) (xy 213.09155 -0.868708) (xy 213.00973 -0.944625) (xy 212.933813 -1.026444)
			(xy 212.864222 -1.113707) (xy 212.801348 -1.205927) (xy 212.74554 -1.302588) (xy 212.697112 -1.403149)
			(xy 212.656335 -1.507047) (xy 212.623435 -1.613703) (xy 212.598599 -1.722519) (xy 212.581963 -1.832887)
			(xy 212.573622 -1.944189) (xy 212.573108 -1.999996) (xy 212.573108 -11.850116) (xy 212.572627 -11.903957)
			(xy 212.564944 -12.011364) (xy 212.549618 -12.11795) (xy 212.526728 -12.223171) (xy 212.49639 -12.32649)
			(xy 212.458758 -12.427382) (xy 212.414025 -12.525333) (xy 212.362418 -12.619843) (xy 212.3042 -12.71043)
			(xy 212.239669 -12.796633) (xy 212.169152 -12.878014) (xy 212.093009 -12.954156) (xy 212.011629 -13.024673)
			(xy 211.925425 -13.089204) (xy 211.834837 -13.147421) (xy 211.740327 -13.199027) (xy 211.642377 -13.24376)
			(xy 211.541484 -13.281392) (xy 211.438165 -13.311729) (xy 211.332944 -13.334619) (xy 211.226358 -13.349944)
			(xy 211.118951 -13.357627) (xy 211.06511 -13.358114) (xy 203.064872 -13.358114) (xy 203.011035 -13.357619)
			(xy 202.903638 -13.34991) (xy 202.797064 -13.334562) (xy 202.691856 -13.311652) (xy 202.588549 -13.281298)
			(xy 202.48767 -13.243654) (xy 202.389733 -13.198912) (xy 202.295235 -13.1473) (xy 202.204659 -13.08908)
			(xy 202.118466 -13.024548) (xy 202.037093 -12.954035) (xy 201.960957 -12.877898) (xy 201.890444 -12.796525)
			(xy 201.825914 -12.710331) (xy 201.767694 -12.619754) (xy 201.716083 -12.525256) (xy 201.671341 -12.427319)
			(xy 201.633698 -12.326439) (xy 201.603345 -12.223133) (xy 201.580436 -12.117924) (xy 201.565089 -12.01135)
			(xy 201.557381 -11.903953) (xy 201.556874 -11.850116) (xy 201.556874 -1.999996) (xy 201.556365 -1.944189)
			(xy 201.548023 -1.832887) (xy 201.531388 -1.722519) (xy 201.506551 -1.613704) (xy 201.473651 -1.507048)
			(xy 201.432873 -1.40315) (xy 201.384445 -1.302589) (xy 201.328638 -1.205929) (xy 201.265762 -1.113709)
			(xy 201.196171 -1.026446) (xy 201.120254 -0.944628) (xy 201.038434 -0.868712) (xy 200.95117 -0.799122)
			(xy 200.858949 -0.736249) (xy 200.762288 -0.680443) (xy 200.661726 -0.632016) (xy 200.557827 -0.59124)
			(xy 200.451171 -0.558343) (xy 200.342355 -0.533507) (xy 200.231987 -0.516874) (xy 200.120685 -0.508534)
			(xy 200.064878 -0.508) (xy 188.064902 -0.508) (xy 188.009095 -0.508522) (xy 187.897793 -0.516862)
			(xy 187.787425 -0.533498) (xy 187.678609 -0.558334) (xy 187.571954 -0.591233) (xy 187.468055 -0.63201)
			(xy 187.367494 -0.680437) (xy 187.270833 -0.736244) (xy 187.178613 -0.799118) (xy 187.091349 -0.868709)
			(xy 187.00953 -0.944625) (xy 186.933613 -1.026444) (xy 186.864022 -1.113708) (xy 186.801147 -1.205928)
			(xy 186.74534 -1.302588) (xy 186.696912 -1.403149) (xy 186.656135 -1.507048) (xy 186.623235 -1.613703)
			(xy 186.598399 -1.722519) (xy 186.581763 -1.832887) (xy 186.573422 -1.944189) (xy 186.572906 -1.999996)
			(xy 186.572906 -11.850116) (xy 186.572425 -11.903957) (xy 186.564742 -12.011364) (xy 186.549416 -12.11795)
			(xy 186.526526 -12.22317) (xy 186.496188 -12.32649) (xy 186.458556 -12.427382) (xy 186.413823 -12.525332)
			(xy 186.362216 -12.619842) (xy 186.303998 -12.71043) (xy 186.239467 -12.796633) (xy 186.16895 -12.878013)
			(xy 186.092807 -12.954155) (xy 186.011427 -13.024672) (xy 185.925223 -13.089203) (xy 185.834635 -13.14742)
			(xy 185.740125 -13.199026) (xy 185.642175 -13.243759) (xy 185.541282 -13.28139) (xy 185.437963 -13.311728)
			(xy 185.332742 -13.334618) (xy 185.226156 -13.349943) (xy 185.118749 -13.357625) (xy 185.064908 -13.358114)
			(xy 177.064924 -13.358114) (xy 177.011082 -13.357646) (xy 176.903671 -13.349965) (xy 176.797083 -13.334642)
			(xy 176.691859 -13.311753) (xy 176.588536 -13.281417) (xy 176.48764 -13.243786) (xy 176.389686 -13.199054)
			(xy 176.295173 -13.147447) (xy 176.204582 -13.08923) (xy 176.118375 -13.024698) (xy 176.036992 -12.954181)
			(xy 175.960846 -12.878038) (xy 175.890327 -12.796656) (xy 175.825793 -12.710451) (xy 175.767573 -12.619862)
			(xy 175.715964 -12.52535) (xy 175.671229 -12.427397) (xy 175.633596 -12.326502) (xy 175.603257 -12.22318)
			(xy 175.580365 -12.117957) (xy 175.565039 -12.011368) (xy 175.557356 -11.903958) (xy 175.556926 -11.850116)
			(xy 175.556926 -1.999996) (xy 175.556404 -1.944189) (xy 175.548063 -1.832886) (xy 175.531428 -1.722518)
			(xy 175.506591 -1.613702) (xy 175.473692 -1.507046) (xy 175.432915 -1.403146) (xy 175.384488 -1.302585)
			(xy 175.328681 -1.205923) (xy 175.265807 -1.113703) (xy 175.196217 -1.026438) (xy 175.1203 -0.944618)
			(xy 175.038481 -0.8687) (xy 174.951218 -0.799109) (xy 174.858999 -0.736233) (xy 174.762338 -0.680424)
			(xy 174.661777 -0.631995) (xy 174.557879 -0.591216) (xy 174.451223 -0.558316) (xy 174.342408 -0.533477)
			(xy 174.23204 -0.51684) (xy 174.120737 -0.508497) (xy 174.06493 -0.508) (xy 162.064954 -0.508) (xy 162.009148 -0.508523)
			(xy 161.897848 -0.516867) (xy 161.787483 -0.533505) (xy 161.67867 -0.558344) (xy 161.572018 -0.591245)
			(xy 161.468122 -0.632024) (xy 161.367564 -0.680453) (xy 161.270907 -0.73626) (xy 161.17869 -0.799135)
			(xy 161.091429 -0.868726) (xy 161.009613 -0.944642) (xy 160.933698 -1.026461) (xy 160.86411 -1.113723)
			(xy 160.801238 -1.205942) (xy 160.745433 -1.302601) (xy 160.697007 -1.403161) (xy 160.656231 -1.507058)
			(xy 160.623333 -1.613711) (xy 160.598498 -1.722525) (xy 160.581863 -1.83289) (xy 160.573522 -1.94419)
			(xy 160.572958 -1.999996) (xy 160.572958 -11.850116) (xy 160.572488 -11.903957) (xy 160.564805 -12.011363)
			(xy 160.549479 -12.117949) (xy 160.526589 -12.223169) (xy 160.49625 -12.326488) (xy 160.458618 -12.427379)
			(xy 160.413884 -12.525329) (xy 160.362276 -12.619838) (xy 160.304058 -12.710424) (xy 160.239525 -12.796626)
			(xy 160.169008 -12.878005) (xy 160.092864 -12.954146) (xy 160.011483 -13.02466) (xy 159.925278 -13.08919)
			(xy 159.834689 -13.147405) (xy 159.740179 -13.199009) (xy 159.642227 -13.243739) (xy 159.541335 -13.281368)
			(xy 159.438014 -13.311702) (xy 159.332793 -13.334589) (xy 159.226208 -13.349911) (xy 159.118801 -13.35759)
			(xy 159.06496 -13.358114) (xy 151.064976 -13.358114) (xy 151.011135 -13.357633) (xy 150.903728 -13.349949)
			(xy 150.797143 -13.334623) (xy 150.691922 -13.311732) (xy 150.588603 -13.281394) (xy 150.487711 -13.243762)
			(xy 150.389761 -13.199028) (xy 150.295252 -13.147421) (xy 150.204664 -13.089204) (xy 150.118461 -13.024672)
			(xy 150.037081 -12.954156) (xy 149.960939 -12.878013) (xy 149.890423 -12.796633) (xy 149.825892 -12.710429)
			(xy 149.767674 -12.619842) (xy 149.716068 -12.525332) (xy 149.671335 -12.427381) (xy 149.633704 -12.326489)
			(xy 149.603366 -12.22317) (xy 149.580476 -12.117949) (xy 149.56515 -12.011364) (xy 149.557467 -11.903957)
			(xy 149.556978 -11.850116) (xy 149.556978 -1.999996) (xy 149.556469 -1.944189) (xy 149.548127 -1.832887)
			(xy 149.531492 -1.722519) (xy 149.506655 -1.613703) (xy 149.473755 -1.507048) (xy 149.432978 -1.403149)
			(xy 149.384549 -1.302588) (xy 149.328742 -1.205928) (xy 149.265867 -1.113708) (xy 149.196276 -1.026445)
			(xy 149.120358 -0.944627) (xy 149.038538 -0.86871) (xy 148.951274 -0.79912) (xy 148.859054 -0.736247)
			(xy 148.762392 -0.68044) (xy 148.661831 -0.632014) (xy 148.557931 -0.591237) (xy 148.451276 -0.55834)
			(xy 148.342459 -0.533504) (xy 148.232091 -0.51687) (xy 148.120789 -0.508531) (xy 148.064982 -0.508)
			(xy 136.065006 -0.508) (xy 136.009198 -0.508509) (xy 135.897895 -0.51685) (xy 135.787526 -0.533485)
			(xy 135.678709 -0.558321) (xy 135.572052 -0.59122) (xy 135.468152 -0.631997) (xy 135.36759 -0.680425)
			(xy 135.270928 -0.736232) (xy 135.178707 -0.799107) (xy 135.091442 -0.868698) (xy 135.009622 -0.944615)
			(xy 134.933704 -1.026435) (xy 134.864113 -1.113699) (xy 134.801237 -1.20592) (xy 134.745429 -1.302581)
			(xy 134.697001 -1.403143) (xy 134.656223 -1.507043) (xy 134.623324 -1.613699) (xy 134.598486 -1.722516)
			(xy 134.581851 -1.832885) (xy 134.573509 -1.944188) (xy 134.57301 -1.999996) (xy 134.57301 -11.850116)
			(xy 134.572529 -11.903957) (xy 134.564846 -12.011364) (xy 134.54952 -12.11795) (xy 134.52663 -12.223171)
			(xy 134.496292 -12.32649) (xy 134.45866 -12.427383) (xy 134.413927 -12.525333) (xy 134.36232 -12.619843)
			(xy 134.304102 -12.710431) (xy 134.239571 -12.796634) (xy 134.169054 -12.878014) (xy 134.092911 -12.954157)
			(xy 134.011531 -13.024673) (xy 133.925327 -13.089205) (xy 133.83474 -13.147422) (xy 133.74023 -13.199029)
			(xy 133.642279 -13.243762) (xy 133.541387 -13.281393) (xy 133.438067 -13.311731) (xy 133.332846 -13.334621)
			(xy 133.22626 -13.349946) (xy 133.118853 -13.357629) (xy 133.065012 -13.358114) (xy 125.065028 -13.358114)
			(xy 125.011186 -13.357646) (xy 124.903775 -13.349966) (xy 124.797186 -13.334642) (xy 124.691962 -13.311754)
			(xy 124.588639 -13.281418) (xy 124.487743 -13.243787) (xy 124.389789 -13.199055) (xy 124.295275 -13.147449)
			(xy 124.204684 -13.089231) (xy 124.118477 -13.0247) (xy 124.037093 -12.954182) (xy 123.960948 -12.878039)
			(xy 123.890428 -12.796657) (xy 123.825894 -12.710452) (xy 123.767674 -12.619863) (xy 123.716065 -12.525351)
			(xy 123.671329 -12.427398) (xy 123.633696 -12.326503) (xy 123.603357 -12.223181) (xy 123.580465 -12.117957)
			(xy 123.565139 -12.011369) (xy 123.557456 -11.903958) (xy 123.55703 -11.850116) (xy 123.55703 -1.999996)
			(xy 123.556508 -1.944189) (xy 123.548167 -1.832886) (xy 123.531532 -1.722518) (xy 123.506695 -1.613701)
			(xy 123.473796 -1.507045) (xy 123.433019 -1.403146) (xy 123.384592 -1.302584) (xy 123.328785 -1.205923)
			(xy 123.265911 -1.113702) (xy 123.196321 -1.026437) (xy 123.120404 -0.944617) (xy 123.038586 -0.868699)
			(xy 122.951322 -0.799107) (xy 122.859103 -0.736231) (xy 122.762442 -0.680422) (xy 122.661882 -0.631993)
			(xy 122.557983 -0.591214) (xy 122.451328 -0.558313) (xy 122.342512 -0.533474) (xy 122.232144 -0.516836)
			(xy 122.120841 -0.508493) (xy 122.065034 -0.508) (xy 97.965006 -0.508) (xy 97.909198 -0.508509) (xy 97.797895 -0.51685)
			(xy 97.687526 -0.533485) (xy 97.578709 -0.558321) (xy 97.472052 -0.59122) (xy 97.368152 -0.631997)
			(xy 97.26759 -0.680425) (xy 97.170928 -0.736232) (xy 97.078707 -0.799107) (xy 96.991442 -0.868698)
			(xy 96.909622 -0.944615) (xy 96.833704 -1.026435) (xy 96.764113 -1.113699) (xy 96.701237 -1.20592)
			(xy 96.645429 -1.302581) (xy 96.597001 -1.403143) (xy 96.556223 -1.507043) (xy 96.523324 -1.613699)
			(xy 96.498486 -1.722516) (xy 96.481851 -1.832885) (xy 96.473509 -1.944188) (xy 96.47301 -1.999996)
			(xy 96.47301 -11.850116) (xy 96.472529 -11.903957) (xy 96.464846 -12.011364) (xy 96.44952 -12.11795)
			(xy 96.42663 -12.223171) (xy 96.396292 -12.32649) (xy 96.35866 -12.427383) (xy 96.313927 -12.525333)
			(xy 96.26232 -12.619843) (xy 96.204102 -12.710431) (xy 96.139571 -12.796634) (xy 96.069054 -12.878014)
			(xy 95.992911 -12.954157) (xy 95.911531 -13.024673) (xy 95.825327 -13.089205) (xy 95.73474 -13.147422)
			(xy 95.64023 -13.199029) (xy 95.542279 -13.243762) (xy 95.441387 -13.281393) (xy 95.338067 -13.311731)
			(xy 95.232846 -13.334621) (xy 95.12626 -13.349946) (xy 95.018853 -13.357629) (xy 94.965012 -13.358114)
			(xy 86.965028 -13.358114) (xy 86.911186 -13.357646) (xy 86.803775 -13.349966) (xy 86.697186 -13.334642)
			(xy 86.591962 -13.311754) (xy 86.488639 -13.281418) (xy 86.387743 -13.243787) (xy 86.289789 -13.199055)
			(xy 86.195275 -13.147449) (xy 86.104684 -13.089231) (xy 86.018477 -13.0247) (xy 85.937093 -12.954182)
			(xy 85.860948 -12.878039) (xy 85.790428 -12.796657) (xy 85.725894 -12.710452) (xy 85.667674 -12.619863)
			(xy 85.616065 -12.525351) (xy 85.571329 -12.427398) (xy 85.533696 -12.326503) (xy 85.503357 -12.223181)
			(xy 85.480465 -12.117957) (xy 85.465139 -12.011369) (xy 85.457456 -11.903958) (xy 85.45703 -11.850116)
			(xy 85.45703 -1.999996) (xy 85.456508 -1.944189) (xy 85.448167 -1.832886) (xy 85.431532 -1.722518)
			(xy 85.406695 -1.613701) (xy 85.373796 -1.507045) (xy 85.333019 -1.403146) (xy 85.284592 -1.302584)
			(xy 85.228785 -1.205923) (xy 85.165911 -1.113702) (xy 85.096321 -1.026437) (xy 85.020404 -0.944617)
			(xy 84.938586 -0.868699) (xy 84.851322 -0.799107) (xy 84.759103 -0.736231) (xy 84.662442 -0.680422)
			(xy 84.561882 -0.631993) (xy 84.457983 -0.591214) (xy 84.351328 -0.558313) (xy 84.242512 -0.533474)
			(xy 84.132144 -0.516836) (xy 84.020841 -0.508493) (xy 83.965034 -0.508) (xy 71.965058 -0.508) (xy 71.909252 -0.508523)
			(xy 71.797952 -0.516867) (xy 71.687587 -0.533505) (xy 71.578774 -0.558343) (xy 71.472121 -0.591244)
			(xy 71.368225 -0.632023) (xy 71.267667 -0.680451) (xy 71.171009 -0.736259) (xy 71.078791 -0.799134)
			(xy 70.991531 -0.868724) (xy 70.909714 -0.944641) (xy 70.8338 -1.026459) (xy 70.764211 -1.113722)
			(xy 70.701339 -1.205941) (xy 70.645534 -1.3026) (xy 70.597107 -1.40316) (xy 70.556331 -1.507057)
			(xy 70.523434 -1.61371) (xy 70.498598 -1.722524) (xy 70.481963 -1.83289) (xy 70.473622 -1.94419)
			(xy 70.473062 -1.999996) (xy 70.473062 -11.850116) (xy 70.472592 -11.903957) (xy 70.464909 -12.011364)
			(xy 70.449583 -12.117949) (xy 70.426693 -12.223169) (xy 70.396354 -12.326488) (xy 70.358722 -12.42738)
			(xy 70.313988 -12.52533) (xy 70.26238 -12.619839) (xy 70.204162 -12.710425) (xy 70.139629 -12.796627)
			(xy 70.069112 -12.878006) (xy 69.992968 -12.954147) (xy 69.911587 -13.024662) (xy 69.825382 -13.089192)
			(xy 69.734794 -13.147407) (xy 69.640283 -13.199011) (xy 69.542332 -13.243742) (xy 69.441439 -13.28137)
			(xy 69.338119 -13.311705) (xy 69.232898 -13.334592) (xy 69.126312 -13.349915) (xy 69.018905 -13.357594)
			(xy 68.965064 -13.358114) (xy 60.96508 -13.358114) (xy 60.911239 -13.357633) (xy 60.803832 -13.349949)
			(xy 60.697246 -13.334624) (xy 60.592026 -13.311733) (xy 60.488706 -13.281395) (xy 60.387814 -13.243763)
			(xy 60.289864 -13.19903) (xy 60.195354 -13.147423) (xy 60.104766 -13.089205) (xy 60.018563 -13.024674)
			(xy 59.937183 -12.954157) (xy 59.86104 -12.878014) (xy 59.790524 -12.796634) (xy 59.725992 -12.71043)
			(xy 59.667775 -12.619843) (xy 59.616169 -12.525333) (xy 59.571435 -12.427382) (xy 59.533804 -12.32649)
			(xy 59.503466 -12.22317) (xy 59.480576 -12.11795) (xy 59.46525 -12.011364) (xy 59.457567 -11.903957)
			(xy 59.457082 -11.850116) (xy 59.457082 -1.999996) (xy 59.456573 -1.944189) (xy 59.448231 -1.832886)
			(xy 59.431596 -1.722519) (xy 59.406759 -1.613703) (xy 59.373859 -1.507047) (xy 59.333082 -1.403148)
			(xy 59.284653 -1.302588) (xy 59.228846 -1.205927) (xy 59.165971 -1.113707) (xy 59.09638 -1.026444)
			(xy 59.020462 -0.944625) (xy 58.938643 -0.868709) (xy 58.851378 -0.799119) (xy 58.759158 -0.736245)
			(xy 58.662496 -0.680438) (xy 58.561935 -0.632011) (xy 58.458036 -0.591235) (xy 58.35138 -0.558337)
			(xy 58.242564 -0.533501) (xy 58.132196 -0.516867) (xy 58.020893 -0.508527) (xy 57.965086 -0.508)
			(xy 45.96511 -0.508) (xy 45.909302 -0.508509) (xy 45.797999 -0.516849) (xy 45.68763 -0.533484) (xy 45.578812 -0.55832)
			(xy 45.472155 -0.591219) (xy 45.368255 -0.631996) (xy 45.267693 -0.680423) (xy 45.17103 -0.736231)
			(xy 45.078809 -0.799106) (xy 44.991544 -0.868696) (xy 44.909724 -0.944614) (xy 44.833805 -1.026433)
			(xy 44.764214 -1.113698) (xy 44.701338 -1.205919) (xy 44.64553 -1.30258) (xy 44.597101 -1.403142)
			(xy 44.556323 -1.507042) (xy 44.523424 -1.613699) (xy 44.498587 -1.722516) (xy 44.481951 -1.832885)
			(xy 44.473609 -1.944188) (xy 44.473114 -1.999996) (xy 44.473114 -11.850116) (xy 44.472633 -11.903957)
			(xy 44.46495 -12.011364) (xy 44.449624 -12.11795) (xy 44.426734 -12.223171) (xy 44.396396 -12.326491)
			(xy 44.358764 -12.427383) (xy 44.314031 -12.525334) (xy 44.262424 -12.619844) (xy 44.204207 -12.710432)
			(xy 44.139675 -12.796635) (xy 44.069158 -12.878016) (xy 43.993016 -12.954158) (xy 43.911635 -13.024675)
			(xy 43.825432 -13.089207) (xy 43.734844 -13.147424) (xy 43.640334 -13.199031) (xy 43.542383 -13.243764)
			(xy 43.441491 -13.281396) (xy 43.338171 -13.311734) (xy 43.23295 -13.334624) (xy 43.126364 -13.34995)
			(xy 43.018957 -13.357633) (xy 42.965116 -13.358114) (xy 34.964878 -13.358114) (xy 34.911037 -13.357633)
			(xy 34.80363 -13.349949) (xy 34.697045 -13.334623) (xy 34.591824 -13.311733) (xy 34.488505 -13.281394)
			(xy 34.387613 -13.243762) (xy 34.289662 -13.199029) (xy 34.195153 -13.147422) (xy 34.104565 -13.089205)
			(xy 34.018362 -13.024673) (xy 33.936982 -12.954156) (xy 33.86084 -12.878014) (xy 33.790323 -12.796633)
			(xy 33.725792 -12.71043) (xy 33.667575 -12.619842) (xy 33.615968 -12.525332) (xy 33.571235 -12.427382)
			(xy 33.533604 -12.32649) (xy 33.503266 -12.22317) (xy 33.480376 -12.11795) (xy 33.46505 -12.011364)
			(xy 33.457367 -11.903957) (xy 33.45688 -11.850116) (xy 33.45688 -1.999996) (xy 33.456371 -1.944189)
			(xy 33.448029 -1.832887) (xy 33.431394 -1.722519) (xy 33.406557 -1.613703) (xy 33.373657 -1.507048)
			(xy 33.33288 -1.403149) (xy 33.284451 -1.302588) (xy 33.228644 -1.205927) (xy 33.165769 -1.113708)
			(xy 33.096178 -1.026444) (xy 33.02026 -0.944626) (xy 32.93844 -0.868709) (xy 32.851176 -0.79912)
			(xy 32.758956 -0.736246) (xy 32.662294 -0.680439) (xy 32.561733 -0.632012) (xy 32.457834 -0.591236)
			(xy 32.351178 -0.558338) (xy 32.242361 -0.533503) (xy 32.131994 -0.516868) (xy 32.020691 -0.508529)
			(xy 31.964884 -0.508) (xy 19.964908 -0.508) (xy 19.9091 -0.508509) (xy 19.797797 -0.516849) (xy 19.687428 -0.533484)
			(xy 19.578611 -0.55832) (xy 19.471954 -0.591219) (xy 19.368054 -0.631996) (xy 19.267491 -0.680424)
			(xy 19.170829 -0.736231) (xy 19.078608 -0.799106) (xy 18.991343 -0.868697) (xy 18.909523 -0.944614)
			(xy 18.833605 -1.026434) (xy 18.764013 -1.113698) (xy 18.701138 -1.205919) (xy 18.64533 -1.302581)
			(xy 18.596901 -1.403143) (xy 18.556123 -1.507043) (xy 18.523224 -1.613699) (xy 18.498386 -1.722516)
			(xy 18.481751 -1.832885) (xy 18.473409 -1.944188) (xy 18.472912 -1.999996) (xy 18.472912 -11.850116)
			(xy 18.472443 -11.903958) (xy 18.464761 -12.011366) (xy 18.449437 -12.117953) (xy 18.426547 -12.223176)
			(xy 18.396209 -12.326497) (xy 18.358578 -12.42739) (xy 18.313845 -12.525342) (xy 18.262238 -12.619854)
			(xy 18.20402 -12.710442) (xy 18.139488 -12.796647) (xy 18.068971 -12.878029) (xy 17.992827 -12.954172)
			(xy 17.911446 -13.024689) (xy 17.825241 -13.089221) (xy 17.734652 -13.147439) (xy 17.640141 -13.199046)
			(xy 17.542189 -13.243779) (xy 17.441295 -13.28141) (xy 17.337974 -13.311748) (xy 17.232751 -13.334637)
			(xy 17.126164 -13.349961) (xy 17.018756 -13.357643) (xy 16.964914 -13.358114) (xy 8.96493 -13.358114)
			(xy 8.911089 -13.357645) (xy 8.80368 -13.349963) (xy 8.697093 -13.334638) (xy 8.591871 -13.311748)
			(xy 8.48855 -13.28141) (xy 8.387656 -13.243779) (xy 8.289705 -13.199046) (xy 8.195194 -13.147439)
			(xy 8.104605 -13.089221) (xy 8.0184 -13.024689) (xy 7.937019 -12.954171) (xy 7.860876 -12.878028)
			(xy 7.790359 -12.796646) (xy 7.725827 -12.710442) (xy 7.667609 -12.619853) (xy 7.616002 -12.525342)
			(xy 7.57127 -12.42739) (xy 7.533638 -12.326496) (xy 7.503301 -12.223175) (xy 7.480411 -12.117953)
			(xy 7.465087 -12.011366) (xy 7.457405 -11.903957) (xy 7.456932 -11.850116) (xy 7.456932 -1.999996)
			(xy 7.45641 -1.944189) (xy 7.448069 -1.832887) (xy 7.431434 -1.72252) (xy 7.406597 -1.613704) (xy 7.373698 -1.507049)
			(xy 7.332921 -1.40315) (xy 7.284493 -1.30259) (xy 7.228686 -1.205929) (xy 7.165812 -1.113709) (xy 7.096221 -1.026446)
			(xy 7.020305 -0.944627) (xy 6.938486 -0.86871) (xy 6.851222 -0.79912) (xy 6.759003 -0.736245) (xy 6.662342 -0.680438)
			(xy 6.561782 -0.63201) (xy 6.457883 -0.591233) (xy 6.351228 -0.558334) (xy 6.242412 -0.533497) (xy 6.132045 -0.516861)
			(xy 6.020743 -0.50852) (xy 5.964936 -0.508) (xy 1.999996 -0.508) (xy 1.944189 -0.508522) (xy 1.832887 -0.516863)
			(xy 1.72252 -0.533498) (xy 1.613704 -0.558335) (xy 1.507049 -0.591234) (xy 1.403151 -0.632011) (xy 1.30259 -0.680439)
			(xy 1.205929 -0.736246) (xy 1.11371 -0.799121) (xy 1.026446 -0.868711) (xy 0.944628 -0.944628) (xy 0.868711 -1.026446)
			(xy 0.799121 -1.11371) (xy 0.736246 -1.205929) (xy 0.680439 -1.30259) (xy 0.632011 -1.403151) (xy 0.591234 -1.507049)
			(xy 0.558335 -1.613704) (xy 0.533498 -1.72252) (xy 0.516863 -1.832887) (xy 0.508522 -1.944189) (xy 0.508 -1.999996)
			(xy 0.508 -15.200122) (xy 459.541372 -15.200122) (xy 459.541372 -13.599922) (xy 459.54188 -13.535242)
			(xy 459.550003 -13.406136) (xy 459.566216 -13.277796) (xy 459.590456 -13.150726) (xy 459.622626 -13.02543)
			(xy 459.662601 -12.9024) (xy 459.710222 -12.782124) (xy 459.765301 -12.665075) (xy 459.827621 -12.551715)
			(xy 459.896936 -12.442492) (xy 459.972972 -12.337837) (xy 460.05543 -12.238163) (xy 460.143983 -12.143863)
			(xy 460.238283 -12.05531) (xy 460.337957 -11.972852) (xy 460.442612 -11.896816) (xy 460.551835 -11.827501)
			(xy 460.665195 -11.765181) (xy 460.782244 -11.710102) (xy 460.90252 -11.662481) (xy 461.02555 -11.622506)
			(xy 461.150846 -11.590336) (xy 461.277916 -11.566096) (xy 461.406256 -11.549883) (xy 461.535362 -11.54176)
			(xy 461.664722 -11.54176) (xy 461.793828 -11.549883) (xy 461.922168 -11.566096) (xy 462.049238 -11.590336)
			(xy 462.174534 -11.622506) (xy 462.297564 -11.662481) (xy 462.41784 -11.710102) (xy 462.534889 -11.765181)
			(xy 462.648249 -11.827501) (xy 462.757472 -11.896816) (xy 462.862127 -11.972852) (xy 462.961801 -12.05531)
			(xy 463.056101 -12.143863) (xy 463.144654 -12.238163) (xy 463.227112 -12.337837) (xy 463.303148 -12.442492)
			(xy 463.372463 -12.551715) (xy 463.434783 -12.665075) (xy 463.489862 -12.782124) (xy 463.537483 -12.9024)
			(xy 463.577458 -13.02543) (xy 463.609628 -13.150726) (xy 463.633868 -13.277796) (xy 463.650081 -13.406136)
			(xy 463.658204 -13.535242) (xy 463.658712 -13.599922) (xy 463.658712 -15.200122) (xy 463.658204 -15.264802)
			(xy 463.650081 -15.393908) (xy 463.633868 -15.522248) (xy 463.609628 -15.649318) (xy 463.577458 -15.774614)
			(xy 463.537483 -15.897644) (xy 463.489862 -16.01792) (xy 463.434783 -16.134969) (xy 463.372463 -16.248329)
			(xy 463.303148 -16.357552) (xy 463.227112 -16.462207) (xy 463.144654 -16.561881) (xy 463.056101 -16.656181)
			(xy 462.961801 -16.744734) (xy 462.862127 -16.827192) (xy 462.757472 -16.903228) (xy 462.648249 -16.972543)
			(xy 462.534889 -17.034863) (xy 462.41784 -17.089942) (xy 462.297564 -17.137563) (xy 462.174534 -17.177538)
			(xy 462.049238 -17.209708) (xy 461.922168 -17.233948) (xy 461.793828 -17.250161) (xy 461.664722 -17.258284)
			(xy 461.535362 -17.258284) (xy 461.406256 -17.250161) (xy 461.277916 -17.233948) (xy 461.150846 -17.209708)
			(xy 461.02555 -17.177538) (xy 460.90252 -17.137563) (xy 460.782244 -17.089942) (xy 460.665195 -17.034863)
			(xy 460.551835 -16.972543) (xy 460.442612 -16.903228) (xy 460.337957 -16.827192) (xy 460.238283 -16.744734)
			(xy 460.143983 -16.656181) (xy 460.05543 -16.561881) (xy 459.972972 -16.462207) (xy 459.896936 -16.357552)
			(xy 459.827621 -16.248329) (xy 459.765301 -16.134969) (xy 459.710222 -16.01792) (xy 459.662601 -15.897644)
			(xy 459.622626 -15.774614) (xy 459.590456 -15.649318) (xy 459.566216 -15.522248) (xy 459.550003 -15.393908)
			(xy 459.54188 -15.264802) (xy 459.541372 -15.200122) (xy 0.508 -15.200122) (xy 0.508 -16.969994)
			(xy 13.748265 -16.969994) (xy 13.75227 -16.882086) (xy 13.764253 -16.794906) (xy 13.784113 -16.709177)
			(xy 13.811688 -16.625609) (xy 13.846747 -16.544895) (xy 13.889 -16.467703) (xy 13.938098 -16.394674)
			(xy 13.993634 -16.326412) (xy 14.055146 -16.263482) (xy 14.122127 -16.206408) (xy 14.19402 -16.15566)
			(xy 14.270229 -16.11166) (xy 14.350124 -16.074773) (xy 14.433043 -16.045304) (xy 14.518298 -16.023497)
			(xy 14.605182 -16.009533) (xy 14.692976 -16.003527) (xy 14.780953 -16.005531) (xy 14.868383 -16.015526)
			(xy 14.954542 -16.03343) (xy 15.038716 -16.059094) (xy 15.120207 -16.092307) (xy 15.198341 -16.132793)
			(xy 15.272469 -16.180215) (xy 15.341977 -16.234182) (xy 15.406291 -16.294247) (xy 15.464875 -16.359911)
			(xy 15.517246 -16.43063) (xy 15.562969 -16.505818) (xy 15.601666 -16.584853) (xy 15.633015 -16.667079)
			(xy 15.656757 -16.751815) (xy 15.672695 -16.838359) (xy 15.680697 -16.925994) (xy 15.681198 -16.969994)
			(xy 39.748213 -16.969994) (xy 39.752218 -16.882086) (xy 39.764201 -16.794906) (xy 39.784061 -16.709177)
			(xy 39.811636 -16.625609) (xy 39.846695 -16.544895) (xy 39.888948 -16.467703) (xy 39.938046 -16.394674)
			(xy 39.993582 -16.326412) (xy 40.055094 -16.263482) (xy 40.122075 -16.206408) (xy 40.193968 -16.15566)
			(xy 40.270177 -16.11166) (xy 40.350072 -16.074773) (xy 40.432991 -16.045304) (xy 40.518246 -16.023497)
			(xy 40.60513 -16.009533) (xy 40.692924 -16.003527) (xy 40.780901 -16.005531) (xy 40.868331 -16.015526)
			(xy 40.95449 -16.03343) (xy 41.038664 -16.059094) (xy 41.120155 -16.092307) (xy 41.198289 -16.132793)
			(xy 41.272417 -16.180215) (xy 41.341925 -16.234182) (xy 41.406239 -16.294247) (xy 41.464823 -16.359911)
			(xy 41.517194 -16.43063) (xy 41.562917 -16.505818) (xy 41.601614 -16.584853) (xy 41.632963 -16.667079)
			(xy 41.656705 -16.751815) (xy 41.672643 -16.838359) (xy 41.680645 -16.925994) (xy 41.681146 -16.969994)
			(xy 65.748161 -16.969994) (xy 65.752166 -16.882086) (xy 65.764149 -16.794906) (xy 65.784009 -16.709177)
			(xy 65.811584 -16.625609) (xy 65.846643 -16.544895) (xy 65.888896 -16.467703) (xy 65.937994 -16.394674)
			(xy 65.99353 -16.326412) (xy 66.055042 -16.263482) (xy 66.122023 -16.206408) (xy 66.193916 -16.15566)
			(xy 66.270125 -16.11166) (xy 66.35002 -16.074773) (xy 66.432939 -16.045304) (xy 66.518194 -16.023497)
			(xy 66.605078 -16.009533) (xy 66.692872 -16.003527) (xy 66.780849 -16.005531) (xy 66.868279 -16.015526)
			(xy 66.954438 -16.03343) (xy 67.038612 -16.059094) (xy 67.120103 -16.092307) (xy 67.198237 -16.132793)
			(xy 67.272365 -16.180215) (xy 67.341873 -16.234182) (xy 67.406187 -16.294247) (xy 67.464771 -16.359911)
			(xy 67.517142 -16.43063) (xy 67.562865 -16.505818) (xy 67.601562 -16.584853) (xy 67.632911 -16.667079)
			(xy 67.656653 -16.751815) (xy 67.672591 -16.838359) (xy 67.680593 -16.925994) (xy 67.681094 -16.969994)
			(xy 91.748109 -16.969994) (xy 91.752114 -16.882086) (xy 91.764097 -16.794906) (xy 91.783957 -16.709177)
			(xy 91.811532 -16.625609) (xy 91.846591 -16.544895) (xy 91.888844 -16.467703) (xy 91.937942 -16.394674)
			(xy 91.993478 -16.326412) (xy 92.05499 -16.263482) (xy 92.121971 -16.206408) (xy 92.193864 -16.15566)
			(xy 92.270073 -16.11166) (xy 92.349968 -16.074773) (xy 92.432887 -16.045304) (xy 92.518142 -16.023497)
			(xy 92.605026 -16.009533) (xy 92.69282 -16.003527) (xy 92.780797 -16.005531) (xy 92.868227 -16.015526)
			(xy 92.954386 -16.03343) (xy 93.03856 -16.059094) (xy 93.120051 -16.092307) (xy 93.198185 -16.132793)
			(xy 93.272313 -16.180215) (xy 93.341821 -16.234182) (xy 93.406135 -16.294247) (xy 93.464719 -16.359911)
			(xy 93.51709 -16.43063) (xy 93.562813 -16.505818) (xy 93.60151 -16.584853) (xy 93.632859 -16.667079)
			(xy 93.656601 -16.751815) (xy 93.672539 -16.838359) (xy 93.680541 -16.925994) (xy 93.681042 -16.969994)
			(xy 129.848363 -16.969994) (xy 129.852368 -16.882086) (xy 129.864351 -16.794906) (xy 129.884211 -16.709177)
			(xy 129.911786 -16.625609) (xy 129.946845 -16.544895) (xy 129.989098 -16.467703) (xy 130.038196 -16.394674)
			(xy 130.093732 -16.326412) (xy 130.155244 -16.263482) (xy 130.222225 -16.206408) (xy 130.294118 -16.15566)
			(xy 130.370327 -16.11166) (xy 130.450222 -16.074773) (xy 130.533141 -16.045304) (xy 130.618396 -16.023497)
			(xy 130.70528 -16.009533) (xy 130.793074 -16.003527) (xy 130.881051 -16.005531) (xy 130.968481 -16.015526)
			(xy 131.05464 -16.03343) (xy 131.138814 -16.059094) (xy 131.220305 -16.092307) (xy 131.298439 -16.132793)
			(xy 131.372567 -16.180215) (xy 131.442075 -16.234182) (xy 131.506389 -16.294247) (xy 131.564973 -16.359911)
			(xy 131.617344 -16.43063) (xy 131.663067 -16.505818) (xy 131.701764 -16.584853) (xy 131.733113 -16.667079)
			(xy 131.756855 -16.751815) (xy 131.772793 -16.838359) (xy 131.780795 -16.925994) (xy 131.781296 -16.969994)
			(xy 155.848311 -16.969994) (xy 155.852316 -16.882086) (xy 155.864299 -16.794906) (xy 155.884159 -16.709177)
			(xy 155.911734 -16.625609) (xy 155.946793 -16.544895) (xy 155.989046 -16.467703) (xy 156.038144 -16.394674)
			(xy 156.09368 -16.326412) (xy 156.155192 -16.263482) (xy 156.222173 -16.206408) (xy 156.294066 -16.15566)
			(xy 156.370275 -16.11166) (xy 156.45017 -16.074773) (xy 156.533089 -16.045304) (xy 156.618344 -16.023497)
			(xy 156.705228 -16.009533) (xy 156.793022 -16.003527) (xy 156.880999 -16.005531) (xy 156.968429 -16.015526)
			(xy 157.054588 -16.03343) (xy 157.138762 -16.059094) (xy 157.220253 -16.092307) (xy 157.298387 -16.132793)
			(xy 157.372515 -16.180215) (xy 157.442023 -16.234182) (xy 157.506337 -16.294247) (xy 157.564921 -16.359911)
			(xy 157.617292 -16.43063) (xy 157.663015 -16.505818) (xy 157.701712 -16.584853) (xy 157.733061 -16.667079)
			(xy 157.756803 -16.751815) (xy 157.772741 -16.838359) (xy 157.780743 -16.925994) (xy 157.781244 -16.969994)
			(xy 181.848259 -16.969994) (xy 181.852264 -16.882086) (xy 181.864247 -16.794906) (xy 181.884107 -16.709177)
			(xy 181.911682 -16.625609) (xy 181.946741 -16.544895) (xy 181.988994 -16.467703) (xy 182.038092 -16.394674)
			(xy 182.093628 -16.326412) (xy 182.15514 -16.263482) (xy 182.222121 -16.206408) (xy 182.294014 -16.15566)
			(xy 182.370223 -16.11166) (xy 182.450118 -16.074773) (xy 182.533037 -16.045304) (xy 182.618292 -16.023497)
			(xy 182.705176 -16.009533) (xy 182.79297 -16.003527) (xy 182.880947 -16.005531) (xy 182.968377 -16.015526)
			(xy 183.054536 -16.03343) (xy 183.13871 -16.059094) (xy 183.220201 -16.092307) (xy 183.298335 -16.132793)
			(xy 183.372463 -16.180215) (xy 183.441971 -16.234182) (xy 183.506285 -16.294247) (xy 183.564869 -16.359911)
			(xy 183.61724 -16.43063) (xy 183.662963 -16.505818) (xy 183.70166 -16.584853) (xy 183.733009 -16.667079)
			(xy 183.756751 -16.751815) (xy 183.772689 -16.838359) (xy 183.780691 -16.925994) (xy 183.781192 -16.969994)
			(xy 207.848207 -16.969994) (xy 207.852212 -16.882086) (xy 207.864195 -16.794906) (xy 207.884055 -16.709177)
			(xy 207.91163 -16.625609) (xy 207.946689 -16.544895) (xy 207.988942 -16.467703) (xy 208.03804 -16.394674)
			(xy 208.093576 -16.326412) (xy 208.155088 -16.263482) (xy 208.222069 -16.206408) (xy 208.293962 -16.15566)
			(xy 208.370171 -16.11166) (xy 208.450066 -16.074773) (xy 208.532985 -16.045304) (xy 208.61824 -16.023497)
			(xy 208.705124 -16.009533) (xy 208.792918 -16.003527) (xy 208.880895 -16.005531) (xy 208.968325 -16.015526)
			(xy 209.054484 -16.03343) (xy 209.138658 -16.059094) (xy 209.220149 -16.092307) (xy 209.298283 -16.132793)
			(xy 209.372411 -16.180215) (xy 209.441919 -16.234182) (xy 209.506233 -16.294247) (xy 209.564817 -16.359911)
			(xy 209.617188 -16.43063) (xy 209.662911 -16.505818) (xy 209.701608 -16.584853) (xy 209.732957 -16.667079)
			(xy 209.756699 -16.751815) (xy 209.772637 -16.838359) (xy 209.780639 -16.925994) (xy 209.78114 -16.969994)
			(xy 245.948207 -16.969994) (xy 245.952212 -16.882086) (xy 245.964195 -16.794906) (xy 245.984055 -16.709177)
			(xy 246.01163 -16.625609) (xy 246.046689 -16.544895) (xy 246.088942 -16.467703) (xy 246.13804 -16.394674)
			(xy 246.193576 -16.326412) (xy 246.255088 -16.263482) (xy 246.322069 -16.206408) (xy 246.393962 -16.15566)
			(xy 246.470171 -16.11166) (xy 246.550066 -16.074773) (xy 246.632985 -16.045304) (xy 246.71824 -16.023497)
			(xy 246.805124 -16.009533) (xy 246.892918 -16.003527) (xy 246.980895 -16.005531) (xy 247.068325 -16.015526)
			(xy 247.154484 -16.03343) (xy 247.238658 -16.059094) (xy 247.320149 -16.092307) (xy 247.398283 -16.132793)
			(xy 247.472411 -16.180215) (xy 247.541919 -16.234182) (xy 247.606233 -16.294247) (xy 247.664817 -16.359911)
			(xy 247.717188 -16.43063) (xy 247.762911 -16.505818) (xy 247.801608 -16.584853) (xy 247.832957 -16.667079)
			(xy 247.856699 -16.751815) (xy 247.872637 -16.838359) (xy 247.880639 -16.925994) (xy 247.88114 -16.969994)
			(xy 271.948155 -16.969994) (xy 271.95216 -16.882086) (xy 271.964143 -16.794906) (xy 271.984003 -16.709177)
			(xy 272.011578 -16.625609) (xy 272.046637 -16.544895) (xy 272.08889 -16.467703) (xy 272.137988 -16.394674)
			(xy 272.193524 -16.326412) (xy 272.255036 -16.263482) (xy 272.322017 -16.206408) (xy 272.39391 -16.15566)
			(xy 272.470119 -16.11166) (xy 272.550014 -16.074773) (xy 272.632933 -16.045304) (xy 272.718188 -16.023497)
			(xy 272.805072 -16.009533) (xy 272.892866 -16.003527) (xy 272.980843 -16.005531) (xy 273.068273 -16.015526)
			(xy 273.154432 -16.03343) (xy 273.238606 -16.059094) (xy 273.320097 -16.092307) (xy 273.398231 -16.132793)
			(xy 273.472359 -16.180215) (xy 273.541867 -16.234182) (xy 273.606181 -16.294247) (xy 273.664765 -16.359911)
			(xy 273.717136 -16.43063) (xy 273.762859 -16.505818) (xy 273.801556 -16.584853) (xy 273.832905 -16.667079)
			(xy 273.856647 -16.751815) (xy 273.872585 -16.838359) (xy 273.880587 -16.925994) (xy 273.881088 -16.969994)
			(xy 297.948103 -16.969994) (xy 297.952108 -16.882086) (xy 297.964091 -16.794906) (xy 297.983951 -16.709177)
			(xy 298.011526 -16.625609) (xy 298.046585 -16.544895) (xy 298.088838 -16.467703) (xy 298.137936 -16.394674)
			(xy 298.193472 -16.326412) (xy 298.254984 -16.263482) (xy 298.321965 -16.206408) (xy 298.393858 -16.15566)
			(xy 298.470067 -16.11166) (xy 298.549962 -16.074773) (xy 298.632881 -16.045304) (xy 298.718136 -16.023497)
			(xy 298.80502 -16.009533) (xy 298.892814 -16.003527) (xy 298.980791 -16.005531) (xy 299.068221 -16.015526)
			(xy 299.15438 -16.03343) (xy 299.238554 -16.059094) (xy 299.320045 -16.092307) (xy 299.398179 -16.132793)
			(xy 299.472307 -16.180215) (xy 299.541815 -16.234182) (xy 299.606129 -16.294247) (xy 299.664713 -16.359911)
			(xy 299.717084 -16.43063) (xy 299.762807 -16.505818) (xy 299.801504 -16.584853) (xy 299.832853 -16.667079)
			(xy 299.856595 -16.751815) (xy 299.872533 -16.838359) (xy 299.880535 -16.925994) (xy 299.881036 -16.969994)
			(xy 323.948051 -16.969994) (xy 323.952056 -16.882086) (xy 323.964039 -16.794906) (xy 323.983899 -16.709177)
			(xy 324.011474 -16.625609) (xy 324.046533 -16.544895) (xy 324.088786 -16.467703) (xy 324.137884 -16.394674)
			(xy 324.19342 -16.326412) (xy 324.254932 -16.263482) (xy 324.321913 -16.206408) (xy 324.393806 -16.15566)
			(xy 324.470015 -16.11166) (xy 324.54991 -16.074773) (xy 324.632829 -16.045304) (xy 324.718084 -16.023497)
			(xy 324.804968 -16.009533) (xy 324.892762 -16.003527) (xy 324.980739 -16.005531) (xy 325.068169 -16.015526)
			(xy 325.154328 -16.03343) (xy 325.238502 -16.059094) (xy 325.319993 -16.092307) (xy 325.398127 -16.132793)
			(xy 325.472255 -16.180215) (xy 325.541763 -16.234182) (xy 325.606077 -16.294247) (xy 325.664661 -16.359911)
			(xy 325.717032 -16.43063) (xy 325.762755 -16.505818) (xy 325.801452 -16.584853) (xy 325.832801 -16.667079)
			(xy 325.856543 -16.751815) (xy 325.872481 -16.838359) (xy 325.880483 -16.925994) (xy 325.880984 -16.969994)
			(xy 362.048305 -16.969994) (xy 362.05231 -16.882086) (xy 362.064293 -16.794906) (xy 362.084153 -16.709177)
			(xy 362.111728 -16.625609) (xy 362.146787 -16.544895) (xy 362.18904 -16.467703) (xy 362.238138 -16.394674)
			(xy 362.293674 -16.326412) (xy 362.355186 -16.263482) (xy 362.422167 -16.206408) (xy 362.49406 -16.15566)
			(xy 362.570269 -16.11166) (xy 362.650164 -16.074773) (xy 362.733083 -16.045304) (xy 362.818338 -16.023497)
			(xy 362.905222 -16.009533) (xy 362.993016 -16.003527) (xy 363.080993 -16.005531) (xy 363.168423 -16.015526)
			(xy 363.254582 -16.03343) (xy 363.338756 -16.059094) (xy 363.420247 -16.092307) (xy 363.498381 -16.132793)
			(xy 363.572509 -16.180215) (xy 363.642017 -16.234182) (xy 363.706331 -16.294247) (xy 363.764915 -16.359911)
			(xy 363.817286 -16.43063) (xy 363.863009 -16.505818) (xy 363.901706 -16.584853) (xy 363.933055 -16.667079)
			(xy 363.956797 -16.751815) (xy 363.972735 -16.838359) (xy 363.980737 -16.925994) (xy 363.981238 -16.969994)
			(xy 388.048253 -16.969994) (xy 388.052258 -16.882086) (xy 388.064241 -16.794906) (xy 388.084101 -16.709177)
			(xy 388.111676 -16.625609) (xy 388.146735 -16.544895) (xy 388.188988 -16.467703) (xy 388.238086 -16.394674)
			(xy 388.293622 -16.326412) (xy 388.355134 -16.263482) (xy 388.422115 -16.206408) (xy 388.494008 -16.15566)
			(xy 388.570217 -16.11166) (xy 388.650112 -16.074773) (xy 388.733031 -16.045304) (xy 388.818286 -16.023497)
			(xy 388.90517 -16.009533) (xy 388.992964 -16.003527) (xy 389.080941 -16.005531) (xy 389.168371 -16.015526)
			(xy 389.25453 -16.03343) (xy 389.338704 -16.059094) (xy 389.420195 -16.092307) (xy 389.498329 -16.132793)
			(xy 389.572457 -16.180215) (xy 389.641965 -16.234182) (xy 389.706279 -16.294247) (xy 389.764863 -16.359911)
			(xy 389.817234 -16.43063) (xy 389.862957 -16.505818) (xy 389.901654 -16.584853) (xy 389.933003 -16.667079)
			(xy 389.956745 -16.751815) (xy 389.972683 -16.838359) (xy 389.980685 -16.925994) (xy 389.981186 -16.969994)
			(xy 414.048201 -16.969994) (xy 414.052206 -16.882086) (xy 414.064189 -16.794906) (xy 414.084049 -16.709177)
			(xy 414.111624 -16.625609) (xy 414.146683 -16.544895) (xy 414.188936 -16.467703) (xy 414.238034 -16.394674)
			(xy 414.29357 -16.326412) (xy 414.355082 -16.263482) (xy 414.422063 -16.206408) (xy 414.493956 -16.15566)
			(xy 414.570165 -16.11166) (xy 414.65006 -16.074773) (xy 414.732979 -16.045304) (xy 414.818234 -16.023497)
			(xy 414.905118 -16.009533) (xy 414.992912 -16.003527) (xy 415.080889 -16.005531) (xy 415.168319 -16.015526)
			(xy 415.254478 -16.03343) (xy 415.338652 -16.059094) (xy 415.420143 -16.092307) (xy 415.498277 -16.132793)
			(xy 415.572405 -16.180215) (xy 415.641913 -16.234182) (xy 415.706227 -16.294247) (xy 415.764811 -16.359911)
			(xy 415.817182 -16.43063) (xy 415.862905 -16.505818) (xy 415.901602 -16.584853) (xy 415.932951 -16.667079)
			(xy 415.956693 -16.751815) (xy 415.972631 -16.838359) (xy 415.980633 -16.925994) (xy 415.981134 -16.969994)
			(xy 440.048149 -16.969994) (xy 440.052154 -16.882086) (xy 440.064137 -16.794906) (xy 440.083997 -16.709177)
			(xy 440.111572 -16.625609) (xy 440.146631 -16.544895) (xy 440.188884 -16.467703) (xy 440.237982 -16.394674)
			(xy 440.293518 -16.326412) (xy 440.35503 -16.263482) (xy 440.422011 -16.206408) (xy 440.493904 -16.15566)
			(xy 440.570113 -16.11166) (xy 440.650008 -16.074773) (xy 440.732927 -16.045304) (xy 440.818182 -16.023497)
			(xy 440.905066 -16.009533) (xy 440.99286 -16.003527) (xy 441.080837 -16.005531) (xy 441.168267 -16.015526)
			(xy 441.254426 -16.03343) (xy 441.3386 -16.059094) (xy 441.420091 -16.092307) (xy 441.498225 -16.132793)
			(xy 441.572353 -16.180215) (xy 441.641861 -16.234182) (xy 441.706175 -16.294247) (xy 441.764759 -16.359911)
			(xy 441.81713 -16.43063) (xy 441.862853 -16.505818) (xy 441.90155 -16.584853) (xy 441.932899 -16.667079)
			(xy 441.956641 -16.751815) (xy 441.972579 -16.838359) (xy 441.980581 -16.925994) (xy 441.981082 -16.969994)
			(xy 441.980581 -17.013994) (xy 441.972579 -17.101629) (xy 441.956641 -17.188173) (xy 441.932899 -17.272909)
			(xy 441.90155 -17.355135) (xy 441.862853 -17.43417) (xy 441.81713 -17.509358) (xy 441.764759 -17.580077)
			(xy 441.706175 -17.645741) (xy 441.641861 -17.705806) (xy 441.572353 -17.759773) (xy 441.498225 -17.807195)
			(xy 441.420091 -17.847681) (xy 441.3386 -17.880894) (xy 441.254426 -17.906558) (xy 441.168267 -17.924462)
			(xy 441.080837 -17.934457) (xy 440.99286 -17.936461) (xy 440.905066 -17.930455) (xy 440.818182 -17.916491)
			(xy 440.732927 -17.894684) (xy 440.650008 -17.865215) (xy 440.570113 -17.828328) (xy 440.493904 -17.784328)
			(xy 440.422011 -17.73358) (xy 440.35503 -17.676506) (xy 440.293518 -17.613576) (xy 440.237982 -17.545314)
			(xy 440.188884 -17.472285) (xy 440.146631 -17.395093) (xy 440.111572 -17.314379) (xy 440.083997 -17.230811)
			(xy 440.064137 -17.145082) (xy 440.052154 -17.057902) (xy 440.048149 -16.969994) (xy 415.981134 -16.969994)
			(xy 415.980633 -17.013994) (xy 415.972631 -17.101629) (xy 415.956693 -17.188173) (xy 415.932951 -17.272909)
			(xy 415.901602 -17.355135) (xy 415.862905 -17.43417) (xy 415.817182 -17.509358) (xy 415.764811 -17.580077)
			(xy 415.706227 -17.645741) (xy 415.641913 -17.705806) (xy 415.572405 -17.759773) (xy 415.498277 -17.807195)
			(xy 415.420143 -17.847681) (xy 415.338652 -17.880894) (xy 415.254478 -17.906558) (xy 415.168319 -17.924462)
			(xy 415.080889 -17.934457) (xy 414.992912 -17.936461) (xy 414.905118 -17.930455) (xy 414.818234 -17.916491)
			(xy 414.732979 -17.894684) (xy 414.65006 -17.865215) (xy 414.570165 -17.828328) (xy 414.493956 -17.784328)
			(xy 414.422063 -17.73358) (xy 414.355082 -17.676506) (xy 414.29357 -17.613576) (xy 414.238034 -17.545314)
			(xy 414.188936 -17.472285) (xy 414.146683 -17.395093) (xy 414.111624 -17.314379) (xy 414.084049 -17.230811)
			(xy 414.064189 -17.145082) (xy 414.052206 -17.057902) (xy 414.048201 -16.969994) (xy 389.981186 -16.969994)
			(xy 389.980685 -17.013994) (xy 389.972683 -17.101629) (xy 389.956745 -17.188173) (xy 389.933003 -17.272909)
			(xy 389.901654 -17.355135) (xy 389.862957 -17.43417) (xy 389.817234 -17.509358) (xy 389.764863 -17.580077)
			(xy 389.706279 -17.645741) (xy 389.641965 -17.705806) (xy 389.572457 -17.759773) (xy 389.498329 -17.807195)
			(xy 389.420195 -17.847681) (xy 389.338704 -17.880894) (xy 389.25453 -17.906558) (xy 389.168371 -17.924462)
			(xy 389.080941 -17.934457) (xy 388.992964 -17.936461) (xy 388.90517 -17.930455) (xy 388.818286 -17.916491)
			(xy 388.733031 -17.894684) (xy 388.650112 -17.865215) (xy 388.570217 -17.828328) (xy 388.494008 -17.784328)
			(xy 388.422115 -17.73358) (xy 388.355134 -17.676506) (xy 388.293622 -17.613576) (xy 388.238086 -17.545314)
			(xy 388.188988 -17.472285) (xy 388.146735 -17.395093) (xy 388.111676 -17.314379) (xy 388.084101 -17.230811)
			(xy 388.064241 -17.145082) (xy 388.052258 -17.057902) (xy 388.048253 -16.969994) (xy 363.981238 -16.969994)
			(xy 363.980737 -17.013994) (xy 363.972735 -17.101629) (xy 363.956797 -17.188173) (xy 363.933055 -17.272909)
			(xy 363.901706 -17.355135) (xy 363.863009 -17.43417) (xy 363.817286 -17.509358) (xy 363.764915 -17.580077)
			(xy 363.706331 -17.645741) (xy 363.642017 -17.705806) (xy 363.572509 -17.759773) (xy 363.498381 -17.807195)
			(xy 363.420247 -17.847681) (xy 363.338756 -17.880894) (xy 363.254582 -17.906558) (xy 363.168423 -17.924462)
			(xy 363.080993 -17.934457) (xy 362.993016 -17.936461) (xy 362.905222 -17.930455) (xy 362.818338 -17.916491)
			(xy 362.733083 -17.894684) (xy 362.650164 -17.865215) (xy 362.570269 -17.828328) (xy 362.49406 -17.784328)
			(xy 362.422167 -17.73358) (xy 362.355186 -17.676506) (xy 362.293674 -17.613576) (xy 362.238138 -17.545314)
			(xy 362.18904 -17.472285) (xy 362.146787 -17.395093) (xy 362.111728 -17.314379) (xy 362.084153 -17.230811)
			(xy 362.064293 -17.145082) (xy 362.05231 -17.057902) (xy 362.048305 -16.969994) (xy 325.880984 -16.969994)
			(xy 325.880483 -17.013994) (xy 325.872481 -17.101629) (xy 325.856543 -17.188173) (xy 325.832801 -17.272909)
			(xy 325.801452 -17.355135) (xy 325.762755 -17.43417) (xy 325.717032 -17.509358) (xy 325.664661 -17.580077)
			(xy 325.606077 -17.645741) (xy 325.541763 -17.705806) (xy 325.472255 -17.759773) (xy 325.398127 -17.807195)
			(xy 325.319993 -17.847681) (xy 325.238502 -17.880894) (xy 325.154328 -17.906558) (xy 325.068169 -17.924462)
			(xy 324.980739 -17.934457) (xy 324.892762 -17.936461) (xy 324.804968 -17.930455) (xy 324.718084 -17.916491)
			(xy 324.632829 -17.894684) (xy 324.54991 -17.865215) (xy 324.470015 -17.828328) (xy 324.393806 -17.784328)
			(xy 324.321913 -17.73358) (xy 324.254932 -17.676506) (xy 324.19342 -17.613576) (xy 324.137884 -17.545314)
			(xy 324.088786 -17.472285) (xy 324.046533 -17.395093) (xy 324.011474 -17.314379) (xy 323.983899 -17.230811)
			(xy 323.964039 -17.145082) (xy 323.952056 -17.057902) (xy 323.948051 -16.969994) (xy 299.881036 -16.969994)
			(xy 299.880535 -17.013994) (xy 299.872533 -17.101629) (xy 299.856595 -17.188173) (xy 299.832853 -17.272909)
			(xy 299.801504 -17.355135) (xy 299.762807 -17.43417) (xy 299.717084 -17.509358) (xy 299.664713 -17.580077)
			(xy 299.606129 -17.645741) (xy 299.541815 -17.705806) (xy 299.472307 -17.759773) (xy 299.398179 -17.807195)
			(xy 299.320045 -17.847681) (xy 299.238554 -17.880894) (xy 299.15438 -17.906558) (xy 299.068221 -17.924462)
			(xy 298.980791 -17.934457) (xy 298.892814 -17.936461) (xy 298.80502 -17.930455) (xy 298.718136 -17.916491)
			(xy 298.632881 -17.894684) (xy 298.549962 -17.865215) (xy 298.470067 -17.828328) (xy 298.393858 -17.784328)
			(xy 298.321965 -17.73358) (xy 298.254984 -17.676506) (xy 298.193472 -17.613576) (xy 298.137936 -17.545314)
			(xy 298.088838 -17.472285) (xy 298.046585 -17.395093) (xy 298.011526 -17.314379) (xy 297.983951 -17.230811)
			(xy 297.964091 -17.145082) (xy 297.952108 -17.057902) (xy 297.948103 -16.969994) (xy 273.881088 -16.969994)
			(xy 273.880587 -17.013994) (xy 273.872585 -17.101629) (xy 273.856647 -17.188173) (xy 273.832905 -17.272909)
			(xy 273.801556 -17.355135) (xy 273.762859 -17.43417) (xy 273.717136 -17.509358) (xy 273.664765 -17.580077)
			(xy 273.606181 -17.645741) (xy 273.541867 -17.705806) (xy 273.472359 -17.759773) (xy 273.398231 -17.807195)
			(xy 273.320097 -17.847681) (xy 273.238606 -17.880894) (xy 273.154432 -17.906558) (xy 273.068273 -17.924462)
			(xy 272.980843 -17.934457) (xy 272.892866 -17.936461) (xy 272.805072 -17.930455) (xy 272.718188 -17.916491)
			(xy 272.632933 -17.894684) (xy 272.550014 -17.865215) (xy 272.470119 -17.828328) (xy 272.39391 -17.784328)
			(xy 272.322017 -17.73358) (xy 272.255036 -17.676506) (xy 272.193524 -17.613576) (xy 272.137988 -17.545314)
			(xy 272.08889 -17.472285) (xy 272.046637 -17.395093) (xy 272.011578 -17.314379) (xy 271.984003 -17.230811)
			(xy 271.964143 -17.145082) (xy 271.95216 -17.057902) (xy 271.948155 -16.969994) (xy 247.88114 -16.969994)
			(xy 247.880639 -17.013994) (xy 247.872637 -17.101629) (xy 247.856699 -17.188173) (xy 247.832957 -17.272909)
			(xy 247.801608 -17.355135) (xy 247.762911 -17.43417) (xy 247.717188 -17.509358) (xy 247.664817 -17.580077)
			(xy 247.606233 -17.645741) (xy 247.541919 -17.705806) (xy 247.472411 -17.759773) (xy 247.398283 -17.807195)
			(xy 247.320149 -17.847681) (xy 247.238658 -17.880894) (xy 247.154484 -17.906558) (xy 247.068325 -17.924462)
			(xy 246.980895 -17.934457) (xy 246.892918 -17.936461) (xy 246.805124 -17.930455) (xy 246.71824 -17.916491)
			(xy 246.632985 -17.894684) (xy 246.550066 -17.865215) (xy 246.470171 -17.828328) (xy 246.393962 -17.784328)
			(xy 246.322069 -17.73358) (xy 246.255088 -17.676506) (xy 246.193576 -17.613576) (xy 246.13804 -17.545314)
			(xy 246.088942 -17.472285) (xy 246.046689 -17.395093) (xy 246.01163 -17.314379) (xy 245.984055 -17.230811)
			(xy 245.964195 -17.145082) (xy 245.952212 -17.057902) (xy 245.948207 -16.969994) (xy 209.78114 -16.969994)
			(xy 209.780639 -17.013994) (xy 209.772637 -17.101629) (xy 209.756699 -17.188173) (xy 209.732957 -17.272909)
			(xy 209.701608 -17.355135) (xy 209.662911 -17.43417) (xy 209.617188 -17.509358) (xy 209.564817 -17.580077)
			(xy 209.506233 -17.645741) (xy 209.441919 -17.705806) (xy 209.372411 -17.759773) (xy 209.298283 -17.807195)
			(xy 209.220149 -17.847681) (xy 209.138658 -17.880894) (xy 209.054484 -17.906558) (xy 208.968325 -17.924462)
			(xy 208.880895 -17.934457) (xy 208.792918 -17.936461) (xy 208.705124 -17.930455) (xy 208.61824 -17.916491)
			(xy 208.532985 -17.894684) (xy 208.450066 -17.865215) (xy 208.370171 -17.828328) (xy 208.293962 -17.784328)
			(xy 208.222069 -17.73358) (xy 208.155088 -17.676506) (xy 208.093576 -17.613576) (xy 208.03804 -17.545314)
			(xy 207.988942 -17.472285) (xy 207.946689 -17.395093) (xy 207.91163 -17.314379) (xy 207.884055 -17.230811)
			(xy 207.864195 -17.145082) (xy 207.852212 -17.057902) (xy 207.848207 -16.969994) (xy 183.781192 -16.969994)
			(xy 183.780691 -17.013994) (xy 183.772689 -17.101629) (xy 183.756751 -17.188173) (xy 183.733009 -17.272909)
			(xy 183.70166 -17.355135) (xy 183.662963 -17.43417) (xy 183.61724 -17.509358) (xy 183.564869 -17.580077)
			(xy 183.506285 -17.645741) (xy 183.441971 -17.705806) (xy 183.372463 -17.759773) (xy 183.298335 -17.807195)
			(xy 183.220201 -17.847681) (xy 183.13871 -17.880894) (xy 183.054536 -17.906558) (xy 182.968377 -17.924462)
			(xy 182.880947 -17.934457) (xy 182.79297 -17.936461) (xy 182.705176 -17.930455) (xy 182.618292 -17.916491)
			(xy 182.533037 -17.894684) (xy 182.450118 -17.865215) (xy 182.370223 -17.828328) (xy 182.294014 -17.784328)
			(xy 182.222121 -17.73358) (xy 182.15514 -17.676506) (xy 182.093628 -17.613576) (xy 182.038092 -17.545314)
			(xy 181.988994 -17.472285) (xy 181.946741 -17.395093) (xy 181.911682 -17.314379) (xy 181.884107 -17.230811)
			(xy 181.864247 -17.145082) (xy 181.852264 -17.057902) (xy 181.848259 -16.969994) (xy 157.781244 -16.969994)
			(xy 157.780743 -17.013994) (xy 157.772741 -17.101629) (xy 157.756803 -17.188173) (xy 157.733061 -17.272909)
			(xy 157.701712 -17.355135) (xy 157.663015 -17.43417) (xy 157.617292 -17.509358) (xy 157.564921 -17.580077)
			(xy 157.506337 -17.645741) (xy 157.442023 -17.705806) (xy 157.372515 -17.759773) (xy 157.298387 -17.807195)
			(xy 157.220253 -17.847681) (xy 157.138762 -17.880894) (xy 157.054588 -17.906558) (xy 156.968429 -17.924462)
			(xy 156.880999 -17.934457) (xy 156.793022 -17.936461) (xy 156.705228 -17.930455) (xy 156.618344 -17.916491)
			(xy 156.533089 -17.894684) (xy 156.45017 -17.865215) (xy 156.370275 -17.828328) (xy 156.294066 -17.784328)
			(xy 156.222173 -17.73358) (xy 156.155192 -17.676506) (xy 156.09368 -17.613576) (xy 156.038144 -17.545314)
			(xy 155.989046 -17.472285) (xy 155.946793 -17.395093) (xy 155.911734 -17.314379) (xy 155.884159 -17.230811)
			(xy 155.864299 -17.145082) (xy 155.852316 -17.057902) (xy 155.848311 -16.969994) (xy 131.781296 -16.969994)
			(xy 131.780795 -17.013994) (xy 131.772793 -17.101629) (xy 131.756855 -17.188173) (xy 131.733113 -17.272909)
			(xy 131.701764 -17.355135) (xy 131.663067 -17.43417) (xy 131.617344 -17.509358) (xy 131.564973 -17.580077)
			(xy 131.506389 -17.645741) (xy 131.442075 -17.705806) (xy 131.372567 -17.759773) (xy 131.298439 -17.807195)
			(xy 131.220305 -17.847681) (xy 131.138814 -17.880894) (xy 131.05464 -17.906558) (xy 130.968481 -17.924462)
			(xy 130.881051 -17.934457) (xy 130.793074 -17.936461) (xy 130.70528 -17.930455) (xy 130.618396 -17.916491)
			(xy 130.533141 -17.894684) (xy 130.450222 -17.865215) (xy 130.370327 -17.828328) (xy 130.294118 -17.784328)
			(xy 130.222225 -17.73358) (xy 130.155244 -17.676506) (xy 130.093732 -17.613576) (xy 130.038196 -17.545314)
			(xy 129.989098 -17.472285) (xy 129.946845 -17.395093) (xy 129.911786 -17.314379) (xy 129.884211 -17.230811)
			(xy 129.864351 -17.145082) (xy 129.852368 -17.057902) (xy 129.848363 -16.969994) (xy 93.681042 -16.969994)
			(xy 93.680541 -17.013994) (xy 93.672539 -17.101629) (xy 93.656601 -17.188173) (xy 93.632859 -17.272909)
			(xy 93.60151 -17.355135) (xy 93.562813 -17.43417) (xy 93.51709 -17.509358) (xy 93.464719 -17.580077)
			(xy 93.406135 -17.645741) (xy 93.341821 -17.705806) (xy 93.272313 -17.759773) (xy 93.198185 -17.807195)
			(xy 93.120051 -17.847681) (xy 93.03856 -17.880894) (xy 92.954386 -17.906558) (xy 92.868227 -17.924462)
			(xy 92.780797 -17.934457) (xy 92.69282 -17.936461) (xy 92.605026 -17.930455) (xy 92.518142 -17.916491)
			(xy 92.432887 -17.894684) (xy 92.349968 -17.865215) (xy 92.270073 -17.828328) (xy 92.193864 -17.784328)
			(xy 92.121971 -17.73358) (xy 92.05499 -17.676506) (xy 91.993478 -17.613576) (xy 91.937942 -17.545314)
			(xy 91.888844 -17.472285) (xy 91.846591 -17.395093) (xy 91.811532 -17.314379) (xy 91.783957 -17.230811)
			(xy 91.764097 -17.145082) (xy 91.752114 -17.057902) (xy 91.748109 -16.969994) (xy 67.681094 -16.969994)
			(xy 67.680593 -17.013994) (xy 67.672591 -17.101629) (xy 67.656653 -17.188173) (xy 67.632911 -17.272909)
			(xy 67.601562 -17.355135) (xy 67.562865 -17.43417) (xy 67.517142 -17.509358) (xy 67.464771 -17.580077)
			(xy 67.406187 -17.645741) (xy 67.341873 -17.705806) (xy 67.272365 -17.759773) (xy 67.198237 -17.807195)
			(xy 67.120103 -17.847681) (xy 67.038612 -17.880894) (xy 66.954438 -17.906558) (xy 66.868279 -17.924462)
			(xy 66.780849 -17.934457) (xy 66.692872 -17.936461) (xy 66.605078 -17.930455) (xy 66.518194 -17.916491)
			(xy 66.432939 -17.894684) (xy 66.35002 -17.865215) (xy 66.270125 -17.828328) (xy 66.193916 -17.784328)
			(xy 66.122023 -17.73358) (xy 66.055042 -17.676506) (xy 65.99353 -17.613576) (xy 65.937994 -17.545314)
			(xy 65.888896 -17.472285) (xy 65.846643 -17.395093) (xy 65.811584 -17.314379) (xy 65.784009 -17.230811)
			(xy 65.764149 -17.145082) (xy 65.752166 -17.057902) (xy 65.748161 -16.969994) (xy 41.681146 -16.969994)
			(xy 41.680645 -17.013994) (xy 41.672643 -17.101629) (xy 41.656705 -17.188173) (xy 41.632963 -17.272909)
			(xy 41.601614 -17.355135) (xy 41.562917 -17.43417) (xy 41.517194 -17.509358) (xy 41.464823 -17.580077)
			(xy 41.406239 -17.645741) (xy 41.341925 -17.705806) (xy 41.272417 -17.759773) (xy 41.198289 -17.807195)
			(xy 41.120155 -17.847681) (xy 41.038664 -17.880894) (xy 40.95449 -17.906558) (xy 40.868331 -17.924462)
			(xy 40.780901 -17.934457) (xy 40.692924 -17.936461) (xy 40.60513 -17.930455) (xy 40.518246 -17.916491)
			(xy 40.432991 -17.894684) (xy 40.350072 -17.865215) (xy 40.270177 -17.828328) (xy 40.193968 -17.784328)
			(xy 40.122075 -17.73358) (xy 40.055094 -17.676506) (xy 39.993582 -17.613576) (xy 39.938046 -17.545314)
			(xy 39.888948 -17.472285) (xy 39.846695 -17.395093) (xy 39.811636 -17.314379) (xy 39.784061 -17.230811)
			(xy 39.764201 -17.145082) (xy 39.752218 -17.057902) (xy 39.748213 -16.969994) (xy 15.681198 -16.969994)
			(xy 15.680697 -17.013994) (xy 15.672695 -17.101629) (xy 15.656757 -17.188173) (xy 15.633015 -17.272909)
			(xy 15.601666 -17.355135) (xy 15.562969 -17.43417) (xy 15.517246 -17.509358) (xy 15.464875 -17.580077)
			(xy 15.406291 -17.645741) (xy 15.341977 -17.705806) (xy 15.272469 -17.759773) (xy 15.198341 -17.807195)
			(xy 15.120207 -17.847681) (xy 15.038716 -17.880894) (xy 14.954542 -17.906558) (xy 14.868383 -17.924462)
			(xy 14.780953 -17.934457) (xy 14.692976 -17.936461) (xy 14.605182 -17.930455) (xy 14.518298 -17.916491)
			(xy 14.433043 -17.894684) (xy 14.350124 -17.865215) (xy 14.270229 -17.828328) (xy 14.19402 -17.784328)
			(xy 14.122127 -17.73358) (xy 14.055146 -17.676506) (xy 13.993634 -17.613576) (xy 13.938098 -17.545314)
			(xy 13.889 -17.472285) (xy 13.846747 -17.395093) (xy 13.811688 -17.314379) (xy 13.784113 -17.230811)
			(xy 13.764253 -17.145082) (xy 13.75227 -17.057902) (xy 13.748265 -16.969994) (xy 0.508 -16.969994)
			(xy 0.508 -27.342846) (xy 16.523716 -27.342846) (xy 16.523716 -26.479246) (xy 16.524206 -26.449278)
			(xy 16.532029 -26.389856) (xy 16.547542 -26.331963) (xy 16.570478 -26.27659) (xy 16.600445 -26.224684)
			(xy 16.636932 -26.177134) (xy 16.679312 -26.134754) (xy 16.726862 -26.098267) (xy 16.778768 -26.0683)
			(xy 16.834141 -26.045364) (xy 16.892034 -26.029851) (xy 16.951456 -26.022028) (xy 17.011392 -26.022028)
			(xy 17.070814 -26.029851) (xy 17.128707 -26.045364) (xy 17.18408 -26.0683) (xy 17.235986 -26.098267)
			(xy 17.283536 -26.134754) (xy 17.325916 -26.177134) (xy 17.362403 -26.224684) (xy 17.39237 -26.27659)
			(xy 17.415306 -26.331963) (xy 17.430819 -26.389856) (xy 17.438642 -26.449278) (xy 17.439132 -26.479246)
			(xy 17.439132 -27.342846) (xy 42.523664 -27.342846) (xy 42.523664 -26.479246) (xy 42.524154 -26.449278)
			(xy 42.531977 -26.389856) (xy 42.54749 -26.331963) (xy 42.570426 -26.27659) (xy 42.600393 -26.224684)
			(xy 42.63688 -26.177134) (xy 42.67926 -26.134754) (xy 42.72681 -26.098267) (xy 42.778716 -26.0683)
			(xy 42.834089 -26.045364) (xy 42.891982 -26.029851) (xy 42.951404 -26.022028) (xy 43.01134 -26.022028)
			(xy 43.070762 -26.029851) (xy 43.128655 -26.045364) (xy 43.184028 -26.0683) (xy 43.235934 -26.098267)
			(xy 43.283484 -26.134754) (xy 43.325864 -26.177134) (xy 43.362351 -26.224684) (xy 43.392318 -26.27659)
			(xy 43.415254 -26.331963) (xy 43.430767 -26.389856) (xy 43.43859 -26.449278) (xy 43.43908 -26.479246)
			(xy 43.43908 -27.342846) (xy 68.523612 -27.342846) (xy 68.523612 -26.479246) (xy 68.524102 -26.449278)
			(xy 68.531925 -26.389856) (xy 68.547438 -26.331963) (xy 68.570374 -26.27659) (xy 68.600341 -26.224684)
			(xy 68.636828 -26.177134) (xy 68.679208 -26.134754) (xy 68.726758 -26.098267) (xy 68.778664 -26.0683)
			(xy 68.834037 -26.045364) (xy 68.89193 -26.029851) (xy 68.951352 -26.022028) (xy 69.011288 -26.022028)
			(xy 69.07071 -26.029851) (xy 69.128603 -26.045364) (xy 69.183976 -26.0683) (xy 69.235882 -26.098267)
			(xy 69.283432 -26.134754) (xy 69.325812 -26.177134) (xy 69.362299 -26.224684) (xy 69.392266 -26.27659)
			(xy 69.415202 -26.331963) (xy 69.430715 -26.389856) (xy 69.438538 -26.449278) (xy 69.439028 -26.479246)
			(xy 69.439028 -27.342846) (xy 94.52356 -27.342846) (xy 94.52356 -26.479246) (xy 94.52405 -26.449278)
			(xy 94.531873 -26.389856) (xy 94.547386 -26.331963) (xy 94.570322 -26.27659) (xy 94.600289 -26.224684)
			(xy 94.636776 -26.177134) (xy 94.679156 -26.134754) (xy 94.726706 -26.098267) (xy 94.778612 -26.0683)
			(xy 94.833985 -26.045364) (xy 94.891878 -26.029851) (xy 94.9513 -26.022028) (xy 95.011236 -26.022028)
			(xy 95.070658 -26.029851) (xy 95.128551 -26.045364) (xy 95.183924 -26.0683) (xy 95.23583 -26.098267)
			(xy 95.28338 -26.134754) (xy 95.32576 -26.177134) (xy 95.362247 -26.224684) (xy 95.392214 -26.27659)
			(xy 95.41515 -26.331963) (xy 95.430663 -26.389856) (xy 95.438486 -26.449278) (xy 95.438976 -26.479246)
			(xy 95.438976 -27.342846) (xy 132.62356 -27.342846) (xy 132.62356 -26.479246) (xy 132.62405 -26.449262)
			(xy 132.631878 -26.389806) (xy 132.647399 -26.331881) (xy 132.670348 -26.276477) (xy 132.700332 -26.224543)
			(xy 132.736838 -26.176967) (xy 132.779243 -26.134562) (xy 132.826819 -26.098056) (xy 132.878753 -26.068072)
			(xy 132.934157 -26.045123) (xy 132.992082 -26.029602) (xy 133.051538 -26.021774) (xy 133.111506 -26.021774)
			(xy 133.170962 -26.029602) (xy 133.228887 -26.045123) (xy 133.284291 -26.068072) (xy 133.336225 -26.098056)
			(xy 133.383801 -26.134562) (xy 133.426206 -26.176967) (xy 133.462712 -26.224543) (xy 133.492696 -26.276477)
			(xy 133.515645 -26.331881) (xy 133.531166 -26.389806) (xy 133.538994 -26.449262) (xy 133.539484 -26.479246)
			(xy 133.539484 -27.342846) (xy 158.623508 -27.342846) (xy 158.623508 -26.479246) (xy 158.623998 -26.449262)
			(xy 158.631826 -26.389806) (xy 158.647347 -26.331881) (xy 158.670296 -26.276477) (xy 158.70028 -26.224543)
			(xy 158.736786 -26.176967) (xy 158.779191 -26.134562) (xy 158.826767 -26.098056) (xy 158.878701 -26.068072)
			(xy 158.934105 -26.045123) (xy 158.99203 -26.029602) (xy 159.051486 -26.021774) (xy 159.111454 -26.021774)
			(xy 159.17091 -26.029602) (xy 159.228835 -26.045123) (xy 159.284239 -26.068072) (xy 159.336173 -26.098056)
			(xy 159.383749 -26.134562) (xy 159.426154 -26.176967) (xy 159.46266 -26.224543) (xy 159.492644 -26.276477)
			(xy 159.515593 -26.331881) (xy 159.531114 -26.389806) (xy 159.538942 -26.449262) (xy 159.539432 -26.479246)
			(xy 159.539432 -27.342846) (xy 184.623456 -27.342846) (xy 184.623456 -26.479246) (xy 184.623946 -26.449262)
			(xy 184.631774 -26.389806) (xy 184.647295 -26.331881) (xy 184.670244 -26.276477) (xy 184.700228 -26.224543)
			(xy 184.736734 -26.176967) (xy 184.779139 -26.134562) (xy 184.826715 -26.098056) (xy 184.878649 -26.068072)
			(xy 184.934053 -26.045123) (xy 184.991978 -26.029602) (xy 185.051434 -26.021774) (xy 185.111402 -26.021774)
			(xy 185.170858 -26.029602) (xy 185.228783 -26.045123) (xy 185.284187 -26.068072) (xy 185.336121 -26.098056)
			(xy 185.383697 -26.134562) (xy 185.426102 -26.176967) (xy 185.462608 -26.224543) (xy 185.492592 -26.276477)
			(xy 185.515541 -26.331881) (xy 185.531062 -26.389806) (xy 185.53889 -26.449262) (xy 185.53938 -26.479246)
			(xy 185.53938 -27.342846) (xy 210.623404 -27.342846) (xy 210.623404 -26.479246) (xy 210.623894 -26.449262)
			(xy 210.631722 -26.389806) (xy 210.647243 -26.331881) (xy 210.670192 -26.276477) (xy 210.700176 -26.224543)
			(xy 210.736682 -26.176967) (xy 210.779087 -26.134562) (xy 210.826663 -26.098056) (xy 210.878597 -26.068072)
			(xy 210.934001 -26.045123) (xy 210.991926 -26.029602) (xy 211.051382 -26.021774) (xy 211.11135 -26.021774)
			(xy 211.170806 -26.029602) (xy 211.228731 -26.045123) (xy 211.284135 -26.068072) (xy 211.336069 -26.098056)
			(xy 211.383645 -26.134562) (xy 211.42605 -26.176967) (xy 211.462556 -26.224543) (xy 211.49254 -26.276477)
			(xy 211.515489 -26.331881) (xy 211.53101 -26.389806) (xy 211.538838 -26.449262) (xy 211.539328 -26.479246)
			(xy 211.539328 -27.342846) (xy 248.723404 -27.342846) (xy 248.723404 -26.479246) (xy 248.723894 -26.449262)
			(xy 248.731722 -26.389806) (xy 248.747243 -26.331881) (xy 248.770192 -26.276477) (xy 248.800176 -26.224543)
			(xy 248.836682 -26.176967) (xy 248.879087 -26.134562) (xy 248.926663 -26.098056) (xy 248.978597 -26.068072)
			(xy 249.034001 -26.045123) (xy 249.091926 -26.029602) (xy 249.151382 -26.021774) (xy 249.21135 -26.021774)
			(xy 249.270806 -26.029602) (xy 249.328731 -26.045123) (xy 249.384135 -26.068072) (xy 249.436069 -26.098056)
			(xy 249.483645 -26.134562) (xy 249.52605 -26.176967) (xy 249.562556 -26.224543) (xy 249.59254 -26.276477)
			(xy 249.615489 -26.331881) (xy 249.63101 -26.389806) (xy 249.638838 -26.449262) (xy 249.639328 -26.479246)
			(xy 249.639328 -27.342846) (xy 274.723352 -27.342846) (xy 274.723352 -26.479246) (xy 274.723842 -26.449262)
			(xy 274.73167 -26.389806) (xy 274.747191 -26.331881) (xy 274.77014 -26.276477) (xy 274.800124 -26.224543)
			(xy 274.83663 -26.176967) (xy 274.879035 -26.134562) (xy 274.926611 -26.098056) (xy 274.978545 -26.068072)
			(xy 275.033949 -26.045123) (xy 275.091874 -26.029602) (xy 275.15133 -26.021774) (xy 275.211298 -26.021774)
			(xy 275.270754 -26.029602) (xy 275.328679 -26.045123) (xy 275.384083 -26.068072) (xy 275.436017 -26.098056)
			(xy 275.483593 -26.134562) (xy 275.525998 -26.176967) (xy 275.562504 -26.224543) (xy 275.592488 -26.276477)
			(xy 275.615437 -26.331881) (xy 275.630958 -26.389806) (xy 275.638786 -26.449262) (xy 275.639276 -26.479246)
			(xy 275.639276 -27.342846) (xy 300.7233 -27.342846) (xy 300.7233 -26.479246) (xy 300.72379 -26.449262)
			(xy 300.731618 -26.389806) (xy 300.747139 -26.331881) (xy 300.770088 -26.276477) (xy 300.800072 -26.224543)
			(xy 300.836578 -26.176967) (xy 300.878983 -26.134562) (xy 300.926559 -26.098056) (xy 300.978493 -26.068072)
			(xy 301.033897 -26.045123) (xy 301.091822 -26.029602) (xy 301.151278 -26.021774) (xy 301.211246 -26.021774)
			(xy 301.270702 -26.029602) (xy 301.328627 -26.045123) (xy 301.384031 -26.068072) (xy 301.435965 -26.098056)
			(xy 301.483541 -26.134562) (xy 301.525946 -26.176967) (xy 301.562452 -26.224543) (xy 301.592436 -26.276477)
			(xy 301.615385 -26.331881) (xy 301.630906 -26.389806) (xy 301.638734 -26.449262) (xy 301.639224 -26.479246)
			(xy 301.639224 -27.342846) (xy 326.723248 -27.342846) (xy 326.723248 -26.479246) (xy 326.723738 -26.449262)
			(xy 326.731566 -26.389806) (xy 326.747087 -26.331881) (xy 326.770036 -26.276477) (xy 326.80002 -26.224543)
			(xy 326.836526 -26.176967) (xy 326.878931 -26.134562) (xy 326.926507 -26.098056) (xy 326.978441 -26.068072)
			(xy 327.033845 -26.045123) (xy 327.09177 -26.029602) (xy 327.151226 -26.021774) (xy 327.211194 -26.021774)
			(xy 327.27065 -26.029602) (xy 327.328575 -26.045123) (xy 327.383979 -26.068072) (xy 327.435913 -26.098056)
			(xy 327.483489 -26.134562) (xy 327.525894 -26.176967) (xy 327.5624 -26.224543) (xy 327.592384 -26.276477)
			(xy 327.615333 -26.331881) (xy 327.630854 -26.389806) (xy 327.638682 -26.449262) (xy 327.639172 -26.479246)
			(xy 327.639172 -27.342846) (xy 364.823756 -27.342846) (xy 364.823756 -26.479246) (xy 364.824246 -26.449278)
			(xy 364.832069 -26.389856) (xy 364.847582 -26.331963) (xy 364.870518 -26.27659) (xy 364.900485 -26.224684)
			(xy 364.936972 -26.177134) (xy 364.979352 -26.134754) (xy 365.026902 -26.098267) (xy 365.078808 -26.0683)
			(xy 365.134181 -26.045364) (xy 365.192074 -26.029851) (xy 365.251496 -26.022028) (xy 365.311432 -26.022028)
			(xy 365.370854 -26.029851) (xy 365.428747 -26.045364) (xy 365.48412 -26.0683) (xy 365.536026 -26.098267)
			(xy 365.583576 -26.134754) (xy 365.625956 -26.177134) (xy 365.662443 -26.224684) (xy 365.69241 -26.27659)
			(xy 365.715346 -26.331963) (xy 365.730859 -26.389856) (xy 365.738682 -26.449278) (xy 365.739172 -26.479246)
			(xy 365.739172 -27.342846) (xy 390.823704 -27.342846) (xy 390.823704 -26.479246) (xy 390.824194 -26.449278)
			(xy 390.832017 -26.389856) (xy 390.84753 -26.331963) (xy 390.870466 -26.27659) (xy 390.900433 -26.224684)
			(xy 390.93692 -26.177134) (xy 390.9793 -26.134754) (xy 391.02685 -26.098267) (xy 391.078756 -26.0683)
			(xy 391.134129 -26.045364) (xy 391.192022 -26.029851) (xy 391.251444 -26.022028) (xy 391.31138 -26.022028)
			(xy 391.370802 -26.029851) (xy 391.428695 -26.045364) (xy 391.484068 -26.0683) (xy 391.535974 -26.098267)
			(xy 391.583524 -26.134754) (xy 391.625904 -26.177134) (xy 391.662391 -26.224684) (xy 391.692358 -26.27659)
			(xy 391.715294 -26.331963) (xy 391.730807 -26.389856) (xy 391.73863 -26.449278) (xy 391.73912 -26.479246)
			(xy 391.73912 -27.342846) (xy 416.823652 -27.342846) (xy 416.823652 -26.479246) (xy 416.824142 -26.449278)
			(xy 416.831965 -26.389856) (xy 416.847478 -26.331963) (xy 416.870414 -26.27659) (xy 416.900381 -26.224684)
			(xy 416.936868 -26.177134) (xy 416.979248 -26.134754) (xy 417.026798 -26.098267) (xy 417.078704 -26.0683)
			(xy 417.134077 -26.045364) (xy 417.19197 -26.029851) (xy 417.251392 -26.022028) (xy 417.311328 -26.022028)
			(xy 417.37075 -26.029851) (xy 417.428643 -26.045364) (xy 417.484016 -26.0683) (xy 417.535922 -26.098267)
			(xy 417.583472 -26.134754) (xy 417.625852 -26.177134) (xy 417.662339 -26.224684) (xy 417.692306 -26.27659)
			(xy 417.715242 -26.331963) (xy 417.730755 -26.389856) (xy 417.738578 -26.449278) (xy 417.739068 -26.479246)
			(xy 417.739068 -27.342846) (xy 442.8236 -27.342846) (xy 442.8236 -26.479246) (xy 442.82409 -26.449278)
			(xy 442.831913 -26.389856) (xy 442.847426 -26.331963) (xy 442.870362 -26.27659) (xy 442.900329 -26.224684)
			(xy 442.936816 -26.177134) (xy 442.979196 -26.134754) (xy 443.026746 -26.098267) (xy 443.078652 -26.0683)
			(xy 443.134025 -26.045364) (xy 443.191918 -26.029851) (xy 443.25134 -26.022028) (xy 443.311276 -26.022028)
			(xy 443.370698 -26.029851) (xy 443.428591 -26.045364) (xy 443.483964 -26.0683) (xy 443.53587 -26.098267)
			(xy 443.58342 -26.134754) (xy 443.6258 -26.177134) (xy 443.662287 -26.224684) (xy 443.692254 -26.27659)
			(xy 443.71519 -26.331963) (xy 443.730703 -26.389856) (xy 443.738526 -26.449278) (xy 443.739016 -26.479246)
			(xy 443.739016 -27.342846) (xy 443.738526 -27.372814) (xy 443.730703 -27.432236) (xy 443.71519 -27.490129)
			(xy 443.692254 -27.545502) (xy 443.662287 -27.597408) (xy 443.6258 -27.644958) (xy 443.58342 -27.687338)
			(xy 443.53587 -27.723825) (xy 443.483964 -27.753792) (xy 443.428591 -27.776728) (xy 443.370698 -27.792241)
			(xy 443.311276 -27.800064) (xy 443.25134 -27.800064) (xy 443.191918 -27.792241) (xy 443.134025 -27.776728)
			(xy 443.078652 -27.753792) (xy 443.026746 -27.723825) (xy 442.979196 -27.687338) (xy 442.936816 -27.644958)
			(xy 442.900329 -27.597408) (xy 442.870362 -27.545502) (xy 442.847426 -27.490129) (xy 442.831913 -27.432236)
			(xy 442.82409 -27.372814) (xy 442.8236 -27.342846) (xy 417.739068 -27.342846) (xy 417.738578 -27.372814)
			(xy 417.730755 -27.432236) (xy 417.715242 -27.490129) (xy 417.692306 -27.545502) (xy 417.662339 -27.597408)
			(xy 417.625852 -27.644958) (xy 417.583472 -27.687338) (xy 417.535922 -27.723825) (xy 417.484016 -27.753792)
			(xy 417.428643 -27.776728) (xy 417.37075 -27.792241) (xy 417.311328 -27.800064) (xy 417.251392 -27.800064)
			(xy 417.19197 -27.792241) (xy 417.134077 -27.776728) (xy 417.078704 -27.753792) (xy 417.026798 -27.723825)
			(xy 416.979248 -27.687338) (xy 416.936868 -27.644958) (xy 416.900381 -27.597408) (xy 416.870414 -27.545502)
			(xy 416.847478 -27.490129) (xy 416.831965 -27.432236) (xy 416.824142 -27.372814) (xy 416.823652 -27.342846)
			(xy 391.73912 -27.342846) (xy 391.73863 -27.372814) (xy 391.730807 -27.432236) (xy 391.715294 -27.490129)
			(xy 391.692358 -27.545502) (xy 391.662391 -27.597408) (xy 391.625904 -27.644958) (xy 391.583524 -27.687338)
			(xy 391.535974 -27.723825) (xy 391.484068 -27.753792) (xy 391.428695 -27.776728) (xy 391.370802 -27.792241)
			(xy 391.31138 -27.800064) (xy 391.251444 -27.800064) (xy 391.192022 -27.792241) (xy 391.134129 -27.776728)
			(xy 391.078756 -27.753792) (xy 391.02685 -27.723825) (xy 390.9793 -27.687338) (xy 390.93692 -27.644958)
			(xy 390.900433 -27.597408) (xy 390.870466 -27.545502) (xy 390.84753 -27.490129) (xy 390.832017 -27.432236)
			(xy 390.824194 -27.372814) (xy 390.823704 -27.342846) (xy 365.739172 -27.342846) (xy 365.738682 -27.372814)
			(xy 365.730859 -27.432236) (xy 365.715346 -27.490129) (xy 365.69241 -27.545502) (xy 365.662443 -27.597408)
			(xy 365.625956 -27.644958) (xy 365.583576 -27.687338) (xy 365.536026 -27.723825) (xy 365.48412 -27.753792)
			(xy 365.428747 -27.776728) (xy 365.370854 -27.792241) (xy 365.311432 -27.800064) (xy 365.251496 -27.800064)
			(xy 365.192074 -27.792241) (xy 365.134181 -27.776728) (xy 365.078808 -27.753792) (xy 365.026902 -27.723825)
			(xy 364.979352 -27.687338) (xy 364.936972 -27.644958) (xy 364.900485 -27.597408) (xy 364.870518 -27.545502)
			(xy 364.847582 -27.490129) (xy 364.832069 -27.432236) (xy 364.824246 -27.372814) (xy 364.823756 -27.342846)
			(xy 327.639172 -27.342846) (xy 327.638682 -27.37283) (xy 327.630854 -27.432286) (xy 327.615333 -27.490211)
			(xy 327.592384 -27.545615) (xy 327.5624 -27.597549) (xy 327.525894 -27.645125) (xy 327.483489 -27.68753)
			(xy 327.435913 -27.724036) (xy 327.383979 -27.75402) (xy 327.328575 -27.776969) (xy 327.27065 -27.79249)
			(xy 327.211194 -27.800318) (xy 327.151226 -27.800318) (xy 327.09177 -27.79249) (xy 327.033845 -27.776969)
			(xy 326.978441 -27.75402) (xy 326.926507 -27.724036) (xy 326.878931 -27.68753) (xy 326.836526 -27.645125)
			(xy 326.80002 -27.597549) (xy 326.770036 -27.545615) (xy 326.747087 -27.490211) (xy 326.731566 -27.432286)
			(xy 326.723738 -27.37283) (xy 326.723248 -27.342846) (xy 301.639224 -27.342846) (xy 301.638734 -27.37283)
			(xy 301.630906 -27.432286) (xy 301.615385 -27.490211) (xy 301.592436 -27.545615) (xy 301.562452 -27.597549)
			(xy 301.525946 -27.645125) (xy 301.483541 -27.68753) (xy 301.435965 -27.724036) (xy 301.384031 -27.75402)
			(xy 301.328627 -27.776969) (xy 301.270702 -27.79249) (xy 301.211246 -27.800318) (xy 301.151278 -27.800318)
			(xy 301.091822 -27.79249) (xy 301.033897 -27.776969) (xy 300.978493 -27.75402) (xy 300.926559 -27.724036)
			(xy 300.878983 -27.68753) (xy 300.836578 -27.645125) (xy 300.800072 -27.597549) (xy 300.770088 -27.545615)
			(xy 300.747139 -27.490211) (xy 300.731618 -27.432286) (xy 300.72379 -27.37283) (xy 300.7233 -27.342846)
			(xy 275.639276 -27.342846) (xy 275.638786 -27.37283) (xy 275.630958 -27.432286) (xy 275.615437 -27.490211)
			(xy 275.592488 -27.545615) (xy 275.562504 -27.597549) (xy 275.525998 -27.645125) (xy 275.483593 -27.68753)
			(xy 275.436017 -27.724036) (xy 275.384083 -27.75402) (xy 275.328679 -27.776969) (xy 275.270754 -27.79249)
			(xy 275.211298 -27.800318) (xy 275.15133 -27.800318) (xy 275.091874 -27.79249) (xy 275.033949 -27.776969)
			(xy 274.978545 -27.75402) (xy 274.926611 -27.724036) (xy 274.879035 -27.68753) (xy 274.83663 -27.645125)
			(xy 274.800124 -27.597549) (xy 274.77014 -27.545615) (xy 274.747191 -27.490211) (xy 274.73167 -27.432286)
			(xy 274.723842 -27.37283) (xy 274.723352 -27.342846) (xy 249.639328 -27.342846) (xy 249.638838 -27.37283)
			(xy 249.63101 -27.432286) (xy 249.615489 -27.490211) (xy 249.59254 -27.545615) (xy 249.562556 -27.597549)
			(xy 249.52605 -27.645125) (xy 249.483645 -27.68753) (xy 249.436069 -27.724036) (xy 249.384135 -27.75402)
			(xy 249.328731 -27.776969) (xy 249.270806 -27.79249) (xy 249.21135 -27.800318) (xy 249.151382 -27.800318)
			(xy 249.091926 -27.79249) (xy 249.034001 -27.776969) (xy 248.978597 -27.75402) (xy 248.926663 -27.724036)
			(xy 248.879087 -27.68753) (xy 248.836682 -27.645125) (xy 248.800176 -27.597549) (xy 248.770192 -27.545615)
			(xy 248.747243 -27.490211) (xy 248.731722 -27.432286) (xy 248.723894 -27.37283) (xy 248.723404 -27.342846)
			(xy 211.539328 -27.342846) (xy 211.538838 -27.37283) (xy 211.53101 -27.432286) (xy 211.515489 -27.490211)
			(xy 211.49254 -27.545615) (xy 211.462556 -27.597549) (xy 211.42605 -27.645125) (xy 211.383645 -27.68753)
			(xy 211.336069 -27.724036) (xy 211.284135 -27.75402) (xy 211.228731 -27.776969) (xy 211.170806 -27.79249)
			(xy 211.11135 -27.800318) (xy 211.051382 -27.800318) (xy 210.991926 -27.79249) (xy 210.934001 -27.776969)
			(xy 210.878597 -27.75402) (xy 210.826663 -27.724036) (xy 210.779087 -27.68753) (xy 210.736682 -27.645125)
			(xy 210.700176 -27.597549) (xy 210.670192 -27.545615) (xy 210.647243 -27.490211) (xy 210.631722 -27.432286)
			(xy 210.623894 -27.37283) (xy 210.623404 -27.342846) (xy 185.53938 -27.342846) (xy 185.53889 -27.37283)
			(xy 185.531062 -27.432286) (xy 185.515541 -27.490211) (xy 185.492592 -27.545615) (xy 185.462608 -27.597549)
			(xy 185.426102 -27.645125) (xy 185.383697 -27.68753) (xy 185.336121 -27.724036) (xy 185.284187 -27.75402)
			(xy 185.228783 -27.776969) (xy 185.170858 -27.79249) (xy 185.111402 -27.800318) (xy 185.051434 -27.800318)
			(xy 184.991978 -27.79249) (xy 184.934053 -27.776969) (xy 184.878649 -27.75402) (xy 184.826715 -27.724036)
			(xy 184.779139 -27.68753) (xy 184.736734 -27.645125) (xy 184.700228 -27.597549) (xy 184.670244 -27.545615)
			(xy 184.647295 -27.490211) (xy 184.631774 -27.432286) (xy 184.623946 -27.37283) (xy 184.623456 -27.342846)
			(xy 159.539432 -27.342846) (xy 159.538942 -27.37283) (xy 159.531114 -27.432286) (xy 159.515593 -27.490211)
			(xy 159.492644 -27.545615) (xy 159.46266 -27.597549) (xy 159.426154 -27.645125) (xy 159.383749 -27.68753)
			(xy 159.336173 -27.724036) (xy 159.284239 -27.75402) (xy 159.228835 -27.776969) (xy 159.17091 -27.79249)
			(xy 159.111454 -27.800318) (xy 159.051486 -27.800318) (xy 158.99203 -27.79249) (xy 158.934105 -27.776969)
			(xy 158.878701 -27.75402) (xy 158.826767 -27.724036) (xy 158.779191 -27.68753) (xy 158.736786 -27.645125)
			(xy 158.70028 -27.597549) (xy 158.670296 -27.545615) (xy 158.647347 -27.490211) (xy 158.631826 -27.432286)
			(xy 158.623998 -27.37283) (xy 158.623508 -27.342846) (xy 133.539484 -27.342846) (xy 133.538994 -27.37283)
			(xy 133.531166 -27.432286) (xy 133.515645 -27.490211) (xy 133.492696 -27.545615) (xy 133.462712 -27.597549)
			(xy 133.426206 -27.645125) (xy 133.383801 -27.68753) (xy 133.336225 -27.724036) (xy 133.284291 -27.75402)
			(xy 133.228887 -27.776969) (xy 133.170962 -27.79249) (xy 133.111506 -27.800318) (xy 133.051538 -27.800318)
			(xy 132.992082 -27.79249) (xy 132.934157 -27.776969) (xy 132.878753 -27.75402) (xy 132.826819 -27.724036)
			(xy 132.779243 -27.68753) (xy 132.736838 -27.645125) (xy 132.700332 -27.597549) (xy 132.670348 -27.545615)
			(xy 132.647399 -27.490211) (xy 132.631878 -27.432286) (xy 132.62405 -27.37283) (xy 132.62356 -27.342846)
			(xy 95.438976 -27.342846) (xy 95.438486 -27.372814) (xy 95.430663 -27.432236) (xy 95.41515 -27.490129)
			(xy 95.392214 -27.545502) (xy 95.362247 -27.597408) (xy 95.32576 -27.644958) (xy 95.28338 -27.687338)
			(xy 95.23583 -27.723825) (xy 95.183924 -27.753792) (xy 95.128551 -27.776728) (xy 95.070658 -27.792241)
			(xy 95.011236 -27.800064) (xy 94.9513 -27.800064) (xy 94.891878 -27.792241) (xy 94.833985 -27.776728)
			(xy 94.778612 -27.753792) (xy 94.726706 -27.723825) (xy 94.679156 -27.687338) (xy 94.636776 -27.644958)
			(xy 94.600289 -27.597408) (xy 94.570322 -27.545502) (xy 94.547386 -27.490129) (xy 94.531873 -27.432236)
			(xy 94.52405 -27.372814) (xy 94.52356 -27.342846) (xy 69.439028 -27.342846) (xy 69.438538 -27.372814)
			(xy 69.430715 -27.432236) (xy 69.415202 -27.490129) (xy 69.392266 -27.545502) (xy 69.362299 -27.597408)
			(xy 69.325812 -27.644958) (xy 69.283432 -27.687338) (xy 69.235882 -27.723825) (xy 69.183976 -27.753792)
			(xy 69.128603 -27.776728) (xy 69.07071 -27.792241) (xy 69.011288 -27.800064) (xy 68.951352 -27.800064)
			(xy 68.89193 -27.792241) (xy 68.834037 -27.776728) (xy 68.778664 -27.753792) (xy 68.726758 -27.723825)
			(xy 68.679208 -27.687338) (xy 68.636828 -27.644958) (xy 68.600341 -27.597408) (xy 68.570374 -27.545502)
			(xy 68.547438 -27.490129) (xy 68.531925 -27.432236) (xy 68.524102 -27.372814) (xy 68.523612 -27.342846)
			(xy 43.43908 -27.342846) (xy 43.43859 -27.372814) (xy 43.430767 -27.432236) (xy 43.415254 -27.490129)
			(xy 43.392318 -27.545502) (xy 43.362351 -27.597408) (xy 43.325864 -27.644958) (xy 43.283484 -27.687338)
			(xy 43.235934 -27.723825) (xy 43.184028 -27.753792) (xy 43.128655 -27.776728) (xy 43.070762 -27.792241)
			(xy 43.01134 -27.800064) (xy 42.951404 -27.800064) (xy 42.891982 -27.792241) (xy 42.834089 -27.776728)
			(xy 42.778716 -27.753792) (xy 42.72681 -27.723825) (xy 42.67926 -27.687338) (xy 42.63688 -27.644958)
			(xy 42.600393 -27.597408) (xy 42.570426 -27.545502) (xy 42.54749 -27.490129) (xy 42.531977 -27.432236)
			(xy 42.524154 -27.372814) (xy 42.523664 -27.342846) (xy 17.439132 -27.342846) (xy 17.438642 -27.372814)
			(xy 17.430819 -27.432236) (xy 17.415306 -27.490129) (xy 17.39237 -27.545502) (xy 17.362403 -27.597408)
			(xy 17.325916 -27.644958) (xy 17.283536 -27.687338) (xy 17.235986 -27.723825) (xy 17.18408 -27.753792)
			(xy 17.128707 -27.776728) (xy 17.070814 -27.792241) (xy 17.011392 -27.800064) (xy 16.951456 -27.800064)
			(xy 16.892034 -27.792241) (xy 16.834141 -27.776728) (xy 16.778768 -27.753792) (xy 16.726862 -27.723825)
			(xy 16.679312 -27.687338) (xy 16.636932 -27.644958) (xy 16.600445 -27.597408) (xy 16.570478 -27.545502)
			(xy 16.547542 -27.490129) (xy 16.532029 -27.432236) (xy 16.524206 -27.372814) (xy 16.523716 -27.342846)
			(xy 0.508 -27.342846) (xy 0.508 -29.12237) (xy 8.607044 -29.12237) (xy 8.607044 -28.25877) (xy 8.607534 -28.228802)
			(xy 8.615357 -28.16938) (xy 8.63087 -28.111487) (xy 8.653806 -28.056114) (xy 8.683773 -28.004208)
			(xy 8.72026 -27.956658) (xy 8.76264 -27.914278) (xy 8.81019 -27.877791) (xy 8.862096 -27.847824)
			(xy 8.917469 -27.824888) (xy 8.975362 -27.809375) (xy 9.034784 -27.801552) (xy 9.09472 -27.801552)
			(xy 9.154142 -27.809375) (xy 9.212035 -27.824888) (xy 9.267408 -27.847824) (xy 9.319314 -27.877791)
			(xy 9.366864 -27.914278) (xy 9.409244 -27.956658) (xy 9.445731 -28.004208) (xy 9.475698 -28.056114)
			(xy 9.498634 -28.111487) (xy 9.514147 -28.16938) (xy 9.52197 -28.228802) (xy 9.52246 -28.25877) (xy 9.52246 -29.114242)
			(xy 18.847308 -29.114242) (xy 18.847308 -28.250642) (xy 18.847798 -28.220658) (xy 18.855626 -28.161202)
			(xy 18.871147 -28.103277) (xy 18.894096 -28.047873) (xy 18.92408 -27.995939) (xy 18.960586 -27.948363)
			(xy 19.002991 -27.905958) (xy 19.050567 -27.869452) (xy 19.102501 -27.839468) (xy 19.157905 -27.816519)
			(xy 19.21583 -27.800998) (xy 19.275286 -27.79317) (xy 19.335254 -27.79317) (xy 19.39471 -27.800998)
			(xy 19.452635 -27.816519) (xy 19.508039 -27.839468) (xy 19.559973 -27.869452) (xy 19.607549 -27.905958)
			(xy 19.649954 -27.948363) (xy 19.68646 -27.995939) (xy 19.716444 -28.047873) (xy 19.739393 -28.103277)
			(xy 19.754914 -28.161202) (xy 19.762742 -28.220658) (xy 19.763232 -28.250642) (xy 19.763232 -29.114242)
			(xy 19.763099 -29.12237) (xy 34.606992 -29.12237) (xy 34.606992 -28.25877) (xy 34.607482 -28.228802)
			(xy 34.615305 -28.16938) (xy 34.630818 -28.111487) (xy 34.653754 -28.056114) (xy 34.683721 -28.004208)
			(xy 34.720208 -27.956658) (xy 34.762588 -27.914278) (xy 34.810138 -27.877791) (xy 34.862044 -27.847824)
			(xy 34.917417 -27.824888) (xy 34.97531 -27.809375) (xy 35.034732 -27.801552) (xy 35.094668 -27.801552)
			(xy 35.15409 -27.809375) (xy 35.211983 -27.824888) (xy 35.267356 -27.847824) (xy 35.319262 -27.877791)
			(xy 35.366812 -27.914278) (xy 35.409192 -27.956658) (xy 35.445679 -28.004208) (xy 35.475646 -28.056114)
			(xy 35.498582 -28.111487) (xy 35.514095 -28.16938) (xy 35.521918 -28.228802) (xy 35.522408 -28.25877)
			(xy 35.522408 -29.114242) (xy 44.847256 -29.114242) (xy 44.847256 -28.250642) (xy 44.847746 -28.220658)
			(xy 44.855574 -28.161202) (xy 44.871095 -28.103277) (xy 44.894044 -28.047873) (xy 44.924028 -27.995939)
			(xy 44.960534 -27.948363) (xy 45.002939 -27.905958) (xy 45.050515 -27.869452) (xy 45.102449 -27.839468)
			(xy 45.157853 -27.816519) (xy 45.215778 -27.800998) (xy 45.275234 -27.79317) (xy 45.335202 -27.79317)
			(xy 45.394658 -27.800998) (xy 45.452583 -27.816519) (xy 45.507987 -27.839468) (xy 45.559921 -27.869452)
			(xy 45.607497 -27.905958) (xy 45.649902 -27.948363) (xy 45.686408 -27.995939) (xy 45.716392 -28.047873)
			(xy 45.739341 -28.103277) (xy 45.754862 -28.161202) (xy 45.76269 -28.220658) (xy 45.76318 -28.250642)
			(xy 45.76318 -29.114242) (xy 45.763047 -29.12237) (xy 60.60694 -29.12237) (xy 60.60694 -28.25877)
			(xy 60.60743 -28.228802) (xy 60.615253 -28.16938) (xy 60.630766 -28.111487) (xy 60.653702 -28.056114)
			(xy 60.683669 -28.004208) (xy 60.720156 -27.956658) (xy 60.762536 -27.914278) (xy 60.810086 -27.877791)
			(xy 60.861992 -27.847824) (xy 60.917365 -27.824888) (xy 60.975258 -27.809375) (xy 61.03468 -27.801552)
			(xy 61.094616 -27.801552) (xy 61.154038 -27.809375) (xy 61.211931 -27.824888) (xy 61.267304 -27.847824)
			(xy 61.31921 -27.877791) (xy 61.36676 -27.914278) (xy 61.40914 -27.956658) (xy 61.445627 -28.004208)
			(xy 61.475594 -28.056114) (xy 61.49853 -28.111487) (xy 61.514043 -28.16938) (xy 61.521866 -28.228802)
			(xy 61.522356 -28.25877) (xy 61.522356 -29.114242) (xy 70.847204 -29.114242) (xy 70.847204 -28.250642)
			(xy 70.847694 -28.220658) (xy 70.855522 -28.161202) (xy 70.871043 -28.103277) (xy 70.893992 -28.047873)
			(xy 70.923976 -27.995939) (xy 70.960482 -27.948363) (xy 71.002887 -27.905958) (xy 71.050463 -27.869452)
			(xy 71.102397 -27.839468) (xy 71.157801 -27.816519) (xy 71.215726 -27.800998) (xy 71.275182 -27.79317)
			(xy 71.33515 -27.79317) (xy 71.394606 -27.800998) (xy 71.452531 -27.816519) (xy 71.507935 -27.839468)
			(xy 71.559869 -27.869452) (xy 71.607445 -27.905958) (xy 71.64985 -27.948363) (xy 71.686356 -27.995939)
			(xy 71.71634 -28.047873) (xy 71.739289 -28.103277) (xy 71.75481 -28.161202) (xy 71.762638 -28.220658)
			(xy 71.763128 -28.250642) (xy 71.763128 -29.114242) (xy 71.762995 -29.12237) (xy 86.606888 -29.12237)
			(xy 86.606888 -28.25877) (xy 86.607378 -28.228802) (xy 86.615201 -28.16938) (xy 86.630714 -28.111487)
			(xy 86.65365 -28.056114) (xy 86.683617 -28.004208) (xy 86.720104 -27.956658) (xy 86.762484 -27.914278)
			(xy 86.810034 -27.877791) (xy 86.86194 -27.847824) (xy 86.917313 -27.824888) (xy 86.975206 -27.809375)
			(xy 87.034628 -27.801552) (xy 87.094564 -27.801552) (xy 87.153986 -27.809375) (xy 87.211879 -27.824888)
			(xy 87.267252 -27.847824) (xy 87.319158 -27.877791) (xy 87.366708 -27.914278) (xy 87.409088 -27.956658)
			(xy 87.445575 -28.004208) (xy 87.475542 -28.056114) (xy 87.498478 -28.111487) (xy 87.513991 -28.16938)
			(xy 87.521814 -28.228802) (xy 87.522304 -28.25877) (xy 87.522304 -29.114242) (xy 96.847152 -29.114242)
			(xy 96.847152 -28.250642) (xy 96.847642 -28.220658) (xy 96.85547 -28.161202) (xy 96.870991 -28.103277)
			(xy 96.89394 -28.047873) (xy 96.923924 -27.995939) (xy 96.96043 -27.948363) (xy 97.002835 -27.905958)
			(xy 97.050411 -27.869452) (xy 97.102345 -27.839468) (xy 97.157749 -27.816519) (xy 97.215674 -27.800998)
			(xy 97.27513 -27.79317) (xy 97.335098 -27.79317) (xy 97.394554 -27.800998) (xy 97.452479 -27.816519)
			(xy 97.507883 -27.839468) (xy 97.559817 -27.869452) (xy 97.607393 -27.905958) (xy 97.649798 -27.948363)
			(xy 97.686304 -27.995939) (xy 97.716288 -28.047873) (xy 97.739237 -28.103277) (xy 97.754758 -28.161202)
			(xy 97.762586 -28.220658) (xy 97.763076 -28.250642) (xy 97.763076 -29.114242) (xy 97.762943 -29.12237)
			(xy 124.706888 -29.12237) (xy 124.706888 -28.25877) (xy 124.707378 -28.228786) (xy 124.715206 -28.16933)
			(xy 124.730727 -28.111405) (xy 124.753676 -28.056001) (xy 124.78366 -28.004067) (xy 124.820166 -27.956491)
			(xy 124.862571 -27.914086) (xy 124.910147 -27.87758) (xy 124.962081 -27.847596) (xy 125.017485 -27.824647)
			(xy 125.07541 -27.809126) (xy 125.134866 -27.801298) (xy 125.194834 -27.801298) (xy 125.25429 -27.809126)
			(xy 125.312215 -27.824647) (xy 125.367619 -27.847596) (xy 125.419553 -27.87758) (xy 125.467129 -27.914086)
			(xy 125.509534 -27.956491) (xy 125.54604 -28.004067) (xy 125.576024 -28.056001) (xy 125.598973 -28.111405)
			(xy 125.614494 -28.16933) (xy 125.622322 -28.228786) (xy 125.622812 -28.25877) (xy 125.622812 -29.114242)
			(xy 134.94766 -29.114242) (xy 134.94766 -28.250642) (xy 134.94815 -28.220674) (xy 134.955973 -28.161252)
			(xy 134.971486 -28.103359) (xy 134.994422 -28.047986) (xy 135.024389 -27.99608) (xy 135.060876 -27.94853)
			(xy 135.103256 -27.90615) (xy 135.150806 -27.869663) (xy 135.202712 -27.839696) (xy 135.258085 -27.81676)
			(xy 135.315978 -27.801247) (xy 135.3754 -27.793424) (xy 135.435336 -27.793424) (xy 135.494758 -27.801247)
			(xy 135.552651 -27.81676) (xy 135.608024 -27.839696) (xy 135.65993 -27.869663) (xy 135.70748 -27.90615)
			(xy 135.74986 -27.94853) (xy 135.786347 -27.99608) (xy 135.816314 -28.047986) (xy 135.83925 -28.103359)
			(xy 135.854763 -28.161252) (xy 135.862586 -28.220674) (xy 135.863076 -28.250642) (xy 135.863076 -29.114242)
			(xy 135.862943 -29.12237) (xy 150.706836 -29.12237) (xy 150.706836 -28.25877) (xy 150.707326 -28.228786)
			(xy 150.715154 -28.16933) (xy 150.730675 -28.111405) (xy 150.753624 -28.056001) (xy 150.783608 -28.004067)
			(xy 150.820114 -27.956491) (xy 150.862519 -27.914086) (xy 150.910095 -27.87758) (xy 150.962029 -27.847596)
			(xy 151.017433 -27.824647) (xy 151.075358 -27.809126) (xy 151.134814 -27.801298) (xy 151.194782 -27.801298)
			(xy 151.254238 -27.809126) (xy 151.312163 -27.824647) (xy 151.367567 -27.847596) (xy 151.419501 -27.87758)
			(xy 151.467077 -27.914086) (xy 151.509482 -27.956491) (xy 151.545988 -28.004067) (xy 151.575972 -28.056001)
			(xy 151.598921 -28.111405) (xy 151.614442 -28.16933) (xy 151.62227 -28.228786) (xy 151.62276 -28.25877)
			(xy 151.62276 -29.114242) (xy 160.947608 -29.114242) (xy 160.947608 -28.250642) (xy 160.948098 -28.220674)
			(xy 160.955921 -28.161252) (xy 160.971434 -28.103359) (xy 160.99437 -28.047986) (xy 161.024337 -27.99608)
			(xy 161.060824 -27.94853) (xy 161.103204 -27.90615) (xy 161.150754 -27.869663) (xy 161.20266 -27.839696)
			(xy 161.258033 -27.81676) (xy 161.315926 -27.801247) (xy 161.375348 -27.793424) (xy 161.435284 -27.793424)
			(xy 161.494706 -27.801247) (xy 161.552599 -27.81676) (xy 161.607972 -27.839696) (xy 161.659878 -27.869663)
			(xy 161.707428 -27.90615) (xy 161.749808 -27.94853) (xy 161.786295 -27.99608) (xy 161.816262 -28.047986)
			(xy 161.839198 -28.103359) (xy 161.854711 -28.161252) (xy 161.862534 -28.220674) (xy 161.863024 -28.250642)
			(xy 161.863024 -29.114242) (xy 161.862891 -29.12237) (xy 176.706784 -29.12237) (xy 176.706784 -28.25877)
			(xy 176.707274 -28.228786) (xy 176.715102 -28.16933) (xy 176.730623 -28.111405) (xy 176.753572 -28.056001)
			(xy 176.783556 -28.004067) (xy 176.820062 -27.956491) (xy 176.862467 -27.914086) (xy 176.910043 -27.87758)
			(xy 176.961977 -27.847596) (xy 177.017381 -27.824647) (xy 177.075306 -27.809126) (xy 177.134762 -27.801298)
			(xy 177.19473 -27.801298) (xy 177.254186 -27.809126) (xy 177.312111 -27.824647) (xy 177.367515 -27.847596)
			(xy 177.419449 -27.87758) (xy 177.467025 -27.914086) (xy 177.50943 -27.956491) (xy 177.545936 -28.004067)
			(xy 177.57592 -28.056001) (xy 177.598869 -28.111405) (xy 177.61439 -28.16933) (xy 177.622218 -28.228786)
			(xy 177.622708 -28.25877) (xy 177.622708 -29.114242) (xy 186.947556 -29.114242) (xy 186.947556 -28.250642)
			(xy 186.948046 -28.220674) (xy 186.955869 -28.161252) (xy 186.971382 -28.103359) (xy 186.994318 -28.047986)
			(xy 187.024285 -27.99608) (xy 187.060772 -27.94853) (xy 187.103152 -27.90615) (xy 187.150702 -27.869663)
			(xy 187.202608 -27.839696) (xy 187.257981 -27.81676) (xy 187.315874 -27.801247) (xy 187.375296 -27.793424)
			(xy 187.435232 -27.793424) (xy 187.494654 -27.801247) (xy 187.552547 -27.81676) (xy 187.60792 -27.839696)
			(xy 187.659826 -27.869663) (xy 187.707376 -27.90615) (xy 187.749756 -27.94853) (xy 187.786243 -27.99608)
			(xy 187.81621 -28.047986) (xy 187.839146 -28.103359) (xy 187.854659 -28.161252) (xy 187.862482 -28.220674)
			(xy 187.862972 -28.250642) (xy 187.862972 -29.114242) (xy 187.862839 -29.12237) (xy 202.706732 -29.12237)
			(xy 202.706732 -28.25877) (xy 202.707222 -28.228786) (xy 202.71505 -28.16933) (xy 202.730571 -28.111405)
			(xy 202.75352 -28.056001) (xy 202.783504 -28.004067) (xy 202.82001 -27.956491) (xy 202.862415 -27.914086)
			(xy 202.909991 -27.87758) (xy 202.961925 -27.847596) (xy 203.017329 -27.824647) (xy 203.075254 -27.809126)
			(xy 203.13471 -27.801298) (xy 203.194678 -27.801298) (xy 203.254134 -27.809126) (xy 203.312059 -27.824647)
			(xy 203.367463 -27.847596) (xy 203.419397 -27.87758) (xy 203.466973 -27.914086) (xy 203.509378 -27.956491)
			(xy 203.545884 -28.004067) (xy 203.575868 -28.056001) (xy 203.598817 -28.111405) (xy 203.614338 -28.16933)
			(xy 203.622166 -28.228786) (xy 203.622656 -28.25877) (xy 203.622656 -29.114242) (xy 212.947504 -29.114242)
			(xy 212.947504 -28.250642) (xy 212.947994 -28.220674) (xy 212.955817 -28.161252) (xy 212.97133 -28.103359)
			(xy 212.994266 -28.047986) (xy 213.024233 -27.99608) (xy 213.06072 -27.94853) (xy 213.1031 -27.90615)
			(xy 213.15065 -27.869663) (xy 213.202556 -27.839696) (xy 213.257929 -27.81676) (xy 213.315822 -27.801247)
			(xy 213.375244 -27.793424) (xy 213.43518 -27.793424) (xy 213.494602 -27.801247) (xy 213.552495 -27.81676)
			(xy 213.607868 -27.839696) (xy 213.659774 -27.869663) (xy 213.707324 -27.90615) (xy 213.749704 -27.94853)
			(xy 213.786191 -27.99608) (xy 213.816158 -28.047986) (xy 213.839094 -28.103359) (xy 213.854607 -28.161252)
			(xy 213.86243 -28.220674) (xy 213.86292 -28.250642) (xy 213.86292 -29.114242) (xy 213.862787 -29.12237)
			(xy 240.806732 -29.12237) (xy 240.806732 -28.25877) (xy 240.807222 -28.228786) (xy 240.81505 -28.16933)
			(xy 240.830571 -28.111405) (xy 240.85352 -28.056001) (xy 240.883504 -28.004067) (xy 240.92001 -27.956491)
			(xy 240.962415 -27.914086) (xy 241.009991 -27.87758) (xy 241.061925 -27.847596) (xy 241.117329 -27.824647)
			(xy 241.175254 -27.809126) (xy 241.23471 -27.801298) (xy 241.294678 -27.801298) (xy 241.354134 -27.809126)
			(xy 241.412059 -27.824647) (xy 241.467463 -27.847596) (xy 241.519397 -27.87758) (xy 241.566973 -27.914086)
			(xy 241.609378 -27.956491) (xy 241.645884 -28.004067) (xy 241.675868 -28.056001) (xy 241.698817 -28.111405)
			(xy 241.714338 -28.16933) (xy 241.722166 -28.228786) (xy 241.722656 -28.25877) (xy 241.722656 -29.114242)
			(xy 251.047504 -29.114242) (xy 251.047504 -28.250642) (xy 251.047994 -28.220674) (xy 251.055817 -28.161252)
			(xy 251.07133 -28.103359) (xy 251.094266 -28.047986) (xy 251.124233 -27.99608) (xy 251.16072 -27.94853)
			(xy 251.2031 -27.90615) (xy 251.25065 -27.869663) (xy 251.302556 -27.839696) (xy 251.357929 -27.81676)
			(xy 251.415822 -27.801247) (xy 251.475244 -27.793424) (xy 251.53518 -27.793424) (xy 251.594602 -27.801247)
			(xy 251.652495 -27.81676) (xy 251.707868 -27.839696) (xy 251.759774 -27.869663) (xy 251.807324 -27.90615)
			(xy 251.849704 -27.94853) (xy 251.886191 -27.99608) (xy 251.916158 -28.047986) (xy 251.939094 -28.103359)
			(xy 251.954607 -28.161252) (xy 251.96243 -28.220674) (xy 251.96292 -28.250642) (xy 251.96292 -29.114242)
			(xy 251.962787 -29.12237) (xy 266.80668 -29.12237) (xy 266.80668 -28.25877) (xy 266.80717 -28.228786)
			(xy 266.814998 -28.16933) (xy 266.830519 -28.111405) (xy 266.853468 -28.056001) (xy 266.883452 -28.004067)
			(xy 266.919958 -27.956491) (xy 266.962363 -27.914086) (xy 267.009939 -27.87758) (xy 267.061873 -27.847596)
			(xy 267.117277 -27.824647) (xy 267.175202 -27.809126) (xy 267.234658 -27.801298) (xy 267.294626 -27.801298)
			(xy 267.354082 -27.809126) (xy 267.412007 -27.824647) (xy 267.467411 -27.847596) (xy 267.519345 -27.87758)
			(xy 267.566921 -27.914086) (xy 267.609326 -27.956491) (xy 267.645832 -28.004067) (xy 267.675816 -28.056001)
			(xy 267.698765 -28.111405) (xy 267.714286 -28.16933) (xy 267.722114 -28.228786) (xy 267.722604 -28.25877)
			(xy 267.722604 -29.114242) (xy 277.047452 -29.114242) (xy 277.047452 -28.250642) (xy 277.047942 -28.220674)
			(xy 277.055765 -28.161252) (xy 277.071278 -28.103359) (xy 277.094214 -28.047986) (xy 277.124181 -27.99608)
			(xy 277.160668 -27.94853) (xy 277.203048 -27.90615) (xy 277.250598 -27.869663) (xy 277.302504 -27.839696)
			(xy 277.357877 -27.81676) (xy 277.41577 -27.801247) (xy 277.475192 -27.793424) (xy 277.535128 -27.793424)
			(xy 277.59455 -27.801247) (xy 277.652443 -27.81676) (xy 277.707816 -27.839696) (xy 277.759722 -27.869663)
			(xy 277.807272 -27.90615) (xy 277.849652 -27.94853) (xy 277.886139 -27.99608) (xy 277.916106 -28.047986)
			(xy 277.939042 -28.103359) (xy 277.954555 -28.161252) (xy 277.962378 -28.220674) (xy 277.962868 -28.250642)
			(xy 277.962868 -29.114242) (xy 277.962735 -29.12237) (xy 292.806628 -29.12237) (xy 292.806628 -28.25877)
			(xy 292.807118 -28.228786) (xy 292.814946 -28.16933) (xy 292.830467 -28.111405) (xy 292.853416 -28.056001)
			(xy 292.8834 -28.004067) (xy 292.919906 -27.956491) (xy 292.962311 -27.914086) (xy 293.009887 -27.87758)
			(xy 293.061821 -27.847596) (xy 293.117225 -27.824647) (xy 293.17515 -27.809126) (xy 293.234606 -27.801298)
			(xy 293.294574 -27.801298) (xy 293.35403 -27.809126) (xy 293.411955 -27.824647) (xy 293.467359 -27.847596)
			(xy 293.519293 -27.87758) (xy 293.566869 -27.914086) (xy 293.609274 -27.956491) (xy 293.64578 -28.004067)
			(xy 293.675764 -28.056001) (xy 293.698713 -28.111405) (xy 293.714234 -28.16933) (xy 293.722062 -28.228786)
			(xy 293.722552 -28.25877) (xy 293.722552 -29.114242) (xy 303.0474 -29.114242) (xy 303.0474 -28.250642)
			(xy 303.04789 -28.220674) (xy 303.055713 -28.161252) (xy 303.071226 -28.103359) (xy 303.094162 -28.047986)
			(xy 303.124129 -27.99608) (xy 303.160616 -27.94853) (xy 303.202996 -27.90615) (xy 303.250546 -27.869663)
			(xy 303.302452 -27.839696) (xy 303.357825 -27.81676) (xy 303.415718 -27.801247) (xy 303.47514 -27.793424)
			(xy 303.535076 -27.793424) (xy 303.594498 -27.801247) (xy 303.652391 -27.81676) (xy 303.707764 -27.839696)
			(xy 303.75967 -27.869663) (xy 303.80722 -27.90615) (xy 303.8496 -27.94853) (xy 303.886087 -27.99608)
			(xy 303.916054 -28.047986) (xy 303.93899 -28.103359) (xy 303.954503 -28.161252) (xy 303.962326 -28.220674)
			(xy 303.962816 -28.250642) (xy 303.962816 -29.114242) (xy 303.962683 -29.12237) (xy 318.806576 -29.12237)
			(xy 318.806576 -28.25877) (xy 318.807066 -28.228786) (xy 318.814894 -28.16933) (xy 318.830415 -28.111405)
			(xy 318.853364 -28.056001) (xy 318.883348 -28.004067) (xy 318.919854 -27.956491) (xy 318.962259 -27.914086)
			(xy 319.009835 -27.87758) (xy 319.061769 -27.847596) (xy 319.117173 -27.824647) (xy 319.175098 -27.809126)
			(xy 319.234554 -27.801298) (xy 319.294522 -27.801298) (xy 319.353978 -27.809126) (xy 319.411903 -27.824647)
			(xy 319.467307 -27.847596) (xy 319.519241 -27.87758) (xy 319.566817 -27.914086) (xy 319.609222 -27.956491)
			(xy 319.645728 -28.004067) (xy 319.675712 -28.056001) (xy 319.698661 -28.111405) (xy 319.714182 -28.16933)
			(xy 319.72201 -28.228786) (xy 319.7225 -28.25877) (xy 319.7225 -29.114242) (xy 329.047348 -29.114242)
			(xy 329.047348 -28.250642) (xy 329.047838 -28.220674) (xy 329.055661 -28.161252) (xy 329.071174 -28.103359)
			(xy 329.09411 -28.047986) (xy 329.124077 -27.99608) (xy 329.160564 -27.94853) (xy 329.202944 -27.90615)
			(xy 329.250494 -27.869663) (xy 329.3024 -27.839696) (xy 329.357773 -27.81676) (xy 329.415666 -27.801247)
			(xy 329.475088 -27.793424) (xy 329.535024 -27.793424) (xy 329.594446 -27.801247) (xy 329.652339 -27.81676)
			(xy 329.707712 -27.839696) (xy 329.759618 -27.869663) (xy 329.807168 -27.90615) (xy 329.849548 -27.94853)
			(xy 329.886035 -27.99608) (xy 329.916002 -28.047986) (xy 329.938938 -28.103359) (xy 329.954451 -28.161252)
			(xy 329.962274 -28.220674) (xy 329.962764 -28.250642) (xy 329.962764 -29.114242) (xy 329.962631 -29.12237)
			(xy 356.907084 -29.12237) (xy 356.907084 -28.25877) (xy 356.907574 -28.228802) (xy 356.915397 -28.16938)
			(xy 356.93091 -28.111487) (xy 356.953846 -28.056114) (xy 356.983813 -28.004208) (xy 357.0203 -27.956658)
			(xy 357.06268 -27.914278) (xy 357.11023 -27.877791) (xy 357.162136 -27.847824) (xy 357.217509 -27.824888)
			(xy 357.275402 -27.809375) (xy 357.334824 -27.801552) (xy 357.39476 -27.801552) (xy 357.454182 -27.809375)
			(xy 357.512075 -27.824888) (xy 357.567448 -27.847824) (xy 357.619354 -27.877791) (xy 357.666904 -27.914278)
			(xy 357.709284 -27.956658) (xy 357.745771 -28.004208) (xy 357.775738 -28.056114) (xy 357.798674 -28.111487)
			(xy 357.814187 -28.16938) (xy 357.82201 -28.228802) (xy 357.8225 -28.25877) (xy 357.8225 -29.114242)
			(xy 367.147348 -29.114242) (xy 367.147348 -28.250642) (xy 367.147838 -28.220658) (xy 367.155666 -28.161202)
			(xy 367.171187 -28.103277) (xy 367.194136 -28.047873) (xy 367.22412 -27.995939) (xy 367.260626 -27.948363)
			(xy 367.303031 -27.905958) (xy 367.350607 -27.869452) (xy 367.402541 -27.839468) (xy 367.457945 -27.816519)
			(xy 367.51587 -27.800998) (xy 367.575326 -27.79317) (xy 367.635294 -27.79317) (xy 367.69475 -27.800998)
			(xy 367.752675 -27.816519) (xy 367.808079 -27.839468) (xy 367.860013 -27.869452) (xy 367.907589 -27.905958)
			(xy 367.949994 -27.948363) (xy 367.9865 -27.995939) (xy 368.016484 -28.047873) (xy 368.039433 -28.103277)
			(xy 368.054954 -28.161202) (xy 368.062782 -28.220658) (xy 368.063272 -28.250642) (xy 368.063272 -29.114242)
			(xy 368.063139 -29.12237) (xy 382.907032 -29.12237) (xy 382.907032 -28.25877) (xy 382.907522 -28.228802)
			(xy 382.915345 -28.16938) (xy 382.930858 -28.111487) (xy 382.953794 -28.056114) (xy 382.983761 -28.004208)
			(xy 383.020248 -27.956658) (xy 383.062628 -27.914278) (xy 383.110178 -27.877791) (xy 383.162084 -27.847824)
			(xy 383.217457 -27.824888) (xy 383.27535 -27.809375) (xy 383.334772 -27.801552) (xy 383.394708 -27.801552)
			(xy 383.45413 -27.809375) (xy 383.512023 -27.824888) (xy 383.567396 -27.847824) (xy 383.619302 -27.877791)
			(xy 383.666852 -27.914278) (xy 383.709232 -27.956658) (xy 383.745719 -28.004208) (xy 383.775686 -28.056114)
			(xy 383.798622 -28.111487) (xy 383.814135 -28.16938) (xy 383.821958 -28.228802) (xy 383.822448 -28.25877)
			(xy 383.822448 -29.114242) (xy 393.147296 -29.114242) (xy 393.147296 -28.250642) (xy 393.147786 -28.220658)
			(xy 393.155614 -28.161202) (xy 393.171135 -28.103277) (xy 393.194084 -28.047873) (xy 393.224068 -27.995939)
			(xy 393.260574 -27.948363) (xy 393.302979 -27.905958) (xy 393.350555 -27.869452) (xy 393.402489 -27.839468)
			(xy 393.457893 -27.816519) (xy 393.515818 -27.800998) (xy 393.575274 -27.79317) (xy 393.635242 -27.79317)
			(xy 393.694698 -27.800998) (xy 393.752623 -27.816519) (xy 393.808027 -27.839468) (xy 393.859961 -27.869452)
			(xy 393.907537 -27.905958) (xy 393.949942 -27.948363) (xy 393.986448 -27.995939) (xy 394.016432 -28.047873)
			(xy 394.039381 -28.103277) (xy 394.054902 -28.161202) (xy 394.06273 -28.220658) (xy 394.06322 -28.250642)
			(xy 394.06322 -29.114242) (xy 394.063087 -29.12237) (xy 408.90698 -29.12237) (xy 408.90698 -28.25877)
			(xy 408.90747 -28.228802) (xy 408.915293 -28.16938) (xy 408.930806 -28.111487) (xy 408.953742 -28.056114)
			(xy 408.983709 -28.004208) (xy 409.020196 -27.956658) (xy 409.062576 -27.914278) (xy 409.110126 -27.877791)
			(xy 409.162032 -27.847824) (xy 409.217405 -27.824888) (xy 409.275298 -27.809375) (xy 409.33472 -27.801552)
			(xy 409.394656 -27.801552) (xy 409.454078 -27.809375) (xy 409.511971 -27.824888) (xy 409.567344 -27.847824)
			(xy 409.61925 -27.877791) (xy 409.6668 -27.914278) (xy 409.70918 -27.956658) (xy 409.745667 -28.004208)
			(xy 409.775634 -28.056114) (xy 409.79857 -28.111487) (xy 409.814083 -28.16938) (xy 409.821906 -28.228802)
			(xy 409.822396 -28.25877) (xy 409.822396 -29.114242) (xy 419.147244 -29.114242) (xy 419.147244 -28.250642)
			(xy 419.147734 -28.220658) (xy 419.155562 -28.161202) (xy 419.171083 -28.103277) (xy 419.194032 -28.047873)
			(xy 419.224016 -27.995939) (xy 419.260522 -27.948363) (xy 419.302927 -27.905958) (xy 419.350503 -27.869452)
			(xy 419.402437 -27.839468) (xy 419.457841 -27.816519) (xy 419.515766 -27.800998) (xy 419.575222 -27.79317)
			(xy 419.63519 -27.79317) (xy 419.694646 -27.800998) (xy 419.752571 -27.816519) (xy 419.807975 -27.839468)
			(xy 419.859909 -27.869452) (xy 419.907485 -27.905958) (xy 419.94989 -27.948363) (xy 419.986396 -27.995939)
			(xy 420.01638 -28.047873) (xy 420.039329 -28.103277) (xy 420.05485 -28.161202) (xy 420.062678 -28.220658)
			(xy 420.063168 -28.250642) (xy 420.063168 -29.114242) (xy 420.063035 -29.12237) (xy 434.906928 -29.12237)
			(xy 434.906928 -28.25877) (xy 434.907418 -28.228802) (xy 434.915241 -28.16938) (xy 434.930754 -28.111487)
			(xy 434.95369 -28.056114) (xy 434.983657 -28.004208) (xy 435.020144 -27.956658) (xy 435.062524 -27.914278)
			(xy 435.110074 -27.877791) (xy 435.16198 -27.847824) (xy 435.217353 -27.824888) (xy 435.275246 -27.809375)
			(xy 435.334668 -27.801552) (xy 435.394604 -27.801552) (xy 435.454026 -27.809375) (xy 435.511919 -27.824888)
			(xy 435.567292 -27.847824) (xy 435.619198 -27.877791) (xy 435.666748 -27.914278) (xy 435.709128 -27.956658)
			(xy 435.745615 -28.004208) (xy 435.775582 -28.056114) (xy 435.798518 -28.111487) (xy 435.814031 -28.16938)
			(xy 435.821854 -28.228802) (xy 435.822344 -28.25877) (xy 435.822344 -29.114242) (xy 445.147192 -29.114242)
			(xy 445.147192 -28.250642) (xy 445.147682 -28.220658) (xy 445.15551 -28.161202) (xy 445.171031 -28.103277)
			(xy 445.19398 -28.047873) (xy 445.223964 -27.995939) (xy 445.26047 -27.948363) (xy 445.302875 -27.905958)
			(xy 445.350451 -27.869452) (xy 445.402385 -27.839468) (xy 445.457789 -27.816519) (xy 445.515714 -27.800998)
			(xy 445.57517 -27.79317) (xy 445.635138 -27.79317) (xy 445.694594 -27.800998) (xy 445.752519 -27.816519)
			(xy 445.807923 -27.839468) (xy 445.859857 -27.869452) (xy 445.907433 -27.905958) (xy 445.949838 -27.948363)
			(xy 445.986344 -27.995939) (xy 446.016328 -28.047873) (xy 446.039277 -28.103277) (xy 446.054798 -28.161202)
			(xy 446.062626 -28.220658) (xy 446.063116 -28.250642) (xy 446.063116 -29.114242) (xy 446.062626 -29.144226)
			(xy 446.054798 -29.203682) (xy 446.039277 -29.261607) (xy 446.016328 -29.317011) (xy 445.986344 -29.368945)
			(xy 445.949838 -29.416521) (xy 445.907433 -29.458926) (xy 445.859857 -29.495432) (xy 445.807923 -29.525416)
			(xy 445.752519 -29.548365) (xy 445.694594 -29.563886) (xy 445.635138 -29.571714) (xy 445.57517 -29.571714)
			(xy 445.515714 -29.563886) (xy 445.457789 -29.548365) (xy 445.402385 -29.525416) (xy 445.350451 -29.495432)
			(xy 445.302875 -29.458926) (xy 445.26047 -29.416521) (xy 445.223964 -29.368945) (xy 445.19398 -29.317011)
			(xy 445.171031 -29.261607) (xy 445.15551 -29.203682) (xy 445.147682 -29.144226) (xy 445.147192 -29.114242)
			(xy 435.822344 -29.114242) (xy 435.822344 -29.12237) (xy 435.821854 -29.152338) (xy 435.814031 -29.21176)
			(xy 435.798518 -29.269653) (xy 435.775582 -29.325026) (xy 435.745615 -29.376932) (xy 435.709128 -29.424482)
			(xy 435.666748 -29.466862) (xy 435.619198 -29.503349) (xy 435.567292 -29.533316) (xy 435.511919 -29.556252)
			(xy 435.454026 -29.571765) (xy 435.394604 -29.579588) (xy 435.334668 -29.579588) (xy 435.275246 -29.571765)
			(xy 435.217353 -29.556252) (xy 435.16198 -29.533316) (xy 435.110074 -29.503349) (xy 435.062524 -29.466862)
			(xy 435.020144 -29.424482) (xy 434.983657 -29.376932) (xy 434.95369 -29.325026) (xy 434.930754 -29.269653)
			(xy 434.915241 -29.21176) (xy 434.907418 -29.152338) (xy 434.906928 -29.12237) (xy 420.063035 -29.12237)
			(xy 420.062678 -29.144226) (xy 420.05485 -29.203682) (xy 420.039329 -29.261607) (xy 420.01638 -29.317011)
			(xy 419.986396 -29.368945) (xy 419.94989 -29.416521) (xy 419.907485 -29.458926) (xy 419.859909 -29.495432)
			(xy 419.807975 -29.525416) (xy 419.752571 -29.548365) (xy 419.694646 -29.563886) (xy 419.63519 -29.571714)
			(xy 419.575222 -29.571714) (xy 419.515766 -29.563886) (xy 419.457841 -29.548365) (xy 419.402437 -29.525416)
			(xy 419.350503 -29.495432) (xy 419.302927 -29.458926) (xy 419.260522 -29.416521) (xy 419.224016 -29.368945)
			(xy 419.194032 -29.317011) (xy 419.171083 -29.261607) (xy 419.155562 -29.203682) (xy 419.147734 -29.144226)
			(xy 419.147244 -29.114242) (xy 409.822396 -29.114242) (xy 409.822396 -29.12237) (xy 409.821906 -29.152338)
			(xy 409.814083 -29.21176) (xy 409.79857 -29.269653) (xy 409.775634 -29.325026) (xy 409.745667 -29.376932)
			(xy 409.70918 -29.424482) (xy 409.6668 -29.466862) (xy 409.61925 -29.503349) (xy 409.567344 -29.533316)
			(xy 409.511971 -29.556252) (xy 409.454078 -29.571765) (xy 409.394656 -29.579588) (xy 409.33472 -29.579588)
			(xy 409.275298 -29.571765) (xy 409.217405 -29.556252) (xy 409.162032 -29.533316) (xy 409.110126 -29.503349)
			(xy 409.062576 -29.466862) (xy 409.020196 -29.424482) (xy 408.983709 -29.376932) (xy 408.953742 -29.325026)
			(xy 408.930806 -29.269653) (xy 408.915293 -29.21176) (xy 408.90747 -29.152338) (xy 408.90698 -29.12237)
			(xy 394.063087 -29.12237) (xy 394.06273 -29.144226) (xy 394.054902 -29.203682) (xy 394.039381 -29.261607)
			(xy 394.016432 -29.317011) (xy 393.986448 -29.368945) (xy 393.949942 -29.416521) (xy 393.907537 -29.458926)
			(xy 393.859961 -29.495432) (xy 393.808027 -29.525416) (xy 393.752623 -29.548365) (xy 393.694698 -29.563886)
			(xy 393.635242 -29.571714) (xy 393.575274 -29.571714) (xy 393.515818 -29.563886) (xy 393.457893 -29.548365)
			(xy 393.402489 -29.525416) (xy 393.350555 -29.495432) (xy 393.302979 -29.458926) (xy 393.260574 -29.416521)
			(xy 393.224068 -29.368945) (xy 393.194084 -29.317011) (xy 393.171135 -29.261607) (xy 393.155614 -29.203682)
			(xy 393.147786 -29.144226) (xy 393.147296 -29.114242) (xy 383.822448 -29.114242) (xy 383.822448 -29.12237)
			(xy 383.821958 -29.152338) (xy 383.814135 -29.21176) (xy 383.798622 -29.269653) (xy 383.775686 -29.325026)
			(xy 383.745719 -29.376932) (xy 383.709232 -29.424482) (xy 383.666852 -29.466862) (xy 383.619302 -29.503349)
			(xy 383.567396 -29.533316) (xy 383.512023 -29.556252) (xy 383.45413 -29.571765) (xy 383.394708 -29.579588)
			(xy 383.334772 -29.579588) (xy 383.27535 -29.571765) (xy 383.217457 -29.556252) (xy 383.162084 -29.533316)
			(xy 383.110178 -29.503349) (xy 383.062628 -29.466862) (xy 383.020248 -29.424482) (xy 382.983761 -29.376932)
			(xy 382.953794 -29.325026) (xy 382.930858 -29.269653) (xy 382.915345 -29.21176) (xy 382.907522 -29.152338)
			(xy 382.907032 -29.12237) (xy 368.063139 -29.12237) (xy 368.062782 -29.144226) (xy 368.054954 -29.203682)
			(xy 368.039433 -29.261607) (xy 368.016484 -29.317011) (xy 367.9865 -29.368945) (xy 367.949994 -29.416521)
			(xy 367.907589 -29.458926) (xy 367.860013 -29.495432) (xy 367.808079 -29.525416) (xy 367.752675 -29.548365)
			(xy 367.69475 -29.563886) (xy 367.635294 -29.571714) (xy 367.575326 -29.571714) (xy 367.51587 -29.563886)
			(xy 367.457945 -29.548365) (xy 367.402541 -29.525416) (xy 367.350607 -29.495432) (xy 367.303031 -29.458926)
			(xy 367.260626 -29.416521) (xy 367.22412 -29.368945) (xy 367.194136 -29.317011) (xy 367.171187 -29.261607)
			(xy 367.155666 -29.203682) (xy 367.147838 -29.144226) (xy 367.147348 -29.114242) (xy 357.8225 -29.114242)
			(xy 357.8225 -29.12237) (xy 357.82201 -29.152338) (xy 357.814187 -29.21176) (xy 357.798674 -29.269653)
			(xy 357.775738 -29.325026) (xy 357.745771 -29.376932) (xy 357.709284 -29.424482) (xy 357.666904 -29.466862)
			(xy 357.619354 -29.503349) (xy 357.567448 -29.533316) (xy 357.512075 -29.556252) (xy 357.454182 -29.571765)
			(xy 357.39476 -29.579588) (xy 357.334824 -29.579588) (xy 357.275402 -29.571765) (xy 357.217509 -29.556252)
			(xy 357.162136 -29.533316) (xy 357.11023 -29.503349) (xy 357.06268 -29.466862) (xy 357.0203 -29.424482)
			(xy 356.983813 -29.376932) (xy 356.953846 -29.325026) (xy 356.93091 -29.269653) (xy 356.915397 -29.21176)
			(xy 356.907574 -29.152338) (xy 356.907084 -29.12237) (xy 329.962631 -29.12237) (xy 329.962274 -29.14421)
			(xy 329.954451 -29.203632) (xy 329.938938 -29.261525) (xy 329.916002 -29.316898) (xy 329.886035 -29.368804)
			(xy 329.849548 -29.416354) (xy 329.807168 -29.458734) (xy 329.759618 -29.495221) (xy 329.707712 -29.525188)
			(xy 329.652339 -29.548124) (xy 329.594446 -29.563637) (xy 329.535024 -29.57146) (xy 329.475088 -29.57146)
			(xy 329.415666 -29.563637) (xy 329.357773 -29.548124) (xy 329.3024 -29.525188) (xy 329.250494 -29.495221)
			(xy 329.202944 -29.458734) (xy 329.160564 -29.416354) (xy 329.124077 -29.368804) (xy 329.09411 -29.316898)
			(xy 329.071174 -29.261525) (xy 329.055661 -29.203632) (xy 329.047838 -29.14421) (xy 329.047348 -29.114242)
			(xy 319.7225 -29.114242) (xy 319.7225 -29.12237) (xy 319.72201 -29.152354) (xy 319.714182 -29.21181)
			(xy 319.698661 -29.269735) (xy 319.675712 -29.325139) (xy 319.645728 -29.377073) (xy 319.609222 -29.424649)
			(xy 319.566817 -29.467054) (xy 319.519241 -29.50356) (xy 319.467307 -29.533544) (xy 319.411903 -29.556493)
			(xy 319.353978 -29.572014) (xy 319.294522 -29.579842) (xy 319.234554 -29.579842) (xy 319.175098 -29.572014)
			(xy 319.117173 -29.556493) (xy 319.061769 -29.533544) (xy 319.009835 -29.50356) (xy 318.962259 -29.467054)
			(xy 318.919854 -29.424649) (xy 318.883348 -29.377073) (xy 318.853364 -29.325139) (xy 318.830415 -29.269735)
			(xy 318.814894 -29.21181) (xy 318.807066 -29.152354) (xy 318.806576 -29.12237) (xy 303.962683 -29.12237)
			(xy 303.962326 -29.14421) (xy 303.954503 -29.203632) (xy 303.93899 -29.261525) (xy 303.916054 -29.316898)
			(xy 303.886087 -29.368804) (xy 303.8496 -29.416354) (xy 303.80722 -29.458734) (xy 303.75967 -29.495221)
			(xy 303.707764 -29.525188) (xy 303.652391 -29.548124) (xy 303.594498 -29.563637) (xy 303.535076 -29.57146)
			(xy 303.47514 -29.57146) (xy 303.415718 -29.563637) (xy 303.357825 -29.548124) (xy 303.302452 -29.525188)
			(xy 303.250546 -29.495221) (xy 303.202996 -29.458734) (xy 303.160616 -29.416354) (xy 303.124129 -29.368804)
			(xy 303.094162 -29.316898) (xy 303.071226 -29.261525) (xy 303.055713 -29.203632) (xy 303.04789 -29.14421)
			(xy 303.0474 -29.114242) (xy 293.722552 -29.114242) (xy 293.722552 -29.12237) (xy 293.722062 -29.152354)
			(xy 293.714234 -29.21181) (xy 293.698713 -29.269735) (xy 293.675764 -29.325139) (xy 293.64578 -29.377073)
			(xy 293.609274 -29.424649) (xy 293.566869 -29.467054) (xy 293.519293 -29.50356) (xy 293.467359 -29.533544)
			(xy 293.411955 -29.556493) (xy 293.35403 -29.572014) (xy 293.294574 -29.579842) (xy 293.234606 -29.579842)
			(xy 293.17515 -29.572014) (xy 293.117225 -29.556493) (xy 293.061821 -29.533544) (xy 293.009887 -29.50356)
			(xy 292.962311 -29.467054) (xy 292.919906 -29.424649) (xy 292.8834 -29.377073) (xy 292.853416 -29.325139)
			(xy 292.830467 -29.269735) (xy 292.814946 -29.21181) (xy 292.807118 -29.152354) (xy 292.806628 -29.12237)
			(xy 277.962735 -29.12237) (xy 277.962378 -29.14421) (xy 277.954555 -29.203632) (xy 277.939042 -29.261525)
			(xy 277.916106 -29.316898) (xy 277.886139 -29.368804) (xy 277.849652 -29.416354) (xy 277.807272 -29.458734)
			(xy 277.759722 -29.495221) (xy 277.707816 -29.525188) (xy 277.652443 -29.548124) (xy 277.59455 -29.563637)
			(xy 277.535128 -29.57146) (xy 277.475192 -29.57146) (xy 277.41577 -29.563637) (xy 277.357877 -29.548124)
			(xy 277.302504 -29.525188) (xy 277.250598 -29.495221) (xy 277.203048 -29.458734) (xy 277.160668 -29.416354)
			(xy 277.124181 -29.368804) (xy 277.094214 -29.316898) (xy 277.071278 -29.261525) (xy 277.055765 -29.203632)
			(xy 277.047942 -29.14421) (xy 277.047452 -29.114242) (xy 267.722604 -29.114242) (xy 267.722604 -29.12237)
			(xy 267.722114 -29.152354) (xy 267.714286 -29.21181) (xy 267.698765 -29.269735) (xy 267.675816 -29.325139)
			(xy 267.645832 -29.377073) (xy 267.609326 -29.424649) (xy 267.566921 -29.467054) (xy 267.519345 -29.50356)
			(xy 267.467411 -29.533544) (xy 267.412007 -29.556493) (xy 267.354082 -29.572014) (xy 267.294626 -29.579842)
			(xy 267.234658 -29.579842) (xy 267.175202 -29.572014) (xy 267.117277 -29.556493) (xy 267.061873 -29.533544)
			(xy 267.009939 -29.50356) (xy 266.962363 -29.467054) (xy 266.919958 -29.424649) (xy 266.883452 -29.377073)
			(xy 266.853468 -29.325139) (xy 266.830519 -29.269735) (xy 266.814998 -29.21181) (xy 266.80717 -29.152354)
			(xy 266.80668 -29.12237) (xy 251.962787 -29.12237) (xy 251.96243 -29.14421) (xy 251.954607 -29.203632)
			(xy 251.939094 -29.261525) (xy 251.916158 -29.316898) (xy 251.886191 -29.368804) (xy 251.849704 -29.416354)
			(xy 251.807324 -29.458734) (xy 251.759774 -29.495221) (xy 251.707868 -29.525188) (xy 251.652495 -29.548124)
			(xy 251.594602 -29.563637) (xy 251.53518 -29.57146) (xy 251.475244 -29.57146) (xy 251.415822 -29.563637)
			(xy 251.357929 -29.548124) (xy 251.302556 -29.525188) (xy 251.25065 -29.495221) (xy 251.2031 -29.458734)
			(xy 251.16072 -29.416354) (xy 251.124233 -29.368804) (xy 251.094266 -29.316898) (xy 251.07133 -29.261525)
			(xy 251.055817 -29.203632) (xy 251.047994 -29.14421) (xy 251.047504 -29.114242) (xy 241.722656 -29.114242)
			(xy 241.722656 -29.12237) (xy 241.722166 -29.152354) (xy 241.714338 -29.21181) (xy 241.698817 -29.269735)
			(xy 241.675868 -29.325139) (xy 241.645884 -29.377073) (xy 241.609378 -29.424649) (xy 241.566973 -29.467054)
			(xy 241.519397 -29.50356) (xy 241.467463 -29.533544) (xy 241.412059 -29.556493) (xy 241.354134 -29.572014)
			(xy 241.294678 -29.579842) (xy 241.23471 -29.579842) (xy 241.175254 -29.572014) (xy 241.117329 -29.556493)
			(xy 241.061925 -29.533544) (xy 241.009991 -29.50356) (xy 240.962415 -29.467054) (xy 240.92001 -29.424649)
			(xy 240.883504 -29.377073) (xy 240.85352 -29.325139) (xy 240.830571 -29.269735) (xy 240.81505 -29.21181)
			(xy 240.807222 -29.152354) (xy 240.806732 -29.12237) (xy 213.862787 -29.12237) (xy 213.86243 -29.14421)
			(xy 213.854607 -29.203632) (xy 213.839094 -29.261525) (xy 213.816158 -29.316898) (xy 213.786191 -29.368804)
			(xy 213.749704 -29.416354) (xy 213.707324 -29.458734) (xy 213.659774 -29.495221) (xy 213.607868 -29.525188)
			(xy 213.552495 -29.548124) (xy 213.494602 -29.563637) (xy 213.43518 -29.57146) (xy 213.375244 -29.57146)
			(xy 213.315822 -29.563637) (xy 213.257929 -29.548124) (xy 213.202556 -29.525188) (xy 213.15065 -29.495221)
			(xy 213.1031 -29.458734) (xy 213.06072 -29.416354) (xy 213.024233 -29.368804) (xy 212.994266 -29.316898)
			(xy 212.97133 -29.261525) (xy 212.955817 -29.203632) (xy 212.947994 -29.14421) (xy 212.947504 -29.114242)
			(xy 203.622656 -29.114242) (xy 203.622656 -29.12237) (xy 203.622166 -29.152354) (xy 203.614338 -29.21181)
			(xy 203.598817 -29.269735) (xy 203.575868 -29.325139) (xy 203.545884 -29.377073) (xy 203.509378 -29.424649)
			(xy 203.466973 -29.467054) (xy 203.419397 -29.50356) (xy 203.367463 -29.533544) (xy 203.312059 -29.556493)
			(xy 203.254134 -29.572014) (xy 203.194678 -29.579842) (xy 203.13471 -29.579842) (xy 203.075254 -29.572014)
			(xy 203.017329 -29.556493) (xy 202.961925 -29.533544) (xy 202.909991 -29.50356) (xy 202.862415 -29.467054)
			(xy 202.82001 -29.424649) (xy 202.783504 -29.377073) (xy 202.75352 -29.325139) (xy 202.730571 -29.269735)
			(xy 202.71505 -29.21181) (xy 202.707222 -29.152354) (xy 202.706732 -29.12237) (xy 187.862839 -29.12237)
			(xy 187.862482 -29.14421) (xy 187.854659 -29.203632) (xy 187.839146 -29.261525) (xy 187.81621 -29.316898)
			(xy 187.786243 -29.368804) (xy 187.749756 -29.416354) (xy 187.707376 -29.458734) (xy 187.659826 -29.495221)
			(xy 187.60792 -29.525188) (xy 187.552547 -29.548124) (xy 187.494654 -29.563637) (xy 187.435232 -29.57146)
			(xy 187.375296 -29.57146) (xy 187.315874 -29.563637) (xy 187.257981 -29.548124) (xy 187.202608 -29.525188)
			(xy 187.150702 -29.495221) (xy 187.103152 -29.458734) (xy 187.060772 -29.416354) (xy 187.024285 -29.368804)
			(xy 186.994318 -29.316898) (xy 186.971382 -29.261525) (xy 186.955869 -29.203632) (xy 186.948046 -29.14421)
			(xy 186.947556 -29.114242) (xy 177.622708 -29.114242) (xy 177.622708 -29.12237) (xy 177.622218 -29.152354)
			(xy 177.61439 -29.21181) (xy 177.598869 -29.269735) (xy 177.57592 -29.325139) (xy 177.545936 -29.377073)
			(xy 177.50943 -29.424649) (xy 177.467025 -29.467054) (xy 177.419449 -29.50356) (xy 177.367515 -29.533544)
			(xy 177.312111 -29.556493) (xy 177.254186 -29.572014) (xy 177.19473 -29.579842) (xy 177.134762 -29.579842)
			(xy 177.075306 -29.572014) (xy 177.017381 -29.556493) (xy 176.961977 -29.533544) (xy 176.910043 -29.50356)
			(xy 176.862467 -29.467054) (xy 176.820062 -29.424649) (xy 176.783556 -29.377073) (xy 176.753572 -29.325139)
			(xy 176.730623 -29.269735) (xy 176.715102 -29.21181) (xy 176.707274 -29.152354) (xy 176.706784 -29.12237)
			(xy 161.862891 -29.12237) (xy 161.862534 -29.14421) (xy 161.854711 -29.203632) (xy 161.839198 -29.261525)
			(xy 161.816262 -29.316898) (xy 161.786295 -29.368804) (xy 161.749808 -29.416354) (xy 161.707428 -29.458734)
			(xy 161.659878 -29.495221) (xy 161.607972 -29.525188) (xy 161.552599 -29.548124) (xy 161.494706 -29.563637)
			(xy 161.435284 -29.57146) (xy 161.375348 -29.57146) (xy 161.315926 -29.563637) (xy 161.258033 -29.548124)
			(xy 161.20266 -29.525188) (xy 161.150754 -29.495221) (xy 161.103204 -29.458734) (xy 161.060824 -29.416354)
			(xy 161.024337 -29.368804) (xy 160.99437 -29.316898) (xy 160.971434 -29.261525) (xy 160.955921 -29.203632)
			(xy 160.948098 -29.14421) (xy 160.947608 -29.114242) (xy 151.62276 -29.114242) (xy 151.62276 -29.12237)
			(xy 151.62227 -29.152354) (xy 151.614442 -29.21181) (xy 151.598921 -29.269735) (xy 151.575972 -29.325139)
			(xy 151.545988 -29.377073) (xy 151.509482 -29.424649) (xy 151.467077 -29.467054) (xy 151.419501 -29.50356)
			(xy 151.367567 -29.533544) (xy 151.312163 -29.556493) (xy 151.254238 -29.572014) (xy 151.194782 -29.579842)
			(xy 151.134814 -29.579842) (xy 151.075358 -29.572014) (xy 151.017433 -29.556493) (xy 150.962029 -29.533544)
			(xy 150.910095 -29.50356) (xy 150.862519 -29.467054) (xy 150.820114 -29.424649) (xy 150.783608 -29.377073)
			(xy 150.753624 -29.325139) (xy 150.730675 -29.269735) (xy 150.715154 -29.21181) (xy 150.707326 -29.152354)
			(xy 150.706836 -29.12237) (xy 135.862943 -29.12237) (xy 135.862586 -29.14421) (xy 135.854763 -29.203632)
			(xy 135.83925 -29.261525) (xy 135.816314 -29.316898) (xy 135.786347 -29.368804) (xy 135.74986 -29.416354)
			(xy 135.70748 -29.458734) (xy 135.65993 -29.495221) (xy 135.608024 -29.525188) (xy 135.552651 -29.548124)
			(xy 135.494758 -29.563637) (xy 135.435336 -29.57146) (xy 135.3754 -29.57146) (xy 135.315978 -29.563637)
			(xy 135.258085 -29.548124) (xy 135.202712 -29.525188) (xy 135.150806 -29.495221) (xy 135.103256 -29.458734)
			(xy 135.060876 -29.416354) (xy 135.024389 -29.368804) (xy 134.994422 -29.316898) (xy 134.971486 -29.261525)
			(xy 134.955973 -29.203632) (xy 134.94815 -29.14421) (xy 134.94766 -29.114242) (xy 125.622812 -29.114242)
			(xy 125.622812 -29.12237) (xy 125.622322 -29.152354) (xy 125.614494 -29.21181) (xy 125.598973 -29.269735)
			(xy 125.576024 -29.325139) (xy 125.54604 -29.377073) (xy 125.509534 -29.424649) (xy 125.467129 -29.467054)
			(xy 125.419553 -29.50356) (xy 125.367619 -29.533544) (xy 125.312215 -29.556493) (xy 125.25429 -29.572014)
			(xy 125.194834 -29.579842) (xy 125.134866 -29.579842) (xy 125.07541 -29.572014) (xy 125.017485 -29.556493)
			(xy 124.962081 -29.533544) (xy 124.910147 -29.50356) (xy 124.862571 -29.467054) (xy 124.820166 -29.424649)
			(xy 124.78366 -29.377073) (xy 124.753676 -29.325139) (xy 124.730727 -29.269735) (xy 124.715206 -29.21181)
			(xy 124.707378 -29.152354) (xy 124.706888 -29.12237) (xy 97.762943 -29.12237) (xy 97.762586 -29.144226)
			(xy 97.754758 -29.203682) (xy 97.739237 -29.261607) (xy 97.716288 -29.317011) (xy 97.686304 -29.368945)
			(xy 97.649798 -29.416521) (xy 97.607393 -29.458926) (xy 97.559817 -29.495432) (xy 97.507883 -29.525416)
			(xy 97.452479 -29.548365) (xy 97.394554 -29.563886) (xy 97.335098 -29.571714) (xy 97.27513 -29.571714)
			(xy 97.215674 -29.563886) (xy 97.157749 -29.548365) (xy 97.102345 -29.525416) (xy 97.050411 -29.495432)
			(xy 97.002835 -29.458926) (xy 96.96043 -29.416521) (xy 96.923924 -29.368945) (xy 96.89394 -29.317011)
			(xy 96.870991 -29.261607) (xy 96.85547 -29.203682) (xy 96.847642 -29.144226) (xy 96.847152 -29.114242)
			(xy 87.522304 -29.114242) (xy 87.522304 -29.12237) (xy 87.521814 -29.152338) (xy 87.513991 -29.21176)
			(xy 87.498478 -29.269653) (xy 87.475542 -29.325026) (xy 87.445575 -29.376932) (xy 87.409088 -29.424482)
			(xy 87.366708 -29.466862) (xy 87.319158 -29.503349) (xy 87.267252 -29.533316) (xy 87.211879 -29.556252)
			(xy 87.153986 -29.571765) (xy 87.094564 -29.579588) (xy 87.034628 -29.579588) (xy 86.975206 -29.571765)
			(xy 86.917313 -29.556252) (xy 86.86194 -29.533316) (xy 86.810034 -29.503349) (xy 86.762484 -29.466862)
			(xy 86.720104 -29.424482) (xy 86.683617 -29.376932) (xy 86.65365 -29.325026) (xy 86.630714 -29.269653)
			(xy 86.615201 -29.21176) (xy 86.607378 -29.152338) (xy 86.606888 -29.12237) (xy 71.762995 -29.12237)
			(xy 71.762638 -29.144226) (xy 71.75481 -29.203682) (xy 71.739289 -29.261607) (xy 71.71634 -29.317011)
			(xy 71.686356 -29.368945) (xy 71.64985 -29.416521) (xy 71.607445 -29.458926) (xy 71.559869 -29.495432)
			(xy 71.507935 -29.525416) (xy 71.452531 -29.548365) (xy 71.394606 -29.563886) (xy 71.33515 -29.571714)
			(xy 71.275182 -29.571714) (xy 71.215726 -29.563886) (xy 71.157801 -29.548365) (xy 71.102397 -29.525416)
			(xy 71.050463 -29.495432) (xy 71.002887 -29.458926) (xy 70.960482 -29.416521) (xy 70.923976 -29.368945)
			(xy 70.893992 -29.317011) (xy 70.871043 -29.261607) (xy 70.855522 -29.203682) (xy 70.847694 -29.144226)
			(xy 70.847204 -29.114242) (xy 61.522356 -29.114242) (xy 61.522356 -29.12237) (xy 61.521866 -29.152338)
			(xy 61.514043 -29.21176) (xy 61.49853 -29.269653) (xy 61.475594 -29.325026) (xy 61.445627 -29.376932)
			(xy 61.40914 -29.424482) (xy 61.36676 -29.466862) (xy 61.31921 -29.503349) (xy 61.267304 -29.533316)
			(xy 61.211931 -29.556252) (xy 61.154038 -29.571765) (xy 61.094616 -29.579588) (xy 61.03468 -29.579588)
			(xy 60.975258 -29.571765) (xy 60.917365 -29.556252) (xy 60.861992 -29.533316) (xy 60.810086 -29.503349)
			(xy 60.762536 -29.466862) (xy 60.720156 -29.424482) (xy 60.683669 -29.376932) (xy 60.653702 -29.325026)
			(xy 60.630766 -29.269653) (xy 60.615253 -29.21176) (xy 60.60743 -29.152338) (xy 60.60694 -29.12237)
			(xy 45.763047 -29.12237) (xy 45.76269 -29.144226) (xy 45.754862 -29.203682) (xy 45.739341 -29.261607)
			(xy 45.716392 -29.317011) (xy 45.686408 -29.368945) (xy 45.649902 -29.416521) (xy 45.607497 -29.458926)
			(xy 45.559921 -29.495432) (xy 45.507987 -29.525416) (xy 45.452583 -29.548365) (xy 45.394658 -29.563886)
			(xy 45.335202 -29.571714) (xy 45.275234 -29.571714) (xy 45.215778 -29.563886) (xy 45.157853 -29.548365)
			(xy 45.102449 -29.525416) (xy 45.050515 -29.495432) (xy 45.002939 -29.458926) (xy 44.960534 -29.416521)
			(xy 44.924028 -29.368945) (xy 44.894044 -29.317011) (xy 44.871095 -29.261607) (xy 44.855574 -29.203682)
			(xy 44.847746 -29.144226) (xy 44.847256 -29.114242) (xy 35.522408 -29.114242) (xy 35.522408 -29.12237)
			(xy 35.521918 -29.152338) (xy 35.514095 -29.21176) (xy 35.498582 -29.269653) (xy 35.475646 -29.325026)
			(xy 35.445679 -29.376932) (xy 35.409192 -29.424482) (xy 35.366812 -29.466862) (xy 35.319262 -29.503349)
			(xy 35.267356 -29.533316) (xy 35.211983 -29.556252) (xy 35.15409 -29.571765) (xy 35.094668 -29.579588)
			(xy 35.034732 -29.579588) (xy 34.97531 -29.571765) (xy 34.917417 -29.556252) (xy 34.862044 -29.533316)
			(xy 34.810138 -29.503349) (xy 34.762588 -29.466862) (xy 34.720208 -29.424482) (xy 34.683721 -29.376932)
			(xy 34.653754 -29.325026) (xy 34.630818 -29.269653) (xy 34.615305 -29.21176) (xy 34.607482 -29.152338)
			(xy 34.606992 -29.12237) (xy 19.763099 -29.12237) (xy 19.762742 -29.144226) (xy 19.754914 -29.203682)
			(xy 19.739393 -29.261607) (xy 19.716444 -29.317011) (xy 19.68646 -29.368945) (xy 19.649954 -29.416521)
			(xy 19.607549 -29.458926) (xy 19.559973 -29.495432) (xy 19.508039 -29.525416) (xy 19.452635 -29.548365)
			(xy 19.39471 -29.563886) (xy 19.335254 -29.571714) (xy 19.275286 -29.571714) (xy 19.21583 -29.563886)
			(xy 19.157905 -29.548365) (xy 19.102501 -29.525416) (xy 19.050567 -29.495432) (xy 19.002991 -29.458926)
			(xy 18.960586 -29.416521) (xy 18.92408 -29.368945) (xy 18.894096 -29.317011) (xy 18.871147 -29.261607)
			(xy 18.855626 -29.203682) (xy 18.847798 -29.144226) (xy 18.847308 -29.114242) (xy 9.52246 -29.114242)
			(xy 9.52246 -29.12237) (xy 9.52197 -29.152338) (xy 9.514147 -29.21176) (xy 9.498634 -29.269653) (xy 9.475698 -29.325026)
			(xy 9.445731 -29.376932) (xy 9.409244 -29.424482) (xy 9.366864 -29.466862) (xy 9.319314 -29.503349)
			(xy 9.267408 -29.533316) (xy 9.212035 -29.556252) (xy 9.154142 -29.571765) (xy 9.09472 -29.579588)
			(xy 9.034784 -29.579588) (xy 8.975362 -29.571765) (xy 8.917469 -29.556252) (xy 8.862096 -29.533316)
			(xy 8.81019 -29.503349) (xy 8.76264 -29.466862) (xy 8.72026 -29.424482) (xy 8.683773 -29.376932)
			(xy 8.653806 -29.325026) (xy 8.63087 -29.269653) (xy 8.615357 -29.21176) (xy 8.607534 -29.152338)
			(xy 8.607044 -29.12237) (xy 0.508 -29.12237) (xy 0.508 -30.922468) (xy 6.752844 -30.922468) (xy 6.752844 -30.058868)
			(xy 6.753334 -30.0289) (xy 6.761157 -29.969478) (xy 6.77667 -29.911585) (xy 6.799606 -29.856212)
			(xy 6.829573 -29.804306) (xy 6.86606 -29.756756) (xy 6.90844 -29.714376) (xy 6.95599 -29.677889)
			(xy 7.007896 -29.647922) (xy 7.063269 -29.624986) (xy 7.121162 -29.609473) (xy 7.180584 -29.60165)
			(xy 7.24052 -29.60165) (xy 7.299942 -29.609473) (xy 7.357835 -29.624986) (xy 7.413208 -29.647922)
			(xy 7.465114 -29.677889) (xy 7.512664 -29.714376) (xy 7.555044 -29.756756) (xy 7.591531 -29.804306)
			(xy 7.621498 -29.856212) (xy 7.644434 -29.911585) (xy 7.659947 -29.969478) (xy 7.66777 -30.0289)
			(xy 7.66826 -30.058868) (xy 7.66826 -30.92069) (xy 21.489416 -30.92069) (xy 21.489416 -30.05709)
			(xy 21.489906 -30.027106) (xy 21.497734 -29.96765) (xy 21.513255 -29.909725) (xy 21.536204 -29.854321)
			(xy 21.566188 -29.802387) (xy 21.602694 -29.754811) (xy 21.645099 -29.712406) (xy 21.692675 -29.6759)
			(xy 21.744609 -29.645916) (xy 21.800013 -29.622967) (xy 21.857938 -29.607446) (xy 21.917394 -29.599618)
			(xy 21.977362 -29.599618) (xy 22.036818 -29.607446) (xy 22.094743 -29.622967) (xy 22.150147 -29.645916)
			(xy 22.202081 -29.6759) (xy 22.249657 -29.712406) (xy 22.292062 -29.754811) (xy 22.328568 -29.802387)
			(xy 22.358552 -29.854321) (xy 22.381501 -29.909725) (xy 22.397022 -29.96765) (xy 22.40485 -30.027106)
			(xy 22.40534 -30.05709) (xy 22.40534 -30.92069) (xy 22.405311 -30.922468) (xy 32.752792 -30.922468)
			(xy 32.752792 -30.058868) (xy 32.753282 -30.0289) (xy 32.761105 -29.969478) (xy 32.776618 -29.911585)
			(xy 32.799554 -29.856212) (xy 32.829521 -29.804306) (xy 32.866008 -29.756756) (xy 32.908388 -29.714376)
			(xy 32.955938 -29.677889) (xy 33.007844 -29.647922) (xy 33.063217 -29.624986) (xy 33.12111 -29.609473)
			(xy 33.180532 -29.60165) (xy 33.240468 -29.60165) (xy 33.29989 -29.609473) (xy 33.357783 -29.624986)
			(xy 33.413156 -29.647922) (xy 33.465062 -29.677889) (xy 33.512612 -29.714376) (xy 33.554992 -29.756756)
			(xy 33.591479 -29.804306) (xy 33.621446 -29.856212) (xy 33.644382 -29.911585) (xy 33.659895 -29.969478)
			(xy 33.667718 -30.0289) (xy 33.668208 -30.058868) (xy 33.668208 -30.92069) (xy 47.489364 -30.92069)
			(xy 47.489364 -30.05709) (xy 47.489854 -30.027106) (xy 47.497682 -29.96765) (xy 47.513203 -29.909725)
			(xy 47.536152 -29.854321) (xy 47.566136 -29.802387) (xy 47.602642 -29.754811) (xy 47.645047 -29.712406)
			(xy 47.692623 -29.6759) (xy 47.744557 -29.645916) (xy 47.799961 -29.622967) (xy 47.857886 -29.607446)
			(xy 47.917342 -29.599618) (xy 47.97731 -29.599618) (xy 48.036766 -29.607446) (xy 48.094691 -29.622967)
			(xy 48.150095 -29.645916) (xy 48.202029 -29.6759) (xy 48.249605 -29.712406) (xy 48.29201 -29.754811)
			(xy 48.328516 -29.802387) (xy 48.3585 -29.854321) (xy 48.381449 -29.909725) (xy 48.39697 -29.96765)
			(xy 48.404798 -30.027106) (xy 48.405288 -30.05709) (xy 48.405288 -30.92069) (xy 48.405259 -30.922468)
			(xy 58.75274 -30.922468) (xy 58.75274 -30.058868) (xy 58.75323 -30.0289) (xy 58.761053 -29.969478)
			(xy 58.776566 -29.911585) (xy 58.799502 -29.856212) (xy 58.829469 -29.804306) (xy 58.865956 -29.756756)
			(xy 58.908336 -29.714376) (xy 58.955886 -29.677889) (xy 59.007792 -29.647922) (xy 59.063165 -29.624986)
			(xy 59.121058 -29.609473) (xy 59.18048 -29.60165) (xy 59.240416 -29.60165) (xy 59.299838 -29.609473)
			(xy 59.357731 -29.624986) (xy 59.413104 -29.647922) (xy 59.46501 -29.677889) (xy 59.51256 -29.714376)
			(xy 59.55494 -29.756756) (xy 59.591427 -29.804306) (xy 59.621394 -29.856212) (xy 59.64433 -29.911585)
			(xy 59.659843 -29.969478) (xy 59.667666 -30.0289) (xy 59.668156 -30.058868) (xy 59.668156 -30.92069)
			(xy 73.489312 -30.92069) (xy 73.489312 -30.05709) (xy 73.489802 -30.027106) (xy 73.49763 -29.96765)
			(xy 73.513151 -29.909725) (xy 73.5361 -29.854321) (xy 73.566084 -29.802387) (xy 73.60259 -29.754811)
			(xy 73.644995 -29.712406) (xy 73.692571 -29.6759) (xy 73.744505 -29.645916) (xy 73.799909 -29.622967)
			(xy 73.857834 -29.607446) (xy 73.91729 -29.599618) (xy 73.977258 -29.599618) (xy 74.036714 -29.607446)
			(xy 74.094639 -29.622967) (xy 74.150043 -29.645916) (xy 74.201977 -29.6759) (xy 74.249553 -29.712406)
			(xy 74.291958 -29.754811) (xy 74.328464 -29.802387) (xy 74.358448 -29.854321) (xy 74.381397 -29.909725)
			(xy 74.396918 -29.96765) (xy 74.404746 -30.027106) (xy 74.405236 -30.05709) (xy 74.405236 -30.92069)
			(xy 74.405207 -30.922468) (xy 84.752688 -30.922468) (xy 84.752688 -30.058868) (xy 84.753178 -30.0289)
			(xy 84.761001 -29.969478) (xy 84.776514 -29.911585) (xy 84.79945 -29.856212) (xy 84.829417 -29.804306)
			(xy 84.865904 -29.756756) (xy 84.908284 -29.714376) (xy 84.955834 -29.677889) (xy 85.00774 -29.647922)
			(xy 85.063113 -29.624986) (xy 85.121006 -29.609473) (xy 85.180428 -29.60165) (xy 85.240364 -29.60165)
			(xy 85.299786 -29.609473) (xy 85.357679 -29.624986) (xy 85.413052 -29.647922) (xy 85.464958 -29.677889)
			(xy 85.512508 -29.714376) (xy 85.554888 -29.756756) (xy 85.591375 -29.804306) (xy 85.621342 -29.856212)
			(xy 85.644278 -29.911585) (xy 85.659791 -29.969478) (xy 85.667614 -30.0289) (xy 85.668104 -30.058868)
			(xy 85.668104 -30.92069) (xy 99.48926 -30.92069) (xy 99.48926 -30.05709) (xy 99.48975 -30.027106)
			(xy 99.497578 -29.96765) (xy 99.513099 -29.909725) (xy 99.536048 -29.854321) (xy 99.566032 -29.802387)
			(xy 99.602538 -29.754811) (xy 99.644943 -29.712406) (xy 99.692519 -29.6759) (xy 99.744453 -29.645916)
			(xy 99.799857 -29.622967) (xy 99.857782 -29.607446) (xy 99.917238 -29.599618) (xy 99.977206 -29.599618)
			(xy 100.036662 -29.607446) (xy 100.094587 -29.622967) (xy 100.149991 -29.645916) (xy 100.201925 -29.6759)
			(xy 100.249501 -29.712406) (xy 100.291906 -29.754811) (xy 100.328412 -29.802387) (xy 100.358396 -29.854321)
			(xy 100.381345 -29.909725) (xy 100.396866 -29.96765) (xy 100.404694 -30.027106) (xy 100.405184 -30.05709)
			(xy 100.405184 -30.92069) (xy 100.405155 -30.922468) (xy 122.852688 -30.922468) (xy 122.852688 -30.058868)
			(xy 122.853178 -30.028884) (xy 122.861006 -29.969428) (xy 122.876527 -29.911503) (xy 122.899476 -29.856099)
			(xy 122.92946 -29.804165) (xy 122.965966 -29.756589) (xy 123.008371 -29.714184) (xy 123.055947 -29.677678)
			(xy 123.107881 -29.647694) (xy 123.163285 -29.624745) (xy 123.22121 -29.609224) (xy 123.280666 -29.601396)
			(xy 123.340634 -29.601396) (xy 123.40009 -29.609224) (xy 123.458015 -29.624745) (xy 123.513419 -29.647694)
			(xy 123.565353 -29.677678) (xy 123.612929 -29.714184) (xy 123.655334 -29.756589) (xy 123.69184 -29.804165)
			(xy 123.721824 -29.856099) (xy 123.744773 -29.911503) (xy 123.760294 -29.969428) (xy 123.768122 -30.028884)
			(xy 123.768612 -30.058868) (xy 123.768612 -30.92069) (xy 137.589768 -30.92069) (xy 137.589768 -30.05709)
			(xy 137.590258 -30.027122) (xy 137.598081 -29.9677) (xy 137.613594 -29.909807) (xy 137.63653 -29.854434)
			(xy 137.666497 -29.802528) (xy 137.702984 -29.754978) (xy 137.745364 -29.712598) (xy 137.792914 -29.676111)
			(xy 137.84482 -29.646144) (xy 137.900193 -29.623208) (xy 137.958086 -29.607695) (xy 138.017508 -29.599872)
			(xy 138.077444 -29.599872) (xy 138.136866 -29.607695) (xy 138.194759 -29.623208) (xy 138.250132 -29.646144)
			(xy 138.302038 -29.676111) (xy 138.349588 -29.712598) (xy 138.391968 -29.754978) (xy 138.428455 -29.802528)
			(xy 138.458422 -29.854434) (xy 138.481358 -29.909807) (xy 138.496871 -29.9677) (xy 138.504694 -30.027122)
			(xy 138.505184 -30.05709) (xy 138.505184 -30.92069) (xy 138.505155 -30.922468) (xy 148.852636 -30.922468)
			(xy 148.852636 -30.058868) (xy 148.853126 -30.028884) (xy 148.860954 -29.969428) (xy 148.876475 -29.911503)
			(xy 148.899424 -29.856099) (xy 148.929408 -29.804165) (xy 148.965914 -29.756589) (xy 149.008319 -29.714184)
			(xy 149.055895 -29.677678) (xy 149.107829 -29.647694) (xy 149.163233 -29.624745) (xy 149.221158 -29.609224)
			(xy 149.280614 -29.601396) (xy 149.340582 -29.601396) (xy 149.400038 -29.609224) (xy 149.457963 -29.624745)
			(xy 149.513367 -29.647694) (xy 149.565301 -29.677678) (xy 149.612877 -29.714184) (xy 149.655282 -29.756589)
			(xy 149.691788 -29.804165) (xy 149.721772 -29.856099) (xy 149.744721 -29.911503) (xy 149.760242 -29.969428)
			(xy 149.76807 -30.028884) (xy 149.76856 -30.058868) (xy 149.76856 -30.92069) (xy 163.589716 -30.92069)
			(xy 163.589716 -30.05709) (xy 163.590206 -30.027122) (xy 163.598029 -29.9677) (xy 163.613542 -29.909807)
			(xy 163.636478 -29.854434) (xy 163.666445 -29.802528) (xy 163.702932 -29.754978) (xy 163.745312 -29.712598)
			(xy 163.792862 -29.676111) (xy 163.844768 -29.646144) (xy 163.900141 -29.623208) (xy 163.958034 -29.607695)
			(xy 164.017456 -29.599872) (xy 164.077392 -29.599872) (xy 164.136814 -29.607695) (xy 164.194707 -29.623208)
			(xy 164.25008 -29.646144) (xy 164.301986 -29.676111) (xy 164.349536 -29.712598) (xy 164.391916 -29.754978)
			(xy 164.428403 -29.802528) (xy 164.45837 -29.854434) (xy 164.481306 -29.909807) (xy 164.496819 -29.9677)
			(xy 164.504642 -30.027122) (xy 164.505132 -30.05709) (xy 164.505132 -30.92069) (xy 164.505103 -30.922468)
			(xy 174.852584 -30.922468) (xy 174.852584 -30.058868) (xy 174.853074 -30.028884) (xy 174.860902 -29.969428)
			(xy 174.876423 -29.911503) (xy 174.899372 -29.856099) (xy 174.929356 -29.804165) (xy 174.965862 -29.756589)
			(xy 175.008267 -29.714184) (xy 175.055843 -29.677678) (xy 175.107777 -29.647694) (xy 175.163181 -29.624745)
			(xy 175.221106 -29.609224) (xy 175.280562 -29.601396) (xy 175.34053 -29.601396) (xy 175.399986 -29.609224)
			(xy 175.457911 -29.624745) (xy 175.513315 -29.647694) (xy 175.565249 -29.677678) (xy 175.612825 -29.714184)
			(xy 175.65523 -29.756589) (xy 175.691736 -29.804165) (xy 175.72172 -29.856099) (xy 175.744669 -29.911503)
			(xy 175.76019 -29.969428) (xy 175.768018 -30.028884) (xy 175.768508 -30.058868) (xy 175.768508 -30.92069)
			(xy 189.589664 -30.92069) (xy 189.589664 -30.05709) (xy 189.590154 -30.027122) (xy 189.597977 -29.9677)
			(xy 189.61349 -29.909807) (xy 189.636426 -29.854434) (xy 189.666393 -29.802528) (xy 189.70288 -29.754978)
			(xy 189.74526 -29.712598) (xy 189.79281 -29.676111) (xy 189.844716 -29.646144) (xy 189.900089 -29.623208)
			(xy 189.957982 -29.607695) (xy 190.017404 -29.599872) (xy 190.07734 -29.599872) (xy 190.136762 -29.607695)
			(xy 190.194655 -29.623208) (xy 190.250028 -29.646144) (xy 190.301934 -29.676111) (xy 190.349484 -29.712598)
			(xy 190.391864 -29.754978) (xy 190.428351 -29.802528) (xy 190.458318 -29.854434) (xy 190.481254 -29.909807)
			(xy 190.496767 -29.9677) (xy 190.50459 -30.027122) (xy 190.50508 -30.05709) (xy 190.50508 -30.92069)
			(xy 190.505051 -30.922468) (xy 200.852532 -30.922468) (xy 200.852532 -30.058868) (xy 200.853022 -30.028884)
			(xy 200.86085 -29.969428) (xy 200.876371 -29.911503) (xy 200.89932 -29.856099) (xy 200.929304 -29.804165)
			(xy 200.96581 -29.756589) (xy 201.008215 -29.714184) (xy 201.055791 -29.677678) (xy 201.107725 -29.647694)
			(xy 201.163129 -29.624745) (xy 201.221054 -29.609224) (xy 201.28051 -29.601396) (xy 201.340478 -29.601396)
			(xy 201.399934 -29.609224) (xy 201.457859 -29.624745) (xy 201.513263 -29.647694) (xy 201.565197 -29.677678)
			(xy 201.612773 -29.714184) (xy 201.655178 -29.756589) (xy 201.691684 -29.804165) (xy 201.721668 -29.856099)
			(xy 201.744617 -29.911503) (xy 201.760138 -29.969428) (xy 201.767966 -30.028884) (xy 201.768456 -30.058868)
			(xy 201.768456 -30.92069) (xy 215.589612 -30.92069) (xy 215.589612 -30.05709) (xy 215.590102 -30.027122)
			(xy 215.597925 -29.9677) (xy 215.613438 -29.909807) (xy 215.636374 -29.854434) (xy 215.666341 -29.802528)
			(xy 215.702828 -29.754978) (xy 215.745208 -29.712598) (xy 215.792758 -29.676111) (xy 215.844664 -29.646144)
			(xy 215.900037 -29.623208) (xy 215.95793 -29.607695) (xy 216.017352 -29.599872) (xy 216.077288 -29.599872)
			(xy 216.13671 -29.607695) (xy 216.194603 -29.623208) (xy 216.249976 -29.646144) (xy 216.301882 -29.676111)
			(xy 216.349432 -29.712598) (xy 216.391812 -29.754978) (xy 216.428299 -29.802528) (xy 216.458266 -29.854434)
			(xy 216.481202 -29.909807) (xy 216.496715 -29.9677) (xy 216.504538 -30.027122) (xy 216.505028 -30.05709)
			(xy 216.505028 -30.92069) (xy 216.504999 -30.922468) (xy 238.952532 -30.922468) (xy 238.952532 -30.058868)
			(xy 238.953022 -30.028884) (xy 238.96085 -29.969428) (xy 238.976371 -29.911503) (xy 238.99932 -29.856099)
			(xy 239.029304 -29.804165) (xy 239.06581 -29.756589) (xy 239.108215 -29.714184) (xy 239.155791 -29.677678)
			(xy 239.207725 -29.647694) (xy 239.263129 -29.624745) (xy 239.321054 -29.609224) (xy 239.38051 -29.601396)
			(xy 239.440478 -29.601396) (xy 239.499934 -29.609224) (xy 239.557859 -29.624745) (xy 239.613263 -29.647694)
			(xy 239.665197 -29.677678) (xy 239.712773 -29.714184) (xy 239.755178 -29.756589) (xy 239.791684 -29.804165)
			(xy 239.821668 -29.856099) (xy 239.844617 -29.911503) (xy 239.860138 -29.969428) (xy 239.867966 -30.028884)
			(xy 239.868456 -30.058868) (xy 239.868456 -30.92069) (xy 253.689612 -30.92069) (xy 253.689612 -30.05709)
			(xy 253.690102 -30.027122) (xy 253.697925 -29.9677) (xy 253.713438 -29.909807) (xy 253.736374 -29.854434)
			(xy 253.766341 -29.802528) (xy 253.802828 -29.754978) (xy 253.845208 -29.712598) (xy 253.892758 -29.676111)
			(xy 253.944664 -29.646144) (xy 254.000037 -29.623208) (xy 254.05793 -29.607695) (xy 254.117352 -29.599872)
			(xy 254.177288 -29.599872) (xy 254.23671 -29.607695) (xy 254.294603 -29.623208) (xy 254.349976 -29.646144)
			(xy 254.401882 -29.676111) (xy 254.449432 -29.712598) (xy 254.491812 -29.754978) (xy 254.528299 -29.802528)
			(xy 254.558266 -29.854434) (xy 254.581202 -29.909807) (xy 254.596715 -29.9677) (xy 254.604538 -30.027122)
			(xy 254.605028 -30.05709) (xy 254.605028 -30.92069) (xy 254.604999 -30.922468) (xy 264.95248 -30.922468)
			(xy 264.95248 -30.058868) (xy 264.95297 -30.028884) (xy 264.960798 -29.969428) (xy 264.976319 -29.911503)
			(xy 264.999268 -29.856099) (xy 265.029252 -29.804165) (xy 265.065758 -29.756589) (xy 265.108163 -29.714184)
			(xy 265.155739 -29.677678) (xy 265.207673 -29.647694) (xy 265.263077 -29.624745) (xy 265.321002 -29.609224)
			(xy 265.380458 -29.601396) (xy 265.440426 -29.601396) (xy 265.499882 -29.609224) (xy 265.557807 -29.624745)
			(xy 265.613211 -29.647694) (xy 265.665145 -29.677678) (xy 265.712721 -29.714184) (xy 265.755126 -29.756589)
			(xy 265.791632 -29.804165) (xy 265.821616 -29.856099) (xy 265.844565 -29.911503) (xy 265.860086 -29.969428)
			(xy 265.867914 -30.028884) (xy 265.868404 -30.058868) (xy 265.868404 -30.92069) (xy 279.68956 -30.92069)
			(xy 279.68956 -30.05709) (xy 279.69005 -30.027122) (xy 279.697873 -29.9677) (xy 279.713386 -29.909807)
			(xy 279.736322 -29.854434) (xy 279.766289 -29.802528) (xy 279.802776 -29.754978) (xy 279.845156 -29.712598)
			(xy 279.892706 -29.676111) (xy 279.944612 -29.646144) (xy 279.999985 -29.623208) (xy 280.057878 -29.607695)
			(xy 280.1173 -29.599872) (xy 280.177236 -29.599872) (xy 280.236658 -29.607695) (xy 280.294551 -29.623208)
			(xy 280.349924 -29.646144) (xy 280.40183 -29.676111) (xy 280.44938 -29.712598) (xy 280.49176 -29.754978)
			(xy 280.528247 -29.802528) (xy 280.558214 -29.854434) (xy 280.58115 -29.909807) (xy 280.596663 -29.9677)
			(xy 280.604486 -30.027122) (xy 280.604976 -30.05709) (xy 280.604976 -30.92069) (xy 280.604947 -30.922468)
			(xy 290.952428 -30.922468) (xy 290.952428 -30.058868) (xy 290.952918 -30.028884) (xy 290.960746 -29.969428)
			(xy 290.976267 -29.911503) (xy 290.999216 -29.856099) (xy 291.0292 -29.804165) (xy 291.065706 -29.756589)
			(xy 291.108111 -29.714184) (xy 291.155687 -29.677678) (xy 291.207621 -29.647694) (xy 291.263025 -29.624745)
			(xy 291.32095 -29.609224) (xy 291.380406 -29.601396) (xy 291.440374 -29.601396) (xy 291.49983 -29.609224)
			(xy 291.557755 -29.624745) (xy 291.613159 -29.647694) (xy 291.665093 -29.677678) (xy 291.712669 -29.714184)
			(xy 291.755074 -29.756589) (xy 291.79158 -29.804165) (xy 291.821564 -29.856099) (xy 291.844513 -29.911503)
			(xy 291.860034 -29.969428) (xy 291.867862 -30.028884) (xy 291.868352 -30.058868) (xy 291.868352 -30.92069)
			(xy 305.689508 -30.92069) (xy 305.689508 -30.05709) (xy 305.689998 -30.027122) (xy 305.697821 -29.9677)
			(xy 305.713334 -29.909807) (xy 305.73627 -29.854434) (xy 305.766237 -29.802528) (xy 305.802724 -29.754978)
			(xy 305.845104 -29.712598) (xy 305.892654 -29.676111) (xy 305.94456 -29.646144) (xy 305.999933 -29.623208)
			(xy 306.057826 -29.607695) (xy 306.117248 -29.599872) (xy 306.177184 -29.599872) (xy 306.236606 -29.607695)
			(xy 306.294499 -29.623208) (xy 306.349872 -29.646144) (xy 306.401778 -29.676111) (xy 306.449328 -29.712598)
			(xy 306.491708 -29.754978) (xy 306.528195 -29.802528) (xy 306.558162 -29.854434) (xy 306.581098 -29.909807)
			(xy 306.596611 -29.9677) (xy 306.604434 -30.027122) (xy 306.604924 -30.05709) (xy 306.604924 -30.92069)
			(xy 306.604895 -30.922468) (xy 316.952376 -30.922468) (xy 316.952376 -30.058868) (xy 316.952866 -30.028884)
			(xy 316.960694 -29.969428) (xy 316.976215 -29.911503) (xy 316.999164 -29.856099) (xy 317.029148 -29.804165)
			(xy 317.065654 -29.756589) (xy 317.108059 -29.714184) (xy 317.155635 -29.677678) (xy 317.207569 -29.647694)
			(xy 317.262973 -29.624745) (xy 317.320898 -29.609224) (xy 317.380354 -29.601396) (xy 317.440322 -29.601396)
			(xy 317.499778 -29.609224) (xy 317.557703 -29.624745) (xy 317.613107 -29.647694) (xy 317.665041 -29.677678)
			(xy 317.712617 -29.714184) (xy 317.755022 -29.756589) (xy 317.791528 -29.804165) (xy 317.821512 -29.856099)
			(xy 317.844461 -29.911503) (xy 317.859982 -29.969428) (xy 317.86781 -30.028884) (xy 317.8683 -30.058868)
			(xy 317.8683 -30.92069) (xy 331.689456 -30.92069) (xy 331.689456 -30.05709) (xy 331.689946 -30.027122)
			(xy 331.697769 -29.9677) (xy 331.713282 -29.909807) (xy 331.736218 -29.854434) (xy 331.766185 -29.802528)
			(xy 331.802672 -29.754978) (xy 331.845052 -29.712598) (xy 331.892602 -29.676111) (xy 331.944508 -29.646144)
			(xy 331.999881 -29.623208) (xy 332.057774 -29.607695) (xy 332.117196 -29.599872) (xy 332.177132 -29.599872)
			(xy 332.236554 -29.607695) (xy 332.294447 -29.623208) (xy 332.34982 -29.646144) (xy 332.401726 -29.676111)
			(xy 332.449276 -29.712598) (xy 332.491656 -29.754978) (xy 332.528143 -29.802528) (xy 332.55811 -29.854434)
			(xy 332.581046 -29.909807) (xy 332.596559 -29.9677) (xy 332.604382 -30.027122) (xy 332.604872 -30.05709)
			(xy 332.604872 -30.92069) (xy 332.604843 -30.922468) (xy 355.052884 -30.922468) (xy 355.052884 -30.058868)
			(xy 355.053374 -30.0289) (xy 355.061197 -29.969478) (xy 355.07671 -29.911585) (xy 355.099646 -29.856212)
			(xy 355.129613 -29.804306) (xy 355.1661 -29.756756) (xy 355.20848 -29.714376) (xy 355.25603 -29.677889)
			(xy 355.307936 -29.647922) (xy 355.363309 -29.624986) (xy 355.421202 -29.609473) (xy 355.480624 -29.60165)
			(xy 355.54056 -29.60165) (xy 355.599982 -29.609473) (xy 355.657875 -29.624986) (xy 355.713248 -29.647922)
			(xy 355.765154 -29.677889) (xy 355.812704 -29.714376) (xy 355.855084 -29.756756) (xy 355.891571 -29.804306)
			(xy 355.921538 -29.856212) (xy 355.944474 -29.911585) (xy 355.959987 -29.969478) (xy 355.96781 -30.0289)
			(xy 355.9683 -30.058868) (xy 355.9683 -30.92069) (xy 369.789456 -30.92069) (xy 369.789456 -30.05709)
			(xy 369.789946 -30.027106) (xy 369.797774 -29.96765) (xy 369.813295 -29.909725) (xy 369.836244 -29.854321)
			(xy 369.866228 -29.802387) (xy 369.902734 -29.754811) (xy 369.945139 -29.712406) (xy 369.992715 -29.6759)
			(xy 370.044649 -29.645916) (xy 370.100053 -29.622967) (xy 370.157978 -29.607446) (xy 370.217434 -29.599618)
			(xy 370.277402 -29.599618) (xy 370.336858 -29.607446) (xy 370.394783 -29.622967) (xy 370.450187 -29.645916)
			(xy 370.502121 -29.6759) (xy 370.549697 -29.712406) (xy 370.592102 -29.754811) (xy 370.628608 -29.802387)
			(xy 370.658592 -29.854321) (xy 370.681541 -29.909725) (xy 370.697062 -29.96765) (xy 370.70489 -30.027106)
			(xy 370.70538 -30.05709) (xy 370.70538 -30.92069) (xy 370.705351 -30.922468) (xy 381.052832 -30.922468)
			(xy 381.052832 -30.058868) (xy 381.053322 -30.0289) (xy 381.061145 -29.969478) (xy 381.076658 -29.911585)
			(xy 381.099594 -29.856212) (xy 381.129561 -29.804306) (xy 381.166048 -29.756756) (xy 381.208428 -29.714376)
			(xy 381.255978 -29.677889) (xy 381.307884 -29.647922) (xy 381.363257 -29.624986) (xy 381.42115 -29.609473)
			(xy 381.480572 -29.60165) (xy 381.540508 -29.60165) (xy 381.59993 -29.609473) (xy 381.657823 -29.624986)
			(xy 381.713196 -29.647922) (xy 381.765102 -29.677889) (xy 381.812652 -29.714376) (xy 381.855032 -29.756756)
			(xy 381.891519 -29.804306) (xy 381.921486 -29.856212) (xy 381.944422 -29.911585) (xy 381.959935 -29.969478)
			(xy 381.967758 -30.0289) (xy 381.968248 -30.058868) (xy 381.968248 -30.92069) (xy 395.789404 -30.92069)
			(xy 395.789404 -30.05709) (xy 395.789894 -30.027106) (xy 395.797722 -29.96765) (xy 395.813243 -29.909725)
			(xy 395.836192 -29.854321) (xy 395.866176 -29.802387) (xy 395.902682 -29.754811) (xy 395.945087 -29.712406)
			(xy 395.992663 -29.6759) (xy 396.044597 -29.645916) (xy 396.100001 -29.622967) (xy 396.157926 -29.607446)
			(xy 396.217382 -29.599618) (xy 396.27735 -29.599618) (xy 396.336806 -29.607446) (xy 396.394731 -29.622967)
			(xy 396.450135 -29.645916) (xy 396.502069 -29.6759) (xy 396.549645 -29.712406) (xy 396.59205 -29.754811)
			(xy 396.628556 -29.802387) (xy 396.65854 -29.854321) (xy 396.681489 -29.909725) (xy 396.69701 -29.96765)
			(xy 396.704838 -30.027106) (xy 396.705328 -30.05709) (xy 396.705328 -30.92069) (xy 396.705299 -30.922468)
			(xy 407.05278 -30.922468) (xy 407.05278 -30.058868) (xy 407.05327 -30.0289) (xy 407.061093 -29.969478)
			(xy 407.076606 -29.911585) (xy 407.099542 -29.856212) (xy 407.129509 -29.804306) (xy 407.165996 -29.756756)
			(xy 407.208376 -29.714376) (xy 407.255926 -29.677889) (xy 407.307832 -29.647922) (xy 407.363205 -29.624986)
			(xy 407.421098 -29.609473) (xy 407.48052 -29.60165) (xy 407.540456 -29.60165) (xy 407.599878 -29.609473)
			(xy 407.657771 -29.624986) (xy 407.713144 -29.647922) (xy 407.76505 -29.677889) (xy 407.8126 -29.714376)
			(xy 407.85498 -29.756756) (xy 407.891467 -29.804306) (xy 407.921434 -29.856212) (xy 407.94437 -29.911585)
			(xy 407.959883 -29.969478) (xy 407.967706 -30.0289) (xy 407.968196 -30.058868) (xy 407.968196 -30.92069)
			(xy 421.789352 -30.92069) (xy 421.789352 -30.05709) (xy 421.789842 -30.027106) (xy 421.79767 -29.96765)
			(xy 421.813191 -29.909725) (xy 421.83614 -29.854321) (xy 421.866124 -29.802387) (xy 421.90263 -29.754811)
			(xy 421.945035 -29.712406) (xy 421.992611 -29.6759) (xy 422.044545 -29.645916) (xy 422.099949 -29.622967)
			(xy 422.157874 -29.607446) (xy 422.21733 -29.599618) (xy 422.277298 -29.599618) (xy 422.336754 -29.607446)
			(xy 422.394679 -29.622967) (xy 422.450083 -29.645916) (xy 422.502017 -29.6759) (xy 422.549593 -29.712406)
			(xy 422.591998 -29.754811) (xy 422.628504 -29.802387) (xy 422.658488 -29.854321) (xy 422.681437 -29.909725)
			(xy 422.696958 -29.96765) (xy 422.704786 -30.027106) (xy 422.705276 -30.05709) (xy 422.705276 -30.92069)
			(xy 422.705247 -30.922468) (xy 433.052728 -30.922468) (xy 433.052728 -30.058868) (xy 433.053218 -30.0289)
			(xy 433.061041 -29.969478) (xy 433.076554 -29.911585) (xy 433.09949 -29.856212) (xy 433.129457 -29.804306)
			(xy 433.165944 -29.756756) (xy 433.208324 -29.714376) (xy 433.255874 -29.677889) (xy 433.30778 -29.647922)
			(xy 433.363153 -29.624986) (xy 433.421046 -29.609473) (xy 433.480468 -29.60165) (xy 433.540404 -29.60165)
			(xy 433.599826 -29.609473) (xy 433.657719 -29.624986) (xy 433.713092 -29.647922) (xy 433.764998 -29.677889)
			(xy 433.812548 -29.714376) (xy 433.854928 -29.756756) (xy 433.891415 -29.804306) (xy 433.921382 -29.856212)
			(xy 433.944318 -29.911585) (xy 433.959831 -29.969478) (xy 433.967654 -30.0289) (xy 433.968144 -30.058868)
			(xy 433.968144 -30.92069) (xy 447.7893 -30.92069) (xy 447.7893 -30.05709) (xy 447.78979 -30.027106)
			(xy 447.797618 -29.96765) (xy 447.813139 -29.909725) (xy 447.836088 -29.854321) (xy 447.866072 -29.802387)
			(xy 447.902578 -29.754811) (xy 447.944983 -29.712406) (xy 447.992559 -29.6759) (xy 448.044493 -29.645916)
			(xy 448.099897 -29.622967) (xy 448.157822 -29.607446) (xy 448.217278 -29.599618) (xy 448.277246 -29.599618)
			(xy 448.336702 -29.607446) (xy 448.394627 -29.622967) (xy 448.450031 -29.645916) (xy 448.501965 -29.6759)
			(xy 448.549541 -29.712406) (xy 448.591946 -29.754811) (xy 448.628452 -29.802387) (xy 448.658436 -29.854321)
			(xy 448.681385 -29.909725) (xy 448.696906 -29.96765) (xy 448.704734 -30.027106) (xy 448.705224 -30.05709)
			(xy 448.705224 -30.745738) (xy 457.614517 -30.745738) (xy 457.614517 -30.616598) (xy 457.622467 -30.487703)
			(xy 457.638337 -30.359543) (xy 457.662066 -30.232602) (xy 457.693565 -30.107363) (xy 457.732714 -29.9843)
			(xy 457.779365 -29.863881) (xy 457.83334 -29.746562) (xy 457.894435 -29.632788) (xy 457.962418 -29.522991)
			(xy 458.037032 -29.417588) (xy 458.117993 -29.316978) (xy 458.204993 -29.221543) (xy 458.297704 -29.131644)
			(xy 458.395774 -29.047623) (xy 458.498829 -28.969799) (xy 458.60648 -28.898467) (xy 458.718319 -28.833897)
			(xy 458.83392 -28.776335) (xy 458.952845 -28.725998) (xy 459.074644 -28.683078) (xy 459.198854 -28.647737)
			(xy 459.325003 -28.62011) (xy 459.452615 -28.600301) (xy 459.581204 -28.588385) (xy 459.710282 -28.584409)
			(xy 459.83936 -28.588385) (xy 459.967949 -28.600301) (xy 460.095561 -28.62011) (xy 460.22171 -28.647737)
			(xy 460.34592 -28.683078) (xy 460.467719 -28.725998) (xy 460.586644 -28.776335) (xy 460.702245 -28.833897)
			(xy 460.814084 -28.898467) (xy 460.921735 -28.969799) (xy 461.02479 -29.047623) (xy 461.12286 -29.131644)
			(xy 461.215571 -29.221543) (xy 461.302571 -29.316978) (xy 461.383532 -29.417588) (xy 461.458146 -29.522991)
			(xy 461.526129 -29.632788) (xy 461.587224 -29.746562) (xy 461.641199 -29.863881) (xy 461.68785 -29.9843)
			(xy 461.726999 -30.107363) (xy 461.758498 -30.232602) (xy 461.782227 -30.359543) (xy 461.798097 -30.487703)
			(xy 461.806047 -30.616598) (xy 461.806544 -30.681168) (xy 461.806047 -30.745738) (xy 461.798097 -30.874633)
			(xy 461.782227 -31.002793) (xy 461.758498 -31.129734) (xy 461.726999 -31.254973) (xy 461.68785 -31.378036)
			(xy 461.641199 -31.498455) (xy 461.587224 -31.615774) (xy 461.526129 -31.729548) (xy 461.458146 -31.839345)
			(xy 461.383532 -31.944748) (xy 461.302571 -32.045358) (xy 461.215571 -32.140793) (xy 461.12286 -32.230692)
			(xy 461.02479 -32.314713) (xy 460.921735 -32.392537) (xy 460.814084 -32.463869) (xy 460.702245 -32.528439)
			(xy 460.586644 -32.586001) (xy 460.467719 -32.636338) (xy 460.34592 -32.679258) (xy 460.22171 -32.714599)
			(xy 460.095561 -32.742226) (xy 459.967949 -32.762035) (xy 459.83936 -32.773951) (xy 459.710282 -32.777928)
			(xy 459.581204 -32.773951) (xy 459.452615 -32.762035) (xy 459.325003 -32.742226) (xy 459.198854 -32.714599)
			(xy 459.074644 -32.679258) (xy 458.952845 -32.636338) (xy 458.83392 -32.586001) (xy 458.718319 -32.528439)
			(xy 458.60648 -32.463869) (xy 458.498829 -32.392537) (xy 458.395774 -32.314713) (xy 458.297704 -32.230692)
			(xy 458.204993 -32.140793) (xy 458.117993 -32.045358) (xy 458.037032 -31.944748) (xy 457.962418 -31.839345)
			(xy 457.894435 -31.729548) (xy 457.83334 -31.615774) (xy 457.779365 -31.498455) (xy 457.732714 -31.378036)
			(xy 457.693565 -31.254973) (xy 457.662066 -31.129734) (xy 457.638337 -31.002793) (xy 457.622467 -30.874633)
			(xy 457.614517 -30.745738) (xy 448.705224 -30.745738) (xy 448.705224 -30.92069) (xy 448.704734 -30.950674)
			(xy 448.696906 -31.01013) (xy 448.681385 -31.068055) (xy 448.658436 -31.123459) (xy 448.628452 -31.175393)
			(xy 448.591946 -31.222969) (xy 448.549541 -31.265374) (xy 448.501965 -31.30188) (xy 448.450031 -31.331864)
			(xy 448.394627 -31.354813) (xy 448.336702 -31.370334) (xy 448.277246 -31.378162) (xy 448.217278 -31.378162)
			(xy 448.157822 -31.370334) (xy 448.099897 -31.354813) (xy 448.044493 -31.331864) (xy 447.992559 -31.30188)
			(xy 447.944983 -31.265374) (xy 447.902578 -31.222969) (xy 447.866072 -31.175393) (xy 447.836088 -31.123459)
			(xy 447.813139 -31.068055) (xy 447.797618 -31.01013) (xy 447.78979 -30.950674) (xy 447.7893 -30.92069)
			(xy 433.968144 -30.92069) (xy 433.968144 -30.922468) (xy 433.967654 -30.952436) (xy 433.959831 -31.011858)
			(xy 433.944318 -31.069751) (xy 433.921382 -31.125124) (xy 433.891415 -31.17703) (xy 433.854928 -31.22458)
			(xy 433.812548 -31.26696) (xy 433.764998 -31.303447) (xy 433.713092 -31.333414) (xy 433.657719 -31.35635)
			(xy 433.599826 -31.371863) (xy 433.540404 -31.379686) (xy 433.480468 -31.379686) (xy 433.421046 -31.371863)
			(xy 433.363153 -31.35635) (xy 433.30778 -31.333414) (xy 433.255874 -31.303447) (xy 433.208324 -31.26696)
			(xy 433.165944 -31.22458) (xy 433.129457 -31.17703) (xy 433.09949 -31.125124) (xy 433.076554 -31.069751)
			(xy 433.061041 -31.011858) (xy 433.053218 -30.952436) (xy 433.052728 -30.922468) (xy 422.705247 -30.922468)
			(xy 422.704786 -30.950674) (xy 422.696958 -31.01013) (xy 422.681437 -31.068055) (xy 422.658488 -31.123459)
			(xy 422.628504 -31.175393) (xy 422.591998 -31.222969) (xy 422.549593 -31.265374) (xy 422.502017 -31.30188)
			(xy 422.450083 -31.331864) (xy 422.394679 -31.354813) (xy 422.336754 -31.370334) (xy 422.277298 -31.378162)
			(xy 422.21733 -31.378162) (xy 422.157874 -31.370334) (xy 422.099949 -31.354813) (xy 422.044545 -31.331864)
			(xy 421.992611 -31.30188) (xy 421.945035 -31.265374) (xy 421.90263 -31.222969) (xy 421.866124 -31.175393)
			(xy 421.83614 -31.123459) (xy 421.813191 -31.068055) (xy 421.79767 -31.01013) (xy 421.789842 -30.950674)
			(xy 421.789352 -30.92069) (xy 407.968196 -30.92069) (xy 407.968196 -30.922468) (xy 407.967706 -30.952436)
			(xy 407.959883 -31.011858) (xy 407.94437 -31.069751) (xy 407.921434 -31.125124) (xy 407.891467 -31.17703)
			(xy 407.85498 -31.22458) (xy 407.8126 -31.26696) (xy 407.76505 -31.303447) (xy 407.713144 -31.333414)
			(xy 407.657771 -31.35635) (xy 407.599878 -31.371863) (xy 407.540456 -31.379686) (xy 407.48052 -31.379686)
			(xy 407.421098 -31.371863) (xy 407.363205 -31.35635) (xy 407.307832 -31.333414) (xy 407.255926 -31.303447)
			(xy 407.208376 -31.26696) (xy 407.165996 -31.22458) (xy 407.129509 -31.17703) (xy 407.099542 -31.125124)
			(xy 407.076606 -31.069751) (xy 407.061093 -31.011858) (xy 407.05327 -30.952436) (xy 407.05278 -30.922468)
			(xy 396.705299 -30.922468) (xy 396.704838 -30.950674) (xy 396.69701 -31.01013) (xy 396.681489 -31.068055)
			(xy 396.65854 -31.123459) (xy 396.628556 -31.175393) (xy 396.59205 -31.222969) (xy 396.549645 -31.265374)
			(xy 396.502069 -31.30188) (xy 396.450135 -31.331864) (xy 396.394731 -31.354813) (xy 396.336806 -31.370334)
			(xy 396.27735 -31.378162) (xy 396.217382 -31.378162) (xy 396.157926 -31.370334) (xy 396.100001 -31.354813)
			(xy 396.044597 -31.331864) (xy 395.992663 -31.30188) (xy 395.945087 -31.265374) (xy 395.902682 -31.222969)
			(xy 395.866176 -31.175393) (xy 395.836192 -31.123459) (xy 395.813243 -31.068055) (xy 395.797722 -31.01013)
			(xy 395.789894 -30.950674) (xy 395.789404 -30.92069) (xy 381.968248 -30.92069) (xy 381.968248 -30.922468)
			(xy 381.967758 -30.952436) (xy 381.959935 -31.011858) (xy 381.944422 -31.069751) (xy 381.921486 -31.125124)
			(xy 381.891519 -31.17703) (xy 381.855032 -31.22458) (xy 381.812652 -31.26696) (xy 381.765102 -31.303447)
			(xy 381.713196 -31.333414) (xy 381.657823 -31.35635) (xy 381.59993 -31.371863) (xy 381.540508 -31.379686)
			(xy 381.480572 -31.379686) (xy 381.42115 -31.371863) (xy 381.363257 -31.35635) (xy 381.307884 -31.333414)
			(xy 381.255978 -31.303447) (xy 381.208428 -31.26696) (xy 381.166048 -31.22458) (xy 381.129561 -31.17703)
			(xy 381.099594 -31.125124) (xy 381.076658 -31.069751) (xy 381.061145 -31.011858) (xy 381.053322 -30.952436)
			(xy 381.052832 -30.922468) (xy 370.705351 -30.922468) (xy 370.70489 -30.950674) (xy 370.697062 -31.01013)
			(xy 370.681541 -31.068055) (xy 370.658592 -31.123459) (xy 370.628608 -31.175393) (xy 370.592102 -31.222969)
			(xy 370.549697 -31.265374) (xy 370.502121 -31.30188) (xy 370.450187 -31.331864) (xy 370.394783 -31.354813)
			(xy 370.336858 -31.370334) (xy 370.277402 -31.378162) (xy 370.217434 -31.378162) (xy 370.157978 -31.370334)
			(xy 370.100053 -31.354813) (xy 370.044649 -31.331864) (xy 369.992715 -31.30188) (xy 369.945139 -31.265374)
			(xy 369.902734 -31.222969) (xy 369.866228 -31.175393) (xy 369.836244 -31.123459) (xy 369.813295 -31.068055)
			(xy 369.797774 -31.01013) (xy 369.789946 -30.950674) (xy 369.789456 -30.92069) (xy 355.9683 -30.92069)
			(xy 355.9683 -30.922468) (xy 355.96781 -30.952436) (xy 355.959987 -31.011858) (xy 355.944474 -31.069751)
			(xy 355.921538 -31.125124) (xy 355.891571 -31.17703) (xy 355.855084 -31.22458) (xy 355.812704 -31.26696)
			(xy 355.765154 -31.303447) (xy 355.713248 -31.333414) (xy 355.657875 -31.35635) (xy 355.599982 -31.371863)
			(xy 355.54056 -31.379686) (xy 355.480624 -31.379686) (xy 355.421202 -31.371863) (xy 355.363309 -31.35635)
			(xy 355.307936 -31.333414) (xy 355.25603 -31.303447) (xy 355.20848 -31.26696) (xy 355.1661 -31.22458)
			(xy 355.129613 -31.17703) (xy 355.099646 -31.125124) (xy 355.07671 -31.069751) (xy 355.061197 -31.011858)
			(xy 355.053374 -30.952436) (xy 355.052884 -30.922468) (xy 332.604843 -30.922468) (xy 332.604382 -30.950658)
			(xy 332.596559 -31.01008) (xy 332.581046 -31.067973) (xy 332.55811 -31.123346) (xy 332.528143 -31.175252)
			(xy 332.491656 -31.222802) (xy 332.449276 -31.265182) (xy 332.401726 -31.301669) (xy 332.34982 -31.331636)
			(xy 332.294447 -31.354572) (xy 332.236554 -31.370085) (xy 332.177132 -31.377908) (xy 332.117196 -31.377908)
			(xy 332.057774 -31.370085) (xy 331.999881 -31.354572) (xy 331.944508 -31.331636) (xy 331.892602 -31.301669)
			(xy 331.845052 -31.265182) (xy 331.802672 -31.222802) (xy 331.766185 -31.175252) (xy 331.736218 -31.123346)
			(xy 331.713282 -31.067973) (xy 331.697769 -31.01008) (xy 331.689946 -30.950658) (xy 331.689456 -30.92069)
			(xy 317.8683 -30.92069) (xy 317.8683 -30.922468) (xy 317.86781 -30.952452) (xy 317.859982 -31.011908)
			(xy 317.844461 -31.069833) (xy 317.821512 -31.125237) (xy 317.791528 -31.177171) (xy 317.755022 -31.224747)
			(xy 317.712617 -31.267152) (xy 317.665041 -31.303658) (xy 317.613107 -31.333642) (xy 317.557703 -31.356591)
			(xy 317.499778 -31.372112) (xy 317.440322 -31.37994) (xy 317.380354 -31.37994) (xy 317.320898 -31.372112)
			(xy 317.262973 -31.356591) (xy 317.207569 -31.333642) (xy 317.155635 -31.303658) (xy 317.108059 -31.267152)
			(xy 317.065654 -31.224747) (xy 317.029148 -31.177171) (xy 316.999164 -31.125237) (xy 316.976215 -31.069833)
			(xy 316.960694 -31.011908) (xy 316.952866 -30.952452) (xy 316.952376 -30.922468) (xy 306.604895 -30.922468)
			(xy 306.604434 -30.950658) (xy 306.596611 -31.01008) (xy 306.581098 -31.067973) (xy 306.558162 -31.123346)
			(xy 306.528195 -31.175252) (xy 306.491708 -31.222802) (xy 306.449328 -31.265182) (xy 306.401778 -31.301669)
			(xy 306.349872 -31.331636) (xy 306.294499 -31.354572) (xy 306.236606 -31.370085) (xy 306.177184 -31.377908)
			(xy 306.117248 -31.377908) (xy 306.057826 -31.370085) (xy 305.999933 -31.354572) (xy 305.94456 -31.331636)
			(xy 305.892654 -31.301669) (xy 305.845104 -31.265182) (xy 305.802724 -31.222802) (xy 305.766237 -31.175252)
			(xy 305.73627 -31.123346) (xy 305.713334 -31.067973) (xy 305.697821 -31.01008) (xy 305.689998 -30.950658)
			(xy 305.689508 -30.92069) (xy 291.868352 -30.92069) (xy 291.868352 -30.922468) (xy 291.867862 -30.952452)
			(xy 291.860034 -31.011908) (xy 291.844513 -31.069833) (xy 291.821564 -31.125237) (xy 291.79158 -31.177171)
			(xy 291.755074 -31.224747) (xy 291.712669 -31.267152) (xy 291.665093 -31.303658) (xy 291.613159 -31.333642)
			(xy 291.557755 -31.356591) (xy 291.49983 -31.372112) (xy 291.440374 -31.37994) (xy 291.380406 -31.37994)
			(xy 291.32095 -31.372112) (xy 291.263025 -31.356591) (xy 291.207621 -31.333642) (xy 291.155687 -31.303658)
			(xy 291.108111 -31.267152) (xy 291.065706 -31.224747) (xy 291.0292 -31.177171) (xy 290.999216 -31.125237)
			(xy 290.976267 -31.069833) (xy 290.960746 -31.011908) (xy 290.952918 -30.952452) (xy 290.952428 -30.922468)
			(xy 280.604947 -30.922468) (xy 280.604486 -30.950658) (xy 280.596663 -31.01008) (xy 280.58115 -31.067973)
			(xy 280.558214 -31.123346) (xy 280.528247 -31.175252) (xy 280.49176 -31.222802) (xy 280.44938 -31.265182)
			(xy 280.40183 -31.301669) (xy 280.349924 -31.331636) (xy 280.294551 -31.354572) (xy 280.236658 -31.370085)
			(xy 280.177236 -31.377908) (xy 280.1173 -31.377908) (xy 280.057878 -31.370085) (xy 279.999985 -31.354572)
			(xy 279.944612 -31.331636) (xy 279.892706 -31.301669) (xy 279.845156 -31.265182) (xy 279.802776 -31.222802)
			(xy 279.766289 -31.175252) (xy 279.736322 -31.123346) (xy 279.713386 -31.067973) (xy 279.697873 -31.01008)
			(xy 279.69005 -30.950658) (xy 279.68956 -30.92069) (xy 265.868404 -30.92069) (xy 265.868404 -30.922468)
			(xy 265.867914 -30.952452) (xy 265.860086 -31.011908) (xy 265.844565 -31.069833) (xy 265.821616 -31.125237)
			(xy 265.791632 -31.177171) (xy 265.755126 -31.224747) (xy 265.712721 -31.267152) (xy 265.665145 -31.303658)
			(xy 265.613211 -31.333642) (xy 265.557807 -31.356591) (xy 265.499882 -31.372112) (xy 265.440426 -31.37994)
			(xy 265.380458 -31.37994) (xy 265.321002 -31.372112) (xy 265.263077 -31.356591) (xy 265.207673 -31.333642)
			(xy 265.155739 -31.303658) (xy 265.108163 -31.267152) (xy 265.065758 -31.224747) (xy 265.029252 -31.177171)
			(xy 264.999268 -31.125237) (xy 264.976319 -31.069833) (xy 264.960798 -31.011908) (xy 264.95297 -30.952452)
			(xy 264.95248 -30.922468) (xy 254.604999 -30.922468) (xy 254.604538 -30.950658) (xy 254.596715 -31.01008)
			(xy 254.581202 -31.067973) (xy 254.558266 -31.123346) (xy 254.528299 -31.175252) (xy 254.491812 -31.222802)
			(xy 254.449432 -31.265182) (xy 254.401882 -31.301669) (xy 254.349976 -31.331636) (xy 254.294603 -31.354572)
			(xy 254.23671 -31.370085) (xy 254.177288 -31.377908) (xy 254.117352 -31.377908) (xy 254.05793 -31.370085)
			(xy 254.000037 -31.354572) (xy 253.944664 -31.331636) (xy 253.892758 -31.301669) (xy 253.845208 -31.265182)
			(xy 253.802828 -31.222802) (xy 253.766341 -31.175252) (xy 253.736374 -31.123346) (xy 253.713438 -31.067973)
			(xy 253.697925 -31.01008) (xy 253.690102 -30.950658) (xy 253.689612 -30.92069) (xy 239.868456 -30.92069)
			(xy 239.868456 -30.922468) (xy 239.867966 -30.952452) (xy 239.860138 -31.011908) (xy 239.844617 -31.069833)
			(xy 239.821668 -31.125237) (xy 239.791684 -31.177171) (xy 239.755178 -31.224747) (xy 239.712773 -31.267152)
			(xy 239.665197 -31.303658) (xy 239.613263 -31.333642) (xy 239.557859 -31.356591) (xy 239.499934 -31.372112)
			(xy 239.440478 -31.37994) (xy 239.38051 -31.37994) (xy 239.321054 -31.372112) (xy 239.263129 -31.356591)
			(xy 239.207725 -31.333642) (xy 239.155791 -31.303658) (xy 239.108215 -31.267152) (xy 239.06581 -31.224747)
			(xy 239.029304 -31.177171) (xy 238.99932 -31.125237) (xy 238.976371 -31.069833) (xy 238.96085 -31.011908)
			(xy 238.953022 -30.952452) (xy 238.952532 -30.922468) (xy 216.504999 -30.922468) (xy 216.504538 -30.950658)
			(xy 216.496715 -31.01008) (xy 216.481202 -31.067973) (xy 216.458266 -31.123346) (xy 216.428299 -31.175252)
			(xy 216.391812 -31.222802) (xy 216.349432 -31.265182) (xy 216.301882 -31.301669) (xy 216.249976 -31.331636)
			(xy 216.194603 -31.354572) (xy 216.13671 -31.370085) (xy 216.077288 -31.377908) (xy 216.017352 -31.377908)
			(xy 215.95793 -31.370085) (xy 215.900037 -31.354572) (xy 215.844664 -31.331636) (xy 215.792758 -31.301669)
			(xy 215.745208 -31.265182) (xy 215.702828 -31.222802) (xy 215.666341 -31.175252) (xy 215.636374 -31.123346)
			(xy 215.613438 -31.067973) (xy 215.597925 -31.01008) (xy 215.590102 -30.950658) (xy 215.589612 -30.92069)
			(xy 201.768456 -30.92069) (xy 201.768456 -30.922468) (xy 201.767966 -30.952452) (xy 201.760138 -31.011908)
			(xy 201.744617 -31.069833) (xy 201.721668 -31.125237) (xy 201.691684 -31.177171) (xy 201.655178 -31.224747)
			(xy 201.612773 -31.267152) (xy 201.565197 -31.303658) (xy 201.513263 -31.333642) (xy 201.457859 -31.356591)
			(xy 201.399934 -31.372112) (xy 201.340478 -31.37994) (xy 201.28051 -31.37994) (xy 201.221054 -31.372112)
			(xy 201.163129 -31.356591) (xy 201.107725 -31.333642) (xy 201.055791 -31.303658) (xy 201.008215 -31.267152)
			(xy 200.96581 -31.224747) (xy 200.929304 -31.177171) (xy 200.89932 -31.125237) (xy 200.876371 -31.069833)
			(xy 200.86085 -31.011908) (xy 200.853022 -30.952452) (xy 200.852532 -30.922468) (xy 190.505051 -30.922468)
			(xy 190.50459 -30.950658) (xy 190.496767 -31.01008) (xy 190.481254 -31.067973) (xy 190.458318 -31.123346)
			(xy 190.428351 -31.175252) (xy 190.391864 -31.222802) (xy 190.349484 -31.265182) (xy 190.301934 -31.301669)
			(xy 190.250028 -31.331636) (xy 190.194655 -31.354572) (xy 190.136762 -31.370085) (xy 190.07734 -31.377908)
			(xy 190.017404 -31.377908) (xy 189.957982 -31.370085) (xy 189.900089 -31.354572) (xy 189.844716 -31.331636)
			(xy 189.79281 -31.301669) (xy 189.74526 -31.265182) (xy 189.70288 -31.222802) (xy 189.666393 -31.175252)
			(xy 189.636426 -31.123346) (xy 189.61349 -31.067973) (xy 189.597977 -31.01008) (xy 189.590154 -30.950658)
			(xy 189.589664 -30.92069) (xy 175.768508 -30.92069) (xy 175.768508 -30.922468) (xy 175.768018 -30.952452)
			(xy 175.76019 -31.011908) (xy 175.744669 -31.069833) (xy 175.72172 -31.125237) (xy 175.691736 -31.177171)
			(xy 175.65523 -31.224747) (xy 175.612825 -31.267152) (xy 175.565249 -31.303658) (xy 175.513315 -31.333642)
			(xy 175.457911 -31.356591) (xy 175.399986 -31.372112) (xy 175.34053 -31.37994) (xy 175.280562 -31.37994)
			(xy 175.221106 -31.372112) (xy 175.163181 -31.356591) (xy 175.107777 -31.333642) (xy 175.055843 -31.303658)
			(xy 175.008267 -31.267152) (xy 174.965862 -31.224747) (xy 174.929356 -31.177171) (xy 174.899372 -31.125237)
			(xy 174.876423 -31.069833) (xy 174.860902 -31.011908) (xy 174.853074 -30.952452) (xy 174.852584 -30.922468)
			(xy 164.505103 -30.922468) (xy 164.504642 -30.950658) (xy 164.496819 -31.01008) (xy 164.481306 -31.067973)
			(xy 164.45837 -31.123346) (xy 164.428403 -31.175252) (xy 164.391916 -31.222802) (xy 164.349536 -31.265182)
			(xy 164.301986 -31.301669) (xy 164.25008 -31.331636) (xy 164.194707 -31.354572) (xy 164.136814 -31.370085)
			(xy 164.077392 -31.377908) (xy 164.017456 -31.377908) (xy 163.958034 -31.370085) (xy 163.900141 -31.354572)
			(xy 163.844768 -31.331636) (xy 163.792862 -31.301669) (xy 163.745312 -31.265182) (xy 163.702932 -31.222802)
			(xy 163.666445 -31.175252) (xy 163.636478 -31.123346) (xy 163.613542 -31.067973) (xy 163.598029 -31.01008)
			(xy 163.590206 -30.950658) (xy 163.589716 -30.92069) (xy 149.76856 -30.92069) (xy 149.76856 -30.922468)
			(xy 149.76807 -30.952452) (xy 149.760242 -31.011908) (xy 149.744721 -31.069833) (xy 149.721772 -31.125237)
			(xy 149.691788 -31.177171) (xy 149.655282 -31.224747) (xy 149.612877 -31.267152) (xy 149.565301 -31.303658)
			(xy 149.513367 -31.333642) (xy 149.457963 -31.356591) (xy 149.400038 -31.372112) (xy 149.340582 -31.37994)
			(xy 149.280614 -31.37994) (xy 149.221158 -31.372112) (xy 149.163233 -31.356591) (xy 149.107829 -31.333642)
			(xy 149.055895 -31.303658) (xy 149.008319 -31.267152) (xy 148.965914 -31.224747) (xy 148.929408 -31.177171)
			(xy 148.899424 -31.125237) (xy 148.876475 -31.069833) (xy 148.860954 -31.011908) (xy 148.853126 -30.952452)
			(xy 148.852636 -30.922468) (xy 138.505155 -30.922468) (xy 138.504694 -30.950658) (xy 138.496871 -31.01008)
			(xy 138.481358 -31.067973) (xy 138.458422 -31.123346) (xy 138.428455 -31.175252) (xy 138.391968 -31.222802)
			(xy 138.349588 -31.265182) (xy 138.302038 -31.301669) (xy 138.250132 -31.331636) (xy 138.194759 -31.354572)
			(xy 138.136866 -31.370085) (xy 138.077444 -31.377908) (xy 138.017508 -31.377908) (xy 137.958086 -31.370085)
			(xy 137.900193 -31.354572) (xy 137.84482 -31.331636) (xy 137.792914 -31.301669) (xy 137.745364 -31.265182)
			(xy 137.702984 -31.222802) (xy 137.666497 -31.175252) (xy 137.63653 -31.123346) (xy 137.613594 -31.067973)
			(xy 137.598081 -31.01008) (xy 137.590258 -30.950658) (xy 137.589768 -30.92069) (xy 123.768612 -30.92069)
			(xy 123.768612 -30.922468) (xy 123.768122 -30.952452) (xy 123.760294 -31.011908) (xy 123.744773 -31.069833)
			(xy 123.721824 -31.125237) (xy 123.69184 -31.177171) (xy 123.655334 -31.224747) (xy 123.612929 -31.267152)
			(xy 123.565353 -31.303658) (xy 123.513419 -31.333642) (xy 123.458015 -31.356591) (xy 123.40009 -31.372112)
			(xy 123.340634 -31.37994) (xy 123.280666 -31.37994) (xy 123.22121 -31.372112) (xy 123.163285 -31.356591)
			(xy 123.107881 -31.333642) (xy 123.055947 -31.303658) (xy 123.008371 -31.267152) (xy 122.965966 -31.224747)
			(xy 122.92946 -31.177171) (xy 122.899476 -31.125237) (xy 122.876527 -31.069833) (xy 122.861006 -31.011908)
			(xy 122.853178 -30.952452) (xy 122.852688 -30.922468) (xy 100.405155 -30.922468) (xy 100.404694 -30.950674)
			(xy 100.396866 -31.01013) (xy 100.381345 -31.068055) (xy 100.358396 -31.123459) (xy 100.328412 -31.175393)
			(xy 100.291906 -31.222969) (xy 100.249501 -31.265374) (xy 100.201925 -31.30188) (xy 100.149991 -31.331864)
			(xy 100.094587 -31.354813) (xy 100.036662 -31.370334) (xy 99.977206 -31.378162) (xy 99.917238 -31.378162)
			(xy 99.857782 -31.370334) (xy 99.799857 -31.354813) (xy 99.744453 -31.331864) (xy 99.692519 -31.30188)
			(xy 99.644943 -31.265374) (xy 99.602538 -31.222969) (xy 99.566032 -31.175393) (xy 99.536048 -31.123459)
			(xy 99.513099 -31.068055) (xy 99.497578 -31.01013) (xy 99.48975 -30.950674) (xy 99.48926 -30.92069)
			(xy 85.668104 -30.92069) (xy 85.668104 -30.922468) (xy 85.667614 -30.952436) (xy 85.659791 -31.011858)
			(xy 85.644278 -31.069751) (xy 85.621342 -31.125124) (xy 85.591375 -31.17703) (xy 85.554888 -31.22458)
			(xy 85.512508 -31.26696) (xy 85.464958 -31.303447) (xy 85.413052 -31.333414) (xy 85.357679 -31.35635)
			(xy 85.299786 -31.371863) (xy 85.240364 -31.379686) (xy 85.180428 -31.379686) (xy 85.121006 -31.371863)
			(xy 85.063113 -31.35635) (xy 85.00774 -31.333414) (xy 84.955834 -31.303447) (xy 84.908284 -31.26696)
			(xy 84.865904 -31.22458) (xy 84.829417 -31.17703) (xy 84.79945 -31.125124) (xy 84.776514 -31.069751)
			(xy 84.761001 -31.011858) (xy 84.753178 -30.952436) (xy 84.752688 -30.922468) (xy 74.405207 -30.922468)
			(xy 74.404746 -30.950674) (xy 74.396918 -31.01013) (xy 74.381397 -31.068055) (xy 74.358448 -31.123459)
			(xy 74.328464 -31.175393) (xy 74.291958 -31.222969) (xy 74.249553 -31.265374) (xy 74.201977 -31.30188)
			(xy 74.150043 -31.331864) (xy 74.094639 -31.354813) (xy 74.036714 -31.370334) (xy 73.977258 -31.378162)
			(xy 73.91729 -31.378162) (xy 73.857834 -31.370334) (xy 73.799909 -31.354813) (xy 73.744505 -31.331864)
			(xy 73.692571 -31.30188) (xy 73.644995 -31.265374) (xy 73.60259 -31.222969) (xy 73.566084 -31.175393)
			(xy 73.5361 -31.123459) (xy 73.513151 -31.068055) (xy 73.49763 -31.01013) (xy 73.489802 -30.950674)
			(xy 73.489312 -30.92069) (xy 59.668156 -30.92069) (xy 59.668156 -30.922468) (xy 59.667666 -30.952436)
			(xy 59.659843 -31.011858) (xy 59.64433 -31.069751) (xy 59.621394 -31.125124) (xy 59.591427 -31.17703)
			(xy 59.55494 -31.22458) (xy 59.51256 -31.26696) (xy 59.46501 -31.303447) (xy 59.413104 -31.333414)
			(xy 59.357731 -31.35635) (xy 59.299838 -31.371863) (xy 59.240416 -31.379686) (xy 59.18048 -31.379686)
			(xy 59.121058 -31.371863) (xy 59.063165 -31.35635) (xy 59.007792 -31.333414) (xy 58.955886 -31.303447)
			(xy 58.908336 -31.26696) (xy 58.865956 -31.22458) (xy 58.829469 -31.17703) (xy 58.799502 -31.125124)
			(xy 58.776566 -31.069751) (xy 58.761053 -31.011858) (xy 58.75323 -30.952436) (xy 58.75274 -30.922468)
			(xy 48.405259 -30.922468) (xy 48.404798 -30.950674) (xy 48.39697 -31.01013) (xy 48.381449 -31.068055)
			(xy 48.3585 -31.123459) (xy 48.328516 -31.175393) (xy 48.29201 -31.222969) (xy 48.249605 -31.265374)
			(xy 48.202029 -31.30188) (xy 48.150095 -31.331864) (xy 48.094691 -31.354813) (xy 48.036766 -31.370334)
			(xy 47.97731 -31.378162) (xy 47.917342 -31.378162) (xy 47.857886 -31.370334) (xy 47.799961 -31.354813)
			(xy 47.744557 -31.331864) (xy 47.692623 -31.30188) (xy 47.645047 -31.265374) (xy 47.602642 -31.222969)
			(xy 47.566136 -31.175393) (xy 47.536152 -31.123459) (xy 47.513203 -31.068055) (xy 47.497682 -31.01013)
			(xy 47.489854 -30.950674) (xy 47.489364 -30.92069) (xy 33.668208 -30.92069) (xy 33.668208 -30.922468)
			(xy 33.667718 -30.952436) (xy 33.659895 -31.011858) (xy 33.644382 -31.069751) (xy 33.621446 -31.125124)
			(xy 33.591479 -31.17703) (xy 33.554992 -31.22458) (xy 33.512612 -31.26696) (xy 33.465062 -31.303447)
			(xy 33.413156 -31.333414) (xy 33.357783 -31.35635) (xy 33.29989 -31.371863) (xy 33.240468 -31.379686)
			(xy 33.180532 -31.379686) (xy 33.12111 -31.371863) (xy 33.063217 -31.35635) (xy 33.007844 -31.333414)
			(xy 32.955938 -31.303447) (xy 32.908388 -31.26696) (xy 32.866008 -31.22458) (xy 32.829521 -31.17703)
			(xy 32.799554 -31.125124) (xy 32.776618 -31.069751) (xy 32.761105 -31.011858) (xy 32.753282 -30.952436)
			(xy 32.752792 -30.922468) (xy 22.405311 -30.922468) (xy 22.40485 -30.950674) (xy 22.397022 -31.01013)
			(xy 22.381501 -31.068055) (xy 22.358552 -31.123459) (xy 22.328568 -31.175393) (xy 22.292062 -31.222969)
			(xy 22.249657 -31.265374) (xy 22.202081 -31.30188) (xy 22.150147 -31.331864) (xy 22.094743 -31.354813)
			(xy 22.036818 -31.370334) (xy 21.977362 -31.378162) (xy 21.917394 -31.378162) (xy 21.857938 -31.370334)
			(xy 21.800013 -31.354813) (xy 21.744609 -31.331864) (xy 21.692675 -31.30188) (xy 21.645099 -31.265374)
			(xy 21.602694 -31.222969) (xy 21.566188 -31.175393) (xy 21.536204 -31.123459) (xy 21.513255 -31.068055)
			(xy 21.497734 -31.01013) (xy 21.489906 -30.950674) (xy 21.489416 -30.92069) (xy 7.66826 -30.92069)
			(xy 7.66826 -30.922468) (xy 7.66777 -30.952436) (xy 7.659947 -31.011858) (xy 7.644434 -31.069751)
			(xy 7.621498 -31.125124) (xy 7.591531 -31.17703) (xy 7.555044 -31.22458) (xy 7.512664 -31.26696)
			(xy 7.465114 -31.303447) (xy 7.413208 -31.333414) (xy 7.357835 -31.35635) (xy 7.299942 -31.371863)
			(xy 7.24052 -31.379686) (xy 7.180584 -31.379686) (xy 7.121162 -31.371863) (xy 7.063269 -31.35635)
			(xy 7.007896 -31.333414) (xy 6.95599 -31.303447) (xy 6.90844 -31.26696) (xy 6.86606 -31.22458) (xy 6.829573 -31.17703)
			(xy 6.799606 -31.125124) (xy 6.77667 -31.069751) (xy 6.761157 -31.011858) (xy 6.753334 -30.952436)
			(xy 6.752844 -30.922468) (xy 0.508 -30.922468) (xy 0.508 -32.722312) (xy 8.607044 -32.722312) (xy 8.607044 -31.858712)
			(xy 8.607534 -31.828744) (xy 8.615357 -31.769322) (xy 8.63087 -31.711429) (xy 8.653806 -31.656056)
			(xy 8.683773 -31.60415) (xy 8.72026 -31.5566) (xy 8.76264 -31.51422) (xy 8.81019 -31.477733) (xy 8.862096 -31.447766)
			(xy 8.917469 -31.42483) (xy 8.975362 -31.409317) (xy 9.034784 -31.401494) (xy 9.09472 -31.401494)
			(xy 9.154142 -31.409317) (xy 9.212035 -31.42483) (xy 9.267408 -31.447766) (xy 9.319314 -31.477733)
			(xy 9.366864 -31.51422) (xy 9.409244 -31.5566) (xy 9.445731 -31.60415) (xy 9.475698 -31.656056) (xy 9.498634 -31.711429)
			(xy 9.514147 -31.769322) (xy 9.52197 -31.828744) (xy 9.52246 -31.858712) (xy 9.52246 -32.714184)
			(xy 18.847308 -32.714184) (xy 18.847308 -31.850584) (xy 18.847798 -31.8206) (xy 18.855626 -31.761144)
			(xy 18.871147 -31.703219) (xy 18.894096 -31.647815) (xy 18.92408 -31.595881) (xy 18.960586 -31.548305)
			(xy 19.002991 -31.5059) (xy 19.050567 -31.469394) (xy 19.102501 -31.43941) (xy 19.157905 -31.416461)
			(xy 19.21583 -31.40094) (xy 19.275286 -31.393112) (xy 19.335254 -31.393112) (xy 19.39471 -31.40094)
			(xy 19.452635 -31.416461) (xy 19.508039 -31.43941) (xy 19.559973 -31.469394) (xy 19.607549 -31.5059)
			(xy 19.649954 -31.548305) (xy 19.68646 -31.595881) (xy 19.716444 -31.647815) (xy 19.739393 -31.703219)
			(xy 19.754914 -31.761144) (xy 19.762742 -31.8206) (xy 19.763232 -31.850584) (xy 19.763232 -32.714184)
			(xy 19.763099 -32.722312) (xy 34.606992 -32.722312) (xy 34.606992 -31.858712) (xy 34.607482 -31.828744)
			(xy 34.615305 -31.769322) (xy 34.630818 -31.711429) (xy 34.653754 -31.656056) (xy 34.683721 -31.60415)
			(xy 34.720208 -31.5566) (xy 34.762588 -31.51422) (xy 34.810138 -31.477733) (xy 34.862044 -31.447766)
			(xy 34.917417 -31.42483) (xy 34.97531 -31.409317) (xy 35.034732 -31.401494) (xy 35.094668 -31.401494)
			(xy 35.15409 -31.409317) (xy 35.211983 -31.42483) (xy 35.267356 -31.447766) (xy 35.319262 -31.477733)
			(xy 35.366812 -31.51422) (xy 35.409192 -31.5566) (xy 35.445679 -31.60415) (xy 35.475646 -31.656056)
			(xy 35.498582 -31.711429) (xy 35.514095 -31.769322) (xy 35.521918 -31.828744) (xy 35.522408 -31.858712)
			(xy 35.522408 -32.714184) (xy 44.847256 -32.714184) (xy 44.847256 -31.850584) (xy 44.847746 -31.8206)
			(xy 44.855574 -31.761144) (xy 44.871095 -31.703219) (xy 44.894044 -31.647815) (xy 44.924028 -31.595881)
			(xy 44.960534 -31.548305) (xy 45.002939 -31.5059) (xy 45.050515 -31.469394) (xy 45.102449 -31.43941)
			(xy 45.157853 -31.416461) (xy 45.215778 -31.40094) (xy 45.275234 -31.393112) (xy 45.335202 -31.393112)
			(xy 45.394658 -31.40094) (xy 45.452583 -31.416461) (xy 45.507987 -31.43941) (xy 45.559921 -31.469394)
			(xy 45.607497 -31.5059) (xy 45.649902 -31.548305) (xy 45.686408 -31.595881) (xy 45.716392 -31.647815)
			(xy 45.739341 -31.703219) (xy 45.754862 -31.761144) (xy 45.76269 -31.8206) (xy 45.76318 -31.850584)
			(xy 45.76318 -32.714184) (xy 45.763047 -32.722312) (xy 60.60694 -32.722312) (xy 60.60694 -31.858712)
			(xy 60.60743 -31.828744) (xy 60.615253 -31.769322) (xy 60.630766 -31.711429) (xy 60.653702 -31.656056)
			(xy 60.683669 -31.60415) (xy 60.720156 -31.5566) (xy 60.762536 -31.51422) (xy 60.810086 -31.477733)
			(xy 60.861992 -31.447766) (xy 60.917365 -31.42483) (xy 60.975258 -31.409317) (xy 61.03468 -31.401494)
			(xy 61.094616 -31.401494) (xy 61.154038 -31.409317) (xy 61.211931 -31.42483) (xy 61.267304 -31.447766)
			(xy 61.31921 -31.477733) (xy 61.36676 -31.51422) (xy 61.40914 -31.5566) (xy 61.445627 -31.60415)
			(xy 61.475594 -31.656056) (xy 61.49853 -31.711429) (xy 61.514043 -31.769322) (xy 61.521866 -31.828744)
			(xy 61.522356 -31.858712) (xy 61.522356 -32.714184) (xy 70.847204 -32.714184) (xy 70.847204 -31.850584)
			(xy 70.847694 -31.8206) (xy 70.855522 -31.761144) (xy 70.871043 -31.703219) (xy 70.893992 -31.647815)
			(xy 70.923976 -31.595881) (xy 70.960482 -31.548305) (xy 71.002887 -31.5059) (xy 71.050463 -31.469394)
			(xy 71.102397 -31.43941) (xy 71.157801 -31.416461) (xy 71.215726 -31.40094) (xy 71.275182 -31.393112)
			(xy 71.33515 -31.393112) (xy 71.394606 -31.40094) (xy 71.452531 -31.416461) (xy 71.507935 -31.43941)
			(xy 71.559869 -31.469394) (xy 71.607445 -31.5059) (xy 71.64985 -31.548305) (xy 71.686356 -31.595881)
			(xy 71.71634 -31.647815) (xy 71.739289 -31.703219) (xy 71.75481 -31.761144) (xy 71.762638 -31.8206)
			(xy 71.763128 -31.850584) (xy 71.763128 -32.714184) (xy 71.762995 -32.722312) (xy 86.606888 -32.722312)
			(xy 86.606888 -31.858712) (xy 86.607378 -31.828744) (xy 86.615201 -31.769322) (xy 86.630714 -31.711429)
			(xy 86.65365 -31.656056) (xy 86.683617 -31.60415) (xy 86.720104 -31.5566) (xy 86.762484 -31.51422)
			(xy 86.810034 -31.477733) (xy 86.86194 -31.447766) (xy 86.917313 -31.42483) (xy 86.975206 -31.409317)
			(xy 87.034628 -31.401494) (xy 87.094564 -31.401494) (xy 87.153986 -31.409317) (xy 87.211879 -31.42483)
			(xy 87.267252 -31.447766) (xy 87.319158 -31.477733) (xy 87.366708 -31.51422) (xy 87.409088 -31.5566)
			(xy 87.445575 -31.60415) (xy 87.475542 -31.656056) (xy 87.498478 -31.711429) (xy 87.513991 -31.769322)
			(xy 87.521814 -31.828744) (xy 87.522304 -31.858712) (xy 87.522304 -32.714184) (xy 96.847152 -32.714184)
			(xy 96.847152 -31.850584) (xy 96.847642 -31.8206) (xy 96.85547 -31.761144) (xy 96.870991 -31.703219)
			(xy 96.89394 -31.647815) (xy 96.923924 -31.595881) (xy 96.96043 -31.548305) (xy 97.002835 -31.5059)
			(xy 97.050411 -31.469394) (xy 97.102345 -31.43941) (xy 97.157749 -31.416461) (xy 97.215674 -31.40094)
			(xy 97.27513 -31.393112) (xy 97.335098 -31.393112) (xy 97.394554 -31.40094) (xy 97.452479 -31.416461)
			(xy 97.507883 -31.43941) (xy 97.559817 -31.469394) (xy 97.607393 -31.5059) (xy 97.649798 -31.548305)
			(xy 97.686304 -31.595881) (xy 97.716288 -31.647815) (xy 97.739237 -31.703219) (xy 97.754758 -31.761144)
			(xy 97.762586 -31.8206) (xy 97.763076 -31.850584) (xy 97.763076 -32.714184) (xy 97.762943 -32.722312)
			(xy 124.706888 -32.722312) (xy 124.706888 -31.858712) (xy 124.707378 -31.828728) (xy 124.715206 -31.769272)
			(xy 124.730727 -31.711347) (xy 124.753676 -31.655943) (xy 124.78366 -31.604009) (xy 124.820166 -31.556433)
			(xy 124.862571 -31.514028) (xy 124.910147 -31.477522) (xy 124.962081 -31.447538) (xy 125.017485 -31.424589)
			(xy 125.07541 -31.409068) (xy 125.134866 -31.40124) (xy 125.194834 -31.40124) (xy 125.25429 -31.409068)
			(xy 125.312215 -31.424589) (xy 125.367619 -31.447538) (xy 125.419553 -31.477522) (xy 125.467129 -31.514028)
			(xy 125.509534 -31.556433) (xy 125.54604 -31.604009) (xy 125.576024 -31.655943) (xy 125.598973 -31.711347)
			(xy 125.614494 -31.769272) (xy 125.622322 -31.828728) (xy 125.622812 -31.858712) (xy 125.622812 -32.714184)
			(xy 134.94766 -32.714184) (xy 134.94766 -31.850584) (xy 134.94815 -31.820616) (xy 134.955973 -31.761194)
			(xy 134.971486 -31.703301) (xy 134.994422 -31.647928) (xy 135.024389 -31.596022) (xy 135.060876 -31.548472)
			(xy 135.103256 -31.506092) (xy 135.150806 -31.469605) (xy 135.202712 -31.439638) (xy 135.258085 -31.416702)
			(xy 135.315978 -31.401189) (xy 135.3754 -31.393366) (xy 135.435336 -31.393366) (xy 135.494758 -31.401189)
			(xy 135.552651 -31.416702) (xy 135.608024 -31.439638) (xy 135.65993 -31.469605) (xy 135.70748 -31.506092)
			(xy 135.74986 -31.548472) (xy 135.786347 -31.596022) (xy 135.816314 -31.647928) (xy 135.83925 -31.703301)
			(xy 135.854763 -31.761194) (xy 135.862586 -31.820616) (xy 135.863076 -31.850584) (xy 135.863076 -32.714184)
			(xy 135.862943 -32.722312) (xy 150.706836 -32.722312) (xy 150.706836 -31.858712) (xy 150.707326 -31.828728)
			(xy 150.715154 -31.769272) (xy 150.730675 -31.711347) (xy 150.753624 -31.655943) (xy 150.783608 -31.604009)
			(xy 150.820114 -31.556433) (xy 150.862519 -31.514028) (xy 150.910095 -31.477522) (xy 150.962029 -31.447538)
			(xy 151.017433 -31.424589) (xy 151.075358 -31.409068) (xy 151.134814 -31.40124) (xy 151.194782 -31.40124)
			(xy 151.254238 -31.409068) (xy 151.312163 -31.424589) (xy 151.367567 -31.447538) (xy 151.419501 -31.477522)
			(xy 151.467077 -31.514028) (xy 151.509482 -31.556433) (xy 151.545988 -31.604009) (xy 151.575972 -31.655943)
			(xy 151.598921 -31.711347) (xy 151.614442 -31.769272) (xy 151.62227 -31.828728) (xy 151.62276 -31.858712)
			(xy 151.62276 -32.714184) (xy 160.947608 -32.714184) (xy 160.947608 -31.850584) (xy 160.948098 -31.820616)
			(xy 160.955921 -31.761194) (xy 160.971434 -31.703301) (xy 160.99437 -31.647928) (xy 161.024337 -31.596022)
			(xy 161.060824 -31.548472) (xy 161.103204 -31.506092) (xy 161.150754 -31.469605) (xy 161.20266 -31.439638)
			(xy 161.258033 -31.416702) (xy 161.315926 -31.401189) (xy 161.375348 -31.393366) (xy 161.435284 -31.393366)
			(xy 161.494706 -31.401189) (xy 161.552599 -31.416702) (xy 161.607972 -31.439638) (xy 161.659878 -31.469605)
			(xy 161.707428 -31.506092) (xy 161.749808 -31.548472) (xy 161.786295 -31.596022) (xy 161.816262 -31.647928)
			(xy 161.839198 -31.703301) (xy 161.854711 -31.761194) (xy 161.862534 -31.820616) (xy 161.863024 -31.850584)
			(xy 161.863024 -32.714184) (xy 161.862891 -32.722312) (xy 176.706784 -32.722312) (xy 176.706784 -31.858712)
			(xy 176.707274 -31.828728) (xy 176.715102 -31.769272) (xy 176.730623 -31.711347) (xy 176.753572 -31.655943)
			(xy 176.783556 -31.604009) (xy 176.820062 -31.556433) (xy 176.862467 -31.514028) (xy 176.910043 -31.477522)
			(xy 176.961977 -31.447538) (xy 177.017381 -31.424589) (xy 177.075306 -31.409068) (xy 177.134762 -31.40124)
			(xy 177.19473 -31.40124) (xy 177.254186 -31.409068) (xy 177.312111 -31.424589) (xy 177.367515 -31.447538)
			(xy 177.419449 -31.477522) (xy 177.467025 -31.514028) (xy 177.50943 -31.556433) (xy 177.545936 -31.604009)
			(xy 177.57592 -31.655943) (xy 177.598869 -31.711347) (xy 177.61439 -31.769272) (xy 177.622218 -31.828728)
			(xy 177.622708 -31.858712) (xy 177.622708 -32.714184) (xy 186.947556 -32.714184) (xy 186.947556 -31.850584)
			(xy 186.948046 -31.820616) (xy 186.955869 -31.761194) (xy 186.971382 -31.703301) (xy 186.994318 -31.647928)
			(xy 187.024285 -31.596022) (xy 187.060772 -31.548472) (xy 187.103152 -31.506092) (xy 187.150702 -31.469605)
			(xy 187.202608 -31.439638) (xy 187.257981 -31.416702) (xy 187.315874 -31.401189) (xy 187.375296 -31.393366)
			(xy 187.435232 -31.393366) (xy 187.494654 -31.401189) (xy 187.552547 -31.416702) (xy 187.60792 -31.439638)
			(xy 187.659826 -31.469605) (xy 187.707376 -31.506092) (xy 187.749756 -31.548472) (xy 187.786243 -31.596022)
			(xy 187.81621 -31.647928) (xy 187.839146 -31.703301) (xy 187.854659 -31.761194) (xy 187.862482 -31.820616)
			(xy 187.862972 -31.850584) (xy 187.862972 -32.714184) (xy 187.862839 -32.722312) (xy 202.706732 -32.722312)
			(xy 202.706732 -31.858712) (xy 202.707222 -31.828728) (xy 202.71505 -31.769272) (xy 202.730571 -31.711347)
			(xy 202.75352 -31.655943) (xy 202.783504 -31.604009) (xy 202.82001 -31.556433) (xy 202.862415 -31.514028)
			(xy 202.909991 -31.477522) (xy 202.961925 -31.447538) (xy 203.017329 -31.424589) (xy 203.075254 -31.409068)
			(xy 203.13471 -31.40124) (xy 203.194678 -31.40124) (xy 203.254134 -31.409068) (xy 203.312059 -31.424589)
			(xy 203.367463 -31.447538) (xy 203.419397 -31.477522) (xy 203.466973 -31.514028) (xy 203.509378 -31.556433)
			(xy 203.545884 -31.604009) (xy 203.575868 -31.655943) (xy 203.598817 -31.711347) (xy 203.614338 -31.769272)
			(xy 203.622166 -31.828728) (xy 203.622656 -31.858712) (xy 203.622656 -32.714184) (xy 212.947504 -32.714184)
			(xy 212.947504 -31.850584) (xy 212.947994 -31.820616) (xy 212.955817 -31.761194) (xy 212.97133 -31.703301)
			(xy 212.994266 -31.647928) (xy 213.024233 -31.596022) (xy 213.06072 -31.548472) (xy 213.1031 -31.506092)
			(xy 213.15065 -31.469605) (xy 213.202556 -31.439638) (xy 213.257929 -31.416702) (xy 213.315822 -31.401189)
			(xy 213.375244 -31.393366) (xy 213.43518 -31.393366) (xy 213.494602 -31.401189) (xy 213.552495 -31.416702)
			(xy 213.607868 -31.439638) (xy 213.659774 -31.469605) (xy 213.707324 -31.506092) (xy 213.749704 -31.548472)
			(xy 213.786191 -31.596022) (xy 213.816158 -31.647928) (xy 213.839094 -31.703301) (xy 213.854607 -31.761194)
			(xy 213.86243 -31.820616) (xy 213.86292 -31.850584) (xy 213.86292 -32.714184) (xy 213.862787 -32.722312)
			(xy 240.806732 -32.722312) (xy 240.806732 -31.858712) (xy 240.807222 -31.828728) (xy 240.81505 -31.769272)
			(xy 240.830571 -31.711347) (xy 240.85352 -31.655943) (xy 240.883504 -31.604009) (xy 240.92001 -31.556433)
			(xy 240.962415 -31.514028) (xy 241.009991 -31.477522) (xy 241.061925 -31.447538) (xy 241.117329 -31.424589)
			(xy 241.175254 -31.409068) (xy 241.23471 -31.40124) (xy 241.294678 -31.40124) (xy 241.354134 -31.409068)
			(xy 241.412059 -31.424589) (xy 241.467463 -31.447538) (xy 241.519397 -31.477522) (xy 241.566973 -31.514028)
			(xy 241.609378 -31.556433) (xy 241.645884 -31.604009) (xy 241.675868 -31.655943) (xy 241.698817 -31.711347)
			(xy 241.714338 -31.769272) (xy 241.722166 -31.828728) (xy 241.722656 -31.858712) (xy 241.722656 -32.714184)
			(xy 251.047504 -32.714184) (xy 251.047504 -31.850584) (xy 251.047994 -31.820616) (xy 251.055817 -31.761194)
			(xy 251.07133 -31.703301) (xy 251.094266 -31.647928) (xy 251.124233 -31.596022) (xy 251.16072 -31.548472)
			(xy 251.2031 -31.506092) (xy 251.25065 -31.469605) (xy 251.302556 -31.439638) (xy 251.357929 -31.416702)
			(xy 251.415822 -31.401189) (xy 251.475244 -31.393366) (xy 251.53518 -31.393366) (xy 251.594602 -31.401189)
			(xy 251.652495 -31.416702) (xy 251.707868 -31.439638) (xy 251.759774 -31.469605) (xy 251.807324 -31.506092)
			(xy 251.849704 -31.548472) (xy 251.886191 -31.596022) (xy 251.916158 -31.647928) (xy 251.939094 -31.703301)
			(xy 251.954607 -31.761194) (xy 251.96243 -31.820616) (xy 251.96292 -31.850584) (xy 251.96292 -32.714184)
			(xy 251.962787 -32.722312) (xy 266.80668 -32.722312) (xy 266.80668 -31.858712) (xy 266.80717 -31.828728)
			(xy 266.814998 -31.769272) (xy 266.830519 -31.711347) (xy 266.853468 -31.655943) (xy 266.883452 -31.604009)
			(xy 266.919958 -31.556433) (xy 266.962363 -31.514028) (xy 267.009939 -31.477522) (xy 267.061873 -31.447538)
			(xy 267.117277 -31.424589) (xy 267.175202 -31.409068) (xy 267.234658 -31.40124) (xy 267.294626 -31.40124)
			(xy 267.354082 -31.409068) (xy 267.412007 -31.424589) (xy 267.467411 -31.447538) (xy 267.519345 -31.477522)
			(xy 267.566921 -31.514028) (xy 267.609326 -31.556433) (xy 267.645832 -31.604009) (xy 267.675816 -31.655943)
			(xy 267.698765 -31.711347) (xy 267.714286 -31.769272) (xy 267.722114 -31.828728) (xy 267.722604 -31.858712)
			(xy 267.722604 -32.714184) (xy 277.047452 -32.714184) (xy 277.047452 -31.850584) (xy 277.047942 -31.820616)
			(xy 277.055765 -31.761194) (xy 277.071278 -31.703301) (xy 277.094214 -31.647928) (xy 277.124181 -31.596022)
			(xy 277.160668 -31.548472) (xy 277.203048 -31.506092) (xy 277.250598 -31.469605) (xy 277.302504 -31.439638)
			(xy 277.357877 -31.416702) (xy 277.41577 -31.401189) (xy 277.475192 -31.393366) (xy 277.535128 -31.393366)
			(xy 277.59455 -31.401189) (xy 277.652443 -31.416702) (xy 277.707816 -31.439638) (xy 277.759722 -31.469605)
			(xy 277.807272 -31.506092) (xy 277.849652 -31.548472) (xy 277.886139 -31.596022) (xy 277.916106 -31.647928)
			(xy 277.939042 -31.703301) (xy 277.954555 -31.761194) (xy 277.962378 -31.820616) (xy 277.962868 -31.850584)
			(xy 277.962868 -32.714184) (xy 277.962735 -32.722312) (xy 292.806628 -32.722312) (xy 292.806628 -31.858712)
			(xy 292.807118 -31.828728) (xy 292.814946 -31.769272) (xy 292.830467 -31.711347) (xy 292.853416 -31.655943)
			(xy 292.8834 -31.604009) (xy 292.919906 -31.556433) (xy 292.962311 -31.514028) (xy 293.009887 -31.477522)
			(xy 293.061821 -31.447538) (xy 293.117225 -31.424589) (xy 293.17515 -31.409068) (xy 293.234606 -31.40124)
			(xy 293.294574 -31.40124) (xy 293.35403 -31.409068) (xy 293.411955 -31.424589) (xy 293.467359 -31.447538)
			(xy 293.519293 -31.477522) (xy 293.566869 -31.514028) (xy 293.609274 -31.556433) (xy 293.64578 -31.604009)
			(xy 293.675764 -31.655943) (xy 293.698713 -31.711347) (xy 293.714234 -31.769272) (xy 293.722062 -31.828728)
			(xy 293.722552 -31.858712) (xy 293.722552 -32.714184) (xy 303.0474 -32.714184) (xy 303.0474 -31.850584)
			(xy 303.04789 -31.820616) (xy 303.055713 -31.761194) (xy 303.071226 -31.703301) (xy 303.094162 -31.647928)
			(xy 303.124129 -31.596022) (xy 303.160616 -31.548472) (xy 303.202996 -31.506092) (xy 303.250546 -31.469605)
			(xy 303.302452 -31.439638) (xy 303.357825 -31.416702) (xy 303.415718 -31.401189) (xy 303.47514 -31.393366)
			(xy 303.535076 -31.393366) (xy 303.594498 -31.401189) (xy 303.652391 -31.416702) (xy 303.707764 -31.439638)
			(xy 303.75967 -31.469605) (xy 303.80722 -31.506092) (xy 303.8496 -31.548472) (xy 303.886087 -31.596022)
			(xy 303.916054 -31.647928) (xy 303.93899 -31.703301) (xy 303.954503 -31.761194) (xy 303.962326 -31.820616)
			(xy 303.962816 -31.850584) (xy 303.962816 -32.714184) (xy 303.962683 -32.722312) (xy 318.806576 -32.722312)
			(xy 318.806576 -31.858712) (xy 318.807066 -31.828728) (xy 318.814894 -31.769272) (xy 318.830415 -31.711347)
			(xy 318.853364 -31.655943) (xy 318.883348 -31.604009) (xy 318.919854 -31.556433) (xy 318.962259 -31.514028)
			(xy 319.009835 -31.477522) (xy 319.061769 -31.447538) (xy 319.117173 -31.424589) (xy 319.175098 -31.409068)
			(xy 319.234554 -31.40124) (xy 319.294522 -31.40124) (xy 319.353978 -31.409068) (xy 319.411903 -31.424589)
			(xy 319.467307 -31.447538) (xy 319.519241 -31.477522) (xy 319.566817 -31.514028) (xy 319.609222 -31.556433)
			(xy 319.645728 -31.604009) (xy 319.675712 -31.655943) (xy 319.698661 -31.711347) (xy 319.714182 -31.769272)
			(xy 319.72201 -31.828728) (xy 319.7225 -31.858712) (xy 319.7225 -32.714184) (xy 329.047348 -32.714184)
			(xy 329.047348 -31.850584) (xy 329.047838 -31.820616) (xy 329.055661 -31.761194) (xy 329.071174 -31.703301)
			(xy 329.09411 -31.647928) (xy 329.124077 -31.596022) (xy 329.160564 -31.548472) (xy 329.202944 -31.506092)
			(xy 329.250494 -31.469605) (xy 329.3024 -31.439638) (xy 329.357773 -31.416702) (xy 329.415666 -31.401189)
			(xy 329.475088 -31.393366) (xy 329.535024 -31.393366) (xy 329.594446 -31.401189) (xy 329.652339 -31.416702)
			(xy 329.707712 -31.439638) (xy 329.759618 -31.469605) (xy 329.807168 -31.506092) (xy 329.849548 -31.548472)
			(xy 329.886035 -31.596022) (xy 329.916002 -31.647928) (xy 329.938938 -31.703301) (xy 329.954451 -31.761194)
			(xy 329.962274 -31.820616) (xy 329.962764 -31.850584) (xy 329.962764 -32.714184) (xy 329.962631 -32.722312)
			(xy 356.907084 -32.722312) (xy 356.907084 -31.858712) (xy 356.907574 -31.828744) (xy 356.915397 -31.769322)
			(xy 356.93091 -31.711429) (xy 356.953846 -31.656056) (xy 356.983813 -31.60415) (xy 357.0203 -31.5566)
			(xy 357.06268 -31.51422) (xy 357.11023 -31.477733) (xy 357.162136 -31.447766) (xy 357.217509 -31.42483)
			(xy 357.275402 -31.409317) (xy 357.334824 -31.401494) (xy 357.39476 -31.401494) (xy 357.454182 -31.409317)
			(xy 357.512075 -31.42483) (xy 357.567448 -31.447766) (xy 357.619354 -31.477733) (xy 357.666904 -31.51422)
			(xy 357.709284 -31.5566) (xy 357.745771 -31.60415) (xy 357.775738 -31.656056) (xy 357.798674 -31.711429)
			(xy 357.814187 -31.769322) (xy 357.82201 -31.828744) (xy 357.8225 -31.858712) (xy 357.8225 -32.714184)
			(xy 367.147348 -32.714184) (xy 367.147348 -31.850584) (xy 367.147838 -31.8206) (xy 367.155666 -31.761144)
			(xy 367.171187 -31.703219) (xy 367.194136 -31.647815) (xy 367.22412 -31.595881) (xy 367.260626 -31.548305)
			(xy 367.303031 -31.5059) (xy 367.350607 -31.469394) (xy 367.402541 -31.43941) (xy 367.457945 -31.416461)
			(xy 367.51587 -31.40094) (xy 367.575326 -31.393112) (xy 367.635294 -31.393112) (xy 367.69475 -31.40094)
			(xy 367.752675 -31.416461) (xy 367.808079 -31.43941) (xy 367.860013 -31.469394) (xy 367.907589 -31.5059)
			(xy 367.949994 -31.548305) (xy 367.9865 -31.595881) (xy 368.016484 -31.647815) (xy 368.039433 -31.703219)
			(xy 368.054954 -31.761144) (xy 368.062782 -31.8206) (xy 368.063272 -31.850584) (xy 368.063272 -32.714184)
			(xy 368.063139 -32.722312) (xy 382.907032 -32.722312) (xy 382.907032 -31.858712) (xy 382.907522 -31.828744)
			(xy 382.915345 -31.769322) (xy 382.930858 -31.711429) (xy 382.953794 -31.656056) (xy 382.983761 -31.60415)
			(xy 383.020248 -31.5566) (xy 383.062628 -31.51422) (xy 383.110178 -31.477733) (xy 383.162084 -31.447766)
			(xy 383.217457 -31.42483) (xy 383.27535 -31.409317) (xy 383.334772 -31.401494) (xy 383.394708 -31.401494)
			(xy 383.45413 -31.409317) (xy 383.512023 -31.42483) (xy 383.567396 -31.447766) (xy 383.619302 -31.477733)
			(xy 383.666852 -31.51422) (xy 383.709232 -31.5566) (xy 383.745719 -31.60415) (xy 383.775686 -31.656056)
			(xy 383.798622 -31.711429) (xy 383.814135 -31.769322) (xy 383.821958 -31.828744) (xy 383.822448 -31.858712)
			(xy 383.822448 -32.714184) (xy 393.147296 -32.714184) (xy 393.147296 -31.850584) (xy 393.147786 -31.8206)
			(xy 393.155614 -31.761144) (xy 393.171135 -31.703219) (xy 393.194084 -31.647815) (xy 393.224068 -31.595881)
			(xy 393.260574 -31.548305) (xy 393.302979 -31.5059) (xy 393.350555 -31.469394) (xy 393.402489 -31.43941)
			(xy 393.457893 -31.416461) (xy 393.515818 -31.40094) (xy 393.575274 -31.393112) (xy 393.635242 -31.393112)
			(xy 393.694698 -31.40094) (xy 393.752623 -31.416461) (xy 393.808027 -31.43941) (xy 393.859961 -31.469394)
			(xy 393.907537 -31.5059) (xy 393.949942 -31.548305) (xy 393.986448 -31.595881) (xy 394.016432 -31.647815)
			(xy 394.039381 -31.703219) (xy 394.054902 -31.761144) (xy 394.06273 -31.8206) (xy 394.06322 -31.850584)
			(xy 394.06322 -32.714184) (xy 394.063087 -32.722312) (xy 408.90698 -32.722312) (xy 408.90698 -31.858712)
			(xy 408.90747 -31.828744) (xy 408.915293 -31.769322) (xy 408.930806 -31.711429) (xy 408.953742 -31.656056)
			(xy 408.983709 -31.60415) (xy 409.020196 -31.5566) (xy 409.062576 -31.51422) (xy 409.110126 -31.477733)
			(xy 409.162032 -31.447766) (xy 409.217405 -31.42483) (xy 409.275298 -31.409317) (xy 409.33472 -31.401494)
			(xy 409.394656 -31.401494) (xy 409.454078 -31.409317) (xy 409.511971 -31.42483) (xy 409.567344 -31.447766)
			(xy 409.61925 -31.477733) (xy 409.6668 -31.51422) (xy 409.70918 -31.5566) (xy 409.745667 -31.60415)
			(xy 409.775634 -31.656056) (xy 409.79857 -31.711429) (xy 409.814083 -31.769322) (xy 409.821906 -31.828744)
			(xy 409.822396 -31.858712) (xy 409.822396 -32.714184) (xy 419.147244 -32.714184) (xy 419.147244 -31.850584)
			(xy 419.147734 -31.8206) (xy 419.155562 -31.761144) (xy 419.171083 -31.703219) (xy 419.194032 -31.647815)
			(xy 419.224016 -31.595881) (xy 419.260522 -31.548305) (xy 419.302927 -31.5059) (xy 419.350503 -31.469394)
			(xy 419.402437 -31.43941) (xy 419.457841 -31.416461) (xy 419.515766 -31.40094) (xy 419.575222 -31.393112)
			(xy 419.63519 -31.393112) (xy 419.694646 -31.40094) (xy 419.752571 -31.416461) (xy 419.807975 -31.43941)
			(xy 419.859909 -31.469394) (xy 419.907485 -31.5059) (xy 419.94989 -31.548305) (xy 419.986396 -31.595881)
			(xy 420.01638 -31.647815) (xy 420.039329 -31.703219) (xy 420.05485 -31.761144) (xy 420.062678 -31.8206)
			(xy 420.063168 -31.850584) (xy 420.063168 -32.714184) (xy 420.063035 -32.722312) (xy 434.906928 -32.722312)
			(xy 434.906928 -31.858712) (xy 434.907418 -31.828744) (xy 434.915241 -31.769322) (xy 434.930754 -31.711429)
			(xy 434.95369 -31.656056) (xy 434.983657 -31.60415) (xy 435.020144 -31.5566) (xy 435.062524 -31.51422)
			(xy 435.110074 -31.477733) (xy 435.16198 -31.447766) (xy 435.217353 -31.42483) (xy 435.275246 -31.409317)
			(xy 435.334668 -31.401494) (xy 435.394604 -31.401494) (xy 435.454026 -31.409317) (xy 435.511919 -31.42483)
			(xy 435.567292 -31.447766) (xy 435.619198 -31.477733) (xy 435.666748 -31.51422) (xy 435.709128 -31.5566)
			(xy 435.745615 -31.60415) (xy 435.775582 -31.656056) (xy 435.798518 -31.711429) (xy 435.814031 -31.769322)
			(xy 435.821854 -31.828744) (xy 435.822344 -31.858712) (xy 435.822344 -32.714184) (xy 445.147192 -32.714184)
			(xy 445.147192 -31.850584) (xy 445.147682 -31.8206) (xy 445.15551 -31.761144) (xy 445.171031 -31.703219)
			(xy 445.19398 -31.647815) (xy 445.223964 -31.595881) (xy 445.26047 -31.548305) (xy 445.302875 -31.5059)
			(xy 445.350451 -31.469394) (xy 445.402385 -31.43941) (xy 445.457789 -31.416461) (xy 445.515714 -31.40094)
			(xy 445.57517 -31.393112) (xy 445.635138 -31.393112) (xy 445.694594 -31.40094) (xy 445.752519 -31.416461)
			(xy 445.807923 -31.43941) (xy 445.859857 -31.469394) (xy 445.907433 -31.5059) (xy 445.949838 -31.548305)
			(xy 445.986344 -31.595881) (xy 446.016328 -31.647815) (xy 446.039277 -31.703219) (xy 446.054798 -31.761144)
			(xy 446.062626 -31.8206) (xy 446.063116 -31.850584) (xy 446.063116 -32.714184) (xy 446.062626 -32.744168)
			(xy 446.054798 -32.803624) (xy 446.039277 -32.861549) (xy 446.016328 -32.916953) (xy 445.986344 -32.968887)
			(xy 445.949838 -33.016463) (xy 445.907433 -33.058868) (xy 445.859857 -33.095374) (xy 445.807923 -33.125358)
			(xy 445.752519 -33.148307) (xy 445.694594 -33.163828) (xy 445.635138 -33.171656) (xy 445.57517 -33.171656)
			(xy 445.515714 -33.163828) (xy 445.457789 -33.148307) (xy 445.402385 -33.125358) (xy 445.350451 -33.095374)
			(xy 445.302875 -33.058868) (xy 445.26047 -33.016463) (xy 445.223964 -32.968887) (xy 445.19398 -32.916953)
			(xy 445.171031 -32.861549) (xy 445.15551 -32.803624) (xy 445.147682 -32.744168) (xy 445.147192 -32.714184)
			(xy 435.822344 -32.714184) (xy 435.822344 -32.722312) (xy 435.821854 -32.75228) (xy 435.814031 -32.811702)
			(xy 435.798518 -32.869595) (xy 435.775582 -32.924968) (xy 435.745615 -32.976874) (xy 435.709128 -33.024424)
			(xy 435.666748 -33.066804) (xy 435.619198 -33.103291) (xy 435.567292 -33.133258) (xy 435.511919 -33.156194)
			(xy 435.454026 -33.171707) (xy 435.394604 -33.17953) (xy 435.334668 -33.17953) (xy 435.275246 -33.171707)
			(xy 435.217353 -33.156194) (xy 435.16198 -33.133258) (xy 435.110074 -33.103291) (xy 435.062524 -33.066804)
			(xy 435.020144 -33.024424) (xy 434.983657 -32.976874) (xy 434.95369 -32.924968) (xy 434.930754 -32.869595)
			(xy 434.915241 -32.811702) (xy 434.907418 -32.75228) (xy 434.906928 -32.722312) (xy 420.063035 -32.722312)
			(xy 420.062678 -32.744168) (xy 420.05485 -32.803624) (xy 420.039329 -32.861549) (xy 420.01638 -32.916953)
			(xy 419.986396 -32.968887) (xy 419.94989 -33.016463) (xy 419.907485 -33.058868) (xy 419.859909 -33.095374)
			(xy 419.807975 -33.125358) (xy 419.752571 -33.148307) (xy 419.694646 -33.163828) (xy 419.63519 -33.171656)
			(xy 419.575222 -33.171656) (xy 419.515766 -33.163828) (xy 419.457841 -33.148307) (xy 419.402437 -33.125358)
			(xy 419.350503 -33.095374) (xy 419.302927 -33.058868) (xy 419.260522 -33.016463) (xy 419.224016 -32.968887)
			(xy 419.194032 -32.916953) (xy 419.171083 -32.861549) (xy 419.155562 -32.803624) (xy 419.147734 -32.744168)
			(xy 419.147244 -32.714184) (xy 409.822396 -32.714184) (xy 409.822396 -32.722312) (xy 409.821906 -32.75228)
			(xy 409.814083 -32.811702) (xy 409.79857 -32.869595) (xy 409.775634 -32.924968) (xy 409.745667 -32.976874)
			(xy 409.70918 -33.024424) (xy 409.6668 -33.066804) (xy 409.61925 -33.103291) (xy 409.567344 -33.133258)
			(xy 409.511971 -33.156194) (xy 409.454078 -33.171707) (xy 409.394656 -33.17953) (xy 409.33472 -33.17953)
			(xy 409.275298 -33.171707) (xy 409.217405 -33.156194) (xy 409.162032 -33.133258) (xy 409.110126 -33.103291)
			(xy 409.062576 -33.066804) (xy 409.020196 -33.024424) (xy 408.983709 -32.976874) (xy 408.953742 -32.924968)
			(xy 408.930806 -32.869595) (xy 408.915293 -32.811702) (xy 408.90747 -32.75228) (xy 408.90698 -32.722312)
			(xy 394.063087 -32.722312) (xy 394.06273 -32.744168) (xy 394.054902 -32.803624) (xy 394.039381 -32.861549)
			(xy 394.016432 -32.916953) (xy 393.986448 -32.968887) (xy 393.949942 -33.016463) (xy 393.907537 -33.058868)
			(xy 393.859961 -33.095374) (xy 393.808027 -33.125358) (xy 393.752623 -33.148307) (xy 393.694698 -33.163828)
			(xy 393.635242 -33.171656) (xy 393.575274 -33.171656) (xy 393.515818 -33.163828) (xy 393.457893 -33.148307)
			(xy 393.402489 -33.125358) (xy 393.350555 -33.095374) (xy 393.302979 -33.058868) (xy 393.260574 -33.016463)
			(xy 393.224068 -32.968887) (xy 393.194084 -32.916953) (xy 393.171135 -32.861549) (xy 393.155614 -32.803624)
			(xy 393.147786 -32.744168) (xy 393.147296 -32.714184) (xy 383.822448 -32.714184) (xy 383.822448 -32.722312)
			(xy 383.821958 -32.75228) (xy 383.814135 -32.811702) (xy 383.798622 -32.869595) (xy 383.775686 -32.924968)
			(xy 383.745719 -32.976874) (xy 383.709232 -33.024424) (xy 383.666852 -33.066804) (xy 383.619302 -33.103291)
			(xy 383.567396 -33.133258) (xy 383.512023 -33.156194) (xy 383.45413 -33.171707) (xy 383.394708 -33.17953)
			(xy 383.334772 -33.17953) (xy 383.27535 -33.171707) (xy 383.217457 -33.156194) (xy 383.162084 -33.133258)
			(xy 383.110178 -33.103291) (xy 383.062628 -33.066804) (xy 383.020248 -33.024424) (xy 382.983761 -32.976874)
			(xy 382.953794 -32.924968) (xy 382.930858 -32.869595) (xy 382.915345 -32.811702) (xy 382.907522 -32.75228)
			(xy 382.907032 -32.722312) (xy 368.063139 -32.722312) (xy 368.062782 -32.744168) (xy 368.054954 -32.803624)
			(xy 368.039433 -32.861549) (xy 368.016484 -32.916953) (xy 367.9865 -32.968887) (xy 367.949994 -33.016463)
			(xy 367.907589 -33.058868) (xy 367.860013 -33.095374) (xy 367.808079 -33.125358) (xy 367.752675 -33.148307)
			(xy 367.69475 -33.163828) (xy 367.635294 -33.171656) (xy 367.575326 -33.171656) (xy 367.51587 -33.163828)
			(xy 367.457945 -33.148307) (xy 367.402541 -33.125358) (xy 367.350607 -33.095374) (xy 367.303031 -33.058868)
			(xy 367.260626 -33.016463) (xy 367.22412 -32.968887) (xy 367.194136 -32.916953) (xy 367.171187 -32.861549)
			(xy 367.155666 -32.803624) (xy 367.147838 -32.744168) (xy 367.147348 -32.714184) (xy 357.8225 -32.714184)
			(xy 357.8225 -32.722312) (xy 357.82201 -32.75228) (xy 357.814187 -32.811702) (xy 357.798674 -32.869595)
			(xy 357.775738 -32.924968) (xy 357.745771 -32.976874) (xy 357.709284 -33.024424) (xy 357.666904 -33.066804)
			(xy 357.619354 -33.103291) (xy 357.567448 -33.133258) (xy 357.512075 -33.156194) (xy 357.454182 -33.171707)
			(xy 357.39476 -33.17953) (xy 357.334824 -33.17953) (xy 357.275402 -33.171707) (xy 357.217509 -33.156194)
			(xy 357.162136 -33.133258) (xy 357.11023 -33.103291) (xy 357.06268 -33.066804) (xy 357.0203 -33.024424)
			(xy 356.983813 -32.976874) (xy 356.953846 -32.924968) (xy 356.93091 -32.869595) (xy 356.915397 -32.811702)
			(xy 356.907574 -32.75228) (xy 356.907084 -32.722312) (xy 329.962631 -32.722312) (xy 329.962274 -32.744152)
			(xy 329.954451 -32.803574) (xy 329.938938 -32.861467) (xy 329.916002 -32.91684) (xy 329.886035 -32.968746)
			(xy 329.849548 -33.016296) (xy 329.807168 -33.058676) (xy 329.759618 -33.095163) (xy 329.707712 -33.12513)
			(xy 329.652339 -33.148066) (xy 329.594446 -33.163579) (xy 329.535024 -33.171402) (xy 329.475088 -33.171402)
			(xy 329.415666 -33.163579) (xy 329.357773 -33.148066) (xy 329.3024 -33.12513) (xy 329.250494 -33.095163)
			(xy 329.202944 -33.058676) (xy 329.160564 -33.016296) (xy 329.124077 -32.968746) (xy 329.09411 -32.91684)
			(xy 329.071174 -32.861467) (xy 329.055661 -32.803574) (xy 329.047838 -32.744152) (xy 329.047348 -32.714184)
			(xy 319.7225 -32.714184) (xy 319.7225 -32.722312) (xy 319.72201 -32.752296) (xy 319.714182 -32.811752)
			(xy 319.698661 -32.869677) (xy 319.675712 -32.925081) (xy 319.645728 -32.977015) (xy 319.609222 -33.024591)
			(xy 319.566817 -33.066996) (xy 319.519241 -33.103502) (xy 319.467307 -33.133486) (xy 319.411903 -33.156435)
			(xy 319.353978 -33.171956) (xy 319.294522 -33.179784) (xy 319.234554 -33.179784) (xy 319.175098 -33.171956)
			(xy 319.117173 -33.156435) (xy 319.061769 -33.133486) (xy 319.009835 -33.103502) (xy 318.962259 -33.066996)
			(xy 318.919854 -33.024591) (xy 318.883348 -32.977015) (xy 318.853364 -32.925081) (xy 318.830415 -32.869677)
			(xy 318.814894 -32.811752) (xy 318.807066 -32.752296) (xy 318.806576 -32.722312) (xy 303.962683 -32.722312)
			(xy 303.962326 -32.744152) (xy 303.954503 -32.803574) (xy 303.93899 -32.861467) (xy 303.916054 -32.91684)
			(xy 303.886087 -32.968746) (xy 303.8496 -33.016296) (xy 303.80722 -33.058676) (xy 303.75967 -33.095163)
			(xy 303.707764 -33.12513) (xy 303.652391 -33.148066) (xy 303.594498 -33.163579) (xy 303.535076 -33.171402)
			(xy 303.47514 -33.171402) (xy 303.415718 -33.163579) (xy 303.357825 -33.148066) (xy 303.302452 -33.12513)
			(xy 303.250546 -33.095163) (xy 303.202996 -33.058676) (xy 303.160616 -33.016296) (xy 303.124129 -32.968746)
			(xy 303.094162 -32.91684) (xy 303.071226 -32.861467) (xy 303.055713 -32.803574) (xy 303.04789 -32.744152)
			(xy 303.0474 -32.714184) (xy 293.722552 -32.714184) (xy 293.722552 -32.722312) (xy 293.722062 -32.752296)
			(xy 293.714234 -32.811752) (xy 293.698713 -32.869677) (xy 293.675764 -32.925081) (xy 293.64578 -32.977015)
			(xy 293.609274 -33.024591) (xy 293.566869 -33.066996) (xy 293.519293 -33.103502) (xy 293.467359 -33.133486)
			(xy 293.411955 -33.156435) (xy 293.35403 -33.171956) (xy 293.294574 -33.179784) (xy 293.234606 -33.179784)
			(xy 293.17515 -33.171956) (xy 293.117225 -33.156435) (xy 293.061821 -33.133486) (xy 293.009887 -33.103502)
			(xy 292.962311 -33.066996) (xy 292.919906 -33.024591) (xy 292.8834 -32.977015) (xy 292.853416 -32.925081)
			(xy 292.830467 -32.869677) (xy 292.814946 -32.811752) (xy 292.807118 -32.752296) (xy 292.806628 -32.722312)
			(xy 277.962735 -32.722312) (xy 277.962378 -32.744152) (xy 277.954555 -32.803574) (xy 277.939042 -32.861467)
			(xy 277.916106 -32.91684) (xy 277.886139 -32.968746) (xy 277.849652 -33.016296) (xy 277.807272 -33.058676)
			(xy 277.759722 -33.095163) (xy 277.707816 -33.12513) (xy 277.652443 -33.148066) (xy 277.59455 -33.163579)
			(xy 277.535128 -33.171402) (xy 277.475192 -33.171402) (xy 277.41577 -33.163579) (xy 277.357877 -33.148066)
			(xy 277.302504 -33.12513) (xy 277.250598 -33.095163) (xy 277.203048 -33.058676) (xy 277.160668 -33.016296)
			(xy 277.124181 -32.968746) (xy 277.094214 -32.91684) (xy 277.071278 -32.861467) (xy 277.055765 -32.803574)
			(xy 277.047942 -32.744152) (xy 277.047452 -32.714184) (xy 267.722604 -32.714184) (xy 267.722604 -32.722312)
			(xy 267.722114 -32.752296) (xy 267.714286 -32.811752) (xy 267.698765 -32.869677) (xy 267.675816 -32.925081)
			(xy 267.645832 -32.977015) (xy 267.609326 -33.024591) (xy 267.566921 -33.066996) (xy 267.519345 -33.103502)
			(xy 267.467411 -33.133486) (xy 267.412007 -33.156435) (xy 267.354082 -33.171956) (xy 267.294626 -33.179784)
			(xy 267.234658 -33.179784) (xy 267.175202 -33.171956) (xy 267.117277 -33.156435) (xy 267.061873 -33.133486)
			(xy 267.009939 -33.103502) (xy 266.962363 -33.066996) (xy 266.919958 -33.024591) (xy 266.883452 -32.977015)
			(xy 266.853468 -32.925081) (xy 266.830519 -32.869677) (xy 266.814998 -32.811752) (xy 266.80717 -32.752296)
			(xy 266.80668 -32.722312) (xy 251.962787 -32.722312) (xy 251.96243 -32.744152) (xy 251.954607 -32.803574)
			(xy 251.939094 -32.861467) (xy 251.916158 -32.91684) (xy 251.886191 -32.968746) (xy 251.849704 -33.016296)
			(xy 251.807324 -33.058676) (xy 251.759774 -33.095163) (xy 251.707868 -33.12513) (xy 251.652495 -33.148066)
			(xy 251.594602 -33.163579) (xy 251.53518 -33.171402) (xy 251.475244 -33.171402) (xy 251.415822 -33.163579)
			(xy 251.357929 -33.148066) (xy 251.302556 -33.12513) (xy 251.25065 -33.095163) (xy 251.2031 -33.058676)
			(xy 251.16072 -33.016296) (xy 251.124233 -32.968746) (xy 251.094266 -32.91684) (xy 251.07133 -32.861467)
			(xy 251.055817 -32.803574) (xy 251.047994 -32.744152) (xy 251.047504 -32.714184) (xy 241.722656 -32.714184)
			(xy 241.722656 -32.722312) (xy 241.722166 -32.752296) (xy 241.714338 -32.811752) (xy 241.698817 -32.869677)
			(xy 241.675868 -32.925081) (xy 241.645884 -32.977015) (xy 241.609378 -33.024591) (xy 241.566973 -33.066996)
			(xy 241.519397 -33.103502) (xy 241.467463 -33.133486) (xy 241.412059 -33.156435) (xy 241.354134 -33.171956)
			(xy 241.294678 -33.179784) (xy 241.23471 -33.179784) (xy 241.175254 -33.171956) (xy 241.117329 -33.156435)
			(xy 241.061925 -33.133486) (xy 241.009991 -33.103502) (xy 240.962415 -33.066996) (xy 240.92001 -33.024591)
			(xy 240.883504 -32.977015) (xy 240.85352 -32.925081) (xy 240.830571 -32.869677) (xy 240.81505 -32.811752)
			(xy 240.807222 -32.752296) (xy 240.806732 -32.722312) (xy 213.862787 -32.722312) (xy 213.86243 -32.744152)
			(xy 213.854607 -32.803574) (xy 213.839094 -32.861467) (xy 213.816158 -32.91684) (xy 213.786191 -32.968746)
			(xy 213.749704 -33.016296) (xy 213.707324 -33.058676) (xy 213.659774 -33.095163) (xy 213.607868 -33.12513)
			(xy 213.552495 -33.148066) (xy 213.494602 -33.163579) (xy 213.43518 -33.171402) (xy 213.375244 -33.171402)
			(xy 213.315822 -33.163579) (xy 213.257929 -33.148066) (xy 213.202556 -33.12513) (xy 213.15065 -33.095163)
			(xy 213.1031 -33.058676) (xy 213.06072 -33.016296) (xy 213.024233 -32.968746) (xy 212.994266 -32.91684)
			(xy 212.97133 -32.861467) (xy 212.955817 -32.803574) (xy 212.947994 -32.744152) (xy 212.947504 -32.714184)
			(xy 203.622656 -32.714184) (xy 203.622656 -32.722312) (xy 203.622166 -32.752296) (xy 203.614338 -32.811752)
			(xy 203.598817 -32.869677) (xy 203.575868 -32.925081) (xy 203.545884 -32.977015) (xy 203.509378 -33.024591)
			(xy 203.466973 -33.066996) (xy 203.419397 -33.103502) (xy 203.367463 -33.133486) (xy 203.312059 -33.156435)
			(xy 203.254134 -33.171956) (xy 203.194678 -33.179784) (xy 203.13471 -33.179784) (xy 203.075254 -33.171956)
			(xy 203.017329 -33.156435) (xy 202.961925 -33.133486) (xy 202.909991 -33.103502) (xy 202.862415 -33.066996)
			(xy 202.82001 -33.024591) (xy 202.783504 -32.977015) (xy 202.75352 -32.925081) (xy 202.730571 -32.869677)
			(xy 202.71505 -32.811752) (xy 202.707222 -32.752296) (xy 202.706732 -32.722312) (xy 187.862839 -32.722312)
			(xy 187.862482 -32.744152) (xy 187.854659 -32.803574) (xy 187.839146 -32.861467) (xy 187.81621 -32.91684)
			(xy 187.786243 -32.968746) (xy 187.749756 -33.016296) (xy 187.707376 -33.058676) (xy 187.659826 -33.095163)
			(xy 187.60792 -33.12513) (xy 187.552547 -33.148066) (xy 187.494654 -33.163579) (xy 187.435232 -33.171402)
			(xy 187.375296 -33.171402) (xy 187.315874 -33.163579) (xy 187.257981 -33.148066) (xy 187.202608 -33.12513)
			(xy 187.150702 -33.095163) (xy 187.103152 -33.058676) (xy 187.060772 -33.016296) (xy 187.024285 -32.968746)
			(xy 186.994318 -32.91684) (xy 186.971382 -32.861467) (xy 186.955869 -32.803574) (xy 186.948046 -32.744152)
			(xy 186.947556 -32.714184) (xy 177.622708 -32.714184) (xy 177.622708 -32.722312) (xy 177.622218 -32.752296)
			(xy 177.61439 -32.811752) (xy 177.598869 -32.869677) (xy 177.57592 -32.925081) (xy 177.545936 -32.977015)
			(xy 177.50943 -33.024591) (xy 177.467025 -33.066996) (xy 177.419449 -33.103502) (xy 177.367515 -33.133486)
			(xy 177.312111 -33.156435) (xy 177.254186 -33.171956) (xy 177.19473 -33.179784) (xy 177.134762 -33.179784)
			(xy 177.075306 -33.171956) (xy 177.017381 -33.156435) (xy 176.961977 -33.133486) (xy 176.910043 -33.103502)
			(xy 176.862467 -33.066996) (xy 176.820062 -33.024591) (xy 176.783556 -32.977015) (xy 176.753572 -32.925081)
			(xy 176.730623 -32.869677) (xy 176.715102 -32.811752) (xy 176.707274 -32.752296) (xy 176.706784 -32.722312)
			(xy 161.862891 -32.722312) (xy 161.862534 -32.744152) (xy 161.854711 -32.803574) (xy 161.839198 -32.861467)
			(xy 161.816262 -32.91684) (xy 161.786295 -32.968746) (xy 161.749808 -33.016296) (xy 161.707428 -33.058676)
			(xy 161.659878 -33.095163) (xy 161.607972 -33.12513) (xy 161.552599 -33.148066) (xy 161.494706 -33.163579)
			(xy 161.435284 -33.171402) (xy 161.375348 -33.171402) (xy 161.315926 -33.163579) (xy 161.258033 -33.148066)
			(xy 161.20266 -33.12513) (xy 161.150754 -33.095163) (xy 161.103204 -33.058676) (xy 161.060824 -33.016296)
			(xy 161.024337 -32.968746) (xy 160.99437 -32.91684) (xy 160.971434 -32.861467) (xy 160.955921 -32.803574)
			(xy 160.948098 -32.744152) (xy 160.947608 -32.714184) (xy 151.62276 -32.714184) (xy 151.62276 -32.722312)
			(xy 151.62227 -32.752296) (xy 151.614442 -32.811752) (xy 151.598921 -32.869677) (xy 151.575972 -32.925081)
			(xy 151.545988 -32.977015) (xy 151.509482 -33.024591) (xy 151.467077 -33.066996) (xy 151.419501 -33.103502)
			(xy 151.367567 -33.133486) (xy 151.312163 -33.156435) (xy 151.254238 -33.171956) (xy 151.194782 -33.179784)
			(xy 151.134814 -33.179784) (xy 151.075358 -33.171956) (xy 151.017433 -33.156435) (xy 150.962029 -33.133486)
			(xy 150.910095 -33.103502) (xy 150.862519 -33.066996) (xy 150.820114 -33.024591) (xy 150.783608 -32.977015)
			(xy 150.753624 -32.925081) (xy 150.730675 -32.869677) (xy 150.715154 -32.811752) (xy 150.707326 -32.752296)
			(xy 150.706836 -32.722312) (xy 135.862943 -32.722312) (xy 135.862586 -32.744152) (xy 135.854763 -32.803574)
			(xy 135.83925 -32.861467) (xy 135.816314 -32.91684) (xy 135.786347 -32.968746) (xy 135.74986 -33.016296)
			(xy 135.70748 -33.058676) (xy 135.65993 -33.095163) (xy 135.608024 -33.12513) (xy 135.552651 -33.148066)
			(xy 135.494758 -33.163579) (xy 135.435336 -33.171402) (xy 135.3754 -33.171402) (xy 135.315978 -33.163579)
			(xy 135.258085 -33.148066) (xy 135.202712 -33.12513) (xy 135.150806 -33.095163) (xy 135.103256 -33.058676)
			(xy 135.060876 -33.016296) (xy 135.024389 -32.968746) (xy 134.994422 -32.91684) (xy 134.971486 -32.861467)
			(xy 134.955973 -32.803574) (xy 134.94815 -32.744152) (xy 134.94766 -32.714184) (xy 125.622812 -32.714184)
			(xy 125.622812 -32.722312) (xy 125.622322 -32.752296) (xy 125.614494 -32.811752) (xy 125.598973 -32.869677)
			(xy 125.576024 -32.925081) (xy 125.54604 -32.977015) (xy 125.509534 -33.024591) (xy 125.467129 -33.066996)
			(xy 125.419553 -33.103502) (xy 125.367619 -33.133486) (xy 125.312215 -33.156435) (xy 125.25429 -33.171956)
			(xy 125.194834 -33.179784) (xy 125.134866 -33.179784) (xy 125.07541 -33.171956) (xy 125.017485 -33.156435)
			(xy 124.962081 -33.133486) (xy 124.910147 -33.103502) (xy 124.862571 -33.066996) (xy 124.820166 -33.024591)
			(xy 124.78366 -32.977015) (xy 124.753676 -32.925081) (xy 124.730727 -32.869677) (xy 124.715206 -32.811752)
			(xy 124.707378 -32.752296) (xy 124.706888 -32.722312) (xy 97.762943 -32.722312) (xy 97.762586 -32.744168)
			(xy 97.754758 -32.803624) (xy 97.739237 -32.861549) (xy 97.716288 -32.916953) (xy 97.686304 -32.968887)
			(xy 97.649798 -33.016463) (xy 97.607393 -33.058868) (xy 97.559817 -33.095374) (xy 97.507883 -33.125358)
			(xy 97.452479 -33.148307) (xy 97.394554 -33.163828) (xy 97.335098 -33.171656) (xy 97.27513 -33.171656)
			(xy 97.215674 -33.163828) (xy 97.157749 -33.148307) (xy 97.102345 -33.125358) (xy 97.050411 -33.095374)
			(xy 97.002835 -33.058868) (xy 96.96043 -33.016463) (xy 96.923924 -32.968887) (xy 96.89394 -32.916953)
			(xy 96.870991 -32.861549) (xy 96.85547 -32.803624) (xy 96.847642 -32.744168) (xy 96.847152 -32.714184)
			(xy 87.522304 -32.714184) (xy 87.522304 -32.722312) (xy 87.521814 -32.75228) (xy 87.513991 -32.811702)
			(xy 87.498478 -32.869595) (xy 87.475542 -32.924968) (xy 87.445575 -32.976874) (xy 87.409088 -33.024424)
			(xy 87.366708 -33.066804) (xy 87.319158 -33.103291) (xy 87.267252 -33.133258) (xy 87.211879 -33.156194)
			(xy 87.153986 -33.171707) (xy 87.094564 -33.17953) (xy 87.034628 -33.17953) (xy 86.975206 -33.171707)
			(xy 86.917313 -33.156194) (xy 86.86194 -33.133258) (xy 86.810034 -33.103291) (xy 86.762484 -33.066804)
			(xy 86.720104 -33.024424) (xy 86.683617 -32.976874) (xy 86.65365 -32.924968) (xy 86.630714 -32.869595)
			(xy 86.615201 -32.811702) (xy 86.607378 -32.75228) (xy 86.606888 -32.722312) (xy 71.762995 -32.722312)
			(xy 71.762638 -32.744168) (xy 71.75481 -32.803624) (xy 71.739289 -32.861549) (xy 71.71634 -32.916953)
			(xy 71.686356 -32.968887) (xy 71.64985 -33.016463) (xy 71.607445 -33.058868) (xy 71.559869 -33.095374)
			(xy 71.507935 -33.125358) (xy 71.452531 -33.148307) (xy 71.394606 -33.163828) (xy 71.33515 -33.171656)
			(xy 71.275182 -33.171656) (xy 71.215726 -33.163828) (xy 71.157801 -33.148307) (xy 71.102397 -33.125358)
			(xy 71.050463 -33.095374) (xy 71.002887 -33.058868) (xy 70.960482 -33.016463) (xy 70.923976 -32.968887)
			(xy 70.893992 -32.916953) (xy 70.871043 -32.861549) (xy 70.855522 -32.803624) (xy 70.847694 -32.744168)
			(xy 70.847204 -32.714184) (xy 61.522356 -32.714184) (xy 61.522356 -32.722312) (xy 61.521866 -32.75228)
			(xy 61.514043 -32.811702) (xy 61.49853 -32.869595) (xy 61.475594 -32.924968) (xy 61.445627 -32.976874)
			(xy 61.40914 -33.024424) (xy 61.36676 -33.066804) (xy 61.31921 -33.103291) (xy 61.267304 -33.133258)
			(xy 61.211931 -33.156194) (xy 61.154038 -33.171707) (xy 61.094616 -33.17953) (xy 61.03468 -33.17953)
			(xy 60.975258 -33.171707) (xy 60.917365 -33.156194) (xy 60.861992 -33.133258) (xy 60.810086 -33.103291)
			(xy 60.762536 -33.066804) (xy 60.720156 -33.024424) (xy 60.683669 -32.976874) (xy 60.653702 -32.924968)
			(xy 60.630766 -32.869595) (xy 60.615253 -32.811702) (xy 60.60743 -32.75228) (xy 60.60694 -32.722312)
			(xy 45.763047 -32.722312) (xy 45.76269 -32.744168) (xy 45.754862 -32.803624) (xy 45.739341 -32.861549)
			(xy 45.716392 -32.916953) (xy 45.686408 -32.968887) (xy 45.649902 -33.016463) (xy 45.607497 -33.058868)
			(xy 45.559921 -33.095374) (xy 45.507987 -33.125358) (xy 45.452583 -33.148307) (xy 45.394658 -33.163828)
			(xy 45.335202 -33.171656) (xy 45.275234 -33.171656) (xy 45.215778 -33.163828) (xy 45.157853 -33.148307)
			(xy 45.102449 -33.125358) (xy 45.050515 -33.095374) (xy 45.002939 -33.058868) (xy 44.960534 -33.016463)
			(xy 44.924028 -32.968887) (xy 44.894044 -32.916953) (xy 44.871095 -32.861549) (xy 44.855574 -32.803624)
			(xy 44.847746 -32.744168) (xy 44.847256 -32.714184) (xy 35.522408 -32.714184) (xy 35.522408 -32.722312)
			(xy 35.521918 -32.75228) (xy 35.514095 -32.811702) (xy 35.498582 -32.869595) (xy 35.475646 -32.924968)
			(xy 35.445679 -32.976874) (xy 35.409192 -33.024424) (xy 35.366812 -33.066804) (xy 35.319262 -33.103291)
			(xy 35.267356 -33.133258) (xy 35.211983 -33.156194) (xy 35.15409 -33.171707) (xy 35.094668 -33.17953)
			(xy 35.034732 -33.17953) (xy 34.97531 -33.171707) (xy 34.917417 -33.156194) (xy 34.862044 -33.133258)
			(xy 34.810138 -33.103291) (xy 34.762588 -33.066804) (xy 34.720208 -33.024424) (xy 34.683721 -32.976874)
			(xy 34.653754 -32.924968) (xy 34.630818 -32.869595) (xy 34.615305 -32.811702) (xy 34.607482 -32.75228)
			(xy 34.606992 -32.722312) (xy 19.763099 -32.722312) (xy 19.762742 -32.744168) (xy 19.754914 -32.803624)
			(xy 19.739393 -32.861549) (xy 19.716444 -32.916953) (xy 19.68646 -32.968887) (xy 19.649954 -33.016463)
			(xy 19.607549 -33.058868) (xy 19.559973 -33.095374) (xy 19.508039 -33.125358) (xy 19.452635 -33.148307)
			(xy 19.39471 -33.163828) (xy 19.335254 -33.171656) (xy 19.275286 -33.171656) (xy 19.21583 -33.163828)
			(xy 19.157905 -33.148307) (xy 19.102501 -33.125358) (xy 19.050567 -33.095374) (xy 19.002991 -33.058868)
			(xy 18.960586 -33.016463) (xy 18.92408 -32.968887) (xy 18.894096 -32.916953) (xy 18.871147 -32.861549)
			(xy 18.855626 -32.803624) (xy 18.847798 -32.744168) (xy 18.847308 -32.714184) (xy 9.52246 -32.714184)
			(xy 9.52246 -32.722312) (xy 9.52197 -32.75228) (xy 9.514147 -32.811702) (xy 9.498634 -32.869595)
			(xy 9.475698 -32.924968) (xy 9.445731 -32.976874) (xy 9.409244 -33.024424) (xy 9.366864 -33.066804)
			(xy 9.319314 -33.103291) (xy 9.267408 -33.133258) (xy 9.212035 -33.156194) (xy 9.154142 -33.171707)
			(xy 9.09472 -33.17953) (xy 9.034784 -33.17953) (xy 8.975362 -33.171707) (xy 8.917469 -33.156194)
			(xy 8.862096 -33.133258) (xy 8.81019 -33.103291) (xy 8.76264 -33.066804) (xy 8.72026 -33.024424)
			(xy 8.683773 -32.976874) (xy 8.653806 -32.924968) (xy 8.63087 -32.869595) (xy 8.615357 -32.811702)
			(xy 8.607534 -32.75228) (xy 8.607044 -32.722312) (xy 0.508 -32.722312) (xy 0.508 -34.52241) (xy 6.752844 -34.52241)
			(xy 6.752844 -33.65881) (xy 6.753334 -33.628842) (xy 6.761157 -33.56942) (xy 6.77667 -33.511527)
			(xy 6.799606 -33.456154) (xy 6.829573 -33.404248) (xy 6.86606 -33.356698) (xy 6.90844 -33.314318)
			(xy 6.95599 -33.277831) (xy 7.007896 -33.247864) (xy 7.063269 -33.224928) (xy 7.121162 -33.209415)
			(xy 7.180584 -33.201592) (xy 7.24052 -33.201592) (xy 7.299942 -33.209415) (xy 7.357835 -33.224928)
			(xy 7.413208 -33.247864) (xy 7.465114 -33.277831) (xy 7.512664 -33.314318) (xy 7.555044 -33.356698)
			(xy 7.591531 -33.404248) (xy 7.621498 -33.456154) (xy 7.644434 -33.511527) (xy 7.659947 -33.56942)
			(xy 7.66777 -33.628842) (xy 7.66826 -33.65881) (xy 7.66826 -34.520886) (xy 21.489416 -34.520886)
			(xy 21.489416 -33.657286) (xy 21.489906 -33.627302) (xy 21.497734 -33.567846) (xy 21.513255 -33.509921)
			(xy 21.536204 -33.454517) (xy 21.566188 -33.402583) (xy 21.602694 -33.355007) (xy 21.645099 -33.312602)
			(xy 21.692675 -33.276096) (xy 21.744609 -33.246112) (xy 21.800013 -33.223163) (xy 21.857938 -33.207642)
			(xy 21.917394 -33.199814) (xy 21.977362 -33.199814) (xy 22.036818 -33.207642) (xy 22.094743 -33.223163)
			(xy 22.150147 -33.246112) (xy 22.202081 -33.276096) (xy 22.249657 -33.312602) (xy 22.292062 -33.355007)
			(xy 22.328568 -33.402583) (xy 22.358552 -33.454517) (xy 22.381501 -33.509921) (xy 22.397022 -33.567846)
			(xy 22.40485 -33.627302) (xy 22.40534 -33.657286) (xy 22.40534 -34.520886) (xy 22.405315 -34.52241)
			(xy 32.752792 -34.52241) (xy 32.752792 -33.65881) (xy 32.753282 -33.628842) (xy 32.761105 -33.56942)
			(xy 32.776618 -33.511527) (xy 32.799554 -33.456154) (xy 32.829521 -33.404248) (xy 32.866008 -33.356698)
			(xy 32.908388 -33.314318) (xy 32.955938 -33.277831) (xy 33.007844 -33.247864) (xy 33.063217 -33.224928)
			(xy 33.12111 -33.209415) (xy 33.180532 -33.201592) (xy 33.240468 -33.201592) (xy 33.29989 -33.209415)
			(xy 33.357783 -33.224928) (xy 33.413156 -33.247864) (xy 33.465062 -33.277831) (xy 33.512612 -33.314318)
			(xy 33.554992 -33.356698) (xy 33.591479 -33.404248) (xy 33.621446 -33.456154) (xy 33.644382 -33.511527)
			(xy 33.659895 -33.56942) (xy 33.667718 -33.628842) (xy 33.668208 -33.65881) (xy 33.668208 -34.520886)
			(xy 47.489364 -34.520886) (xy 47.489364 -33.657286) (xy 47.489854 -33.627302) (xy 47.497682 -33.567846)
			(xy 47.513203 -33.509921) (xy 47.536152 -33.454517) (xy 47.566136 -33.402583) (xy 47.602642 -33.355007)
			(xy 47.645047 -33.312602) (xy 47.692623 -33.276096) (xy 47.744557 -33.246112) (xy 47.799961 -33.223163)
			(xy 47.857886 -33.207642) (xy 47.917342 -33.199814) (xy 47.97731 -33.199814) (xy 48.036766 -33.207642)
			(xy 48.094691 -33.223163) (xy 48.150095 -33.246112) (xy 48.202029 -33.276096) (xy 48.249605 -33.312602)
			(xy 48.29201 -33.355007) (xy 48.328516 -33.402583) (xy 48.3585 -33.454517) (xy 48.381449 -33.509921)
			(xy 48.39697 -33.567846) (xy 48.404798 -33.627302) (xy 48.405288 -33.657286) (xy 48.405288 -34.520886)
			(xy 48.405263 -34.52241) (xy 58.75274 -34.52241) (xy 58.75274 -33.65881) (xy 58.75323 -33.628842)
			(xy 58.761053 -33.56942) (xy 58.776566 -33.511527) (xy 58.799502 -33.456154) (xy 58.829469 -33.404248)
			(xy 58.865956 -33.356698) (xy 58.908336 -33.314318) (xy 58.955886 -33.277831) (xy 59.007792 -33.247864)
			(xy 59.063165 -33.224928) (xy 59.121058 -33.209415) (xy 59.18048 -33.201592) (xy 59.240416 -33.201592)
			(xy 59.299838 -33.209415) (xy 59.357731 -33.224928) (xy 59.413104 -33.247864) (xy 59.46501 -33.277831)
			(xy 59.51256 -33.314318) (xy 59.55494 -33.356698) (xy 59.591427 -33.404248) (xy 59.621394 -33.456154)
			(xy 59.64433 -33.511527) (xy 59.659843 -33.56942) (xy 59.667666 -33.628842) (xy 59.668156 -33.65881)
			(xy 59.668156 -34.520886) (xy 73.489312 -34.520886) (xy 73.489312 -33.657286) (xy 73.489802 -33.627302)
			(xy 73.49763 -33.567846) (xy 73.513151 -33.509921) (xy 73.5361 -33.454517) (xy 73.566084 -33.402583)
			(xy 73.60259 -33.355007) (xy 73.644995 -33.312602) (xy 73.692571 -33.276096) (xy 73.744505 -33.246112)
			(xy 73.799909 -33.223163) (xy 73.857834 -33.207642) (xy 73.91729 -33.199814) (xy 73.977258 -33.199814)
			(xy 74.036714 -33.207642) (xy 74.094639 -33.223163) (xy 74.150043 -33.246112) (xy 74.201977 -33.276096)
			(xy 74.249553 -33.312602) (xy 74.291958 -33.355007) (xy 74.328464 -33.402583) (xy 74.358448 -33.454517)
			(xy 74.381397 -33.509921) (xy 74.396918 -33.567846) (xy 74.404746 -33.627302) (xy 74.405236 -33.657286)
			(xy 74.405236 -34.520886) (xy 74.405211 -34.52241) (xy 84.752688 -34.52241) (xy 84.752688 -33.65881)
			(xy 84.753178 -33.628842) (xy 84.761001 -33.56942) (xy 84.776514 -33.511527) (xy 84.79945 -33.456154)
			(xy 84.829417 -33.404248) (xy 84.865904 -33.356698) (xy 84.908284 -33.314318) (xy 84.955834 -33.277831)
			(xy 85.00774 -33.247864) (xy 85.063113 -33.224928) (xy 85.121006 -33.209415) (xy 85.180428 -33.201592)
			(xy 85.240364 -33.201592) (xy 85.299786 -33.209415) (xy 85.357679 -33.224928) (xy 85.413052 -33.247864)
			(xy 85.464958 -33.277831) (xy 85.512508 -33.314318) (xy 85.554888 -33.356698) (xy 85.591375 -33.404248)
			(xy 85.621342 -33.456154) (xy 85.644278 -33.511527) (xy 85.659791 -33.56942) (xy 85.667614 -33.628842)
			(xy 85.668104 -33.65881) (xy 85.668104 -34.520886) (xy 99.48926 -34.520886) (xy 99.48926 -33.657286)
			(xy 99.48975 -33.627302) (xy 99.497578 -33.567846) (xy 99.513099 -33.509921) (xy 99.536048 -33.454517)
			(xy 99.566032 -33.402583) (xy 99.602538 -33.355007) (xy 99.644943 -33.312602) (xy 99.692519 -33.276096)
			(xy 99.744453 -33.246112) (xy 99.799857 -33.223163) (xy 99.857782 -33.207642) (xy 99.917238 -33.199814)
			(xy 99.977206 -33.199814) (xy 100.036662 -33.207642) (xy 100.094587 -33.223163) (xy 100.149991 -33.246112)
			(xy 100.201925 -33.276096) (xy 100.249501 -33.312602) (xy 100.291906 -33.355007) (xy 100.328412 -33.402583)
			(xy 100.358396 -33.454517) (xy 100.381345 -33.509921) (xy 100.396866 -33.567846) (xy 100.404694 -33.627302)
			(xy 100.405184 -33.657286) (xy 100.405184 -34.520886) (xy 100.405159 -34.52241) (xy 122.852688 -34.52241)
			(xy 122.852688 -33.65881) (xy 122.853178 -33.628826) (xy 122.861006 -33.56937) (xy 122.876527 -33.511445)
			(xy 122.899476 -33.456041) (xy 122.92946 -33.404107) (xy 122.965966 -33.356531) (xy 123.008371 -33.314126)
			(xy 123.055947 -33.27762) (xy 123.107881 -33.247636) (xy 123.163285 -33.224687) (xy 123.22121 -33.209166)
			(xy 123.280666 -33.201338) (xy 123.340634 -33.201338) (xy 123.40009 -33.209166) (xy 123.458015 -33.224687)
			(xy 123.513419 -33.247636) (xy 123.565353 -33.27762) (xy 123.612929 -33.314126) (xy 123.655334 -33.356531)
			(xy 123.69184 -33.404107) (xy 123.721824 -33.456041) (xy 123.744773 -33.511445) (xy 123.760294 -33.56937)
			(xy 123.768122 -33.628826) (xy 123.768612 -33.65881) (xy 123.768612 -34.520886) (xy 137.589768 -34.520886)
			(xy 137.589768 -33.657286) (xy 137.590258 -33.627318) (xy 137.598081 -33.567896) (xy 137.613594 -33.510003)
			(xy 137.63653 -33.45463) (xy 137.666497 -33.402724) (xy 137.702984 -33.355174) (xy 137.745364 -33.312794)
			(xy 137.792914 -33.276307) (xy 137.84482 -33.24634) (xy 137.900193 -33.223404) (xy 137.958086 -33.207891)
			(xy 138.017508 -33.200068) (xy 138.077444 -33.200068) (xy 138.136866 -33.207891) (xy 138.194759 -33.223404)
			(xy 138.250132 -33.24634) (xy 138.302038 -33.276307) (xy 138.349588 -33.312794) (xy 138.391968 -33.355174)
			(xy 138.428455 -33.402724) (xy 138.458422 -33.45463) (xy 138.481358 -33.510003) (xy 138.496871 -33.567896)
			(xy 138.504694 -33.627318) (xy 138.505184 -33.657286) (xy 138.505184 -34.520886) (xy 138.505159 -34.52241)
			(xy 148.852636 -34.52241) (xy 148.852636 -33.65881) (xy 148.853126 -33.628826) (xy 148.860954 -33.56937)
			(xy 148.876475 -33.511445) (xy 148.899424 -33.456041) (xy 148.929408 -33.404107) (xy 148.965914 -33.356531)
			(xy 149.008319 -33.314126) (xy 149.055895 -33.27762) (xy 149.107829 -33.247636) (xy 149.163233 -33.224687)
			(xy 149.221158 -33.209166) (xy 149.280614 -33.201338) (xy 149.340582 -33.201338) (xy 149.400038 -33.209166)
			(xy 149.457963 -33.224687) (xy 149.513367 -33.247636) (xy 149.565301 -33.27762) (xy 149.612877 -33.314126)
			(xy 149.655282 -33.356531) (xy 149.691788 -33.404107) (xy 149.721772 -33.456041) (xy 149.744721 -33.511445)
			(xy 149.760242 -33.56937) (xy 149.76807 -33.628826) (xy 149.76856 -33.65881) (xy 149.76856 -34.520886)
			(xy 163.589716 -34.520886) (xy 163.589716 -33.657286) (xy 163.590206 -33.627318) (xy 163.598029 -33.567896)
			(xy 163.613542 -33.510003) (xy 163.636478 -33.45463) (xy 163.666445 -33.402724) (xy 163.702932 -33.355174)
			(xy 163.745312 -33.312794) (xy 163.792862 -33.276307) (xy 163.844768 -33.24634) (xy 163.900141 -33.223404)
			(xy 163.958034 -33.207891) (xy 164.017456 -33.200068) (xy 164.077392 -33.200068) (xy 164.136814 -33.207891)
			(xy 164.194707 -33.223404) (xy 164.25008 -33.24634) (xy 164.301986 -33.276307) (xy 164.349536 -33.312794)
			(xy 164.391916 -33.355174) (xy 164.428403 -33.402724) (xy 164.45837 -33.45463) (xy 164.481306 -33.510003)
			(xy 164.496819 -33.567896) (xy 164.504642 -33.627318) (xy 164.505132 -33.657286) (xy 164.505132 -34.520886)
			(xy 164.505107 -34.52241) (xy 174.852584 -34.52241) (xy 174.852584 -33.65881) (xy 174.853074 -33.628826)
			(xy 174.860902 -33.56937) (xy 174.876423 -33.511445) (xy 174.899372 -33.456041) (xy 174.929356 -33.404107)
			(xy 174.965862 -33.356531) (xy 175.008267 -33.314126) (xy 175.055843 -33.27762) (xy 175.107777 -33.247636)
			(xy 175.163181 -33.224687) (xy 175.221106 -33.209166) (xy 175.280562 -33.201338) (xy 175.34053 -33.201338)
			(xy 175.399986 -33.209166) (xy 175.457911 -33.224687) (xy 175.513315 -33.247636) (xy 175.565249 -33.27762)
			(xy 175.612825 -33.314126) (xy 175.65523 -33.356531) (xy 175.691736 -33.404107) (xy 175.72172 -33.456041)
			(xy 175.744669 -33.511445) (xy 175.76019 -33.56937) (xy 175.768018 -33.628826) (xy 175.768508 -33.65881)
			(xy 175.768508 -34.520886) (xy 189.589664 -34.520886) (xy 189.589664 -33.657286) (xy 189.590154 -33.627318)
			(xy 189.597977 -33.567896) (xy 189.61349 -33.510003) (xy 189.636426 -33.45463) (xy 189.666393 -33.402724)
			(xy 189.70288 -33.355174) (xy 189.74526 -33.312794) (xy 189.79281 -33.276307) (xy 189.844716 -33.24634)
			(xy 189.900089 -33.223404) (xy 189.957982 -33.207891) (xy 190.017404 -33.200068) (xy 190.07734 -33.200068)
			(xy 190.136762 -33.207891) (xy 190.194655 -33.223404) (xy 190.250028 -33.24634) (xy 190.301934 -33.276307)
			(xy 190.349484 -33.312794) (xy 190.391864 -33.355174) (xy 190.428351 -33.402724) (xy 190.458318 -33.45463)
			(xy 190.481254 -33.510003) (xy 190.496767 -33.567896) (xy 190.50459 -33.627318) (xy 190.50508 -33.657286)
			(xy 190.50508 -34.520886) (xy 190.505055 -34.52241) (xy 200.852532 -34.52241) (xy 200.852532 -33.65881)
			(xy 200.853022 -33.628826) (xy 200.86085 -33.56937) (xy 200.876371 -33.511445) (xy 200.89932 -33.456041)
			(xy 200.929304 -33.404107) (xy 200.96581 -33.356531) (xy 201.008215 -33.314126) (xy 201.055791 -33.27762)
			(xy 201.107725 -33.247636) (xy 201.163129 -33.224687) (xy 201.221054 -33.209166) (xy 201.28051 -33.201338)
			(xy 201.340478 -33.201338) (xy 201.399934 -33.209166) (xy 201.457859 -33.224687) (xy 201.513263 -33.247636)
			(xy 201.565197 -33.27762) (xy 201.612773 -33.314126) (xy 201.655178 -33.356531) (xy 201.691684 -33.404107)
			(xy 201.721668 -33.456041) (xy 201.744617 -33.511445) (xy 201.760138 -33.56937) (xy 201.767966 -33.628826)
			(xy 201.768456 -33.65881) (xy 201.768456 -34.520886) (xy 215.589612 -34.520886) (xy 215.589612 -33.657286)
			(xy 215.590102 -33.627318) (xy 215.597925 -33.567896) (xy 215.613438 -33.510003) (xy 215.636374 -33.45463)
			(xy 215.666341 -33.402724) (xy 215.702828 -33.355174) (xy 215.745208 -33.312794) (xy 215.792758 -33.276307)
			(xy 215.844664 -33.24634) (xy 215.900037 -33.223404) (xy 215.95793 -33.207891) (xy 216.017352 -33.200068)
			(xy 216.077288 -33.200068) (xy 216.13671 -33.207891) (xy 216.194603 -33.223404) (xy 216.249976 -33.24634)
			(xy 216.301882 -33.276307) (xy 216.349432 -33.312794) (xy 216.391812 -33.355174) (xy 216.428299 -33.402724)
			(xy 216.458266 -33.45463) (xy 216.481202 -33.510003) (xy 216.496715 -33.567896) (xy 216.504538 -33.627318)
			(xy 216.505028 -33.657286) (xy 216.505028 -34.520886) (xy 216.505003 -34.52241) (xy 238.952532 -34.52241)
			(xy 238.952532 -33.65881) (xy 238.953022 -33.628826) (xy 238.96085 -33.56937) (xy 238.976371 -33.511445)
			(xy 238.99932 -33.456041) (xy 239.029304 -33.404107) (xy 239.06581 -33.356531) (xy 239.108215 -33.314126)
			(xy 239.155791 -33.27762) (xy 239.207725 -33.247636) (xy 239.263129 -33.224687) (xy 239.321054 -33.209166)
			(xy 239.38051 -33.201338) (xy 239.440478 -33.201338) (xy 239.499934 -33.209166) (xy 239.557859 -33.224687)
			(xy 239.613263 -33.247636) (xy 239.665197 -33.27762) (xy 239.712773 -33.314126) (xy 239.755178 -33.356531)
			(xy 239.791684 -33.404107) (xy 239.821668 -33.456041) (xy 239.844617 -33.511445) (xy 239.860138 -33.56937)
			(xy 239.867966 -33.628826) (xy 239.868456 -33.65881) (xy 239.868456 -34.520886) (xy 253.689612 -34.520886)
			(xy 253.689612 -33.657286) (xy 253.690102 -33.627318) (xy 253.697925 -33.567896) (xy 253.713438 -33.510003)
			(xy 253.736374 -33.45463) (xy 253.766341 -33.402724) (xy 253.802828 -33.355174) (xy 253.845208 -33.312794)
			(xy 253.892758 -33.276307) (xy 253.944664 -33.24634) (xy 254.000037 -33.223404) (xy 254.05793 -33.207891)
			(xy 254.117352 -33.200068) (xy 254.177288 -33.200068) (xy 254.23671 -33.207891) (xy 254.294603 -33.223404)
			(xy 254.349976 -33.24634) (xy 254.401882 -33.276307) (xy 254.449432 -33.312794) (xy 254.491812 -33.355174)
			(xy 254.528299 -33.402724) (xy 254.558266 -33.45463) (xy 254.581202 -33.510003) (xy 254.596715 -33.567896)
			(xy 254.604538 -33.627318) (xy 254.605028 -33.657286) (xy 254.605028 -34.520886) (xy 254.605003 -34.52241)
			(xy 264.95248 -34.52241) (xy 264.95248 -33.65881) (xy 264.95297 -33.628826) (xy 264.960798 -33.56937)
			(xy 264.976319 -33.511445) (xy 264.999268 -33.456041) (xy 265.029252 -33.404107) (xy 265.065758 -33.356531)
			(xy 265.108163 -33.314126) (xy 265.155739 -33.27762) (xy 265.207673 -33.247636) (xy 265.263077 -33.224687)
			(xy 265.321002 -33.209166) (xy 265.380458 -33.201338) (xy 265.440426 -33.201338) (xy 265.499882 -33.209166)
			(xy 265.557807 -33.224687) (xy 265.613211 -33.247636) (xy 265.665145 -33.27762) (xy 265.712721 -33.314126)
			(xy 265.755126 -33.356531) (xy 265.791632 -33.404107) (xy 265.821616 -33.456041) (xy 265.844565 -33.511445)
			(xy 265.860086 -33.56937) (xy 265.867914 -33.628826) (xy 265.868404 -33.65881) (xy 265.868404 -34.520886)
			(xy 279.68956 -34.520886) (xy 279.68956 -33.657286) (xy 279.69005 -33.627318) (xy 279.697873 -33.567896)
			(xy 279.713386 -33.510003) (xy 279.736322 -33.45463) (xy 279.766289 -33.402724) (xy 279.802776 -33.355174)
			(xy 279.845156 -33.312794) (xy 279.892706 -33.276307) (xy 279.944612 -33.24634) (xy 279.999985 -33.223404)
			(xy 280.057878 -33.207891) (xy 280.1173 -33.200068) (xy 280.177236 -33.200068) (xy 280.236658 -33.207891)
			(xy 280.294551 -33.223404) (xy 280.349924 -33.24634) (xy 280.40183 -33.276307) (xy 280.44938 -33.312794)
			(xy 280.49176 -33.355174) (xy 280.528247 -33.402724) (xy 280.558214 -33.45463) (xy 280.58115 -33.510003)
			(xy 280.596663 -33.567896) (xy 280.604486 -33.627318) (xy 280.604976 -33.657286) (xy 280.604976 -34.520886)
			(xy 280.604951 -34.52241) (xy 290.952428 -34.52241) (xy 290.952428 -33.65881) (xy 290.952918 -33.628826)
			(xy 290.960746 -33.56937) (xy 290.976267 -33.511445) (xy 290.999216 -33.456041) (xy 291.0292 -33.404107)
			(xy 291.065706 -33.356531) (xy 291.108111 -33.314126) (xy 291.155687 -33.27762) (xy 291.207621 -33.247636)
			(xy 291.263025 -33.224687) (xy 291.32095 -33.209166) (xy 291.380406 -33.201338) (xy 291.440374 -33.201338)
			(xy 291.49983 -33.209166) (xy 291.557755 -33.224687) (xy 291.613159 -33.247636) (xy 291.665093 -33.27762)
			(xy 291.712669 -33.314126) (xy 291.755074 -33.356531) (xy 291.79158 -33.404107) (xy 291.821564 -33.456041)
			(xy 291.844513 -33.511445) (xy 291.860034 -33.56937) (xy 291.867862 -33.628826) (xy 291.868352 -33.65881)
			(xy 291.868352 -34.520886) (xy 305.689508 -34.520886) (xy 305.689508 -33.657286) (xy 305.689998 -33.627318)
			(xy 305.697821 -33.567896) (xy 305.713334 -33.510003) (xy 305.73627 -33.45463) (xy 305.766237 -33.402724)
			(xy 305.802724 -33.355174) (xy 305.845104 -33.312794) (xy 305.892654 -33.276307) (xy 305.94456 -33.24634)
			(xy 305.999933 -33.223404) (xy 306.057826 -33.207891) (xy 306.117248 -33.200068) (xy 306.177184 -33.200068)
			(xy 306.236606 -33.207891) (xy 306.294499 -33.223404) (xy 306.349872 -33.24634) (xy 306.401778 -33.276307)
			(xy 306.449328 -33.312794) (xy 306.491708 -33.355174) (xy 306.528195 -33.402724) (xy 306.558162 -33.45463)
			(xy 306.581098 -33.510003) (xy 306.596611 -33.567896) (xy 306.604434 -33.627318) (xy 306.604924 -33.657286)
			(xy 306.604924 -34.520886) (xy 306.604899 -34.52241) (xy 316.952376 -34.52241) (xy 316.952376 -33.65881)
			(xy 316.952866 -33.628826) (xy 316.960694 -33.56937) (xy 316.976215 -33.511445) (xy 316.999164 -33.456041)
			(xy 317.029148 -33.404107) (xy 317.065654 -33.356531) (xy 317.108059 -33.314126) (xy 317.155635 -33.27762)
			(xy 317.207569 -33.247636) (xy 317.262973 -33.224687) (xy 317.320898 -33.209166) (xy 317.380354 -33.201338)
			(xy 317.440322 -33.201338) (xy 317.499778 -33.209166) (xy 317.557703 -33.224687) (xy 317.613107 -33.247636)
			(xy 317.665041 -33.27762) (xy 317.712617 -33.314126) (xy 317.755022 -33.356531) (xy 317.791528 -33.404107)
			(xy 317.821512 -33.456041) (xy 317.844461 -33.511445) (xy 317.859982 -33.56937) (xy 317.86781 -33.628826)
			(xy 317.8683 -33.65881) (xy 317.8683 -34.520886) (xy 331.689456 -34.520886) (xy 331.689456 -33.657286)
			(xy 331.689946 -33.627318) (xy 331.697769 -33.567896) (xy 331.713282 -33.510003) (xy 331.736218 -33.45463)
			(xy 331.766185 -33.402724) (xy 331.802672 -33.355174) (xy 331.845052 -33.312794) (xy 331.892602 -33.276307)
			(xy 331.944508 -33.24634) (xy 331.999881 -33.223404) (xy 332.057774 -33.207891) (xy 332.117196 -33.200068)
			(xy 332.177132 -33.200068) (xy 332.236554 -33.207891) (xy 332.294447 -33.223404) (xy 332.34982 -33.24634)
			(xy 332.401726 -33.276307) (xy 332.449276 -33.312794) (xy 332.491656 -33.355174) (xy 332.528143 -33.402724)
			(xy 332.55811 -33.45463) (xy 332.581046 -33.510003) (xy 332.596559 -33.567896) (xy 332.604382 -33.627318)
			(xy 332.604872 -33.657286) (xy 332.604872 -34.520886) (xy 332.604847 -34.52241) (xy 355.052884 -34.52241)
			(xy 355.052884 -33.65881) (xy 355.053374 -33.628842) (xy 355.061197 -33.56942) (xy 355.07671 -33.511527)
			(xy 355.099646 -33.456154) (xy 355.129613 -33.404248) (xy 355.1661 -33.356698) (xy 355.20848 -33.314318)
			(xy 355.25603 -33.277831) (xy 355.307936 -33.247864) (xy 355.363309 -33.224928) (xy 355.421202 -33.209415)
			(xy 355.480624 -33.201592) (xy 355.54056 -33.201592) (xy 355.599982 -33.209415) (xy 355.657875 -33.224928)
			(xy 355.713248 -33.247864) (xy 355.765154 -33.277831) (xy 355.812704 -33.314318) (xy 355.855084 -33.356698)
			(xy 355.891571 -33.404248) (xy 355.921538 -33.456154) (xy 355.944474 -33.511527) (xy 355.959987 -33.56942)
			(xy 355.96781 -33.628842) (xy 355.9683 -33.65881) (xy 355.9683 -34.520886) (xy 369.789456 -34.520886)
			(xy 369.789456 -33.657286) (xy 369.789946 -33.627302) (xy 369.797774 -33.567846) (xy 369.813295 -33.509921)
			(xy 369.836244 -33.454517) (xy 369.866228 -33.402583) (xy 369.902734 -33.355007) (xy 369.945139 -33.312602)
			(xy 369.992715 -33.276096) (xy 370.044649 -33.246112) (xy 370.100053 -33.223163) (xy 370.157978 -33.207642)
			(xy 370.217434 -33.199814) (xy 370.277402 -33.199814) (xy 370.336858 -33.207642) (xy 370.394783 -33.223163)
			(xy 370.450187 -33.246112) (xy 370.502121 -33.276096) (xy 370.549697 -33.312602) (xy 370.592102 -33.355007)
			(xy 370.628608 -33.402583) (xy 370.658592 -33.454517) (xy 370.681541 -33.509921) (xy 370.697062 -33.567846)
			(xy 370.70489 -33.627302) (xy 370.70538 -33.657286) (xy 370.70538 -34.520886) (xy 370.705355 -34.52241)
			(xy 381.052832 -34.52241) (xy 381.052832 -33.65881) (xy 381.053322 -33.628842) (xy 381.061145 -33.56942)
			(xy 381.076658 -33.511527) (xy 381.099594 -33.456154) (xy 381.129561 -33.404248) (xy 381.166048 -33.356698)
			(xy 381.208428 -33.314318) (xy 381.255978 -33.277831) (xy 381.307884 -33.247864) (xy 381.363257 -33.224928)
			(xy 381.42115 -33.209415) (xy 381.480572 -33.201592) (xy 381.540508 -33.201592) (xy 381.59993 -33.209415)
			(xy 381.657823 -33.224928) (xy 381.713196 -33.247864) (xy 381.765102 -33.277831) (xy 381.812652 -33.314318)
			(xy 381.855032 -33.356698) (xy 381.891519 -33.404248) (xy 381.921486 -33.456154) (xy 381.944422 -33.511527)
			(xy 381.959935 -33.56942) (xy 381.967758 -33.628842) (xy 381.968248 -33.65881) (xy 381.968248 -34.520886)
			(xy 395.789404 -34.520886) (xy 395.789404 -33.657286) (xy 395.789894 -33.627302) (xy 395.797722 -33.567846)
			(xy 395.813243 -33.509921) (xy 395.836192 -33.454517) (xy 395.866176 -33.402583) (xy 395.902682 -33.355007)
			(xy 395.945087 -33.312602) (xy 395.992663 -33.276096) (xy 396.044597 -33.246112) (xy 396.100001 -33.223163)
			(xy 396.157926 -33.207642) (xy 396.217382 -33.199814) (xy 396.27735 -33.199814) (xy 396.336806 -33.207642)
			(xy 396.394731 -33.223163) (xy 396.450135 -33.246112) (xy 396.502069 -33.276096) (xy 396.549645 -33.312602)
			(xy 396.59205 -33.355007) (xy 396.628556 -33.402583) (xy 396.65854 -33.454517) (xy 396.681489 -33.509921)
			(xy 396.69701 -33.567846) (xy 396.704838 -33.627302) (xy 396.705328 -33.657286) (xy 396.705328 -34.520886)
			(xy 396.705303 -34.52241) (xy 407.05278 -34.52241) (xy 407.05278 -33.65881) (xy 407.05327 -33.628842)
			(xy 407.061093 -33.56942) (xy 407.076606 -33.511527) (xy 407.099542 -33.456154) (xy 407.129509 -33.404248)
			(xy 407.165996 -33.356698) (xy 407.208376 -33.314318) (xy 407.255926 -33.277831) (xy 407.307832 -33.247864)
			(xy 407.363205 -33.224928) (xy 407.421098 -33.209415) (xy 407.48052 -33.201592) (xy 407.540456 -33.201592)
			(xy 407.599878 -33.209415) (xy 407.657771 -33.224928) (xy 407.713144 -33.247864) (xy 407.76505 -33.277831)
			(xy 407.8126 -33.314318) (xy 407.85498 -33.356698) (xy 407.891467 -33.404248) (xy 407.921434 -33.456154)
			(xy 407.94437 -33.511527) (xy 407.959883 -33.56942) (xy 407.967706 -33.628842) (xy 407.968196 -33.65881)
			(xy 407.968196 -34.520886) (xy 421.789352 -34.520886) (xy 421.789352 -33.657286) (xy 421.789842 -33.627302)
			(xy 421.79767 -33.567846) (xy 421.813191 -33.509921) (xy 421.83614 -33.454517) (xy 421.866124 -33.402583)
			(xy 421.90263 -33.355007) (xy 421.945035 -33.312602) (xy 421.992611 -33.276096) (xy 422.044545 -33.246112)
			(xy 422.099949 -33.223163) (xy 422.157874 -33.207642) (xy 422.21733 -33.199814) (xy 422.277298 -33.199814)
			(xy 422.336754 -33.207642) (xy 422.394679 -33.223163) (xy 422.450083 -33.246112) (xy 422.502017 -33.276096)
			(xy 422.549593 -33.312602) (xy 422.591998 -33.355007) (xy 422.628504 -33.402583) (xy 422.658488 -33.454517)
			(xy 422.681437 -33.509921) (xy 422.696958 -33.567846) (xy 422.704786 -33.627302) (xy 422.705276 -33.657286)
			(xy 422.705276 -34.520886) (xy 422.705251 -34.52241) (xy 433.052728 -34.52241) (xy 433.052728 -33.65881)
			(xy 433.053218 -33.628842) (xy 433.061041 -33.56942) (xy 433.076554 -33.511527) (xy 433.09949 -33.456154)
			(xy 433.129457 -33.404248) (xy 433.165944 -33.356698) (xy 433.208324 -33.314318) (xy 433.255874 -33.277831)
			(xy 433.30778 -33.247864) (xy 433.363153 -33.224928) (xy 433.421046 -33.209415) (xy 433.480468 -33.201592)
			(xy 433.540404 -33.201592) (xy 433.599826 -33.209415) (xy 433.657719 -33.224928) (xy 433.713092 -33.247864)
			(xy 433.764998 -33.277831) (xy 433.812548 -33.314318) (xy 433.854928 -33.356698) (xy 433.891415 -33.404248)
			(xy 433.921382 -33.456154) (xy 433.944318 -33.511527) (xy 433.959831 -33.56942) (xy 433.967654 -33.628842)
			(xy 433.968144 -33.65881) (xy 433.968144 -34.520886) (xy 447.7893 -34.520886) (xy 447.7893 -33.657286)
			(xy 447.78979 -33.627302) (xy 447.797618 -33.567846) (xy 447.813139 -33.509921) (xy 447.836088 -33.454517)
			(xy 447.866072 -33.402583) (xy 447.902578 -33.355007) (xy 447.944983 -33.312602) (xy 447.992559 -33.276096)
			(xy 448.044493 -33.246112) (xy 448.099897 -33.223163) (xy 448.157822 -33.207642) (xy 448.217278 -33.199814)
			(xy 448.277246 -33.199814) (xy 448.336702 -33.207642) (xy 448.394627 -33.223163) (xy 448.450031 -33.246112)
			(xy 448.501965 -33.276096) (xy 448.549541 -33.312602) (xy 448.591946 -33.355007) (xy 448.628452 -33.402583)
			(xy 448.658436 -33.454517) (xy 448.681385 -33.509921) (xy 448.696906 -33.567846) (xy 448.704734 -33.627302)
			(xy 448.705224 -33.657286) (xy 448.705224 -34.520886) (xy 448.704734 -34.55087) (xy 448.696906 -34.610326)
			(xy 448.681385 -34.668251) (xy 448.658436 -34.723655) (xy 448.628452 -34.775589) (xy 448.591946 -34.823165)
			(xy 448.549541 -34.86557) (xy 448.501965 -34.902076) (xy 448.450031 -34.93206) (xy 448.394627 -34.955009)
			(xy 448.336702 -34.97053) (xy 448.277246 -34.978358) (xy 448.217278 -34.978358) (xy 448.157822 -34.97053)
			(xy 448.099897 -34.955009) (xy 448.044493 -34.93206) (xy 447.992559 -34.902076) (xy 447.944983 -34.86557)
			(xy 447.902578 -34.823165) (xy 447.866072 -34.775589) (xy 447.836088 -34.723655) (xy 447.813139 -34.668251)
			(xy 447.797618 -34.610326) (xy 447.78979 -34.55087) (xy 447.7893 -34.520886) (xy 433.968144 -34.520886)
			(xy 433.968144 -34.52241) (xy 433.967654 -34.552378) (xy 433.959831 -34.6118) (xy 433.944318 -34.669693)
			(xy 433.921382 -34.725066) (xy 433.891415 -34.776972) (xy 433.854928 -34.824522) (xy 433.812548 -34.866902)
			(xy 433.764998 -34.903389) (xy 433.713092 -34.933356) (xy 433.657719 -34.956292) (xy 433.599826 -34.971805)
			(xy 433.540404 -34.979628) (xy 433.480468 -34.979628) (xy 433.421046 -34.971805) (xy 433.363153 -34.956292)
			(xy 433.30778 -34.933356) (xy 433.255874 -34.903389) (xy 433.208324 -34.866902) (xy 433.165944 -34.824522)
			(xy 433.129457 -34.776972) (xy 433.09949 -34.725066) (xy 433.076554 -34.669693) (xy 433.061041 -34.6118)
			(xy 433.053218 -34.552378) (xy 433.052728 -34.52241) (xy 422.705251 -34.52241) (xy 422.704786 -34.55087)
			(xy 422.696958 -34.610326) (xy 422.681437 -34.668251) (xy 422.658488 -34.723655) (xy 422.628504 -34.775589)
			(xy 422.591998 -34.823165) (xy 422.549593 -34.86557) (xy 422.502017 -34.902076) (xy 422.450083 -34.93206)
			(xy 422.394679 -34.955009) (xy 422.336754 -34.97053) (xy 422.277298 -34.978358) (xy 422.21733 -34.978358)
			(xy 422.157874 -34.97053) (xy 422.099949 -34.955009) (xy 422.044545 -34.93206) (xy 421.992611 -34.902076)
			(xy 421.945035 -34.86557) (xy 421.90263 -34.823165) (xy 421.866124 -34.775589) (xy 421.83614 -34.723655)
			(xy 421.813191 -34.668251) (xy 421.79767 -34.610326) (xy 421.789842 -34.55087) (xy 421.789352 -34.520886)
			(xy 407.968196 -34.520886) (xy 407.968196 -34.52241) (xy 407.967706 -34.552378) (xy 407.959883 -34.6118)
			(xy 407.94437 -34.669693) (xy 407.921434 -34.725066) (xy 407.891467 -34.776972) (xy 407.85498 -34.824522)
			(xy 407.8126 -34.866902) (xy 407.76505 -34.903389) (xy 407.713144 -34.933356) (xy 407.657771 -34.956292)
			(xy 407.599878 -34.971805) (xy 407.540456 -34.979628) (xy 407.48052 -34.979628) (xy 407.421098 -34.971805)
			(xy 407.363205 -34.956292) (xy 407.307832 -34.933356) (xy 407.255926 -34.903389) (xy 407.208376 -34.866902)
			(xy 407.165996 -34.824522) (xy 407.129509 -34.776972) (xy 407.099542 -34.725066) (xy 407.076606 -34.669693)
			(xy 407.061093 -34.6118) (xy 407.05327 -34.552378) (xy 407.05278 -34.52241) (xy 396.705303 -34.52241)
			(xy 396.704838 -34.55087) (xy 396.69701 -34.610326) (xy 396.681489 -34.668251) (xy 396.65854 -34.723655)
			(xy 396.628556 -34.775589) (xy 396.59205 -34.823165) (xy 396.549645 -34.86557) (xy 396.502069 -34.902076)
			(xy 396.450135 -34.93206) (xy 396.394731 -34.955009) (xy 396.336806 -34.97053) (xy 396.27735 -34.978358)
			(xy 396.217382 -34.978358) (xy 396.157926 -34.97053) (xy 396.100001 -34.955009) (xy 396.044597 -34.93206)
			(xy 395.992663 -34.902076) (xy 395.945087 -34.86557) (xy 395.902682 -34.823165) (xy 395.866176 -34.775589)
			(xy 395.836192 -34.723655) (xy 395.813243 -34.668251) (xy 395.797722 -34.610326) (xy 395.789894 -34.55087)
			(xy 395.789404 -34.520886) (xy 381.968248 -34.520886) (xy 381.968248 -34.52241) (xy 381.967758 -34.552378)
			(xy 381.959935 -34.6118) (xy 381.944422 -34.669693) (xy 381.921486 -34.725066) (xy 381.891519 -34.776972)
			(xy 381.855032 -34.824522) (xy 381.812652 -34.866902) (xy 381.765102 -34.903389) (xy 381.713196 -34.933356)
			(xy 381.657823 -34.956292) (xy 381.59993 -34.971805) (xy 381.540508 -34.979628) (xy 381.480572 -34.979628)
			(xy 381.42115 -34.971805) (xy 381.363257 -34.956292) (xy 381.307884 -34.933356) (xy 381.255978 -34.903389)
			(xy 381.208428 -34.866902) (xy 381.166048 -34.824522) (xy 381.129561 -34.776972) (xy 381.099594 -34.725066)
			(xy 381.076658 -34.669693) (xy 381.061145 -34.6118) (xy 381.053322 -34.552378) (xy 381.052832 -34.52241)
			(xy 370.705355 -34.52241) (xy 370.70489 -34.55087) (xy 370.697062 -34.610326) (xy 370.681541 -34.668251)
			(xy 370.658592 -34.723655) (xy 370.628608 -34.775589) (xy 370.592102 -34.823165) (xy 370.549697 -34.86557)
			(xy 370.502121 -34.902076) (xy 370.450187 -34.93206) (xy 370.394783 -34.955009) (xy 370.336858 -34.97053)
			(xy 370.277402 -34.978358) (xy 370.217434 -34.978358) (xy 370.157978 -34.97053) (xy 370.100053 -34.955009)
			(xy 370.044649 -34.93206) (xy 369.992715 -34.902076) (xy 369.945139 -34.86557) (xy 369.902734 -34.823165)
			(xy 369.866228 -34.775589) (xy 369.836244 -34.723655) (xy 369.813295 -34.668251) (xy 369.797774 -34.610326)
			(xy 369.789946 -34.55087) (xy 369.789456 -34.520886) (xy 355.9683 -34.520886) (xy 355.9683 -34.52241)
			(xy 355.96781 -34.552378) (xy 355.959987 -34.6118) (xy 355.944474 -34.669693) (xy 355.921538 -34.725066)
			(xy 355.891571 -34.776972) (xy 355.855084 -34.824522) (xy 355.812704 -34.866902) (xy 355.765154 -34.903389)
			(xy 355.713248 -34.933356) (xy 355.657875 -34.956292) (xy 355.599982 -34.971805) (xy 355.54056 -34.979628)
			(xy 355.480624 -34.979628) (xy 355.421202 -34.971805) (xy 355.363309 -34.956292) (xy 355.307936 -34.933356)
			(xy 355.25603 -34.903389) (xy 355.20848 -34.866902) (xy 355.1661 -34.824522) (xy 355.129613 -34.776972)
			(xy 355.099646 -34.725066) (xy 355.07671 -34.669693) (xy 355.061197 -34.6118) (xy 355.053374 -34.552378)
			(xy 355.052884 -34.52241) (xy 332.604847 -34.52241) (xy 332.604382 -34.550854) (xy 332.596559 -34.610276)
			(xy 332.581046 -34.668169) (xy 332.55811 -34.723542) (xy 332.528143 -34.775448) (xy 332.491656 -34.822998)
			(xy 332.449276 -34.865378) (xy 332.401726 -34.901865) (xy 332.34982 -34.931832) (xy 332.294447 -34.954768)
			(xy 332.236554 -34.970281) (xy 332.177132 -34.978104) (xy 332.117196 -34.978104) (xy 332.057774 -34.970281)
			(xy 331.999881 -34.954768) (xy 331.944508 -34.931832) (xy 331.892602 -34.901865) (xy 331.845052 -34.865378)
			(xy 331.802672 -34.822998) (xy 331.766185 -34.775448) (xy 331.736218 -34.723542) (xy 331.713282 -34.668169)
			(xy 331.697769 -34.610276) (xy 331.689946 -34.550854) (xy 331.689456 -34.520886) (xy 317.8683 -34.520886)
			(xy 317.8683 -34.52241) (xy 317.86781 -34.552394) (xy 317.859982 -34.61185) (xy 317.844461 -34.669775)
			(xy 317.821512 -34.725179) (xy 317.791528 -34.777113) (xy 317.755022 -34.824689) (xy 317.712617 -34.867094)
			(xy 317.665041 -34.9036) (xy 317.613107 -34.933584) (xy 317.557703 -34.956533) (xy 317.499778 -34.972054)
			(xy 317.440322 -34.979882) (xy 317.380354 -34.979882) (xy 317.320898 -34.972054) (xy 317.262973 -34.956533)
			(xy 317.207569 -34.933584) (xy 317.155635 -34.9036) (xy 317.108059 -34.867094) (xy 317.065654 -34.824689)
			(xy 317.029148 -34.777113) (xy 316.999164 -34.725179) (xy 316.976215 -34.669775) (xy 316.960694 -34.61185)
			(xy 316.952866 -34.552394) (xy 316.952376 -34.52241) (xy 306.604899 -34.52241) (xy 306.604434 -34.550854)
			(xy 306.596611 -34.610276) (xy 306.581098 -34.668169) (xy 306.558162 -34.723542) (xy 306.528195 -34.775448)
			(xy 306.491708 -34.822998) (xy 306.449328 -34.865378) (xy 306.401778 -34.901865) (xy 306.349872 -34.931832)
			(xy 306.294499 -34.954768) (xy 306.236606 -34.970281) (xy 306.177184 -34.978104) (xy 306.117248 -34.978104)
			(xy 306.057826 -34.970281) (xy 305.999933 -34.954768) (xy 305.94456 -34.931832) (xy 305.892654 -34.901865)
			(xy 305.845104 -34.865378) (xy 305.802724 -34.822998) (xy 305.766237 -34.775448) (xy 305.73627 -34.723542)
			(xy 305.713334 -34.668169) (xy 305.697821 -34.610276) (xy 305.689998 -34.550854) (xy 305.689508 -34.520886)
			(xy 291.868352 -34.520886) (xy 291.868352 -34.52241) (xy 291.867862 -34.552394) (xy 291.860034 -34.61185)
			(xy 291.844513 -34.669775) (xy 291.821564 -34.725179) (xy 291.79158 -34.777113) (xy 291.755074 -34.824689)
			(xy 291.712669 -34.867094) (xy 291.665093 -34.9036) (xy 291.613159 -34.933584) (xy 291.557755 -34.956533)
			(xy 291.49983 -34.972054) (xy 291.440374 -34.979882) (xy 291.380406 -34.979882) (xy 291.32095 -34.972054)
			(xy 291.263025 -34.956533) (xy 291.207621 -34.933584) (xy 291.155687 -34.9036) (xy 291.108111 -34.867094)
			(xy 291.065706 -34.824689) (xy 291.0292 -34.777113) (xy 290.999216 -34.725179) (xy 290.976267 -34.669775)
			(xy 290.960746 -34.61185) (xy 290.952918 -34.552394) (xy 290.952428 -34.52241) (xy 280.604951 -34.52241)
			(xy 280.604486 -34.550854) (xy 280.596663 -34.610276) (xy 280.58115 -34.668169) (xy 280.558214 -34.723542)
			(xy 280.528247 -34.775448) (xy 280.49176 -34.822998) (xy 280.44938 -34.865378) (xy 280.40183 -34.901865)
			(xy 280.349924 -34.931832) (xy 280.294551 -34.954768) (xy 280.236658 -34.970281) (xy 280.177236 -34.978104)
			(xy 280.1173 -34.978104) (xy 280.057878 -34.970281) (xy 279.999985 -34.954768) (xy 279.944612 -34.931832)
			(xy 279.892706 -34.901865) (xy 279.845156 -34.865378) (xy 279.802776 -34.822998) (xy 279.766289 -34.775448)
			(xy 279.736322 -34.723542) (xy 279.713386 -34.668169) (xy 279.697873 -34.610276) (xy 279.69005 -34.550854)
			(xy 279.68956 -34.520886) (xy 265.868404 -34.520886) (xy 265.868404 -34.52241) (xy 265.867914 -34.552394)
			(xy 265.860086 -34.61185) (xy 265.844565 -34.669775) (xy 265.821616 -34.725179) (xy 265.791632 -34.777113)
			(xy 265.755126 -34.824689) (xy 265.712721 -34.867094) (xy 265.665145 -34.9036) (xy 265.613211 -34.933584)
			(xy 265.557807 -34.956533) (xy 265.499882 -34.972054) (xy 265.440426 -34.979882) (xy 265.380458 -34.979882)
			(xy 265.321002 -34.972054) (xy 265.263077 -34.956533) (xy 265.207673 -34.933584) (xy 265.155739 -34.9036)
			(xy 265.108163 -34.867094) (xy 265.065758 -34.824689) (xy 265.029252 -34.777113) (xy 264.999268 -34.725179)
			(xy 264.976319 -34.669775) (xy 264.960798 -34.61185) (xy 264.95297 -34.552394) (xy 264.95248 -34.52241)
			(xy 254.605003 -34.52241) (xy 254.604538 -34.550854) (xy 254.596715 -34.610276) (xy 254.581202 -34.668169)
			(xy 254.558266 -34.723542) (xy 254.528299 -34.775448) (xy 254.491812 -34.822998) (xy 254.449432 -34.865378)
			(xy 254.401882 -34.901865) (xy 254.349976 -34.931832) (xy 254.294603 -34.954768) (xy 254.23671 -34.970281)
			(xy 254.177288 -34.978104) (xy 254.117352 -34.978104) (xy 254.05793 -34.970281) (xy 254.000037 -34.954768)
			(xy 253.944664 -34.931832) (xy 253.892758 -34.901865) (xy 253.845208 -34.865378) (xy 253.802828 -34.822998)
			(xy 253.766341 -34.775448) (xy 253.736374 -34.723542) (xy 253.713438 -34.668169) (xy 253.697925 -34.610276)
			(xy 253.690102 -34.550854) (xy 253.689612 -34.520886) (xy 239.868456 -34.520886) (xy 239.868456 -34.52241)
			(xy 239.867966 -34.552394) (xy 239.860138 -34.61185) (xy 239.844617 -34.669775) (xy 239.821668 -34.725179)
			(xy 239.791684 -34.777113) (xy 239.755178 -34.824689) (xy 239.712773 -34.867094) (xy 239.665197 -34.9036)
			(xy 239.613263 -34.933584) (xy 239.557859 -34.956533) (xy 239.499934 -34.972054) (xy 239.440478 -34.979882)
			(xy 239.38051 -34.979882) (xy 239.321054 -34.972054) (xy 239.263129 -34.956533) (xy 239.207725 -34.933584)
			(xy 239.155791 -34.9036) (xy 239.108215 -34.867094) (xy 239.06581 -34.824689) (xy 239.029304 -34.777113)
			(xy 238.99932 -34.725179) (xy 238.976371 -34.669775) (xy 238.96085 -34.61185) (xy 238.953022 -34.552394)
			(xy 238.952532 -34.52241) (xy 216.505003 -34.52241) (xy 216.504538 -34.550854) (xy 216.496715 -34.610276)
			(xy 216.481202 -34.668169) (xy 216.458266 -34.723542) (xy 216.428299 -34.775448) (xy 216.391812 -34.822998)
			(xy 216.349432 -34.865378) (xy 216.301882 -34.901865) (xy 216.249976 -34.931832) (xy 216.194603 -34.954768)
			(xy 216.13671 -34.970281) (xy 216.077288 -34.978104) (xy 216.017352 -34.978104) (xy 215.95793 -34.970281)
			(xy 215.900037 -34.954768) (xy 215.844664 -34.931832) (xy 215.792758 -34.901865) (xy 215.745208 -34.865378)
			(xy 215.702828 -34.822998) (xy 215.666341 -34.775448) (xy 215.636374 -34.723542) (xy 215.613438 -34.668169)
			(xy 215.597925 -34.610276) (xy 215.590102 -34.550854) (xy 215.589612 -34.520886) (xy 201.768456 -34.520886)
			(xy 201.768456 -34.52241) (xy 201.767966 -34.552394) (xy 201.760138 -34.61185) (xy 201.744617 -34.669775)
			(xy 201.721668 -34.725179) (xy 201.691684 -34.777113) (xy 201.655178 -34.824689) (xy 201.612773 -34.867094)
			(xy 201.565197 -34.9036) (xy 201.513263 -34.933584) (xy 201.457859 -34.956533) (xy 201.399934 -34.972054)
			(xy 201.340478 -34.979882) (xy 201.28051 -34.979882) (xy 201.221054 -34.972054) (xy 201.163129 -34.956533)
			(xy 201.107725 -34.933584) (xy 201.055791 -34.9036) (xy 201.008215 -34.867094) (xy 200.96581 -34.824689)
			(xy 200.929304 -34.777113) (xy 200.89932 -34.725179) (xy 200.876371 -34.669775) (xy 200.86085 -34.61185)
			(xy 200.853022 -34.552394) (xy 200.852532 -34.52241) (xy 190.505055 -34.52241) (xy 190.50459 -34.550854)
			(xy 190.496767 -34.610276) (xy 190.481254 -34.668169) (xy 190.458318 -34.723542) (xy 190.428351 -34.775448)
			(xy 190.391864 -34.822998) (xy 190.349484 -34.865378) (xy 190.301934 -34.901865) (xy 190.250028 -34.931832)
			(xy 190.194655 -34.954768) (xy 190.136762 -34.970281) (xy 190.07734 -34.978104) (xy 190.017404 -34.978104)
			(xy 189.957982 -34.970281) (xy 189.900089 -34.954768) (xy 189.844716 -34.931832) (xy 189.79281 -34.901865)
			(xy 189.74526 -34.865378) (xy 189.70288 -34.822998) (xy 189.666393 -34.775448) (xy 189.636426 -34.723542)
			(xy 189.61349 -34.668169) (xy 189.597977 -34.610276) (xy 189.590154 -34.550854) (xy 189.589664 -34.520886)
			(xy 175.768508 -34.520886) (xy 175.768508 -34.52241) (xy 175.768018 -34.552394) (xy 175.76019 -34.61185)
			(xy 175.744669 -34.669775) (xy 175.72172 -34.725179) (xy 175.691736 -34.777113) (xy 175.65523 -34.824689)
			(xy 175.612825 -34.867094) (xy 175.565249 -34.9036) (xy 175.513315 -34.933584) (xy 175.457911 -34.956533)
			(xy 175.399986 -34.972054) (xy 175.34053 -34.979882) (xy 175.280562 -34.979882) (xy 175.221106 -34.972054)
			(xy 175.163181 -34.956533) (xy 175.107777 -34.933584) (xy 175.055843 -34.9036) (xy 175.008267 -34.867094)
			(xy 174.965862 -34.824689) (xy 174.929356 -34.777113) (xy 174.899372 -34.725179) (xy 174.876423 -34.669775)
			(xy 174.860902 -34.61185) (xy 174.853074 -34.552394) (xy 174.852584 -34.52241) (xy 164.505107 -34.52241)
			(xy 164.504642 -34.550854) (xy 164.496819 -34.610276) (xy 164.481306 -34.668169) (xy 164.45837 -34.723542)
			(xy 164.428403 -34.775448) (xy 164.391916 -34.822998) (xy 164.349536 -34.865378) (xy 164.301986 -34.901865)
			(xy 164.25008 -34.931832) (xy 164.194707 -34.954768) (xy 164.136814 -34.970281) (xy 164.077392 -34.978104)
			(xy 164.017456 -34.978104) (xy 163.958034 -34.970281) (xy 163.900141 -34.954768) (xy 163.844768 -34.931832)
			(xy 163.792862 -34.901865) (xy 163.745312 -34.865378) (xy 163.702932 -34.822998) (xy 163.666445 -34.775448)
			(xy 163.636478 -34.723542) (xy 163.613542 -34.668169) (xy 163.598029 -34.610276) (xy 163.590206 -34.550854)
			(xy 163.589716 -34.520886) (xy 149.76856 -34.520886) (xy 149.76856 -34.52241) (xy 149.76807 -34.552394)
			(xy 149.760242 -34.61185) (xy 149.744721 -34.669775) (xy 149.721772 -34.725179) (xy 149.691788 -34.777113)
			(xy 149.655282 -34.824689) (xy 149.612877 -34.867094) (xy 149.565301 -34.9036) (xy 149.513367 -34.933584)
			(xy 149.457963 -34.956533) (xy 149.400038 -34.972054) (xy 149.340582 -34.979882) (xy 149.280614 -34.979882)
			(xy 149.221158 -34.972054) (xy 149.163233 -34.956533) (xy 149.107829 -34.933584) (xy 149.055895 -34.9036)
			(xy 149.008319 -34.867094) (xy 148.965914 -34.824689) (xy 148.929408 -34.777113) (xy 148.899424 -34.725179)
			(xy 148.876475 -34.669775) (xy 148.860954 -34.61185) (xy 148.853126 -34.552394) (xy 148.852636 -34.52241)
			(xy 138.505159 -34.52241) (xy 138.504694 -34.550854) (xy 138.496871 -34.610276) (xy 138.481358 -34.668169)
			(xy 138.458422 -34.723542) (xy 138.428455 -34.775448) (xy 138.391968 -34.822998) (xy 138.349588 -34.865378)
			(xy 138.302038 -34.901865) (xy 138.250132 -34.931832) (xy 138.194759 -34.954768) (xy 138.136866 -34.970281)
			(xy 138.077444 -34.978104) (xy 138.017508 -34.978104) (xy 137.958086 -34.970281) (xy 137.900193 -34.954768)
			(xy 137.84482 -34.931832) (xy 137.792914 -34.901865) (xy 137.745364 -34.865378) (xy 137.702984 -34.822998)
			(xy 137.666497 -34.775448) (xy 137.63653 -34.723542) (xy 137.613594 -34.668169) (xy 137.598081 -34.610276)
			(xy 137.590258 -34.550854) (xy 137.589768 -34.520886) (xy 123.768612 -34.520886) (xy 123.768612 -34.52241)
			(xy 123.768122 -34.552394) (xy 123.760294 -34.61185) (xy 123.744773 -34.669775) (xy 123.721824 -34.725179)
			(xy 123.69184 -34.777113) (xy 123.655334 -34.824689) (xy 123.612929 -34.867094) (xy 123.565353 -34.9036)
			(xy 123.513419 -34.933584) (xy 123.458015 -34.956533) (xy 123.40009 -34.972054) (xy 123.340634 -34.979882)
			(xy 123.280666 -34.979882) (xy 123.22121 -34.972054) (xy 123.163285 -34.956533) (xy 123.107881 -34.933584)
			(xy 123.055947 -34.9036) (xy 123.008371 -34.867094) (xy 122.965966 -34.824689) (xy 122.92946 -34.777113)
			(xy 122.899476 -34.725179) (xy 122.876527 -34.669775) (xy 122.861006 -34.61185) (xy 122.853178 -34.552394)
			(xy 122.852688 -34.52241) (xy 100.405159 -34.52241) (xy 100.404694 -34.55087) (xy 100.396866 -34.610326)
			(xy 100.381345 -34.668251) (xy 100.358396 -34.723655) (xy 100.328412 -34.775589) (xy 100.291906 -34.823165)
			(xy 100.249501 -34.86557) (xy 100.201925 -34.902076) (xy 100.149991 -34.93206) (xy 100.094587 -34.955009)
			(xy 100.036662 -34.97053) (xy 99.977206 -34.978358) (xy 99.917238 -34.978358) (xy 99.857782 -34.97053)
			(xy 99.799857 -34.955009) (xy 99.744453 -34.93206) (xy 99.692519 -34.902076) (xy 99.644943 -34.86557)
			(xy 99.602538 -34.823165) (xy 99.566032 -34.775589) (xy 99.536048 -34.723655) (xy 99.513099 -34.668251)
			(xy 99.497578 -34.610326) (xy 99.48975 -34.55087) (xy 99.48926 -34.520886) (xy 85.668104 -34.520886)
			(xy 85.668104 -34.52241) (xy 85.667614 -34.552378) (xy 85.659791 -34.6118) (xy 85.644278 -34.669693)
			(xy 85.621342 -34.725066) (xy 85.591375 -34.776972) (xy 85.554888 -34.824522) (xy 85.512508 -34.866902)
			(xy 85.464958 -34.903389) (xy 85.413052 -34.933356) (xy 85.357679 -34.956292) (xy 85.299786 -34.971805)
			(xy 85.240364 -34.979628) (xy 85.180428 -34.979628) (xy 85.121006 -34.971805) (xy 85.063113 -34.956292)
			(xy 85.00774 -34.933356) (xy 84.955834 -34.903389) (xy 84.908284 -34.866902) (xy 84.865904 -34.824522)
			(xy 84.829417 -34.776972) (xy 84.79945 -34.725066) (xy 84.776514 -34.669693) (xy 84.761001 -34.6118)
			(xy 84.753178 -34.552378) (xy 84.752688 -34.52241) (xy 74.405211 -34.52241) (xy 74.404746 -34.55087)
			(xy 74.396918 -34.610326) (xy 74.381397 -34.668251) (xy 74.358448 -34.723655) (xy 74.328464 -34.775589)
			(xy 74.291958 -34.823165) (xy 74.249553 -34.86557) (xy 74.201977 -34.902076) (xy 74.150043 -34.93206)
			(xy 74.094639 -34.955009) (xy 74.036714 -34.97053) (xy 73.977258 -34.978358) (xy 73.91729 -34.978358)
			(xy 73.857834 -34.97053) (xy 73.799909 -34.955009) (xy 73.744505 -34.93206) (xy 73.692571 -34.902076)
			(xy 73.644995 -34.86557) (xy 73.60259 -34.823165) (xy 73.566084 -34.775589) (xy 73.5361 -34.723655)
			(xy 73.513151 -34.668251) (xy 73.49763 -34.610326) (xy 73.489802 -34.55087) (xy 73.489312 -34.520886)
			(xy 59.668156 -34.520886) (xy 59.668156 -34.52241) (xy 59.667666 -34.552378) (xy 59.659843 -34.6118)
			(xy 59.64433 -34.669693) (xy 59.621394 -34.725066) (xy 59.591427 -34.776972) (xy 59.55494 -34.824522)
			(xy 59.51256 -34.866902) (xy 59.46501 -34.903389) (xy 59.413104 -34.933356) (xy 59.357731 -34.956292)
			(xy 59.299838 -34.971805) (xy 59.240416 -34.979628) (xy 59.18048 -34.979628) (xy 59.121058 -34.971805)
			(xy 59.063165 -34.956292) (xy 59.007792 -34.933356) (xy 58.955886 -34.903389) (xy 58.908336 -34.866902)
			(xy 58.865956 -34.824522) (xy 58.829469 -34.776972) (xy 58.799502 -34.725066) (xy 58.776566 -34.669693)
			(xy 58.761053 -34.6118) (xy 58.75323 -34.552378) (xy 58.75274 -34.52241) (xy 48.405263 -34.52241)
			(xy 48.404798 -34.55087) (xy 48.39697 -34.610326) (xy 48.381449 -34.668251) (xy 48.3585 -34.723655)
			(xy 48.328516 -34.775589) (xy 48.29201 -34.823165) (xy 48.249605 -34.86557) (xy 48.202029 -34.902076)
			(xy 48.150095 -34.93206) (xy 48.094691 -34.955009) (xy 48.036766 -34.97053) (xy 47.97731 -34.978358)
			(xy 47.917342 -34.978358) (xy 47.857886 -34.97053) (xy 47.799961 -34.955009) (xy 47.744557 -34.93206)
			(xy 47.692623 -34.902076) (xy 47.645047 -34.86557) (xy 47.602642 -34.823165) (xy 47.566136 -34.775589)
			(xy 47.536152 -34.723655) (xy 47.513203 -34.668251) (xy 47.497682 -34.610326) (xy 47.489854 -34.55087)
			(xy 47.489364 -34.520886) (xy 33.668208 -34.520886) (xy 33.668208 -34.52241) (xy 33.667718 -34.552378)
			(xy 33.659895 -34.6118) (xy 33.644382 -34.669693) (xy 33.621446 -34.725066) (xy 33.591479 -34.776972)
			(xy 33.554992 -34.824522) (xy 33.512612 -34.866902) (xy 33.465062 -34.903389) (xy 33.413156 -34.933356)
			(xy 33.357783 -34.956292) (xy 33.29989 -34.971805) (xy 33.240468 -34.979628) (xy 33.180532 -34.979628)
			(xy 33.12111 -34.971805) (xy 33.063217 -34.956292) (xy 33.007844 -34.933356) (xy 32.955938 -34.903389)
			(xy 32.908388 -34.866902) (xy 32.866008 -34.824522) (xy 32.829521 -34.776972) (xy 32.799554 -34.725066)
			(xy 32.776618 -34.669693) (xy 32.761105 -34.6118) (xy 32.753282 -34.552378) (xy 32.752792 -34.52241)
			(xy 22.405315 -34.52241) (xy 22.40485 -34.55087) (xy 22.397022 -34.610326) (xy 22.381501 -34.668251)
			(xy 22.358552 -34.723655) (xy 22.328568 -34.775589) (xy 22.292062 -34.823165) (xy 22.249657 -34.86557)
			(xy 22.202081 -34.902076) (xy 22.150147 -34.93206) (xy 22.094743 -34.955009) (xy 22.036818 -34.97053)
			(xy 21.977362 -34.978358) (xy 21.917394 -34.978358) (xy 21.857938 -34.97053) (xy 21.800013 -34.955009)
			(xy 21.744609 -34.93206) (xy 21.692675 -34.902076) (xy 21.645099 -34.86557) (xy 21.602694 -34.823165)
			(xy 21.566188 -34.775589) (xy 21.536204 -34.723655) (xy 21.513255 -34.668251) (xy 21.497734 -34.610326)
			(xy 21.489906 -34.55087) (xy 21.489416 -34.520886) (xy 7.66826 -34.520886) (xy 7.66826 -34.52241)
			(xy 7.66777 -34.552378) (xy 7.659947 -34.6118) (xy 7.644434 -34.669693) (xy 7.621498 -34.725066)
			(xy 7.591531 -34.776972) (xy 7.555044 -34.824522) (xy 7.512664 -34.866902) (xy 7.465114 -34.903389)
			(xy 7.413208 -34.933356) (xy 7.357835 -34.956292) (xy 7.299942 -34.971805) (xy 7.24052 -34.979628)
			(xy 7.180584 -34.979628) (xy 7.121162 -34.971805) (xy 7.063269 -34.956292) (xy 7.007896 -34.933356)
			(xy 6.95599 -34.903389) (xy 6.90844 -34.866902) (xy 6.86606 -34.824522) (xy 6.829573 -34.776972)
			(xy 6.799606 -34.725066) (xy 6.77667 -34.669693) (xy 6.761157 -34.6118) (xy 6.753334 -34.552378)
			(xy 6.752844 -34.52241) (xy 0.508 -34.52241) (xy 0.508 -36.60013) (xy 11.998205 -36.60013) (xy 12.00221 -36.512222)
			(xy 12.014193 -36.425042) (xy 12.034053 -36.339313) (xy 12.061628 -36.255745) (xy 12.096687 -36.175031)
			(xy 12.13894 -36.097839) (xy 12.188038 -36.02481) (xy 12.243574 -35.956548) (xy 12.305086 -35.893618)
			(xy 12.372067 -35.836544) (xy 12.44396 -35.785796) (xy 12.520169 -35.741796) (xy 12.600064 -35.704909)
			(xy 12.682983 -35.67544) (xy 12.768238 -35.653633) (xy 12.855122 -35.639669) (xy 12.942916 -35.633663)
			(xy 13.030893 -35.635667) (xy 13.118323 -35.645662) (xy 13.204482 -35.663566) (xy 13.288656 -35.68923)
			(xy 13.370147 -35.722443) (xy 13.448281 -35.762929) (xy 13.522409 -35.810351) (xy 13.591917 -35.864318)
			(xy 13.656231 -35.924383) (xy 13.714815 -35.990047) (xy 13.767186 -36.060766) (xy 13.812909 -36.135954)
			(xy 13.851606 -36.214989) (xy 13.882955 -36.297215) (xy 13.906697 -36.381951) (xy 13.922635 -36.468495)
			(xy 13.930637 -36.55613) (xy 13.931138 -36.60013) (xy 37.998153 -36.60013) (xy 38.002158 -36.512222)
			(xy 38.014141 -36.425042) (xy 38.034001 -36.339313) (xy 38.061576 -36.255745) (xy 38.096635 -36.175031)
			(xy 38.138888 -36.097839) (xy 38.187986 -36.02481) (xy 38.243522 -35.956548) (xy 38.305034 -35.893618)
			(xy 38.372015 -35.836544) (xy 38.443908 -35.785796) (xy 38.520117 -35.741796) (xy 38.600012 -35.704909)
			(xy 38.682931 -35.67544) (xy 38.768186 -35.653633) (xy 38.85507 -35.639669) (xy 38.942864 -35.633663)
			(xy 39.030841 -35.635667) (xy 39.118271 -35.645662) (xy 39.20443 -35.663566) (xy 39.288604 -35.68923)
			(xy 39.370095 -35.722443) (xy 39.448229 -35.762929) (xy 39.522357 -35.810351) (xy 39.591865 -35.864318)
			(xy 39.656179 -35.924383) (xy 39.714763 -35.990047) (xy 39.767134 -36.060766) (xy 39.812857 -36.135954)
			(xy 39.851554 -36.214989) (xy 39.882903 -36.297215) (xy 39.906645 -36.381951) (xy 39.922583 -36.468495)
			(xy 39.930585 -36.55613) (xy 39.931086 -36.60013) (xy 63.998101 -36.60013) (xy 64.002106 -36.512222)
			(xy 64.014089 -36.425042) (xy 64.033949 -36.339313) (xy 64.061524 -36.255745) (xy 64.096583 -36.175031)
			(xy 64.138836 -36.097839) (xy 64.187934 -36.02481) (xy 64.24347 -35.956548) (xy 64.304982 -35.893618)
			(xy 64.371963 -35.836544) (xy 64.443856 -35.785796) (xy 64.520065 -35.741796) (xy 64.59996 -35.704909)
			(xy 64.682879 -35.67544) (xy 64.768134 -35.653633) (xy 64.855018 -35.639669) (xy 64.942812 -35.633663)
			(xy 65.030789 -35.635667) (xy 65.118219 -35.645662) (xy 65.204378 -35.663566) (xy 65.288552 -35.68923)
			(xy 65.370043 -35.722443) (xy 65.448177 -35.762929) (xy 65.522305 -35.810351) (xy 65.591813 -35.864318)
			(xy 65.656127 -35.924383) (xy 65.714711 -35.990047) (xy 65.767082 -36.060766) (xy 65.812805 -36.135954)
			(xy 65.851502 -36.214989) (xy 65.882851 -36.297215) (xy 65.906593 -36.381951) (xy 65.922531 -36.468495)
			(xy 65.930533 -36.55613) (xy 65.931034 -36.60013) (xy 89.998049 -36.60013) (xy 90.002054 -36.512222)
			(xy 90.014037 -36.425042) (xy 90.033897 -36.339313) (xy 90.061472 -36.255745) (xy 90.096531 -36.175031)
			(xy 90.138784 -36.097839) (xy 90.187882 -36.02481) (xy 90.243418 -35.956548) (xy 90.30493 -35.893618)
			(xy 90.371911 -35.836544) (xy 90.443804 -35.785796) (xy 90.520013 -35.741796) (xy 90.599908 -35.704909)
			(xy 90.682827 -35.67544) (xy 90.768082 -35.653633) (xy 90.854966 -35.639669) (xy 90.94276 -35.633663)
			(xy 91.030737 -35.635667) (xy 91.118167 -35.645662) (xy 91.204326 -35.663566) (xy 91.2885 -35.68923)
			(xy 91.369991 -35.722443) (xy 91.448125 -35.762929) (xy 91.522253 -35.810351) (xy 91.591761 -35.864318)
			(xy 91.656075 -35.924383) (xy 91.714659 -35.990047) (xy 91.76703 -36.060766) (xy 91.812753 -36.135954)
			(xy 91.85145 -36.214989) (xy 91.882799 -36.297215) (xy 91.906541 -36.381951) (xy 91.922479 -36.468495)
			(xy 91.930481 -36.55613) (xy 91.930982 -36.60013) (xy 128.098303 -36.60013) (xy 128.102308 -36.512222)
			(xy 128.114291 -36.425042) (xy 128.134151 -36.339313) (xy 128.161726 -36.255745) (xy 128.196785 -36.175031)
			(xy 128.239038 -36.097839) (xy 128.288136 -36.02481) (xy 128.343672 -35.956548) (xy 128.405184 -35.893618)
			(xy 128.472165 -35.836544) (xy 128.544058 -35.785796) (xy 128.620267 -35.741796) (xy 128.700162 -35.704909)
			(xy 128.783081 -35.67544) (xy 128.868336 -35.653633) (xy 128.95522 -35.639669) (xy 129.043014 -35.633663)
			(xy 129.130991 -35.635667) (xy 129.218421 -35.645662) (xy 129.30458 -35.663566) (xy 129.388754 -35.68923)
			(xy 129.470245 -35.722443) (xy 129.548379 -35.762929) (xy 129.622507 -35.810351) (xy 129.692015 -35.864318)
			(xy 129.756329 -35.924383) (xy 129.814913 -35.990047) (xy 129.867284 -36.060766) (xy 129.913007 -36.135954)
			(xy 129.951704 -36.214989) (xy 129.983053 -36.297215) (xy 130.006795 -36.381951) (xy 130.022733 -36.468495)
			(xy 130.030735 -36.55613) (xy 130.031236 -36.60013) (xy 154.098251 -36.60013) (xy 154.102256 -36.512222)
			(xy 154.114239 -36.425042) (xy 154.134099 -36.339313) (xy 154.161674 -36.255745) (xy 154.196733 -36.175031)
			(xy 154.238986 -36.097839) (xy 154.288084 -36.02481) (xy 154.34362 -35.956548) (xy 154.405132 -35.893618)
			(xy 154.472113 -35.836544) (xy 154.544006 -35.785796) (xy 154.620215 -35.741796) (xy 154.70011 -35.704909)
			(xy 154.783029 -35.67544) (xy 154.868284 -35.653633) (xy 154.955168 -35.639669) (xy 155.042962 -35.633663)
			(xy 155.130939 -35.635667) (xy 155.218369 -35.645662) (xy 155.304528 -35.663566) (xy 155.388702 -35.68923)
			(xy 155.470193 -35.722443) (xy 155.548327 -35.762929) (xy 155.622455 -35.810351) (xy 155.691963 -35.864318)
			(xy 155.756277 -35.924383) (xy 155.814861 -35.990047) (xy 155.867232 -36.060766) (xy 155.912955 -36.135954)
			(xy 155.951652 -36.214989) (xy 155.983001 -36.297215) (xy 156.006743 -36.381951) (xy 156.022681 -36.468495)
			(xy 156.030683 -36.55613) (xy 156.031184 -36.60013) (xy 180.098199 -36.60013) (xy 180.102204 -36.512222)
			(xy 180.114187 -36.425042) (xy 180.134047 -36.339313) (xy 180.161622 -36.255745) (xy 180.196681 -36.175031)
			(xy 180.238934 -36.097839) (xy 180.288032 -36.02481) (xy 180.343568 -35.956548) (xy 180.40508 -35.893618)
			(xy 180.472061 -35.836544) (xy 180.543954 -35.785796) (xy 180.620163 -35.741796) (xy 180.700058 -35.704909)
			(xy 180.782977 -35.67544) (xy 180.868232 -35.653633) (xy 180.955116 -35.639669) (xy 181.04291 -35.633663)
			(xy 181.130887 -35.635667) (xy 181.218317 -35.645662) (xy 181.304476 -35.663566) (xy 181.38865 -35.68923)
			(xy 181.470141 -35.722443) (xy 181.548275 -35.762929) (xy 181.622403 -35.810351) (xy 181.691911 -35.864318)
			(xy 181.756225 -35.924383) (xy 181.814809 -35.990047) (xy 181.86718 -36.060766) (xy 181.912903 -36.135954)
			(xy 181.9516 -36.214989) (xy 181.982949 -36.297215) (xy 182.006691 -36.381951) (xy 182.022629 -36.468495)
			(xy 182.030631 -36.55613) (xy 182.031132 -36.60013) (xy 206.098655 -36.60013) (xy 206.102659 -36.512245)
			(xy 206.114639 -36.425088) (xy 206.134494 -36.339381) (xy 206.162061 -36.255836) (xy 206.197111 -36.175143)
			(xy 206.239353 -36.097971) (xy 206.288438 -36.024961) (xy 206.343959 -35.956717) (xy 206.405456 -35.893804)
			(xy 206.472418 -35.836744) (xy 206.544292 -35.78601) (xy 206.620482 -35.742022) (xy 206.700356 -35.705144)
			(xy 206.783253 -35.675683) (xy 206.868485 -35.653881) (xy 206.955347 -35.639921) (xy 207.043118 -35.633917)
			(xy 207.131072 -35.63592) (xy 207.218479 -35.645912) (xy 207.304615 -35.663812) (xy 207.388767 -35.68947)
			(xy 207.470237 -35.722674) (xy 207.54835 -35.763148) (xy 207.622458 -35.810559) (xy 207.691949 -35.864512)
			(xy 207.756245 -35.92456) (xy 207.814814 -35.990207) (xy 207.867171 -36.060907) (xy 207.912883 -36.136076)
			(xy 207.951569 -36.21509) (xy 207.98291 -36.297295) (xy 208.006645 -36.382009) (xy 208.022579 -36.46853)
			(xy 208.030579 -36.556142) (xy 208.03108 -36.60013) (xy 244.198655 -36.60013) (xy 244.202659 -36.512245)
			(xy 244.214639 -36.425088) (xy 244.234494 -36.339381) (xy 244.262061 -36.255836) (xy 244.297111 -36.175143)
			(xy 244.339353 -36.097971) (xy 244.388438 -36.024961) (xy 244.443959 -35.956717) (xy 244.505456 -35.893804)
			(xy 244.572418 -35.836744) (xy 244.644292 -35.78601) (xy 244.720482 -35.742022) (xy 244.800356 -35.705144)
			(xy 244.883253 -35.675683) (xy 244.968485 -35.653881) (xy 245.055347 -35.639921) (xy 245.143118 -35.633917)
			(xy 245.231072 -35.63592) (xy 245.318479 -35.645912) (xy 245.404615 -35.663812) (xy 245.488767 -35.68947)
			(xy 245.570237 -35.722674) (xy 245.64835 -35.763148) (xy 245.722458 -35.810559) (xy 245.791949 -35.864512)
			(xy 245.856245 -35.92456) (xy 245.914814 -35.990207) (xy 245.967171 -36.060907) (xy 246.012883 -36.136076)
			(xy 246.051569 -36.21509) (xy 246.08291 -36.297295) (xy 246.106645 -36.382009) (xy 246.122579 -36.46853)
			(xy 246.130579 -36.556142) (xy 246.13108 -36.60013) (xy 270.198603 -36.60013) (xy 270.202607 -36.512245)
			(xy 270.214587 -36.425088) (xy 270.234442 -36.339381) (xy 270.262009 -36.255836) (xy 270.297059 -36.175143)
			(xy 270.339301 -36.097971) (xy 270.388386 -36.024961) (xy 270.443907 -35.956717) (xy 270.505404 -35.893804)
			(xy 270.572366 -35.836744) (xy 270.64424 -35.78601) (xy 270.72043 -35.742022) (xy 270.800304 -35.705144)
			(xy 270.883201 -35.675683) (xy 270.968433 -35.653881) (xy 271.055295 -35.639921) (xy 271.143066 -35.633917)
			(xy 271.23102 -35.63592) (xy 271.318427 -35.645912) (xy 271.404563 -35.663812) (xy 271.488715 -35.68947)
			(xy 271.570185 -35.722674) (xy 271.648298 -35.763148) (xy 271.722406 -35.810559) (xy 271.791897 -35.864512)
			(xy 271.856193 -35.92456) (xy 271.914762 -35.990207) (xy 271.967119 -36.060907) (xy 272.012831 -36.136076)
			(xy 272.051517 -36.21509) (xy 272.082858 -36.297295) (xy 272.106593 -36.382009) (xy 272.122527 -36.46853)
			(xy 272.130527 -36.556142) (xy 272.131028 -36.60013) (xy 296.198551 -36.60013) (xy 296.202555 -36.512245)
			(xy 296.214535 -36.425088) (xy 296.23439 -36.339381) (xy 296.261957 -36.255836) (xy 296.297007 -36.175143)
			(xy 296.339249 -36.097971) (xy 296.388334 -36.024961) (xy 296.443855 -35.956717) (xy 296.505352 -35.893804)
			(xy 296.572314 -35.836744) (xy 296.644188 -35.78601) (xy 296.720378 -35.742022) (xy 296.800252 -35.705144)
			(xy 296.883149 -35.675683) (xy 296.968381 -35.653881) (xy 297.055243 -35.639921) (xy 297.143014 -35.633917)
			(xy 297.230968 -35.63592) (xy 297.318375 -35.645912) (xy 297.404511 -35.663812) (xy 297.488663 -35.68947)
			(xy 297.570133 -35.722674) (xy 297.648246 -35.763148) (xy 297.722354 -35.810559) (xy 297.791845 -35.864512)
			(xy 297.856141 -35.92456) (xy 297.91471 -35.990207) (xy 297.967067 -36.060907) (xy 298.012779 -36.136076)
			(xy 298.051465 -36.21509) (xy 298.082806 -36.297295) (xy 298.106541 -36.382009) (xy 298.122475 -36.46853)
			(xy 298.130475 -36.556142) (xy 298.130976 -36.60013) (xy 322.197991 -36.60013) (xy 322.201996 -36.512222)
			(xy 322.213979 -36.425042) (xy 322.233839 -36.339313) (xy 322.261414 -36.255745) (xy 322.296473 -36.175031)
			(xy 322.338726 -36.097839) (xy 322.387824 -36.02481) (xy 322.44336 -35.956548) (xy 322.504872 -35.893618)
			(xy 322.571853 -35.836544) (xy 322.643746 -35.785796) (xy 322.719955 -35.741796) (xy 322.79985 -35.704909)
			(xy 322.882769 -35.67544) (xy 322.968024 -35.653633) (xy 323.054908 -35.639669) (xy 323.142702 -35.633663)
			(xy 323.230679 -35.635667) (xy 323.318109 -35.645662) (xy 323.404268 -35.663566) (xy 323.488442 -35.68923)
			(xy 323.569933 -35.722443) (xy 323.648067 -35.762929) (xy 323.722195 -35.810351) (xy 323.791703 -35.864318)
			(xy 323.856017 -35.924383) (xy 323.914601 -35.990047) (xy 323.966972 -36.060766) (xy 324.012695 -36.135954)
			(xy 324.051392 -36.214989) (xy 324.082741 -36.297215) (xy 324.106483 -36.381951) (xy 324.122421 -36.468495)
			(xy 324.130423 -36.55613) (xy 324.130924 -36.60013) (xy 360.298245 -36.60013) (xy 360.30225 -36.512222)
			(xy 360.314233 -36.425042) (xy 360.334093 -36.339313) (xy 360.361668 -36.255745) (xy 360.396727 -36.175031)
			(xy 360.43898 -36.097839) (xy 360.488078 -36.02481) (xy 360.543614 -35.956548) (xy 360.605126 -35.893618)
			(xy 360.672107 -35.836544) (xy 360.744 -35.785796) (xy 360.820209 -35.741796) (xy 360.900104 -35.704909)
			(xy 360.983023 -35.67544) (xy 361.068278 -35.653633) (xy 361.155162 -35.639669) (xy 361.242956 -35.633663)
			(xy 361.330933 -35.635667) (xy 361.418363 -35.645662) (xy 361.504522 -35.663566) (xy 361.588696 -35.68923)
			(xy 361.670187 -35.722443) (xy 361.748321 -35.762929) (xy 361.822449 -35.810351) (xy 361.891957 -35.864318)
			(xy 361.956271 -35.924383) (xy 362.014855 -35.990047) (xy 362.067226 -36.060766) (xy 362.112949 -36.135954)
			(xy 362.151646 -36.214989) (xy 362.182995 -36.297215) (xy 362.206737 -36.381951) (xy 362.222675 -36.468495)
			(xy 362.230677 -36.55613) (xy 362.231178 -36.60013) (xy 386.298193 -36.60013) (xy 386.302198 -36.512222)
			(xy 386.314181 -36.425042) (xy 386.334041 -36.339313) (xy 386.361616 -36.255745) (xy 386.396675 -36.175031)
			(xy 386.438928 -36.097839) (xy 386.488026 -36.02481) (xy 386.543562 -35.956548) (xy 386.605074 -35.893618)
			(xy 386.672055 -35.836544) (xy 386.743948 -35.785796) (xy 386.820157 -35.741796) (xy 386.900052 -35.704909)
			(xy 386.982971 -35.67544) (xy 387.068226 -35.653633) (xy 387.15511 -35.639669) (xy 387.242904 -35.633663)
			(xy 387.330881 -35.635667) (xy 387.418311 -35.645662) (xy 387.50447 -35.663566) (xy 387.588644 -35.68923)
			(xy 387.670135 -35.722443) (xy 387.748269 -35.762929) (xy 387.822397 -35.810351) (xy 387.891905 -35.864318)
			(xy 387.956219 -35.924383) (xy 388.014803 -35.990047) (xy 388.067174 -36.060766) (xy 388.112897 -36.135954)
			(xy 388.151594 -36.214989) (xy 388.182943 -36.297215) (xy 388.206685 -36.381951) (xy 388.222623 -36.468495)
			(xy 388.230625 -36.55613) (xy 388.231126 -36.60013) (xy 412.298649 -36.60013) (xy 412.302653 -36.512245)
			(xy 412.314633 -36.425088) (xy 412.334488 -36.339381) (xy 412.362055 -36.255836) (xy 412.397105 -36.175143)
			(xy 412.439347 -36.097971) (xy 412.488432 -36.024961) (xy 412.543953 -35.956717) (xy 412.60545 -35.893804)
			(xy 412.672412 -35.836744) (xy 412.744286 -35.78601) (xy 412.820476 -35.742022) (xy 412.90035 -35.705144)
			(xy 412.983247 -35.675683) (xy 413.068479 -35.653881) (xy 413.155341 -35.639921) (xy 413.243112 -35.633917)
			(xy 413.331066 -35.63592) (xy 413.418473 -35.645912) (xy 413.504609 -35.663812) (xy 413.588761 -35.68947)
			(xy 413.670231 -35.722674) (xy 413.748344 -35.763148) (xy 413.822452 -35.810559) (xy 413.891943 -35.864512)
			(xy 413.956239 -35.92456) (xy 414.014808 -35.990207) (xy 414.067165 -36.060907) (xy 414.112877 -36.136076)
			(xy 414.151563 -36.21509) (xy 414.182904 -36.297295) (xy 414.206639 -36.382009) (xy 414.222573 -36.46853)
			(xy 414.230573 -36.556142) (xy 414.231074 -36.60013) (xy 438.298597 -36.60013) (xy 438.302601 -36.512245)
			(xy 438.314581 -36.425088) (xy 438.334436 -36.339381) (xy 438.362003 -36.255836) (xy 438.397053 -36.175143)
			(xy 438.439295 -36.097971) (xy 438.48838 -36.024961) (xy 438.543901 -35.956717) (xy 438.605398 -35.893804)
			(xy 438.67236 -35.836744) (xy 438.744234 -35.78601) (xy 438.820424 -35.742022) (xy 438.900298 -35.705144)
			(xy 438.983195 -35.675683) (xy 439.068427 -35.653881) (xy 439.155289 -35.639921) (xy 439.24306 -35.633917)
			(xy 439.331014 -35.63592) (xy 439.418421 -35.645912) (xy 439.504557 -35.663812) (xy 439.588709 -35.68947)
			(xy 439.670179 -35.722674) (xy 439.748292 -35.763148) (xy 439.8224 -35.810559) (xy 439.891891 -35.864512)
			(xy 439.956187 -35.92456) (xy 440.014756 -35.990207) (xy 440.067113 -36.060907) (xy 440.112825 -36.136076)
			(xy 440.151511 -36.21509) (xy 440.182852 -36.297295) (xy 440.206587 -36.382009) (xy 440.222521 -36.46853)
			(xy 440.230521 -36.556142) (xy 440.231022 -36.60013) (xy 440.230521 -36.644118) (xy 440.222521 -36.73173)
			(xy 440.206587 -36.818251) (xy 440.182852 -36.902965) (xy 440.151511 -36.98517) (xy 440.112825 -37.064184)
			(xy 440.067113 -37.139353) (xy 440.014756 -37.210053) (xy 439.956187 -37.2757) (xy 439.891891 -37.335748)
			(xy 439.8224 -37.389701) (xy 439.748292 -37.437112) (xy 439.670179 -37.477586) (xy 439.588709 -37.51079)
			(xy 439.504557 -37.536448) (xy 439.418421 -37.554348) (xy 439.331014 -37.56434) (xy 439.24306 -37.566343)
			(xy 439.155289 -37.560339) (xy 439.068427 -37.546379) (xy 438.983195 -37.524577) (xy 438.900298 -37.495116)
			(xy 438.820424 -37.458238) (xy 438.744234 -37.41425) (xy 438.67236 -37.363516) (xy 438.605398 -37.306456)
			(xy 438.543901 -37.243543) (xy 438.48838 -37.175299) (xy 438.439295 -37.102289) (xy 438.397053 -37.025117)
			(xy 438.362003 -36.944424) (xy 438.334436 -36.860879) (xy 438.314581 -36.775172) (xy 438.302601 -36.688015)
			(xy 438.298597 -36.60013) (xy 414.231074 -36.60013) (xy 414.230573 -36.644118) (xy 414.222573 -36.73173)
			(xy 414.206639 -36.818251) (xy 414.182904 -36.902965) (xy 414.151563 -36.98517) (xy 414.112877 -37.064184)
			(xy 414.067165 -37.139353) (xy 414.014808 -37.210053) (xy 413.956239 -37.2757) (xy 413.891943 -37.335748)
			(xy 413.822452 -37.389701) (xy 413.748344 -37.437112) (xy 413.670231 -37.477586) (xy 413.588761 -37.51079)
			(xy 413.504609 -37.536448) (xy 413.418473 -37.554348) (xy 413.331066 -37.56434) (xy 413.243112 -37.566343)
			(xy 413.155341 -37.560339) (xy 413.068479 -37.546379) (xy 412.983247 -37.524577) (xy 412.90035 -37.495116)
			(xy 412.820476 -37.458238) (xy 412.744286 -37.41425) (xy 412.672412 -37.363516) (xy 412.60545 -37.306456)
			(xy 412.543953 -37.243543) (xy 412.488432 -37.175299) (xy 412.439347 -37.102289) (xy 412.397105 -37.025117)
			(xy 412.362055 -36.944424) (xy 412.334488 -36.860879) (xy 412.314633 -36.775172) (xy 412.302653 -36.688015)
			(xy 412.298649 -36.60013) (xy 388.231126 -36.60013) (xy 388.230625 -36.64413) (xy 388.222623 -36.731765)
			(xy 388.206685 -36.818309) (xy 388.182943 -36.903045) (xy 388.151594 -36.985271) (xy 388.112897 -37.064306)
			(xy 388.067174 -37.139494) (xy 388.014803 -37.210213) (xy 387.956219 -37.275877) (xy 387.891905 -37.335942)
			(xy 387.822397 -37.389909) (xy 387.748269 -37.437331) (xy 387.670135 -37.477817) (xy 387.588644 -37.51103)
			(xy 387.50447 -37.536694) (xy 387.418311 -37.554598) (xy 387.330881 -37.564593) (xy 387.242904 -37.566597)
			(xy 387.15511 -37.560591) (xy 387.068226 -37.546627) (xy 386.982971 -37.52482) (xy 386.900052 -37.495351)
			(xy 386.820157 -37.458464) (xy 386.743948 -37.414464) (xy 386.672055 -37.363716) (xy 386.605074 -37.306642)
			(xy 386.543562 -37.243712) (xy 386.488026 -37.17545) (xy 386.438928 -37.102421) (xy 386.396675 -37.025229)
			(xy 386.361616 -36.944515) (xy 386.334041 -36.860947) (xy 386.314181 -36.775218) (xy 386.302198 -36.688038)
			(xy 386.298193 -36.60013) (xy 362.231178 -36.60013) (xy 362.230677 -36.64413) (xy 362.222675 -36.731765)
			(xy 362.206737 -36.818309) (xy 362.182995 -36.903045) (xy 362.151646 -36.985271) (xy 362.112949 -37.064306)
			(xy 362.067226 -37.139494) (xy 362.014855 -37.210213) (xy 361.956271 -37.275877) (xy 361.891957 -37.335942)
			(xy 361.822449 -37.389909) (xy 361.748321 -37.437331) (xy 361.670187 -37.477817) (xy 361.588696 -37.51103)
			(xy 361.504522 -37.536694) (xy 361.418363 -37.554598) (xy 361.330933 -37.564593) (xy 361.242956 -37.566597)
			(xy 361.155162 -37.560591) (xy 361.068278 -37.546627) (xy 360.983023 -37.52482) (xy 360.900104 -37.495351)
			(xy 360.820209 -37.458464) (xy 360.744 -37.414464) (xy 360.672107 -37.363716) (xy 360.605126 -37.306642)
			(xy 360.543614 -37.243712) (xy 360.488078 -37.17545) (xy 360.43898 -37.102421) (xy 360.396727 -37.025229)
			(xy 360.361668 -36.944515) (xy 360.334093 -36.860947) (xy 360.314233 -36.775218) (xy 360.30225 -36.688038)
			(xy 360.298245 -36.60013) (xy 324.130924 -36.60013) (xy 324.130423 -36.64413) (xy 324.122421 -36.731765)
			(xy 324.106483 -36.818309) (xy 324.082741 -36.903045) (xy 324.051392 -36.985271) (xy 324.012695 -37.064306)
			(xy 323.966972 -37.139494) (xy 323.914601 -37.210213) (xy 323.856017 -37.275877) (xy 323.791703 -37.335942)
			(xy 323.722195 -37.389909) (xy 323.648067 -37.437331) (xy 323.569933 -37.477817) (xy 323.488442 -37.51103)
			(xy 323.404268 -37.536694) (xy 323.318109 -37.554598) (xy 323.230679 -37.564593) (xy 323.142702 -37.566597)
			(xy 323.054908 -37.560591) (xy 322.968024 -37.546627) (xy 322.882769 -37.52482) (xy 322.79985 -37.495351)
			(xy 322.719955 -37.458464) (xy 322.643746 -37.414464) (xy 322.571853 -37.363716) (xy 322.504872 -37.306642)
			(xy 322.44336 -37.243712) (xy 322.387824 -37.17545) (xy 322.338726 -37.102421) (xy 322.296473 -37.025229)
			(xy 322.261414 -36.944515) (xy 322.233839 -36.860947) (xy 322.213979 -36.775218) (xy 322.201996 -36.688038)
			(xy 322.197991 -36.60013) (xy 298.130976 -36.60013) (xy 298.130475 -36.644118) (xy 298.122475 -36.73173)
			(xy 298.106541 -36.818251) (xy 298.082806 -36.902965) (xy 298.051465 -36.98517) (xy 298.012779 -37.064184)
			(xy 297.967067 -37.139353) (xy 297.91471 -37.210053) (xy 297.856141 -37.2757) (xy 297.791845 -37.335748)
			(xy 297.722354 -37.389701) (xy 297.648246 -37.437112) (xy 297.570133 -37.477586) (xy 297.488663 -37.51079)
			(xy 297.404511 -37.536448) (xy 297.318375 -37.554348) (xy 297.230968 -37.56434) (xy 297.143014 -37.566343)
			(xy 297.055243 -37.560339) (xy 296.968381 -37.546379) (xy 296.883149 -37.524577) (xy 296.800252 -37.495116)
			(xy 296.720378 -37.458238) (xy 296.644188 -37.41425) (xy 296.572314 -37.363516) (xy 296.505352 -37.306456)
			(xy 296.443855 -37.243543) (xy 296.388334 -37.175299) (xy 296.339249 -37.102289) (xy 296.297007 -37.025117)
			(xy 296.261957 -36.944424) (xy 296.23439 -36.860879) (xy 296.214535 -36.775172) (xy 296.202555 -36.688015)
			(xy 296.198551 -36.60013) (xy 272.131028 -36.60013) (xy 272.130527 -36.644118) (xy 272.122527 -36.73173)
			(xy 272.106593 -36.818251) (xy 272.082858 -36.902965) (xy 272.051517 -36.98517) (xy 272.012831 -37.064184)
			(xy 271.967119 -37.139353) (xy 271.914762 -37.210053) (xy 271.856193 -37.2757) (xy 271.791897 -37.335748)
			(xy 271.722406 -37.389701) (xy 271.648298 -37.437112) (xy 271.570185 -37.477586) (xy 271.488715 -37.51079)
			(xy 271.404563 -37.536448) (xy 271.318427 -37.554348) (xy 271.23102 -37.56434) (xy 271.143066 -37.566343)
			(xy 271.055295 -37.560339) (xy 270.968433 -37.546379) (xy 270.883201 -37.524577) (xy 270.800304 -37.495116)
			(xy 270.72043 -37.458238) (xy 270.64424 -37.41425) (xy 270.572366 -37.363516) (xy 270.505404 -37.306456)
			(xy 270.443907 -37.243543) (xy 270.388386 -37.175299) (xy 270.339301 -37.102289) (xy 270.297059 -37.025117)
			(xy 270.262009 -36.944424) (xy 270.234442 -36.860879) (xy 270.214587 -36.775172) (xy 270.202607 -36.688015)
			(xy 270.198603 -36.60013) (xy 246.13108 -36.60013) (xy 246.130579 -36.644118) (xy 246.122579 -36.73173)
			(xy 246.106645 -36.818251) (xy 246.08291 -36.902965) (xy 246.051569 -36.98517) (xy 246.012883 -37.064184)
			(xy 245.967171 -37.139353) (xy 245.914814 -37.210053) (xy 245.856245 -37.2757) (xy 245.791949 -37.335748)
			(xy 245.722458 -37.389701) (xy 245.64835 -37.437112) (xy 245.570237 -37.477586) (xy 245.488767 -37.51079)
			(xy 245.404615 -37.536448) (xy 245.318479 -37.554348) (xy 245.231072 -37.56434) (xy 245.143118 -37.566343)
			(xy 245.055347 -37.560339) (xy 244.968485 -37.546379) (xy 244.883253 -37.524577) (xy 244.800356 -37.495116)
			(xy 244.720482 -37.458238) (xy 244.644292 -37.41425) (xy 244.572418 -37.363516) (xy 244.505456 -37.306456)
			(xy 244.443959 -37.243543) (xy 244.388438 -37.175299) (xy 244.339353 -37.102289) (xy 244.297111 -37.025117)
			(xy 244.262061 -36.944424) (xy 244.234494 -36.860879) (xy 244.214639 -36.775172) (xy 244.202659 -36.688015)
			(xy 244.198655 -36.60013) (xy 208.03108 -36.60013) (xy 208.030579 -36.644118) (xy 208.022579 -36.73173)
			(xy 208.006645 -36.818251) (xy 207.98291 -36.902965) (xy 207.951569 -36.98517) (xy 207.912883 -37.064184)
			(xy 207.867171 -37.139353) (xy 207.814814 -37.210053) (xy 207.756245 -37.2757) (xy 207.691949 -37.335748)
			(xy 207.622458 -37.389701) (xy 207.54835 -37.437112) (xy 207.470237 -37.477586) (xy 207.388767 -37.51079)
			(xy 207.304615 -37.536448) (xy 207.218479 -37.554348) (xy 207.131072 -37.56434) (xy 207.043118 -37.566343)
			(xy 206.955347 -37.560339) (xy 206.868485 -37.546379) (xy 206.783253 -37.524577) (xy 206.700356 -37.495116)
			(xy 206.620482 -37.458238) (xy 206.544292 -37.41425) (xy 206.472418 -37.363516) (xy 206.405456 -37.306456)
			(xy 206.343959 -37.243543) (xy 206.288438 -37.175299) (xy 206.239353 -37.102289) (xy 206.197111 -37.025117)
			(xy 206.162061 -36.944424) (xy 206.134494 -36.860879) (xy 206.114639 -36.775172) (xy 206.102659 -36.688015)
			(xy 206.098655 -36.60013) (xy 182.031132 -36.60013) (xy 182.030631 -36.64413) (xy 182.022629 -36.731765)
			(xy 182.006691 -36.818309) (xy 181.982949 -36.903045) (xy 181.9516 -36.985271) (xy 181.912903 -37.064306)
			(xy 181.86718 -37.139494) (xy 181.814809 -37.210213) (xy 181.756225 -37.275877) (xy 181.691911 -37.335942)
			(xy 181.622403 -37.389909) (xy 181.548275 -37.437331) (xy 181.470141 -37.477817) (xy 181.38865 -37.51103)
			(xy 181.304476 -37.536694) (xy 181.218317 -37.554598) (xy 181.130887 -37.564593) (xy 181.04291 -37.566597)
			(xy 180.955116 -37.560591) (xy 180.868232 -37.546627) (xy 180.782977 -37.52482) (xy 180.700058 -37.495351)
			(xy 180.620163 -37.458464) (xy 180.543954 -37.414464) (xy 180.472061 -37.363716) (xy 180.40508 -37.306642)
			(xy 180.343568 -37.243712) (xy 180.288032 -37.17545) (xy 180.238934 -37.102421) (xy 180.196681 -37.025229)
			(xy 180.161622 -36.944515) (xy 180.134047 -36.860947) (xy 180.114187 -36.775218) (xy 180.102204 -36.688038)
			(xy 180.098199 -36.60013) (xy 156.031184 -36.60013) (xy 156.030683 -36.64413) (xy 156.022681 -36.731765)
			(xy 156.006743 -36.818309) (xy 155.983001 -36.903045) (xy 155.951652 -36.985271) (xy 155.912955 -37.064306)
			(xy 155.867232 -37.139494) (xy 155.814861 -37.210213) (xy 155.756277 -37.275877) (xy 155.691963 -37.335942)
			(xy 155.622455 -37.389909) (xy 155.548327 -37.437331) (xy 155.470193 -37.477817) (xy 155.388702 -37.51103)
			(xy 155.304528 -37.536694) (xy 155.218369 -37.554598) (xy 155.130939 -37.564593) (xy 155.042962 -37.566597)
			(xy 154.955168 -37.560591) (xy 154.868284 -37.546627) (xy 154.783029 -37.52482) (xy 154.70011 -37.495351)
			(xy 154.620215 -37.458464) (xy 154.544006 -37.414464) (xy 154.472113 -37.363716) (xy 154.405132 -37.306642)
			(xy 154.34362 -37.243712) (xy 154.288084 -37.17545) (xy 154.238986 -37.102421) (xy 154.196733 -37.025229)
			(xy 154.161674 -36.944515) (xy 154.134099 -36.860947) (xy 154.114239 -36.775218) (xy 154.102256 -36.688038)
			(xy 154.098251 -36.60013) (xy 130.031236 -36.60013) (xy 130.030735 -36.64413) (xy 130.022733 -36.731765)
			(xy 130.006795 -36.818309) (xy 129.983053 -36.903045) (xy 129.951704 -36.985271) (xy 129.913007 -37.064306)
			(xy 129.867284 -37.139494) (xy 129.814913 -37.210213) (xy 129.756329 -37.275877) (xy 129.692015 -37.335942)
			(xy 129.622507 -37.389909) (xy 129.548379 -37.437331) (xy 129.470245 -37.477817) (xy 129.388754 -37.51103)
			(xy 129.30458 -37.536694) (xy 129.218421 -37.554598) (xy 129.130991 -37.564593) (xy 129.043014 -37.566597)
			(xy 128.95522 -37.560591) (xy 128.868336 -37.546627) (xy 128.783081 -37.52482) (xy 128.700162 -37.495351)
			(xy 128.620267 -37.458464) (xy 128.544058 -37.414464) (xy 128.472165 -37.363716) (xy 128.405184 -37.306642)
			(xy 128.343672 -37.243712) (xy 128.288136 -37.17545) (xy 128.239038 -37.102421) (xy 128.196785 -37.025229)
			(xy 128.161726 -36.944515) (xy 128.134151 -36.860947) (xy 128.114291 -36.775218) (xy 128.102308 -36.688038)
			(xy 128.098303 -36.60013) (xy 91.930982 -36.60013) (xy 91.930481 -36.64413) (xy 91.922479 -36.731765)
			(xy 91.906541 -36.818309) (xy 91.882799 -36.903045) (xy 91.85145 -36.985271) (xy 91.812753 -37.064306)
			(xy 91.76703 -37.139494) (xy 91.714659 -37.210213) (xy 91.656075 -37.275877) (xy 91.591761 -37.335942)
			(xy 91.522253 -37.389909) (xy 91.448125 -37.437331) (xy 91.369991 -37.477817) (xy 91.2885 -37.51103)
			(xy 91.204326 -37.536694) (xy 91.118167 -37.554598) (xy 91.030737 -37.564593) (xy 90.94276 -37.566597)
			(xy 90.854966 -37.560591) (xy 90.768082 -37.546627) (xy 90.682827 -37.52482) (xy 90.599908 -37.495351)
			(xy 90.520013 -37.458464) (xy 90.443804 -37.414464) (xy 90.371911 -37.363716) (xy 90.30493 -37.306642)
			(xy 90.243418 -37.243712) (xy 90.187882 -37.17545) (xy 90.138784 -37.102421) (xy 90.096531 -37.025229)
			(xy 90.061472 -36.944515) (xy 90.033897 -36.860947) (xy 90.014037 -36.775218) (xy 90.002054 -36.688038)
			(xy 89.998049 -36.60013) (xy 65.931034 -36.60013) (xy 65.930533 -36.64413) (xy 65.922531 -36.731765)
			(xy 65.906593 -36.818309) (xy 65.882851 -36.903045) (xy 65.851502 -36.985271) (xy 65.812805 -37.064306)
			(xy 65.767082 -37.139494) (xy 65.714711 -37.210213) (xy 65.656127 -37.275877) (xy 65.591813 -37.335942)
			(xy 65.522305 -37.389909) (xy 65.448177 -37.437331) (xy 65.370043 -37.477817) (xy 65.288552 -37.51103)
			(xy 65.204378 -37.536694) (xy 65.118219 -37.554598) (xy 65.030789 -37.564593) (xy 64.942812 -37.566597)
			(xy 64.855018 -37.560591) (xy 64.768134 -37.546627) (xy 64.682879 -37.52482) (xy 64.59996 -37.495351)
			(xy 64.520065 -37.458464) (xy 64.443856 -37.414464) (xy 64.371963 -37.363716) (xy 64.304982 -37.306642)
			(xy 64.24347 -37.243712) (xy 64.187934 -37.17545) (xy 64.138836 -37.102421) (xy 64.096583 -37.025229)
			(xy 64.061524 -36.944515) (xy 64.033949 -36.860947) (xy 64.014089 -36.775218) (xy 64.002106 -36.688038)
			(xy 63.998101 -36.60013) (xy 39.931086 -36.60013) (xy 39.930585 -36.64413) (xy 39.922583 -36.731765)
			(xy 39.906645 -36.818309) (xy 39.882903 -36.903045) (xy 39.851554 -36.985271) (xy 39.812857 -37.064306)
			(xy 39.767134 -37.139494) (xy 39.714763 -37.210213) (xy 39.656179 -37.275877) (xy 39.591865 -37.335942)
			(xy 39.522357 -37.389909) (xy 39.448229 -37.437331) (xy 39.370095 -37.477817) (xy 39.288604 -37.51103)
			(xy 39.20443 -37.536694) (xy 39.118271 -37.554598) (xy 39.030841 -37.564593) (xy 38.942864 -37.566597)
			(xy 38.85507 -37.560591) (xy 38.768186 -37.546627) (xy 38.682931 -37.52482) (xy 38.600012 -37.495351)
			(xy 38.520117 -37.458464) (xy 38.443908 -37.414464) (xy 38.372015 -37.363716) (xy 38.305034 -37.306642)
			(xy 38.243522 -37.243712) (xy 38.187986 -37.17545) (xy 38.138888 -37.102421) (xy 38.096635 -37.025229)
			(xy 38.061576 -36.944515) (xy 38.034001 -36.860947) (xy 38.014141 -36.775218) (xy 38.002158 -36.688038)
			(xy 37.998153 -36.60013) (xy 13.931138 -36.60013) (xy 13.930637 -36.64413) (xy 13.922635 -36.731765)
			(xy 13.906697 -36.818309) (xy 13.882955 -36.903045) (xy 13.851606 -36.985271) (xy 13.812909 -37.064306)
			(xy 13.767186 -37.139494) (xy 13.714815 -37.210213) (xy 13.656231 -37.275877) (xy 13.591917 -37.335942)
			(xy 13.522409 -37.389909) (xy 13.448281 -37.437331) (xy 13.370147 -37.477817) (xy 13.288656 -37.51103)
			(xy 13.204482 -37.536694) (xy 13.118323 -37.554598) (xy 13.030893 -37.564593) (xy 12.942916 -37.566597)
			(xy 12.855122 -37.560591) (xy 12.768238 -37.546627) (xy 12.682983 -37.52482) (xy 12.600064 -37.495351)
			(xy 12.520169 -37.458464) (xy 12.44396 -37.414464) (xy 12.372067 -37.363716) (xy 12.305086 -37.306642)
			(xy 12.243574 -37.243712) (xy 12.188038 -37.17545) (xy 12.13894 -37.102421) (xy 12.096687 -37.025229)
			(xy 12.061628 -36.944515) (xy 12.034053 -36.860947) (xy 12.014193 -36.775218) (xy 12.00221 -36.688038)
			(xy 11.998205 -36.60013) (xy 0.508 -36.60013) (xy 0.508 -58.698471) (xy 229.808523 -58.698471) (xy 229.808523 -58.601777)
			(xy 229.816508 -58.505414) (xy 229.832424 -58.410039) (xy 229.85616 -58.316305) (xy 229.887557 -58.22485)
			(xy 229.926398 -58.136301) (xy 229.972419 -58.051261) (xy 230.025305 -57.970313) (xy 230.084696 -57.894008)
			(xy 230.150184 -57.822868) (xy 230.221324 -57.75738) (xy 230.297629 -57.697989) (xy 230.378577 -57.645103)
			(xy 230.463617 -57.599082) (xy 230.552166 -57.560241) (xy 230.643621 -57.528844) (xy 230.737355 -57.505108)
			(xy 230.83273 -57.489192) (xy 230.929093 -57.481207) (xy 231.025787 -57.481207) (xy 231.12215 -57.489192)
			(xy 231.217525 -57.505108) (xy 231.311259 -57.528844) (xy 231.402714 -57.560241) (xy 231.491263 -57.599082)
			(xy 231.576303 -57.645103) (xy 231.657251 -57.697989) (xy 231.733556 -57.75738) (xy 231.804696 -57.822868)
			(xy 231.870184 -57.894008) (xy 231.929575 -57.970313) (xy 231.982461 -58.051261) (xy 232.028482 -58.136301)
			(xy 232.067323 -58.22485) (xy 232.09872 -58.316305) (xy 232.122456 -58.410039) (xy 232.138372 -58.505414)
			(xy 232.146357 -58.601777) (xy 232.146856 -58.650124) (xy 232.146357 -58.698471) (xy 232.138372 -58.794834)
			(xy 232.122456 -58.890209) (xy 232.09872 -58.983943) (xy 232.067323 -59.075398) (xy 232.028482 -59.163947)
			(xy 231.982461 -59.248987) (xy 231.929575 -59.329935) (xy 231.870184 -59.40624) (xy 231.804696 -59.47738)
			(xy 231.733556 -59.542868) (xy 231.657251 -59.602259) (xy 231.576303 -59.655145) (xy 231.491263 -59.701166)
			(xy 231.402714 -59.740007) (xy 231.311259 -59.771404) (xy 231.217525 -59.79514) (xy 231.12215 -59.811056)
			(xy 231.025787 -59.819041) (xy 230.929093 -59.819041) (xy 230.83273 -59.811056) (xy 230.737355 -59.79514)
			(xy 230.643621 -59.771404) (xy 230.552166 -59.740007) (xy 230.463617 -59.701166) (xy 230.378577 -59.655145)
			(xy 230.297629 -59.602259) (xy 230.221324 -59.542868) (xy 230.150184 -59.47738) (xy 230.084696 -59.40624)
			(xy 230.025305 -59.329935) (xy 229.972419 -59.248987) (xy 229.926398 -59.163947) (xy 229.887557 -59.075398)
			(xy 229.85616 -58.983943) (xy 229.832424 -58.890209) (xy 229.816508 -58.794834) (xy 229.808523 -58.698471)
			(xy 0.508 -58.698471) (xy 0.508 -60.13196) (xy 226.436428 -60.13196) (xy 226.436428 -59.26836) (xy 226.436918 -59.238392)
			(xy 226.444741 -59.17897) (xy 226.460254 -59.121077) (xy 226.48319 -59.065704) (xy 226.513157 -59.013798)
			(xy 226.549644 -58.966248) (xy 226.592024 -58.923868) (xy 226.639574 -58.887381) (xy 226.69148 -58.857414)
			(xy 226.746853 -58.834478) (xy 226.804746 -58.818965) (xy 226.864168 -58.811142) (xy 226.924104 -58.811142)
			(xy 226.983526 -58.818965) (xy 227.041419 -58.834478) (xy 227.096792 -58.857414) (xy 227.148698 -58.887381)
			(xy 227.196248 -58.923868) (xy 227.238628 -58.966248) (xy 227.275115 -59.013798) (xy 227.305082 -59.065704)
			(xy 227.328018 -59.121077) (xy 227.343531 -59.17897) (xy 227.351354 -59.238392) (xy 227.351844 -59.26836)
			(xy 227.351844 -60.13196) (xy 227.351354 -60.161928) (xy 227.343531 -60.22135) (xy 227.328018 -60.279243)
			(xy 227.305082 -60.334616) (xy 227.275115 -60.386522) (xy 227.238628 -60.434072) (xy 227.196248 -60.476452)
			(xy 227.148698 -60.512939) (xy 227.096792 -60.542906) (xy 227.041419 -60.565842) (xy 226.983526 -60.581355)
			(xy 226.924104 -60.589178) (xy 226.864168 -60.589178) (xy 226.804746 -60.581355) (xy 226.746853 -60.565842)
			(xy 226.69148 -60.542906) (xy 226.639574 -60.512939) (xy 226.592024 -60.476452) (xy 226.549644 -60.434072)
			(xy 226.513157 -60.386522) (xy 226.48319 -60.334616) (xy 226.460254 -60.279243) (xy 226.444741 -60.22135)
			(xy 226.436918 -60.161928) (xy 226.436428 -60.13196) (xy 0.508 -60.13196) (xy 0.508 -69.798271) (xy 229.808523 -69.798271)
			(xy 229.808523 -69.701577) (xy 229.816508 -69.605214) (xy 229.832424 -69.509839) (xy 229.85616 -69.416105)
			(xy 229.887557 -69.32465) (xy 229.926398 -69.236101) (xy 229.972419 -69.151061) (xy 230.025305 -69.070113)
			(xy 230.084696 -68.993808) (xy 230.150184 -68.922668) (xy 230.221324 -68.85718) (xy 230.297629 -68.797789)
			(xy 230.378577 -68.744903) (xy 230.463617 -68.698882) (xy 230.552166 -68.660041) (xy 230.643621 -68.628644)
			(xy 230.737355 -68.604908) (xy 230.83273 -68.588992) (xy 230.929093 -68.581007) (xy 231.025787 -68.581007)
			(xy 231.12215 -68.588992) (xy 231.217525 -68.604908) (xy 231.311259 -68.628644) (xy 231.402714 -68.660041)
			(xy 231.491263 -68.698882) (xy 231.576303 -68.744903) (xy 231.657251 -68.797789) (xy 231.733556 -68.85718)
			(xy 231.804696 -68.922668) (xy 231.870184 -68.993808) (xy 231.929575 -69.070113) (xy 231.982461 -69.151061)
			(xy 232.028482 -69.236101) (xy 232.067323 -69.32465) (xy 232.09872 -69.416105) (xy 232.122456 -69.509839)
			(xy 232.138372 -69.605214) (xy 232.146357 -69.701577) (xy 232.146856 -69.749924) (xy 232.146357 -69.798271)
			(xy 232.138372 -69.894634) (xy 232.122456 -69.990009) (xy 232.09872 -70.083743) (xy 232.067323 -70.175198)
			(xy 232.028482 -70.263747) (xy 231.982461 -70.348787) (xy 231.929575 -70.429735) (xy 231.870184 -70.50604)
			(xy 231.804696 -70.57718) (xy 231.733556 -70.642668) (xy 231.657251 -70.702059) (xy 231.576303 -70.754945)
			(xy 231.491263 -70.800966) (xy 231.402714 -70.839807) (xy 231.311259 -70.871204) (xy 231.217525 -70.89494)
			(xy 231.12215 -70.910856) (xy 231.025787 -70.918841) (xy 230.929093 -70.918841) (xy 230.83273 -70.910856)
			(xy 230.737355 -70.89494) (xy 230.643621 -70.871204) (xy 230.552166 -70.839807) (xy 230.463617 -70.800966)
			(xy 230.378577 -70.754945) (xy 230.297629 -70.702059) (xy 230.221324 -70.642668) (xy 230.150184 -70.57718)
			(xy 230.084696 -70.50604) (xy 230.025305 -70.429735) (xy 229.972419 -70.348787) (xy 229.926398 -70.263747)
			(xy 229.887557 -70.175198) (xy 229.85616 -70.083743) (xy 229.832424 -69.990009) (xy 229.816508 -69.894634)
			(xy 229.808523 -69.798271) (xy 0.508 -69.798271) (xy 0.508 -75.288385) (xy 262.150829 -75.288385)
			(xy 262.150829 -75.228415) (xy 262.158657 -75.168959) (xy 262.174178 -75.111033) (xy 262.197128 -75.055628)
			(xy 262.227114 -75.003693) (xy 262.263621 -74.956116) (xy 262.306027 -74.913712) (xy 262.353605 -74.877206)
			(xy 262.405541 -74.847222) (xy 262.460946 -74.824274) (xy 262.518872 -74.808754) (xy 262.578329 -74.800928)
			(xy 262.608314 -74.80046) (xy 263.471914 -74.80046) (xy 263.501899 -74.800907) (xy 263.561356 -74.808736)
			(xy 263.619283 -74.824259) (xy 263.674687 -74.84721) (xy 263.726623 -74.877196) (xy 263.7742 -74.913705)
			(xy 263.816604 -74.956111) (xy 263.853111 -75.003689) (xy 263.883096 -75.055625) (xy 263.906045 -75.111031)
			(xy 263.921566 -75.168958) (xy 263.929394 -75.228415) (xy 263.929394 -75.288385) (xy 263.921566 -75.347842)
			(xy 263.906045 -75.405769) (xy 263.883096 -75.461175) (xy 263.853111 -75.513111) (xy 263.816604 -75.560689)
			(xy 263.7742 -75.603095) (xy 263.726623 -75.639604) (xy 263.674687 -75.66959) (xy 263.619283 -75.692541)
			(xy 263.561356 -75.708064) (xy 263.501899 -75.715893) (xy 263.471914 -75.716384) (xy 262.608314 -75.716384)
			(xy 262.578329 -75.715872) (xy 262.518872 -75.708046) (xy 262.460946 -75.692526) (xy 262.405541 -75.669578)
			(xy 262.353605 -75.639594) (xy 262.306027 -75.603088) (xy 262.263621 -75.560684) (xy 262.227114 -75.513107)
			(xy 262.197128 -75.461172) (xy 262.174178 -75.405767) (xy 262.158657 -75.347841) (xy 262.150829 -75.288385)
			(xy 0.508 -75.288385) (xy 0.508 -76.826085) (xy 229.640845 -76.826085) (xy 229.640845 -76.766115)
			(xy 229.648673 -76.706658) (xy 229.664196 -76.648731) (xy 229.687147 -76.593327) (xy 229.717134 -76.541392)
			(xy 229.753643 -76.493816) (xy 229.796051 -76.451413) (xy 229.84363 -76.414908) (xy 229.895568 -76.384926)
			(xy 229.950975 -76.361981) (xy 230.008903 -76.346464) (xy 230.068361 -76.338642) (xy 230.098346 -76.338176)
			(xy 230.961946 -76.338176) (xy 230.991931 -76.338593) (xy 231.051387 -76.346426) (xy 231.109312 -76.361952)
			(xy 231.164715 -76.384906) (xy 231.216648 -76.414894) (xy 231.264223 -76.451404) (xy 231.306626 -76.493811)
			(xy 231.343131 -76.54139) (xy 231.373114 -76.593326) (xy 231.396063 -76.648732) (xy 231.411583 -76.706658)
			(xy 231.41941 -76.766115) (xy 231.41941 -76.826085) (xy 231.411583 -76.885542) (xy 231.396063 -76.943468)
			(xy 231.373114 -76.998874) (xy 231.343131 -77.05081) (xy 231.306626 -77.098389) (xy 231.264223 -77.140796)
			(xy 231.216648 -77.177306) (xy 231.164715 -77.207294) (xy 231.109312 -77.230248) (xy 231.051387 -77.245774)
			(xy 230.991931 -77.253607) (xy 230.961946 -77.2541) (xy 230.098346 -77.2541) (xy 230.068361 -77.253558)
			(xy 230.008903 -77.245736) (xy 229.950975 -77.230219) (xy 229.895568 -77.207274) (xy 229.84363 -77.177292)
			(xy 229.796051 -77.140787) (xy 229.753643 -77.098384) (xy 229.717134 -77.050808) (xy 229.687147 -76.998873)
			(xy 229.664196 -76.943469) (xy 229.648673 -76.885542) (xy 229.640845 -76.826085) (xy 0.508 -76.826085)
			(xy 0.508 -77.365367) (xy 105.150162 -77.365367) (xy 105.150162 -77.305433) (xy 105.157985 -77.246011)
			(xy 105.173496 -77.188119) (xy 105.19643 -77.132746) (xy 105.226396 -77.08084) (xy 105.26288 -77.03329)
			(xy 105.305258 -76.990908) (xy 105.352805 -76.954419) (xy 105.404708 -76.924449) (xy 105.460079 -76.901509)
			(xy 105.51797 -76.885993) (xy 105.577391 -76.878165) (xy 105.607358 -76.877672) (xy 106.470958 -76.877672)
			(xy 106.500928 -76.878178) (xy 106.560354 -76.885997) (xy 106.618252 -76.901506) (xy 106.67363 -76.92444)
			(xy 106.72554 -76.954406) (xy 106.773095 -76.990892) (xy 106.81548 -77.033273) (xy 106.851971 -77.080825)
			(xy 106.881942 -77.132732) (xy 106.904881 -77.188108) (xy 106.920395 -77.246004) (xy 106.928219 -77.305431)
			(xy 106.928219 -77.365367) (xy 109.150162 -77.365367) (xy 109.150162 -77.305433) (xy 109.157984 -77.246012)
			(xy 109.173495 -77.18812) (xy 109.196429 -77.132748) (xy 109.226394 -77.080843) (xy 109.262878 -77.033292)
			(xy 109.305255 -76.990911) (xy 109.352801 -76.954422) (xy 109.404703 -76.924452) (xy 109.460073 -76.901511)
			(xy 109.517963 -76.885994) (xy 109.577383 -76.878165) (xy 109.60735 -76.877672) (xy 110.47095 -76.877672)
			(xy 110.50092 -76.878178) (xy 110.560347 -76.885996) (xy 110.618246 -76.901504) (xy 110.673625 -76.924437)
			(xy 110.725536 -76.954403) (xy 110.773092 -76.990889) (xy 110.815478 -77.03327) (xy 110.851969 -77.080822)
			(xy 110.881941 -77.13273) (xy 110.90488 -77.188107) (xy 110.920395 -77.246003) (xy 110.928219 -77.30543)
			(xy 110.928219 -77.36537) (xy 110.920395 -77.424797) (xy 110.90488 -77.482693) (xy 110.881941 -77.53807)
			(xy 110.851969 -77.589978) (xy 110.815478 -77.63753) (xy 110.773092 -77.679911) (xy 110.725536 -77.716397)
			(xy 110.673625 -77.746363) (xy 110.618246 -77.769296) (xy 110.560347 -77.784804) (xy 110.50092 -77.792622)
			(xy 110.47095 -77.793088) (xy 109.60735 -77.793088) (xy 109.577383 -77.792635) (xy 109.517963 -77.784806)
			(xy 109.460073 -77.769289) (xy 109.404703 -77.746348) (xy 109.352801 -77.716378) (xy 109.305255 -77.679889)
			(xy 109.262878 -77.637508) (xy 109.226394 -77.589957) (xy 109.196429 -77.538052) (xy 109.173495 -77.48268)
			(xy 109.157984 -77.424788) (xy 109.150162 -77.365367) (xy 106.928219 -77.365367) (xy 106.928219 -77.365369)
			(xy 106.920395 -77.424796) (xy 106.904881 -77.482692) (xy 106.881942 -77.538068) (xy 106.851971 -77.589975)
			(xy 106.81548 -77.637527) (xy 106.773095 -77.679908) (xy 106.72554 -77.716394) (xy 106.67363 -77.74636)
			(xy 106.618252 -77.769294) (xy 106.560354 -77.784803) (xy 106.500928 -77.792622) (xy 106.470958 -77.793088)
			(xy 105.607358 -77.793088) (xy 105.577391 -77.792635) (xy 105.51797 -77.784807) (xy 105.460079 -77.769291)
			(xy 105.404708 -77.746351) (xy 105.352805 -77.716381) (xy 105.305258 -77.679892) (xy 105.26288 -77.63751)
			(xy 105.226396 -77.58996) (xy 105.19643 -77.538054) (xy 105.173496 -77.482681) (xy 105.157985 -77.424789)
			(xy 105.150162 -77.365367) (xy 0.508 -77.365367) (xy 0.508 -78.127367) (xy 107.150162 -78.127367)
			(xy 107.150162 -78.067433) (xy 107.157984 -78.008012) (xy 107.173496 -77.950119) (xy 107.19643 -77.894747)
			(xy 107.226395 -77.842842) (xy 107.262879 -77.795291) (xy 107.305256 -77.752909) (xy 107.352803 -77.716421)
			(xy 107.404706 -77.68645) (xy 107.460076 -77.66351) (xy 107.517966 -77.647993) (xy 107.577387 -77.640165)
			(xy 107.607354 -77.639672) (xy 108.470954 -77.639672) (xy 108.500924 -77.640178) (xy 108.560351 -77.647996)
			(xy 108.618249 -77.663505) (xy 108.673627 -77.686438) (xy 108.725538 -77.716405) (xy 108.773094 -77.752891)
			(xy 108.815479 -77.795272) (xy 108.85197 -77.842823) (xy 108.881941 -77.894731) (xy 108.90488 -77.950107)
			(xy 108.920395 -78.008004) (xy 108.928219 -78.06743) (xy 108.928219 -78.12737) (xy 108.920395 -78.186796)
			(xy 108.90488 -78.244693) (xy 108.881941 -78.300069) (xy 108.85197 -78.351977) (xy 108.815479 -78.399528)
			(xy 108.773093 -78.441909) (xy 108.725538 -78.478395) (xy 108.673627 -78.508362) (xy 108.618249 -78.531295)
			(xy 108.560351 -78.546804) (xy 108.500924 -78.554622) (xy 108.470954 -78.555088) (xy 107.607354 -78.555088)
			(xy 107.577387 -78.554635) (xy 107.517966 -78.546807) (xy 107.460076 -78.53129) (xy 107.404706 -78.50835)
			(xy 107.352803 -78.478379) (xy 107.305256 -78.441891) (xy 107.262879 -78.399509) (xy 107.226395 -78.351958)
			(xy 107.19643 -78.300053) (xy 107.173496 -78.244681) (xy 107.157984 -78.186788) (xy 107.150162 -78.127367)
			(xy 0.508 -78.127367) (xy 0.508 -79.238094) (xy 227.9777 -79.238094) (xy 227.9777 -78.374494) (xy 227.97819 -78.344526)
			(xy 227.986013 -78.285104) (xy 228.001526 -78.227211) (xy 228.024462 -78.171838) (xy 228.054429 -78.119932)
			(xy 228.090916 -78.072382) (xy 228.133296 -78.030002) (xy 228.180846 -77.993515) (xy 228.232752 -77.963548)
			(xy 228.288125 -77.940612) (xy 228.346018 -77.925099) (xy 228.40544 -77.917276) (xy 228.465376 -77.917276)
			(xy 228.524798 -77.925099) (xy 228.582691 -77.940612) (xy 228.638064 -77.963548) (xy 228.68997 -77.993515)
			(xy 228.73752 -78.030002) (xy 228.7799 -78.072382) (xy 228.816387 -78.119932) (xy 228.83413 -78.150664)
			(xy 336.40703 -78.150664) (xy 336.40703 -78.090736) (xy 336.414852 -78.031319) (xy 336.430363 -77.973433)
			(xy 336.453297 -77.918066) (xy 336.483261 -77.866166) (xy 336.519743 -77.818621) (xy 336.562119 -77.776245)
			(xy 336.609664 -77.739762) (xy 336.661564 -77.709797) (xy 336.716931 -77.686864) (xy 336.774817 -77.671353)
			(xy 336.834234 -77.66353) (xy 336.864198 -77.66304) (xy 337.727798 -77.66304) (xy 337.75777 -77.663413)
			(xy 337.817202 -77.671237) (xy 337.875104 -77.686751) (xy 337.930486 -77.709691) (xy 337.982399 -77.739663)
			(xy 338.029957 -77.776155) (xy 338.072344 -77.818542) (xy 338.108836 -77.866099) (xy 338.138808 -77.918013)
			(xy 338.161748 -77.973394) (xy 338.177263 -78.031296) (xy 338.185087 -78.090728) (xy 338.185087 -78.150672)
			(xy 338.177263 -78.210104) (xy 338.161748 -78.268006) (xy 338.138808 -78.323387) (xy 338.108836 -78.375301)
			(xy 338.072344 -78.422858) (xy 338.029957 -78.465245) (xy 337.982399 -78.501737) (xy 337.930486 -78.531709)
			(xy 337.875104 -78.554649) (xy 337.817202 -78.570163) (xy 337.75777 -78.577987) (xy 337.727798 -78.578456)
			(xy 336.864198 -78.578456) (xy 336.834234 -78.57787) (xy 336.774817 -78.570047) (xy 336.716931 -78.554536)
			(xy 336.661564 -78.531603) (xy 336.609664 -78.501638) (xy 336.562119 -78.465155) (xy 336.519743 -78.422779)
			(xy 336.483261 -78.375234) (xy 336.453297 -78.323334) (xy 336.430363 -78.267967) (xy 336.414852 -78.210081)
			(xy 336.40703 -78.150664) (xy 228.83413 -78.150664) (xy 228.846354 -78.171838) (xy 228.86929 -78.227211)
			(xy 228.884803 -78.285104) (xy 228.892626 -78.344526) (xy 228.893116 -78.374494) (xy 228.893116 -79.238094)
			(xy 228.892626 -79.268062) (xy 228.884803 -79.327484) (xy 228.86929 -79.385377) (xy 228.846354 -79.44075)
			(xy 228.816387 -79.492656) (xy 228.7799 -79.540206) (xy 228.73752 -79.582586) (xy 228.68997 -79.619073)
			(xy 228.638064 -79.64904) (xy 228.582691 -79.671976) (xy 228.524798 -79.687489) (xy 228.465376 -79.695312)
			(xy 228.40544 -79.695312) (xy 228.346018 -79.687489) (xy 228.288125 -79.671976) (xy 228.232752 -79.64904)
			(xy 228.180846 -79.619073) (xy 228.133296 -79.582586) (xy 228.090916 -79.540206) (xy 228.054429 -79.492656)
			(xy 228.024462 -79.44075) (xy 228.001526 -79.385377) (xy 227.986013 -79.327484) (xy 227.97819 -79.268062)
			(xy 227.9777 -79.238094) (xy 0.508 -79.238094) (xy 0.508 -80.183482) (xy 237.540292 -80.183482) (xy 237.540292 -79.319882)
			(xy 237.540782 -79.289914) (xy 237.548605 -79.230492) (xy 237.564118 -79.172599) (xy 237.587054 -79.117226)
			(xy 237.617021 -79.06532) (xy 237.653508 -79.01777) (xy 237.695888 -78.97539) (xy 237.743438 -78.938903)
			(xy 237.795344 -78.908936) (xy 237.850717 -78.886) (xy 237.90861 -78.870487) (xy 237.968032 -78.862664)
			(xy 238.027968 -78.862664) (xy 238.08739 -78.870487) (xy 238.145283 -78.886) (xy 238.200656 -78.908936)
			(xy 238.207117 -78.912666) (xy 334.407009 -78.912666) (xy 334.407009 -78.852734) (xy 334.414832 -78.793315)
			(xy 334.430343 -78.735425) (xy 334.453278 -78.680055) (xy 334.483244 -78.628153) (xy 334.519729 -78.580606)
			(xy 334.562107 -78.538227) (xy 334.609654 -78.501743) (xy 334.661557 -78.471777) (xy 334.716927 -78.448843)
			(xy 334.774817 -78.433331) (xy 334.834236 -78.425509) (xy 334.864202 -78.42504) (xy 335.727802 -78.42504)
			(xy 335.757773 -78.425434) (xy 335.817201 -78.433258) (xy 335.8751 -78.448773) (xy 335.930479 -78.471711)
			(xy 335.982389 -78.501682) (xy 336.029944 -78.538172) (xy 336.072329 -78.580557) (xy 336.108819 -78.628112)
			(xy 336.13879 -78.680023) (xy 336.161728 -78.735402) (xy 336.177242 -78.793301) (xy 336.185066 -78.852729)
			(xy 336.185066 -78.912664) (xy 338.40703 -78.912664) (xy 338.40703 -78.852736) (xy 338.414852 -78.79332)
			(xy 338.430363 -78.735433) (xy 338.453296 -78.680067) (xy 338.48326 -78.628167) (xy 338.519742 -78.580622)
			(xy 338.562118 -78.538246) (xy 338.609662 -78.501763) (xy 338.661561 -78.471799) (xy 338.716928 -78.448865)
			(xy 338.774814 -78.433353) (xy 338.83423 -78.42553) (xy 338.864194 -78.42504) (xy 339.727794 -78.42504)
			(xy 339.757766 -78.425412) (xy 339.817199 -78.433236) (xy 339.875101 -78.44875) (xy 339.930483 -78.47169)
			(xy 339.982397 -78.501662) (xy 340.029955 -78.538153) (xy 340.072343 -78.580541) (xy 340.108835 -78.628098)
			(xy 340.138808 -78.680011) (xy 340.161748 -78.735393) (xy 340.177263 -78.793296) (xy 340.185087 -78.852728)
			(xy 340.185087 -78.912672) (xy 340.177263 -78.972104) (xy 340.161748 -79.030007) (xy 340.138808 -79.085389)
			(xy 340.108835 -79.137302) (xy 340.072343 -79.184859) (xy 340.029955 -79.227247) (xy 339.982397 -79.263738)
			(xy 339.930483 -79.29371) (xy 339.875101 -79.31665) (xy 339.817199 -79.332164) (xy 339.757766 -79.339988)
			(xy 339.727794 -79.340456) (xy 338.864194 -79.340456) (xy 338.83423 -79.33987) (xy 338.774814 -79.332047)
			(xy 338.716928 -79.316535) (xy 338.661561 -79.293601) (xy 338.609662 -79.263637) (xy 338.562118 -79.227154)
			(xy 338.519742 -79.184778) (xy 338.48326 -79.137233) (xy 338.453296 -79.085333) (xy 338.430363 -79.029967)
			(xy 338.414852 -78.97208) (xy 338.40703 -78.912664) (xy 336.185066 -78.912664) (xy 336.185066 -78.912671)
			(xy 336.177242 -78.972099) (xy 336.161728 -79.029998) (xy 336.13879 -79.085377) (xy 336.108819 -79.137288)
			(xy 336.072329 -79.184843) (xy 336.029944 -79.227228) (xy 335.982389 -79.263718) (xy 335.930479 -79.293689)
			(xy 335.8751 -79.316627) (xy 335.817201 -79.332142) (xy 335.757773 -79.339966) (xy 335.727802 -79.340456)
			(xy 334.864202 -79.340456) (xy 334.834236 -79.339891) (xy 334.774817 -79.332069) (xy 334.716927 -79.316557)
			(xy 334.661557 -79.293623) (xy 334.609654 -79.263657) (xy 334.562107 -79.227173) (xy 334.519729 -79.184794)
			(xy 334.483244 -79.137247) (xy 334.453278 -79.085345) (xy 334.430343 -79.029975) (xy 334.414832 -78.972085)
			(xy 334.407009 -78.912666) (xy 238.207117 -78.912666) (xy 238.252562 -78.938903) (xy 238.300112 -78.97539)
			(xy 238.342492 -79.01777) (xy 238.378979 -79.06532) (xy 238.408946 -79.117226) (xy 238.431882 -79.172599)
			(xy 238.447395 -79.230492) (xy 238.455218 -79.289914) (xy 238.455708 -79.319882) (xy 238.455708 -80.183482)
			(xy 238.455218 -80.21345) (xy 238.447395 -80.272872) (xy 238.431882 -80.330765) (xy 238.408946 -80.386138)
			(xy 238.378979 -80.438044) (xy 238.342492 -80.485594) (xy 238.300112 -80.527974) (xy 238.252562 -80.564461)
			(xy 238.200656 -80.594428) (xy 238.145283 -80.617364) (xy 238.08739 -80.632877) (xy 238.027968 -80.6407)
			(xy 237.968032 -80.6407) (xy 237.90861 -80.632877) (xy 237.850717 -80.617364) (xy 237.795344 -80.594428)
			(xy 237.743438 -80.564461) (xy 237.695888 -80.527974) (xy 237.653508 -80.485594) (xy 237.617021 -80.438044)
			(xy 237.587054 -80.386138) (xy 237.564118 -80.330765) (xy 237.548605 -80.272872) (xy 237.540782 -80.21345)
			(xy 237.540292 -80.183482) (xy 0.508 -80.183482) (xy 0.508 -82.131916) (xy 0.508487 -82.185165) (xy 0.516104 -82.291392)
			(xy 0.531277 -82.396804) (xy 0.553928 -82.500867) (xy 0.583941 -82.603049) (xy 0.621164 -82.702831)
			(xy 0.665407 -82.799705) (xy 0.716446 -82.893178) (xy 0.774019 -82.982773) (xy 0.837835 -83.068035)
			(xy 0.907568 -83.14853) (xy 0.94488 -83.186524) (xy 2.783716 -85.025538) (xy 44.856389 -85.025538)
			(xy 44.856389 -84.896398) (xy 44.864339 -84.767503) (xy 44.880209 -84.639343) (xy 44.903938 -84.512402)
			(xy 44.935437 -84.387163) (xy 44.974586 -84.2641) (xy 45.021237 -84.143681) (xy 45.075212 -84.026362)
			(xy 45.136307 -83.912588) (xy 45.20429 -83.802791) (xy 45.278904 -83.697388) (xy 45.359865 -83.596778)
			(xy 45.446865 -83.501343) (xy 45.539576 -83.411444) (xy 45.637646 -83.327423) (xy 45.740701 -83.249599)
			(xy 45.848352 -83.178267) (xy 45.960191 -83.113697) (xy 46.075792 -83.056135) (xy 46.194717 -83.005798)
			(xy 46.316516 -82.962878) (xy 46.440726 -82.927537) (xy 46.566875 -82.89991) (xy 46.694487 -82.880101)
			(xy 46.823076 -82.868185) (xy 46.952154 -82.864209) (xy 47.081232 -82.868185) (xy 47.209821 -82.880101)
			(xy 47.337433 -82.89991) (xy 47.463582 -82.927537) (xy 47.587792 -82.962878) (xy 47.709591 -83.005798)
			(xy 47.828516 -83.056135) (xy 47.944117 -83.113697) (xy 48.055956 -83.178267) (xy 48.163607 -83.249599)
			(xy 48.266662 -83.327423) (xy 48.303507 -83.35899) (xy 116.623592 -83.35899) (xy 116.623592 -82.49539)
			(xy 116.624082 -82.465422) (xy 116.631905 -82.406) (xy 116.647418 -82.348107) (xy 116.670354 -82.292734)
			(xy 116.700321 -82.240828) (xy 116.736808 -82.193278) (xy 116.779188 -82.150898) (xy 116.826738 -82.114411)
			(xy 116.878644 -82.084444) (xy 116.934017 -82.061508) (xy 116.99191 -82.045995) (xy 117.051332 -82.038172)
			(xy 117.111268 -82.038172) (xy 117.17069 -82.045995) (xy 117.228583 -82.061508) (xy 117.283956 -82.084444)
			(xy 117.335862 -82.114411) (xy 117.383412 -82.150898) (xy 117.425792 -82.193278) (xy 117.462279 -82.240828)
			(xy 117.492246 -82.292734) (xy 117.515182 -82.348107) (xy 117.530695 -82.406) (xy 117.538518 -82.465422)
			(xy 117.539008 -82.49539) (xy 117.539008 -83.35899) (xy 117.538875 -83.367118) (xy 232.68432 -83.367118)
			(xy 232.68432 -82.503518) (xy 232.68481 -82.47355) (xy 232.692633 -82.414128) (xy 232.708146 -82.356235)
			(xy 232.731082 -82.300862) (xy 232.761049 -82.248956) (xy 232.797536 -82.201406) (xy 232.839916 -82.159026)
			(xy 232.887466 -82.122539) (xy 232.939372 -82.092572) (xy 232.994745 -82.069636) (xy 233.052638 -82.054123)
			(xy 233.11206 -82.0463) (xy 233.171996 -82.0463) (xy 233.231418 -82.054123) (xy 233.289311 -82.069636)
			(xy 233.344684 -82.092572) (xy 233.39659 -82.122539) (xy 233.44414 -82.159026) (xy 233.48652 -82.201406)
			(xy 233.523007 -82.248956) (xy 233.552974 -82.300862) (xy 233.568014 -82.337171) (xy 238.132537 -82.337171)
			(xy 238.132537 -82.277229) (xy 238.140362 -82.217799) (xy 238.155876 -82.159898) (xy 238.178816 -82.104519)
			(xy 238.208788 -82.052607) (xy 238.24528 -82.005052) (xy 238.287667 -81.962667) (xy 238.335224 -81.926177)
			(xy 238.387137 -81.896207) (xy 238.442517 -81.87327) (xy 238.500418 -81.857758) (xy 238.559849 -81.849936)
			(xy 238.58982 -81.849468) (xy 239.45342 -81.849468) (xy 239.483385 -81.850007) (xy 239.542803 -81.857832)
			(xy 239.600691 -81.873345) (xy 239.656058 -81.896282) (xy 239.707959 -81.926248) (xy 239.755504 -81.962733)
			(xy 239.769238 -81.976468) (xy 273.798284 -81.976468) (xy 273.798284 -81.112868) (xy 273.798774 -81.0829)
			(xy 273.806597 -81.023478) (xy 273.82211 -80.965585) (xy 273.845046 -80.910212) (xy 273.875013 -80.858306)
			(xy 273.9115 -80.810756) (xy 273.95388 -80.768376) (xy 274.00143 -80.731889) (xy 274.053336 -80.701922)
			(xy 274.108709 -80.678986) (xy 274.166602 -80.663473) (xy 274.226024 -80.65565) (xy 274.28596 -80.65565)
			(xy 274.345382 -80.663473) (xy 274.403275 -80.678986) (xy 274.458648 -80.701922) (xy 274.510554 -80.731889)
			(xy 274.558104 -80.768376) (xy 274.600484 -80.810756) (xy 274.636971 -80.858306) (xy 274.666938 -80.910212)
			(xy 274.689874 -80.965585) (xy 274.705387 -81.023478) (xy 274.71321 -81.0829) (xy 274.7137 -81.112868)
			(xy 274.7137 -81.976468) (xy 274.71321 -82.006436) (xy 274.705387 -82.065858) (xy 274.689874 -82.123751)
			(xy 274.666938 -82.179124) (xy 274.636971 -82.23103) (xy 274.600484 -82.27858) (xy 274.558104 -82.32096)
			(xy 274.510554 -82.357447) (xy 274.458648 -82.387414) (xy 274.403275 -82.41035) (xy 274.345382 -82.425863)
			(xy 274.28596 -82.433686) (xy 274.226024 -82.433686) (xy 274.166602 -82.425863) (xy 274.108709 -82.41035)
			(xy 274.053336 -82.387414) (xy 274.00143 -82.357447) (xy 273.95388 -82.32096) (xy 273.9115 -82.27858)
			(xy 273.875013 -82.23103) (xy 273.845046 -82.179124) (xy 273.82211 -82.123751) (xy 273.806597 -82.065858)
			(xy 273.798774 -82.006436) (xy 273.798284 -81.976468) (xy 239.769238 -81.976468) (xy 239.79788 -82.005111)
			(xy 239.834363 -82.052658) (xy 239.864327 -82.10456) (xy 239.887261 -82.159928) (xy 239.902772 -82.217817)
			(xy 239.910594 -82.277235) (xy 239.910594 -82.337165) (xy 239.902772 -82.396583) (xy 239.887261 -82.454472)
			(xy 239.864327 -82.50984) (xy 239.834363 -82.561742) (xy 239.79788 -82.609289) (xy 239.755504 -82.651667)
			(xy 239.707959 -82.688152) (xy 239.656058 -82.718118) (xy 239.600691 -82.741055) (xy 239.542803 -82.756568)
			(xy 239.483385 -82.764393) (xy 239.45342 -82.764884) (xy 238.58982 -82.764884) (xy 238.559849 -82.764464)
			(xy 238.500418 -82.756642) (xy 238.442517 -82.74113) (xy 238.387137 -82.718193) (xy 238.335224 -82.688223)
			(xy 238.287667 -82.651733) (xy 238.24528 -82.609348) (xy 238.208788 -82.561793) (xy 238.178816 -82.509881)
			(xy 238.155876 -82.454502) (xy 238.140362 -82.396601) (xy 238.132537 -82.337171) (xy 233.568014 -82.337171)
			(xy 233.57591 -82.356235) (xy 233.591423 -82.414128) (xy 233.599246 -82.47355) (xy 233.599736 -82.503518)
			(xy 233.599736 -83.367118) (xy 233.599246 -83.397086) (xy 233.591423 -83.456508) (xy 233.57591 -83.514401)
			(xy 233.552974 -83.569774) (xy 233.523007 -83.62168) (xy 233.48652 -83.66923) (xy 233.44414 -83.71161)
			(xy 233.39659 -83.748097) (xy 233.344684 -83.778064) (xy 233.289311 -83.801) (xy 233.231418 -83.816513)
			(xy 233.171996 -83.824336) (xy 233.11206 -83.824336) (xy 233.052638 -83.816513) (xy 232.994745 -83.801)
			(xy 232.939372 -83.778064) (xy 232.887466 -83.748097) (xy 232.839916 -83.71161) (xy 232.797536 -83.66923)
			(xy 232.761049 -83.62168) (xy 232.731082 -83.569774) (xy 232.708146 -83.514401) (xy 232.692633 -83.456508)
			(xy 232.68481 -83.397086) (xy 232.68432 -83.367118) (xy 117.538875 -83.367118) (xy 117.538518 -83.388958)
			(xy 117.530695 -83.44838) (xy 117.515182 -83.506273) (xy 117.492246 -83.561646) (xy 117.462279 -83.613552)
			(xy 117.425792 -83.661102) (xy 117.383412 -83.703482) (xy 117.335862 -83.739969) (xy 117.283956 -83.769936)
			(xy 117.228583 -83.792872) (xy 117.17069 -83.808385) (xy 117.111268 -83.816208) (xy 117.051332 -83.816208)
			(xy 116.99191 -83.808385) (xy 116.934017 -83.792872) (xy 116.878644 -83.769936) (xy 116.826738 -83.739969)
			(xy 116.779188 -83.703482) (xy 116.736808 -83.661102) (xy 116.700321 -83.613552) (xy 116.670354 -83.561646)
			(xy 116.647418 -83.506273) (xy 116.631905 -83.44838) (xy 116.624082 -83.388958) (xy 116.623592 -83.35899)
			(xy 48.303507 -83.35899) (xy 48.364732 -83.411444) (xy 48.457443 -83.501343) (xy 48.544443 -83.596778)
			(xy 48.625404 -83.697388) (xy 48.700018 -83.802791) (xy 48.768001 -83.912588) (xy 48.829096 -84.026362)
			(xy 48.883071 -84.143681) (xy 48.929722 -84.2641) (xy 48.968871 -84.387163) (xy 49.00037 -84.512402)
			(xy 49.024099 -84.639343) (xy 49.039969 -84.767503) (xy 49.047919 -84.896398) (xy 49.048416 -84.960968)
			(xy 49.047919 -85.025538) (xy 49.039969 -85.154433) (xy 49.024099 -85.282593) (xy 49.009819 -85.358986)
			(xy 117.385592 -85.358986) (xy 117.385592 -84.495386) (xy 117.386082 -84.465418) (xy 117.393905 -84.405996)
			(xy 117.409418 -84.348103) (xy 117.432354 -84.29273) (xy 117.462321 -84.240824) (xy 117.498808 -84.193274)
			(xy 117.541188 -84.150894) (xy 117.588738 -84.114407) (xy 117.640644 -84.08444) (xy 117.696017 -84.061504)
			(xy 117.75391 -84.045991) (xy 117.813332 -84.038168) (xy 117.873268 -84.038168) (xy 117.93269 -84.045991)
			(xy 117.990583 -84.061504) (xy 118.045956 -84.08444) (xy 118.097862 -84.114407) (xy 118.145412 -84.150894)
			(xy 118.187792 -84.193274) (xy 118.224279 -84.240824) (xy 118.254246 -84.29273) (xy 118.277182 -84.348103)
			(xy 118.292695 -84.405996) (xy 118.300518 -84.465418) (xy 118.301008 -84.495386) (xy 118.301008 -85.358986)
			(xy 118.300518 -85.388954) (xy 118.292695 -85.448376) (xy 118.289959 -85.458587) (xy 232.264389 -85.458587)
			(xy 232.264389 -85.398613) (xy 232.272218 -85.339151) (xy 232.28774 -85.28122) (xy 232.310692 -85.225811)
			(xy 232.34068 -85.173871) (xy 232.377191 -85.126291) (xy 232.4196 -85.083883) (xy 232.467181 -85.047373)
			(xy 232.519122 -85.017387) (xy 232.574531 -84.994437) (xy 232.632463 -84.978915) (xy 232.691925 -84.971088)
			(xy 232.721912 -84.97062) (xy 233.585512 -84.97062) (xy 233.615495 -84.971147) (xy 233.674947 -84.978975)
			(xy 233.732868 -84.994497) (xy 233.788268 -85.017445) (xy 233.840199 -85.047429) (xy 233.887772 -85.083934)
			(xy 233.930174 -85.126337) (xy 233.963295 -85.169502) (xy 238.555276 -85.169502) (xy 238.555276 -84.305902)
			(xy 238.555766 -84.275918) (xy 238.563594 -84.216462) (xy 238.579115 -84.158537) (xy 238.602064 -84.103133)
			(xy 238.632048 -84.051199) (xy 238.668554 -84.003623) (xy 238.710959 -83.961218) (xy 238.758535 -83.924712)
			(xy 238.810469 -83.894728) (xy 238.865873 -83.871779) (xy 238.923798 -83.856258) (xy 238.983254 -83.84843)
			(xy 239.043222 -83.84843) (xy 239.102678 -83.856258) (xy 239.160603 -83.871779) (xy 239.216007 -83.894728)
			(xy 239.267941 -83.924712) (xy 239.315517 -83.961218) (xy 239.357922 -84.003623) (xy 239.394428 -84.051199)
			(xy 239.424412 -84.103133) (xy 239.447361 -84.158537) (xy 239.462882 -84.216462) (xy 239.46603 -84.24037)
			(xy 273.951192 -84.24037) (xy 273.951192 -83.37677) (xy 273.951682 -83.346786) (xy 273.95951 -83.28733)
			(xy 273.975031 -83.229405) (xy 273.99798 -83.174001) (xy 274.027964 -83.122067) (xy 274.06447 -83.074491)
			(xy 274.106875 -83.032086) (xy 274.154451 -82.99558) (xy 274.206385 -82.965596) (xy 274.261789 -82.942647)
			(xy 274.319714 -82.927126) (xy 274.37917 -82.919298) (xy 274.439138 -82.919298) (xy 274.498594 -82.927126)
			(xy 274.556519 -82.942647) (xy 274.611923 -82.965596) (xy 274.663857 -82.99558) (xy 274.711433 -83.032086)
			(xy 274.753838 -83.074491) (xy 274.790344 -83.122067) (xy 274.820328 -83.174001) (xy 274.843277 -83.229405)
			(xy 274.858798 -83.28733) (xy 274.866626 -83.346786) (xy 274.867116 -83.37677) (xy 274.867116 -84.144612)
			(xy 345.879928 -84.144612) (xy 345.879928 -83.281012) (xy 345.880418 -83.251028) (xy 345.888246 -83.191572)
			(xy 345.903767 -83.133647) (xy 345.926716 -83.078243) (xy 345.9567 -83.026309) (xy 345.993206 -82.978733)
			(xy 346.035611 -82.936328) (xy 346.083187 -82.899822) (xy 346.135121 -82.869838) (xy 346.190525 -82.846889)
			(xy 346.24845 -82.831368) (xy 346.307906 -82.82354) (xy 346.367874 -82.82354) (xy 346.42733 -82.831368)
			(xy 346.485255 -82.846889) (xy 346.540659 -82.869838) (xy 346.592593 -82.899822) (xy 346.640169 -82.936328)
			(xy 346.682574 -82.978733) (xy 346.71908 -83.026309) (xy 346.749064 -83.078243) (xy 346.772013 -83.133647)
			(xy 346.787534 -83.191572) (xy 346.795362 -83.251028) (xy 346.795852 -83.281012) (xy 346.795852 -84.144612)
			(xy 346.795362 -84.174596) (xy 346.787534 -84.234052) (xy 346.772013 -84.291977) (xy 346.749064 -84.347381)
			(xy 346.71908 -84.399315) (xy 346.682574 -84.446891) (xy 346.640169 -84.489296) (xy 346.592593 -84.525802)
			(xy 346.540659 -84.555786) (xy 346.485255 -84.578735) (xy 346.42733 -84.594256) (xy 346.367874 -84.602084)
			(xy 346.307906 -84.602084) (xy 346.24845 -84.594256) (xy 346.190525 -84.578735) (xy 346.135121 -84.555786)
			(xy 346.083187 -84.525802) (xy 346.035611 -84.489296) (xy 345.993206 -84.446891) (xy 345.9567 -84.399315)
			(xy 345.926716 -84.347381) (xy 345.903767 -84.291977) (xy 345.888246 -84.234052) (xy 345.880418 -84.174596)
			(xy 345.879928 -84.144612) (xy 274.867116 -84.144612) (xy 274.867116 -84.24037) (xy 274.866626 -84.270354)
			(xy 274.858798 -84.32981) (xy 274.843277 -84.387735) (xy 274.820328 -84.443139) (xy 274.790344 -84.495073)
			(xy 274.753838 -84.542649) (xy 274.711433 -84.585054) (xy 274.663857 -84.62156) (xy 274.611923 -84.651544)
			(xy 274.556519 -84.674493) (xy 274.498594 -84.690014) (xy 274.439138 -84.697842) (xy 274.37917 -84.697842)
			(xy 274.319714 -84.690014) (xy 274.261789 -84.674493) (xy 274.206385 -84.651544) (xy 274.154451 -84.62156)
			(xy 274.106875 -84.585054) (xy 274.06447 -84.542649) (xy 274.027964 -84.495073) (xy 273.99798 -84.443139)
			(xy 273.975031 -84.387735) (xy 273.95951 -84.32981) (xy 273.951682 -84.270354) (xy 273.951192 -84.24037)
			(xy 239.46603 -84.24037) (xy 239.47071 -84.275918) (xy 239.4712 -84.305902) (xy 239.4712 -85.169502)
			(xy 239.47071 -85.199486) (xy 239.462882 -85.258942) (xy 239.447361 -85.316867) (xy 239.424412 -85.372271)
			(xy 239.394428 -85.424205) (xy 239.357922 -85.471781) (xy 239.315517 -85.514186) (xy 239.267941 -85.550692)
			(xy 239.216007 -85.580676) (xy 239.160603 -85.603625) (xy 239.102678 -85.619146) (xy 239.043222 -85.626974)
			(xy 238.983254 -85.626974) (xy 238.923798 -85.619146) (xy 238.865873 -85.603625) (xy 238.810469 -85.580676)
			(xy 238.758535 -85.550692) (xy 238.710959 -85.514186) (xy 238.668554 -85.471781) (xy 238.632048 -85.424205)
			(xy 238.602064 -85.372271) (xy 238.579115 -85.316867) (xy 238.563594 -85.258942) (xy 238.555766 -85.199486)
			(xy 238.555276 -85.169502) (xy 233.963295 -85.169502) (xy 233.966678 -85.173911) (xy 233.99666 -85.225842)
			(xy 234.019607 -85.281243) (xy 234.035127 -85.339165) (xy 234.042954 -85.398617) (xy 234.042954 -85.458583)
			(xy 234.035127 -85.518035) (xy 234.019607 -85.575957) (xy 233.99666 -85.631358) (xy 233.966678 -85.683289)
			(xy 233.930174 -85.730863) (xy 233.887772 -85.773266) (xy 233.840199 -85.809771) (xy 233.788268 -85.839755)
			(xy 233.732868 -85.862703) (xy 233.674947 -85.878225) (xy 233.615495 -85.886053) (xy 233.585512 -85.886544)
			(xy 232.721912 -85.886544) (xy 232.691925 -85.886112) (xy 232.632463 -85.878285) (xy 232.574531 -85.862763)
			(xy 232.519122 -85.839813) (xy 232.467181 -85.809827) (xy 232.4196 -85.773317) (xy 232.377191 -85.730909)
			(xy 232.34068 -85.683329) (xy 232.310692 -85.631389) (xy 232.28774 -85.57598) (xy 232.272218 -85.518049)
			(xy 232.264389 -85.458587) (xy 118.289959 -85.458587) (xy 118.277182 -85.506269) (xy 118.254246 -85.561642)
			(xy 118.224279 -85.613548) (xy 118.187792 -85.661098) (xy 118.145412 -85.703478) (xy 118.097862 -85.739965)
			(xy 118.045956 -85.769932) (xy 117.990583 -85.792868) (xy 117.93269 -85.808381) (xy 117.873268 -85.816204)
			(xy 117.813332 -85.816204) (xy 117.75391 -85.808381) (xy 117.696017 -85.792868) (xy 117.640644 -85.769932)
			(xy 117.588738 -85.739965) (xy 117.541188 -85.703478) (xy 117.498808 -85.661098) (xy 117.462321 -85.613548)
			(xy 117.432354 -85.561642) (xy 117.409418 -85.506269) (xy 117.393905 -85.448376) (xy 117.386082 -85.388954)
			(xy 117.385592 -85.358986) (xy 49.009819 -85.358986) (xy 49.00037 -85.409534) (xy 48.968871 -85.534773)
			(xy 48.929722 -85.657836) (xy 48.883071 -85.778255) (xy 48.829096 -85.895574) (xy 48.768001 -86.009348)
			(xy 48.700018 -86.119145) (xy 48.625404 -86.224548) (xy 48.544443 -86.325158) (xy 48.457443 -86.420593)
			(xy 48.364732 -86.510492) (xy 48.266662 -86.594513) (xy 48.163607 -86.672337) (xy 48.055956 -86.743669)
			(xy 47.944117 -86.808239) (xy 47.937853 -86.811358) (xy 99.84232 -86.811358) (xy 99.84232 -85.947758)
			(xy 99.84281 -85.917774) (xy 99.850638 -85.858318) (xy 99.866159 -85.800393) (xy 99.889108 -85.744989)
			(xy 99.919092 -85.693055) (xy 99.955598 -85.645479) (xy 99.998003 -85.603074) (xy 100.045579 -85.566568)
			(xy 100.097513 -85.536584) (xy 100.152917 -85.513635) (xy 100.210842 -85.498114) (xy 100.270298 -85.490286)
			(xy 100.330266 -85.490286) (xy 100.389722 -85.498114) (xy 100.447647 -85.513635) (xy 100.503051 -85.536584)
			(xy 100.554985 -85.566568) (xy 100.602561 -85.603074) (xy 100.644966 -85.645479) (xy 100.681472 -85.693055)
			(xy 100.711456 -85.744989) (xy 100.734405 -85.800393) (xy 100.749926 -85.858318) (xy 100.757754 -85.917774)
			(xy 100.758244 -85.947758) (xy 100.758244 -86.811358) (xy 100.757754 -86.841342) (xy 100.749926 -86.900798)
			(xy 100.734405 -86.958723) (xy 100.711456 -87.014127) (xy 100.681472 -87.066061) (xy 100.644966 -87.113637)
			(xy 100.602561 -87.156042) (xy 100.554985 -87.192548) (xy 100.503051 -87.222532) (xy 100.447647 -87.245481)
			(xy 100.389722 -87.261002) (xy 100.330266 -87.26883) (xy 100.270298 -87.26883) (xy 100.210842 -87.261002)
			(xy 100.152917 -87.245481) (xy 100.097513 -87.222532) (xy 100.045579 -87.192548) (xy 99.998003 -87.156042)
			(xy 99.955598 -87.113637) (xy 99.919092 -87.066061) (xy 99.889108 -87.014127) (xy 99.866159 -86.958723)
			(xy 99.850638 -86.900798) (xy 99.84281 -86.841342) (xy 99.84232 -86.811358) (xy 47.937853 -86.811358)
			(xy 47.828516 -86.865801) (xy 47.709591 -86.916138) (xy 47.587792 -86.959058) (xy 47.463582 -86.994399)
			(xy 47.337433 -87.022026) (xy 47.209821 -87.041835) (xy 47.081232 -87.053751) (xy 46.952154 -87.057728)
			(xy 46.823076 -87.053751) (xy 46.694487 -87.041835) (xy 46.566875 -87.022026) (xy 46.440726 -86.994399)
			(xy 46.316516 -86.959058) (xy 46.194717 -86.916138) (xy 46.075792 -86.865801) (xy 45.960191 -86.808239)
			(xy 45.848352 -86.743669) (xy 45.740701 -86.672337) (xy 45.637646 -86.594513) (xy 45.539576 -86.510492)
			(xy 45.446865 -86.420593) (xy 45.359865 -86.325158) (xy 45.278904 -86.224548) (xy 45.20429 -86.119145)
			(xy 45.136307 -86.009348) (xy 45.075212 -85.895574) (xy 45.021237 -85.778255) (xy 44.974586 -85.657836)
			(xy 44.935437 -85.534773) (xy 44.903938 -85.409534) (xy 44.880209 -85.282593) (xy 44.864339 -85.154433)
			(xy 44.856389 -85.025538) (xy 2.783716 -85.025538) (xy 3.573272 -85.81517) (xy 3.622687 -85.865245)
			(xy 3.716468 -85.970133) (xy 3.804219 -86.080117) (xy 3.885663 -86.194848) (xy 3.960544 -86.313966)
			(xy 4.028628 -86.437097) (xy 4.089698 -86.563852) (xy 4.143563 -86.693833) (xy 4.190054 -86.82663)
			(xy 4.229024 -86.961825) (xy 4.260351 -87.098994) (xy 4.283935 -87.237703) (xy 4.297613 -87.358982)
			(xy 116.623592 -87.358982) (xy 116.623592 -86.495382) (xy 116.624082 -86.465414) (xy 116.631905 -86.405992)
			(xy 116.647418 -86.348099) (xy 116.670354 -86.292726) (xy 116.700321 -86.24082) (xy 116.736808 -86.19327)
			(xy 116.779188 -86.15089) (xy 116.826738 -86.114403) (xy 116.878644 -86.084436) (xy 116.934017 -86.0615)
			(xy 116.99191 -86.045987) (xy 117.051332 -86.038164) (xy 117.111268 -86.038164) (xy 117.17069 -86.045987)
			(xy 117.228583 -86.0615) (xy 117.283956 -86.084436) (xy 117.335862 -86.114403) (xy 117.383412 -86.15089)
			(xy 117.425792 -86.19327) (xy 117.462279 -86.24082) (xy 117.492246 -86.292726) (xy 117.515182 -86.348099)
			(xy 117.530695 -86.405992) (xy 117.538518 -86.465414) (xy 117.539008 -86.495382) (xy 117.539008 -87.358982)
			(xy 117.538518 -87.38895) (xy 117.531262 -87.444066) (xy 232.194882 -87.444066) (xy 232.194882 -87.384134)
			(xy 232.202704 -87.324714) (xy 232.218215 -87.266824) (xy 232.241149 -87.211454) (xy 232.271114 -87.15955)
			(xy 232.307596 -87.112002) (xy 232.349973 -87.069621) (xy 232.397519 -87.033135) (xy 232.44942 -87.003166)
			(xy 232.504788 -86.980227) (xy 232.562677 -86.964712) (xy 232.622096 -86.956884) (xy 232.652062 -86.956392)
			(xy 233.515662 -86.956392) (xy 233.545633 -86.956859) (xy 233.605062 -86.964678) (xy 233.662961 -86.980188)
			(xy 233.718341 -87.003123) (xy 233.770254 -87.033091) (xy 233.81781 -87.069578) (xy 233.860197 -87.111961)
			(xy 233.896688 -87.159515) (xy 233.92666 -87.211425) (xy 233.9496 -87.266803) (xy 233.965115 -87.324701)
			(xy 233.972939 -87.384129) (xy 233.972939 -87.416385) (xy 234.381521 -87.416385) (xy 234.381521 -87.356415)
			(xy 234.389349 -87.296959) (xy 234.40487 -87.239032) (xy 234.42782 -87.183628) (xy 234.457804 -87.131692)
			(xy 234.494312 -87.084115) (xy 234.536717 -87.04171) (xy 234.584294 -87.005203) (xy 234.636229 -86.975219)
			(xy 234.691634 -86.952269) (xy 234.749561 -86.936748) (xy 234.809017 -86.928921) (xy 234.839002 -86.928452)
			(xy 235.702602 -86.928452) (xy 235.732587 -86.928914) (xy 235.792044 -86.936742) (xy 235.849971 -86.952264)
			(xy 235.905376 -86.975214) (xy 235.957312 -87.005199) (xy 236.004889 -87.041707) (xy 236.047295 -87.084112)
			(xy 236.083802 -87.13169) (xy 236.113787 -87.183626) (xy 236.136737 -87.239031) (xy 236.152258 -87.296958)
			(xy 236.155843 -87.324184) (xy 330.477876 -87.324184) (xy 330.477876 -86.460584) (xy 330.478366 -86.430616)
			(xy 330.486189 -86.371194) (xy 330.501702 -86.313301) (xy 330.524638 -86.257928) (xy 330.554605 -86.206022)
			(xy 330.591092 -86.158472) (xy 330.633472 -86.116092) (xy 330.681022 -86.079605) (xy 330.732928 -86.049638)
			(xy 330.788301 -86.026702) (xy 330.846194 -86.011189) (xy 330.905616 -86.003366) (xy 330.965552 -86.003366)
			(xy 331.024974 -86.011189) (xy 331.082867 -86.026702) (xy 331.13824 -86.049638) (xy 331.190146 -86.079605)
			(xy 331.237696 -86.116092) (xy 331.266212 -86.144608) (xy 346.641928 -86.144608) (xy 346.641928 -85.281008)
			(xy 346.642418 -85.251024) (xy 346.650246 -85.191568) (xy 346.665767 -85.133643) (xy 346.688716 -85.078239)
			(xy 346.7187 -85.026305) (xy 346.755206 -84.978729) (xy 346.797611 -84.936324) (xy 346.845187 -84.899818)
			(xy 346.897121 -84.869834) (xy 346.952525 -84.846885) (xy 347.01045 -84.831364) (xy 347.069906 -84.823536)
			(xy 347.129874 -84.823536) (xy 347.18933 -84.831364) (xy 347.247255 -84.846885) (xy 347.302659 -84.869834)
			(xy 347.354593 -84.899818) (xy 347.402169 -84.936324) (xy 347.444574 -84.978729) (xy 347.48108 -85.026305)
			(xy 347.511064 -85.078239) (xy 347.534013 -85.133643) (xy 347.549534 -85.191568) (xy 347.557362 -85.251024)
			(xy 347.557852 -85.281008) (xy 347.557852 -86.144608) (xy 347.557362 -86.174592) (xy 347.549534 -86.234048)
			(xy 347.534013 -86.291973) (xy 347.511064 -86.347377) (xy 347.48108 -86.399311) (xy 347.444574 -86.446887)
			(xy 347.402169 -86.489292) (xy 347.354593 -86.525798) (xy 347.302659 -86.555782) (xy 347.247255 -86.578731)
			(xy 347.18933 -86.594252) (xy 347.129874 -86.60208) (xy 347.069906 -86.60208) (xy 347.01045 -86.594252)
			(xy 346.952525 -86.578731) (xy 346.897121 -86.555782) (xy 346.845187 -86.525798) (xy 346.797611 -86.489292)
			(xy 346.755206 -86.446887) (xy 346.7187 -86.399311) (xy 346.688716 -86.347377) (xy 346.665767 -86.291973)
			(xy 346.650246 -86.234048) (xy 346.642418 -86.174592) (xy 346.641928 -86.144608) (xy 331.266212 -86.144608)
			(xy 331.280076 -86.158472) (xy 331.316563 -86.206022) (xy 331.34653 -86.257928) (xy 331.369466 -86.313301)
			(xy 331.384979 -86.371194) (xy 331.392802 -86.430616) (xy 331.393292 -86.460584) (xy 331.393292 -87.324184)
			(xy 331.392802 -87.354152) (xy 331.384979 -87.413574) (xy 331.369466 -87.471467) (xy 331.34653 -87.52684)
			(xy 331.316563 -87.578746) (xy 331.280076 -87.626296) (xy 331.237696 -87.668676) (xy 331.190146 -87.705163)
			(xy 331.13824 -87.73513) (xy 331.082867 -87.758066) (xy 331.024974 -87.773579) (xy 330.965552 -87.781402)
			(xy 330.905616 -87.781402) (xy 330.846194 -87.773579) (xy 330.788301 -87.758066) (xy 330.732928 -87.73513)
			(xy 330.681022 -87.705163) (xy 330.633472 -87.668676) (xy 330.591092 -87.626296) (xy 330.554605 -87.578746)
			(xy 330.524638 -87.52684) (xy 330.501702 -87.471467) (xy 330.486189 -87.413574) (xy 330.478366 -87.354152)
			(xy 330.477876 -87.324184) (xy 236.155843 -87.324184) (xy 236.160086 -87.356415) (xy 236.160086 -87.416385)
			(xy 236.152258 -87.475842) (xy 236.136737 -87.533769) (xy 236.113787 -87.589174) (xy 236.083802 -87.64111)
			(xy 236.047295 -87.688688) (xy 236.004889 -87.731093) (xy 235.957312 -87.767601) (xy 235.905376 -87.797586)
			(xy 235.849971 -87.820536) (xy 235.792044 -87.836058) (xy 235.732587 -87.843886) (xy 235.702602 -87.844376)
			(xy 234.839002 -87.844376) (xy 234.809017 -87.843879) (xy 234.749561 -87.836052) (xy 234.691634 -87.820531)
			(xy 234.636229 -87.797581) (xy 234.584294 -87.767597) (xy 234.536717 -87.73109) (xy 234.494312 -87.688685)
			(xy 234.457804 -87.641108) (xy 234.42782 -87.589172) (xy 234.40487 -87.533768) (xy 234.389349 -87.475841)
			(xy 234.381521 -87.416385) (xy 233.972939 -87.416385) (xy 233.972939 -87.444071) (xy 233.965115 -87.503499)
			(xy 233.9496 -87.561397) (xy 233.92666 -87.616775) (xy 233.896688 -87.668685) (xy 233.860197 -87.716239)
			(xy 233.81781 -87.758622) (xy 233.770254 -87.795109) (xy 233.718341 -87.825077) (xy 233.662961 -87.848012)
			(xy 233.605062 -87.863522) (xy 233.545633 -87.871341) (xy 233.515662 -87.871808) (xy 232.652062 -87.871808)
			(xy 232.622096 -87.871316) (xy 232.562677 -87.863488) (xy 232.504788 -87.847973) (xy 232.44942 -87.825034)
			(xy 232.397519 -87.795065) (xy 232.349973 -87.758579) (xy 232.307596 -87.716198) (xy 232.271114 -87.66865)
			(xy 232.241149 -87.616746) (xy 232.218215 -87.561376) (xy 232.202704 -87.503486) (xy 232.194882 -87.444066)
			(xy 117.531262 -87.444066) (xy 117.530695 -87.448372) (xy 117.515182 -87.506265) (xy 117.492246 -87.561638)
			(xy 117.462279 -87.613544) (xy 117.425792 -87.661094) (xy 117.383412 -87.703474) (xy 117.335862 -87.739961)
			(xy 117.283956 -87.769928) (xy 117.228583 -87.792864) (xy 117.17069 -87.808377) (xy 117.111268 -87.8162)
			(xy 117.051332 -87.8162) (xy 116.99191 -87.808377) (xy 116.934017 -87.792864) (xy 116.878644 -87.769928)
			(xy 116.826738 -87.739961) (xy 116.779188 -87.703474) (xy 116.736808 -87.661094) (xy 116.700321 -87.613544)
			(xy 116.670354 -87.561638) (xy 116.647418 -87.506265) (xy 116.631905 -87.448372) (xy 116.624082 -87.38895)
			(xy 116.623592 -87.358982) (xy 4.297613 -87.358982) (xy 4.299703 -87.377516) (xy 4.307605 -87.517994)
			(xy 4.308094 -87.588344) (xy 4.308094 -88.006187) (xy 238.124409 -88.006187) (xy 238.124409 -87.946213)
			(xy 238.132238 -87.886751) (xy 238.147762 -87.82882) (xy 238.170714 -87.773411) (xy 238.200704 -87.721472)
			(xy 238.237216 -87.673892) (xy 238.279627 -87.631486) (xy 238.32721 -87.594978) (xy 238.379152 -87.564994)
			(xy 238.434563 -87.542047) (xy 238.492496 -87.526529) (xy 238.551959 -87.518706) (xy 238.581946 -87.51824)
			(xy 239.445546 -87.51824) (xy 239.475528 -87.518729) (xy 239.53498 -87.526561) (xy 239.5929 -87.542086)
			(xy 239.648299 -87.565038) (xy 239.700228 -87.595024) (xy 239.747799 -87.631531) (xy 239.790199 -87.673935)
			(xy 239.826701 -87.72151) (xy 239.856682 -87.773442) (xy 239.879628 -87.828843) (xy 239.895148 -87.886765)
			(xy 239.902974 -87.946217) (xy 239.902974 -88.006183) (xy 239.895148 -88.065635) (xy 239.879628 -88.123557)
			(xy 239.870911 -88.144604) (xy 345.879928 -88.144604) (xy 345.879928 -87.281004) (xy 345.880418 -87.25102)
			(xy 345.888246 -87.191564) (xy 345.903767 -87.133639) (xy 345.926716 -87.078235) (xy 345.9567 -87.026301)
			(xy 345.993206 -86.978725) (xy 346.035611 -86.93632) (xy 346.083187 -86.899814) (xy 346.135121 -86.86983)
			(xy 346.190525 -86.846881) (xy 346.24845 -86.83136) (xy 346.307906 -86.823532) (xy 346.367874 -86.823532)
			(xy 346.42733 -86.83136) (xy 346.485255 -86.846881) (xy 346.540659 -86.86983) (xy 346.592593 -86.899814)
			(xy 346.640169 -86.93632) (xy 346.682574 -86.978725) (xy 346.71908 -87.026301) (xy 346.749064 -87.078235)
			(xy 346.772013 -87.133639) (xy 346.787534 -87.191564) (xy 346.795362 -87.25102) (xy 346.795852 -87.281004)
			(xy 346.795852 -88.144604) (xy 346.795362 -88.174588) (xy 346.787534 -88.234044) (xy 346.772013 -88.291969)
			(xy 346.749064 -88.347373) (xy 346.71908 -88.399307) (xy 346.682574 -88.446883) (xy 346.640169 -88.489288)
			(xy 346.592593 -88.525794) (xy 346.540659 -88.555778) (xy 346.485255 -88.578727) (xy 346.42733 -88.594248)
			(xy 346.367874 -88.602076) (xy 346.307906 -88.602076) (xy 346.24845 -88.594248) (xy 346.190525 -88.578727)
			(xy 346.135121 -88.555778) (xy 346.083187 -88.525794) (xy 346.035611 -88.489288) (xy 345.993206 -88.446883)
			(xy 345.9567 -88.399307) (xy 345.926716 -88.347373) (xy 345.903767 -88.291969) (xy 345.888246 -88.234044)
			(xy 345.880418 -88.174588) (xy 345.879928 -88.144604) (xy 239.870911 -88.144604) (xy 239.856682 -88.178958)
			(xy 239.826701 -88.23089) (xy 239.790199 -88.278465) (xy 239.747799 -88.320869) (xy 239.700228 -88.357376)
			(xy 239.648299 -88.387362) (xy 239.5929 -88.410314) (xy 239.53498 -88.425839) (xy 239.475528 -88.433671)
			(xy 239.445546 -88.434164) (xy 238.581946 -88.434164) (xy 238.551959 -88.433694) (xy 238.492496 -88.425871)
			(xy 238.434563 -88.410353) (xy 238.379152 -88.387406) (xy 238.32721 -88.357422) (xy 238.279627 -88.320914)
			(xy 238.237216 -88.278508) (xy 238.200704 -88.230928) (xy 238.170714 -88.178989) (xy 238.147762 -88.12358)
			(xy 238.132238 -88.065649) (xy 238.124409 -88.006187) (xy 4.308094 -88.006187) (xy 4.308094 -89.358978)
			(xy 117.385592 -89.358978) (xy 117.385592 -88.495378) (xy 117.386082 -88.46541) (xy 117.393905 -88.405988)
			(xy 117.409418 -88.348095) (xy 117.432354 -88.292722) (xy 117.462321 -88.240816) (xy 117.498808 -88.193266)
			(xy 117.541188 -88.150886) (xy 117.588738 -88.114399) (xy 117.640644 -88.084432) (xy 117.696017 -88.061496)
			(xy 117.75391 -88.045983) (xy 117.813332 -88.03816) (xy 117.873268 -88.03816) (xy 117.93269 -88.045983)
			(xy 117.990583 -88.061496) (xy 118.045956 -88.084432) (xy 118.097862 -88.114399) (xy 118.145412 -88.150886)
			(xy 118.187792 -88.193266) (xy 118.224279 -88.240816) (xy 118.254246 -88.292722) (xy 118.277182 -88.348095)
			(xy 118.292695 -88.405988) (xy 118.300518 -88.46541) (xy 118.301008 -88.495378) (xy 118.301008 -89.358978)
			(xy 118.300518 -89.388946) (xy 118.292695 -89.448368) (xy 118.277182 -89.506261) (xy 118.254246 -89.561634)
			(xy 118.224279 -89.61354) (xy 118.187792 -89.66109) (xy 118.145412 -89.70347) (xy 118.097862 -89.739957)
			(xy 118.045956 -89.769924) (xy 117.990583 -89.79286) (xy 117.93269 -89.808373) (xy 117.873268 -89.816196)
			(xy 117.813332 -89.816196) (xy 117.75391 -89.808373) (xy 117.696017 -89.79286) (xy 117.640644 -89.769924)
			(xy 117.588738 -89.739957) (xy 117.541188 -89.70347) (xy 117.498808 -89.66109) (xy 117.462321 -89.61354)
			(xy 117.432354 -89.561634) (xy 117.409418 -89.506261) (xy 117.393905 -89.448368) (xy 117.386082 -89.388946)
			(xy 117.385592 -89.358978) (xy 4.308094 -89.358978) (xy 4.308094 -90.1446) (xy 346.641928 -90.1446)
			(xy 346.641928 -89.281) (xy 346.642418 -89.251016) (xy 346.650246 -89.19156) (xy 346.665767 -89.133635)
			(xy 346.688716 -89.078231) (xy 346.7187 -89.026297) (xy 346.755206 -88.978721) (xy 346.797611 -88.936316)
			(xy 346.845187 -88.89981) (xy 346.897121 -88.869826) (xy 346.952525 -88.846877) (xy 347.01045 -88.831356)
			(xy 347.069906 -88.823528) (xy 347.129874 -88.823528) (xy 347.18933 -88.831356) (xy 347.247255 -88.846877)
			(xy 347.302659 -88.869826) (xy 347.354593 -88.89981) (xy 347.402169 -88.936316) (xy 347.444574 -88.978721)
			(xy 347.48108 -89.026297) (xy 347.511064 -89.078231) (xy 347.534013 -89.133635) (xy 347.549534 -89.19156)
			(xy 347.557362 -89.251016) (xy 347.557852 -89.281) (xy 347.557852 -90.1446) (xy 347.557362 -90.174584)
			(xy 347.549534 -90.23404) (xy 347.534013 -90.291965) (xy 347.511064 -90.347369) (xy 347.48108 -90.399303)
			(xy 347.444574 -90.446879) (xy 347.402169 -90.489284) (xy 347.354593 -90.52579) (xy 347.302659 -90.555774)
			(xy 347.247255 -90.578723) (xy 347.18933 -90.594244) (xy 347.129874 -90.602072) (xy 347.069906 -90.602072)
			(xy 347.01045 -90.594244) (xy 346.952525 -90.578723) (xy 346.897121 -90.555774) (xy 346.845187 -90.52579)
			(xy 346.797611 -90.489284) (xy 346.755206 -90.446879) (xy 346.7187 -90.399303) (xy 346.688716 -90.347369)
			(xy 346.665767 -90.291965) (xy 346.650246 -90.23404) (xy 346.642418 -90.174584) (xy 346.641928 -90.1446)
			(xy 4.308094 -90.1446) (xy 4.308094 -94.088485) (xy 109.149614 -94.088485) (xy 109.149614 -94.028515)
			(xy 109.157442 -93.969058) (xy 109.172963 -93.911131) (xy 109.195912 -93.855726) (xy 109.225897 -93.80379)
			(xy 109.262405 -93.756213) (xy 109.30481 -93.713807) (xy 109.352387 -93.6773) (xy 109.404322 -93.647314)
			(xy 109.459727 -93.624364) (xy 109.517654 -93.608843) (xy 109.577111 -93.601014) (xy 109.607096 -93.600524)
			(xy 110.470696 -93.600524) (xy 110.500681 -93.601021) (xy 110.560138 -93.608848) (xy 110.618064 -93.624369)
			(xy 110.673469 -93.647318) (xy 110.725405 -93.677303) (xy 110.772982 -93.71381) (xy 110.815388 -93.756215)
			(xy 110.851895 -93.803792) (xy 110.88188 -93.855727) (xy 110.90483 -93.911132) (xy 110.920351 -93.969058)
			(xy 110.928179 -94.028515) (xy 110.928179 -94.088485) (xy 110.920351 -94.147942) (xy 110.90483 -94.205868)
			(xy 110.88188 -94.261273) (xy 110.851895 -94.313208) (xy 110.815388 -94.360785) (xy 110.772982 -94.40319)
			(xy 110.725405 -94.439697) (xy 110.673469 -94.469682) (xy 110.618064 -94.492631) (xy 110.560138 -94.508152)
			(xy 110.500681 -94.515979) (xy 110.470696 -94.516448) (xy 109.607096 -94.516448) (xy 109.577111 -94.515986)
			(xy 109.517654 -94.508157) (xy 109.459727 -94.492636) (xy 109.404322 -94.469686) (xy 109.352387 -94.4397)
			(xy 109.30481 -94.403193) (xy 109.262405 -94.360787) (xy 109.225897 -94.31321) (xy 109.195912 -94.261274)
			(xy 109.172963 -94.205869) (xy 109.157442 -94.147942) (xy 109.149614 -94.088485) (xy 4.308094 -94.088485)
			(xy 4.308094 -95.214948) (xy 47.274239 -95.214948) (xy 47.278194 -95.123111) (xy 47.290029 -95.031954)
			(xy 47.309656 -94.942151) (xy 47.33693 -94.854369) (xy 47.37165 -94.769255) (xy 47.413558 -94.687442)
			(xy 47.462344 -94.609534) (xy 47.517647 -94.536109) (xy 47.579057 -94.467709) (xy 47.646119 -94.404842)
			(xy 47.718338 -94.347972) (xy 47.795178 -94.297521) (xy 47.876071 -94.253862) (xy 47.960417 -94.217319)
			(xy 48.047593 -94.188162) (xy 48.136952 -94.166608) (xy 48.227833 -94.152814) (xy 48.319564 -94.146884)
			(xy 48.411465 -94.148862) (xy 48.502856 -94.158733) (xy 48.59306 -94.176423) (xy 48.681409 -94.201803)
			(xy 48.767249 -94.234683) (xy 48.849945 -94.274821) (xy 48.928885 -94.32192) (xy 49.003483 -94.37563)
			(xy 49.073189 -94.435554) (xy 49.137484 -94.501248) (xy 49.195895 -94.572226) (xy 49.247987 -94.647963)
			(xy 49.293376 -94.727898) (xy 49.331726 -94.811438) (xy 49.362751 -94.897966) (xy 49.386224 -94.986841)
			(xy 49.40197 -95.077405) (xy 49.409872 -95.168987) (xy 49.410366 -95.214948) (xy 71.639189 -95.214948)
			(xy 71.643144 -95.123111) (xy 71.654979 -95.031954) (xy 71.674606 -94.942151) (xy 71.70188 -94.854369)
			(xy 71.7366 -94.769255) (xy 71.778508 -94.687442) (xy 71.827294 -94.609534) (xy 71.882597 -94.536109)
			(xy 71.944007 -94.467709) (xy 72.011069 -94.404842) (xy 72.083288 -94.347972) (xy 72.160128 -94.297521)
			(xy 72.241021 -94.253862) (xy 72.325367 -94.217319) (xy 72.412543 -94.188162) (xy 72.501902 -94.166608)
			(xy 72.592783 -94.152814) (xy 72.684514 -94.146884) (xy 72.776415 -94.148862) (xy 72.867806 -94.158733)
			(xy 72.95801 -94.176423) (xy 73.046359 -94.201803) (xy 73.132199 -94.234683) (xy 73.214895 -94.274821)
			(xy 73.293835 -94.32192) (xy 73.368433 -94.37563) (xy 73.438139 -94.435554) (xy 73.502434 -94.501248)
			(xy 73.560845 -94.572226) (xy 73.612937 -94.647963) (xy 73.658326 -94.727898) (xy 73.696676 -94.811438)
			(xy 73.727701 -94.897966) (xy 73.751174 -94.986841) (xy 73.76692 -95.077405) (xy 73.774822 -95.168987)
			(xy 73.775316 -95.214948) (xy 73.774822 -95.260909) (xy 73.774772 -95.261486) (xy 163.375394 -95.261486)
			(xy 163.375394 -95.168314) (xy 163.383515 -95.075496) (xy 163.399694 -94.983738) (xy 163.423808 -94.893741)
			(xy 163.455675 -94.806187) (xy 163.495052 -94.721744) (xy 163.541638 -94.641054) (xy 163.595079 -94.564731)
			(xy 163.654969 -94.493357) (xy 163.720852 -94.427473) (xy 163.792226 -94.367583) (xy 163.868549 -94.314141)
			(xy 163.949238 -94.267554) (xy 164.033681 -94.228178) (xy 164.121235 -94.19631) (xy 164.211233 -94.172195)
			(xy 164.30299 -94.156015) (xy 164.395808 -94.147894) (xy 164.442394 -94.147386) (xy 164.442648 -94.147386)
			(xy 164.489237 -94.1478) (xy 164.582061 -94.155925) (xy 164.673824 -94.172109) (xy 164.763826 -94.196229)
			(xy 164.851385 -94.228101) (xy 164.935832 -94.267483) (xy 165.016526 -94.314074) (xy 165.092852 -94.367522)
			(xy 165.164229 -94.427418) (xy 165.230115 -94.493306) (xy 165.290008 -94.564687) (xy 165.343451 -94.641015)
			(xy 165.390039 -94.721711) (xy 165.429417 -94.80616) (xy 165.461286 -94.893719) (xy 165.485401 -94.983723)
			(xy 165.501581 -95.075487) (xy 165.509702 -95.168311) (xy 165.509702 -95.214948) (xy 187.739796 -95.214948)
			(xy 187.743748 -95.123155) (xy 187.755578 -95.032041) (xy 187.775195 -94.942281) (xy 187.802457 -94.85454)
			(xy 187.83716 -94.769468) (xy 187.879048 -94.687693) (xy 187.927811 -94.609822) (xy 187.983087 -94.536432)
			(xy 188.044468 -94.468065) (xy 188.111499 -94.405227) (xy 188.183683 -94.348385) (xy 188.260487 -94.297958)
			(xy 188.341341 -94.25432) (xy 188.425647 -94.217794) (xy 188.512781 -94.188651) (xy 188.602098 -94.167106)
			(xy 188.692936 -94.15332) (xy 188.784623 -94.147393) (xy 188.87648 -94.14937) (xy 188.967828 -94.159236)
			(xy 189.057988 -94.176918) (xy 189.146296 -94.202285) (xy 189.232095 -94.23515) (xy 189.314752 -94.275269)
			(xy 189.393654 -94.322345) (xy 189.468217 -94.376029) (xy 189.537889 -94.435925) (xy 189.602154 -94.501588)
			(xy 189.660537 -94.572532) (xy 189.712604 -94.648233) (xy 189.757972 -94.72813) (xy 189.796303 -94.81163)
			(xy 189.827314 -94.898117) (xy 189.850775 -94.98695) (xy 189.866514 -95.07747) (xy 189.874412 -95.169009)
			(xy 189.874906 -95.214948) (xy 279.474181 -95.214948) (xy 279.478136 -95.123111) (xy 279.489971 -95.031954)
			(xy 279.509598 -94.942151) (xy 279.536872 -94.854369) (xy 279.571592 -94.769255) (xy 279.6135 -94.687442)
			(xy 279.662286 -94.609534) (xy 279.717589 -94.536109) (xy 279.778999 -94.467709) (xy 279.846061 -94.404842)
			(xy 279.91828 -94.347972) (xy 279.99512 -94.297521) (xy 280.076013 -94.253862) (xy 280.160359 -94.217319)
			(xy 280.247535 -94.188162) (xy 280.336894 -94.166608) (xy 280.427775 -94.152814) (xy 280.519506 -94.146884)
			(xy 280.611407 -94.148862) (xy 280.702798 -94.158733) (xy 280.793002 -94.176423) (xy 280.881351 -94.201803)
			(xy 280.967191 -94.234683) (xy 281.049887 -94.274821) (xy 281.128827 -94.32192) (xy 281.203425 -94.37563)
			(xy 281.273131 -94.435554) (xy 281.337426 -94.501248) (xy 281.395837 -94.572226) (xy 281.447929 -94.647963)
			(xy 281.493318 -94.727898) (xy 281.531668 -94.811438) (xy 281.562693 -94.897966) (xy 281.586166 -94.986841)
			(xy 281.601912 -95.077405) (xy 281.609814 -95.168987) (xy 281.610308 -95.214948) (xy 303.839131 -95.214948)
			(xy 303.843086 -95.123111) (xy 303.854921 -95.031954) (xy 303.874548 -94.942151) (xy 303.901822 -94.854369)
			(xy 303.936542 -94.769255) (xy 303.97845 -94.687442) (xy 304.027236 -94.609534) (xy 304.082539 -94.536109)
			(xy 304.143949 -94.467709) (xy 304.211011 -94.404842) (xy 304.28323 -94.347972) (xy 304.36007 -94.297521)
			(xy 304.440963 -94.253862) (xy 304.525309 -94.217319) (xy 304.612485 -94.188162) (xy 304.701844 -94.166608)
			(xy 304.792725 -94.152814) (xy 304.884456 -94.146884) (xy 304.976357 -94.148862) (xy 305.067748 -94.158733)
			(xy 305.157952 -94.176423) (xy 305.246301 -94.201803) (xy 305.332141 -94.234683) (xy 305.414837 -94.274821)
			(xy 305.493777 -94.32192) (xy 305.568375 -94.37563) (xy 305.638081 -94.435554) (xy 305.702376 -94.501248)
			(xy 305.760787 -94.572226) (xy 305.812879 -94.647963) (xy 305.858268 -94.727898) (xy 305.896618 -94.811438)
			(xy 305.91901 -94.87389) (xy 338.405861 -94.87389) (xy 338.405861 -94.81391) (xy 338.413691 -94.754443)
			(xy 338.429215 -94.696507) (xy 338.45217 -94.641093) (xy 338.482161 -94.58915) (xy 338.518676 -94.541565)
			(xy 338.561089 -94.499155) (xy 338.608676 -94.462643) (xy 338.660622 -94.432655) (xy 338.716037 -94.409705)
			(xy 338.773975 -94.394184) (xy 338.833442 -94.386359) (xy 338.863432 -94.385892) (xy 339.727032 -94.385892)
			(xy 339.757012 -94.386476) (xy 339.816458 -94.394306) (xy 339.874374 -94.409828) (xy 339.929769 -94.432777)
			(xy 339.981694 -94.462759) (xy 340.029262 -94.499262) (xy 340.071659 -94.541662) (xy 340.108159 -94.589232)
			(xy 340.138137 -94.64116) (xy 340.161082 -94.696556) (xy 340.1766 -94.754473) (xy 340.184426 -94.81392)
			(xy 340.184426 -94.87388) (xy 340.1766 -94.933327) (xy 340.161082 -94.991244) (xy 340.138137 -95.04664)
			(xy 340.108159 -95.098568) (xy 340.071659 -95.146138) (xy 340.029262 -95.188538) (xy 339.994846 -95.214948)
			(xy 395.574279 -95.214948) (xy 395.578234 -95.123111) (xy 395.590069 -95.031954) (xy 395.609696 -94.942151)
			(xy 395.63697 -94.854369) (xy 395.67169 -94.769255) (xy 395.713598 -94.687442) (xy 395.762384 -94.609534)
			(xy 395.817687 -94.536109) (xy 395.879097 -94.467709) (xy 395.946159 -94.404842) (xy 396.018378 -94.347972)
			(xy 396.095218 -94.297521) (xy 396.176111 -94.253862) (xy 396.260457 -94.217319) (xy 396.347633 -94.188162)
			(xy 396.436992 -94.166608) (xy 396.527873 -94.152814) (xy 396.619604 -94.146884) (xy 396.711505 -94.148862)
			(xy 396.802896 -94.158733) (xy 396.8931 -94.176423) (xy 396.981449 -94.201803) (xy 397.067289 -94.234683)
			(xy 397.149985 -94.274821) (xy 397.228925 -94.32192) (xy 397.303523 -94.37563) (xy 397.373229 -94.435554)
			(xy 397.437524 -94.501248) (xy 397.495935 -94.572226) (xy 397.548027 -94.647963) (xy 397.593416 -94.727898)
			(xy 397.631766 -94.811438) (xy 397.662791 -94.897966) (xy 397.686264 -94.986841) (xy 397.70201 -95.077405)
			(xy 397.709912 -95.168987) (xy 397.710406 -95.214948) (xy 419.939229 -95.214948) (xy 419.943184 -95.123111)
			(xy 419.955019 -95.031954) (xy 419.974646 -94.942151) (xy 420.00192 -94.854369) (xy 420.03664 -94.769255)
			(xy 420.078548 -94.687442) (xy 420.127334 -94.609534) (xy 420.182637 -94.536109) (xy 420.244047 -94.467709)
			(xy 420.311109 -94.404842) (xy 420.383328 -94.347972) (xy 420.460168 -94.297521) (xy 420.541061 -94.253862)
			(xy 420.625407 -94.217319) (xy 420.712583 -94.188162) (xy 420.801942 -94.166608) (xy 420.892823 -94.152814)
			(xy 420.984554 -94.146884) (xy 421.076455 -94.148862) (xy 421.167846 -94.158733) (xy 421.25805 -94.176423)
			(xy 421.346399 -94.201803) (xy 421.432239 -94.234683) (xy 421.514935 -94.274821) (xy 421.593875 -94.32192)
			(xy 421.668473 -94.37563) (xy 421.738179 -94.435554) (xy 421.802474 -94.501248) (xy 421.860885 -94.572226)
			(xy 421.912977 -94.647963) (xy 421.958366 -94.727898) (xy 421.996716 -94.811438) (xy 422.027741 -94.897966)
			(xy 422.051214 -94.986841) (xy 422.06696 -95.077405) (xy 422.074862 -95.168987) (xy 422.075356 -95.214948)
			(xy 422.074862 -95.260909) (xy 422.06696 -95.352491) (xy 422.051214 -95.443055) (xy 422.027741 -95.53193)
			(xy 421.996716 -95.618458) (xy 421.958366 -95.701998) (xy 421.912977 -95.781933) (xy 421.860885 -95.85767)
			(xy 421.802474 -95.928648) (xy 421.738179 -95.994342) (xy 421.668473 -96.054266) (xy 421.593875 -96.107976)
			(xy 421.514935 -96.155075) (xy 421.432239 -96.195213) (xy 421.346399 -96.228093) (xy 421.25805 -96.253473)
			(xy 421.167846 -96.271163) (xy 421.076455 -96.281034) (xy 420.984554 -96.283012) (xy 420.892823 -96.277082)
			(xy 420.801942 -96.263288) (xy 420.712583 -96.241734) (xy 420.625407 -96.212577) (xy 420.541061 -96.176034)
			(xy 420.460168 -96.132375) (xy 420.383328 -96.081924) (xy 420.311109 -96.025054) (xy 420.244047 -95.962187)
			(xy 420.182637 -95.893787) (xy 420.127334 -95.820362) (xy 420.078548 -95.742454) (xy 420.03664 -95.660641)
			(xy 420.00192 -95.575527) (xy 419.974646 -95.487745) (xy 419.955019 -95.397942) (xy 419.943184 -95.306785)
			(xy 419.939229 -95.214948) (xy 397.710406 -95.214948) (xy 397.709912 -95.260909) (xy 397.70201 -95.352491)
			(xy 397.686264 -95.443055) (xy 397.662791 -95.53193) (xy 397.631766 -95.618458) (xy 397.593416 -95.701998)
			(xy 397.548027 -95.781933) (xy 397.495935 -95.85767) (xy 397.437524 -95.928648) (xy 397.373229 -95.994342)
			(xy 397.303523 -96.054266) (xy 397.228925 -96.107976) (xy 397.149985 -96.155075) (xy 397.067289 -96.195213)
			(xy 396.981449 -96.228093) (xy 396.8931 -96.253473) (xy 396.802896 -96.271163) (xy 396.711505 -96.281034)
			(xy 396.619604 -96.283012) (xy 396.527873 -96.277082) (xy 396.436992 -96.263288) (xy 396.347633 -96.241734)
			(xy 396.260457 -96.212577) (xy 396.176111 -96.176034) (xy 396.095218 -96.132375) (xy 396.018378 -96.081924)
			(xy 395.946159 -96.025054) (xy 395.879097 -95.962187) (xy 395.817687 -95.893787) (xy 395.762384 -95.820362)
			(xy 395.713598 -95.742454) (xy 395.67169 -95.660641) (xy 395.63697 -95.575527) (xy 395.609696 -95.487745)
			(xy 395.590069 -95.397942) (xy 395.578234 -95.306785) (xy 395.574279 -95.214948) (xy 339.994846 -95.214948)
			(xy 339.981694 -95.225041) (xy 339.929769 -95.255023) (xy 339.874374 -95.277972) (xy 339.816458 -95.293494)
			(xy 339.757012 -95.301324) (xy 339.727032 -95.301816) (xy 338.863432 -95.301816) (xy 338.833442 -95.301441)
			(xy 338.773975 -95.293616) (xy 338.716037 -95.278095) (xy 338.660622 -95.255145) (xy 338.608676 -95.225157)
			(xy 338.561089 -95.188645) (xy 338.518676 -95.146235) (xy 338.482161 -95.09865) (xy 338.45217 -95.046707)
			(xy 338.429215 -94.991293) (xy 338.413691 -94.933357) (xy 338.405861 -94.87389) (xy 305.91901 -94.87389)
			(xy 305.927643 -94.897966) (xy 305.951116 -94.986841) (xy 305.966862 -95.077405) (xy 305.974764 -95.168987)
			(xy 305.975258 -95.214948) (xy 305.974764 -95.260909) (xy 305.966862 -95.352491) (xy 305.951116 -95.443055)
			(xy 305.927643 -95.53193) (xy 305.896618 -95.618458) (xy 305.858268 -95.701998) (xy 305.812879 -95.781933)
			(xy 305.760787 -95.85767) (xy 305.702376 -95.928648) (xy 305.638081 -95.994342) (xy 305.568375 -96.054266)
			(xy 305.493777 -96.107976) (xy 305.414837 -96.155075) (xy 305.332141 -96.195213) (xy 305.246301 -96.228093)
			(xy 305.157952 -96.253473) (xy 305.067748 -96.271163) (xy 304.976357 -96.281034) (xy 304.884456 -96.283012)
			(xy 304.792725 -96.277082) (xy 304.701844 -96.263288) (xy 304.612485 -96.241734) (xy 304.525309 -96.212577)
			(xy 304.440963 -96.176034) (xy 304.36007 -96.132375) (xy 304.28323 -96.081924) (xy 304.211011 -96.025054)
			(xy 304.143949 -95.962187) (xy 304.082539 -95.893787) (xy 304.027236 -95.820362) (xy 303.97845 -95.742454)
			(xy 303.936542 -95.660641) (xy 303.901822 -95.575527) (xy 303.874548 -95.487745) (xy 303.854921 -95.397942)
			(xy 303.843086 -95.306785) (xy 303.839131 -95.214948) (xy 281.610308 -95.214948) (xy 281.609814 -95.260909)
			(xy 281.601912 -95.352491) (xy 281.586166 -95.443055) (xy 281.562693 -95.53193) (xy 281.531668 -95.618458)
			(xy 281.493318 -95.701998) (xy 281.447929 -95.781933) (xy 281.395837 -95.85767) (xy 281.337426 -95.928648)
			(xy 281.273131 -95.994342) (xy 281.203425 -96.054266) (xy 281.128827 -96.107976) (xy 281.049887 -96.155075)
			(xy 280.967191 -96.195213) (xy 280.881351 -96.228093) (xy 280.793002 -96.253473) (xy 280.702798 -96.271163)
			(xy 280.611407 -96.281034) (xy 280.519506 -96.283012) (xy 280.427775 -96.277082) (xy 280.336894 -96.263288)
			(xy 280.247535 -96.241734) (xy 280.160359 -96.212577) (xy 280.076013 -96.176034) (xy 279.99512 -96.132375)
			(xy 279.91828 -96.081924) (xy 279.846061 -96.025054) (xy 279.778999 -95.962187) (xy 279.717589 -95.893787)
			(xy 279.662286 -95.820362) (xy 279.6135 -95.742454) (xy 279.571592 -95.660641) (xy 279.536872 -95.575527)
			(xy 279.509598 -95.487745) (xy 279.489971 -95.397942) (xy 279.478136 -95.306785) (xy 279.474181 -95.214948)
			(xy 189.874906 -95.214948) (xy 189.874412 -95.260887) (xy 189.866514 -95.352426) (xy 189.850775 -95.442946)
			(xy 189.827314 -95.531779) (xy 189.796303 -95.618266) (xy 189.757972 -95.701766) (xy 189.712604 -95.781663)
			(xy 189.660537 -95.857364) (xy 189.602154 -95.928308) (xy 189.537889 -95.993971) (xy 189.468217 -96.053867)
			(xy 189.393654 -96.107551) (xy 189.314752 -96.154627) (xy 189.232095 -96.194746) (xy 189.146296 -96.227611)
			(xy 189.057988 -96.252978) (xy 188.967828 -96.27066) (xy 188.87648 -96.280526) (xy 188.784623 -96.282503)
			(xy 188.692936 -96.276576) (xy 188.602098 -96.26279) (xy 188.512781 -96.241245) (xy 188.425647 -96.212102)
			(xy 188.341341 -96.175576) (xy 188.260487 -96.131938) (xy 188.183683 -96.081511) (xy 188.111499 -96.024669)
			(xy 188.044468 -95.961831) (xy 187.983087 -95.893464) (xy 187.927811 -95.820074) (xy 187.879048 -95.742203)
			(xy 187.83716 -95.660428) (xy 187.802457 -95.575356) (xy 187.775195 -95.487615) (xy 187.755578 -95.397855)
			(xy 187.743748 -95.306741) (xy 187.739796 -95.214948) (xy 165.509702 -95.214948) (xy 165.509702 -95.261489)
			(xy 165.501581 -95.354313) (xy 165.485401 -95.446077) (xy 165.461286 -95.536081) (xy 165.429417 -95.62364)
			(xy 165.390039 -95.708089) (xy 165.343451 -95.788785) (xy 165.290008 -95.865113) (xy 165.230115 -95.936494)
			(xy 165.164229 -96.002382) (xy 165.092852 -96.062278) (xy 165.016526 -96.115726) (xy 164.935832 -96.162317)
			(xy 164.851385 -96.201699) (xy 164.763826 -96.233571) (xy 164.673824 -96.257691) (xy 164.582061 -96.273875)
			(xy 164.489237 -96.282) (xy 164.442648 -96.28251) (xy 164.442394 -96.28251) (xy 164.395808 -96.281906)
			(xy 164.30299 -96.273785) (xy 164.211233 -96.257605) (xy 164.121235 -96.23349) (xy 164.033681 -96.201622)
			(xy 163.949238 -96.162246) (xy 163.868549 -96.115659) (xy 163.792226 -96.062217) (xy 163.720852 -96.002327)
			(xy 163.654969 -95.936443) (xy 163.595079 -95.865069) (xy 163.541638 -95.788746) (xy 163.495052 -95.708056)
			(xy 163.455675 -95.623613) (xy 163.423808 -95.536059) (xy 163.399694 -95.446062) (xy 163.383515 -95.354304)
			(xy 163.375394 -95.261486) (xy 73.774772 -95.261486) (xy 73.76692 -95.352491) (xy 73.751174 -95.443055)
			(xy 73.727701 -95.53193) (xy 73.696676 -95.618458) (xy 73.658326 -95.701998) (xy 73.612937 -95.781933)
			(xy 73.560845 -95.85767) (xy 73.502434 -95.928648) (xy 73.438139 -95.994342) (xy 73.368433 -96.054266)
			(xy 73.293835 -96.107976) (xy 73.214895 -96.155075) (xy 73.132199 -96.195213) (xy 73.046359 -96.228093)
			(xy 72.95801 -96.253473) (xy 72.867806 -96.271163) (xy 72.776415 -96.281034) (xy 72.684514 -96.283012)
			(xy 72.592783 -96.277082) (xy 72.501902 -96.263288) (xy 72.412543 -96.241734) (xy 72.325367 -96.212577)
			(xy 72.241021 -96.176034) (xy 72.160128 -96.132375) (xy 72.083288 -96.081924) (xy 72.011069 -96.025054)
			(xy 71.944007 -95.962187) (xy 71.882597 -95.893787) (xy 71.827294 -95.820362) (xy 71.778508 -95.742454)
			(xy 71.7366 -95.660641) (xy 71.70188 -95.575527) (xy 71.674606 -95.487745) (xy 71.654979 -95.397942)
			(xy 71.643144 -95.306785) (xy 71.639189 -95.214948) (xy 49.410366 -95.214948) (xy 49.409872 -95.260909)
			(xy 49.40197 -95.352491) (xy 49.386224 -95.443055) (xy 49.362751 -95.53193) (xy 49.331726 -95.618458)
			(xy 49.293376 -95.701998) (xy 49.247987 -95.781933) (xy 49.195895 -95.85767) (xy 49.137484 -95.928648)
			(xy 49.073189 -95.994342) (xy 49.003483 -96.054266) (xy 48.928885 -96.107976) (xy 48.849945 -96.155075)
			(xy 48.767249 -96.195213) (xy 48.681409 -96.228093) (xy 48.59306 -96.253473) (xy 48.502856 -96.271163)
			(xy 48.411465 -96.281034) (xy 48.319564 -96.283012) (xy 48.227833 -96.277082) (xy 48.136952 -96.263288)
			(xy 48.047593 -96.241734) (xy 47.960417 -96.212577) (xy 47.876071 -96.176034) (xy 47.795178 -96.132375)
			(xy 47.718338 -96.081924) (xy 47.646119 -96.025054) (xy 47.579057 -95.962187) (xy 47.517647 -95.893787)
			(xy 47.462344 -95.820362) (xy 47.413558 -95.742454) (xy 47.37165 -95.660641) (xy 47.33693 -95.575527)
			(xy 47.309656 -95.487745) (xy 47.290029 -95.397942) (xy 47.278194 -95.306785) (xy 47.274239 -95.214948)
			(xy 4.308094 -95.214948) (xy 4.308094 -98.766863) (xy 206.090008 -98.766863) (xy 206.090008 -98.633301)
			(xy 206.098072 -98.499983) (xy 206.114172 -98.367395) (xy 206.138247 -98.236021) (xy 206.17021 -98.10634)
			(xy 206.209945 -97.978826) (xy 206.257307 -97.853943) (xy 206.312122 -97.732148) (xy 206.374192 -97.613885)
			(xy 206.443288 -97.499586) (xy 206.51916 -97.389666) (xy 206.60153 -97.284529) (xy 206.690098 -97.184556)
			(xy 206.78454 -97.090114) (xy 206.884513 -97.001546) (xy 206.98965 -96.919176) (xy 207.09957 -96.843304)
			(xy 207.213869 -96.774208) (xy 207.332132 -96.712138) (xy 207.453927 -96.657323) (xy 207.57881 -96.609961)
			(xy 207.706324 -96.570226) (xy 207.836005 -96.538263) (xy 207.967379 -96.514188) (xy 208.099967 -96.498088)
			(xy 208.233285 -96.490024) (xy 208.366847 -96.490024) (xy 208.500165 -96.498088) (xy 208.632753 -96.514188)
			(xy 208.764127 -96.538263) (xy 208.893808 -96.570226) (xy 209.021322 -96.609961) (xy 209.146205 -96.657323)
			(xy 209.268 -96.712138) (xy 209.386263 -96.774208) (xy 209.500562 -96.843304) (xy 209.610482 -96.919176)
			(xy 209.715619 -97.001546) (xy 209.815592 -97.090114) (xy 209.910034 -97.184556) (xy 209.998602 -97.284529)
			(xy 210.080972 -97.389666) (xy 210.156844 -97.499586) (xy 210.22594 -97.613885) (xy 210.28801 -97.732148)
			(xy 210.342825 -97.853943) (xy 210.390187 -97.978826) (xy 210.429922 -98.10634) (xy 210.461885 -98.236021)
			(xy 210.48596 -98.367395) (xy 210.50206 -98.499983) (xy 210.510124 -98.633301) (xy 210.510628 -98.700082)
			(xy 210.510124 -98.766863) (xy 257.089906 -98.766863) (xy 257.089906 -98.633301) (xy 257.09797 -98.499983)
			(xy 257.11407 -98.367395) (xy 257.138145 -98.236021) (xy 257.170108 -98.10634) (xy 257.209843 -97.978826)
			(xy 257.257205 -97.853943) (xy 257.31202 -97.732148) (xy 257.37409 -97.613885) (xy 257.443186 -97.499586)
			(xy 257.519058 -97.389666) (xy 257.601428 -97.284529) (xy 257.689996 -97.184556) (xy 257.784438 -97.090114)
			(xy 257.884411 -97.001546) (xy 257.989548 -96.919176) (xy 258.099468 -96.843304) (xy 258.213767 -96.774208)
			(xy 258.33203 -96.712138) (xy 258.453825 -96.657323) (xy 258.578708 -96.609961) (xy 258.706222 -96.570226)
			(xy 258.835903 -96.538263) (xy 258.967277 -96.514188) (xy 259.099865 -96.498088) (xy 259.233183 -96.490024)
			(xy 259.366745 -96.490024) (xy 259.500063 -96.498088) (xy 259.632651 -96.514188) (xy 259.764025 -96.538263)
			(xy 259.893706 -96.570226) (xy 260.02122 -96.609961) (xy 260.146103 -96.657323) (xy 260.267898 -96.712138)
			(xy 260.386161 -96.774208) (xy 260.50046 -96.843304) (xy 260.61038 -96.919176) (xy 260.715517 -97.001546)
			(xy 260.81549 -97.090114) (xy 260.909932 -97.184556) (xy 260.9985 -97.284529) (xy 261.08087 -97.389666)
			(xy 261.156742 -97.499586) (xy 261.225838 -97.613885) (xy 261.287908 -97.732148) (xy 261.342723 -97.853943)
			(xy 261.390085 -97.978826) (xy 261.42982 -98.10634) (xy 261.461783 -98.236021) (xy 261.485858 -98.367395)
			(xy 261.501958 -98.499983) (xy 261.510022 -98.633301) (xy 261.510526 -98.700082) (xy 261.510022 -98.766863)
			(xy 261.501958 -98.900181) (xy 261.485858 -99.032769) (xy 261.461783 -99.164143) (xy 261.42982 -99.293824)
			(xy 261.390085 -99.421338) (xy 261.342723 -99.546221) (xy 261.287908 -99.668016) (xy 261.225838 -99.786279)
			(xy 261.156742 -99.900578) (xy 261.08087 -100.010498) (xy 260.9985 -100.115635) (xy 260.943379 -100.177854)
			(xy 269.509748 -100.177854) (xy 269.509748 -99.314254) (xy 269.510238 -99.28427) (xy 269.518066 -99.224814)
			(xy 269.533587 -99.166889) (xy 269.556536 -99.111485) (xy 269.58652 -99.059551) (xy 269.623026 -99.011975)
			(xy 269.665431 -98.96957) (xy 269.713007 -98.933064) (xy 269.764941 -98.90308) (xy 269.820345 -98.880131)
			(xy 269.87827 -98.86461) (xy 269.937726 -98.856782) (xy 269.997694 -98.856782) (xy 270.05715 -98.86461)
			(xy 270.115075 -98.880131) (xy 270.170479 -98.90308) (xy 270.222413 -98.933064) (xy 270.269989 -98.96957)
			(xy 270.312394 -99.011975) (xy 270.3489 -99.059551) (xy 270.378884 -99.111485) (xy 270.401833 -99.166889)
			(xy 270.417354 -99.224814) (xy 270.425182 -99.28427) (xy 270.425672 -99.314254) (xy 270.425672 -100.17633)
			(xy 285.8389 -100.17633) (xy 285.8389 -99.31273) (xy 285.83939 -99.282746) (xy 285.847218 -99.22329)
			(xy 285.862739 -99.165365) (xy 285.885688 -99.109961) (xy 285.915672 -99.058027) (xy 285.952178 -99.010451)
			(xy 285.994583 -98.968046) (xy 286.042159 -98.93154) (xy 286.094093 -98.901556) (xy 286.149497 -98.878607)
			(xy 286.207422 -98.863086) (xy 286.266878 -98.855258) (xy 286.326846 -98.855258) (xy 286.386302 -98.863086)
			(xy 286.444227 -98.878607) (xy 286.499631 -98.901556) (xy 286.551565 -98.93154) (xy 286.599141 -98.968046)
			(xy 286.641546 -99.010451) (xy 286.678052 -99.058027) (xy 286.708036 -99.109961) (xy 286.730985 -99.165365)
			(xy 286.746506 -99.22329) (xy 286.754334 -99.282746) (xy 286.754824 -99.31273) (xy 286.754824 -100.17633)
			(xy 286.754799 -100.177854) (xy 385.6101 -100.177854) (xy 385.6101 -99.314254) (xy 385.61059 -99.284286)
			(xy 385.618413 -99.224864) (xy 385.633926 -99.166971) (xy 385.656862 -99.111598) (xy 385.686829 -99.059692)
			(xy 385.723316 -99.012142) (xy 385.765696 -98.969762) (xy 385.813246 -98.933275) (xy 385.865152 -98.903308)
			(xy 385.920525 -98.880372) (xy 385.978418 -98.864859) (xy 386.03784 -98.857036) (xy 386.097776 -98.857036)
			(xy 386.157198 -98.864859) (xy 386.215091 -98.880372) (xy 386.270464 -98.903308) (xy 386.32237 -98.933275)
			(xy 386.36992 -98.969762) (xy 386.4123 -99.012142) (xy 386.448787 -99.059692) (xy 386.478754 -99.111598)
			(xy 386.50169 -99.166971) (xy 386.517203 -99.224864) (xy 386.525026 -99.284286) (xy 386.525516 -99.314254)
			(xy 386.525516 -100.17633) (xy 401.939252 -100.17633) (xy 401.939252 -99.31273) (xy 401.939742 -99.282762)
			(xy 401.947565 -99.22334) (xy 401.963078 -99.165447) (xy 401.986014 -99.110074) (xy 402.015981 -99.058168)
			(xy 402.052468 -99.010618) (xy 402.094848 -98.968238) (xy 402.142398 -98.931751) (xy 402.194304 -98.901784)
			(xy 402.249677 -98.878848) (xy 402.30757 -98.863335) (xy 402.366992 -98.855512) (xy 402.426928 -98.855512)
			(xy 402.48635 -98.863335) (xy 402.544243 -98.878848) (xy 402.599616 -98.901784) (xy 402.651522 -98.931751)
			(xy 402.699072 -98.968238) (xy 402.741452 -99.010618) (xy 402.777939 -99.058168) (xy 402.807906 -99.110074)
			(xy 402.830842 -99.165447) (xy 402.846355 -99.22334) (xy 402.854178 -99.282762) (xy 402.854668 -99.31273)
			(xy 402.854668 -100.17633) (xy 402.854178 -100.206298) (xy 402.846355 -100.26572) (xy 402.830842 -100.323613)
			(xy 402.807906 -100.378986) (xy 402.777939 -100.430892) (xy 402.741452 -100.478442) (xy 402.699072 -100.520822)
			(xy 402.651522 -100.557309) (xy 402.599616 -100.587276) (xy 402.544243 -100.610212) (xy 402.48635 -100.625725)
			(xy 402.426928 -100.633548) (xy 402.366992 -100.633548) (xy 402.30757 -100.625725) (xy 402.249677 -100.610212)
			(xy 402.194304 -100.587276) (xy 402.142398 -100.557309) (xy 402.094848 -100.520822) (xy 402.052468 -100.478442)
			(xy 402.015981 -100.430892) (xy 401.986014 -100.378986) (xy 401.963078 -100.323613) (xy 401.947565 -100.26572)
			(xy 401.939742 -100.206298) (xy 401.939252 -100.17633) (xy 386.525516 -100.17633) (xy 386.525516 -100.177854)
			(xy 386.525026 -100.207822) (xy 386.517203 -100.267244) (xy 386.50169 -100.325137) (xy 386.478754 -100.38051)
			(xy 386.448787 -100.432416) (xy 386.4123 -100.479966) (xy 386.36992 -100.522346) (xy 386.32237 -100.558833)
			(xy 386.270464 -100.5888) (xy 386.215091 -100.611736) (xy 386.157198 -100.627249) (xy 386.097776 -100.635072)
			(xy 386.03784 -100.635072) (xy 385.978418 -100.627249) (xy 385.920525 -100.611736) (xy 385.865152 -100.5888)
			(xy 385.813246 -100.558833) (xy 385.765696 -100.522346) (xy 385.723316 -100.479966) (xy 385.686829 -100.432416)
			(xy 385.656862 -100.38051) (xy 385.633926 -100.325137) (xy 385.618413 -100.267244) (xy 385.61059 -100.207822)
			(xy 385.6101 -100.177854) (xy 286.754799 -100.177854) (xy 286.754334 -100.206314) (xy 286.746506 -100.26577)
			(xy 286.730985 -100.323695) (xy 286.708036 -100.379099) (xy 286.678052 -100.431033) (xy 286.641546 -100.478609)
			(xy 286.599141 -100.521014) (xy 286.551565 -100.55752) (xy 286.499631 -100.587504) (xy 286.444227 -100.610453)
			(xy 286.386302 -100.625974) (xy 286.326846 -100.633802) (xy 286.266878 -100.633802) (xy 286.207422 -100.625974)
			(xy 286.149497 -100.610453) (xy 286.094093 -100.587504) (xy 286.042159 -100.55752) (xy 285.994583 -100.521014)
			(xy 285.952178 -100.478609) (xy 285.915672 -100.431033) (xy 285.885688 -100.379099) (xy 285.862739 -100.323695)
			(xy 285.847218 -100.26577) (xy 285.83939 -100.206314) (xy 285.8389 -100.17633) (xy 270.425672 -100.17633)
			(xy 270.425672 -100.177854) (xy 270.425182 -100.207838) (xy 270.417354 -100.267294) (xy 270.401833 -100.325219)
			(xy 270.378884 -100.380623) (xy 270.3489 -100.432557) (xy 270.312394 -100.480133) (xy 270.269989 -100.522538)
			(xy 270.222413 -100.559044) (xy 270.170479 -100.589028) (xy 270.115075 -100.611977) (xy 270.05715 -100.627498)
			(xy 269.997694 -100.635326) (xy 269.937726 -100.635326) (xy 269.87827 -100.627498) (xy 269.820345 -100.611977)
			(xy 269.764941 -100.589028) (xy 269.713007 -100.559044) (xy 269.665431 -100.522538) (xy 269.623026 -100.480133)
			(xy 269.58652 -100.432557) (xy 269.556536 -100.380623) (xy 269.533587 -100.325219) (xy 269.518066 -100.267294)
			(xy 269.510238 -100.207838) (xy 269.509748 -100.177854) (xy 260.943379 -100.177854) (xy 260.909932 -100.215608)
			(xy 260.81549 -100.31005) (xy 260.715517 -100.398618) (xy 260.61038 -100.480988) (xy 260.50046 -100.55686)
			(xy 260.386161 -100.625956) (xy 260.267898 -100.688026) (xy 260.146103 -100.742841) (xy 260.02122 -100.790203)
			(xy 259.893706 -100.829938) (xy 259.764025 -100.861901) (xy 259.632651 -100.885976) (xy 259.500063 -100.902076)
			(xy 259.366745 -100.91014) (xy 259.233183 -100.91014) (xy 259.099865 -100.902076) (xy 258.967277 -100.885976)
			(xy 258.835903 -100.861901) (xy 258.706222 -100.829938) (xy 258.578708 -100.790203) (xy 258.453825 -100.742841)
			(xy 258.33203 -100.688026) (xy 258.213767 -100.625956) (xy 258.099468 -100.55686) (xy 257.989548 -100.480988)
			(xy 257.884411 -100.398618) (xy 257.784438 -100.31005) (xy 257.689996 -100.215608) (xy 257.601428 -100.115635)
			(xy 257.519058 -100.010498) (xy 257.443186 -99.900578) (xy 257.37409 -99.786279) (xy 257.31202 -99.668016)
			(xy 257.257205 -99.546221) (xy 257.209843 -99.421338) (xy 257.170108 -99.293824) (xy 257.138145 -99.164143)
			(xy 257.11407 -99.032769) (xy 257.09797 -98.900181) (xy 257.089906 -98.766863) (xy 210.510124 -98.766863)
			(xy 210.50206 -98.900181) (xy 210.48596 -99.032769) (xy 210.461885 -99.164143) (xy 210.429922 -99.293824)
			(xy 210.390187 -99.421338) (xy 210.342825 -99.546221) (xy 210.28801 -99.668016) (xy 210.22594 -99.786279)
			(xy 210.156844 -99.900578) (xy 210.080972 -100.010498) (xy 209.998602 -100.115635) (xy 209.910034 -100.215608)
			(xy 209.815592 -100.31005) (xy 209.715619 -100.398618) (xy 209.610482 -100.480988) (xy 209.500562 -100.55686)
			(xy 209.386263 -100.625956) (xy 209.268 -100.688026) (xy 209.146205 -100.742841) (xy 209.021322 -100.790203)
			(xy 208.893808 -100.829938) (xy 208.764127 -100.861901) (xy 208.632753 -100.885976) (xy 208.500165 -100.902076)
			(xy 208.366847 -100.91014) (xy 208.233285 -100.91014) (xy 208.099967 -100.902076) (xy 207.967379 -100.885976)
			(xy 207.836005 -100.861901) (xy 207.706324 -100.829938) (xy 207.57881 -100.790203) (xy 207.453927 -100.742841)
			(xy 207.332132 -100.688026) (xy 207.213869 -100.625956) (xy 207.09957 -100.55686) (xy 206.98965 -100.480988)
			(xy 206.884513 -100.398618) (xy 206.78454 -100.31005) (xy 206.690098 -100.215608) (xy 206.60153 -100.115635)
			(xy 206.51916 -100.010498) (xy 206.443288 -99.900578) (xy 206.374192 -99.786279) (xy 206.312122 -99.668016)
			(xy 206.257307 -99.546221) (xy 206.209945 -99.421338) (xy 206.17021 -99.293824) (xy 206.138247 -99.164143)
			(xy 206.114172 -99.032769) (xy 206.098072 -98.900181) (xy 206.090008 -98.766863) (xy 4.308094 -98.766863)
			(xy 4.308094 -100.177854) (xy 37.31006 -100.177854) (xy 37.31006 -99.314254) (xy 37.31055 -99.284286)
			(xy 37.318373 -99.224864) (xy 37.333886 -99.166971) (xy 37.356822 -99.111598) (xy 37.386789 -99.059692)
			(xy 37.423276 -99.012142) (xy 37.465656 -98.969762) (xy 37.513206 -98.933275) (xy 37.565112 -98.903308)
			(xy 37.620485 -98.880372) (xy 37.678378 -98.864859) (xy 37.7378 -98.857036) (xy 37.797736 -98.857036)
			(xy 37.857158 -98.864859) (xy 37.915051 -98.880372) (xy 37.970424 -98.903308) (xy 38.02233 -98.933275)
			(xy 38.06988 -98.969762) (xy 38.11226 -99.012142) (xy 38.148747 -99.059692) (xy 38.178714 -99.111598)
			(xy 38.20165 -99.166971) (xy 38.217163 -99.224864) (xy 38.224986 -99.284286) (xy 38.225476 -99.314254)
			(xy 38.225476 -100.17633) (xy 53.639212 -100.17633) (xy 53.639212 -99.31273) (xy 53.639702 -99.282762)
			(xy 53.647525 -99.22334) (xy 53.663038 -99.165447) (xy 53.685974 -99.110074) (xy 53.715941 -99.058168)
			(xy 53.752428 -99.010618) (xy 53.794808 -98.968238) (xy 53.842358 -98.931751) (xy 53.894264 -98.901784)
			(xy 53.949637 -98.878848) (xy 54.00753 -98.863335) (xy 54.066952 -98.855512) (xy 54.126888 -98.855512)
			(xy 54.18631 -98.863335) (xy 54.244203 -98.878848) (xy 54.299576 -98.901784) (xy 54.351482 -98.931751)
			(xy 54.399032 -98.968238) (xy 54.441412 -99.010618) (xy 54.477899 -99.058168) (xy 54.507866 -99.110074)
			(xy 54.530802 -99.165447) (xy 54.546315 -99.22334) (xy 54.554138 -99.282762) (xy 54.554628 -99.31273)
			(xy 54.554628 -100.17633) (xy 54.554603 -100.177854) (xy 153.409904 -100.177854) (xy 153.409904 -99.314254)
			(xy 153.410394 -99.28427) (xy 153.418222 -99.224814) (xy 153.433743 -99.166889) (xy 153.456692 -99.111485)
			(xy 153.486676 -99.059551) (xy 153.523182 -99.011975) (xy 153.565587 -98.96957) (xy 153.613163 -98.933064)
			(xy 153.665097 -98.90308) (xy 153.720501 -98.880131) (xy 153.778426 -98.86461) (xy 153.837882 -98.856782)
			(xy 153.89785 -98.856782) (xy 153.957306 -98.86461) (xy 154.015231 -98.880131) (xy 154.070635 -98.90308)
			(xy 154.122569 -98.933064) (xy 154.170145 -98.96957) (xy 154.21255 -99.011975) (xy 154.249056 -99.059551)
			(xy 154.27904 -99.111485) (xy 154.301989 -99.166889) (xy 154.31751 -99.224814) (xy 154.325338 -99.28427)
			(xy 154.325828 -99.314254) (xy 154.325828 -100.17633) (xy 169.739056 -100.17633) (xy 169.739056 -99.31273)
			(xy 169.739546 -99.282746) (xy 169.747374 -99.22329) (xy 169.762895 -99.165365) (xy 169.785844 -99.109961)
			(xy 169.815828 -99.058027) (xy 169.852334 -99.010451) (xy 169.894739 -98.968046) (xy 169.942315 -98.93154)
			(xy 169.994249 -98.901556) (xy 170.049653 -98.878607) (xy 170.107578 -98.863086) (xy 170.167034 -98.855258)
			(xy 170.227002 -98.855258) (xy 170.286458 -98.863086) (xy 170.344383 -98.878607) (xy 170.399787 -98.901556)
			(xy 170.451721 -98.93154) (xy 170.499297 -98.968046) (xy 170.541702 -99.010451) (xy 170.578208 -99.058027)
			(xy 170.608192 -99.109961) (xy 170.631141 -99.165365) (xy 170.646662 -99.22329) (xy 170.65449 -99.282746)
			(xy 170.65498 -99.31273) (xy 170.65498 -100.17633) (xy 170.65449 -100.206314) (xy 170.646662 -100.26577)
			(xy 170.631141 -100.323695) (xy 170.608192 -100.379099) (xy 170.578208 -100.431033) (xy 170.541702 -100.478609)
			(xy 170.499297 -100.521014) (xy 170.451721 -100.55752) (xy 170.399787 -100.587504) (xy 170.344383 -100.610453)
			(xy 170.286458 -100.625974) (xy 170.227002 -100.633802) (xy 170.167034 -100.633802) (xy 170.107578 -100.625974)
			(xy 170.049653 -100.610453) (xy 169.994249 -100.587504) (xy 169.942315 -100.55752) (xy 169.894739 -100.521014)
			(xy 169.852334 -100.478609) (xy 169.815828 -100.431033) (xy 169.785844 -100.379099) (xy 169.762895 -100.323695)
			(xy 169.747374 -100.26577) (xy 169.739546 -100.206314) (xy 169.739056 -100.17633) (xy 154.325828 -100.17633)
			(xy 154.325828 -100.177854) (xy 154.325338 -100.207838) (xy 154.31751 -100.267294) (xy 154.301989 -100.325219)
			(xy 154.27904 -100.380623) (xy 154.249056 -100.432557) (xy 154.21255 -100.480133) (xy 154.170145 -100.522538)
			(xy 154.122569 -100.559044) (xy 154.070635 -100.589028) (xy 154.015231 -100.611977) (xy 153.957306 -100.627498)
			(xy 153.89785 -100.635326) (xy 153.837882 -100.635326) (xy 153.778426 -100.627498) (xy 153.720501 -100.611977)
			(xy 153.665097 -100.589028) (xy 153.613163 -100.559044) (xy 153.565587 -100.522538) (xy 153.523182 -100.480133)
			(xy 153.486676 -100.432557) (xy 153.456692 -100.380623) (xy 153.433743 -100.325219) (xy 153.418222 -100.267294)
			(xy 153.410394 -100.207838) (xy 153.409904 -100.177854) (xy 54.554603 -100.177854) (xy 54.554138 -100.206298)
			(xy 54.546315 -100.26572) (xy 54.530802 -100.323613) (xy 54.507866 -100.378986) (xy 54.477899 -100.430892)
			(xy 54.441412 -100.478442) (xy 54.399032 -100.520822) (xy 54.351482 -100.557309) (xy 54.299576 -100.587276)
			(xy 54.244203 -100.610212) (xy 54.18631 -100.625725) (xy 54.126888 -100.633548) (xy 54.066952 -100.633548)
			(xy 54.00753 -100.625725) (xy 53.949637 -100.610212) (xy 53.894264 -100.587276) (xy 53.842358 -100.557309)
			(xy 53.794808 -100.520822) (xy 53.752428 -100.478442) (xy 53.715941 -100.430892) (xy 53.685974 -100.378986)
			(xy 53.663038 -100.323613) (xy 53.647525 -100.26572) (xy 53.639702 -100.206298) (xy 53.639212 -100.17633)
			(xy 38.225476 -100.17633) (xy 38.225476 -100.177854) (xy 38.224986 -100.207822) (xy 38.217163 -100.267244)
			(xy 38.20165 -100.325137) (xy 38.178714 -100.38051) (xy 38.148747 -100.432416) (xy 38.11226 -100.479966)
			(xy 38.06988 -100.522346) (xy 38.02233 -100.558833) (xy 37.970424 -100.5888) (xy 37.915051 -100.611736)
			(xy 37.857158 -100.627249) (xy 37.797736 -100.635072) (xy 37.7378 -100.635072) (xy 37.678378 -100.627249)
			(xy 37.620485 -100.611736) (xy 37.565112 -100.5888) (xy 37.513206 -100.558833) (xy 37.465656 -100.522346)
			(xy 37.423276 -100.479966) (xy 37.386789 -100.432416) (xy 37.356822 -100.38051) (xy 37.333886 -100.325137)
			(xy 37.318373 -100.267244) (xy 37.31055 -100.207822) (xy 37.31006 -100.177854) (xy 4.308094 -100.177854)
			(xy 4.308094 -101.984302) (xy 35.277552 -101.984302) (xy 35.277552 -101.120702) (xy 35.278042 -101.090734)
			(xy 35.285865 -101.031312) (xy 35.301378 -100.973419) (xy 35.324314 -100.918046) (xy 35.354281 -100.86614)
			(xy 35.390768 -100.81859) (xy 35.433148 -100.77621) (xy 35.480698 -100.739723) (xy 35.532604 -100.709756)
			(xy 35.587977 -100.68682) (xy 35.64587 -100.671307) (xy 35.705292 -100.663484) (xy 35.765228 -100.663484)
			(xy 35.82465 -100.671307) (xy 35.882543 -100.68682) (xy 35.937916 -100.709756) (xy 35.989822 -100.739723)
			(xy 36.037372 -100.77621) (xy 36.079752 -100.81859) (xy 36.116239 -100.86614) (xy 36.146206 -100.918046)
			(xy 36.169142 -100.973419) (xy 36.184655 -101.031312) (xy 36.192478 -101.090734) (xy 36.192968 -101.120702)
			(xy 36.192968 -101.976428) (xy 51.785012 -101.976428) (xy 51.785012 -101.112828) (xy 51.785502 -101.08286)
			(xy 51.793325 -101.023438) (xy 51.808838 -100.965545) (xy 51.831774 -100.910172) (xy 51.861741 -100.858266)
			(xy 51.898228 -100.810716) (xy 51.940608 -100.768336) (xy 51.988158 -100.731849) (xy 52.040064 -100.701882)
			(xy 52.095437 -100.678946) (xy 52.15333 -100.663433) (xy 52.212752 -100.65561) (xy 52.272688 -100.65561)
			(xy 52.33211 -100.663433) (xy 52.390003 -100.678946) (xy 52.445376 -100.701882) (xy 52.497282 -100.731849)
			(xy 52.544832 -100.768336) (xy 52.587212 -100.810716) (xy 52.623699 -100.858266) (xy 52.653666 -100.910172)
			(xy 52.676602 -100.965545) (xy 52.692115 -101.023438) (xy 52.699938 -101.08286) (xy 52.700428 -101.112828)
			(xy 52.700428 -101.976428) (xy 52.700299 -101.984302) (xy 151.377396 -101.984302) (xy 151.377396 -101.120702)
			(xy 151.377886 -101.090718) (xy 151.385714 -101.031262) (xy 151.401235 -100.973337) (xy 151.424184 -100.917933)
			(xy 151.454168 -100.865999) (xy 151.490674 -100.818423) (xy 151.533079 -100.776018) (xy 151.580655 -100.739512)
			(xy 151.632589 -100.709528) (xy 151.687993 -100.686579) (xy 151.745918 -100.671058) (xy 151.805374 -100.66323)
			(xy 151.865342 -100.66323) (xy 151.924798 -100.671058) (xy 151.982723 -100.686579) (xy 152.038127 -100.709528)
			(xy 152.090061 -100.739512) (xy 152.137637 -100.776018) (xy 152.180042 -100.818423) (xy 152.216548 -100.865999)
			(xy 152.246532 -100.917933) (xy 152.269481 -100.973337) (xy 152.285002 -101.031262) (xy 152.29283 -101.090718)
			(xy 152.29332 -101.120702) (xy 152.29332 -101.976428) (xy 167.884856 -101.976428) (xy 167.884856 -101.112828)
			(xy 167.885346 -101.082844) (xy 167.893174 -101.023388) (xy 167.908695 -100.965463) (xy 167.931644 -100.910059)
			(xy 167.961628 -100.858125) (xy 167.998134 -100.810549) (xy 168.040539 -100.768144) (xy 168.088115 -100.731638)
			(xy 168.140049 -100.701654) (xy 168.195453 -100.678705) (xy 168.253378 -100.663184) (xy 168.312834 -100.655356)
			(xy 168.372802 -100.655356) (xy 168.432258 -100.663184) (xy 168.490183 -100.678705) (xy 168.545587 -100.701654)
			(xy 168.597521 -100.731638) (xy 168.645097 -100.768144) (xy 168.687502 -100.810549) (xy 168.724008 -100.858125)
			(xy 168.753992 -100.910059) (xy 168.776941 -100.965463) (xy 168.792462 -101.023388) (xy 168.80029 -101.082844)
			(xy 168.80078 -101.112828) (xy 168.80078 -101.976428) (xy 168.800651 -101.984302) (xy 267.47724 -101.984302)
			(xy 267.47724 -101.120702) (xy 267.47773 -101.090718) (xy 267.485558 -101.031262) (xy 267.501079 -100.973337)
			(xy 267.524028 -100.917933) (xy 267.554012 -100.865999) (xy 267.590518 -100.818423) (xy 267.632923 -100.776018)
			(xy 267.680499 -100.739512) (xy 267.732433 -100.709528) (xy 267.787837 -100.686579) (xy 267.845762 -100.671058)
			(xy 267.905218 -100.66323) (xy 267.965186 -100.66323) (xy 268.024642 -100.671058) (xy 268.082567 -100.686579)
			(xy 268.137971 -100.709528) (xy 268.189905 -100.739512) (xy 268.237481 -100.776018) (xy 268.279886 -100.818423)
			(xy 268.316392 -100.865999) (xy 268.346376 -100.917933) (xy 268.369325 -100.973337) (xy 268.384846 -101.031262)
			(xy 268.392674 -101.090718) (xy 268.393164 -101.120702) (xy 268.393164 -101.976428) (xy 283.9847 -101.976428)
			(xy 283.9847 -101.112828) (xy 283.98519 -101.082844) (xy 283.993018 -101.023388) (xy 284.008539 -100.965463)
			(xy 284.031488 -100.910059) (xy 284.061472 -100.858125) (xy 284.097978 -100.810549) (xy 284.140383 -100.768144)
			(xy 284.187959 -100.731638) (xy 284.239893 -100.701654) (xy 284.295297 -100.678705) (xy 284.353222 -100.663184)
			(xy 284.412678 -100.655356) (xy 284.472646 -100.655356) (xy 284.532102 -100.663184) (xy 284.590027 -100.678705)
			(xy 284.645431 -100.701654) (xy 284.697365 -100.731638) (xy 284.744941 -100.768144) (xy 284.787346 -100.810549)
			(xy 284.823852 -100.858125) (xy 284.853836 -100.910059) (xy 284.876785 -100.965463) (xy 284.892306 -101.023388)
			(xy 284.900134 -101.082844) (xy 284.900624 -101.112828) (xy 284.900624 -101.976428) (xy 284.900495 -101.984302)
			(xy 383.577592 -101.984302) (xy 383.577592 -101.120702) (xy 383.578082 -101.090734) (xy 383.585905 -101.031312)
			(xy 383.601418 -100.973419) (xy 383.624354 -100.918046) (xy 383.654321 -100.86614) (xy 383.690808 -100.81859)
			(xy 383.733188 -100.77621) (xy 383.780738 -100.739723) (xy 383.832644 -100.709756) (xy 383.888017 -100.68682)
			(xy 383.94591 -100.671307) (xy 384.005332 -100.663484) (xy 384.065268 -100.663484) (xy 384.12469 -100.671307)
			(xy 384.182583 -100.68682) (xy 384.237956 -100.709756) (xy 384.289862 -100.739723) (xy 384.337412 -100.77621)
			(xy 384.379792 -100.81859) (xy 384.416279 -100.86614) (xy 384.446246 -100.918046) (xy 384.469182 -100.973419)
			(xy 384.484695 -101.031312) (xy 384.492518 -101.090734) (xy 384.493008 -101.120702) (xy 384.493008 -101.976428)
			(xy 400.085052 -101.976428) (xy 400.085052 -101.112828) (xy 400.085542 -101.08286) (xy 400.093365 -101.023438)
			(xy 400.108878 -100.965545) (xy 400.131814 -100.910172) (xy 400.161781 -100.858266) (xy 400.198268 -100.810716)
			(xy 400.240648 -100.768336) (xy 400.288198 -100.731849) (xy 400.340104 -100.701882) (xy 400.395477 -100.678946)
			(xy 400.45337 -100.663433) (xy 400.512792 -100.65561) (xy 400.572728 -100.65561) (xy 400.63215 -100.663433)
			(xy 400.690043 -100.678946) (xy 400.745416 -100.701882) (xy 400.797322 -100.731849) (xy 400.844872 -100.768336)
			(xy 400.887252 -100.810716) (xy 400.923739 -100.858266) (xy 400.953706 -100.910172) (xy 400.976642 -100.965545)
			(xy 400.992155 -101.023438) (xy 400.999978 -101.08286) (xy 401.000468 -101.112828) (xy 401.000468 -101.976428)
			(xy 400.999978 -102.006396) (xy 400.992155 -102.065818) (xy 400.976642 -102.123711) (xy 400.953706 -102.179084)
			(xy 400.923739 -102.23099) (xy 400.887252 -102.27854) (xy 400.844872 -102.32092) (xy 400.797322 -102.357407)
			(xy 400.745416 -102.387374) (xy 400.690043 -102.41031) (xy 400.63215 -102.425823) (xy 400.572728 -102.433646)
			(xy 400.512792 -102.433646) (xy 400.45337 -102.425823) (xy 400.395477 -102.41031) (xy 400.340104 -102.387374)
			(xy 400.288198 -102.357407) (xy 400.240648 -102.32092) (xy 400.198268 -102.27854) (xy 400.161781 -102.23099)
			(xy 400.131814 -102.179084) (xy 400.108878 -102.123711) (xy 400.093365 -102.065818) (xy 400.085542 -102.006396)
			(xy 400.085052 -101.976428) (xy 384.493008 -101.976428) (xy 384.493008 -101.984302) (xy 384.492518 -102.01427)
			(xy 384.484695 -102.073692) (xy 384.469182 -102.131585) (xy 384.446246 -102.186958) (xy 384.416279 -102.238864)
			(xy 384.379792 -102.286414) (xy 384.337412 -102.328794) (xy 384.289862 -102.365281) (xy 384.237956 -102.395248)
			(xy 384.182583 -102.418184) (xy 384.12469 -102.433697) (xy 384.065268 -102.44152) (xy 384.005332 -102.44152)
			(xy 383.94591 -102.433697) (xy 383.888017 -102.418184) (xy 383.832644 -102.395248) (xy 383.780738 -102.365281)
			(xy 383.733188 -102.328794) (xy 383.690808 -102.286414) (xy 383.654321 -102.238864) (xy 383.624354 -102.186958)
			(xy 383.601418 -102.131585) (xy 383.585905 -102.073692) (xy 383.578082 -102.01427) (xy 383.577592 -101.984302)
			(xy 284.900495 -101.984302) (xy 284.900134 -102.006412) (xy 284.892306 -102.065868) (xy 284.876785 -102.123793)
			(xy 284.853836 -102.179197) (xy 284.823852 -102.231131) (xy 284.787346 -102.278707) (xy 284.744941 -102.321112)
			(xy 284.697365 -102.357618) (xy 284.645431 -102.387602) (xy 284.590027 -102.410551) (xy 284.532102 -102.426072)
			(xy 284.472646 -102.4339) (xy 284.412678 -102.4339) (xy 284.353222 -102.426072) (xy 284.295297 -102.410551)
			(xy 284.239893 -102.387602) (xy 284.187959 -102.357618) (xy 284.140383 -102.321112) (xy 284.097978 -102.278707)
			(xy 284.061472 -102.231131) (xy 284.031488 -102.179197) (xy 284.008539 -102.123793) (xy 283.993018 -102.065868)
			(xy 283.98519 -102.006412) (xy 283.9847 -101.976428) (xy 268.393164 -101.976428) (xy 268.393164 -101.984302)
			(xy 268.392674 -102.014286) (xy 268.384846 -102.073742) (xy 268.369325 -102.131667) (xy 268.346376 -102.187071)
			(xy 268.316392 -102.239005) (xy 268.279886 -102.286581) (xy 268.237481 -102.328986) (xy 268.189905 -102.365492)
			(xy 268.137971 -102.395476) (xy 268.082567 -102.418425) (xy 268.024642 -102.433946) (xy 267.965186 -102.441774)
			(xy 267.905218 -102.441774) (xy 267.845762 -102.433946) (xy 267.787837 -102.418425) (xy 267.732433 -102.395476)
			(xy 267.680499 -102.365492) (xy 267.632923 -102.328986) (xy 267.590518 -102.286581) (xy 267.554012 -102.239005)
			(xy 267.524028 -102.187071) (xy 267.501079 -102.131667) (xy 267.485558 -102.073742) (xy 267.47773 -102.014286)
			(xy 267.47724 -101.984302) (xy 168.800651 -101.984302) (xy 168.80029 -102.006412) (xy 168.792462 -102.065868)
			(xy 168.776941 -102.123793) (xy 168.753992 -102.179197) (xy 168.724008 -102.231131) (xy 168.687502 -102.278707)
			(xy 168.645097 -102.321112) (xy 168.597521 -102.357618) (xy 168.545587 -102.387602) (xy 168.490183 -102.410551)
			(xy 168.432258 -102.426072) (xy 168.372802 -102.4339) (xy 168.312834 -102.4339) (xy 168.253378 -102.426072)
			(xy 168.195453 -102.410551) (xy 168.140049 -102.387602) (xy 168.088115 -102.357618) (xy 168.040539 -102.321112)
			(xy 167.998134 -102.278707) (xy 167.961628 -102.231131) (xy 167.931644 -102.179197) (xy 167.908695 -102.123793)
			(xy 167.893174 -102.065868) (xy 167.885346 -102.006412) (xy 167.884856 -101.976428) (xy 152.29332 -101.976428)
			(xy 152.29332 -101.984302) (xy 152.29283 -102.014286) (xy 152.285002 -102.073742) (xy 152.269481 -102.131667)
			(xy 152.246532 -102.187071) (xy 152.216548 -102.239005) (xy 152.180042 -102.286581) (xy 152.137637 -102.328986)
			(xy 152.090061 -102.365492) (xy 152.038127 -102.395476) (xy 151.982723 -102.418425) (xy 151.924798 -102.433946)
			(xy 151.865342 -102.441774) (xy 151.805374 -102.441774) (xy 151.745918 -102.433946) (xy 151.687993 -102.418425)
			(xy 151.632589 -102.395476) (xy 151.580655 -102.365492) (xy 151.533079 -102.328986) (xy 151.490674 -102.286581)
			(xy 151.454168 -102.239005) (xy 151.424184 -102.187071) (xy 151.401235 -102.131667) (xy 151.385714 -102.073742)
			(xy 151.377886 -102.014286) (xy 151.377396 -101.984302) (xy 52.700299 -101.984302) (xy 52.699938 -102.006396)
			(xy 52.692115 -102.065818) (xy 52.676602 -102.123711) (xy 52.653666 -102.179084) (xy 52.623699 -102.23099)
			(xy 52.587212 -102.27854) (xy 52.544832 -102.32092) (xy 52.497282 -102.357407) (xy 52.445376 -102.387374)
			(xy 52.390003 -102.41031) (xy 52.33211 -102.425823) (xy 52.272688 -102.433646) (xy 52.212752 -102.433646)
			(xy 52.15333 -102.425823) (xy 52.095437 -102.41031) (xy 52.040064 -102.387374) (xy 51.988158 -102.357407)
			(xy 51.940608 -102.32092) (xy 51.898228 -102.27854) (xy 51.861741 -102.23099) (xy 51.831774 -102.179084)
			(xy 51.808838 -102.123711) (xy 51.793325 -102.065818) (xy 51.785502 -102.006396) (xy 51.785012 -101.976428)
			(xy 36.192968 -101.976428) (xy 36.192968 -101.984302) (xy 36.192478 -102.01427) (xy 36.184655 -102.073692)
			(xy 36.169142 -102.131585) (xy 36.146206 -102.186958) (xy 36.116239 -102.238864) (xy 36.079752 -102.286414)
			(xy 36.037372 -102.328794) (xy 35.989822 -102.365281) (xy 35.937916 -102.395248) (xy 35.882543 -102.418184)
			(xy 35.82465 -102.433697) (xy 35.765228 -102.44152) (xy 35.705292 -102.44152) (xy 35.64587 -102.433697)
			(xy 35.587977 -102.418184) (xy 35.532604 -102.395248) (xy 35.480698 -102.365281) (xy 35.433148 -102.328794)
			(xy 35.390768 -102.286414) (xy 35.354281 -102.238864) (xy 35.324314 -102.186958) (xy 35.301378 -102.131585)
			(xy 35.285865 -102.073692) (xy 35.278042 -102.01427) (xy 35.277552 -101.984302) (xy 4.308094 -101.984302)
			(xy 4.308094 -103.777796) (xy 37.31006 -103.777796) (xy 37.31006 -102.914196) (xy 37.31055 -102.884228)
			(xy 37.318373 -102.824806) (xy 37.333886 -102.766913) (xy 37.356822 -102.71154) (xy 37.386789 -102.659634)
			(xy 37.423276 -102.612084) (xy 37.465656 -102.569704) (xy 37.513206 -102.533217) (xy 37.565112 -102.50325)
			(xy 37.620485 -102.480314) (xy 37.678378 -102.464801) (xy 37.7378 -102.456978) (xy 37.797736 -102.456978)
			(xy 37.857158 -102.464801) (xy 37.915051 -102.480314) (xy 37.970424 -102.50325) (xy 38.02233 -102.533217)
			(xy 38.06988 -102.569704) (xy 38.11226 -102.612084) (xy 38.148747 -102.659634) (xy 38.178714 -102.71154)
			(xy 38.20165 -102.766913) (xy 38.217163 -102.824806) (xy 38.224986 -102.884228) (xy 38.225476 -102.914196)
			(xy 38.225476 -103.776272) (xy 53.639212 -103.776272) (xy 53.639212 -102.912672) (xy 53.639702 -102.882704)
			(xy 53.647525 -102.823282) (xy 53.663038 -102.765389) (xy 53.685974 -102.710016) (xy 53.715941 -102.65811)
			(xy 53.752428 -102.61056) (xy 53.794808 -102.56818) (xy 53.842358 -102.531693) (xy 53.894264 -102.501726)
			(xy 53.949637 -102.47879) (xy 54.00753 -102.463277) (xy 54.066952 -102.455454) (xy 54.126888 -102.455454)
			(xy 54.18631 -102.463277) (xy 54.244203 -102.47879) (xy 54.299576 -102.501726) (xy 54.351482 -102.531693)
			(xy 54.399032 -102.56818) (xy 54.441412 -102.61056) (xy 54.477899 -102.65811) (xy 54.507866 -102.710016)
			(xy 54.530802 -102.765389) (xy 54.546315 -102.823282) (xy 54.554138 -102.882704) (xy 54.554628 -102.912672)
			(xy 54.554628 -103.776272) (xy 54.554603 -103.777796) (xy 153.409904 -103.777796) (xy 153.409904 -102.914196)
			(xy 153.410394 -102.884212) (xy 153.418222 -102.824756) (xy 153.433743 -102.766831) (xy 153.456692 -102.711427)
			(xy 153.486676 -102.659493) (xy 153.523182 -102.611917) (xy 153.565587 -102.569512) (xy 153.613163 -102.533006)
			(xy 153.665097 -102.503022) (xy 153.720501 -102.480073) (xy 153.778426 -102.464552) (xy 153.837882 -102.456724)
			(xy 153.89785 -102.456724) (xy 153.957306 -102.464552) (xy 154.015231 -102.480073) (xy 154.070635 -102.503022)
			(xy 154.122569 -102.533006) (xy 154.170145 -102.569512) (xy 154.21255 -102.611917) (xy 154.249056 -102.659493)
			(xy 154.27904 -102.711427) (xy 154.301989 -102.766831) (xy 154.31751 -102.824756) (xy 154.325338 -102.884212)
			(xy 154.325828 -102.914196) (xy 154.325828 -103.776272) (xy 169.739056 -103.776272) (xy 169.739056 -102.912672)
			(xy 169.739546 -102.882688) (xy 169.747374 -102.823232) (xy 169.762895 -102.765307) (xy 169.785844 -102.709903)
			(xy 169.815828 -102.657969) (xy 169.852334 -102.610393) (xy 169.894739 -102.567988) (xy 169.942315 -102.531482)
			(xy 169.994249 -102.501498) (xy 170.049653 -102.478549) (xy 170.107578 -102.463028) (xy 170.167034 -102.4552)
			(xy 170.227002 -102.4552) (xy 170.286458 -102.463028) (xy 170.344383 -102.478549) (xy 170.399787 -102.501498)
			(xy 170.451721 -102.531482) (xy 170.499297 -102.567988) (xy 170.541702 -102.610393) (xy 170.578208 -102.657969)
			(xy 170.608192 -102.709903) (xy 170.631141 -102.765307) (xy 170.646662 -102.823232) (xy 170.65449 -102.882688)
			(xy 170.65498 -102.912672) (xy 170.65498 -103.776272) (xy 170.654955 -103.777796) (xy 269.509748 -103.777796)
			(xy 269.509748 -102.914196) (xy 269.510238 -102.884212) (xy 269.518066 -102.824756) (xy 269.533587 -102.766831)
			(xy 269.556536 -102.711427) (xy 269.58652 -102.659493) (xy 269.623026 -102.611917) (xy 269.665431 -102.569512)
			(xy 269.713007 -102.533006) (xy 269.764941 -102.503022) (xy 269.820345 -102.480073) (xy 269.87827 -102.464552)
			(xy 269.937726 -102.456724) (xy 269.997694 -102.456724) (xy 270.05715 -102.464552) (xy 270.115075 -102.480073)
			(xy 270.170479 -102.503022) (xy 270.222413 -102.533006) (xy 270.269989 -102.569512) (xy 270.312394 -102.611917)
			(xy 270.3489 -102.659493) (xy 270.378884 -102.711427) (xy 270.401833 -102.766831) (xy 270.417354 -102.824756)
			(xy 270.425182 -102.884212) (xy 270.425672 -102.914196) (xy 270.425672 -103.776272) (xy 285.8389 -103.776272)
			(xy 285.8389 -102.912672) (xy 285.83939 -102.882688) (xy 285.847218 -102.823232) (xy 285.862739 -102.765307)
			(xy 285.885688 -102.709903) (xy 285.915672 -102.657969) (xy 285.952178 -102.610393) (xy 285.994583 -102.567988)
			(xy 286.042159 -102.531482) (xy 286.094093 -102.501498) (xy 286.149497 -102.478549) (xy 286.207422 -102.463028)
			(xy 286.266878 -102.4552) (xy 286.326846 -102.4552) (xy 286.386302 -102.463028) (xy 286.444227 -102.478549)
			(xy 286.499631 -102.501498) (xy 286.551565 -102.531482) (xy 286.599141 -102.567988) (xy 286.641546 -102.610393)
			(xy 286.678052 -102.657969) (xy 286.708036 -102.709903) (xy 286.730985 -102.765307) (xy 286.746506 -102.823232)
			(xy 286.754334 -102.882688) (xy 286.754824 -102.912672) (xy 286.754824 -103.776272) (xy 286.754799 -103.777796)
			(xy 385.6101 -103.777796) (xy 385.6101 -102.914196) (xy 385.61059 -102.884228) (xy 385.618413 -102.824806)
			(xy 385.633926 -102.766913) (xy 385.656862 -102.71154) (xy 385.686829 -102.659634) (xy 385.723316 -102.612084)
			(xy 385.765696 -102.569704) (xy 385.813246 -102.533217) (xy 385.865152 -102.50325) (xy 385.920525 -102.480314)
			(xy 385.978418 -102.464801) (xy 386.03784 -102.456978) (xy 386.097776 -102.456978) (xy 386.157198 -102.464801)
			(xy 386.215091 -102.480314) (xy 386.270464 -102.50325) (xy 386.32237 -102.533217) (xy 386.36992 -102.569704)
			(xy 386.4123 -102.612084) (xy 386.448787 -102.659634) (xy 386.478754 -102.71154) (xy 386.50169 -102.766913)
			(xy 386.517203 -102.824806) (xy 386.525026 -102.884228) (xy 386.525516 -102.914196) (xy 386.525516 -103.776272)
			(xy 401.939252 -103.776272) (xy 401.939252 -102.912672) (xy 401.939742 -102.882704) (xy 401.947565 -102.823282)
			(xy 401.963078 -102.765389) (xy 401.986014 -102.710016) (xy 402.015981 -102.65811) (xy 402.052468 -102.61056)
			(xy 402.094848 -102.56818) (xy 402.142398 -102.531693) (xy 402.194304 -102.501726) (xy 402.249677 -102.47879)
			(xy 402.30757 -102.463277) (xy 402.366992 -102.455454) (xy 402.426928 -102.455454) (xy 402.48635 -102.463277)
			(xy 402.544243 -102.47879) (xy 402.599616 -102.501726) (xy 402.651522 -102.531693) (xy 402.699072 -102.56818)
			(xy 402.741452 -102.61056) (xy 402.777939 -102.65811) (xy 402.807906 -102.710016) (xy 402.830842 -102.765389)
			(xy 402.846355 -102.823282) (xy 402.854178 -102.882704) (xy 402.854668 -102.912672) (xy 402.854668 -103.776272)
			(xy 402.854178 -103.80624) (xy 402.846355 -103.865662) (xy 402.830842 -103.923555) (xy 402.807906 -103.978928)
			(xy 402.777939 -104.030834) (xy 402.741452 -104.078384) (xy 402.699072 -104.120764) (xy 402.651522 -104.157251)
			(xy 402.599616 -104.187218) (xy 402.544243 -104.210154) (xy 402.48635 -104.225667) (xy 402.426928 -104.23349)
			(xy 402.366992 -104.23349) (xy 402.30757 -104.225667) (xy 402.249677 -104.210154) (xy 402.194304 -104.187218)
			(xy 402.142398 -104.157251) (xy 402.094848 -104.120764) (xy 402.052468 -104.078384) (xy 402.015981 -104.030834)
			(xy 401.986014 -103.978928) (xy 401.963078 -103.923555) (xy 401.947565 -103.865662) (xy 401.939742 -103.80624)
			(xy 401.939252 -103.776272) (xy 386.525516 -103.776272) (xy 386.525516 -103.777796) (xy 386.525026 -103.807764)
			(xy 386.517203 -103.867186) (xy 386.50169 -103.925079) (xy 386.478754 -103.980452) (xy 386.448787 -104.032358)
			(xy 386.4123 -104.079908) (xy 386.36992 -104.122288) (xy 386.32237 -104.158775) (xy 386.270464 -104.188742)
			(xy 386.215091 -104.211678) (xy 386.157198 -104.227191) (xy 386.097776 -104.235014) (xy 386.03784 -104.235014)
			(xy 385.978418 -104.227191) (xy 385.920525 -104.211678) (xy 385.865152 -104.188742) (xy 385.813246 -104.158775)
			(xy 385.765696 -104.122288) (xy 385.723316 -104.079908) (xy 385.686829 -104.032358) (xy 385.656862 -103.980452)
			(xy 385.633926 -103.925079) (xy 385.618413 -103.867186) (xy 385.61059 -103.807764) (xy 385.6101 -103.777796)
			(xy 286.754799 -103.777796) (xy 286.754334 -103.806256) (xy 286.746506 -103.865712) (xy 286.730985 -103.923637)
			(xy 286.708036 -103.979041) (xy 286.678052 -104.030975) (xy 286.641546 -104.078551) (xy 286.599141 -104.120956)
			(xy 286.551565 -104.157462) (xy 286.499631 -104.187446) (xy 286.444227 -104.210395) (xy 286.386302 -104.225916)
			(xy 286.326846 -104.233744) (xy 286.266878 -104.233744) (xy 286.207422 -104.225916) (xy 286.149497 -104.210395)
			(xy 286.094093 -104.187446) (xy 286.042159 -104.157462) (xy 285.994583 -104.120956) (xy 285.952178 -104.078551)
			(xy 285.915672 -104.030975) (xy 285.885688 -103.979041) (xy 285.862739 -103.923637) (xy 285.847218 -103.865712)
			(xy 285.83939 -103.806256) (xy 285.8389 -103.776272) (xy 270.425672 -103.776272) (xy 270.425672 -103.777796)
			(xy 270.425182 -103.80778) (xy 270.417354 -103.867236) (xy 270.401833 -103.925161) (xy 270.378884 -103.980565)
			(xy 270.3489 -104.032499) (xy 270.312394 -104.080075) (xy 270.269989 -104.12248) (xy 270.222413 -104.158986)
			(xy 270.170479 -104.18897) (xy 270.115075 -104.211919) (xy 270.05715 -104.22744) (xy 269.997694 -104.235268)
			(xy 269.937726 -104.235268) (xy 269.87827 -104.22744) (xy 269.820345 -104.211919) (xy 269.764941 -104.18897)
			(xy 269.713007 -104.158986) (xy 269.665431 -104.12248) (xy 269.623026 -104.080075) (xy 269.58652 -104.032499)
			(xy 269.556536 -103.980565) (xy 269.533587 -103.925161) (xy 269.518066 -103.867236) (xy 269.510238 -103.80778)
			(xy 269.509748 -103.777796) (xy 170.654955 -103.777796) (xy 170.65449 -103.806256) (xy 170.646662 -103.865712)
			(xy 170.631141 -103.923637) (xy 170.608192 -103.979041) (xy 170.578208 -104.030975) (xy 170.541702 -104.078551)
			(xy 170.499297 -104.120956) (xy 170.451721 -104.157462) (xy 170.399787 -104.187446) (xy 170.344383 -104.210395)
			(xy 170.286458 -104.225916) (xy 170.227002 -104.233744) (xy 170.167034 -104.233744) (xy 170.107578 -104.225916)
			(xy 170.049653 -104.210395) (xy 169.994249 -104.187446) (xy 169.942315 -104.157462) (xy 169.894739 -104.120956)
			(xy 169.852334 -104.078551) (xy 169.815828 -104.030975) (xy 169.785844 -103.979041) (xy 169.762895 -103.923637)
			(xy 169.747374 -103.865712) (xy 169.739546 -103.806256) (xy 169.739056 -103.776272) (xy 154.325828 -103.776272)
			(xy 154.325828 -103.777796) (xy 154.325338 -103.80778) (xy 154.31751 -103.867236) (xy 154.301989 -103.925161)
			(xy 154.27904 -103.980565) (xy 154.249056 -104.032499) (xy 154.21255 -104.080075) (xy 154.170145 -104.12248)
			(xy 154.122569 -104.158986) (xy 154.070635 -104.18897) (xy 154.015231 -104.211919) (xy 153.957306 -104.22744)
			(xy 153.89785 -104.235268) (xy 153.837882 -104.235268) (xy 153.778426 -104.22744) (xy 153.720501 -104.211919)
			(xy 153.665097 -104.18897) (xy 153.613163 -104.158986) (xy 153.565587 -104.12248) (xy 153.523182 -104.080075)
			(xy 153.486676 -104.032499) (xy 153.456692 -103.980565) (xy 153.433743 -103.925161) (xy 153.418222 -103.867236)
			(xy 153.410394 -103.80778) (xy 153.409904 -103.777796) (xy 54.554603 -103.777796) (xy 54.554138 -103.80624)
			(xy 54.546315 -103.865662) (xy 54.530802 -103.923555) (xy 54.507866 -103.978928) (xy 54.477899 -104.030834)
			(xy 54.441412 -104.078384) (xy 54.399032 -104.120764) (xy 54.351482 -104.157251) (xy 54.299576 -104.187218)
			(xy 54.244203 -104.210154) (xy 54.18631 -104.225667) (xy 54.126888 -104.23349) (xy 54.066952 -104.23349)
			(xy 54.00753 -104.225667) (xy 53.949637 -104.210154) (xy 53.894264 -104.187218) (xy 53.842358 -104.157251)
			(xy 53.794808 -104.120764) (xy 53.752428 -104.078384) (xy 53.715941 -104.030834) (xy 53.685974 -103.978928)
			(xy 53.663038 -103.923555) (xy 53.647525 -103.865662) (xy 53.639702 -103.80624) (xy 53.639212 -103.776272)
			(xy 38.225476 -103.776272) (xy 38.225476 -103.777796) (xy 38.224986 -103.807764) (xy 38.217163 -103.867186)
			(xy 38.20165 -103.925079) (xy 38.178714 -103.980452) (xy 38.148747 -104.032358) (xy 38.11226 -104.079908)
			(xy 38.06988 -104.122288) (xy 38.02233 -104.158775) (xy 37.970424 -104.188742) (xy 37.915051 -104.211678)
			(xy 37.857158 -104.227191) (xy 37.797736 -104.235014) (xy 37.7378 -104.235014) (xy 37.678378 -104.227191)
			(xy 37.620485 -104.211678) (xy 37.565112 -104.188742) (xy 37.513206 -104.158775) (xy 37.465656 -104.122288)
			(xy 37.423276 -104.079908) (xy 37.386789 -104.032358) (xy 37.356822 -103.980452) (xy 37.333886 -103.925079)
			(xy 37.318373 -103.867186) (xy 37.31055 -103.807764) (xy 37.31006 -103.777796) (xy 4.308094 -103.777796)
			(xy 4.308094 -105.584498) (xy 34.667952 -105.584498) (xy 34.667952 -104.720898) (xy 34.668442 -104.69093)
			(xy 34.676265 -104.631508) (xy 34.691778 -104.573615) (xy 34.714714 -104.518242) (xy 34.744681 -104.466336)
			(xy 34.781168 -104.418786) (xy 34.823548 -104.376406) (xy 34.871098 -104.339919) (xy 34.923004 -104.309952)
			(xy 34.978377 -104.287016) (xy 35.03627 -104.271503) (xy 35.095692 -104.26368) (xy 35.155628 -104.26368)
			(xy 35.21505 -104.271503) (xy 35.272943 -104.287016) (xy 35.328316 -104.309952) (xy 35.380222 -104.339919)
			(xy 35.427772 -104.376406) (xy 35.470152 -104.418786) (xy 35.506639 -104.466336) (xy 35.536606 -104.518242)
			(xy 35.559542 -104.573615) (xy 35.575055 -104.631508) (xy 35.582878 -104.69093) (xy 35.583368 -104.720898)
			(xy 35.583368 -105.57637) (xy 51.785012 -105.57637) (xy 51.785012 -104.71277) (xy 51.785502 -104.682802)
			(xy 51.793325 -104.62338) (xy 51.808838 -104.565487) (xy 51.831774 -104.510114) (xy 51.861741 -104.458208)
			(xy 51.898228 -104.410658) (xy 51.940608 -104.368278) (xy 51.988158 -104.331791) (xy 52.040064 -104.301824)
			(xy 52.095437 -104.278888) (xy 52.15333 -104.263375) (xy 52.212752 -104.255552) (xy 52.272688 -104.255552)
			(xy 52.33211 -104.263375) (xy 52.390003 -104.278888) (xy 52.445376 -104.301824) (xy 52.497282 -104.331791)
			(xy 52.544832 -104.368278) (xy 52.587212 -104.410658) (xy 52.623699 -104.458208) (xy 52.653666 -104.510114)
			(xy 52.676602 -104.565487) (xy 52.692115 -104.62338) (xy 52.699938 -104.682802) (xy 52.700428 -104.71277)
			(xy 52.700428 -105.57637) (xy 52.700295 -105.584498) (xy 150.767796 -105.584498) (xy 150.767796 -104.720898)
			(xy 150.768286 -104.690914) (xy 150.776114 -104.631458) (xy 150.791635 -104.573533) (xy 150.814584 -104.518129)
			(xy 150.844568 -104.466195) (xy 150.881074 -104.418619) (xy 150.923479 -104.376214) (xy 150.971055 -104.339708)
			(xy 151.022989 -104.309724) (xy 151.078393 -104.286775) (xy 151.136318 -104.271254) (xy 151.195774 -104.263426)
			(xy 151.255742 -104.263426) (xy 151.315198 -104.271254) (xy 151.373123 -104.286775) (xy 151.428527 -104.309724)
			(xy 151.480461 -104.339708) (xy 151.528037 -104.376214) (xy 151.570442 -104.418619) (xy 151.606948 -104.466195)
			(xy 151.636932 -104.518129) (xy 151.659881 -104.573533) (xy 151.675402 -104.631458) (xy 151.68323 -104.690914)
			(xy 151.68372 -104.720898) (xy 151.68372 -105.57637) (xy 167.884856 -105.57637) (xy 167.884856 -104.71277)
			(xy 167.885346 -104.682786) (xy 167.893174 -104.62333) (xy 167.908695 -104.565405) (xy 167.931644 -104.510001)
			(xy 167.961628 -104.458067) (xy 167.998134 -104.410491) (xy 168.040539 -104.368086) (xy 168.088115 -104.33158)
			(xy 168.140049 -104.301596) (xy 168.195453 -104.278647) (xy 168.253378 -104.263126) (xy 168.312834 -104.255298)
			(xy 168.372802 -104.255298) (xy 168.432258 -104.263126) (xy 168.490183 -104.278647) (xy 168.545587 -104.301596)
			(xy 168.597521 -104.33158) (xy 168.645097 -104.368086) (xy 168.687502 -104.410491) (xy 168.724008 -104.458067)
			(xy 168.753992 -104.510001) (xy 168.776941 -104.565405) (xy 168.792462 -104.62333) (xy 168.80029 -104.682786)
			(xy 168.80078 -104.71277) (xy 168.80078 -105.57637) (xy 168.800647 -105.584498) (xy 266.86764 -105.584498)
			(xy 266.86764 -104.720898) (xy 266.86813 -104.690914) (xy 266.875958 -104.631458) (xy 266.891479 -104.573533)
			(xy 266.914428 -104.518129) (xy 266.944412 -104.466195) (xy 266.980918 -104.418619) (xy 267.023323 -104.376214)
			(xy 267.070899 -104.339708) (xy 267.122833 -104.309724) (xy 267.178237 -104.286775) (xy 267.236162 -104.271254)
			(xy 267.295618 -104.263426) (xy 267.355586 -104.263426) (xy 267.415042 -104.271254) (xy 267.472967 -104.286775)
			(xy 267.528371 -104.309724) (xy 267.580305 -104.339708) (xy 267.627881 -104.376214) (xy 267.670286 -104.418619)
			(xy 267.706792 -104.466195) (xy 267.736776 -104.518129) (xy 267.759725 -104.573533) (xy 267.775246 -104.631458)
			(xy 267.783074 -104.690914) (xy 267.783564 -104.720898) (xy 267.783564 -105.57637) (xy 283.9847 -105.57637)
			(xy 283.9847 -104.71277) (xy 283.98519 -104.682786) (xy 283.993018 -104.62333) (xy 284.008539 -104.565405)
			(xy 284.031488 -104.510001) (xy 284.061472 -104.458067) (xy 284.097978 -104.410491) (xy 284.140383 -104.368086)
			(xy 284.187959 -104.33158) (xy 284.239893 -104.301596) (xy 284.295297 -104.278647) (xy 284.353222 -104.263126)
			(xy 284.412678 -104.255298) (xy 284.472646 -104.255298) (xy 284.532102 -104.263126) (xy 284.590027 -104.278647)
			(xy 284.645431 -104.301596) (xy 284.697365 -104.33158) (xy 284.744941 -104.368086) (xy 284.787346 -104.410491)
			(xy 284.823852 -104.458067) (xy 284.853836 -104.510001) (xy 284.876785 -104.565405) (xy 284.892306 -104.62333)
			(xy 284.900134 -104.682786) (xy 284.900624 -104.71277) (xy 284.900624 -105.57637) (xy 284.900491 -105.584498)
			(xy 382.967992 -105.584498) (xy 382.967992 -104.720898) (xy 382.968482 -104.69093) (xy 382.976305 -104.631508)
			(xy 382.991818 -104.573615) (xy 383.014754 -104.518242) (xy 383.044721 -104.466336) (xy 383.081208 -104.418786)
			(xy 383.123588 -104.376406) (xy 383.171138 -104.339919) (xy 383.223044 -104.309952) (xy 383.278417 -104.287016)
			(xy 383.33631 -104.271503) (xy 383.395732 -104.26368) (xy 383.455668 -104.26368) (xy 383.51509 -104.271503)
			(xy 383.572983 -104.287016) (xy 383.628356 -104.309952) (xy 383.680262 -104.339919) (xy 383.727812 -104.376406)
			(xy 383.770192 -104.418786) (xy 383.806679 -104.466336) (xy 383.836646 -104.518242) (xy 383.859582 -104.573615)
			(xy 383.875095 -104.631508) (xy 383.882918 -104.69093) (xy 383.883408 -104.720898) (xy 383.883408 -105.57637)
			(xy 400.085052 -105.57637) (xy 400.085052 -104.71277) (xy 400.085542 -104.682802) (xy 400.093365 -104.62338)
			(xy 400.108878 -104.565487) (xy 400.131814 -104.510114) (xy 400.161781 -104.458208) (xy 400.198268 -104.410658)
			(xy 400.240648 -104.368278) (xy 400.288198 -104.331791) (xy 400.340104 -104.301824) (xy 400.395477 -104.278888)
			(xy 400.45337 -104.263375) (xy 400.512792 -104.255552) (xy 400.572728 -104.255552) (xy 400.63215 -104.263375)
			(xy 400.690043 -104.278888) (xy 400.745416 -104.301824) (xy 400.797322 -104.331791) (xy 400.844872 -104.368278)
			(xy 400.887252 -104.410658) (xy 400.923739 -104.458208) (xy 400.953706 -104.510114) (xy 400.976642 -104.565487)
			(xy 400.992155 -104.62338) (xy 400.999978 -104.682802) (xy 401.000468 -104.71277) (xy 401.000468 -105.57637)
			(xy 400.999978 -105.606338) (xy 400.992155 -105.66576) (xy 400.976642 -105.723653) (xy 400.953706 -105.779026)
			(xy 400.923739 -105.830932) (xy 400.887252 -105.878482) (xy 400.844872 -105.920862) (xy 400.797322 -105.957349)
			(xy 400.745416 -105.987316) (xy 400.690043 -106.010252) (xy 400.63215 -106.025765) (xy 400.572728 -106.033588)
			(xy 400.512792 -106.033588) (xy 400.45337 -106.025765) (xy 400.395477 -106.010252) (xy 400.340104 -105.987316)
			(xy 400.288198 -105.957349) (xy 400.240648 -105.920862) (xy 400.198268 -105.878482) (xy 400.161781 -105.830932)
			(xy 400.131814 -105.779026) (xy 400.108878 -105.723653) (xy 400.093365 -105.66576) (xy 400.085542 -105.606338)
			(xy 400.085052 -105.57637) (xy 383.883408 -105.57637) (xy 383.883408 -105.584498) (xy 383.882918 -105.614466)
			(xy 383.875095 -105.673888) (xy 383.859582 -105.731781) (xy 383.836646 -105.787154) (xy 383.806679 -105.83906)
			(xy 383.770192 -105.88661) (xy 383.727812 -105.92899) (xy 383.680262 -105.965477) (xy 383.628356 -105.995444)
			(xy 383.572983 -106.01838) (xy 383.51509 -106.033893) (xy 383.455668 -106.041716) (xy 383.395732 -106.041716)
			(xy 383.33631 -106.033893) (xy 383.278417 -106.01838) (xy 383.223044 -105.995444) (xy 383.171138 -105.965477)
			(xy 383.123588 -105.92899) (xy 383.081208 -105.88661) (xy 383.044721 -105.83906) (xy 383.014754 -105.787154)
			(xy 382.991818 -105.731781) (xy 382.976305 -105.673888) (xy 382.968482 -105.614466) (xy 382.967992 -105.584498)
			(xy 284.900491 -105.584498) (xy 284.900134 -105.606354) (xy 284.892306 -105.66581) (xy 284.876785 -105.723735)
			(xy 284.853836 -105.779139) (xy 284.823852 -105.831073) (xy 284.787346 -105.878649) (xy 284.744941 -105.921054)
			(xy 284.697365 -105.95756) (xy 284.645431 -105.987544) (xy 284.590027 -106.010493) (xy 284.532102 -106.026014)
			(xy 284.472646 -106.033842) (xy 284.412678 -106.033842) (xy 284.353222 -106.026014) (xy 284.295297 -106.010493)
			(xy 284.239893 -105.987544) (xy 284.187959 -105.95756) (xy 284.140383 -105.921054) (xy 284.097978 -105.878649)
			(xy 284.061472 -105.831073) (xy 284.031488 -105.779139) (xy 284.008539 -105.723735) (xy 283.993018 -105.66581)
			(xy 283.98519 -105.606354) (xy 283.9847 -105.57637) (xy 267.783564 -105.57637) (xy 267.783564 -105.584498)
			(xy 267.783074 -105.614482) (xy 267.775246 -105.673938) (xy 267.759725 -105.731863) (xy 267.736776 -105.787267)
			(xy 267.706792 -105.839201) (xy 267.670286 -105.886777) (xy 267.627881 -105.929182) (xy 267.580305 -105.965688)
			(xy 267.528371 -105.995672) (xy 267.472967 -106.018621) (xy 267.415042 -106.034142) (xy 267.355586 -106.04197)
			(xy 267.295618 -106.04197) (xy 267.236162 -106.034142) (xy 267.178237 -106.018621) (xy 267.122833 -105.995672)
			(xy 267.070899 -105.965688) (xy 267.023323 -105.929182) (xy 266.980918 -105.886777) (xy 266.944412 -105.839201)
			(xy 266.914428 -105.787267) (xy 266.891479 -105.731863) (xy 266.875958 -105.673938) (xy 266.86813 -105.614482)
			(xy 266.86764 -105.584498) (xy 168.800647 -105.584498) (xy 168.80029 -105.606354) (xy 168.792462 -105.66581)
			(xy 168.776941 -105.723735) (xy 168.753992 -105.779139) (xy 168.724008 -105.831073) (xy 168.687502 -105.878649)
			(xy 168.645097 -105.921054) (xy 168.597521 -105.95756) (xy 168.545587 -105.987544) (xy 168.490183 -106.010493)
			(xy 168.432258 -106.026014) (xy 168.372802 -106.033842) (xy 168.312834 -106.033842) (xy 168.253378 -106.026014)
			(xy 168.195453 -106.010493) (xy 168.140049 -105.987544) (xy 168.088115 -105.95756) (xy 168.040539 -105.921054)
			(xy 167.998134 -105.878649) (xy 167.961628 -105.831073) (xy 167.931644 -105.779139) (xy 167.908695 -105.723735)
			(xy 167.893174 -105.66581) (xy 167.885346 -105.606354) (xy 167.884856 -105.57637) (xy 151.68372 -105.57637)
			(xy 151.68372 -105.584498) (xy 151.68323 -105.614482) (xy 151.675402 -105.673938) (xy 151.659881 -105.731863)
			(xy 151.636932 -105.787267) (xy 151.606948 -105.839201) (xy 151.570442 -105.886777) (xy 151.528037 -105.929182)
			(xy 151.480461 -105.965688) (xy 151.428527 -105.995672) (xy 151.373123 -106.018621) (xy 151.315198 -106.034142)
			(xy 151.255742 -106.04197) (xy 151.195774 -106.04197) (xy 151.136318 -106.034142) (xy 151.078393 -106.018621)
			(xy 151.022989 -105.995672) (xy 150.971055 -105.965688) (xy 150.923479 -105.929182) (xy 150.881074 -105.886777)
			(xy 150.844568 -105.839201) (xy 150.814584 -105.787267) (xy 150.791635 -105.731863) (xy 150.776114 -105.673938)
			(xy 150.768286 -105.614482) (xy 150.767796 -105.584498) (xy 52.700295 -105.584498) (xy 52.699938 -105.606338)
			(xy 52.692115 -105.66576) (xy 52.676602 -105.723653) (xy 52.653666 -105.779026) (xy 52.623699 -105.830932)
			(xy 52.587212 -105.878482) (xy 52.544832 -105.920862) (xy 52.497282 -105.957349) (xy 52.445376 -105.987316)
			(xy 52.390003 -106.010252) (xy 52.33211 -106.025765) (xy 52.272688 -106.033588) (xy 52.212752 -106.033588)
			(xy 52.15333 -106.025765) (xy 52.095437 -106.010252) (xy 52.040064 -105.987316) (xy 51.988158 -105.957349)
			(xy 51.940608 -105.920862) (xy 51.898228 -105.878482) (xy 51.861741 -105.830932) (xy 51.831774 -105.779026)
			(xy 51.808838 -105.723653) (xy 51.793325 -105.66576) (xy 51.785502 -105.606338) (xy 51.785012 -105.57637)
			(xy 35.583368 -105.57637) (xy 35.583368 -105.584498) (xy 35.582878 -105.614466) (xy 35.575055 -105.673888)
			(xy 35.559542 -105.731781) (xy 35.536606 -105.787154) (xy 35.506639 -105.83906) (xy 35.470152 -105.88661)
			(xy 35.427772 -105.92899) (xy 35.380222 -105.965477) (xy 35.328316 -105.995444) (xy 35.272943 -106.01838)
			(xy 35.21505 -106.033893) (xy 35.155628 -106.041716) (xy 35.095692 -106.041716) (xy 35.03627 -106.033893)
			(xy 34.978377 -106.01838) (xy 34.923004 -105.995444) (xy 34.871098 -105.965477) (xy 34.823548 -105.92899)
			(xy 34.781168 -105.88661) (xy 34.744681 -105.83906) (xy 34.714714 -105.787154) (xy 34.691778 -105.731781)
			(xy 34.676265 -105.673888) (xy 34.668442 -105.614466) (xy 34.667952 -105.584498) (xy 4.308094 -105.584498)
			(xy 4.308094 -107.377738) (xy 37.31006 -107.377738) (xy 37.31006 -106.514138) (xy 37.31055 -106.48417)
			(xy 37.318373 -106.424748) (xy 37.333886 -106.366855) (xy 37.356822 -106.311482) (xy 37.386789 -106.259576)
			(xy 37.423276 -106.212026) (xy 37.465656 -106.169646) (xy 37.513206 -106.133159) (xy 37.565112 -106.103192)
			(xy 37.620485 -106.080256) (xy 37.678378 -106.064743) (xy 37.7378 -106.05692) (xy 37.797736 -106.05692)
			(xy 37.857158 -106.064743) (xy 37.915051 -106.080256) (xy 37.970424 -106.103192) (xy 38.02233 -106.133159)
			(xy 38.06988 -106.169646) (xy 38.11226 -106.212026) (xy 38.148747 -106.259576) (xy 38.178714 -106.311482)
			(xy 38.20165 -106.366855) (xy 38.217163 -106.424748) (xy 38.224986 -106.48417) (xy 38.225476 -106.514138)
			(xy 38.225476 -107.376214) (xy 53.639212 -107.376214) (xy 53.639212 -106.512614) (xy 53.639702 -106.482646)
			(xy 53.647525 -106.423224) (xy 53.663038 -106.365331) (xy 53.685974 -106.309958) (xy 53.715941 -106.258052)
			(xy 53.752428 -106.210502) (xy 53.794808 -106.168122) (xy 53.842358 -106.131635) (xy 53.894264 -106.101668)
			(xy 53.949637 -106.078732) (xy 54.00753 -106.063219) (xy 54.066952 -106.055396) (xy 54.126888 -106.055396)
			(xy 54.18631 -106.063219) (xy 54.244203 -106.078732) (xy 54.299576 -106.101668) (xy 54.351482 -106.131635)
			(xy 54.399032 -106.168122) (xy 54.441412 -106.210502) (xy 54.477899 -106.258052) (xy 54.507866 -106.309958)
			(xy 54.530802 -106.365331) (xy 54.546315 -106.423224) (xy 54.554138 -106.482646) (xy 54.554628 -106.512614)
			(xy 54.554628 -107.376214) (xy 54.554603 -107.377738) (xy 153.409904 -107.377738) (xy 153.409904 -106.514138)
			(xy 153.410394 -106.484154) (xy 153.418222 -106.424698) (xy 153.433743 -106.366773) (xy 153.456692 -106.311369)
			(xy 153.486676 -106.259435) (xy 153.523182 -106.211859) (xy 153.565587 -106.169454) (xy 153.613163 -106.132948)
			(xy 153.665097 -106.102964) (xy 153.720501 -106.080015) (xy 153.778426 -106.064494) (xy 153.837882 -106.056666)
			(xy 153.89785 -106.056666) (xy 153.957306 -106.064494) (xy 154.015231 -106.080015) (xy 154.070635 -106.102964)
			(xy 154.122569 -106.132948) (xy 154.170145 -106.169454) (xy 154.21255 -106.211859) (xy 154.249056 -106.259435)
			(xy 154.27904 -106.311369) (xy 154.301989 -106.366773) (xy 154.31751 -106.424698) (xy 154.325338 -106.484154)
			(xy 154.325828 -106.514138) (xy 154.325828 -107.376214) (xy 169.739056 -107.376214) (xy 169.739056 -106.512614)
			(xy 169.739546 -106.48263) (xy 169.747374 -106.423174) (xy 169.762895 -106.365249) (xy 169.785844 -106.309845)
			(xy 169.815828 -106.257911) (xy 169.852334 -106.210335) (xy 169.894739 -106.16793) (xy 169.942315 -106.131424)
			(xy 169.994249 -106.10144) (xy 170.049653 -106.078491) (xy 170.107578 -106.06297) (xy 170.167034 -106.055142)
			(xy 170.227002 -106.055142) (xy 170.286458 -106.06297) (xy 170.344383 -106.078491) (xy 170.399787 -106.10144)
			(xy 170.451721 -106.131424) (xy 170.499297 -106.16793) (xy 170.541702 -106.210335) (xy 170.578208 -106.257911)
			(xy 170.608192 -106.309845) (xy 170.631141 -106.365249) (xy 170.646662 -106.423174) (xy 170.65449 -106.48263)
			(xy 170.65498 -106.512614) (xy 170.65498 -107.376214) (xy 170.654955 -107.377738) (xy 269.509748 -107.377738)
			(xy 269.509748 -106.514138) (xy 269.510238 -106.484154) (xy 269.518066 -106.424698) (xy 269.533587 -106.366773)
			(xy 269.556536 -106.311369) (xy 269.58652 -106.259435) (xy 269.623026 -106.211859) (xy 269.665431 -106.169454)
			(xy 269.713007 -106.132948) (xy 269.764941 -106.102964) (xy 269.820345 -106.080015) (xy 269.87827 -106.064494)
			(xy 269.937726 -106.056666) (xy 269.997694 -106.056666) (xy 270.05715 -106.064494) (xy 270.115075 -106.080015)
			(xy 270.170479 -106.102964) (xy 270.222413 -106.132948) (xy 270.269989 -106.169454) (xy 270.312394 -106.211859)
			(xy 270.3489 -106.259435) (xy 270.378884 -106.311369) (xy 270.401833 -106.366773) (xy 270.417354 -106.424698)
			(xy 270.425182 -106.484154) (xy 270.425672 -106.514138) (xy 270.425672 -107.376214) (xy 285.8389 -107.376214)
			(xy 285.8389 -106.512614) (xy 285.83939 -106.48263) (xy 285.847218 -106.423174) (xy 285.862739 -106.365249)
			(xy 285.885688 -106.309845) (xy 285.915672 -106.257911) (xy 285.952178 -106.210335) (xy 285.994583 -106.16793)
			(xy 286.042159 -106.131424) (xy 286.094093 -106.10144) (xy 286.149497 -106.078491) (xy 286.207422 -106.06297)
			(xy 286.266878 -106.055142) (xy 286.326846 -106.055142) (xy 286.386302 -106.06297) (xy 286.444227 -106.078491)
			(xy 286.499631 -106.10144) (xy 286.551565 -106.131424) (xy 286.599141 -106.16793) (xy 286.641546 -106.210335)
			(xy 286.678052 -106.257911) (xy 286.708036 -106.309845) (xy 286.730985 -106.365249) (xy 286.746506 -106.423174)
			(xy 286.754334 -106.48263) (xy 286.754824 -106.512614) (xy 286.754824 -107.376214) (xy 286.754799 -107.377738)
			(xy 385.6101 -107.377738) (xy 385.6101 -106.514138) (xy 385.61059 -106.48417) (xy 385.618413 -106.424748)
			(xy 385.633926 -106.366855) (xy 385.656862 -106.311482) (xy 385.686829 -106.259576) (xy 385.723316 -106.212026)
			(xy 385.765696 -106.169646) (xy 385.813246 -106.133159) (xy 385.865152 -106.103192) (xy 385.920525 -106.080256)
			(xy 385.978418 -106.064743) (xy 386.03784 -106.05692) (xy 386.097776 -106.05692) (xy 386.157198 -106.064743)
			(xy 386.215091 -106.080256) (xy 386.270464 -106.103192) (xy 386.32237 -106.133159) (xy 386.36992 -106.169646)
			(xy 386.4123 -106.212026) (xy 386.448787 -106.259576) (xy 386.478754 -106.311482) (xy 386.50169 -106.366855)
			(xy 386.517203 -106.424748) (xy 386.525026 -106.48417) (xy 386.525516 -106.514138) (xy 386.525516 -107.376214)
			(xy 401.939252 -107.376214) (xy 401.939252 -106.512614) (xy 401.939742 -106.482646) (xy 401.947565 -106.423224)
			(xy 401.963078 -106.365331) (xy 401.986014 -106.309958) (xy 402.015981 -106.258052) (xy 402.052468 -106.210502)
			(xy 402.094848 -106.168122) (xy 402.142398 -106.131635) (xy 402.194304 -106.101668) (xy 402.249677 -106.078732)
			(xy 402.30757 -106.063219) (xy 402.366992 -106.055396) (xy 402.426928 -106.055396) (xy 402.48635 -106.063219)
			(xy 402.544243 -106.078732) (xy 402.599616 -106.101668) (xy 402.651522 -106.131635) (xy 402.699072 -106.168122)
			(xy 402.741452 -106.210502) (xy 402.777939 -106.258052) (xy 402.807906 -106.309958) (xy 402.830842 -106.365331)
			(xy 402.846355 -106.423224) (xy 402.854178 -106.482646) (xy 402.854668 -106.512614) (xy 402.854668 -107.376214)
			(xy 402.854178 -107.406182) (xy 402.846355 -107.465604) (xy 402.830842 -107.523497) (xy 402.807906 -107.57887)
			(xy 402.777939 -107.630776) (xy 402.741452 -107.678326) (xy 402.699072 -107.720706) (xy 402.651522 -107.757193)
			(xy 402.599616 -107.78716) (xy 402.544243 -107.810096) (xy 402.48635 -107.825609) (xy 402.426928 -107.833432)
			(xy 402.366992 -107.833432) (xy 402.30757 -107.825609) (xy 402.249677 -107.810096) (xy 402.194304 -107.78716)
			(xy 402.142398 -107.757193) (xy 402.094848 -107.720706) (xy 402.052468 -107.678326) (xy 402.015981 -107.630776)
			(xy 401.986014 -107.57887) (xy 401.963078 -107.523497) (xy 401.947565 -107.465604) (xy 401.939742 -107.406182)
			(xy 401.939252 -107.376214) (xy 386.525516 -107.376214) (xy 386.525516 -107.377738) (xy 386.525026 -107.407706)
			(xy 386.517203 -107.467128) (xy 386.50169 -107.525021) (xy 386.478754 -107.580394) (xy 386.448787 -107.6323)
			(xy 386.4123 -107.67985) (xy 386.36992 -107.72223) (xy 386.32237 -107.758717) (xy 386.270464 -107.788684)
			(xy 386.215091 -107.81162) (xy 386.157198 -107.827133) (xy 386.097776 -107.834956) (xy 386.03784 -107.834956)
			(xy 385.978418 -107.827133) (xy 385.920525 -107.81162) (xy 385.865152 -107.788684) (xy 385.813246 -107.758717)
			(xy 385.765696 -107.72223) (xy 385.723316 -107.67985) (xy 385.686829 -107.6323) (xy 385.656862 -107.580394)
			(xy 385.633926 -107.525021) (xy 385.618413 -107.467128) (xy 385.61059 -107.407706) (xy 385.6101 -107.377738)
			(xy 286.754799 -107.377738) (xy 286.754334 -107.406198) (xy 286.746506 -107.465654) (xy 286.730985 -107.523579)
			(xy 286.708036 -107.578983) (xy 286.678052 -107.630917) (xy 286.641546 -107.678493) (xy 286.599141 -107.720898)
			(xy 286.551565 -107.757404) (xy 286.499631 -107.787388) (xy 286.444227 -107.810337) (xy 286.386302 -107.825858)
			(xy 286.326846 -107.833686) (xy 286.266878 -107.833686) (xy 286.207422 -107.825858) (xy 286.149497 -107.810337)
			(xy 286.094093 -107.787388) (xy 286.042159 -107.757404) (xy 285.994583 -107.720898) (xy 285.952178 -107.678493)
			(xy 285.915672 -107.630917) (xy 285.885688 -107.578983) (xy 285.862739 -107.523579) (xy 285.847218 -107.465654)
			(xy 285.83939 -107.406198) (xy 285.8389 -107.376214) (xy 270.425672 -107.376214) (xy 270.425672 -107.377738)
			(xy 270.425182 -107.407722) (xy 270.417354 -107.467178) (xy 270.401833 -107.525103) (xy 270.378884 -107.580507)
			(xy 270.3489 -107.632441) (xy 270.312394 -107.680017) (xy 270.269989 -107.722422) (xy 270.222413 -107.758928)
			(xy 270.170479 -107.788912) (xy 270.115075 -107.811861) (xy 270.05715 -107.827382) (xy 269.997694 -107.83521)
			(xy 269.937726 -107.83521) (xy 269.87827 -107.827382) (xy 269.820345 -107.811861) (xy 269.764941 -107.788912)
			(xy 269.713007 -107.758928) (xy 269.665431 -107.722422) (xy 269.623026 -107.680017) (xy 269.58652 -107.632441)
			(xy 269.556536 -107.580507) (xy 269.533587 -107.525103) (xy 269.518066 -107.467178) (xy 269.510238 -107.407722)
			(xy 269.509748 -107.377738) (xy 170.654955 -107.377738) (xy 170.65449 -107.406198) (xy 170.646662 -107.465654)
			(xy 170.631141 -107.523579) (xy 170.608192 -107.578983) (xy 170.578208 -107.630917) (xy 170.541702 -107.678493)
			(xy 170.499297 -107.720898) (xy 170.451721 -107.757404) (xy 170.399787 -107.787388) (xy 170.344383 -107.810337)
			(xy 170.286458 -107.825858) (xy 170.227002 -107.833686) (xy 170.167034 -107.833686) (xy 170.107578 -107.825858)
			(xy 170.049653 -107.810337) (xy 169.994249 -107.787388) (xy 169.942315 -107.757404) (xy 169.894739 -107.720898)
			(xy 169.852334 -107.678493) (xy 169.815828 -107.630917) (xy 169.785844 -107.578983) (xy 169.762895 -107.523579)
			(xy 169.747374 -107.465654) (xy 169.739546 -107.406198) (xy 169.739056 -107.376214) (xy 154.325828 -107.376214)
			(xy 154.325828 -107.377738) (xy 154.325338 -107.407722) (xy 154.31751 -107.467178) (xy 154.301989 -107.525103)
			(xy 154.27904 -107.580507) (xy 154.249056 -107.632441) (xy 154.21255 -107.680017) (xy 154.170145 -107.722422)
			(xy 154.122569 -107.758928) (xy 154.070635 -107.788912) (xy 154.015231 -107.811861) (xy 153.957306 -107.827382)
			(xy 153.89785 -107.83521) (xy 153.837882 -107.83521) (xy 153.778426 -107.827382) (xy 153.720501 -107.811861)
			(xy 153.665097 -107.788912) (xy 153.613163 -107.758928) (xy 153.565587 -107.722422) (xy 153.523182 -107.680017)
			(xy 153.486676 -107.632441) (xy 153.456692 -107.580507) (xy 153.433743 -107.525103) (xy 153.418222 -107.467178)
			(xy 153.410394 -107.407722) (xy 153.409904 -107.377738) (xy 54.554603 -107.377738) (xy 54.554138 -107.406182)
			(xy 54.546315 -107.465604) (xy 54.530802 -107.523497) (xy 54.507866 -107.57887) (xy 54.477899 -107.630776)
			(xy 54.441412 -107.678326) (xy 54.399032 -107.720706) (xy 54.351482 -107.757193) (xy 54.299576 -107.78716)
			(xy 54.244203 -107.810096) (xy 54.18631 -107.825609) (xy 54.126888 -107.833432) (xy 54.066952 -107.833432)
			(xy 54.00753 -107.825609) (xy 53.949637 -107.810096) (xy 53.894264 -107.78716) (xy 53.842358 -107.757193)
			(xy 53.794808 -107.720706) (xy 53.752428 -107.678326) (xy 53.715941 -107.630776) (xy 53.685974 -107.57887)
			(xy 53.663038 -107.523497) (xy 53.647525 -107.465604) (xy 53.639702 -107.406182) (xy 53.639212 -107.376214)
			(xy 38.225476 -107.376214) (xy 38.225476 -107.377738) (xy 38.224986 -107.407706) (xy 38.217163 -107.467128)
			(xy 38.20165 -107.525021) (xy 38.178714 -107.580394) (xy 38.148747 -107.6323) (xy 38.11226 -107.67985)
			(xy 38.06988 -107.72223) (xy 38.02233 -107.758717) (xy 37.970424 -107.788684) (xy 37.915051 -107.81162)
			(xy 37.857158 -107.827133) (xy 37.797736 -107.834956) (xy 37.7378 -107.834956) (xy 37.678378 -107.827133)
			(xy 37.620485 -107.81162) (xy 37.565112 -107.788684) (xy 37.513206 -107.758717) (xy 37.465656 -107.72223)
			(xy 37.423276 -107.67985) (xy 37.386789 -107.6323) (xy 37.356822 -107.580394) (xy 37.333886 -107.525021)
			(xy 37.318373 -107.467128) (xy 37.31055 -107.407706) (xy 37.31006 -107.377738) (xy 4.308094 -107.377738)
			(xy 4.308094 -109.18444) (xy 34.667952 -109.18444) (xy 34.667952 -108.32084) (xy 34.668442 -108.290872)
			(xy 34.676265 -108.23145) (xy 34.691778 -108.173557) (xy 34.714714 -108.118184) (xy 34.744681 -108.066278)
			(xy 34.781168 -108.018728) (xy 34.823548 -107.976348) (xy 34.871098 -107.939861) (xy 34.923004 -107.909894)
			(xy 34.978377 -107.886958) (xy 35.03627 -107.871445) (xy 35.095692 -107.863622) (xy 35.155628 -107.863622)
			(xy 35.21505 -107.871445) (xy 35.272943 -107.886958) (xy 35.328316 -107.909894) (xy 35.380222 -107.939861)
			(xy 35.427772 -107.976348) (xy 35.470152 -108.018728) (xy 35.506639 -108.066278) (xy 35.536606 -108.118184)
			(xy 35.559542 -108.173557) (xy 35.575055 -108.23145) (xy 35.582878 -108.290872) (xy 35.583368 -108.32084)
			(xy 35.583368 -109.176312) (xy 51.785012 -109.176312) (xy 51.785012 -108.312712) (xy 51.785502 -108.282744)
			(xy 51.793325 -108.223322) (xy 51.808838 -108.165429) (xy 51.831774 -108.110056) (xy 51.861741 -108.05815)
			(xy 51.898228 -108.0106) (xy 51.940608 -107.96822) (xy 51.988158 -107.931733) (xy 52.040064 -107.901766)
			(xy 52.095437 -107.87883) (xy 52.15333 -107.863317) (xy 52.212752 -107.855494) (xy 52.272688 -107.855494)
			(xy 52.33211 -107.863317) (xy 52.390003 -107.87883) (xy 52.445376 -107.901766) (xy 52.497282 -107.931733)
			(xy 52.544832 -107.96822) (xy 52.587212 -108.0106) (xy 52.623699 -108.05815) (xy 52.653666 -108.110056)
			(xy 52.676602 -108.165429) (xy 52.692115 -108.223322) (xy 52.699938 -108.282744) (xy 52.700428 -108.312712)
			(xy 52.700428 -109.176312) (xy 52.700295 -109.18444) (xy 150.767796 -109.18444) (xy 150.767796 -108.32084)
			(xy 150.768286 -108.290856) (xy 150.776114 -108.2314) (xy 150.791635 -108.173475) (xy 150.814584 -108.118071)
			(xy 150.844568 -108.066137) (xy 150.881074 -108.018561) (xy 150.923479 -107.976156) (xy 150.971055 -107.93965)
			(xy 151.022989 -107.909666) (xy 151.078393 -107.886717) (xy 151.136318 -107.871196) (xy 151.195774 -107.863368)
			(xy 151.255742 -107.863368) (xy 151.315198 -107.871196) (xy 151.373123 -107.886717) (xy 151.428527 -107.909666)
			(xy 151.480461 -107.93965) (xy 151.528037 -107.976156) (xy 151.570442 -108.018561) (xy 151.606948 -108.066137)
			(xy 151.636932 -108.118071) (xy 151.659881 -108.173475) (xy 151.675402 -108.2314) (xy 151.68323 -108.290856)
			(xy 151.68372 -108.32084) (xy 151.68372 -109.176312) (xy 167.884856 -109.176312) (xy 167.884856 -108.312712)
			(xy 167.885346 -108.282728) (xy 167.893174 -108.223272) (xy 167.908695 -108.165347) (xy 167.931644 -108.109943)
			(xy 167.961628 -108.058009) (xy 167.998134 -108.010433) (xy 168.040539 -107.968028) (xy 168.088115 -107.931522)
			(xy 168.140049 -107.901538) (xy 168.195453 -107.878589) (xy 168.253378 -107.863068) (xy 168.312834 -107.85524)
			(xy 168.372802 -107.85524) (xy 168.432258 -107.863068) (xy 168.490183 -107.878589) (xy 168.545587 -107.901538)
			(xy 168.597521 -107.931522) (xy 168.645097 -107.968028) (xy 168.687502 -108.010433) (xy 168.724008 -108.058009)
			(xy 168.753992 -108.109943) (xy 168.776941 -108.165347) (xy 168.792462 -108.223272) (xy 168.80029 -108.282728)
			(xy 168.80078 -108.312712) (xy 168.80078 -109.176312) (xy 168.800647 -109.18444) (xy 266.86764 -109.18444)
			(xy 266.86764 -108.32084) (xy 266.86813 -108.290856) (xy 266.875958 -108.2314) (xy 266.891479 -108.173475)
			(xy 266.914428 -108.118071) (xy 266.944412 -108.066137) (xy 266.980918 -108.018561) (xy 267.023323 -107.976156)
			(xy 267.070899 -107.93965) (xy 267.122833 -107.909666) (xy 267.178237 -107.886717) (xy 267.236162 -107.871196)
			(xy 267.295618 -107.863368) (xy 267.355586 -107.863368) (xy 267.415042 -107.871196) (xy 267.472967 -107.886717)
			(xy 267.528371 -107.909666) (xy 267.580305 -107.93965) (xy 267.627881 -107.976156) (xy 267.670286 -108.018561)
			(xy 267.706792 -108.066137) (xy 267.736776 -108.118071) (xy 267.759725 -108.173475) (xy 267.775246 -108.2314)
			(xy 267.783074 -108.290856) (xy 267.783564 -108.32084) (xy 267.783564 -109.176312) (xy 283.9847 -109.176312)
			(xy 283.9847 -108.312712) (xy 283.98519 -108.282728) (xy 283.993018 -108.223272) (xy 284.008539 -108.165347)
			(xy 284.031488 -108.109943) (xy 284.061472 -108.058009) (xy 284.097978 -108.010433) (xy 284.140383 -107.968028)
			(xy 284.187959 -107.931522) (xy 284.239893 -107.901538) (xy 284.295297 -107.878589) (xy 284.353222 -107.863068)
			(xy 284.412678 -107.85524) (xy 284.472646 -107.85524) (xy 284.532102 -107.863068) (xy 284.590027 -107.878589)
			(xy 284.645431 -107.901538) (xy 284.697365 -107.931522) (xy 284.744941 -107.968028) (xy 284.787346 -108.010433)
			(xy 284.823852 -108.058009) (xy 284.853836 -108.109943) (xy 284.876785 -108.165347) (xy 284.892306 -108.223272)
			(xy 284.900134 -108.282728) (xy 284.900624 -108.312712) (xy 284.900624 -109.176312) (xy 284.900491 -109.18444)
			(xy 382.967992 -109.18444) (xy 382.967992 -108.32084) (xy 382.968482 -108.290872) (xy 382.976305 -108.23145)
			(xy 382.991818 -108.173557) (xy 383.014754 -108.118184) (xy 383.044721 -108.066278) (xy 383.081208 -108.018728)
			(xy 383.123588 -107.976348) (xy 383.171138 -107.939861) (xy 383.223044 -107.909894) (xy 383.278417 -107.886958)
			(xy 383.33631 -107.871445) (xy 383.395732 -107.863622) (xy 383.455668 -107.863622) (xy 383.51509 -107.871445)
			(xy 383.572983 -107.886958) (xy 383.628356 -107.909894) (xy 383.680262 -107.939861) (xy 383.727812 -107.976348)
			(xy 383.770192 -108.018728) (xy 383.806679 -108.066278) (xy 383.836646 -108.118184) (xy 383.859582 -108.173557)
			(xy 383.875095 -108.23145) (xy 383.882918 -108.290872) (xy 383.883408 -108.32084) (xy 383.883408 -109.176312)
			(xy 400.085052 -109.176312) (xy 400.085052 -108.312712) (xy 400.085542 -108.282744) (xy 400.093365 -108.223322)
			(xy 400.108878 -108.165429) (xy 400.131814 -108.110056) (xy 400.161781 -108.05815) (xy 400.198268 -108.0106)
			(xy 400.240648 -107.96822) (xy 400.288198 -107.931733) (xy 400.340104 -107.901766) (xy 400.395477 -107.87883)
			(xy 400.45337 -107.863317) (xy 400.512792 -107.855494) (xy 400.572728 -107.855494) (xy 400.63215 -107.863317)
			(xy 400.690043 -107.87883) (xy 400.745416 -107.901766) (xy 400.797322 -107.931733) (xy 400.844872 -107.96822)
			(xy 400.887252 -108.0106) (xy 400.923739 -108.05815) (xy 400.953706 -108.110056) (xy 400.976642 -108.165429)
			(xy 400.992155 -108.223322) (xy 400.999978 -108.282744) (xy 401.000468 -108.312712) (xy 401.000468 -109.176312)
			(xy 400.999978 -109.20628) (xy 400.992155 -109.265702) (xy 400.976642 -109.323595) (xy 400.953706 -109.378968)
			(xy 400.923739 -109.430874) (xy 400.887252 -109.478424) (xy 400.844872 -109.520804) (xy 400.797322 -109.557291)
			(xy 400.745416 -109.587258) (xy 400.690043 -109.610194) (xy 400.63215 -109.625707) (xy 400.572728 -109.63353)
			(xy 400.512792 -109.63353) (xy 400.45337 -109.625707) (xy 400.395477 -109.610194) (xy 400.340104 -109.587258)
			(xy 400.288198 -109.557291) (xy 400.240648 -109.520804) (xy 400.198268 -109.478424) (xy 400.161781 -109.430874)
			(xy 400.131814 -109.378968) (xy 400.108878 -109.323595) (xy 400.093365 -109.265702) (xy 400.085542 -109.20628)
			(xy 400.085052 -109.176312) (xy 383.883408 -109.176312) (xy 383.883408 -109.18444) (xy 383.882918 -109.214408)
			(xy 383.875095 -109.27383) (xy 383.859582 -109.331723) (xy 383.836646 -109.387096) (xy 383.806679 -109.439002)
			(xy 383.770192 -109.486552) (xy 383.727812 -109.528932) (xy 383.680262 -109.565419) (xy 383.628356 -109.595386)
			(xy 383.572983 -109.618322) (xy 383.51509 -109.633835) (xy 383.455668 -109.641658) (xy 383.395732 -109.641658)
			(xy 383.33631 -109.633835) (xy 383.278417 -109.618322) (xy 383.223044 -109.595386) (xy 383.171138 -109.565419)
			(xy 383.123588 -109.528932) (xy 383.081208 -109.486552) (xy 383.044721 -109.439002) (xy 383.014754 -109.387096)
			(xy 382.991818 -109.331723) (xy 382.976305 -109.27383) (xy 382.968482 -109.214408) (xy 382.967992 -109.18444)
			(xy 284.900491 -109.18444) (xy 284.900134 -109.206296) (xy 284.892306 -109.265752) (xy 284.876785 -109.323677)
			(xy 284.853836 -109.379081) (xy 284.823852 -109.431015) (xy 284.787346 -109.478591) (xy 284.744941 -109.520996)
			(xy 284.697365 -109.557502) (xy 284.645431 -109.587486) (xy 284.590027 -109.610435) (xy 284.532102 -109.625956)
			(xy 284.472646 -109.633784) (xy 284.412678 -109.633784) (xy 284.353222 -109.625956) (xy 284.295297 -109.610435)
			(xy 284.239893 -109.587486) (xy 284.187959 -109.557502) (xy 284.140383 -109.520996) (xy 284.097978 -109.478591)
			(xy 284.061472 -109.431015) (xy 284.031488 -109.379081) (xy 284.008539 -109.323677) (xy 283.993018 -109.265752)
			(xy 283.98519 -109.206296) (xy 283.9847 -109.176312) (xy 267.783564 -109.176312) (xy 267.783564 -109.18444)
			(xy 267.783074 -109.214424) (xy 267.775246 -109.27388) (xy 267.759725 -109.331805) (xy 267.736776 -109.387209)
			(xy 267.706792 -109.439143) (xy 267.670286 -109.486719) (xy 267.627881 -109.529124) (xy 267.580305 -109.56563)
			(xy 267.528371 -109.595614) (xy 267.472967 -109.618563) (xy 267.415042 -109.634084) (xy 267.355586 -109.641912)
			(xy 267.295618 -109.641912) (xy 267.236162 -109.634084) (xy 267.178237 -109.618563) (xy 267.122833 -109.595614)
			(xy 267.070899 -109.56563) (xy 267.023323 -109.529124) (xy 266.980918 -109.486719) (xy 266.944412 -109.439143)
			(xy 266.914428 -109.387209) (xy 266.891479 -109.331805) (xy 266.875958 -109.27388) (xy 266.86813 -109.214424)
			(xy 266.86764 -109.18444) (xy 168.800647 -109.18444) (xy 168.80029 -109.206296) (xy 168.792462 -109.265752)
			(xy 168.776941 -109.323677) (xy 168.753992 -109.379081) (xy 168.724008 -109.431015) (xy 168.687502 -109.478591)
			(xy 168.645097 -109.520996) (xy 168.597521 -109.557502) (xy 168.545587 -109.587486) (xy 168.490183 -109.610435)
			(xy 168.432258 -109.625956) (xy 168.372802 -109.633784) (xy 168.312834 -109.633784) (xy 168.253378 -109.625956)
			(xy 168.195453 -109.610435) (xy 168.140049 -109.587486) (xy 168.088115 -109.557502) (xy 168.040539 -109.520996)
			(xy 167.998134 -109.478591) (xy 167.961628 -109.431015) (xy 167.931644 -109.379081) (xy 167.908695 -109.323677)
			(xy 167.893174 -109.265752) (xy 167.885346 -109.206296) (xy 167.884856 -109.176312) (xy 151.68372 -109.176312)
			(xy 151.68372 -109.18444) (xy 151.68323 -109.214424) (xy 151.675402 -109.27388) (xy 151.659881 -109.331805)
			(xy 151.636932 -109.387209) (xy 151.606948 -109.439143) (xy 151.570442 -109.486719) (xy 151.528037 -109.529124)
			(xy 151.480461 -109.56563) (xy 151.428527 -109.595614) (xy 151.373123 -109.618563) (xy 151.315198 -109.634084)
			(xy 151.255742 -109.641912) (xy 151.195774 -109.641912) (xy 151.136318 -109.634084) (xy 151.078393 -109.618563)
			(xy 151.022989 -109.595614) (xy 150.971055 -109.56563) (xy 150.923479 -109.529124) (xy 150.881074 -109.486719)
			(xy 150.844568 -109.439143) (xy 150.814584 -109.387209) (xy 150.791635 -109.331805) (xy 150.776114 -109.27388)
			(xy 150.768286 -109.214424) (xy 150.767796 -109.18444) (xy 52.700295 -109.18444) (xy 52.699938 -109.20628)
			(xy 52.692115 -109.265702) (xy 52.676602 -109.323595) (xy 52.653666 -109.378968) (xy 52.623699 -109.430874)
			(xy 52.587212 -109.478424) (xy 52.544832 -109.520804) (xy 52.497282 -109.557291) (xy 52.445376 -109.587258)
			(xy 52.390003 -109.610194) (xy 52.33211 -109.625707) (xy 52.272688 -109.63353) (xy 52.212752 -109.63353)
			(xy 52.15333 -109.625707) (xy 52.095437 -109.610194) (xy 52.040064 -109.587258) (xy 51.988158 -109.557291)
			(xy 51.940608 -109.520804) (xy 51.898228 -109.478424) (xy 51.861741 -109.430874) (xy 51.831774 -109.378968)
			(xy 51.808838 -109.323595) (xy 51.793325 -109.265702) (xy 51.785502 -109.20628) (xy 51.785012 -109.176312)
			(xy 35.583368 -109.176312) (xy 35.583368 -109.18444) (xy 35.582878 -109.214408) (xy 35.575055 -109.27383)
			(xy 35.559542 -109.331723) (xy 35.536606 -109.387096) (xy 35.506639 -109.439002) (xy 35.470152 -109.486552)
			(xy 35.427772 -109.528932) (xy 35.380222 -109.565419) (xy 35.328316 -109.595386) (xy 35.272943 -109.618322)
			(xy 35.21505 -109.633835) (xy 35.155628 -109.641658) (xy 35.095692 -109.641658) (xy 35.03627 -109.633835)
			(xy 34.978377 -109.618322) (xy 34.923004 -109.595386) (xy 34.871098 -109.565419) (xy 34.823548 -109.528932)
			(xy 34.781168 -109.486552) (xy 34.744681 -109.439002) (xy 34.714714 -109.387096) (xy 34.691778 -109.331723)
			(xy 34.676265 -109.27383) (xy 34.668442 -109.214408) (xy 34.667952 -109.18444) (xy 4.308094 -109.18444)
			(xy 4.308094 -110.977934) (xy 37.31006 -110.977934) (xy 37.31006 -110.114334) (xy 37.31055 -110.084366)
			(xy 37.318373 -110.024944) (xy 37.333886 -109.967051) (xy 37.356822 -109.911678) (xy 37.386789 -109.859772)
			(xy 37.423276 -109.812222) (xy 37.465656 -109.769842) (xy 37.513206 -109.733355) (xy 37.565112 -109.703388)
			(xy 37.620485 -109.680452) (xy 37.678378 -109.664939) (xy 37.7378 -109.657116) (xy 37.797736 -109.657116)
			(xy 37.857158 -109.664939) (xy 37.915051 -109.680452) (xy 37.970424 -109.703388) (xy 38.02233 -109.733355)
			(xy 38.06988 -109.769842) (xy 38.11226 -109.812222) (xy 38.148747 -109.859772) (xy 38.178714 -109.911678)
			(xy 38.20165 -109.967051) (xy 38.217163 -110.024944) (xy 38.224986 -110.084366) (xy 38.225476 -110.114334)
			(xy 38.225476 -110.97641) (xy 53.639212 -110.97641) (xy 53.639212 -110.11281) (xy 53.639702 -110.082842)
			(xy 53.647525 -110.02342) (xy 53.663038 -109.965527) (xy 53.685974 -109.910154) (xy 53.715941 -109.858248)
			(xy 53.752428 -109.810698) (xy 53.794808 -109.768318) (xy 53.842358 -109.731831) (xy 53.894264 -109.701864)
			(xy 53.949637 -109.678928) (xy 54.00753 -109.663415) (xy 54.066952 -109.655592) (xy 54.126888 -109.655592)
			(xy 54.18631 -109.663415) (xy 54.244203 -109.678928) (xy 54.299576 -109.701864) (xy 54.351482 -109.731831)
			(xy 54.399032 -109.768318) (xy 54.441412 -109.810698) (xy 54.477899 -109.858248) (xy 54.507866 -109.910154)
			(xy 54.530802 -109.965527) (xy 54.546315 -110.02342) (xy 54.554138 -110.082842) (xy 54.554628 -110.11281)
			(xy 54.554628 -110.97641) (xy 54.554603 -110.977934) (xy 153.409904 -110.977934) (xy 153.409904 -110.114334)
			(xy 153.410394 -110.08435) (xy 153.418222 -110.024894) (xy 153.433743 -109.966969) (xy 153.456692 -109.911565)
			(xy 153.486676 -109.859631) (xy 153.523182 -109.812055) (xy 153.565587 -109.76965) (xy 153.613163 -109.733144)
			(xy 153.665097 -109.70316) (xy 153.720501 -109.680211) (xy 153.778426 -109.66469) (xy 153.837882 -109.656862)
			(xy 153.89785 -109.656862) (xy 153.957306 -109.66469) (xy 154.015231 -109.680211) (xy 154.070635 -109.70316)
			(xy 154.122569 -109.733144) (xy 154.170145 -109.76965) (xy 154.21255 -109.812055) (xy 154.249056 -109.859631)
			(xy 154.27904 -109.911565) (xy 154.301989 -109.966969) (xy 154.31751 -110.024894) (xy 154.325338 -110.08435)
			(xy 154.325828 -110.114334) (xy 154.325828 -110.97641) (xy 169.739056 -110.97641) (xy 169.739056 -110.11281)
			(xy 169.739546 -110.082826) (xy 169.747374 -110.02337) (xy 169.762895 -109.965445) (xy 169.785844 -109.910041)
			(xy 169.815828 -109.858107) (xy 169.852334 -109.810531) (xy 169.894739 -109.768126) (xy 169.942315 -109.73162)
			(xy 169.994249 -109.701636) (xy 170.049653 -109.678687) (xy 170.107578 -109.663166) (xy 170.167034 -109.655338)
			(xy 170.227002 -109.655338) (xy 170.286458 -109.663166) (xy 170.344383 -109.678687) (xy 170.399787 -109.701636)
			(xy 170.451721 -109.73162) (xy 170.499297 -109.768126) (xy 170.541702 -109.810531) (xy 170.578208 -109.858107)
			(xy 170.608192 -109.910041) (xy 170.631141 -109.965445) (xy 170.646662 -110.02337) (xy 170.65449 -110.082826)
			(xy 170.65498 -110.11281) (xy 170.65498 -110.97641) (xy 170.654955 -110.977934) (xy 269.509748 -110.977934)
			(xy 269.509748 -110.114334) (xy 269.510238 -110.08435) (xy 269.518066 -110.024894) (xy 269.533587 -109.966969)
			(xy 269.556536 -109.911565) (xy 269.58652 -109.859631) (xy 269.623026 -109.812055) (xy 269.665431 -109.76965)
			(xy 269.713007 -109.733144) (xy 269.764941 -109.70316) (xy 269.820345 -109.680211) (xy 269.87827 -109.66469)
			(xy 269.937726 -109.656862) (xy 269.997694 -109.656862) (xy 270.05715 -109.66469) (xy 270.115075 -109.680211)
			(xy 270.170479 -109.70316) (xy 270.222413 -109.733144) (xy 270.269989 -109.76965) (xy 270.312394 -109.812055)
			(xy 270.3489 -109.859631) (xy 270.378884 -109.911565) (xy 270.401833 -109.966969) (xy 270.417354 -110.024894)
			(xy 270.425182 -110.08435) (xy 270.425672 -110.114334) (xy 270.425672 -110.97641) (xy 285.8389 -110.97641)
			(xy 285.8389 -110.11281) (xy 285.83939 -110.082826) (xy 285.847218 -110.02337) (xy 285.862739 -109.965445)
			(xy 285.885688 -109.910041) (xy 285.915672 -109.858107) (xy 285.952178 -109.810531) (xy 285.994583 -109.768126)
			(xy 286.042159 -109.73162) (xy 286.094093 -109.701636) (xy 286.149497 -109.678687) (xy 286.207422 -109.663166)
			(xy 286.266878 -109.655338) (xy 286.326846 -109.655338) (xy 286.386302 -109.663166) (xy 286.444227 -109.678687)
			(xy 286.499631 -109.701636) (xy 286.551565 -109.73162) (xy 286.599141 -109.768126) (xy 286.641546 -109.810531)
			(xy 286.678052 -109.858107) (xy 286.708036 -109.910041) (xy 286.730985 -109.965445) (xy 286.746506 -110.02337)
			(xy 286.754334 -110.082826) (xy 286.754824 -110.11281) (xy 286.754824 -110.97641) (xy 286.754799 -110.977934)
			(xy 385.6101 -110.977934) (xy 385.6101 -110.114334) (xy 385.61059 -110.084366) (xy 385.618413 -110.024944)
			(xy 385.633926 -109.967051) (xy 385.656862 -109.911678) (xy 385.686829 -109.859772) (xy 385.723316 -109.812222)
			(xy 385.765696 -109.769842) (xy 385.813246 -109.733355) (xy 385.865152 -109.703388) (xy 385.920525 -109.680452)
			(xy 385.978418 -109.664939) (xy 386.03784 -109.657116) (xy 386.097776 -109.657116) (xy 386.157198 -109.664939)
			(xy 386.215091 -109.680452) (xy 386.270464 -109.703388) (xy 386.32237 -109.733355) (xy 386.36992 -109.769842)
			(xy 386.4123 -109.812222) (xy 386.448787 -109.859772) (xy 386.478754 -109.911678) (xy 386.50169 -109.967051)
			(xy 386.517203 -110.024944) (xy 386.525026 -110.084366) (xy 386.525516 -110.114334) (xy 386.525516 -110.97641)
			(xy 401.939252 -110.97641) (xy 401.939252 -110.11281) (xy 401.939742 -110.082842) (xy 401.947565 -110.02342)
			(xy 401.963078 -109.965527) (xy 401.986014 -109.910154) (xy 402.015981 -109.858248) (xy 402.052468 -109.810698)
			(xy 402.094848 -109.768318) (xy 402.142398 -109.731831) (xy 402.194304 -109.701864) (xy 402.249677 -109.678928)
			(xy 402.30757 -109.663415) (xy 402.366992 -109.655592) (xy 402.426928 -109.655592) (xy 402.48635 -109.663415)
			(xy 402.544243 -109.678928) (xy 402.599616 -109.701864) (xy 402.651522 -109.731831) (xy 402.699072 -109.768318)
			(xy 402.741452 -109.810698) (xy 402.777939 -109.858248) (xy 402.807906 -109.910154) (xy 402.830842 -109.965527)
			(xy 402.846355 -110.02342) (xy 402.854178 -110.082842) (xy 402.854668 -110.11281) (xy 402.854668 -110.97641)
			(xy 402.854178 -111.006378) (xy 402.846355 -111.0658) (xy 402.830842 -111.123693) (xy 402.807906 -111.179066)
			(xy 402.777939 -111.230972) (xy 402.741452 -111.278522) (xy 402.699072 -111.320902) (xy 402.651522 -111.357389)
			(xy 402.599616 -111.387356) (xy 402.544243 -111.410292) (xy 402.48635 -111.425805) (xy 402.426928 -111.433628)
			(xy 402.366992 -111.433628) (xy 402.30757 -111.425805) (xy 402.249677 -111.410292) (xy 402.194304 -111.387356)
			(xy 402.142398 -111.357389) (xy 402.094848 -111.320902) (xy 402.052468 -111.278522) (xy 402.015981 -111.230972)
			(xy 401.986014 -111.179066) (xy 401.963078 -111.123693) (xy 401.947565 -111.0658) (xy 401.939742 -111.006378)
			(xy 401.939252 -110.97641) (xy 386.525516 -110.97641) (xy 386.525516 -110.977934) (xy 386.525026 -111.007902)
			(xy 386.517203 -111.067324) (xy 386.50169 -111.125217) (xy 386.478754 -111.18059) (xy 386.448787 -111.232496)
			(xy 386.4123 -111.280046) (xy 386.36992 -111.322426) (xy 386.32237 -111.358913) (xy 386.270464 -111.38888)
			(xy 386.215091 -111.411816) (xy 386.157198 -111.427329) (xy 386.097776 -111.435152) (xy 386.03784 -111.435152)
			(xy 385.978418 -111.427329) (xy 385.920525 -111.411816) (xy 385.865152 -111.38888) (xy 385.813246 -111.358913)
			(xy 385.765696 -111.322426) (xy 385.723316 -111.280046) (xy 385.686829 -111.232496) (xy 385.656862 -111.18059)
			(xy 385.633926 -111.125217) (xy 385.618413 -111.067324) (xy 385.61059 -111.007902) (xy 385.6101 -110.977934)
			(xy 286.754799 -110.977934) (xy 286.754334 -111.006394) (xy 286.746506 -111.06585) (xy 286.730985 -111.123775)
			(xy 286.708036 -111.179179) (xy 286.678052 -111.231113) (xy 286.641546 -111.278689) (xy 286.599141 -111.321094)
			(xy 286.551565 -111.3576) (xy 286.499631 -111.387584) (xy 286.444227 -111.410533) (xy 286.386302 -111.426054)
			(xy 286.326846 -111.433882) (xy 286.266878 -111.433882) (xy 286.207422 -111.426054) (xy 286.149497 -111.410533)
			(xy 286.094093 -111.387584) (xy 286.042159 -111.3576) (xy 285.994583 -111.321094) (xy 285.952178 -111.278689)
			(xy 285.915672 -111.231113) (xy 285.885688 -111.179179) (xy 285.862739 -111.123775) (xy 285.847218 -111.06585)
			(xy 285.83939 -111.006394) (xy 285.8389 -110.97641) (xy 270.425672 -110.97641) (xy 270.425672 -110.977934)
			(xy 270.425182 -111.007918) (xy 270.417354 -111.067374) (xy 270.401833 -111.125299) (xy 270.378884 -111.180703)
			(xy 270.3489 -111.232637) (xy 270.312394 -111.280213) (xy 270.269989 -111.322618) (xy 270.222413 -111.359124)
			(xy 270.170479 -111.389108) (xy 270.115075 -111.412057) (xy 270.05715 -111.427578) (xy 269.997694 -111.435406)
			(xy 269.937726 -111.435406) (xy 269.87827 -111.427578) (xy 269.820345 -111.412057) (xy 269.764941 -111.389108)
			(xy 269.713007 -111.359124) (xy 269.665431 -111.322618) (xy 269.623026 -111.280213) (xy 269.58652 -111.232637)
			(xy 269.556536 -111.180703) (xy 269.533587 -111.125299) (xy 269.518066 -111.067374) (xy 269.510238 -111.007918)
			(xy 269.509748 -110.977934) (xy 170.654955 -110.977934) (xy 170.65449 -111.006394) (xy 170.646662 -111.06585)
			(xy 170.631141 -111.123775) (xy 170.608192 -111.179179) (xy 170.578208 -111.231113) (xy 170.541702 -111.278689)
			(xy 170.499297 -111.321094) (xy 170.451721 -111.3576) (xy 170.399787 -111.387584) (xy 170.344383 -111.410533)
			(xy 170.286458 -111.426054) (xy 170.227002 -111.433882) (xy 170.167034 -111.433882) (xy 170.107578 -111.426054)
			(xy 170.049653 -111.410533) (xy 169.994249 -111.387584) (xy 169.942315 -111.3576) (xy 169.894739 -111.321094)
			(xy 169.852334 -111.278689) (xy 169.815828 -111.231113) (xy 169.785844 -111.179179) (xy 169.762895 -111.123775)
			(xy 169.747374 -111.06585) (xy 169.739546 -111.006394) (xy 169.739056 -110.97641) (xy 154.325828 -110.97641)
			(xy 154.325828 -110.977934) (xy 154.325338 -111.007918) (xy 154.31751 -111.067374) (xy 154.301989 -111.125299)
			(xy 154.27904 -111.180703) (xy 154.249056 -111.232637) (xy 154.21255 -111.280213) (xy 154.170145 -111.322618)
			(xy 154.122569 -111.359124) (xy 154.070635 -111.389108) (xy 154.015231 -111.412057) (xy 153.957306 -111.427578)
			(xy 153.89785 -111.435406) (xy 153.837882 -111.435406) (xy 153.778426 -111.427578) (xy 153.720501 -111.412057)
			(xy 153.665097 -111.389108) (xy 153.613163 -111.359124) (xy 153.565587 -111.322618) (xy 153.523182 -111.280213)
			(xy 153.486676 -111.232637) (xy 153.456692 -111.180703) (xy 153.433743 -111.125299) (xy 153.418222 -111.067374)
			(xy 153.410394 -111.007918) (xy 153.409904 -110.977934) (xy 54.554603 -110.977934) (xy 54.554138 -111.006378)
			(xy 54.546315 -111.0658) (xy 54.530802 -111.123693) (xy 54.507866 -111.179066) (xy 54.477899 -111.230972)
			(xy 54.441412 -111.278522) (xy 54.399032 -111.320902) (xy 54.351482 -111.357389) (xy 54.299576 -111.387356)
			(xy 54.244203 -111.410292) (xy 54.18631 -111.425805) (xy 54.126888 -111.433628) (xy 54.066952 -111.433628)
			(xy 54.00753 -111.425805) (xy 53.949637 -111.410292) (xy 53.894264 -111.387356) (xy 53.842358 -111.357389)
			(xy 53.794808 -111.320902) (xy 53.752428 -111.278522) (xy 53.715941 -111.230972) (xy 53.685974 -111.179066)
			(xy 53.663038 -111.123693) (xy 53.647525 -111.0658) (xy 53.639702 -111.006378) (xy 53.639212 -110.97641)
			(xy 38.225476 -110.97641) (xy 38.225476 -110.977934) (xy 38.224986 -111.007902) (xy 38.217163 -111.067324)
			(xy 38.20165 -111.125217) (xy 38.178714 -111.18059) (xy 38.148747 -111.232496) (xy 38.11226 -111.280046)
			(xy 38.06988 -111.322426) (xy 38.02233 -111.358913) (xy 37.970424 -111.38888) (xy 37.915051 -111.411816)
			(xy 37.857158 -111.427329) (xy 37.797736 -111.435152) (xy 37.7378 -111.435152) (xy 37.678378 -111.427329)
			(xy 37.620485 -111.411816) (xy 37.565112 -111.38888) (xy 37.513206 -111.358913) (xy 37.465656 -111.322426)
			(xy 37.423276 -111.280046) (xy 37.386789 -111.232496) (xy 37.356822 -111.18059) (xy 37.333886 -111.125217)
			(xy 37.318373 -111.067324) (xy 37.31055 -111.007902) (xy 37.31006 -110.977934) (xy 4.308094 -110.977934)
			(xy 4.308094 -112.784382) (xy 34.667952 -112.784382) (xy 34.667952 -111.920782) (xy 34.668442 -111.890814)
			(xy 34.676265 -111.831392) (xy 34.691778 -111.773499) (xy 34.714714 -111.718126) (xy 34.744681 -111.66622)
			(xy 34.781168 -111.61867) (xy 34.823548 -111.57629) (xy 34.871098 -111.539803) (xy 34.923004 -111.509836)
			(xy 34.978377 -111.4869) (xy 35.03627 -111.471387) (xy 35.095692 -111.463564) (xy 35.155628 -111.463564)
			(xy 35.21505 -111.471387) (xy 35.272943 -111.4869) (xy 35.328316 -111.509836) (xy 35.380222 -111.539803)
			(xy 35.427772 -111.57629) (xy 35.470152 -111.61867) (xy 35.506639 -111.66622) (xy 35.536606 -111.718126)
			(xy 35.559542 -111.773499) (xy 35.575055 -111.831392) (xy 35.582878 -111.890814) (xy 35.583368 -111.920782)
			(xy 35.583368 -112.776508) (xy 51.785012 -112.776508) (xy 51.785012 -111.912908) (xy 51.785502 -111.88294)
			(xy 51.793325 -111.823518) (xy 51.808838 -111.765625) (xy 51.831774 -111.710252) (xy 51.861741 -111.658346)
			(xy 51.898228 -111.610796) (xy 51.940608 -111.568416) (xy 51.988158 -111.531929) (xy 52.040064 -111.501962)
			(xy 52.095437 -111.479026) (xy 52.15333 -111.463513) (xy 52.212752 -111.45569) (xy 52.272688 -111.45569)
			(xy 52.33211 -111.463513) (xy 52.390003 -111.479026) (xy 52.445376 -111.501962) (xy 52.497282 -111.531929)
			(xy 52.544832 -111.568416) (xy 52.587212 -111.610796) (xy 52.623699 -111.658346) (xy 52.653666 -111.710252)
			(xy 52.676602 -111.765625) (xy 52.692115 -111.823518) (xy 52.699938 -111.88294) (xy 52.700428 -111.912908)
			(xy 52.700428 -112.776508) (xy 52.700299 -112.784382) (xy 150.767796 -112.784382) (xy 150.767796 -111.920782)
			(xy 150.768286 -111.890798) (xy 150.776114 -111.831342) (xy 150.791635 -111.773417) (xy 150.814584 -111.718013)
			(xy 150.844568 -111.666079) (xy 150.881074 -111.618503) (xy 150.923479 -111.576098) (xy 150.971055 -111.539592)
			(xy 151.022989 -111.509608) (xy 151.078393 -111.486659) (xy 151.136318 -111.471138) (xy 151.195774 -111.46331)
			(xy 151.255742 -111.46331) (xy 151.315198 -111.471138) (xy 151.373123 -111.486659) (xy 151.428527 -111.509608)
			(xy 151.480461 -111.539592) (xy 151.528037 -111.576098) (xy 151.570442 -111.618503) (xy 151.606948 -111.666079)
			(xy 151.636932 -111.718013) (xy 151.659881 -111.773417) (xy 151.675402 -111.831342) (xy 151.68323 -111.890798)
			(xy 151.68372 -111.920782) (xy 151.68372 -112.776508) (xy 167.884856 -112.776508) (xy 167.884856 -111.912908)
			(xy 167.885346 -111.882924) (xy 167.893174 -111.823468) (xy 167.908695 -111.765543) (xy 167.931644 -111.710139)
			(xy 167.961628 -111.658205) (xy 167.998134 -111.610629) (xy 168.040539 -111.568224) (xy 168.088115 -111.531718)
			(xy 168.140049 -111.501734) (xy 168.195453 -111.478785) (xy 168.253378 -111.463264) (xy 168.312834 -111.455436)
			(xy 168.372802 -111.455436) (xy 168.432258 -111.463264) (xy 168.490183 -111.478785) (xy 168.545587 -111.501734)
			(xy 168.597521 -111.531718) (xy 168.645097 -111.568224) (xy 168.687502 -111.610629) (xy 168.724008 -111.658205)
			(xy 168.753992 -111.710139) (xy 168.776941 -111.765543) (xy 168.792462 -111.823468) (xy 168.80029 -111.882924)
			(xy 168.80078 -111.912908) (xy 168.80078 -112.776508) (xy 168.800651 -112.784382) (xy 266.86764 -112.784382)
			(xy 266.86764 -111.920782) (xy 266.86813 -111.890798) (xy 266.875958 -111.831342) (xy 266.891479 -111.773417)
			(xy 266.914428 -111.718013) (xy 266.944412 -111.666079) (xy 266.980918 -111.618503) (xy 267.023323 -111.576098)
			(xy 267.070899 -111.539592) (xy 267.122833 -111.509608) (xy 267.178237 -111.486659) (xy 267.236162 -111.471138)
			(xy 267.295618 -111.46331) (xy 267.355586 -111.46331) (xy 267.415042 -111.471138) (xy 267.472967 -111.486659)
			(xy 267.528371 -111.509608) (xy 267.580305 -111.539592) (xy 267.627881 -111.576098) (xy 267.670286 -111.618503)
			(xy 267.706792 -111.666079) (xy 267.736776 -111.718013) (xy 267.759725 -111.773417) (xy 267.775246 -111.831342)
			(xy 267.783074 -111.890798) (xy 267.783564 -111.920782) (xy 267.783564 -112.776508) (xy 283.9847 -112.776508)
			(xy 283.9847 -111.912908) (xy 283.98519 -111.882924) (xy 283.993018 -111.823468) (xy 284.008539 -111.765543)
			(xy 284.031488 -111.710139) (xy 284.061472 -111.658205) (xy 284.097978 -111.610629) (xy 284.140383 -111.568224)
			(xy 284.187959 -111.531718) (xy 284.239893 -111.501734) (xy 284.295297 -111.478785) (xy 284.353222 -111.463264)
			(xy 284.412678 -111.455436) (xy 284.472646 -111.455436) (xy 284.532102 -111.463264) (xy 284.590027 -111.478785)
			(xy 284.645431 -111.501734) (xy 284.697365 -111.531718) (xy 284.744941 -111.568224) (xy 284.787346 -111.610629)
			(xy 284.823852 -111.658205) (xy 284.853836 -111.710139) (xy 284.876785 -111.765543) (xy 284.892306 -111.823468)
			(xy 284.900134 -111.882924) (xy 284.900624 -111.912908) (xy 284.900624 -112.776508) (xy 284.900495 -112.784382)
			(xy 382.967992 -112.784382) (xy 382.967992 -111.920782) (xy 382.968482 -111.890814) (xy 382.976305 -111.831392)
			(xy 382.991818 -111.773499) (xy 383.014754 -111.718126) (xy 383.044721 -111.66622) (xy 383.081208 -111.61867)
			(xy 383.123588 -111.57629) (xy 383.171138 -111.539803) (xy 383.223044 -111.509836) (xy 383.278417 -111.4869)
			(xy 383.33631 -111.471387) (xy 383.395732 -111.463564) (xy 383.455668 -111.463564) (xy 383.51509 -111.471387)
			(xy 383.572983 -111.4869) (xy 383.628356 -111.509836) (xy 383.680262 -111.539803) (xy 383.727812 -111.57629)
			(xy 383.770192 -111.61867) (xy 383.806679 -111.66622) (xy 383.836646 -111.718126) (xy 383.859582 -111.773499)
			(xy 383.875095 -111.831392) (xy 383.882918 -111.890814) (xy 383.883408 -111.920782) (xy 383.883408 -112.776508)
			(xy 400.085052 -112.776508) (xy 400.085052 -111.912908) (xy 400.085542 -111.88294) (xy 400.093365 -111.823518)
			(xy 400.108878 -111.765625) (xy 400.131814 -111.710252) (xy 400.161781 -111.658346) (xy 400.198268 -111.610796)
			(xy 400.240648 -111.568416) (xy 400.288198 -111.531929) (xy 400.340104 -111.501962) (xy 400.395477 -111.479026)
			(xy 400.45337 -111.463513) (xy 400.512792 -111.45569) (xy 400.572728 -111.45569) (xy 400.63215 -111.463513)
			(xy 400.690043 -111.479026) (xy 400.745416 -111.501962) (xy 400.797322 -111.531929) (xy 400.844872 -111.568416)
			(xy 400.887252 -111.610796) (xy 400.923739 -111.658346) (xy 400.953706 -111.710252) (xy 400.976642 -111.765625)
			(xy 400.992155 -111.823518) (xy 400.999978 -111.88294) (xy 401.000468 -111.912908) (xy 401.000468 -112.776508)
			(xy 400.999978 -112.806476) (xy 400.992155 -112.865898) (xy 400.976642 -112.923791) (xy 400.953706 -112.979164)
			(xy 400.923739 -113.03107) (xy 400.887252 -113.07862) (xy 400.844872 -113.121) (xy 400.797322 -113.157487)
			(xy 400.745416 -113.187454) (xy 400.690043 -113.21039) (xy 400.63215 -113.225903) (xy 400.572728 -113.233726)
			(xy 400.512792 -113.233726) (xy 400.45337 -113.225903) (xy 400.395477 -113.21039) (xy 400.340104 -113.187454)
			(xy 400.288198 -113.157487) (xy 400.240648 -113.121) (xy 400.198268 -113.07862) (xy 400.161781 -113.03107)
			(xy 400.131814 -112.979164) (xy 400.108878 -112.923791) (xy 400.093365 -112.865898) (xy 400.085542 -112.806476)
			(xy 400.085052 -112.776508) (xy 383.883408 -112.776508) (xy 383.883408 -112.784382) (xy 383.882918 -112.81435)
			(xy 383.875095 -112.873772) (xy 383.859582 -112.931665) (xy 383.836646 -112.987038) (xy 383.806679 -113.038944)
			(xy 383.770192 -113.086494) (xy 383.727812 -113.128874) (xy 383.680262 -113.165361) (xy 383.628356 -113.195328)
			(xy 383.572983 -113.218264) (xy 383.51509 -113.233777) (xy 383.455668 -113.2416) (xy 383.395732 -113.2416)
			(xy 383.33631 -113.233777) (xy 383.278417 -113.218264) (xy 383.223044 -113.195328) (xy 383.171138 -113.165361)
			(xy 383.123588 -113.128874) (xy 383.081208 -113.086494) (xy 383.044721 -113.038944) (xy 383.014754 -112.987038)
			(xy 382.991818 -112.931665) (xy 382.976305 -112.873772) (xy 382.968482 -112.81435) (xy 382.967992 -112.784382)
			(xy 284.900495 -112.784382) (xy 284.900134 -112.806492) (xy 284.892306 -112.865948) (xy 284.876785 -112.923873)
			(xy 284.853836 -112.979277) (xy 284.823852 -113.031211) (xy 284.787346 -113.078787) (xy 284.744941 -113.121192)
			(xy 284.697365 -113.157698) (xy 284.645431 -113.187682) (xy 284.590027 -113.210631) (xy 284.532102 -113.226152)
			(xy 284.472646 -113.23398) (xy 284.412678 -113.23398) (xy 284.353222 -113.226152) (xy 284.295297 -113.210631)
			(xy 284.239893 -113.187682) (xy 284.187959 -113.157698) (xy 284.140383 -113.121192) (xy 284.097978 -113.078787)
			(xy 284.061472 -113.031211) (xy 284.031488 -112.979277) (xy 284.008539 -112.923873) (xy 283.993018 -112.865948)
			(xy 283.98519 -112.806492) (xy 283.9847 -112.776508) (xy 267.783564 -112.776508) (xy 267.783564 -112.784382)
			(xy 267.783074 -112.814366) (xy 267.775246 -112.873822) (xy 267.759725 -112.931747) (xy 267.736776 -112.987151)
			(xy 267.706792 -113.039085) (xy 267.670286 -113.086661) (xy 267.627881 -113.129066) (xy 267.580305 -113.165572)
			(xy 267.528371 -113.195556) (xy 267.472967 -113.218505) (xy 267.415042 -113.234026) (xy 267.355586 -113.241854)
			(xy 267.295618 -113.241854) (xy 267.236162 -113.234026) (xy 267.178237 -113.218505) (xy 267.122833 -113.195556)
			(xy 267.070899 -113.165572) (xy 267.023323 -113.129066) (xy 266.980918 -113.086661) (xy 266.944412 -113.039085)
			(xy 266.914428 -112.987151) (xy 266.891479 -112.931747) (xy 266.875958 -112.873822) (xy 266.86813 -112.814366)
			(xy 266.86764 -112.784382) (xy 168.800651 -112.784382) (xy 168.80029 -112.806492) (xy 168.792462 -112.865948)
			(xy 168.776941 -112.923873) (xy 168.753992 -112.979277) (xy 168.724008 -113.031211) (xy 168.687502 -113.078787)
			(xy 168.645097 -113.121192) (xy 168.597521 -113.157698) (xy 168.545587 -113.187682) (xy 168.490183 -113.210631)
			(xy 168.432258 -113.226152) (xy 168.372802 -113.23398) (xy 168.312834 -113.23398) (xy 168.253378 -113.226152)
			(xy 168.195453 -113.210631) (xy 168.140049 -113.187682) (xy 168.088115 -113.157698) (xy 168.040539 -113.121192)
			(xy 167.998134 -113.078787) (xy 167.961628 -113.031211) (xy 167.931644 -112.979277) (xy 167.908695 -112.923873)
			(xy 167.893174 -112.865948) (xy 167.885346 -112.806492) (xy 167.884856 -112.776508) (xy 151.68372 -112.776508)
			(xy 151.68372 -112.784382) (xy 151.68323 -112.814366) (xy 151.675402 -112.873822) (xy 151.659881 -112.931747)
			(xy 151.636932 -112.987151) (xy 151.606948 -113.039085) (xy 151.570442 -113.086661) (xy 151.528037 -113.129066)
			(xy 151.480461 -113.165572) (xy 151.428527 -113.195556) (xy 151.373123 -113.218505) (xy 151.315198 -113.234026)
			(xy 151.255742 -113.241854) (xy 151.195774 -113.241854) (xy 151.136318 -113.234026) (xy 151.078393 -113.218505)
			(xy 151.022989 -113.195556) (xy 150.971055 -113.165572) (xy 150.923479 -113.129066) (xy 150.881074 -113.086661)
			(xy 150.844568 -113.039085) (xy 150.814584 -112.987151) (xy 150.791635 -112.931747) (xy 150.776114 -112.873822)
			(xy 150.768286 -112.814366) (xy 150.767796 -112.784382) (xy 52.700299 -112.784382) (xy 52.699938 -112.806476)
			(xy 52.692115 -112.865898) (xy 52.676602 -112.923791) (xy 52.653666 -112.979164) (xy 52.623699 -113.03107)
			(xy 52.587212 -113.07862) (xy 52.544832 -113.121) (xy 52.497282 -113.157487) (xy 52.445376 -113.187454)
			(xy 52.390003 -113.21039) (xy 52.33211 -113.225903) (xy 52.272688 -113.233726) (xy 52.212752 -113.233726)
			(xy 52.15333 -113.225903) (xy 52.095437 -113.21039) (xy 52.040064 -113.187454) (xy 51.988158 -113.157487)
			(xy 51.940608 -113.121) (xy 51.898228 -113.07862) (xy 51.861741 -113.03107) (xy 51.831774 -112.979164)
			(xy 51.808838 -112.923791) (xy 51.793325 -112.865898) (xy 51.785502 -112.806476) (xy 51.785012 -112.776508)
			(xy 35.583368 -112.776508) (xy 35.583368 -112.784382) (xy 35.582878 -112.81435) (xy 35.575055 -112.873772)
			(xy 35.559542 -112.931665) (xy 35.536606 -112.987038) (xy 35.506639 -113.038944) (xy 35.470152 -113.086494)
			(xy 35.427772 -113.128874) (xy 35.380222 -113.165361) (xy 35.328316 -113.195328) (xy 35.272943 -113.218264)
			(xy 35.21505 -113.233777) (xy 35.155628 -113.2416) (xy 35.095692 -113.2416) (xy 35.03627 -113.233777)
			(xy 34.978377 -113.218264) (xy 34.923004 -113.195328) (xy 34.871098 -113.165361) (xy 34.823548 -113.128874)
			(xy 34.781168 -113.086494) (xy 34.744681 -113.038944) (xy 34.714714 -112.987038) (xy 34.691778 -112.931665)
			(xy 34.676265 -112.873772) (xy 34.668442 -112.81435) (xy 34.667952 -112.784382) (xy 4.308094 -112.784382)
			(xy 4.308094 -117.758718) (xy 74.474832 -117.758718) (xy 74.474832 -116.895118) (xy 74.475322 -116.865134)
			(xy 74.48315 -116.805678) (xy 74.498671 -116.747753) (xy 74.52162 -116.692349) (xy 74.551604 -116.640415)
			(xy 74.58811 -116.592839) (xy 74.630515 -116.550434) (xy 74.678091 -116.513928) (xy 74.730025 -116.483944)
			(xy 74.785429 -116.460995) (xy 74.843354 -116.445474) (xy 74.90281 -116.437646) (xy 74.962778 -116.437646)
			(xy 75.022234 -116.445474) (xy 75.080159 -116.460995) (xy 75.135563 -116.483944) (xy 75.187497 -116.513928)
			(xy 75.235073 -116.550434) (xy 75.277478 -116.592839) (xy 75.313984 -116.640415) (xy 75.343968 -116.692349)
			(xy 75.366917 -116.747753) (xy 75.382438 -116.805678) (xy 75.390266 -116.865134) (xy 75.390756 -116.895118)
			(xy 75.390756 -117.758718) (xy 190.574676 -117.758718) (xy 190.574676 -116.895118) (xy 190.575166 -116.865134)
			(xy 190.582994 -116.805678) (xy 190.598515 -116.747753) (xy 190.621464 -116.692349) (xy 190.651448 -116.640415)
			(xy 190.687954 -116.592839) (xy 190.730359 -116.550434) (xy 190.777935 -116.513928) (xy 190.829869 -116.483944)
			(xy 190.885273 -116.460995) (xy 190.943198 -116.445474) (xy 191.002654 -116.437646) (xy 191.062622 -116.437646)
			(xy 191.122078 -116.445474) (xy 191.180003 -116.460995) (xy 191.235407 -116.483944) (xy 191.287341 -116.513928)
			(xy 191.334917 -116.550434) (xy 191.377322 -116.592839) (xy 191.413828 -116.640415) (xy 191.443812 -116.692349)
			(xy 191.466761 -116.747753) (xy 191.482282 -116.805678) (xy 191.49011 -116.865134) (xy 191.4906 -116.895118)
			(xy 191.4906 -117.758718) (xy 306.675028 -117.758718) (xy 306.675028 -116.895118) (xy 306.675518 -116.86515)
			(xy 306.683341 -116.805728) (xy 306.698854 -116.747835) (xy 306.72179 -116.692462) (xy 306.751757 -116.640556)
			(xy 306.788244 -116.593006) (xy 306.830624 -116.550626) (xy 306.878174 -116.514139) (xy 306.93008 -116.484172)
			(xy 306.985453 -116.461236) (xy 307.043346 -116.445723) (xy 307.102768 -116.4379) (xy 307.162704 -116.4379)
			(xy 307.222126 -116.445723) (xy 307.280019 -116.461236) (xy 307.335392 -116.484172) (xy 307.387298 -116.514139)
			(xy 307.434848 -116.550626) (xy 307.477228 -116.593006) (xy 307.513715 -116.640556) (xy 307.543682 -116.692462)
			(xy 307.566618 -116.747835) (xy 307.582131 -116.805728) (xy 307.589954 -116.86515) (xy 307.590444 -116.895118)
			(xy 307.590444 -117.758718) (xy 307.590436 -117.759226) (xy 422.774872 -117.759226) (xy 422.774872 -116.895626)
			(xy 422.775362 -116.865642) (xy 422.78319 -116.806186) (xy 422.798711 -116.748261) (xy 422.82166 -116.692857)
			(xy 422.851644 -116.640923) (xy 422.88815 -116.593347) (xy 422.930555 -116.550942) (xy 422.978131 -116.514436)
			(xy 423.030065 -116.484452) (xy 423.085469 -116.461503) (xy 423.143394 -116.445982) (xy 423.20285 -116.438154)
			(xy 423.262818 -116.438154) (xy 423.322274 -116.445982) (xy 423.380199 -116.461503) (xy 423.435603 -116.484452)
			(xy 423.487537 -116.514436) (xy 423.535113 -116.550942) (xy 423.577518 -116.593347) (xy 423.614024 -116.640923)
			(xy 423.644008 -116.692857) (xy 423.666957 -116.748261) (xy 423.682478 -116.806186) (xy 423.690306 -116.865642)
			(xy 423.690796 -116.895626) (xy 423.690796 -117.759226) (xy 423.690306 -117.78921) (xy 423.682478 -117.848666)
			(xy 423.666957 -117.906591) (xy 423.644008 -117.961995) (xy 423.614024 -118.013929) (xy 423.577518 -118.061505)
			(xy 423.535113 -118.10391) (xy 423.487537 -118.140416) (xy 423.435603 -118.1704) (xy 423.380199 -118.193349)
			(xy 423.322274 -118.20887) (xy 423.262818 -118.216698) (xy 423.20285 -118.216698) (xy 423.143394 -118.20887)
			(xy 423.085469 -118.193349) (xy 423.030065 -118.1704) (xy 422.978131 -118.140416) (xy 422.930555 -118.10391)
			(xy 422.88815 -118.061505) (xy 422.851644 -118.013929) (xy 422.82166 -117.961995) (xy 422.798711 -117.906591)
			(xy 422.78319 -117.848666) (xy 422.775362 -117.78921) (xy 422.774872 -117.759226) (xy 307.590436 -117.759226)
			(xy 307.589954 -117.788686) (xy 307.582131 -117.848108) (xy 307.566618 -117.906001) (xy 307.543682 -117.961374)
			(xy 307.513715 -118.01328) (xy 307.477228 -118.06083) (xy 307.434848 -118.10321) (xy 307.387298 -118.139697)
			(xy 307.335392 -118.169664) (xy 307.280019 -118.1926) (xy 307.222126 -118.208113) (xy 307.162704 -118.215936)
			(xy 307.102768 -118.215936) (xy 307.043346 -118.208113) (xy 306.985453 -118.1926) (xy 306.93008 -118.169664)
			(xy 306.878174 -118.139697) (xy 306.830624 -118.10321) (xy 306.788244 -118.06083) (xy 306.751757 -118.01328)
			(xy 306.72179 -117.961374) (xy 306.698854 -117.906001) (xy 306.683341 -117.848108) (xy 306.675518 -117.788686)
			(xy 306.675028 -117.758718) (xy 191.4906 -117.758718) (xy 191.49011 -117.788702) (xy 191.482282 -117.848158)
			(xy 191.466761 -117.906083) (xy 191.443812 -117.961487) (xy 191.413828 -118.013421) (xy 191.377322 -118.060997)
			(xy 191.334917 -118.103402) (xy 191.287341 -118.139908) (xy 191.235407 -118.169892) (xy 191.180003 -118.192841)
			(xy 191.122078 -118.208362) (xy 191.062622 -118.21619) (xy 191.002654 -118.21619) (xy 190.943198 -118.208362)
			(xy 190.885273 -118.192841) (xy 190.829869 -118.169892) (xy 190.777935 -118.139908) (xy 190.730359 -118.103402)
			(xy 190.687954 -118.060997) (xy 190.651448 -118.013421) (xy 190.621464 -117.961487) (xy 190.598515 -117.906083)
			(xy 190.582994 -117.848158) (xy 190.575166 -117.788702) (xy 190.574676 -117.758718) (xy 75.390756 -117.758718)
			(xy 75.390266 -117.788702) (xy 75.382438 -117.848158) (xy 75.366917 -117.906083) (xy 75.343968 -117.961487)
			(xy 75.313984 -118.013421) (xy 75.277478 -118.060997) (xy 75.235073 -118.103402) (xy 75.187497 -118.139908)
			(xy 75.135563 -118.169892) (xy 75.080159 -118.192841) (xy 75.022234 -118.208362) (xy 74.962778 -118.21619)
			(xy 74.90281 -118.21619) (xy 74.843354 -118.208362) (xy 74.785429 -118.192841) (xy 74.730025 -118.169892)
			(xy 74.678091 -118.139908) (xy 74.630515 -118.103402) (xy 74.58811 -118.060997) (xy 74.551604 -118.013421)
			(xy 74.52162 -117.961487) (xy 74.498671 -117.906083) (xy 74.48315 -117.848158) (xy 74.475322 -117.788702)
			(xy 74.474832 -117.758718) (xy 4.308094 -117.758718) (xy 4.308094 -120.087898) (xy 34.667952 -120.087898)
			(xy 34.667952 -119.224298) (xy 34.668442 -119.19433) (xy 34.676265 -119.134908) (xy 34.691778 -119.077015)
			(xy 34.714714 -119.021642) (xy 34.744681 -118.969736) (xy 34.781168 -118.922186) (xy 34.823548 -118.879806)
			(xy 34.871098 -118.843319) (xy 34.923004 -118.813352) (xy 34.978377 -118.790416) (xy 35.03627 -118.774903)
			(xy 35.095692 -118.76708) (xy 35.155628 -118.76708) (xy 35.21505 -118.774903) (xy 35.272943 -118.790416)
			(xy 35.328316 -118.813352) (xy 35.380222 -118.843319) (xy 35.427772 -118.879806) (xy 35.470152 -118.922186)
			(xy 35.506639 -118.969736) (xy 35.536606 -119.021642) (xy 35.559542 -119.077015) (xy 35.575055 -119.134908)
			(xy 35.582878 -119.19433) (xy 35.583368 -119.224298) (xy 35.583368 -120.086374) (xy 53.639212 -120.086374)
			(xy 53.639212 -119.222774) (xy 53.639702 -119.192806) (xy 53.647525 -119.133384) (xy 53.663038 -119.075491)
			(xy 53.685974 -119.020118) (xy 53.715941 -118.968212) (xy 53.752428 -118.920662) (xy 53.794808 -118.878282)
			(xy 53.842358 -118.841795) (xy 53.894264 -118.811828) (xy 53.949637 -118.788892) (xy 54.00753 -118.773379)
			(xy 54.066952 -118.765556) (xy 54.126888 -118.765556) (xy 54.18631 -118.773379) (xy 54.244203 -118.788892)
			(xy 54.299576 -118.811828) (xy 54.351482 -118.841795) (xy 54.399032 -118.878282) (xy 54.441412 -118.920662)
			(xy 54.477899 -118.968212) (xy 54.507866 -119.020118) (xy 54.530802 -119.075491) (xy 54.546315 -119.133384)
			(xy 54.554138 -119.192806) (xy 54.554628 -119.222774) (xy 54.554628 -119.567198) (xy 66.599308 -119.567198)
			(xy 66.599308 -118.703598) (xy 66.599798 -118.673614) (xy 66.607626 -118.614158) (xy 66.623147 -118.556233)
			(xy 66.646096 -118.500829) (xy 66.67608 -118.448895) (xy 66.712586 -118.401319) (xy 66.754991 -118.358914)
			(xy 66.802567 -118.322408) (xy 66.854501 -118.292424) (xy 66.909905 -118.269475) (xy 66.96783 -118.253954)
			(xy 67.027286 -118.246126) (xy 67.087254 -118.246126) (xy 67.14671 -118.253954) (xy 67.204635 -118.269475)
			(xy 67.260039 -118.292424) (xy 67.311973 -118.322408) (xy 67.359549 -118.358914) (xy 67.401954 -118.401319)
			(xy 67.43846 -118.448895) (xy 67.468444 -118.500829) (xy 67.491393 -118.556233) (xy 67.506914 -118.614158)
			(xy 67.514742 -118.673614) (xy 67.515232 -118.703598) (xy 67.515232 -119.55907) (xy 81.07426 -119.55907)
			(xy 81.07426 -118.69547) (xy 81.07475 -118.665486) (xy 81.082578 -118.60603) (xy 81.098099 -118.548105)
			(xy 81.121048 -118.492701) (xy 81.151032 -118.440767) (xy 81.187538 -118.393191) (xy 81.229943 -118.350786)
			(xy 81.277519 -118.31428) (xy 81.329453 -118.284296) (xy 81.384857 -118.261347) (xy 81.442782 -118.245826)
			(xy 81.502238 -118.237998) (xy 81.562206 -118.237998) (xy 81.621662 -118.245826) (xy 81.679587 -118.261347)
			(xy 81.734991 -118.284296) (xy 81.786925 -118.31428) (xy 81.834501 -118.350786) (xy 81.876906 -118.393191)
			(xy 81.913412 -118.440767) (xy 81.943396 -118.492701) (xy 81.966345 -118.548105) (xy 81.981866 -118.60603)
			(xy 81.989694 -118.665486) (xy 81.990184 -118.69547) (xy 81.990184 -119.55907) (xy 81.989694 -119.589054)
			(xy 81.981866 -119.64851) (xy 81.966345 -119.706435) (xy 81.943396 -119.761839) (xy 81.913412 -119.813773)
			(xy 81.876906 -119.861349) (xy 81.834501 -119.903754) (xy 81.786925 -119.94026) (xy 81.734991 -119.970244)
			(xy 81.679587 -119.993193) (xy 81.621662 -120.008714) (xy 81.562206 -120.016542) (xy 81.502238 -120.016542)
			(xy 81.442782 -120.008714) (xy 81.384857 -119.993193) (xy 81.329453 -119.970244) (xy 81.277519 -119.94026)
			(xy 81.229943 -119.903754) (xy 81.187538 -119.861349) (xy 81.151032 -119.813773) (xy 81.121048 -119.761839)
			(xy 81.098099 -119.706435) (xy 81.082578 -119.64851) (xy 81.07475 -119.589054) (xy 81.07426 -119.55907)
			(xy 67.515232 -119.55907) (xy 67.515232 -119.567198) (xy 67.514742 -119.597182) (xy 67.506914 -119.656638)
			(xy 67.491393 -119.714563) (xy 67.468444 -119.769967) (xy 67.43846 -119.821901) (xy 67.401954 -119.869477)
			(xy 67.359549 -119.911882) (xy 67.311973 -119.948388) (xy 67.260039 -119.978372) (xy 67.204635 -120.001321)
			(xy 67.14671 -120.016842) (xy 67.087254 -120.02467) (xy 67.027286 -120.02467) (xy 66.96783 -120.016842)
			(xy 66.909905 -120.001321) (xy 66.854501 -119.978372) (xy 66.802567 -119.948388) (xy 66.754991 -119.911882)
			(xy 66.712586 -119.869477) (xy 66.67608 -119.821901) (xy 66.646096 -119.769967) (xy 66.623147 -119.714563)
			(xy 66.607626 -119.656638) (xy 66.599798 -119.597182) (xy 66.599308 -119.567198) (xy 54.554628 -119.567198)
			(xy 54.554628 -120.086374) (xy 54.554138 -120.116342) (xy 54.546315 -120.175764) (xy 54.530802 -120.233657)
			(xy 54.507866 -120.28903) (xy 54.477899 -120.340936) (xy 54.441412 -120.388486) (xy 54.399032 -120.430866)
			(xy 54.351482 -120.467353) (xy 54.299576 -120.49732) (xy 54.244203 -120.520256) (xy 54.18631 -120.535769)
			(xy 54.126888 -120.543592) (xy 54.066952 -120.543592) (xy 54.00753 -120.535769) (xy 53.949637 -120.520256)
			(xy 53.894264 -120.49732) (xy 53.842358 -120.467353) (xy 53.794808 -120.430866) (xy 53.752428 -120.388486)
			(xy 53.715941 -120.340936) (xy 53.685974 -120.28903) (xy 53.663038 -120.233657) (xy 53.647525 -120.175764)
			(xy 53.639702 -120.116342) (xy 53.639212 -120.086374) (xy 35.583368 -120.086374) (xy 35.583368 -120.087898)
			(xy 35.582878 -120.117866) (xy 35.575055 -120.177288) (xy 35.559542 -120.235181) (xy 35.536606 -120.290554)
			(xy 35.506639 -120.34246) (xy 35.470152 -120.39001) (xy 35.427772 -120.43239) (xy 35.380222 -120.468877)
			(xy 35.328316 -120.498844) (xy 35.272943 -120.52178) (xy 35.21505 -120.537293) (xy 35.155628 -120.545116)
			(xy 35.095692 -120.545116) (xy 35.03627 -120.537293) (xy 34.978377 -120.52178) (xy 34.923004 -120.498844)
			(xy 34.871098 -120.468877) (xy 34.823548 -120.43239) (xy 34.781168 -120.39001) (xy 34.744681 -120.34246)
			(xy 34.714714 -120.290554) (xy 34.691778 -120.235181) (xy 34.676265 -120.177288) (xy 34.668442 -120.117866)
			(xy 34.667952 -120.087898) (xy 4.308094 -120.087898) (xy 4.308094 -121.894346) (xy 37.31006 -121.894346)
			(xy 37.31006 -121.030746) (xy 37.31055 -121.000778) (xy 37.318373 -120.941356) (xy 37.333886 -120.883463)
			(xy 37.356822 -120.82809) (xy 37.386789 -120.776184) (xy 37.423276 -120.728634) (xy 37.465656 -120.686254)
			(xy 37.513206 -120.649767) (xy 37.565112 -120.6198) (xy 37.620485 -120.596864) (xy 37.678378 -120.581351)
			(xy 37.7378 -120.573528) (xy 37.797736 -120.573528) (xy 37.857158 -120.581351) (xy 37.915051 -120.596864)
			(xy 37.970424 -120.6198) (xy 38.02233 -120.649767) (xy 38.06988 -120.686254) (xy 38.11226 -120.728634)
			(xy 38.148747 -120.776184) (xy 38.178714 -120.82809) (xy 38.20165 -120.883463) (xy 38.217163 -120.941356)
			(xy 38.224986 -121.000778) (xy 38.225476 -121.030746) (xy 38.225476 -121.886472) (xy 51.785012 -121.886472)
			(xy 51.785012 -121.022872) (xy 51.785502 -120.992904) (xy 51.793325 -120.933482) (xy 51.808838 -120.875589)
			(xy 51.831774 -120.820216) (xy 51.861741 -120.76831) (xy 51.898228 -120.72076) (xy 51.940608 -120.67838)
			(xy 51.988158 -120.641893) (xy 52.040064 -120.611926) (xy 52.095437 -120.58899) (xy 52.15333 -120.573477)
			(xy 52.212752 -120.565654) (xy 52.272688 -120.565654) (xy 52.33211 -120.573477) (xy 52.390003 -120.58899)
			(xy 52.445376 -120.611926) (xy 52.497282 -120.641893) (xy 52.544832 -120.67838) (xy 52.587212 -120.72076)
			(xy 52.623699 -120.76831) (xy 52.653666 -120.820216) (xy 52.676602 -120.875589) (xy 52.692115 -120.933482)
			(xy 52.699938 -120.992904) (xy 52.700428 -121.022872) (xy 52.700428 -121.367296) (xy 64.745108 -121.367296)
			(xy 64.745108 -120.503696) (xy 64.745598 -120.473712) (xy 64.753426 -120.414256) (xy 64.768947 -120.356331)
			(xy 64.791896 -120.300927) (xy 64.82188 -120.248993) (xy 64.858386 -120.201417) (xy 64.900791 -120.159012)
			(xy 64.948367 -120.122506) (xy 65.000301 -120.092522) (xy 65.055705 -120.069573) (xy 65.11363 -120.054052)
			(xy 65.173086 -120.046224) (xy 65.233054 -120.046224) (xy 65.29251 -120.054052) (xy 65.350435 -120.069573)
			(xy 65.405839 -120.092522) (xy 65.457773 -120.122506) (xy 65.505349 -120.159012) (xy 65.547754 -120.201417)
			(xy 65.58426 -120.248993) (xy 65.614244 -120.300927) (xy 65.637193 -120.356331) (xy 65.652714 -120.414256)
			(xy 65.660542 -120.473712) (xy 65.661032 -120.503696) (xy 65.661032 -121.365772) (xy 83.716368 -121.365772)
			(xy 83.716368 -120.502172) (xy 83.716858 -120.472188) (xy 83.724686 -120.412732) (xy 83.740207 -120.354807)
			(xy 83.763156 -120.299403) (xy 83.79314 -120.247469) (xy 83.829646 -120.199893) (xy 83.872051 -120.157488)
			(xy 83.919627 -120.120982) (xy 83.971561 -120.090998) (xy 84.026965 -120.068049) (xy 84.08489 -120.052528)
			(xy 84.144346 -120.0447) (xy 84.204314 -120.0447) (xy 84.26377 -120.052528) (xy 84.321695 -120.068049)
			(xy 84.369615 -120.087898) (xy 150.767796 -120.087898) (xy 150.767796 -119.224298) (xy 150.768286 -119.194314)
			(xy 150.776114 -119.134858) (xy 150.791635 -119.076933) (xy 150.814584 -119.021529) (xy 150.844568 -118.969595)
			(xy 150.881074 -118.922019) (xy 150.923479 -118.879614) (xy 150.971055 -118.843108) (xy 151.022989 -118.813124)
			(xy 151.078393 -118.790175) (xy 151.136318 -118.774654) (xy 151.195774 -118.766826) (xy 151.255742 -118.766826)
			(xy 151.315198 -118.774654) (xy 151.373123 -118.790175) (xy 151.428527 -118.813124) (xy 151.480461 -118.843108)
			(xy 151.528037 -118.879614) (xy 151.570442 -118.922019) (xy 151.606948 -118.969595) (xy 151.636932 -119.021529)
			(xy 151.659881 -119.076933) (xy 151.675402 -119.134858) (xy 151.68323 -119.194314) (xy 151.68372 -119.224298)
			(xy 151.68372 -120.086374) (xy 169.739056 -120.086374) (xy 169.739056 -119.222774) (xy 169.739546 -119.19279)
			(xy 169.747374 -119.133334) (xy 169.762895 -119.075409) (xy 169.785844 -119.020005) (xy 169.815828 -118.968071)
			(xy 169.852334 -118.920495) (xy 169.894739 -118.87809) (xy 169.942315 -118.841584) (xy 169.994249 -118.8116)
			(xy 170.049653 -118.788651) (xy 170.107578 -118.77313) (xy 170.167034 -118.765302) (xy 170.227002 -118.765302)
			(xy 170.286458 -118.77313) (xy 170.344383 -118.788651) (xy 170.399787 -118.8116) (xy 170.451721 -118.841584)
			(xy 170.499297 -118.87809) (xy 170.541702 -118.920495) (xy 170.578208 -118.968071) (xy 170.608192 -119.020005)
			(xy 170.631141 -119.075409) (xy 170.646662 -119.133334) (xy 170.65449 -119.19279) (xy 170.65498 -119.222774)
			(xy 170.65498 -119.567198) (xy 182.69966 -119.567198) (xy 182.69966 -118.703598) (xy 182.70015 -118.67363)
			(xy 182.707973 -118.614208) (xy 182.723486 -118.556315) (xy 182.746422 -118.500942) (xy 182.776389 -118.449036)
			(xy 182.812876 -118.401486) (xy 182.855256 -118.359106) (xy 182.902806 -118.322619) (xy 182.954712 -118.292652)
			(xy 183.010085 -118.269716) (xy 183.067978 -118.254203) (xy 183.1274 -118.24638) (xy 183.187336 -118.24638)
			(xy 183.246758 -118.254203) (xy 183.304651 -118.269716) (xy 183.360024 -118.292652) (xy 183.41193 -118.322619)
			(xy 183.45948 -118.359106) (xy 183.50186 -118.401486) (xy 183.538347 -118.449036) (xy 183.568314 -118.500942)
			(xy 183.59125 -118.556315) (xy 183.606763 -118.614208) (xy 183.614586 -118.67363) (xy 183.615076 -118.703598)
			(xy 183.615076 -119.559324) (xy 197.174612 -119.559324) (xy 197.174612 -118.695724) (xy 197.175102 -118.665756)
			(xy 197.182925 -118.606334) (xy 197.198438 -118.548441) (xy 197.221374 -118.493068) (xy 197.251341 -118.441162)
			(xy 197.287828 -118.393612) (xy 197.330208 -118.351232) (xy 197.377758 -118.314745) (xy 197.429664 -118.284778)
			(xy 197.485037 -118.261842) (xy 197.54293 -118.246329) (xy 197.602352 -118.238506) (xy 197.662288 -118.238506)
			(xy 197.72171 -118.246329) (xy 197.779603 -118.261842) (xy 197.834976 -118.284778) (xy 197.886882 -118.314745)
			(xy 197.934432 -118.351232) (xy 197.976812 -118.393612) (xy 198.013299 -118.441162) (xy 198.043266 -118.493068)
			(xy 198.066202 -118.548441) (xy 198.081715 -118.606334) (xy 198.089538 -118.665756) (xy 198.090028 -118.695724)
			(xy 198.090028 -119.559324) (xy 198.089538 -119.589292) (xy 198.081715 -119.648714) (xy 198.066202 -119.706607)
			(xy 198.043266 -119.76198) (xy 198.013299 -119.813886) (xy 197.976812 -119.861436) (xy 197.934432 -119.903816)
			(xy 197.886882 -119.940303) (xy 197.834976 -119.97027) (xy 197.779603 -119.993206) (xy 197.72171 -120.008719)
			(xy 197.662288 -120.016542) (xy 197.602352 -120.016542) (xy 197.54293 -120.008719) (xy 197.485037 -119.993206)
			(xy 197.429664 -119.97027) (xy 197.377758 -119.940303) (xy 197.330208 -119.903816) (xy 197.287828 -119.861436)
			(xy 197.251341 -119.813886) (xy 197.221374 -119.76198) (xy 197.198438 -119.706607) (xy 197.182925 -119.648714)
			(xy 197.175102 -119.589292) (xy 197.174612 -119.559324) (xy 183.615076 -119.559324) (xy 183.615076 -119.567198)
			(xy 183.614586 -119.597166) (xy 183.606763 -119.656588) (xy 183.59125 -119.714481) (xy 183.568314 -119.769854)
			(xy 183.538347 -119.82176) (xy 183.50186 -119.86931) (xy 183.45948 -119.91169) (xy 183.41193 -119.948177)
			(xy 183.360024 -119.978144) (xy 183.304651 -120.00108) (xy 183.246758 -120.016593) (xy 183.187336 -120.024416)
			(xy 183.1274 -120.024416) (xy 183.067978 -120.016593) (xy 183.010085 -120.00108) (xy 182.954712 -119.978144)
			(xy 182.902806 -119.948177) (xy 182.855256 -119.91169) (xy 182.812876 -119.86931) (xy 182.776389 -119.82176)
			(xy 182.746422 -119.769854) (xy 182.723486 -119.714481) (xy 182.707973 -119.656588) (xy 182.70015 -119.597166)
			(xy 182.69966 -119.567198) (xy 170.65498 -119.567198) (xy 170.65498 -120.086374) (xy 170.65449 -120.116358)
			(xy 170.646662 -120.175814) (xy 170.631141 -120.233739) (xy 170.608192 -120.289143) (xy 170.578208 -120.341077)
			(xy 170.541702 -120.388653) (xy 170.499297 -120.431058) (xy 170.451721 -120.467564) (xy 170.399787 -120.497548)
			(xy 170.344383 -120.520497) (xy 170.286458 -120.536018) (xy 170.227002 -120.543846) (xy 170.167034 -120.543846)
			(xy 170.107578 -120.536018) (xy 170.049653 -120.520497) (xy 169.994249 -120.497548) (xy 169.942315 -120.467564)
			(xy 169.894739 -120.431058) (xy 169.852334 -120.388653) (xy 169.815828 -120.341077) (xy 169.785844 -120.289143)
			(xy 169.762895 -120.233739) (xy 169.747374 -120.175814) (xy 169.739546 -120.116358) (xy 169.739056 -120.086374)
			(xy 151.68372 -120.086374) (xy 151.68372 -120.087898) (xy 151.68323 -120.117882) (xy 151.675402 -120.177338)
			(xy 151.659881 -120.235263) (xy 151.636932 -120.290667) (xy 151.606948 -120.342601) (xy 151.570442 -120.390177)
			(xy 151.528037 -120.432582) (xy 151.480461 -120.469088) (xy 151.428527 -120.499072) (xy 151.373123 -120.522021)
			(xy 151.315198 -120.537542) (xy 151.255742 -120.54537) (xy 151.195774 -120.54537) (xy 151.136318 -120.537542)
			(xy 151.078393 -120.522021) (xy 151.022989 -120.499072) (xy 150.971055 -120.469088) (xy 150.923479 -120.432582)
			(xy 150.881074 -120.390177) (xy 150.844568 -120.342601) (xy 150.814584 -120.290667) (xy 150.791635 -120.235263)
			(xy 150.776114 -120.177338) (xy 150.768286 -120.117882) (xy 150.767796 -120.087898) (xy 84.369615 -120.087898)
			(xy 84.377099 -120.090998) (xy 84.429033 -120.120982) (xy 84.476609 -120.157488) (xy 84.519014 -120.199893)
			(xy 84.55552 -120.247469) (xy 84.585504 -120.299403) (xy 84.608453 -120.354807) (xy 84.623974 -120.412732)
			(xy 84.631802 -120.472188) (xy 84.632292 -120.502172) (xy 84.632292 -121.365772) (xy 84.631802 -121.395756)
			(xy 84.623974 -121.455212) (xy 84.608453 -121.513137) (xy 84.585504 -121.568541) (xy 84.55552 -121.620475)
			(xy 84.519014 -121.668051) (xy 84.476609 -121.710456) (xy 84.429033 -121.746962) (xy 84.377099 -121.776946)
			(xy 84.321695 -121.799895) (xy 84.26377 -121.815416) (xy 84.204314 -121.823244) (xy 84.144346 -121.823244)
			(xy 84.08489 -121.815416) (xy 84.026965 -121.799895) (xy 83.971561 -121.776946) (xy 83.919627 -121.746962)
			(xy 83.872051 -121.710456) (xy 83.829646 -121.668051) (xy 83.79314 -121.620475) (xy 83.763156 -121.568541)
			(xy 83.740207 -121.513137) (xy 83.724686 -121.455212) (xy 83.716858 -121.395756) (xy 83.716368 -121.365772)
			(xy 65.661032 -121.365772) (xy 65.661032 -121.367296) (xy 65.660542 -121.39728) (xy 65.652714 -121.456736)
			(xy 65.637193 -121.514661) (xy 65.614244 -121.570065) (xy 65.58426 -121.621999) (xy 65.547754 -121.669575)
			(xy 65.505349 -121.71198) (xy 65.457773 -121.748486) (xy 65.405839 -121.77847) (xy 65.350435 -121.801419)
			(xy 65.29251 -121.81694) (xy 65.233054 -121.824768) (xy 65.173086 -121.824768) (xy 65.11363 -121.81694)
			(xy 65.055705 -121.801419) (xy 65.000301 -121.77847) (xy 64.948367 -121.748486) (xy 64.900791 -121.71198)
			(xy 64.858386 -121.669575) (xy 64.82188 -121.621999) (xy 64.791896 -121.570065) (xy 64.768947 -121.514661)
			(xy 64.753426 -121.456736) (xy 64.745598 -121.39728) (xy 64.745108 -121.367296) (xy 52.700428 -121.367296)
			(xy 52.700428 -121.886472) (xy 52.699938 -121.91644) (xy 52.692115 -121.975862) (xy 52.676602 -122.033755)
			(xy 52.653666 -122.089128) (xy 52.623699 -122.141034) (xy 52.587212 -122.188584) (xy 52.544832 -122.230964)
			(xy 52.497282 -122.267451) (xy 52.445376 -122.297418) (xy 52.390003 -122.320354) (xy 52.33211 -122.335867)
			(xy 52.272688 -122.34369) (xy 52.212752 -122.34369) (xy 52.15333 -122.335867) (xy 52.095437 -122.320354)
			(xy 52.040064 -122.297418) (xy 51.988158 -122.267451) (xy 51.940608 -122.230964) (xy 51.898228 -122.188584)
			(xy 51.861741 -122.141034) (xy 51.831774 -122.089128) (xy 51.808838 -122.033755) (xy 51.793325 -121.975862)
			(xy 51.785502 -121.91644) (xy 51.785012 -121.886472) (xy 38.225476 -121.886472) (xy 38.225476 -121.894346)
			(xy 38.224986 -121.924314) (xy 38.217163 -121.983736) (xy 38.20165 -122.041629) (xy 38.178714 -122.097002)
			(xy 38.148747 -122.148908) (xy 38.11226 -122.196458) (xy 38.06988 -122.238838) (xy 38.02233 -122.275325)
			(xy 37.970424 -122.305292) (xy 37.915051 -122.328228) (xy 37.857158 -122.343741) (xy 37.797736 -122.351564)
			(xy 37.7378 -122.351564) (xy 37.678378 -122.343741) (xy 37.620485 -122.328228) (xy 37.565112 -122.305292)
			(xy 37.513206 -122.275325) (xy 37.465656 -122.238838) (xy 37.423276 -122.196458) (xy 37.386789 -122.148908)
			(xy 37.356822 -122.097002) (xy 37.333886 -122.041629) (xy 37.318373 -121.983736) (xy 37.31055 -121.924314)
			(xy 37.31006 -121.894346) (xy 4.308094 -121.894346) (xy 4.308094 -123.68784) (xy 34.667952 -123.68784)
			(xy 34.667952 -122.82424) (xy 34.668442 -122.794272) (xy 34.676265 -122.73485) (xy 34.691778 -122.676957)
			(xy 34.714714 -122.621584) (xy 34.744681 -122.569678) (xy 34.781168 -122.522128) (xy 34.823548 -122.479748)
			(xy 34.871098 -122.443261) (xy 34.923004 -122.413294) (xy 34.978377 -122.390358) (xy 35.03627 -122.374845)
			(xy 35.095692 -122.367022) (xy 35.155628 -122.367022) (xy 35.21505 -122.374845) (xy 35.272943 -122.390358)
			(xy 35.328316 -122.413294) (xy 35.380222 -122.443261) (xy 35.427772 -122.479748) (xy 35.470152 -122.522128)
			(xy 35.506639 -122.569678) (xy 35.536606 -122.621584) (xy 35.559542 -122.676957) (xy 35.575055 -122.73485)
			(xy 35.582878 -122.794272) (xy 35.583368 -122.82424) (xy 35.583368 -123.686316) (xy 53.639212 -123.686316)
			(xy 53.639212 -122.822716) (xy 53.639702 -122.792748) (xy 53.647525 -122.733326) (xy 53.663038 -122.675433)
			(xy 53.685974 -122.62006) (xy 53.715941 -122.568154) (xy 53.752428 -122.520604) (xy 53.794808 -122.478224)
			(xy 53.842358 -122.441737) (xy 53.894264 -122.41177) (xy 53.949637 -122.388834) (xy 54.00753 -122.373321)
			(xy 54.066952 -122.365498) (xy 54.126888 -122.365498) (xy 54.18631 -122.373321) (xy 54.244203 -122.388834)
			(xy 54.299576 -122.41177) (xy 54.351482 -122.441737) (xy 54.399032 -122.478224) (xy 54.441412 -122.520604)
			(xy 54.477899 -122.568154) (xy 54.507866 -122.62006) (xy 54.530802 -122.675433) (xy 54.546315 -122.733326)
			(xy 54.554138 -122.792748) (xy 54.554628 -122.822716) (xy 54.554628 -123.16714) (xy 66.599308 -123.16714)
			(xy 66.599308 -122.30354) (xy 66.599798 -122.273556) (xy 66.607626 -122.2141) (xy 66.623147 -122.156175)
			(xy 66.646096 -122.100771) (xy 66.67608 -122.048837) (xy 66.712586 -122.001261) (xy 66.754991 -121.958856)
			(xy 66.802567 -121.92235) (xy 66.854501 -121.892366) (xy 66.909905 -121.869417) (xy 66.96783 -121.853896)
			(xy 67.027286 -121.846068) (xy 67.087254 -121.846068) (xy 67.14671 -121.853896) (xy 67.204635 -121.869417)
			(xy 67.260039 -121.892366) (xy 67.311973 -121.92235) (xy 67.359549 -121.958856) (xy 67.401954 -122.001261)
			(xy 67.43846 -122.048837) (xy 67.468444 -122.100771) (xy 67.491393 -122.156175) (xy 67.506914 -122.2141)
			(xy 67.514742 -122.273556) (xy 67.515232 -122.30354) (xy 67.515232 -123.159266) (xy 81.07426 -123.159266)
			(xy 81.07426 -122.295666) (xy 81.07475 -122.265682) (xy 81.082578 -122.206226) (xy 81.098099 -122.148301)
			(xy 81.121048 -122.092897) (xy 81.151032 -122.040963) (xy 81.187538 -121.993387) (xy 81.229943 -121.950982)
			(xy 81.277519 -121.914476) (xy 81.329453 -121.884492) (xy 81.384857 -121.861543) (xy 81.442782 -121.846022)
			(xy 81.502238 -121.838194) (xy 81.562206 -121.838194) (xy 81.621662 -121.846022) (xy 81.679587 -121.861543)
			(xy 81.734991 -121.884492) (xy 81.752059 -121.894346) (xy 153.409904 -121.894346) (xy 153.409904 -121.030746)
			(xy 153.410394 -121.000762) (xy 153.418222 -120.941306) (xy 153.433743 -120.883381) (xy 153.456692 -120.827977)
			(xy 153.486676 -120.776043) (xy 153.523182 -120.728467) (xy 153.565587 -120.686062) (xy 153.613163 -120.649556)
			(xy 153.665097 -120.619572) (xy 153.720501 -120.596623) (xy 153.778426 -120.581102) (xy 153.837882 -120.573274)
			(xy 153.89785 -120.573274) (xy 153.957306 -120.581102) (xy 154.015231 -120.596623) (xy 154.070635 -120.619572)
			(xy 154.122569 -120.649556) (xy 154.170145 -120.686062) (xy 154.21255 -120.728467) (xy 154.249056 -120.776043)
			(xy 154.27904 -120.827977) (xy 154.301989 -120.883381) (xy 154.31751 -120.941306) (xy 154.325338 -121.000762)
			(xy 154.325828 -121.030746) (xy 154.325828 -121.886472) (xy 167.884856 -121.886472) (xy 167.884856 -121.022872)
			(xy 167.885346 -120.992888) (xy 167.893174 -120.933432) (xy 167.908695 -120.875507) (xy 167.931644 -120.820103)
			(xy 167.961628 -120.768169) (xy 167.998134 -120.720593) (xy 168.040539 -120.678188) (xy 168.088115 -120.641682)
			(xy 168.140049 -120.611698) (xy 168.195453 -120.588749) (xy 168.253378 -120.573228) (xy 168.312834 -120.5654)
			(xy 168.372802 -120.5654) (xy 168.432258 -120.573228) (xy 168.490183 -120.588749) (xy 168.545587 -120.611698)
			(xy 168.597521 -120.641682) (xy 168.645097 -120.678188) (xy 168.687502 -120.720593) (xy 168.724008 -120.768169)
			(xy 168.753992 -120.820103) (xy 168.776941 -120.875507) (xy 168.792462 -120.933432) (xy 168.80029 -120.992888)
			(xy 168.80078 -121.022872) (xy 168.80078 -121.367296) (xy 180.84546 -121.367296) (xy 180.84546 -120.503696)
			(xy 180.84595 -120.473728) (xy 180.853773 -120.414306) (xy 180.869286 -120.356413) (xy 180.892222 -120.30104)
			(xy 180.922189 -120.249134) (xy 180.958676 -120.201584) (xy 181.001056 -120.159204) (xy 181.048606 -120.122717)
			(xy 181.100512 -120.09275) (xy 181.155885 -120.069814) (xy 181.213778 -120.054301) (xy 181.2732 -120.046478)
			(xy 181.333136 -120.046478) (xy 181.392558 -120.054301) (xy 181.450451 -120.069814) (xy 181.505824 -120.09275)
			(xy 181.55773 -120.122717) (xy 181.60528 -120.159204) (xy 181.64766 -120.201584) (xy 181.684147 -120.249134)
			(xy 181.714114 -120.30104) (xy 181.73705 -120.356413) (xy 181.752563 -120.414306) (xy 181.760386 -120.473728)
			(xy 181.760876 -120.503696) (xy 181.760876 -121.365772) (xy 199.81672 -121.365772) (xy 199.81672 -120.502172)
			(xy 199.81721 -120.472204) (xy 199.825033 -120.412782) (xy 199.840546 -120.354889) (xy 199.863482 -120.299516)
			(xy 199.893449 -120.24761) (xy 199.929936 -120.20006) (xy 199.972316 -120.15768) (xy 200.019866 -120.121193)
			(xy 200.071772 -120.091226) (xy 200.127145 -120.06829) (xy 200.185038 -120.052777) (xy 200.24446 -120.044954)
			(xy 200.304396 -120.044954) (xy 200.363818 -120.052777) (xy 200.421711 -120.06829) (xy 200.469049 -120.087898)
			(xy 266.86764 -120.087898) (xy 266.86764 -119.224298) (xy 266.86813 -119.194314) (xy 266.875958 -119.134858)
			(xy 266.891479 -119.076933) (xy 266.914428 -119.021529) (xy 266.944412 -118.969595) (xy 266.980918 -118.922019)
			(xy 267.023323 -118.879614) (xy 267.070899 -118.843108) (xy 267.122833 -118.813124) (xy 267.178237 -118.790175)
			(xy 267.236162 -118.774654) (xy 267.295618 -118.766826) (xy 267.355586 -118.766826) (xy 267.415042 -118.774654)
			(xy 267.472967 -118.790175) (xy 267.528371 -118.813124) (xy 267.580305 -118.843108) (xy 267.627881 -118.879614)
			(xy 267.670286 -118.922019) (xy 267.706792 -118.969595) (xy 267.736776 -119.021529) (xy 267.759725 -119.076933)
			(xy 267.775246 -119.134858) (xy 267.783074 -119.194314) (xy 267.783564 -119.224298) (xy 267.783564 -120.086374)
			(xy 285.8389 -120.086374) (xy 285.8389 -119.222774) (xy 285.83939 -119.19279) (xy 285.847218 -119.133334)
			(xy 285.862739 -119.075409) (xy 285.885688 -119.020005) (xy 285.915672 -118.968071) (xy 285.952178 -118.920495)
			(xy 285.994583 -118.87809) (xy 286.042159 -118.841584) (xy 286.094093 -118.8116) (xy 286.149497 -118.788651)
			(xy 286.207422 -118.77313) (xy 286.266878 -118.765302) (xy 286.326846 -118.765302) (xy 286.386302 -118.77313)
			(xy 286.444227 -118.788651) (xy 286.499631 -118.8116) (xy 286.551565 -118.841584) (xy 286.599141 -118.87809)
			(xy 286.641546 -118.920495) (xy 286.678052 -118.968071) (xy 286.708036 -119.020005) (xy 286.730985 -119.075409)
			(xy 286.746506 -119.133334) (xy 286.754334 -119.19279) (xy 286.754824 -119.222774) (xy 286.754824 -119.567198)
			(xy 298.799504 -119.567198) (xy 298.799504 -118.703598) (xy 298.799994 -118.67363) (xy 298.807817 -118.614208)
			(xy 298.82333 -118.556315) (xy 298.846266 -118.500942) (xy 298.876233 -118.449036) (xy 298.91272 -118.401486)
			(xy 298.9551 -118.359106) (xy 299.00265 -118.322619) (xy 299.054556 -118.292652) (xy 299.109929 -118.269716)
			(xy 299.167822 -118.254203) (xy 299.227244 -118.24638) (xy 299.28718 -118.24638) (xy 299.346602 -118.254203)
			(xy 299.404495 -118.269716) (xy 299.459868 -118.292652) (xy 299.511774 -118.322619) (xy 299.559324 -118.359106)
			(xy 299.601704 -118.401486) (xy 299.638191 -118.449036) (xy 299.668158 -118.500942) (xy 299.691094 -118.556315)
			(xy 299.706607 -118.614208) (xy 299.71443 -118.67363) (xy 299.71492 -118.703598) (xy 299.71492 -119.559324)
			(xy 313.274456 -119.559324) (xy 313.274456 -118.695724) (xy 313.274946 -118.665756) (xy 313.282769 -118.606334)
			(xy 313.298282 -118.548441) (xy 313.321218 -118.493068) (xy 313.351185 -118.441162) (xy 313.387672 -118.393612)
			(xy 313.430052 -118.351232) (xy 313.477602 -118.314745) (xy 313.529508 -118.284778) (xy 313.584881 -118.261842)
			(xy 313.642774 -118.246329) (xy 313.702196 -118.238506) (xy 313.762132 -118.238506) (xy 313.821554 -118.246329)
			(xy 313.879447 -118.261842) (xy 313.93482 -118.284778) (xy 313.986726 -118.314745) (xy 314.034276 -118.351232)
			(xy 314.076656 -118.393612) (xy 314.113143 -118.441162) (xy 314.14311 -118.493068) (xy 314.166046 -118.548441)
			(xy 314.181559 -118.606334) (xy 314.189382 -118.665756) (xy 314.189872 -118.695724) (xy 314.189872 -119.559324)
			(xy 314.189382 -119.589292) (xy 314.181559 -119.648714) (xy 314.166046 -119.706607) (xy 314.14311 -119.76198)
			(xy 314.113143 -119.813886) (xy 314.076656 -119.861436) (xy 314.034276 -119.903816) (xy 313.986726 -119.940303)
			(xy 313.93482 -119.97027) (xy 313.879447 -119.993206) (xy 313.821554 -120.008719) (xy 313.762132 -120.016542)
			(xy 313.702196 -120.016542) (xy 313.642774 -120.008719) (xy 313.584881 -119.993206) (xy 313.529508 -119.97027)
			(xy 313.477602 -119.940303) (xy 313.430052 -119.903816) (xy 313.387672 -119.861436) (xy 313.351185 -119.813886)
			(xy 313.321218 -119.76198) (xy 313.298282 -119.706607) (xy 313.282769 -119.648714) (xy 313.274946 -119.589292)
			(xy 313.274456 -119.559324) (xy 299.71492 -119.559324) (xy 299.71492 -119.567198) (xy 299.71443 -119.597166)
			(xy 299.706607 -119.656588) (xy 299.691094 -119.714481) (xy 299.668158 -119.769854) (xy 299.638191 -119.82176)
			(xy 299.601704 -119.86931) (xy 299.559324 -119.91169) (xy 299.511774 -119.948177) (xy 299.459868 -119.978144)
			(xy 299.404495 -120.00108) (xy 299.346602 -120.016593) (xy 299.28718 -120.024416) (xy 299.227244 -120.024416)
			(xy 299.167822 -120.016593) (xy 299.109929 -120.00108) (xy 299.054556 -119.978144) (xy 299.00265 -119.948177)
			(xy 298.9551 -119.91169) (xy 298.91272 -119.86931) (xy 298.876233 -119.82176) (xy 298.846266 -119.769854)
			(xy 298.82333 -119.714481) (xy 298.807817 -119.656588) (xy 298.799994 -119.597166) (xy 298.799504 -119.567198)
			(xy 286.754824 -119.567198) (xy 286.754824 -120.086374) (xy 286.754334 -120.116358) (xy 286.746506 -120.175814)
			(xy 286.730985 -120.233739) (xy 286.708036 -120.289143) (xy 286.678052 -120.341077) (xy 286.641546 -120.388653)
			(xy 286.599141 -120.431058) (xy 286.551565 -120.467564) (xy 286.499631 -120.497548) (xy 286.444227 -120.520497)
			(xy 286.386302 -120.536018) (xy 286.326846 -120.543846) (xy 286.266878 -120.543846) (xy 286.207422 -120.536018)
			(xy 286.149497 -120.520497) (xy 286.094093 -120.497548) (xy 286.042159 -120.467564) (xy 285.994583 -120.431058)
			(xy 285.952178 -120.388653) (xy 285.915672 -120.341077) (xy 285.885688 -120.289143) (xy 285.862739 -120.233739)
			(xy 285.847218 -120.175814) (xy 285.83939 -120.116358) (xy 285.8389 -120.086374) (xy 267.783564 -120.086374)
			(xy 267.783564 -120.087898) (xy 267.783074 -120.117882) (xy 267.775246 -120.177338) (xy 267.759725 -120.235263)
			(xy 267.736776 -120.290667) (xy 267.706792 -120.342601) (xy 267.670286 -120.390177) (xy 267.627881 -120.432582)
			(xy 267.580305 -120.469088) (xy 267.528371 -120.499072) (xy 267.472967 -120.522021) (xy 267.415042 -120.537542)
			(xy 267.355586 -120.54537) (xy 267.295618 -120.54537) (xy 267.236162 -120.537542) (xy 267.178237 -120.522021)
			(xy 267.122833 -120.499072) (xy 267.070899 -120.469088) (xy 267.023323 -120.432582) (xy 266.980918 -120.390177)
			(xy 266.944412 -120.342601) (xy 266.914428 -120.290667) (xy 266.891479 -120.235263) (xy 266.875958 -120.177338)
			(xy 266.86813 -120.117882) (xy 266.86764 -120.087898) (xy 200.469049 -120.087898) (xy 200.477084 -120.091226)
			(xy 200.52899 -120.121193) (xy 200.57654 -120.15768) (xy 200.61892 -120.20006) (xy 200.655407 -120.24761)
			(xy 200.685374 -120.299516) (xy 200.70831 -120.354889) (xy 200.723823 -120.412782) (xy 200.731646 -120.472204)
			(xy 200.732136 -120.502172) (xy 200.732136 -121.365772) (xy 200.731646 -121.39574) (xy 200.723823 -121.455162)
			(xy 200.70831 -121.513055) (xy 200.685374 -121.568428) (xy 200.655407 -121.620334) (xy 200.61892 -121.667884)
			(xy 200.57654 -121.710264) (xy 200.52899 -121.746751) (xy 200.477084 -121.776718) (xy 200.421711 -121.799654)
			(xy 200.363818 -121.815167) (xy 200.304396 -121.82299) (xy 200.24446 -121.82299) (xy 200.185038 -121.815167)
			(xy 200.127145 -121.799654) (xy 200.071772 -121.776718) (xy 200.019866 -121.746751) (xy 199.972316 -121.710264)
			(xy 199.929936 -121.667884) (xy 199.893449 -121.620334) (xy 199.863482 -121.568428) (xy 199.840546 -121.513055)
			(xy 199.825033 -121.455162) (xy 199.81721 -121.39574) (xy 199.81672 -121.365772) (xy 181.760876 -121.365772)
			(xy 181.760876 -121.367296) (xy 181.760386 -121.397264) (xy 181.752563 -121.456686) (xy 181.73705 -121.514579)
			(xy 181.714114 -121.569952) (xy 181.684147 -121.621858) (xy 181.64766 -121.669408) (xy 181.60528 -121.711788)
			(xy 181.55773 -121.748275) (xy 181.505824 -121.778242) (xy 181.450451 -121.801178) (xy 181.392558 -121.816691)
			(xy 181.333136 -121.824514) (xy 181.2732 -121.824514) (xy 181.213778 -121.816691) (xy 181.155885 -121.801178)
			(xy 181.100512 -121.778242) (xy 181.048606 -121.748275) (xy 181.001056 -121.711788) (xy 180.958676 -121.669408)
			(xy 180.922189 -121.621858) (xy 180.892222 -121.569952) (xy 180.869286 -121.514579) (xy 180.853773 -121.456686)
			(xy 180.84595 -121.397264) (xy 180.84546 -121.367296) (xy 168.80078 -121.367296) (xy 168.80078 -121.886472)
			(xy 168.80029 -121.916456) (xy 168.792462 -121.975912) (xy 168.776941 -122.033837) (xy 168.753992 -122.089241)
			(xy 168.724008 -122.141175) (xy 168.687502 -122.188751) (xy 168.645097 -122.231156) (xy 168.597521 -122.267662)
			(xy 168.545587 -122.297646) (xy 168.490183 -122.320595) (xy 168.432258 -122.336116) (xy 168.372802 -122.343944)
			(xy 168.312834 -122.343944) (xy 168.253378 -122.336116) (xy 168.195453 -122.320595) (xy 168.140049 -122.297646)
			(xy 168.088115 -122.267662) (xy 168.040539 -122.231156) (xy 167.998134 -122.188751) (xy 167.961628 -122.141175)
			(xy 167.931644 -122.089241) (xy 167.908695 -122.033837) (xy 167.893174 -121.975912) (xy 167.885346 -121.916456)
			(xy 167.884856 -121.886472) (xy 154.325828 -121.886472) (xy 154.325828 -121.894346) (xy 154.325338 -121.92433)
			(xy 154.31751 -121.983786) (xy 154.301989 -122.041711) (xy 154.27904 -122.097115) (xy 154.249056 -122.149049)
			(xy 154.21255 -122.196625) (xy 154.170145 -122.23903) (xy 154.122569 -122.275536) (xy 154.070635 -122.30552)
			(xy 154.015231 -122.328469) (xy 153.957306 -122.34399) (xy 153.89785 -122.351818) (xy 153.837882 -122.351818)
			(xy 153.778426 -122.34399) (xy 153.720501 -122.328469) (xy 153.665097 -122.30552) (xy 153.613163 -122.275536)
			(xy 153.565587 -122.23903) (xy 153.523182 -122.196625) (xy 153.486676 -122.149049) (xy 153.456692 -122.097115)
			(xy 153.433743 -122.041711) (xy 153.418222 -121.983786) (xy 153.410394 -121.92433) (xy 153.409904 -121.894346)
			(xy 81.752059 -121.894346) (xy 81.786925 -121.914476) (xy 81.834501 -121.950982) (xy 81.876906 -121.993387)
			(xy 81.913412 -122.040963) (xy 81.943396 -122.092897) (xy 81.966345 -122.148301) (xy 81.981866 -122.206226)
			(xy 81.989694 -122.265682) (xy 81.990184 -122.295666) (xy 81.990184 -123.159266) (xy 81.989694 -123.18925)
			(xy 81.981866 -123.248706) (xy 81.966345 -123.306631) (xy 81.943396 -123.362035) (xy 81.913412 -123.413969)
			(xy 81.876906 -123.461545) (xy 81.834501 -123.50395) (xy 81.786925 -123.540456) (xy 81.734991 -123.57044)
			(xy 81.679587 -123.593389) (xy 81.621662 -123.60891) (xy 81.562206 -123.616738) (xy 81.502238 -123.616738)
			(xy 81.442782 -123.60891) (xy 81.384857 -123.593389) (xy 81.329453 -123.57044) (xy 81.277519 -123.540456)
			(xy 81.229943 -123.50395) (xy 81.187538 -123.461545) (xy 81.151032 -123.413969) (xy 81.121048 -123.362035)
			(xy 81.098099 -123.306631) (xy 81.082578 -123.248706) (xy 81.07475 -123.18925) (xy 81.07426 -123.159266)
			(xy 67.515232 -123.159266) (xy 67.515232 -123.16714) (xy 67.514742 -123.197124) (xy 67.506914 -123.25658)
			(xy 67.491393 -123.314505) (xy 67.468444 -123.369909) (xy 67.43846 -123.421843) (xy 67.401954 -123.469419)
			(xy 67.359549 -123.511824) (xy 67.311973 -123.54833) (xy 67.260039 -123.578314) (xy 67.204635 -123.601263)
			(xy 67.14671 -123.616784) (xy 67.087254 -123.624612) (xy 67.027286 -123.624612) (xy 66.96783 -123.616784)
			(xy 66.909905 -123.601263) (xy 66.854501 -123.578314) (xy 66.802567 -123.54833) (xy 66.754991 -123.511824)
			(xy 66.712586 -123.469419) (xy 66.67608 -123.421843) (xy 66.646096 -123.369909) (xy 66.623147 -123.314505)
			(xy 66.607626 -123.25658) (xy 66.599798 -123.197124) (xy 66.599308 -123.16714) (xy 54.554628 -123.16714)
			(xy 54.554628 -123.686316) (xy 54.554138 -123.716284) (xy 54.546315 -123.775706) (xy 54.530802 -123.833599)
			(xy 54.507866 -123.888972) (xy 54.477899 -123.940878) (xy 54.441412 -123.988428) (xy 54.399032 -124.030808)
			(xy 54.351482 -124.067295) (xy 54.299576 -124.097262) (xy 54.244203 -124.120198) (xy 54.18631 -124.135711)
			(xy 54.126888 -124.143534) (xy 54.066952 -124.143534) (xy 54.00753 -124.135711) (xy 53.949637 -124.120198)
			(xy 53.894264 -124.097262) (xy 53.842358 -124.067295) (xy 53.794808 -124.030808) (xy 53.752428 -123.988428)
			(xy 53.715941 -123.940878) (xy 53.685974 -123.888972) (xy 53.663038 -123.833599) (xy 53.647525 -123.775706)
			(xy 53.639702 -123.716284) (xy 53.639212 -123.686316) (xy 35.583368 -123.686316) (xy 35.583368 -123.68784)
			(xy 35.582878 -123.717808) (xy 35.575055 -123.77723) (xy 35.559542 -123.835123) (xy 35.536606 -123.890496)
			(xy 35.506639 -123.942402) (xy 35.470152 -123.989952) (xy 35.427772 -124.032332) (xy 35.380222 -124.068819)
			(xy 35.328316 -124.098786) (xy 35.272943 -124.121722) (xy 35.21505 -124.137235) (xy 35.155628 -124.145058)
			(xy 35.095692 -124.145058) (xy 35.03627 -124.137235) (xy 34.978377 -124.121722) (xy 34.923004 -124.098786)
			(xy 34.871098 -124.068819) (xy 34.823548 -124.032332) (xy 34.781168 -123.989952) (xy 34.744681 -123.942402)
			(xy 34.714714 -123.890496) (xy 34.691778 -123.835123) (xy 34.676265 -123.77723) (xy 34.668442 -123.717808)
			(xy 34.667952 -123.68784) (xy 4.308094 -123.68784) (xy 4.308094 -125.494542) (xy 37.31006 -125.494542)
			(xy 37.31006 -124.630942) (xy 37.31055 -124.600974) (xy 37.318373 -124.541552) (xy 37.333886 -124.483659)
			(xy 37.356822 -124.428286) (xy 37.386789 -124.37638) (xy 37.423276 -124.32883) (xy 37.465656 -124.28645)
			(xy 37.513206 -124.249963) (xy 37.565112 -124.219996) (xy 37.620485 -124.19706) (xy 37.678378 -124.181547)
			(xy 37.7378 -124.173724) (xy 37.797736 -124.173724) (xy 37.857158 -124.181547) (xy 37.915051 -124.19706)
			(xy 37.970424 -124.219996) (xy 38.02233 -124.249963) (xy 38.06988 -124.28645) (xy 38.11226 -124.32883)
			(xy 38.148747 -124.37638) (xy 38.178714 -124.428286) (xy 38.20165 -124.483659) (xy 38.217163 -124.541552)
			(xy 38.224986 -124.600974) (xy 38.225476 -124.630942) (xy 38.225476 -125.486414) (xy 51.785012 -125.486414)
			(xy 51.785012 -124.622814) (xy 51.785502 -124.592846) (xy 51.793325 -124.533424) (xy 51.808838 -124.475531)
			(xy 51.831774 -124.420158) (xy 51.861741 -124.368252) (xy 51.898228 -124.320702) (xy 51.940608 -124.278322)
			(xy 51.988158 -124.241835) (xy 52.040064 -124.211868) (xy 52.095437 -124.188932) (xy 52.15333 -124.173419)
			(xy 52.212752 -124.165596) (xy 52.272688 -124.165596) (xy 52.33211 -124.173419) (xy 52.390003 -124.188932)
			(xy 52.445376 -124.211868) (xy 52.497282 -124.241835) (xy 52.544832 -124.278322) (xy 52.587212 -124.320702)
			(xy 52.623699 -124.368252) (xy 52.653666 -124.420158) (xy 52.676602 -124.475531) (xy 52.692115 -124.533424)
			(xy 52.699938 -124.592846) (xy 52.700428 -124.622814) (xy 52.700428 -124.967238) (xy 64.745108 -124.967238)
			(xy 64.745108 -124.103638) (xy 64.745598 -124.073654) (xy 64.753426 -124.014198) (xy 64.768947 -123.956273)
			(xy 64.791896 -123.900869) (xy 64.82188 -123.848935) (xy 64.858386 -123.801359) (xy 64.900791 -123.758954)
			(xy 64.948367 -123.722448) (xy 65.000301 -123.692464) (xy 65.055705 -123.669515) (xy 65.11363 -123.653994)
			(xy 65.173086 -123.646166) (xy 65.233054 -123.646166) (xy 65.29251 -123.653994) (xy 65.350435 -123.669515)
			(xy 65.405839 -123.692464) (xy 65.457773 -123.722448) (xy 65.505349 -123.758954) (xy 65.547754 -123.801359)
			(xy 65.58426 -123.848935) (xy 65.614244 -123.900869) (xy 65.637193 -123.956273) (xy 65.652714 -124.014198)
			(xy 65.660542 -124.073654) (xy 65.661032 -124.103638) (xy 65.661032 -124.965714) (xy 83.716368 -124.965714)
			(xy 83.716368 -124.102114) (xy 83.716858 -124.07213) (xy 83.724686 -124.012674) (xy 83.740207 -123.954749)
			(xy 83.763156 -123.899345) (xy 83.79314 -123.847411) (xy 83.829646 -123.799835) (xy 83.872051 -123.75743)
			(xy 83.919627 -123.720924) (xy 83.971561 -123.69094) (xy 84.026965 -123.667991) (xy 84.08489 -123.65247)
			(xy 84.144346 -123.644642) (xy 84.204314 -123.644642) (xy 84.26377 -123.65247) (xy 84.321695 -123.667991)
			(xy 84.369615 -123.68784) (xy 150.767796 -123.68784) (xy 150.767796 -122.82424) (xy 150.768286 -122.794256)
			(xy 150.776114 -122.7348) (xy 150.791635 -122.676875) (xy 150.814584 -122.621471) (xy 150.844568 -122.569537)
			(xy 150.881074 -122.521961) (xy 150.923479 -122.479556) (xy 150.971055 -122.44305) (xy 151.022989 -122.413066)
			(xy 151.078393 -122.390117) (xy 151.136318 -122.374596) (xy 151.195774 -122.366768) (xy 151.255742 -122.366768)
			(xy 151.315198 -122.374596) (xy 151.373123 -122.390117) (xy 151.428527 -122.413066) (xy 151.480461 -122.44305)
			(xy 151.528037 -122.479556) (xy 151.570442 -122.521961) (xy 151.606948 -122.569537) (xy 151.636932 -122.621471)
			(xy 151.659881 -122.676875) (xy 151.675402 -122.7348) (xy 151.68323 -122.794256) (xy 151.68372 -122.82424)
			(xy 151.68372 -123.686316) (xy 169.739056 -123.686316) (xy 169.739056 -122.822716) (xy 169.739546 -122.792732)
			(xy 169.747374 -122.733276) (xy 169.762895 -122.675351) (xy 169.785844 -122.619947) (xy 169.815828 -122.568013)
			(xy 169.852334 -122.520437) (xy 169.894739 -122.478032) (xy 169.942315 -122.441526) (xy 169.994249 -122.411542)
			(xy 170.049653 -122.388593) (xy 170.107578 -122.373072) (xy 170.167034 -122.365244) (xy 170.227002 -122.365244)
			(xy 170.286458 -122.373072) (xy 170.344383 -122.388593) (xy 170.399787 -122.411542) (xy 170.451721 -122.441526)
			(xy 170.499297 -122.478032) (xy 170.541702 -122.520437) (xy 170.578208 -122.568013) (xy 170.608192 -122.619947)
			(xy 170.631141 -122.675351) (xy 170.646662 -122.733276) (xy 170.65449 -122.792732) (xy 170.65498 -122.822716)
			(xy 170.65498 -123.16714) (xy 182.69966 -123.16714) (xy 182.69966 -122.30354) (xy 182.70015 -122.273572)
			(xy 182.707973 -122.21415) (xy 182.723486 -122.156257) (xy 182.746422 -122.100884) (xy 182.776389 -122.048978)
			(xy 182.812876 -122.001428) (xy 182.855256 -121.959048) (xy 182.902806 -121.922561) (xy 182.954712 -121.892594)
			(xy 183.010085 -121.869658) (xy 183.067978 -121.854145) (xy 183.1274 -121.846322) (xy 183.187336 -121.846322)
			(xy 183.246758 -121.854145) (xy 183.304651 -121.869658) (xy 183.360024 -121.892594) (xy 183.41193 -121.922561)
			(xy 183.45948 -121.959048) (xy 183.50186 -122.001428) (xy 183.538347 -122.048978) (xy 183.568314 -122.100884)
			(xy 183.59125 -122.156257) (xy 183.606763 -122.21415) (xy 183.614586 -122.273572) (xy 183.615076 -122.30354)
			(xy 183.615076 -123.159266) (xy 197.174612 -123.159266) (xy 197.174612 -122.295666) (xy 197.175102 -122.265698)
			(xy 197.182925 -122.206276) (xy 197.198438 -122.148383) (xy 197.221374 -122.09301) (xy 197.251341 -122.041104)
			(xy 197.287828 -121.993554) (xy 197.330208 -121.951174) (xy 197.377758 -121.914687) (xy 197.429664 -121.88472)
			(xy 197.485037 -121.861784) (xy 197.54293 -121.846271) (xy 197.602352 -121.838448) (xy 197.662288 -121.838448)
			(xy 197.72171 -121.846271) (xy 197.779603 -121.861784) (xy 197.834976 -121.88472) (xy 197.851649 -121.894346)
			(xy 269.509748 -121.894346) (xy 269.509748 -121.030746) (xy 269.510238 -121.000762) (xy 269.518066 -120.941306)
			(xy 269.533587 -120.883381) (xy 269.556536 -120.827977) (xy 269.58652 -120.776043) (xy 269.623026 -120.728467)
			(xy 269.665431 -120.686062) (xy 269.713007 -120.649556) (xy 269.764941 -120.619572) (xy 269.820345 -120.596623)
			(xy 269.87827 -120.581102) (xy 269.937726 -120.573274) (xy 269.997694 -120.573274) (xy 270.05715 -120.581102)
			(xy 270.115075 -120.596623) (xy 270.170479 -120.619572) (xy 270.222413 -120.649556) (xy 270.269989 -120.686062)
			(xy 270.312394 -120.728467) (xy 270.3489 -120.776043) (xy 270.378884 -120.827977) (xy 270.401833 -120.883381)
			(xy 270.417354 -120.941306) (xy 270.425182 -121.000762) (xy 270.425672 -121.030746) (xy 270.425672 -121.886472)
			(xy 283.9847 -121.886472) (xy 283.9847 -121.022872) (xy 283.98519 -120.992888) (xy 283.993018 -120.933432)
			(xy 284.008539 -120.875507) (xy 284.031488 -120.820103) (xy 284.061472 -120.768169) (xy 284.097978 -120.720593)
			(xy 284.140383 -120.678188) (xy 284.187959 -120.641682) (xy 284.239893 -120.611698) (xy 284.295297 -120.588749)
			(xy 284.353222 -120.573228) (xy 284.412678 -120.5654) (xy 284.472646 -120.5654) (xy 284.532102 -120.573228)
			(xy 284.590027 -120.588749) (xy 284.645431 -120.611698) (xy 284.697365 -120.641682) (xy 284.744941 -120.678188)
			(xy 284.787346 -120.720593) (xy 284.823852 -120.768169) (xy 284.853836 -120.820103) (xy 284.876785 -120.875507)
			(xy 284.892306 -120.933432) (xy 284.900134 -120.992888) (xy 284.900624 -121.022872) (xy 284.900624 -121.367296)
			(xy 296.945304 -121.367296) (xy 296.945304 -120.503696) (xy 296.945794 -120.473728) (xy 296.953617 -120.414306)
			(xy 296.96913 -120.356413) (xy 296.992066 -120.30104) (xy 297.022033 -120.249134) (xy 297.05852 -120.201584)
			(xy 297.1009 -120.159204) (xy 297.14845 -120.122717) (xy 297.200356 -120.09275) (xy 297.255729 -120.069814)
			(xy 297.313622 -120.054301) (xy 297.373044 -120.046478) (xy 297.43298 -120.046478) (xy 297.492402 -120.054301)
			(xy 297.550295 -120.069814) (xy 297.605668 -120.09275) (xy 297.657574 -120.122717) (xy 297.705124 -120.159204)
			(xy 297.747504 -120.201584) (xy 297.783991 -120.249134) (xy 297.813958 -120.30104) (xy 297.836894 -120.356413)
			(xy 297.852407 -120.414306) (xy 297.86023 -120.473728) (xy 297.86072 -120.503696) (xy 297.86072 -121.365772)
			(xy 315.916564 -121.365772) (xy 315.916564 -120.502172) (xy 315.917054 -120.472204) (xy 315.924877 -120.412782)
			(xy 315.94039 -120.354889) (xy 315.963326 -120.299516) (xy 315.993293 -120.24761) (xy 316.02978 -120.20006)
			(xy 316.07216 -120.15768) (xy 316.11971 -120.121193) (xy 316.171616 -120.091226) (xy 316.226989 -120.06829)
			(xy 316.284882 -120.052777) (xy 316.344304 -120.044954) (xy 316.40424 -120.044954) (xy 316.463662 -120.052777)
			(xy 316.521555 -120.06829) (xy 316.568893 -120.087898) (xy 382.967992 -120.087898) (xy 382.967992 -119.224298)
			(xy 382.968482 -119.19433) (xy 382.976305 -119.134908) (xy 382.991818 -119.077015) (xy 383.014754 -119.021642)
			(xy 383.044721 -118.969736) (xy 383.081208 -118.922186) (xy 383.123588 -118.879806) (xy 383.171138 -118.843319)
			(xy 383.223044 -118.813352) (xy 383.278417 -118.790416) (xy 383.33631 -118.774903) (xy 383.395732 -118.76708)
			(xy 383.455668 -118.76708) (xy 383.51509 -118.774903) (xy 383.572983 -118.790416) (xy 383.628356 -118.813352)
			(xy 383.680262 -118.843319) (xy 383.727812 -118.879806) (xy 383.770192 -118.922186) (xy 383.806679 -118.969736)
			(xy 383.836646 -119.021642) (xy 383.859582 -119.077015) (xy 383.875095 -119.134908) (xy 383.882918 -119.19433)
			(xy 383.883408 -119.224298) (xy 383.883408 -120.086374) (xy 401.939252 -120.086374) (xy 401.939252 -119.222774)
			(xy 401.939742 -119.192806) (xy 401.947565 -119.133384) (xy 401.963078 -119.075491) (xy 401.986014 -119.020118)
			(xy 402.015981 -118.968212) (xy 402.052468 -118.920662) (xy 402.094848 -118.878282) (xy 402.142398 -118.841795)
			(xy 402.194304 -118.811828) (xy 402.249677 -118.788892) (xy 402.30757 -118.773379) (xy 402.366992 -118.765556)
			(xy 402.426928 -118.765556) (xy 402.48635 -118.773379) (xy 402.544243 -118.788892) (xy 402.599616 -118.811828)
			(xy 402.651522 -118.841795) (xy 402.699072 -118.878282) (xy 402.741452 -118.920662) (xy 402.777939 -118.968212)
			(xy 402.807906 -119.020118) (xy 402.830842 -119.075491) (xy 402.846355 -119.133384) (xy 402.854178 -119.192806)
			(xy 402.854668 -119.222774) (xy 402.854668 -119.567198) (xy 414.899348 -119.567198) (xy 414.899348 -118.703598)
			(xy 414.899838 -118.673614) (xy 414.907666 -118.614158) (xy 414.923187 -118.556233) (xy 414.946136 -118.500829)
			(xy 414.97612 -118.448895) (xy 415.012626 -118.401319) (xy 415.055031 -118.358914) (xy 415.102607 -118.322408)
			(xy 415.154541 -118.292424) (xy 415.209945 -118.269475) (xy 415.26787 -118.253954) (xy 415.327326 -118.246126)
			(xy 415.387294 -118.246126) (xy 415.44675 -118.253954) (xy 415.504675 -118.269475) (xy 415.560079 -118.292424)
			(xy 415.612013 -118.322408) (xy 415.659589 -118.358914) (xy 415.701994 -118.401319) (xy 415.7385 -118.448895)
			(xy 415.768484 -118.500829) (xy 415.791433 -118.556233) (xy 415.806954 -118.614158) (xy 415.814782 -118.673614)
			(xy 415.815272 -118.703598) (xy 415.815272 -119.559324) (xy 429.3743 -119.559324) (xy 429.3743 -118.695724)
			(xy 429.37479 -118.66574) (xy 429.382618 -118.606284) (xy 429.398139 -118.548359) (xy 429.421088 -118.492955)
			(xy 429.451072 -118.441021) (xy 429.487578 -118.393445) (xy 429.529983 -118.35104) (xy 429.577559 -118.314534)
			(xy 429.629493 -118.28455) (xy 429.684897 -118.261601) (xy 429.742822 -118.24608) (xy 429.802278 -118.238252)
			(xy 429.862246 -118.238252) (xy 429.921702 -118.24608) (xy 429.979627 -118.261601) (xy 430.035031 -118.28455)
			(xy 430.086965 -118.314534) (xy 430.134541 -118.35104) (xy 430.176946 -118.393445) (xy 430.213452 -118.441021)
			(xy 430.243436 -118.492955) (xy 430.266385 -118.548359) (xy 430.281906 -118.606284) (xy 430.289734 -118.66574)
			(xy 430.290224 -118.695724) (xy 430.290224 -119.559324) (xy 430.289734 -119.589308) (xy 430.281906 -119.648764)
			(xy 430.266385 -119.706689) (xy 430.243436 -119.762093) (xy 430.213452 -119.814027) (xy 430.176946 -119.861603)
			(xy 430.134541 -119.904008) (xy 430.086965 -119.940514) (xy 430.035031 -119.970498) (xy 429.979627 -119.993447)
			(xy 429.921702 -120.008968) (xy 429.862246 -120.016796) (xy 429.802278 -120.016796) (xy 429.742822 -120.008968)
			(xy 429.684897 -119.993447) (xy 429.629493 -119.970498) (xy 429.577559 -119.940514) (xy 429.529983 -119.904008)
			(xy 429.487578 -119.861603) (xy 429.451072 -119.814027) (xy 429.421088 -119.762093) (xy 429.398139 -119.706689)
			(xy 429.382618 -119.648764) (xy 429.37479 -119.589308) (xy 429.3743 -119.559324) (xy 415.815272 -119.559324)
			(xy 415.815272 -119.567198) (xy 415.814782 -119.597182) (xy 415.806954 -119.656638) (xy 415.791433 -119.714563)
			(xy 415.768484 -119.769967) (xy 415.7385 -119.821901) (xy 415.701994 -119.869477) (xy 415.659589 -119.911882)
			(xy 415.612013 -119.948388) (xy 415.560079 -119.978372) (xy 415.504675 -120.001321) (xy 415.44675 -120.016842)
			(xy 415.387294 -120.02467) (xy 415.327326 -120.02467) (xy 415.26787 -120.016842) (xy 415.209945 -120.001321)
			(xy 415.154541 -119.978372) (xy 415.102607 -119.948388) (xy 415.055031 -119.911882) (xy 415.012626 -119.869477)
			(xy 414.97612 -119.821901) (xy 414.946136 -119.769967) (xy 414.923187 -119.714563) (xy 414.907666 -119.656638)
			(xy 414.899838 -119.597182) (xy 414.899348 -119.567198) (xy 402.854668 -119.567198) (xy 402.854668 -120.086374)
			(xy 402.854178 -120.116342) (xy 402.846355 -120.175764) (xy 402.830842 -120.233657) (xy 402.807906 -120.28903)
			(xy 402.777939 -120.340936) (xy 402.741452 -120.388486) (xy 402.699072 -120.430866) (xy 402.651522 -120.467353)
			(xy 402.599616 -120.49732) (xy 402.544243 -120.520256) (xy 402.48635 -120.535769) (xy 402.426928 -120.543592)
			(xy 402.366992 -120.543592) (xy 402.30757 -120.535769) (xy 402.249677 -120.520256) (xy 402.194304 -120.49732)
			(xy 402.142398 -120.467353) (xy 402.094848 -120.430866) (xy 402.052468 -120.388486) (xy 402.015981 -120.340936)
			(xy 401.986014 -120.28903) (xy 401.963078 -120.233657) (xy 401.947565 -120.175764) (xy 401.939742 -120.116342)
			(xy 401.939252 -120.086374) (xy 383.883408 -120.086374) (xy 383.883408 -120.087898) (xy 383.882918 -120.117866)
			(xy 383.875095 -120.177288) (xy 383.859582 -120.235181) (xy 383.836646 -120.290554) (xy 383.806679 -120.34246)
			(xy 383.770192 -120.39001) (xy 383.727812 -120.43239) (xy 383.680262 -120.468877) (xy 383.628356 -120.498844)
			(xy 383.572983 -120.52178) (xy 383.51509 -120.537293) (xy 383.455668 -120.545116) (xy 383.395732 -120.545116)
			(xy 383.33631 -120.537293) (xy 383.278417 -120.52178) (xy 383.223044 -120.498844) (xy 383.171138 -120.468877)
			(xy 383.123588 -120.43239) (xy 383.081208 -120.39001) (xy 383.044721 -120.34246) (xy 383.014754 -120.290554)
			(xy 382.991818 -120.235181) (xy 382.976305 -120.177288) (xy 382.968482 -120.117866) (xy 382.967992 -120.087898)
			(xy 316.568893 -120.087898) (xy 316.576928 -120.091226) (xy 316.628834 -120.121193) (xy 316.676384 -120.15768)
			(xy 316.718764 -120.20006) (xy 316.755251 -120.24761) (xy 316.785218 -120.299516) (xy 316.808154 -120.354889)
			(xy 316.823667 -120.412782) (xy 316.83149 -120.472204) (xy 316.83198 -120.502172) (xy 316.83198 -121.365772)
			(xy 316.83149 -121.39574) (xy 316.823667 -121.455162) (xy 316.808154 -121.513055) (xy 316.785218 -121.568428)
			(xy 316.755251 -121.620334) (xy 316.718764 -121.667884) (xy 316.676384 -121.710264) (xy 316.628834 -121.746751)
			(xy 316.576928 -121.776718) (xy 316.521555 -121.799654) (xy 316.463662 -121.815167) (xy 316.40424 -121.82299)
			(xy 316.344304 -121.82299) (xy 316.284882 -121.815167) (xy 316.226989 -121.799654) (xy 316.171616 -121.776718)
			(xy 316.11971 -121.746751) (xy 316.07216 -121.710264) (xy 316.02978 -121.667884) (xy 315.993293 -121.620334)
			(xy 315.963326 -121.568428) (xy 315.94039 -121.513055) (xy 315.924877 -121.455162) (xy 315.917054 -121.39574)
			(xy 315.916564 -121.365772) (xy 297.86072 -121.365772) (xy 297.86072 -121.367296) (xy 297.86023 -121.397264)
			(xy 297.852407 -121.456686) (xy 297.836894 -121.514579) (xy 297.813958 -121.569952) (xy 297.783991 -121.621858)
			(xy 297.747504 -121.669408) (xy 297.705124 -121.711788) (xy 297.657574 -121.748275) (xy 297.605668 -121.778242)
			(xy 297.550295 -121.801178) (xy 297.492402 -121.816691) (xy 297.43298 -121.824514) (xy 297.373044 -121.824514)
			(xy 297.313622 -121.816691) (xy 297.255729 -121.801178) (xy 297.200356 -121.778242) (xy 297.14845 -121.748275)
			(xy 297.1009 -121.711788) (xy 297.05852 -121.669408) (xy 297.022033 -121.621858) (xy 296.992066 -121.569952)
			(xy 296.96913 -121.514579) (xy 296.953617 -121.456686) (xy 296.945794 -121.397264) (xy 296.945304 -121.367296)
			(xy 284.900624 -121.367296) (xy 284.900624 -121.886472) (xy 284.900134 -121.916456) (xy 284.892306 -121.975912)
			(xy 284.876785 -122.033837) (xy 284.853836 -122.089241) (xy 284.823852 -122.141175) (xy 284.787346 -122.188751)
			(xy 284.744941 -122.231156) (xy 284.697365 -122.267662) (xy 284.645431 -122.297646) (xy 284.590027 -122.320595)
			(xy 284.532102 -122.336116) (xy 284.472646 -122.343944) (xy 284.412678 -122.343944) (xy 284.353222 -122.336116)
			(xy 284.295297 -122.320595) (xy 284.239893 -122.297646) (xy 284.187959 -122.267662) (xy 284.140383 -122.231156)
			(xy 284.097978 -122.188751) (xy 284.061472 -122.141175) (xy 284.031488 -122.089241) (xy 284.008539 -122.033837)
			(xy 283.993018 -121.975912) (xy 283.98519 -121.916456) (xy 283.9847 -121.886472) (xy 270.425672 -121.886472)
			(xy 270.425672 -121.894346) (xy 270.425182 -121.92433) (xy 270.417354 -121.983786) (xy 270.401833 -122.041711)
			(xy 270.378884 -122.097115) (xy 270.3489 -122.149049) (xy 270.312394 -122.196625) (xy 270.269989 -122.23903)
			(xy 270.222413 -122.275536) (xy 270.170479 -122.30552) (xy 270.115075 -122.328469) (xy 270.05715 -122.34399)
			(xy 269.997694 -122.351818) (xy 269.937726 -122.351818) (xy 269.87827 -122.34399) (xy 269.820345 -122.328469)
			(xy 269.764941 -122.30552) (xy 269.713007 -122.275536) (xy 269.665431 -122.23903) (xy 269.623026 -122.196625)
			(xy 269.58652 -122.149049) (xy 269.556536 -122.097115) (xy 269.533587 -122.041711) (xy 269.518066 -121.983786)
			(xy 269.510238 -121.92433) (xy 269.509748 -121.894346) (xy 197.851649 -121.894346) (xy 197.886882 -121.914687)
			(xy 197.934432 -121.951174) (xy 197.976812 -121.993554) (xy 198.013299 -122.041104) (xy 198.043266 -122.09301)
			(xy 198.066202 -122.148383) (xy 198.081715 -122.206276) (xy 198.089538 -122.265698) (xy 198.090028 -122.295666)
			(xy 198.090028 -123.159266) (xy 198.089538 -123.189234) (xy 198.081715 -123.248656) (xy 198.066202 -123.306549)
			(xy 198.043266 -123.361922) (xy 198.013299 -123.413828) (xy 197.976812 -123.461378) (xy 197.934432 -123.503758)
			(xy 197.886882 -123.540245) (xy 197.834976 -123.570212) (xy 197.779603 -123.593148) (xy 197.72171 -123.608661)
			(xy 197.662288 -123.616484) (xy 197.602352 -123.616484) (xy 197.54293 -123.608661) (xy 197.485037 -123.593148)
			(xy 197.429664 -123.570212) (xy 197.377758 -123.540245) (xy 197.330208 -123.503758) (xy 197.287828 -123.461378)
			(xy 197.251341 -123.413828) (xy 197.221374 -123.361922) (xy 197.198438 -123.306549) (xy 197.182925 -123.248656)
			(xy 197.175102 -123.189234) (xy 197.174612 -123.159266) (xy 183.615076 -123.159266) (xy 183.615076 -123.16714)
			(xy 183.614586 -123.197108) (xy 183.606763 -123.25653) (xy 183.59125 -123.314423) (xy 183.568314 -123.369796)
			(xy 183.538347 -123.421702) (xy 183.50186 -123.469252) (xy 183.45948 -123.511632) (xy 183.41193 -123.548119)
			(xy 183.360024 -123.578086) (xy 183.304651 -123.601022) (xy 183.246758 -123.616535) (xy 183.187336 -123.624358)
			(xy 183.1274 -123.624358) (xy 183.067978 -123.616535) (xy 183.010085 -123.601022) (xy 182.954712 -123.578086)
			(xy 182.902806 -123.548119) (xy 182.855256 -123.511632) (xy 182.812876 -123.469252) (xy 182.776389 -123.421702)
			(xy 182.746422 -123.369796) (xy 182.723486 -123.314423) (xy 182.707973 -123.25653) (xy 182.70015 -123.197108)
			(xy 182.69966 -123.16714) (xy 170.65498 -123.16714) (xy 170.65498 -123.686316) (xy 170.65449 -123.7163)
			(xy 170.646662 -123.775756) (xy 170.631141 -123.833681) (xy 170.608192 -123.889085) (xy 170.578208 -123.941019)
			(xy 170.541702 -123.988595) (xy 170.499297 -124.031) (xy 170.451721 -124.067506) (xy 170.399787 -124.09749)
			(xy 170.344383 -124.120439) (xy 170.286458 -124.13596) (xy 170.227002 -124.143788) (xy 170.167034 -124.143788)
			(xy 170.107578 -124.13596) (xy 170.049653 -124.120439) (xy 169.994249 -124.09749) (xy 169.942315 -124.067506)
			(xy 169.894739 -124.031) (xy 169.852334 -123.988595) (xy 169.815828 -123.941019) (xy 169.785844 -123.889085)
			(xy 169.762895 -123.833681) (xy 169.747374 -123.775756) (xy 169.739546 -123.7163) (xy 169.739056 -123.686316)
			(xy 151.68372 -123.686316) (xy 151.68372 -123.68784) (xy 151.68323 -123.717824) (xy 151.675402 -123.77728)
			(xy 151.659881 -123.835205) (xy 151.636932 -123.890609) (xy 151.606948 -123.942543) (xy 151.570442 -123.990119)
			(xy 151.528037 -124.032524) (xy 151.480461 -124.06903) (xy 151.428527 -124.099014) (xy 151.373123 -124.121963)
			(xy 151.315198 -124.137484) (xy 151.255742 -124.145312) (xy 151.195774 -124.145312) (xy 151.136318 -124.137484)
			(xy 151.078393 -124.121963) (xy 151.022989 -124.099014) (xy 150.971055 -124.06903) (xy 150.923479 -124.032524)
			(xy 150.881074 -123.990119) (xy 150.844568 -123.942543) (xy 150.814584 -123.890609) (xy 150.791635 -123.835205)
			(xy 150.776114 -123.77728) (xy 150.768286 -123.717824) (xy 150.767796 -123.68784) (xy 84.369615 -123.68784)
			(xy 84.377099 -123.69094) (xy 84.429033 -123.720924) (xy 84.476609 -123.75743) (xy 84.519014 -123.799835)
			(xy 84.55552 -123.847411) (xy 84.585504 -123.899345) (xy 84.608453 -123.954749) (xy 84.623974 -124.012674)
			(xy 84.631802 -124.07213) (xy 84.632292 -124.102114) (xy 84.632292 -124.965714) (xy 84.631802 -124.995698)
			(xy 84.623974 -125.055154) (xy 84.608453 -125.113079) (xy 84.585504 -125.168483) (xy 84.55552 -125.220417)
			(xy 84.519014 -125.267993) (xy 84.476609 -125.310398) (xy 84.429033 -125.346904) (xy 84.377099 -125.376888)
			(xy 84.321695 -125.399837) (xy 84.26377 -125.415358) (xy 84.204314 -125.423186) (xy 84.144346 -125.423186)
			(xy 84.08489 -125.415358) (xy 84.026965 -125.399837) (xy 83.971561 -125.376888) (xy 83.919627 -125.346904)
			(xy 83.872051 -125.310398) (xy 83.829646 -125.267993) (xy 83.79314 -125.220417) (xy 83.763156 -125.168483)
			(xy 83.740207 -125.113079) (xy 83.724686 -125.055154) (xy 83.716858 -124.995698) (xy 83.716368 -124.965714)
			(xy 65.661032 -124.965714) (xy 65.661032 -124.967238) (xy 65.660542 -124.997222) (xy 65.652714 -125.056678)
			(xy 65.637193 -125.114603) (xy 65.614244 -125.170007) (xy 65.58426 -125.221941) (xy 65.547754 -125.269517)
			(xy 65.505349 -125.311922) (xy 65.457773 -125.348428) (xy 65.405839 -125.378412) (xy 65.350435 -125.401361)
			(xy 65.29251 -125.416882) (xy 65.233054 -125.42471) (xy 65.173086 -125.42471) (xy 65.11363 -125.416882)
			(xy 65.055705 -125.401361) (xy 65.000301 -125.378412) (xy 64.948367 -125.348428) (xy 64.900791 -125.311922)
			(xy 64.858386 -125.269517) (xy 64.82188 -125.221941) (xy 64.791896 -125.170007) (xy 64.768947 -125.114603)
			(xy 64.753426 -125.056678) (xy 64.745598 -124.997222) (xy 64.745108 -124.967238) (xy 52.700428 -124.967238)
			(xy 52.700428 -125.486414) (xy 52.700295 -125.494542) (xy 153.409904 -125.494542) (xy 153.409904 -124.630942)
			(xy 153.410394 -124.600958) (xy 153.418222 -124.541502) (xy 153.433743 -124.483577) (xy 153.456692 -124.428173)
			(xy 153.486676 -124.376239) (xy 153.523182 -124.328663) (xy 153.565587 -124.286258) (xy 153.613163 -124.249752)
			(xy 153.665097 -124.219768) (xy 153.720501 -124.196819) (xy 153.778426 -124.181298) (xy 153.837882 -124.17347)
			(xy 153.89785 -124.17347) (xy 153.957306 -124.181298) (xy 154.015231 -124.196819) (xy 154.070635 -124.219768)
			(xy 154.122569 -124.249752) (xy 154.170145 -124.286258) (xy 154.21255 -124.328663) (xy 154.249056 -124.376239)
			(xy 154.27904 -124.428173) (xy 154.301989 -124.483577) (xy 154.31751 -124.541502) (xy 154.325338 -124.600958)
			(xy 154.325828 -124.630942) (xy 154.325828 -125.486414) (xy 167.884856 -125.486414) (xy 167.884856 -124.622814)
			(xy 167.885346 -124.59283) (xy 167.893174 -124.533374) (xy 167.908695 -124.475449) (xy 167.931644 -124.420045)
			(xy 167.961628 -124.368111) (xy 167.998134 -124.320535) (xy 168.040539 -124.27813) (xy 168.088115 -124.241624)
			(xy 168.140049 -124.21164) (xy 168.195453 -124.188691) (xy 168.253378 -124.17317) (xy 168.312834 -124.165342)
			(xy 168.372802 -124.165342) (xy 168.432258 -124.17317) (xy 168.490183 -124.188691) (xy 168.545587 -124.21164)
			(xy 168.597521 -124.241624) (xy 168.645097 -124.27813) (xy 168.687502 -124.320535) (xy 168.724008 -124.368111)
			(xy 168.753992 -124.420045) (xy 168.776941 -124.475449) (xy 168.792462 -124.533374) (xy 168.80029 -124.59283)
			(xy 168.80078 -124.622814) (xy 168.80078 -124.967238) (xy 180.84546 -124.967238) (xy 180.84546 -124.103638)
			(xy 180.84595 -124.07367) (xy 180.853773 -124.014248) (xy 180.869286 -123.956355) (xy 180.892222 -123.900982)
			(xy 180.922189 -123.849076) (xy 180.958676 -123.801526) (xy 181.001056 -123.759146) (xy 181.048606 -123.722659)
			(xy 181.100512 -123.692692) (xy 181.155885 -123.669756) (xy 181.213778 -123.654243) (xy 181.2732 -123.64642)
			(xy 181.333136 -123.64642) (xy 181.392558 -123.654243) (xy 181.450451 -123.669756) (xy 181.505824 -123.692692)
			(xy 181.55773 -123.722659) (xy 181.60528 -123.759146) (xy 181.64766 -123.801526) (xy 181.684147 -123.849076)
			(xy 181.714114 -123.900982) (xy 181.73705 -123.956355) (xy 181.752563 -124.014248) (xy 181.760386 -124.07367)
			(xy 181.760876 -124.103638) (xy 181.760876 -124.965714) (xy 199.81672 -124.965714) (xy 199.81672 -124.102114)
			(xy 199.81721 -124.072146) (xy 199.825033 -124.012724) (xy 199.840546 -123.954831) (xy 199.863482 -123.899458)
			(xy 199.893449 -123.847552) (xy 199.929936 -123.800002) (xy 199.972316 -123.757622) (xy 200.019866 -123.721135)
			(xy 200.071772 -123.691168) (xy 200.127145 -123.668232) (xy 200.185038 -123.652719) (xy 200.24446 -123.644896)
			(xy 200.304396 -123.644896) (xy 200.363818 -123.652719) (xy 200.421711 -123.668232) (xy 200.469049 -123.68784)
			(xy 266.86764 -123.68784) (xy 266.86764 -122.82424) (xy 266.86813 -122.794256) (xy 266.875958 -122.7348)
			(xy 266.891479 -122.676875) (xy 266.914428 -122.621471) (xy 266.944412 -122.569537) (xy 266.980918 -122.521961)
			(xy 267.023323 -122.479556) (xy 267.070899 -122.44305) (xy 267.122833 -122.413066) (xy 267.178237 -122.390117)
			(xy 267.236162 -122.374596) (xy 267.295618 -122.366768) (xy 267.355586 -122.366768) (xy 267.415042 -122.374596)
			(xy 267.472967 -122.390117) (xy 267.528371 -122.413066) (xy 267.580305 -122.44305) (xy 267.627881 -122.479556)
			(xy 267.670286 -122.521961) (xy 267.706792 -122.569537) (xy 267.736776 -122.621471) (xy 267.759725 -122.676875)
			(xy 267.775246 -122.7348) (xy 267.783074 -122.794256) (xy 267.783564 -122.82424) (xy 267.783564 -123.686316)
			(xy 285.8389 -123.686316) (xy 285.8389 -122.822716) (xy 285.83939 -122.792732) (xy 285.847218 -122.733276)
			(xy 285.862739 -122.675351) (xy 285.885688 -122.619947) (xy 285.915672 -122.568013) (xy 285.952178 -122.520437)
			(xy 285.994583 -122.478032) (xy 286.042159 -122.441526) (xy 286.094093 -122.411542) (xy 286.149497 -122.388593)
			(xy 286.207422 -122.373072) (xy 286.266878 -122.365244) (xy 286.326846 -122.365244) (xy 286.386302 -122.373072)
			(xy 286.444227 -122.388593) (xy 286.499631 -122.411542) (xy 286.551565 -122.441526) (xy 286.599141 -122.478032)
			(xy 286.641546 -122.520437) (xy 286.678052 -122.568013) (xy 286.708036 -122.619947) (xy 286.730985 -122.675351)
			(xy 286.746506 -122.733276) (xy 286.754334 -122.792732) (xy 286.754824 -122.822716) (xy 286.754824 -123.16714)
			(xy 298.799504 -123.16714) (xy 298.799504 -122.30354) (xy 298.799994 -122.273572) (xy 298.807817 -122.21415)
			(xy 298.82333 -122.156257) (xy 298.846266 -122.100884) (xy 298.876233 -122.048978) (xy 298.91272 -122.001428)
			(xy 298.9551 -121.959048) (xy 299.00265 -121.922561) (xy 299.054556 -121.892594) (xy 299.109929 -121.869658)
			(xy 299.167822 -121.854145) (xy 299.227244 -121.846322) (xy 299.28718 -121.846322) (xy 299.346602 -121.854145)
			(xy 299.404495 -121.869658) (xy 299.459868 -121.892594) (xy 299.511774 -121.922561) (xy 299.559324 -121.959048)
			(xy 299.601704 -122.001428) (xy 299.638191 -122.048978) (xy 299.668158 -122.100884) (xy 299.691094 -122.156257)
			(xy 299.706607 -122.21415) (xy 299.71443 -122.273572) (xy 299.71492 -122.30354) (xy 299.71492 -123.159266)
			(xy 313.274456 -123.159266) (xy 313.274456 -122.295666) (xy 313.274946 -122.265698) (xy 313.282769 -122.206276)
			(xy 313.298282 -122.148383) (xy 313.321218 -122.09301) (xy 313.351185 -122.041104) (xy 313.387672 -121.993554)
			(xy 313.430052 -121.951174) (xy 313.477602 -121.914687) (xy 313.529508 -121.88472) (xy 313.584881 -121.861784)
			(xy 313.642774 -121.846271) (xy 313.702196 -121.838448) (xy 313.762132 -121.838448) (xy 313.821554 -121.846271)
			(xy 313.879447 -121.861784) (xy 313.93482 -121.88472) (xy 313.951493 -121.894346) (xy 385.6101 -121.894346)
			(xy 385.6101 -121.030746) (xy 385.61059 -121.000778) (xy 385.618413 -120.941356) (xy 385.633926 -120.883463)
			(xy 385.656862 -120.82809) (xy 385.686829 -120.776184) (xy 385.723316 -120.728634) (xy 385.765696 -120.686254)
			(xy 385.813246 -120.649767) (xy 385.865152 -120.6198) (xy 385.920525 -120.596864) (xy 385.978418 -120.581351)
			(xy 386.03784 -120.573528) (xy 386.097776 -120.573528) (xy 386.157198 -120.581351) (xy 386.215091 -120.596864)
			(xy 386.270464 -120.6198) (xy 386.32237 -120.649767) (xy 386.36992 -120.686254) (xy 386.4123 -120.728634)
			(xy 386.448787 -120.776184) (xy 386.478754 -120.82809) (xy 386.50169 -120.883463) (xy 386.517203 -120.941356)
			(xy 386.525026 -121.000778) (xy 386.525516 -121.030746) (xy 386.525516 -121.886472) (xy 400.085052 -121.886472)
			(xy 400.085052 -121.022872) (xy 400.085542 -120.992904) (xy 400.093365 -120.933482) (xy 400.108878 -120.875589)
			(xy 400.131814 -120.820216) (xy 400.161781 -120.76831) (xy 400.198268 -120.72076) (xy 400.240648 -120.67838)
			(xy 400.288198 -120.641893) (xy 400.340104 -120.611926) (xy 400.395477 -120.58899) (xy 400.45337 -120.573477)
			(xy 400.512792 -120.565654) (xy 400.572728 -120.565654) (xy 400.63215 -120.573477) (xy 400.690043 -120.58899)
			(xy 400.745416 -120.611926) (xy 400.797322 -120.641893) (xy 400.844872 -120.67838) (xy 400.887252 -120.72076)
			(xy 400.923739 -120.76831) (xy 400.953706 -120.820216) (xy 400.976642 -120.875589) (xy 400.992155 -120.933482)
			(xy 400.999978 -120.992904) (xy 401.000468 -121.022872) (xy 401.000468 -121.367296) (xy 413.045148 -121.367296)
			(xy 413.045148 -120.503696) (xy 413.045638 -120.473712) (xy 413.053466 -120.414256) (xy 413.068987 -120.356331)
			(xy 413.091936 -120.300927) (xy 413.12192 -120.248993) (xy 413.158426 -120.201417) (xy 413.200831 -120.159012)
			(xy 413.248407 -120.122506) (xy 413.300341 -120.092522) (xy 413.355745 -120.069573) (xy 413.41367 -120.054052)
			(xy 413.473126 -120.046224) (xy 413.533094 -120.046224) (xy 413.59255 -120.054052) (xy 413.650475 -120.069573)
			(xy 413.705879 -120.092522) (xy 413.757813 -120.122506) (xy 413.805389 -120.159012) (xy 413.847794 -120.201417)
			(xy 413.8843 -120.248993) (xy 413.914284 -120.300927) (xy 413.937233 -120.356331) (xy 413.952754 -120.414256)
			(xy 413.960582 -120.473712) (xy 413.961072 -120.503696) (xy 413.961072 -121.365772) (xy 432.016408 -121.365772)
			(xy 432.016408 -120.502172) (xy 432.016898 -120.472188) (xy 432.024726 -120.412732) (xy 432.040247 -120.354807)
			(xy 432.063196 -120.299403) (xy 432.09318 -120.247469) (xy 432.129686 -120.199893) (xy 432.172091 -120.157488)
			(xy 432.219667 -120.120982) (xy 432.271601 -120.090998) (xy 432.327005 -120.068049) (xy 432.38493 -120.052528)
			(xy 432.444386 -120.0447) (xy 432.504354 -120.0447) (xy 432.56381 -120.052528) (xy 432.621735 -120.068049)
			(xy 432.677139 -120.090998) (xy 432.729073 -120.120982) (xy 432.776649 -120.157488) (xy 432.819054 -120.199893)
			(xy 432.85556 -120.247469) (xy 432.885544 -120.299403) (xy 432.908493 -120.354807) (xy 432.924014 -120.412732)
			(xy 432.931842 -120.472188) (xy 432.932332 -120.502172) (xy 432.932332 -121.365772) (xy 432.931842 -121.395756)
			(xy 432.924014 -121.455212) (xy 432.908493 -121.513137) (xy 432.885544 -121.568541) (xy 432.85556 -121.620475)
			(xy 432.819054 -121.668051) (xy 432.776649 -121.710456) (xy 432.729073 -121.746962) (xy 432.677139 -121.776946)
			(xy 432.621735 -121.799895) (xy 432.56381 -121.815416) (xy 432.504354 -121.823244) (xy 432.444386 -121.823244)
			(xy 432.38493 -121.815416) (xy 432.327005 -121.799895) (xy 432.271601 -121.776946) (xy 432.219667 -121.746962)
			(xy 432.172091 -121.710456) (xy 432.129686 -121.668051) (xy 432.09318 -121.620475) (xy 432.063196 -121.568541)
			(xy 432.040247 -121.513137) (xy 432.024726 -121.455212) (xy 432.016898 -121.395756) (xy 432.016408 -121.365772)
			(xy 413.961072 -121.365772) (xy 413.961072 -121.367296) (xy 413.960582 -121.39728) (xy 413.952754 -121.456736)
			(xy 413.937233 -121.514661) (xy 413.914284 -121.570065) (xy 413.8843 -121.621999) (xy 413.847794 -121.669575)
			(xy 413.805389 -121.71198) (xy 413.757813 -121.748486) (xy 413.705879 -121.77847) (xy 413.650475 -121.801419)
			(xy 413.59255 -121.81694) (xy 413.533094 -121.824768) (xy 413.473126 -121.824768) (xy 413.41367 -121.81694)
			(xy 413.355745 -121.801419) (xy 413.300341 -121.77847) (xy 413.248407 -121.748486) (xy 413.200831 -121.71198)
			(xy 413.158426 -121.669575) (xy 413.12192 -121.621999) (xy 413.091936 -121.570065) (xy 413.068987 -121.514661)
			(xy 413.053466 -121.456736) (xy 413.045638 -121.39728) (xy 413.045148 -121.367296) (xy 401.000468 -121.367296)
			(xy 401.000468 -121.886472) (xy 400.999978 -121.91644) (xy 400.992155 -121.975862) (xy 400.976642 -122.033755)
			(xy 400.953706 -122.089128) (xy 400.923739 -122.141034) (xy 400.887252 -122.188584) (xy 400.844872 -122.230964)
			(xy 400.797322 -122.267451) (xy 400.745416 -122.297418) (xy 400.690043 -122.320354) (xy 400.63215 -122.335867)
			(xy 400.572728 -122.34369) (xy 400.512792 -122.34369) (xy 400.45337 -122.335867) (xy 400.395477 -122.320354)
			(xy 400.340104 -122.297418) (xy 400.288198 -122.267451) (xy 400.240648 -122.230964) (xy 400.198268 -122.188584)
			(xy 400.161781 -122.141034) (xy 400.131814 -122.089128) (xy 400.108878 -122.033755) (xy 400.093365 -121.975862)
			(xy 400.085542 -121.91644) (xy 400.085052 -121.886472) (xy 386.525516 -121.886472) (xy 386.525516 -121.894346)
			(xy 386.525026 -121.924314) (xy 386.517203 -121.983736) (xy 386.50169 -122.041629) (xy 386.478754 -122.097002)
			(xy 386.448787 -122.148908) (xy 386.4123 -122.196458) (xy 386.36992 -122.238838) (xy 386.32237 -122.275325)
			(xy 386.270464 -122.305292) (xy 386.215091 -122.328228) (xy 386.157198 -122.343741) (xy 386.097776 -122.351564)
			(xy 386.03784 -122.351564) (xy 385.978418 -122.343741) (xy 385.920525 -122.328228) (xy 385.865152 -122.305292)
			(xy 385.813246 -122.275325) (xy 385.765696 -122.238838) (xy 385.723316 -122.196458) (xy 385.686829 -122.148908)
			(xy 385.656862 -122.097002) (xy 385.633926 -122.041629) (xy 385.618413 -121.983736) (xy 385.61059 -121.924314)
			(xy 385.6101 -121.894346) (xy 313.951493 -121.894346) (xy 313.986726 -121.914687) (xy 314.034276 -121.951174)
			(xy 314.076656 -121.993554) (xy 314.113143 -122.041104) (xy 314.14311 -122.09301) (xy 314.166046 -122.148383)
			(xy 314.181559 -122.206276) (xy 314.189382 -122.265698) (xy 314.189872 -122.295666) (xy 314.189872 -123.159266)
			(xy 314.189382 -123.189234) (xy 314.181559 -123.248656) (xy 314.166046 -123.306549) (xy 314.14311 -123.361922)
			(xy 314.113143 -123.413828) (xy 314.076656 -123.461378) (xy 314.034276 -123.503758) (xy 313.986726 -123.540245)
			(xy 313.93482 -123.570212) (xy 313.879447 -123.593148) (xy 313.821554 -123.608661) (xy 313.762132 -123.616484)
			(xy 313.702196 -123.616484) (xy 313.642774 -123.608661) (xy 313.584881 -123.593148) (xy 313.529508 -123.570212)
			(xy 313.477602 -123.540245) (xy 313.430052 -123.503758) (xy 313.387672 -123.461378) (xy 313.351185 -123.413828)
			(xy 313.321218 -123.361922) (xy 313.298282 -123.306549) (xy 313.282769 -123.248656) (xy 313.274946 -123.189234)
			(xy 313.274456 -123.159266) (xy 299.71492 -123.159266) (xy 299.71492 -123.16714) (xy 299.71443 -123.197108)
			(xy 299.706607 -123.25653) (xy 299.691094 -123.314423) (xy 299.668158 -123.369796) (xy 299.638191 -123.421702)
			(xy 299.601704 -123.469252) (xy 299.559324 -123.511632) (xy 299.511774 -123.548119) (xy 299.459868 -123.578086)
			(xy 299.404495 -123.601022) (xy 299.346602 -123.616535) (xy 299.28718 -123.624358) (xy 299.227244 -123.624358)
			(xy 299.167822 -123.616535) (xy 299.109929 -123.601022) (xy 299.054556 -123.578086) (xy 299.00265 -123.548119)
			(xy 298.9551 -123.511632) (xy 298.91272 -123.469252) (xy 298.876233 -123.421702) (xy 298.846266 -123.369796)
			(xy 298.82333 -123.314423) (xy 298.807817 -123.25653) (xy 298.799994 -123.197108) (xy 298.799504 -123.16714)
			(xy 286.754824 -123.16714) (xy 286.754824 -123.686316) (xy 286.754334 -123.7163) (xy 286.746506 -123.775756)
			(xy 286.730985 -123.833681) (xy 286.708036 -123.889085) (xy 286.678052 -123.941019) (xy 286.641546 -123.988595)
			(xy 286.599141 -124.031) (xy 286.551565 -124.067506) (xy 286.499631 -124.09749) (xy 286.444227 -124.120439)
			(xy 286.386302 -124.13596) (xy 286.326846 -124.143788) (xy 286.266878 -124.143788) (xy 286.207422 -124.13596)
			(xy 286.149497 -124.120439) (xy 286.094093 -124.09749) (xy 286.042159 -124.067506) (xy 285.994583 -124.031)
			(xy 285.952178 -123.988595) (xy 285.915672 -123.941019) (xy 285.885688 -123.889085) (xy 285.862739 -123.833681)
			(xy 285.847218 -123.775756) (xy 285.83939 -123.7163) (xy 285.8389 -123.686316) (xy 267.783564 -123.686316)
			(xy 267.783564 -123.68784) (xy 267.783074 -123.717824) (xy 267.775246 -123.77728) (xy 267.759725 -123.835205)
			(xy 267.736776 -123.890609) (xy 267.706792 -123.942543) (xy 267.670286 -123.990119) (xy 267.627881 -124.032524)
			(xy 267.580305 -124.06903) (xy 267.528371 -124.099014) (xy 267.472967 -124.121963) (xy 267.415042 -124.137484)
			(xy 267.355586 -124.145312) (xy 267.295618 -124.145312) (xy 267.236162 -124.137484) (xy 267.178237 -124.121963)
			(xy 267.122833 -124.099014) (xy 267.070899 -124.06903) (xy 267.023323 -124.032524) (xy 266.980918 -123.990119)
			(xy 266.944412 -123.942543) (xy 266.914428 -123.890609) (xy 266.891479 -123.835205) (xy 266.875958 -123.77728)
			(xy 266.86813 -123.717824) (xy 266.86764 -123.68784) (xy 200.469049 -123.68784) (xy 200.477084 -123.691168)
			(xy 200.52899 -123.721135) (xy 200.57654 -123.757622) (xy 200.61892 -123.800002) (xy 200.655407 -123.847552)
			(xy 200.685374 -123.899458) (xy 200.70831 -123.954831) (xy 200.723823 -124.012724) (xy 200.731646 -124.072146)
			(xy 200.732136 -124.102114) (xy 200.732136 -124.965714) (xy 200.731646 -124.995682) (xy 200.723823 -125.055104)
			(xy 200.70831 -125.112997) (xy 200.685374 -125.16837) (xy 200.655407 -125.220276) (xy 200.61892 -125.267826)
			(xy 200.57654 -125.310206) (xy 200.52899 -125.346693) (xy 200.477084 -125.37666) (xy 200.421711 -125.399596)
			(xy 200.363818 -125.415109) (xy 200.304396 -125.422932) (xy 200.24446 -125.422932) (xy 200.185038 -125.415109)
			(xy 200.127145 -125.399596) (xy 200.071772 -125.37666) (xy 200.019866 -125.346693) (xy 199.972316 -125.310206)
			(xy 199.929936 -125.267826) (xy 199.893449 -125.220276) (xy 199.863482 -125.16837) (xy 199.840546 -125.112997)
			(xy 199.825033 -125.055104) (xy 199.81721 -124.995682) (xy 199.81672 -124.965714) (xy 181.760876 -124.965714)
			(xy 181.760876 -124.967238) (xy 181.760386 -124.997206) (xy 181.752563 -125.056628) (xy 181.73705 -125.114521)
			(xy 181.714114 -125.169894) (xy 181.684147 -125.2218) (xy 181.64766 -125.26935) (xy 181.60528 -125.31173)
			(xy 181.55773 -125.348217) (xy 181.505824 -125.378184) (xy 181.450451 -125.40112) (xy 181.392558 -125.416633)
			(xy 181.333136 -125.424456) (xy 181.2732 -125.424456) (xy 181.213778 -125.416633) (xy 181.155885 -125.40112)
			(xy 181.100512 -125.378184) (xy 181.048606 -125.348217) (xy 181.001056 -125.31173) (xy 180.958676 -125.26935)
			(xy 180.922189 -125.2218) (xy 180.892222 -125.169894) (xy 180.869286 -125.114521) (xy 180.853773 -125.056628)
			(xy 180.84595 -124.997206) (xy 180.84546 -124.967238) (xy 168.80078 -124.967238) (xy 168.80078 -125.486414)
			(xy 168.800647 -125.494542) (xy 269.509748 -125.494542) (xy 269.509748 -124.630942) (xy 269.510238 -124.600958)
			(xy 269.518066 -124.541502) (xy 269.533587 -124.483577) (xy 269.556536 -124.428173) (xy 269.58652 -124.376239)
			(xy 269.623026 -124.328663) (xy 269.665431 -124.286258) (xy 269.713007 -124.249752) (xy 269.764941 -124.219768)
			(xy 269.820345 -124.196819) (xy 269.87827 -124.181298) (xy 269.937726 -124.17347) (xy 269.997694 -124.17347)
			(xy 270.05715 -124.181298) (xy 270.115075 -124.196819) (xy 270.170479 -124.219768) (xy 270.222413 -124.249752)
			(xy 270.269989 -124.286258) (xy 270.312394 -124.328663) (xy 270.3489 -124.376239) (xy 270.378884 -124.428173)
			(xy 270.401833 -124.483577) (xy 270.417354 -124.541502) (xy 270.425182 -124.600958) (xy 270.425672 -124.630942)
			(xy 270.425672 -125.486414) (xy 283.9847 -125.486414) (xy 283.9847 -124.622814) (xy 283.98519 -124.59283)
			(xy 283.993018 -124.533374) (xy 284.008539 -124.475449) (xy 284.031488 -124.420045) (xy 284.061472 -124.368111)
			(xy 284.097978 -124.320535) (xy 284.140383 -124.27813) (xy 284.187959 -124.241624) (xy 284.239893 -124.21164)
			(xy 284.295297 -124.188691) (xy 284.353222 -124.17317) (xy 284.412678 -124.165342) (xy 284.472646 -124.165342)
			(xy 284.532102 -124.17317) (xy 284.590027 -124.188691) (xy 284.645431 -124.21164) (xy 284.697365 -124.241624)
			(xy 284.744941 -124.27813) (xy 284.787346 -124.320535) (xy 284.823852 -124.368111) (xy 284.853836 -124.420045)
			(xy 284.876785 -124.475449) (xy 284.892306 -124.533374) (xy 284.900134 -124.59283) (xy 284.900624 -124.622814)
			(xy 284.900624 -124.967238) (xy 296.945304 -124.967238) (xy 296.945304 -124.103638) (xy 296.945794 -124.07367)
			(xy 296.953617 -124.014248) (xy 296.96913 -123.956355) (xy 296.992066 -123.900982) (xy 297.022033 -123.849076)
			(xy 297.05852 -123.801526) (xy 297.1009 -123.759146) (xy 297.14845 -123.722659) (xy 297.200356 -123.692692)
			(xy 297.255729 -123.669756) (xy 297.313622 -123.654243) (xy 297.373044 -123.64642) (xy 297.43298 -123.64642)
			(xy 297.492402 -123.654243) (xy 297.550295 -123.669756) (xy 297.605668 -123.692692) (xy 297.657574 -123.722659)
			(xy 297.705124 -123.759146) (xy 297.747504 -123.801526) (xy 297.783991 -123.849076) (xy 297.813958 -123.900982)
			(xy 297.836894 -123.956355) (xy 297.852407 -124.014248) (xy 297.86023 -124.07367) (xy 297.86072 -124.103638)
			(xy 297.86072 -124.965714) (xy 315.916564 -124.965714) (xy 315.916564 -124.102114) (xy 315.917054 -124.072146)
			(xy 315.924877 -124.012724) (xy 315.94039 -123.954831) (xy 315.963326 -123.899458) (xy 315.993293 -123.847552)
			(xy 316.02978 -123.800002) (xy 316.07216 -123.757622) (xy 316.11971 -123.721135) (xy 316.171616 -123.691168)
			(xy 316.226989 -123.668232) (xy 316.284882 -123.652719) (xy 316.344304 -123.644896) (xy 316.40424 -123.644896)
			(xy 316.463662 -123.652719) (xy 316.521555 -123.668232) (xy 316.568893 -123.68784) (xy 382.967992 -123.68784)
			(xy 382.967992 -122.82424) (xy 382.968482 -122.794272) (xy 382.976305 -122.73485) (xy 382.991818 -122.676957)
			(xy 383.014754 -122.621584) (xy 383.044721 -122.569678) (xy 383.081208 -122.522128) (xy 383.123588 -122.479748)
			(xy 383.171138 -122.443261) (xy 383.223044 -122.413294) (xy 383.278417 -122.390358) (xy 383.33631 -122.374845)
			(xy 383.395732 -122.367022) (xy 383.455668 -122.367022) (xy 383.51509 -122.374845) (xy 383.572983 -122.390358)
			(xy 383.628356 -122.413294) (xy 383.680262 -122.443261) (xy 383.727812 -122.479748) (xy 383.770192 -122.522128)
			(xy 383.806679 -122.569678) (xy 383.836646 -122.621584) (xy 383.859582 -122.676957) (xy 383.875095 -122.73485)
			(xy 383.882918 -122.794272) (xy 383.883408 -122.82424) (xy 383.883408 -123.686316) (xy 401.939252 -123.686316)
			(xy 401.939252 -122.822716) (xy 401.939742 -122.792748) (xy 401.947565 -122.733326) (xy 401.963078 -122.675433)
			(xy 401.986014 -122.62006) (xy 402.015981 -122.568154) (xy 402.052468 -122.520604) (xy 402.094848 -122.478224)
			(xy 402.142398 -122.441737) (xy 402.194304 -122.41177) (xy 402.249677 -122.388834) (xy 402.30757 -122.373321)
			(xy 402.366992 -122.365498) (xy 402.426928 -122.365498) (xy 402.48635 -122.373321) (xy 402.544243 -122.388834)
			(xy 402.599616 -122.41177) (xy 402.651522 -122.441737) (xy 402.699072 -122.478224) (xy 402.741452 -122.520604)
			(xy 402.777939 -122.568154) (xy 402.807906 -122.62006) (xy 402.830842 -122.675433) (xy 402.846355 -122.733326)
			(xy 402.854178 -122.792748) (xy 402.854668 -122.822716) (xy 402.854668 -123.16714) (xy 414.899348 -123.16714)
			(xy 414.899348 -122.30354) (xy 414.899838 -122.273556) (xy 414.907666 -122.2141) (xy 414.923187 -122.156175)
			(xy 414.946136 -122.100771) (xy 414.97612 -122.048837) (xy 415.012626 -122.001261) (xy 415.055031 -121.958856)
			(xy 415.102607 -121.92235) (xy 415.154541 -121.892366) (xy 415.209945 -121.869417) (xy 415.26787 -121.853896)
			(xy 415.327326 -121.846068) (xy 415.387294 -121.846068) (xy 415.44675 -121.853896) (xy 415.504675 -121.869417)
			(xy 415.560079 -121.892366) (xy 415.612013 -121.92235) (xy 415.659589 -121.958856) (xy 415.701994 -122.001261)
			(xy 415.7385 -122.048837) (xy 415.768484 -122.100771) (xy 415.791433 -122.156175) (xy 415.806954 -122.2141)
			(xy 415.814782 -122.273556) (xy 415.815272 -122.30354) (xy 415.815272 -123.159266) (xy 429.3743 -123.159266)
			(xy 429.3743 -122.295666) (xy 429.37479 -122.265682) (xy 429.382618 -122.206226) (xy 429.398139 -122.148301)
			(xy 429.421088 -122.092897) (xy 429.451072 -122.040963) (xy 429.487578 -121.993387) (xy 429.529983 -121.950982)
			(xy 429.577559 -121.914476) (xy 429.629493 -121.884492) (xy 429.684897 -121.861543) (xy 429.742822 -121.846022)
			(xy 429.802278 -121.838194) (xy 429.862246 -121.838194) (xy 429.921702 -121.846022) (xy 429.979627 -121.861543)
			(xy 430.035031 -121.884492) (xy 430.086965 -121.914476) (xy 430.134541 -121.950982) (xy 430.176946 -121.993387)
			(xy 430.213452 -122.040963) (xy 430.243436 -122.092897) (xy 430.266385 -122.148301) (xy 430.281906 -122.206226)
			(xy 430.289734 -122.265682) (xy 430.290224 -122.295666) (xy 430.290224 -123.159266) (xy 430.289734 -123.18925)
			(xy 430.281906 -123.248706) (xy 430.266385 -123.306631) (xy 430.243436 -123.362035) (xy 430.213452 -123.413969)
			(xy 430.176946 -123.461545) (xy 430.134541 -123.50395) (xy 430.086965 -123.540456) (xy 430.035031 -123.57044)
			(xy 429.979627 -123.593389) (xy 429.921702 -123.60891) (xy 429.862246 -123.616738) (xy 429.802278 -123.616738)
			(xy 429.742822 -123.60891) (xy 429.684897 -123.593389) (xy 429.629493 -123.57044) (xy 429.577559 -123.540456)
			(xy 429.529983 -123.50395) (xy 429.487578 -123.461545) (xy 429.451072 -123.413969) (xy 429.421088 -123.362035)
			(xy 429.398139 -123.306631) (xy 429.382618 -123.248706) (xy 429.37479 -123.18925) (xy 429.3743 -123.159266)
			(xy 415.815272 -123.159266) (xy 415.815272 -123.16714) (xy 415.814782 -123.197124) (xy 415.806954 -123.25658)
			(xy 415.791433 -123.314505) (xy 415.768484 -123.369909) (xy 415.7385 -123.421843) (xy 415.701994 -123.469419)
			(xy 415.659589 -123.511824) (xy 415.612013 -123.54833) (xy 415.560079 -123.578314) (xy 415.504675 -123.601263)
			(xy 415.44675 -123.616784) (xy 415.387294 -123.624612) (xy 415.327326 -123.624612) (xy 415.26787 -123.616784)
			(xy 415.209945 -123.601263) (xy 415.154541 -123.578314) (xy 415.102607 -123.54833) (xy 415.055031 -123.511824)
			(xy 415.012626 -123.469419) (xy 414.97612 -123.421843) (xy 414.946136 -123.369909) (xy 414.923187 -123.314505)
			(xy 414.907666 -123.25658) (xy 414.899838 -123.197124) (xy 414.899348 -123.16714) (xy 402.854668 -123.16714)
			(xy 402.854668 -123.686316) (xy 402.854178 -123.716284) (xy 402.846355 -123.775706) (xy 402.830842 -123.833599)
			(xy 402.807906 -123.888972) (xy 402.777939 -123.940878) (xy 402.741452 -123.988428) (xy 402.699072 -124.030808)
			(xy 402.651522 -124.067295) (xy 402.599616 -124.097262) (xy 402.544243 -124.120198) (xy 402.48635 -124.135711)
			(xy 402.426928 -124.143534) (xy 402.366992 -124.143534) (xy 402.30757 -124.135711) (xy 402.249677 -124.120198)
			(xy 402.194304 -124.097262) (xy 402.142398 -124.067295) (xy 402.094848 -124.030808) (xy 402.052468 -123.988428)
			(xy 402.015981 -123.940878) (xy 401.986014 -123.888972) (xy 401.963078 -123.833599) (xy 401.947565 -123.775706)
			(xy 401.939742 -123.716284) (xy 401.939252 -123.686316) (xy 383.883408 -123.686316) (xy 383.883408 -123.68784)
			(xy 383.882918 -123.717808) (xy 383.875095 -123.77723) (xy 383.859582 -123.835123) (xy 383.836646 -123.890496)
			(xy 383.806679 -123.942402) (xy 383.770192 -123.989952) (xy 383.727812 -124.032332) (xy 383.680262 -124.068819)
			(xy 383.628356 -124.098786) (xy 383.572983 -124.121722) (xy 383.51509 -124.137235) (xy 383.455668 -124.145058)
			(xy 383.395732 -124.145058) (xy 383.33631 -124.137235) (xy 383.278417 -124.121722) (xy 383.223044 -124.098786)
			(xy 383.171138 -124.068819) (xy 383.123588 -124.032332) (xy 383.081208 -123.989952) (xy 383.044721 -123.942402)
			(xy 383.014754 -123.890496) (xy 382.991818 -123.835123) (xy 382.976305 -123.77723) (xy 382.968482 -123.717808)
			(xy 382.967992 -123.68784) (xy 316.568893 -123.68784) (xy 316.576928 -123.691168) (xy 316.628834 -123.721135)
			(xy 316.676384 -123.757622) (xy 316.718764 -123.800002) (xy 316.755251 -123.847552) (xy 316.785218 -123.899458)
			(xy 316.808154 -123.954831) (xy 316.823667 -124.012724) (xy 316.83149 -124.072146) (xy 316.83198 -124.102114)
			(xy 316.83198 -124.965714) (xy 316.83149 -124.995682) (xy 316.823667 -125.055104) (xy 316.808154 -125.112997)
			(xy 316.785218 -125.16837) (xy 316.755251 -125.220276) (xy 316.718764 -125.267826) (xy 316.676384 -125.310206)
			(xy 316.628834 -125.346693) (xy 316.576928 -125.37666) (xy 316.521555 -125.399596) (xy 316.463662 -125.415109)
			(xy 316.40424 -125.422932) (xy 316.344304 -125.422932) (xy 316.284882 -125.415109) (xy 316.226989 -125.399596)
			(xy 316.171616 -125.37666) (xy 316.11971 -125.346693) (xy 316.07216 -125.310206) (xy 316.02978 -125.267826)
			(xy 315.993293 -125.220276) (xy 315.963326 -125.16837) (xy 315.94039 -125.112997) (xy 315.924877 -125.055104)
			(xy 315.917054 -124.995682) (xy 315.916564 -124.965714) (xy 297.86072 -124.965714) (xy 297.86072 -124.967238)
			(xy 297.86023 -124.997206) (xy 297.852407 -125.056628) (xy 297.836894 -125.114521) (xy 297.813958 -125.169894)
			(xy 297.783991 -125.2218) (xy 297.747504 -125.26935) (xy 297.705124 -125.31173) (xy 297.657574 -125.348217)
			(xy 297.605668 -125.378184) (xy 297.550295 -125.40112) (xy 297.492402 -125.416633) (xy 297.43298 -125.424456)
			(xy 297.373044 -125.424456) (xy 297.313622 -125.416633) (xy 297.255729 -125.40112) (xy 297.200356 -125.378184)
			(xy 297.14845 -125.348217) (xy 297.1009 -125.31173) (xy 297.05852 -125.26935) (xy 297.022033 -125.2218)
			(xy 296.992066 -125.169894) (xy 296.96913 -125.114521) (xy 296.953617 -125.056628) (xy 296.945794 -124.997206)
			(xy 296.945304 -124.967238) (xy 284.900624 -124.967238) (xy 284.900624 -125.486414) (xy 284.900491 -125.494542)
			(xy 385.6101 -125.494542) (xy 385.6101 -124.630942) (xy 385.61059 -124.600974) (xy 385.618413 -124.541552)
			(xy 385.633926 -124.483659) (xy 385.656862 -124.428286) (xy 385.686829 -124.37638) (xy 385.723316 -124.32883)
			(xy 385.765696 -124.28645) (xy 385.813246 -124.249963) (xy 385.865152 -124.219996) (xy 385.920525 -124.19706)
			(xy 385.978418 -124.181547) (xy 386.03784 -124.173724) (xy 386.097776 -124.173724) (xy 386.157198 -124.181547)
			(xy 386.215091 -124.19706) (xy 386.270464 -124.219996) (xy 386.32237 -124.249963) (xy 386.36992 -124.28645)
			(xy 386.4123 -124.32883) (xy 386.448787 -124.37638) (xy 386.478754 -124.428286) (xy 386.50169 -124.483659)
			(xy 386.517203 -124.541552) (xy 386.525026 -124.600974) (xy 386.525516 -124.630942) (xy 386.525516 -125.486414)
			(xy 400.085052 -125.486414) (xy 400.085052 -124.622814) (xy 400.085542 -124.592846) (xy 400.093365 -124.533424)
			(xy 400.108878 -124.475531) (xy 400.131814 -124.420158) (xy 400.161781 -124.368252) (xy 400.198268 -124.320702)
			(xy 400.240648 -124.278322) (xy 400.288198 -124.241835) (xy 400.340104 -124.211868) (xy 400.395477 -124.188932)
			(xy 400.45337 -124.173419) (xy 400.512792 -124.165596) (xy 400.572728 -124.165596) (xy 400.63215 -124.173419)
			(xy 400.690043 -124.188932) (xy 400.745416 -124.211868) (xy 400.797322 -124.241835) (xy 400.844872 -124.278322)
			(xy 400.887252 -124.320702) (xy 400.923739 -124.368252) (xy 400.953706 -124.420158) (xy 400.976642 -124.475531)
			(xy 400.992155 -124.533424) (xy 400.999978 -124.592846) (xy 401.000468 -124.622814) (xy 401.000468 -124.967238)
			(xy 413.045148 -124.967238) (xy 413.045148 -124.103638) (xy 413.045638 -124.073654) (xy 413.053466 -124.014198)
			(xy 413.068987 -123.956273) (xy 413.091936 -123.900869) (xy 413.12192 -123.848935) (xy 413.158426 -123.801359)
			(xy 413.200831 -123.758954) (xy 413.248407 -123.722448) (xy 413.300341 -123.692464) (xy 413.355745 -123.669515)
			(xy 413.41367 -123.653994) (xy 413.473126 -123.646166) (xy 413.533094 -123.646166) (xy 413.59255 -123.653994)
			(xy 413.650475 -123.669515) (xy 413.705879 -123.692464) (xy 413.757813 -123.722448) (xy 413.805389 -123.758954)
			(xy 413.847794 -123.801359) (xy 413.8843 -123.848935) (xy 413.914284 -123.900869) (xy 413.937233 -123.956273)
			(xy 413.952754 -124.014198) (xy 413.960582 -124.073654) (xy 413.961072 -124.103638) (xy 413.961072 -124.965714)
			(xy 432.016408 -124.965714) (xy 432.016408 -124.102114) (xy 432.016898 -124.07213) (xy 432.024726 -124.012674)
			(xy 432.040247 -123.954749) (xy 432.063196 -123.899345) (xy 432.09318 -123.847411) (xy 432.129686 -123.799835)
			(xy 432.172091 -123.75743) (xy 432.219667 -123.720924) (xy 432.271601 -123.69094) (xy 432.327005 -123.667991)
			(xy 432.38493 -123.65247) (xy 432.444386 -123.644642) (xy 432.504354 -123.644642) (xy 432.56381 -123.65247)
			(xy 432.621735 -123.667991) (xy 432.677139 -123.69094) (xy 432.729073 -123.720924) (xy 432.776649 -123.75743)
			(xy 432.819054 -123.799835) (xy 432.85556 -123.847411) (xy 432.885544 -123.899345) (xy 432.908493 -123.954749)
			(xy 432.924014 -124.012674) (xy 432.931842 -124.07213) (xy 432.932332 -124.102114) (xy 432.932332 -124.965714)
			(xy 432.931842 -124.995698) (xy 432.924014 -125.055154) (xy 432.908493 -125.113079) (xy 432.885544 -125.168483)
			(xy 432.85556 -125.220417) (xy 432.819054 -125.267993) (xy 432.776649 -125.310398) (xy 432.729073 -125.346904)
			(xy 432.677139 -125.376888) (xy 432.621735 -125.399837) (xy 432.56381 -125.415358) (xy 432.504354 -125.423186)
			(xy 432.444386 -125.423186) (xy 432.38493 -125.415358) (xy 432.327005 -125.399837) (xy 432.271601 -125.376888)
			(xy 432.219667 -125.346904) (xy 432.172091 -125.310398) (xy 432.129686 -125.267993) (xy 432.09318 -125.220417)
			(xy 432.063196 -125.168483) (xy 432.040247 -125.113079) (xy 432.024726 -125.055154) (xy 432.016898 -124.995698)
			(xy 432.016408 -124.965714) (xy 413.961072 -124.965714) (xy 413.961072 -124.967238) (xy 413.960582 -124.997222)
			(xy 413.952754 -125.056678) (xy 413.937233 -125.114603) (xy 413.914284 -125.170007) (xy 413.8843 -125.221941)
			(xy 413.847794 -125.269517) (xy 413.805389 -125.311922) (xy 413.757813 -125.348428) (xy 413.705879 -125.378412)
			(xy 413.650475 -125.401361) (xy 413.59255 -125.416882) (xy 413.533094 -125.42471) (xy 413.473126 -125.42471)
			(xy 413.41367 -125.416882) (xy 413.355745 -125.401361) (xy 413.300341 -125.378412) (xy 413.248407 -125.348428)
			(xy 413.200831 -125.311922) (xy 413.158426 -125.269517) (xy 413.12192 -125.221941) (xy 413.091936 -125.170007)
			(xy 413.068987 -125.114603) (xy 413.053466 -125.056678) (xy 413.045638 -124.997222) (xy 413.045148 -124.967238)
			(xy 401.000468 -124.967238) (xy 401.000468 -125.486414) (xy 400.999978 -125.516382) (xy 400.992155 -125.575804)
			(xy 400.976642 -125.633697) (xy 400.953706 -125.68907) (xy 400.923739 -125.740976) (xy 400.887252 -125.788526)
			(xy 400.844872 -125.830906) (xy 400.797322 -125.867393) (xy 400.745416 -125.89736) (xy 400.690043 -125.920296)
			(xy 400.63215 -125.935809) (xy 400.572728 -125.943632) (xy 400.512792 -125.943632) (xy 400.45337 -125.935809)
			(xy 400.395477 -125.920296) (xy 400.340104 -125.89736) (xy 400.288198 -125.867393) (xy 400.240648 -125.830906)
			(xy 400.198268 -125.788526) (xy 400.161781 -125.740976) (xy 400.131814 -125.68907) (xy 400.108878 -125.633697)
			(xy 400.093365 -125.575804) (xy 400.085542 -125.516382) (xy 400.085052 -125.486414) (xy 386.525516 -125.486414)
			(xy 386.525516 -125.494542) (xy 386.525026 -125.52451) (xy 386.517203 -125.583932) (xy 386.50169 -125.641825)
			(xy 386.478754 -125.697198) (xy 386.448787 -125.749104) (xy 386.4123 -125.796654) (xy 386.36992 -125.839034)
			(xy 386.32237 -125.875521) (xy 386.270464 -125.905488) (xy 386.215091 -125.928424) (xy 386.157198 -125.943937)
			(xy 386.097776 -125.95176) (xy 386.03784 -125.95176) (xy 385.978418 -125.943937) (xy 385.920525 -125.928424)
			(xy 385.865152 -125.905488) (xy 385.813246 -125.875521) (xy 385.765696 -125.839034) (xy 385.723316 -125.796654)
			(xy 385.686829 -125.749104) (xy 385.656862 -125.697198) (xy 385.633926 -125.641825) (xy 385.618413 -125.583932)
			(xy 385.61059 -125.52451) (xy 385.6101 -125.494542) (xy 284.900491 -125.494542) (xy 284.900134 -125.516398)
			(xy 284.892306 -125.575854) (xy 284.876785 -125.633779) (xy 284.853836 -125.689183) (xy 284.823852 -125.741117)
			(xy 284.787346 -125.788693) (xy 284.744941 -125.831098) (xy 284.697365 -125.867604) (xy 284.645431 -125.897588)
			(xy 284.590027 -125.920537) (xy 284.532102 -125.936058) (xy 284.472646 -125.943886) (xy 284.412678 -125.943886)
			(xy 284.353222 -125.936058) (xy 284.295297 -125.920537) (xy 284.239893 -125.897588) (xy 284.187959 -125.867604)
			(xy 284.140383 -125.831098) (xy 284.097978 -125.788693) (xy 284.061472 -125.741117) (xy 284.031488 -125.689183)
			(xy 284.008539 -125.633779) (xy 283.993018 -125.575854) (xy 283.98519 -125.516398) (xy 283.9847 -125.486414)
			(xy 270.425672 -125.486414) (xy 270.425672 -125.494542) (xy 270.425182 -125.524526) (xy 270.417354 -125.583982)
			(xy 270.401833 -125.641907) (xy 270.378884 -125.697311) (xy 270.3489 -125.749245) (xy 270.312394 -125.796821)
			(xy 270.269989 -125.839226) (xy 270.222413 -125.875732) (xy 270.170479 -125.905716) (xy 270.115075 -125.928665)
			(xy 270.05715 -125.944186) (xy 269.997694 -125.952014) (xy 269.937726 -125.952014) (xy 269.87827 -125.944186)
			(xy 269.820345 -125.928665) (xy 269.764941 -125.905716) (xy 269.713007 -125.875732) (xy 269.665431 -125.839226)
			(xy 269.623026 -125.796821) (xy 269.58652 -125.749245) (xy 269.556536 -125.697311) (xy 269.533587 -125.641907)
			(xy 269.518066 -125.583982) (xy 269.510238 -125.524526) (xy 269.509748 -125.494542) (xy 168.800647 -125.494542)
			(xy 168.80029 -125.516398) (xy 168.792462 -125.575854) (xy 168.776941 -125.633779) (xy 168.753992 -125.689183)
			(xy 168.724008 -125.741117) (xy 168.687502 -125.788693) (xy 168.645097 -125.831098) (xy 168.597521 -125.867604)
			(xy 168.545587 -125.897588) (xy 168.490183 -125.920537) (xy 168.432258 -125.936058) (xy 168.372802 -125.943886)
			(xy 168.312834 -125.943886) (xy 168.253378 -125.936058) (xy 168.195453 -125.920537) (xy 168.140049 -125.897588)
			(xy 168.088115 -125.867604) (xy 168.040539 -125.831098) (xy 167.998134 -125.788693) (xy 167.961628 -125.741117)
			(xy 167.931644 -125.689183) (xy 167.908695 -125.633779) (xy 167.893174 -125.575854) (xy 167.885346 -125.516398)
			(xy 167.884856 -125.486414) (xy 154.325828 -125.486414) (xy 154.325828 -125.494542) (xy 154.325338 -125.524526)
			(xy 154.31751 -125.583982) (xy 154.301989 -125.641907) (xy 154.27904 -125.697311) (xy 154.249056 -125.749245)
			(xy 154.21255 -125.796821) (xy 154.170145 -125.839226) (xy 154.122569 -125.875732) (xy 154.070635 -125.905716)
			(xy 154.015231 -125.928665) (xy 153.957306 -125.944186) (xy 153.89785 -125.952014) (xy 153.837882 -125.952014)
			(xy 153.778426 -125.944186) (xy 153.720501 -125.928665) (xy 153.665097 -125.905716) (xy 153.613163 -125.875732)
			(xy 153.565587 -125.839226) (xy 153.523182 -125.796821) (xy 153.486676 -125.749245) (xy 153.456692 -125.697311)
			(xy 153.433743 -125.641907) (xy 153.418222 -125.583982) (xy 153.410394 -125.524526) (xy 153.409904 -125.494542)
			(xy 52.700295 -125.494542) (xy 52.699938 -125.516382) (xy 52.692115 -125.575804) (xy 52.676602 -125.633697)
			(xy 52.653666 -125.68907) (xy 52.623699 -125.740976) (xy 52.587212 -125.788526) (xy 52.544832 -125.830906)
			(xy 52.497282 -125.867393) (xy 52.445376 -125.89736) (xy 52.390003 -125.920296) (xy 52.33211 -125.935809)
			(xy 52.272688 -125.943632) (xy 52.212752 -125.943632) (xy 52.15333 -125.935809) (xy 52.095437 -125.920296)
			(xy 52.040064 -125.89736) (xy 51.988158 -125.867393) (xy 51.940608 -125.830906) (xy 51.898228 -125.788526)
			(xy 51.861741 -125.740976) (xy 51.831774 -125.68907) (xy 51.808838 -125.633697) (xy 51.793325 -125.575804)
			(xy 51.785502 -125.516382) (xy 51.785012 -125.486414) (xy 38.225476 -125.486414) (xy 38.225476 -125.494542)
			(xy 38.224986 -125.52451) (xy 38.217163 -125.583932) (xy 38.20165 -125.641825) (xy 38.178714 -125.697198)
			(xy 38.148747 -125.749104) (xy 38.11226 -125.796654) (xy 38.06988 -125.839034) (xy 38.02233 -125.875521)
			(xy 37.970424 -125.905488) (xy 37.915051 -125.928424) (xy 37.857158 -125.943937) (xy 37.797736 -125.95176)
			(xy 37.7378 -125.95176) (xy 37.678378 -125.943937) (xy 37.620485 -125.928424) (xy 37.565112 -125.905488)
			(xy 37.513206 -125.875521) (xy 37.465656 -125.839034) (xy 37.423276 -125.796654) (xy 37.386789 -125.749104)
			(xy 37.356822 -125.697198) (xy 37.333886 -125.641825) (xy 37.318373 -125.583932) (xy 37.31055 -125.52451)
			(xy 37.31006 -125.494542) (xy 4.308094 -125.494542) (xy 4.308094 -131.297934) (xy 34.667952 -131.297934)
			(xy 34.667952 -130.434334) (xy 34.668442 -130.404366) (xy 34.676265 -130.344944) (xy 34.691778 -130.287051)
			(xy 34.714714 -130.231678) (xy 34.744681 -130.179772) (xy 34.781168 -130.132222) (xy 34.823548 -130.089842)
			(xy 34.871098 -130.053355) (xy 34.923004 -130.023388) (xy 34.978377 -130.000452) (xy 35.03627 -129.984939)
			(xy 35.095692 -129.977116) (xy 35.155628 -129.977116) (xy 35.21505 -129.984939) (xy 35.272943 -130.000452)
			(xy 35.328316 -130.023388) (xy 35.380222 -130.053355) (xy 35.427772 -130.089842) (xy 35.470152 -130.132222)
			(xy 35.506639 -130.179772) (xy 35.536606 -130.231678) (xy 35.559542 -130.287051) (xy 35.575055 -130.344944)
			(xy 35.582878 -130.404366) (xy 35.583368 -130.434334) (xy 35.583368 -131.29641) (xy 53.639212 -131.29641)
			(xy 53.639212 -130.43281) (xy 53.639702 -130.402842) (xy 53.647525 -130.34342) (xy 53.663038 -130.285527)
			(xy 53.685974 -130.230154) (xy 53.715941 -130.178248) (xy 53.752428 -130.130698) (xy 53.794808 -130.088318)
			(xy 53.842358 -130.051831) (xy 53.894264 -130.021864) (xy 53.949637 -129.998928) (xy 54.00753 -129.983415)
			(xy 54.066952 -129.975592) (xy 54.126888 -129.975592) (xy 54.18631 -129.983415) (xy 54.244203 -129.998928)
			(xy 54.299576 -130.021864) (xy 54.351482 -130.051831) (xy 54.399032 -130.088318) (xy 54.441412 -130.130698)
			(xy 54.477899 -130.178248) (xy 54.507866 -130.230154) (xy 54.530802 -130.285527) (xy 54.546315 -130.34342)
			(xy 54.554138 -130.402842) (xy 54.554628 -130.43281) (xy 54.554628 -130.777234) (xy 66.599308 -130.777234)
			(xy 66.599308 -129.913634) (xy 66.599798 -129.88365) (xy 66.607626 -129.824194) (xy 66.623147 -129.766269)
			(xy 66.646096 -129.710865) (xy 66.67608 -129.658931) (xy 66.712586 -129.611355) (xy 66.754991 -129.56895)
			(xy 66.802567 -129.532444) (xy 66.854501 -129.50246) (xy 66.909905 -129.479511) (xy 66.96783 -129.46399)
			(xy 67.027286 -129.456162) (xy 67.087254 -129.456162) (xy 67.14671 -129.46399) (xy 67.204635 -129.479511)
			(xy 67.260039 -129.50246) (xy 67.311973 -129.532444) (xy 67.359549 -129.56895) (xy 67.401954 -129.611355)
			(xy 67.43846 -129.658931) (xy 67.468444 -129.710865) (xy 67.491393 -129.766269) (xy 67.506914 -129.824194)
			(xy 67.514742 -129.88365) (xy 67.515232 -129.913634) (xy 67.515232 -130.769106) (xy 81.07426 -130.769106)
			(xy 81.07426 -129.905506) (xy 81.07475 -129.875522) (xy 81.082578 -129.816066) (xy 81.098099 -129.758141)
			(xy 81.121048 -129.702737) (xy 81.151032 -129.650803) (xy 81.187538 -129.603227) (xy 81.229943 -129.560822)
			(xy 81.277519 -129.524316) (xy 81.329453 -129.494332) (xy 81.384857 -129.471383) (xy 81.442782 -129.455862)
			(xy 81.502238 -129.448034) (xy 81.562206 -129.448034) (xy 81.621662 -129.455862) (xy 81.679587 -129.471383)
			(xy 81.734991 -129.494332) (xy 81.786925 -129.524316) (xy 81.834501 -129.560822) (xy 81.876906 -129.603227)
			(xy 81.913412 -129.650803) (xy 81.943396 -129.702737) (xy 81.966345 -129.758141) (xy 81.981866 -129.816066)
			(xy 81.989694 -129.875522) (xy 81.990184 -129.905506) (xy 81.990184 -130.769106) (xy 81.989694 -130.79909)
			(xy 81.981866 -130.858546) (xy 81.966345 -130.916471) (xy 81.943396 -130.971875) (xy 81.913412 -131.023809)
			(xy 81.876906 -131.071385) (xy 81.834501 -131.11379) (xy 81.786925 -131.150296) (xy 81.734991 -131.18028)
			(xy 81.679587 -131.203229) (xy 81.621662 -131.21875) (xy 81.562206 -131.226578) (xy 81.502238 -131.226578)
			(xy 81.442782 -131.21875) (xy 81.384857 -131.203229) (xy 81.329453 -131.18028) (xy 81.277519 -131.150296)
			(xy 81.229943 -131.11379) (xy 81.187538 -131.071385) (xy 81.151032 -131.023809) (xy 81.121048 -130.971875)
			(xy 81.098099 -130.916471) (xy 81.082578 -130.858546) (xy 81.07475 -130.79909) (xy 81.07426 -130.769106)
			(xy 67.515232 -130.769106) (xy 67.515232 -130.777234) (xy 67.514742 -130.807218) (xy 67.506914 -130.866674)
			(xy 67.491393 -130.924599) (xy 67.468444 -130.980003) (xy 67.43846 -131.031937) (xy 67.401954 -131.079513)
			(xy 67.359549 -131.121918) (xy 67.311973 -131.158424) (xy 67.260039 -131.188408) (xy 67.204635 -131.211357)
			(xy 67.14671 -131.226878) (xy 67.087254 -131.234706) (xy 67.027286 -131.234706) (xy 66.96783 -131.226878)
			(xy 66.909905 -131.211357) (xy 66.854501 -131.188408) (xy 66.802567 -131.158424) (xy 66.754991 -131.121918)
			(xy 66.712586 -131.079513) (xy 66.67608 -131.031937) (xy 66.646096 -130.980003) (xy 66.623147 -130.924599)
			(xy 66.607626 -130.866674) (xy 66.599798 -130.807218) (xy 66.599308 -130.777234) (xy 54.554628 -130.777234)
			(xy 54.554628 -131.29641) (xy 54.554138 -131.326378) (xy 54.546315 -131.3858) (xy 54.530802 -131.443693)
			(xy 54.507866 -131.499066) (xy 54.477899 -131.550972) (xy 54.441412 -131.598522) (xy 54.399032 -131.640902)
			(xy 54.351482 -131.677389) (xy 54.299576 -131.707356) (xy 54.244203 -131.730292) (xy 54.18631 -131.745805)
			(xy 54.126888 -131.753628) (xy 54.066952 -131.753628) (xy 54.00753 -131.745805) (xy 53.949637 -131.730292)
			(xy 53.894264 -131.707356) (xy 53.842358 -131.677389) (xy 53.794808 -131.640902) (xy 53.752428 -131.598522)
			(xy 53.715941 -131.550972) (xy 53.685974 -131.499066) (xy 53.663038 -131.443693) (xy 53.647525 -131.3858)
			(xy 53.639702 -131.326378) (xy 53.639212 -131.29641) (xy 35.583368 -131.29641) (xy 35.583368 -131.297934)
			(xy 35.582878 -131.327902) (xy 35.575055 -131.387324) (xy 35.559542 -131.445217) (xy 35.536606 -131.50059)
			(xy 35.506639 -131.552496) (xy 35.470152 -131.600046) (xy 35.427772 -131.642426) (xy 35.380222 -131.678913)
			(xy 35.328316 -131.70888) (xy 35.272943 -131.731816) (xy 35.21505 -131.747329) (xy 35.155628 -131.755152)
			(xy 35.095692 -131.755152) (xy 35.03627 -131.747329) (xy 34.978377 -131.731816) (xy 34.923004 -131.70888)
			(xy 34.871098 -131.678913) (xy 34.823548 -131.642426) (xy 34.781168 -131.600046) (xy 34.744681 -131.552496)
			(xy 34.714714 -131.50059) (xy 34.691778 -131.445217) (xy 34.676265 -131.387324) (xy 34.668442 -131.327902)
			(xy 34.667952 -131.297934) (xy 4.308094 -131.297934) (xy 4.308094 -133.104382) (xy 37.31006 -133.104382)
			(xy 37.31006 -132.240782) (xy 37.31055 -132.210814) (xy 37.318373 -132.151392) (xy 37.333886 -132.093499)
			(xy 37.356822 -132.038126) (xy 37.386789 -131.98622) (xy 37.423276 -131.93867) (xy 37.465656 -131.89629)
			(xy 37.513206 -131.859803) (xy 37.565112 -131.829836) (xy 37.620485 -131.8069) (xy 37.678378 -131.791387)
			(xy 37.7378 -131.783564) (xy 37.797736 -131.783564) (xy 37.857158 -131.791387) (xy 37.915051 -131.8069)
			(xy 37.970424 -131.829836) (xy 38.02233 -131.859803) (xy 38.06988 -131.89629) (xy 38.11226 -131.93867)
			(xy 38.148747 -131.98622) (xy 38.178714 -132.038126) (xy 38.20165 -132.093499) (xy 38.217163 -132.151392)
			(xy 38.224986 -132.210814) (xy 38.225476 -132.240782) (xy 38.225476 -133.096508) (xy 51.785012 -133.096508)
			(xy 51.785012 -132.232908) (xy 51.785502 -132.20294) (xy 51.793325 -132.143518) (xy 51.808838 -132.085625)
			(xy 51.831774 -132.030252) (xy 51.861741 -131.978346) (xy 51.898228 -131.930796) (xy 51.940608 -131.888416)
			(xy 51.988158 -131.851929) (xy 52.040064 -131.821962) (xy 52.095437 -131.799026) (xy 52.15333 -131.783513)
			(xy 52.212752 -131.77569) (xy 52.272688 -131.77569) (xy 52.33211 -131.783513) (xy 52.390003 -131.799026)
			(xy 52.445376 -131.821962) (xy 52.497282 -131.851929) (xy 52.544832 -131.888416) (xy 52.587212 -131.930796)
			(xy 52.623699 -131.978346) (xy 52.653666 -132.030252) (xy 52.676602 -132.085625) (xy 52.692115 -132.143518)
			(xy 52.699938 -132.20294) (xy 52.700428 -132.232908) (xy 52.700428 -132.577332) (xy 64.745108 -132.577332)
			(xy 64.745108 -131.713732) (xy 64.745598 -131.683748) (xy 64.753426 -131.624292) (xy 64.768947 -131.566367)
			(xy 64.791896 -131.510963) (xy 64.82188 -131.459029) (xy 64.858386 -131.411453) (xy 64.900791 -131.369048)
			(xy 64.948367 -131.332542) (xy 65.000301 -131.302558) (xy 65.055705 -131.279609) (xy 65.11363 -131.264088)
			(xy 65.173086 -131.25626) (xy 65.233054 -131.25626) (xy 65.29251 -131.264088) (xy 65.350435 -131.279609)
			(xy 65.405839 -131.302558) (xy 65.457773 -131.332542) (xy 65.505349 -131.369048) (xy 65.547754 -131.411453)
			(xy 65.58426 -131.459029) (xy 65.614244 -131.510963) (xy 65.637193 -131.566367) (xy 65.652714 -131.624292)
			(xy 65.660542 -131.683748) (xy 65.661032 -131.713732) (xy 65.661032 -132.575808) (xy 83.716368 -132.575808)
			(xy 83.716368 -131.712208) (xy 83.716858 -131.682224) (xy 83.724686 -131.622768) (xy 83.740207 -131.564843)
			(xy 83.763156 -131.509439) (xy 83.79314 -131.457505) (xy 83.829646 -131.409929) (xy 83.872051 -131.367524)
			(xy 83.919627 -131.331018) (xy 83.971561 -131.301034) (xy 84.026965 -131.278085) (xy 84.08489 -131.262564)
			(xy 84.144346 -131.254736) (xy 84.204314 -131.254736) (xy 84.26377 -131.262564) (xy 84.321695 -131.278085)
			(xy 84.369615 -131.297934) (xy 150.767796 -131.297934) (xy 150.767796 -130.434334) (xy 150.768286 -130.40435)
			(xy 150.776114 -130.344894) (xy 150.791635 -130.286969) (xy 150.814584 -130.231565) (xy 150.844568 -130.179631)
			(xy 150.881074 -130.132055) (xy 150.923479 -130.08965) (xy 150.971055 -130.053144) (xy 151.022989 -130.02316)
			(xy 151.078393 -130.000211) (xy 151.136318 -129.98469) (xy 151.195774 -129.976862) (xy 151.255742 -129.976862)
			(xy 151.315198 -129.98469) (xy 151.373123 -130.000211) (xy 151.428527 -130.02316) (xy 151.480461 -130.053144)
			(xy 151.528037 -130.08965) (xy 151.570442 -130.132055) (xy 151.606948 -130.179631) (xy 151.636932 -130.231565)
			(xy 151.659881 -130.286969) (xy 151.675402 -130.344894) (xy 151.68323 -130.40435) (xy 151.68372 -130.434334)
			(xy 151.68372 -131.29641) (xy 169.739056 -131.29641) (xy 169.739056 -130.43281) (xy 169.739546 -130.402826)
			(xy 169.747374 -130.34337) (xy 169.762895 -130.285445) (xy 169.785844 -130.230041) (xy 169.815828 -130.178107)
			(xy 169.852334 -130.130531) (xy 169.894739 -130.088126) (xy 169.942315 -130.05162) (xy 169.994249 -130.021636)
			(xy 170.049653 -129.998687) (xy 170.107578 -129.983166) (xy 170.167034 -129.975338) (xy 170.227002 -129.975338)
			(xy 170.286458 -129.983166) (xy 170.344383 -129.998687) (xy 170.399787 -130.021636) (xy 170.451721 -130.05162)
			(xy 170.499297 -130.088126) (xy 170.541702 -130.130531) (xy 170.578208 -130.178107) (xy 170.608192 -130.230041)
			(xy 170.631141 -130.285445) (xy 170.646662 -130.34337) (xy 170.65449 -130.402826) (xy 170.65498 -130.43281)
			(xy 170.65498 -130.777234) (xy 182.69966 -130.777234) (xy 182.69966 -129.913634) (xy 182.70015 -129.883666)
			(xy 182.707973 -129.824244) (xy 182.723486 -129.766351) (xy 182.746422 -129.710978) (xy 182.776389 -129.659072)
			(xy 182.812876 -129.611522) (xy 182.855256 -129.569142) (xy 182.902806 -129.532655) (xy 182.954712 -129.502688)
			(xy 183.010085 -129.479752) (xy 183.067978 -129.464239) (xy 183.1274 -129.456416) (xy 183.187336 -129.456416)
			(xy 183.246758 -129.464239) (xy 183.304651 -129.479752) (xy 183.360024 -129.502688) (xy 183.41193 -129.532655)
			(xy 183.45948 -129.569142) (xy 183.50186 -129.611522) (xy 183.538347 -129.659072) (xy 183.568314 -129.710978)
			(xy 183.59125 -129.766351) (xy 183.606763 -129.824244) (xy 183.614586 -129.883666) (xy 183.615076 -129.913634)
			(xy 183.615076 -130.769106) (xy 197.174612 -130.769106) (xy 197.174612 -129.905506) (xy 197.175102 -129.875538)
			(xy 197.182925 -129.816116) (xy 197.198438 -129.758223) (xy 197.221374 -129.70285) (xy 197.251341 -129.650944)
			(xy 197.287828 -129.603394) (xy 197.330208 -129.561014) (xy 197.377758 -129.524527) (xy 197.429664 -129.49456)
			(xy 197.485037 -129.471624) (xy 197.54293 -129.456111) (xy 197.602352 -129.448288) (xy 197.662288 -129.448288)
			(xy 197.72171 -129.456111) (xy 197.779603 -129.471624) (xy 197.834976 -129.49456) (xy 197.886882 -129.524527)
			(xy 197.934432 -129.561014) (xy 197.976812 -129.603394) (xy 198.013299 -129.650944) (xy 198.043266 -129.70285)
			(xy 198.066202 -129.758223) (xy 198.081715 -129.816116) (xy 198.089538 -129.875538) (xy 198.090028 -129.905506)
			(xy 198.090028 -130.769106) (xy 198.089538 -130.799074) (xy 198.081715 -130.858496) (xy 198.066202 -130.916389)
			(xy 198.043266 -130.971762) (xy 198.013299 -131.023668) (xy 197.976812 -131.071218) (xy 197.934432 -131.113598)
			(xy 197.886882 -131.150085) (xy 197.834976 -131.180052) (xy 197.779603 -131.202988) (xy 197.72171 -131.218501)
			(xy 197.662288 -131.226324) (xy 197.602352 -131.226324) (xy 197.54293 -131.218501) (xy 197.485037 -131.202988)
			(xy 197.429664 -131.180052) (xy 197.377758 -131.150085) (xy 197.330208 -131.113598) (xy 197.287828 -131.071218)
			(xy 197.251341 -131.023668) (xy 197.221374 -130.971762) (xy 197.198438 -130.916389) (xy 197.182925 -130.858496)
			(xy 197.175102 -130.799074) (xy 197.174612 -130.769106) (xy 183.615076 -130.769106) (xy 183.615076 -130.777234)
			(xy 183.614586 -130.807202) (xy 183.606763 -130.866624) (xy 183.59125 -130.924517) (xy 183.568314 -130.97989)
			(xy 183.538347 -131.031796) (xy 183.50186 -131.079346) (xy 183.45948 -131.121726) (xy 183.41193 -131.158213)
			(xy 183.360024 -131.18818) (xy 183.304651 -131.211116) (xy 183.246758 -131.226629) (xy 183.187336 -131.234452)
			(xy 183.1274 -131.234452) (xy 183.067978 -131.226629) (xy 183.010085 -131.211116) (xy 182.954712 -131.18818)
			(xy 182.902806 -131.158213) (xy 182.855256 -131.121726) (xy 182.812876 -131.079346) (xy 182.776389 -131.031796)
			(xy 182.746422 -130.97989) (xy 182.723486 -130.924517) (xy 182.707973 -130.866624) (xy 182.70015 -130.807202)
			(xy 182.69966 -130.777234) (xy 170.65498 -130.777234) (xy 170.65498 -131.29641) (xy 170.65449 -131.326394)
			(xy 170.646662 -131.38585) (xy 170.631141 -131.443775) (xy 170.608192 -131.499179) (xy 170.578208 -131.551113)
			(xy 170.541702 -131.598689) (xy 170.499297 -131.641094) (xy 170.451721 -131.6776) (xy 170.399787 -131.707584)
			(xy 170.344383 -131.730533) (xy 170.286458 -131.746054) (xy 170.227002 -131.753882) (xy 170.167034 -131.753882)
			(xy 170.107578 -131.746054) (xy 170.049653 -131.730533) (xy 169.994249 -131.707584) (xy 169.942315 -131.6776)
			(xy 169.894739 -131.641094) (xy 169.852334 -131.598689) (xy 169.815828 -131.551113) (xy 169.785844 -131.499179)
			(xy 169.762895 -131.443775) (xy 169.747374 -131.38585) (xy 169.739546 -131.326394) (xy 169.739056 -131.29641)
			(xy 151.68372 -131.29641) (xy 151.68372 -131.297934) (xy 151.68323 -131.327918) (xy 151.675402 -131.387374)
			(xy 151.659881 -131.445299) (xy 151.636932 -131.500703) (xy 151.606948 -131.552637) (xy 151.570442 -131.600213)
			(xy 151.528037 -131.642618) (xy 151.480461 -131.679124) (xy 151.428527 -131.709108) (xy 151.373123 -131.732057)
			(xy 151.315198 -131.747578) (xy 151.255742 -131.755406) (xy 151.195774 -131.755406) (xy 151.136318 -131.747578)
			(xy 151.078393 -131.732057) (xy 151.022989 -131.709108) (xy 150.971055 -131.679124) (xy 150.923479 -131.642618)
			(xy 150.881074 -131.600213) (xy 150.844568 -131.552637) (xy 150.814584 -131.500703) (xy 150.791635 -131.445299)
			(xy 150.776114 -131.387374) (xy 150.768286 -131.327918) (xy 150.767796 -131.297934) (xy 84.369615 -131.297934)
			(xy 84.377099 -131.301034) (xy 84.429033 -131.331018) (xy 84.476609 -131.367524) (xy 84.519014 -131.409929)
			(xy 84.55552 -131.457505) (xy 84.585504 -131.509439) (xy 84.608453 -131.564843) (xy 84.623974 -131.622768)
			(xy 84.631802 -131.682224) (xy 84.632292 -131.712208) (xy 84.632292 -132.575808) (xy 84.631802 -132.605792)
			(xy 84.623974 -132.665248) (xy 84.608453 -132.723173) (xy 84.585504 -132.778577) (xy 84.55552 -132.830511)
			(xy 84.519014 -132.878087) (xy 84.476609 -132.920492) (xy 84.429033 -132.956998) (xy 84.377099 -132.986982)
			(xy 84.321695 -133.009931) (xy 84.26377 -133.025452) (xy 84.204314 -133.03328) (xy 84.144346 -133.03328)
			(xy 84.08489 -133.025452) (xy 84.026965 -133.009931) (xy 83.971561 -132.986982) (xy 83.919627 -132.956998)
			(xy 83.872051 -132.920492) (xy 83.829646 -132.878087) (xy 83.79314 -132.830511) (xy 83.763156 -132.778577)
			(xy 83.740207 -132.723173) (xy 83.724686 -132.665248) (xy 83.716858 -132.605792) (xy 83.716368 -132.575808)
			(xy 65.661032 -132.575808) (xy 65.661032 -132.577332) (xy 65.660542 -132.607316) (xy 65.652714 -132.666772)
			(xy 65.637193 -132.724697) (xy 65.614244 -132.780101) (xy 65.58426 -132.832035) (xy 65.547754 -132.879611)
			(xy 65.505349 -132.922016) (xy 65.457773 -132.958522) (xy 65.405839 -132.988506) (xy 65.350435 -133.011455)
			(xy 65.29251 -133.026976) (xy 65.233054 -133.034804) (xy 65.173086 -133.034804) (xy 65.11363 -133.026976)
			(xy 65.055705 -133.011455) (xy 65.000301 -132.988506) (xy 64.948367 -132.958522) (xy 64.900791 -132.922016)
			(xy 64.858386 -132.879611) (xy 64.82188 -132.832035) (xy 64.791896 -132.780101) (xy 64.768947 -132.724697)
			(xy 64.753426 -132.666772) (xy 64.745598 -132.607316) (xy 64.745108 -132.577332) (xy 52.700428 -132.577332)
			(xy 52.700428 -133.096508) (xy 52.699938 -133.126476) (xy 52.692115 -133.185898) (xy 52.676602 -133.243791)
			(xy 52.653666 -133.299164) (xy 52.623699 -133.35107) (xy 52.587212 -133.39862) (xy 52.544832 -133.441)
			(xy 52.497282 -133.477487) (xy 52.445376 -133.507454) (xy 52.390003 -133.53039) (xy 52.33211 -133.545903)
			(xy 52.272688 -133.553726) (xy 52.212752 -133.553726) (xy 52.15333 -133.545903) (xy 52.095437 -133.53039)
			(xy 52.040064 -133.507454) (xy 51.988158 -133.477487) (xy 51.940608 -133.441) (xy 51.898228 -133.39862)
			(xy 51.861741 -133.35107) (xy 51.831774 -133.299164) (xy 51.808838 -133.243791) (xy 51.793325 -133.185898)
			(xy 51.785502 -133.126476) (xy 51.785012 -133.096508) (xy 38.225476 -133.096508) (xy 38.225476 -133.104382)
			(xy 38.224986 -133.13435) (xy 38.217163 -133.193772) (xy 38.20165 -133.251665) (xy 38.178714 -133.307038)
			(xy 38.148747 -133.358944) (xy 38.11226 -133.406494) (xy 38.06988 -133.448874) (xy 38.02233 -133.485361)
			(xy 37.970424 -133.515328) (xy 37.915051 -133.538264) (xy 37.857158 -133.553777) (xy 37.797736 -133.5616)
			(xy 37.7378 -133.5616) (xy 37.678378 -133.553777) (xy 37.620485 -133.538264) (xy 37.565112 -133.515328)
			(xy 37.513206 -133.485361) (xy 37.465656 -133.448874) (xy 37.423276 -133.406494) (xy 37.386789 -133.358944)
			(xy 37.356822 -133.307038) (xy 37.333886 -133.251665) (xy 37.318373 -133.193772) (xy 37.31055 -133.13435)
			(xy 37.31006 -133.104382) (xy 4.308094 -133.104382) (xy 4.308094 -134.897876) (xy 34.667952 -134.897876)
			(xy 34.667952 -134.034276) (xy 34.668442 -134.004308) (xy 34.676265 -133.944886) (xy 34.691778 -133.886993)
			(xy 34.714714 -133.83162) (xy 34.744681 -133.779714) (xy 34.781168 -133.732164) (xy 34.823548 -133.689784)
			(xy 34.871098 -133.653297) (xy 34.923004 -133.62333) (xy 34.978377 -133.600394) (xy 35.03627 -133.584881)
			(xy 35.095692 -133.577058) (xy 35.155628 -133.577058) (xy 35.21505 -133.584881) (xy 35.272943 -133.600394)
			(xy 35.328316 -133.62333) (xy 35.380222 -133.653297) (xy 35.427772 -133.689784) (xy 35.470152 -133.732164)
			(xy 35.506639 -133.779714) (xy 35.536606 -133.83162) (xy 35.559542 -133.886993) (xy 35.575055 -133.944886)
			(xy 35.582878 -134.004308) (xy 35.583368 -134.034276) (xy 35.583368 -134.896352) (xy 53.639212 -134.896352)
			(xy 53.639212 -134.032752) (xy 53.639702 -134.002784) (xy 53.647525 -133.943362) (xy 53.663038 -133.885469)
			(xy 53.685974 -133.830096) (xy 53.715941 -133.77819) (xy 53.752428 -133.73064) (xy 53.794808 -133.68826)
			(xy 53.842358 -133.651773) (xy 53.894264 -133.621806) (xy 53.949637 -133.59887) (xy 54.00753 -133.583357)
			(xy 54.066952 -133.575534) (xy 54.126888 -133.575534) (xy 54.18631 -133.583357) (xy 54.244203 -133.59887)
			(xy 54.299576 -133.621806) (xy 54.351482 -133.651773) (xy 54.399032 -133.68826) (xy 54.441412 -133.73064)
			(xy 54.477899 -133.77819) (xy 54.507866 -133.830096) (xy 54.530802 -133.885469) (xy 54.546315 -133.943362)
			(xy 54.554138 -134.002784) (xy 54.554628 -134.032752) (xy 54.554628 -134.377176) (xy 66.599308 -134.377176)
			(xy 66.599308 -133.513576) (xy 66.599798 -133.483592) (xy 66.607626 -133.424136) (xy 66.623147 -133.366211)
			(xy 66.646096 -133.310807) (xy 66.67608 -133.258873) (xy 66.712586 -133.211297) (xy 66.754991 -133.168892)
			(xy 66.802567 -133.132386) (xy 66.854501 -133.102402) (xy 66.909905 -133.079453) (xy 66.96783 -133.063932)
			(xy 67.027286 -133.056104) (xy 67.087254 -133.056104) (xy 67.14671 -133.063932) (xy 67.204635 -133.079453)
			(xy 67.260039 -133.102402) (xy 67.311973 -133.132386) (xy 67.359549 -133.168892) (xy 67.401954 -133.211297)
			(xy 67.43846 -133.258873) (xy 67.468444 -133.310807) (xy 67.491393 -133.366211) (xy 67.506914 -133.424136)
			(xy 67.514742 -133.483592) (xy 67.515232 -133.513576) (xy 67.515232 -134.369302) (xy 81.07426 -134.369302)
			(xy 81.07426 -133.505702) (xy 81.07475 -133.475718) (xy 81.082578 -133.416262) (xy 81.098099 -133.358337)
			(xy 81.121048 -133.302933) (xy 81.151032 -133.250999) (xy 81.187538 -133.203423) (xy 81.229943 -133.161018)
			(xy 81.277519 -133.124512) (xy 81.329453 -133.094528) (xy 81.384857 -133.071579) (xy 81.442782 -133.056058)
			(xy 81.502238 -133.04823) (xy 81.562206 -133.04823) (xy 81.621662 -133.056058) (xy 81.679587 -133.071579)
			(xy 81.734991 -133.094528) (xy 81.752059 -133.104382) (xy 153.409904 -133.104382) (xy 153.409904 -132.240782)
			(xy 153.410394 -132.210798) (xy 153.418222 -132.151342) (xy 153.433743 -132.093417) (xy 153.456692 -132.038013)
			(xy 153.486676 -131.986079) (xy 153.523182 -131.938503) (xy 153.565587 -131.896098) (xy 153.613163 -131.859592)
			(xy 153.665097 -131.829608) (xy 153.720501 -131.806659) (xy 153.778426 -131.791138) (xy 153.837882 -131.78331)
			(xy 153.89785 -131.78331) (xy 153.957306 -131.791138) (xy 154.015231 -131.806659) (xy 154.070635 -131.829608)
			(xy 154.122569 -131.859592) (xy 154.170145 -131.896098) (xy 154.21255 -131.938503) (xy 154.249056 -131.986079)
			(xy 154.27904 -132.038013) (xy 154.301989 -132.093417) (xy 154.31751 -132.151342) (xy 154.325338 -132.210798)
			(xy 154.325828 -132.240782) (xy 154.325828 -133.096508) (xy 167.884856 -133.096508) (xy 167.884856 -132.232908)
			(xy 167.885346 -132.202924) (xy 167.893174 -132.143468) (xy 167.908695 -132.085543) (xy 167.931644 -132.030139)
			(xy 167.961628 -131.978205) (xy 167.998134 -131.930629) (xy 168.040539 -131.888224) (xy 168.088115 -131.851718)
			(xy 168.140049 -131.821734) (xy 168.195453 -131.798785) (xy 168.253378 -131.783264) (xy 168.312834 -131.775436)
			(xy 168.372802 -131.775436) (xy 168.432258 -131.783264) (xy 168.490183 -131.798785) (xy 168.545587 -131.821734)
			(xy 168.597521 -131.851718) (xy 168.645097 -131.888224) (xy 168.687502 -131.930629) (xy 168.724008 -131.978205)
			(xy 168.753992 -132.030139) (xy 168.776941 -132.085543) (xy 168.792462 -132.143468) (xy 168.80029 -132.202924)
			(xy 168.80078 -132.232908) (xy 168.80078 -132.577332) (xy 180.84546 -132.577332) (xy 180.84546 -131.713732)
			(xy 180.84595 -131.683764) (xy 180.853773 -131.624342) (xy 180.869286 -131.566449) (xy 180.892222 -131.511076)
			(xy 180.922189 -131.45917) (xy 180.958676 -131.41162) (xy 181.001056 -131.36924) (xy 181.048606 -131.332753)
			(xy 181.100512 -131.302786) (xy 181.155885 -131.27985) (xy 181.213778 -131.264337) (xy 181.2732 -131.256514)
			(xy 181.333136 -131.256514) (xy 181.392558 -131.264337) (xy 181.450451 -131.27985) (xy 181.505824 -131.302786)
			(xy 181.55773 -131.332753) (xy 181.60528 -131.36924) (xy 181.64766 -131.41162) (xy 181.684147 -131.45917)
			(xy 181.714114 -131.511076) (xy 181.73705 -131.566449) (xy 181.752563 -131.624342) (xy 181.760386 -131.683764)
			(xy 181.760876 -131.713732) (xy 181.760876 -132.575808) (xy 199.81672 -132.575808) (xy 199.81672 -131.712208)
			(xy 199.81721 -131.68224) (xy 199.825033 -131.622818) (xy 199.840546 -131.564925) (xy 199.863482 -131.509552)
			(xy 199.893449 -131.457646) (xy 199.929936 -131.410096) (xy 199.972316 -131.367716) (xy 200.019866 -131.331229)
			(xy 200.071772 -131.301262) (xy 200.127145 -131.278326) (xy 200.185038 -131.262813) (xy 200.24446 -131.25499)
			(xy 200.304396 -131.25499) (xy 200.363818 -131.262813) (xy 200.421711 -131.278326) (xy 200.469049 -131.297934)
			(xy 266.86764 -131.297934) (xy 266.86764 -130.434334) (xy 266.86813 -130.40435) (xy 266.875958 -130.344894)
			(xy 266.891479 -130.286969) (xy 266.914428 -130.231565) (xy 266.944412 -130.179631) (xy 266.980918 -130.132055)
			(xy 267.023323 -130.08965) (xy 267.070899 -130.053144) (xy 267.122833 -130.02316) (xy 267.178237 -130.000211)
			(xy 267.236162 -129.98469) (xy 267.295618 -129.976862) (xy 267.355586 -129.976862) (xy 267.415042 -129.98469)
			(xy 267.472967 -130.000211) (xy 267.528371 -130.02316) (xy 267.580305 -130.053144) (xy 267.627881 -130.08965)
			(xy 267.670286 -130.132055) (xy 267.706792 -130.179631) (xy 267.736776 -130.231565) (xy 267.759725 -130.286969)
			(xy 267.775246 -130.344894) (xy 267.783074 -130.40435) (xy 267.783564 -130.434334) (xy 267.783564 -131.29641)
			(xy 285.8389 -131.29641) (xy 285.8389 -130.43281) (xy 285.83939 -130.402826) (xy 285.847218 -130.34337)
			(xy 285.862739 -130.285445) (xy 285.885688 -130.230041) (xy 285.915672 -130.178107) (xy 285.952178 -130.130531)
			(xy 285.994583 -130.088126) (xy 286.042159 -130.05162) (xy 286.094093 -130.021636) (xy 286.149497 -129.998687)
			(xy 286.207422 -129.983166) (xy 286.266878 -129.975338) (xy 286.326846 -129.975338) (xy 286.386302 -129.983166)
			(xy 286.444227 -129.998687) (xy 286.499631 -130.021636) (xy 286.551565 -130.05162) (xy 286.599141 -130.088126)
			(xy 286.641546 -130.130531) (xy 286.678052 -130.178107) (xy 286.708036 -130.230041) (xy 286.730985 -130.285445)
			(xy 286.746506 -130.34337) (xy 286.754334 -130.402826) (xy 286.754824 -130.43281) (xy 286.754824 -130.777234)
			(xy 298.799504 -130.777234) (xy 298.799504 -129.913634) (xy 298.799994 -129.883666) (xy 298.807817 -129.824244)
			(xy 298.82333 -129.766351) (xy 298.846266 -129.710978) (xy 298.876233 -129.659072) (xy 298.91272 -129.611522)
			(xy 298.9551 -129.569142) (xy 299.00265 -129.532655) (xy 299.054556 -129.502688) (xy 299.109929 -129.479752)
			(xy 299.167822 -129.464239) (xy 299.227244 -129.456416) (xy 299.28718 -129.456416) (xy 299.346602 -129.464239)
			(xy 299.404495 -129.479752) (xy 299.459868 -129.502688) (xy 299.511774 -129.532655) (xy 299.559324 -129.569142)
			(xy 299.601704 -129.611522) (xy 299.638191 -129.659072) (xy 299.668158 -129.710978) (xy 299.691094 -129.766351)
			(xy 299.706607 -129.824244) (xy 299.71443 -129.883666) (xy 299.71492 -129.913634) (xy 299.71492 -130.769106)
			(xy 313.274456 -130.769106) (xy 313.274456 -129.905506) (xy 313.274946 -129.875538) (xy 313.282769 -129.816116)
			(xy 313.298282 -129.758223) (xy 313.321218 -129.70285) (xy 313.351185 -129.650944) (xy 313.387672 -129.603394)
			(xy 313.430052 -129.561014) (xy 313.477602 -129.524527) (xy 313.529508 -129.49456) (xy 313.584881 -129.471624)
			(xy 313.642774 -129.456111) (xy 313.702196 -129.448288) (xy 313.762132 -129.448288) (xy 313.821554 -129.456111)
			(xy 313.879447 -129.471624) (xy 313.93482 -129.49456) (xy 313.986726 -129.524527) (xy 314.034276 -129.561014)
			(xy 314.076656 -129.603394) (xy 314.113143 -129.650944) (xy 314.14311 -129.70285) (xy 314.166046 -129.758223)
			(xy 314.181559 -129.816116) (xy 314.189382 -129.875538) (xy 314.189872 -129.905506) (xy 314.189872 -130.769106)
			(xy 314.189382 -130.799074) (xy 314.181559 -130.858496) (xy 314.166046 -130.916389) (xy 314.14311 -130.971762)
			(xy 314.113143 -131.023668) (xy 314.076656 -131.071218) (xy 314.034276 -131.113598) (xy 313.986726 -131.150085)
			(xy 313.93482 -131.180052) (xy 313.879447 -131.202988) (xy 313.821554 -131.218501) (xy 313.762132 -131.226324)
			(xy 313.702196 -131.226324) (xy 313.642774 -131.218501) (xy 313.584881 -131.202988) (xy 313.529508 -131.180052)
			(xy 313.477602 -131.150085) (xy 313.430052 -131.113598) (xy 313.387672 -131.071218) (xy 313.351185 -131.023668)
			(xy 313.321218 -130.971762) (xy 313.298282 -130.916389) (xy 313.282769 -130.858496) (xy 313.274946 -130.799074)
			(xy 313.274456 -130.769106) (xy 299.71492 -130.769106) (xy 299.71492 -130.777234) (xy 299.71443 -130.807202)
			(xy 299.706607 -130.866624) (xy 299.691094 -130.924517) (xy 299.668158 -130.97989) (xy 299.638191 -131.031796)
			(xy 299.601704 -131.079346) (xy 299.559324 -131.121726) (xy 299.511774 -131.158213) (xy 299.459868 -131.18818)
			(xy 299.404495 -131.211116) (xy 299.346602 -131.226629) (xy 299.28718 -131.234452) (xy 299.227244 -131.234452)
			(xy 299.167822 -131.226629) (xy 299.109929 -131.211116) (xy 299.054556 -131.18818) (xy 299.00265 -131.158213)
			(xy 298.9551 -131.121726) (xy 298.91272 -131.079346) (xy 298.876233 -131.031796) (xy 298.846266 -130.97989)
			(xy 298.82333 -130.924517) (xy 298.807817 -130.866624) (xy 298.799994 -130.807202) (xy 298.799504 -130.777234)
			(xy 286.754824 -130.777234) (xy 286.754824 -131.29641) (xy 286.754334 -131.326394) (xy 286.746506 -131.38585)
			(xy 286.730985 -131.443775) (xy 286.708036 -131.499179) (xy 286.678052 -131.551113) (xy 286.641546 -131.598689)
			(xy 286.599141 -131.641094) (xy 286.551565 -131.6776) (xy 286.499631 -131.707584) (xy 286.444227 -131.730533)
			(xy 286.386302 -131.746054) (xy 286.326846 -131.753882) (xy 286.266878 -131.753882) (xy 286.207422 -131.746054)
			(xy 286.149497 -131.730533) (xy 286.094093 -131.707584) (xy 286.042159 -131.6776) (xy 285.994583 -131.641094)
			(xy 285.952178 -131.598689) (xy 285.915672 -131.551113) (xy 285.885688 -131.499179) (xy 285.862739 -131.443775)
			(xy 285.847218 -131.38585) (xy 285.83939 -131.326394) (xy 285.8389 -131.29641) (xy 267.783564 -131.29641)
			(xy 267.783564 -131.297934) (xy 267.783074 -131.327918) (xy 267.775246 -131.387374) (xy 267.759725 -131.445299)
			(xy 267.736776 -131.500703) (xy 267.706792 -131.552637) (xy 267.670286 -131.600213) (xy 267.627881 -131.642618)
			(xy 267.580305 -131.679124) (xy 267.528371 -131.709108) (xy 267.472967 -131.732057) (xy 267.415042 -131.747578)
			(xy 267.355586 -131.755406) (xy 267.295618 -131.755406) (xy 267.236162 -131.747578) (xy 267.178237 -131.732057)
			(xy 267.122833 -131.709108) (xy 267.070899 -131.679124) (xy 267.023323 -131.642618) (xy 266.980918 -131.600213)
			(xy 266.944412 -131.552637) (xy 266.914428 -131.500703) (xy 266.891479 -131.445299) (xy 266.875958 -131.387374)
			(xy 266.86813 -131.327918) (xy 266.86764 -131.297934) (xy 200.469049 -131.297934) (xy 200.477084 -131.301262)
			(xy 200.52899 -131.331229) (xy 200.57654 -131.367716) (xy 200.61892 -131.410096) (xy 200.655407 -131.457646)
			(xy 200.685374 -131.509552) (xy 200.70831 -131.564925) (xy 200.723823 -131.622818) (xy 200.731646 -131.68224)
			(xy 200.732136 -131.712208) (xy 200.732136 -132.575808) (xy 200.731646 -132.605776) (xy 200.723823 -132.665198)
			(xy 200.70831 -132.723091) (xy 200.685374 -132.778464) (xy 200.655407 -132.83037) (xy 200.61892 -132.87792)
			(xy 200.57654 -132.9203) (xy 200.52899 -132.956787) (xy 200.477084 -132.986754) (xy 200.421711 -133.00969)
			(xy 200.363818 -133.025203) (xy 200.304396 -133.033026) (xy 200.24446 -133.033026) (xy 200.185038 -133.025203)
			(xy 200.127145 -133.00969) (xy 200.071772 -132.986754) (xy 200.019866 -132.956787) (xy 199.972316 -132.9203)
			(xy 199.929936 -132.87792) (xy 199.893449 -132.83037) (xy 199.863482 -132.778464) (xy 199.840546 -132.723091)
			(xy 199.825033 -132.665198) (xy 199.81721 -132.605776) (xy 199.81672 -132.575808) (xy 181.760876 -132.575808)
			(xy 181.760876 -132.577332) (xy 181.760386 -132.6073) (xy 181.752563 -132.666722) (xy 181.73705 -132.724615)
			(xy 181.714114 -132.779988) (xy 181.684147 -132.831894) (xy 181.64766 -132.879444) (xy 181.60528 -132.921824)
			(xy 181.55773 -132.958311) (xy 181.505824 -132.988278) (xy 181.450451 -133.011214) (xy 181.392558 -133.026727)
			(xy 181.333136 -133.03455) (xy 181.2732 -133.03455) (xy 181.213778 -133.026727) (xy 181.155885 -133.011214)
			(xy 181.100512 -132.988278) (xy 181.048606 -132.958311) (xy 181.001056 -132.921824) (xy 180.958676 -132.879444)
			(xy 180.922189 -132.831894) (xy 180.892222 -132.779988) (xy 180.869286 -132.724615) (xy 180.853773 -132.666722)
			(xy 180.84595 -132.6073) (xy 180.84546 -132.577332) (xy 168.80078 -132.577332) (xy 168.80078 -133.096508)
			(xy 168.80029 -133.126492) (xy 168.792462 -133.185948) (xy 168.776941 -133.243873) (xy 168.753992 -133.299277)
			(xy 168.724008 -133.351211) (xy 168.687502 -133.398787) (xy 168.645097 -133.441192) (xy 168.597521 -133.477698)
			(xy 168.545587 -133.507682) (xy 168.490183 -133.530631) (xy 168.432258 -133.546152) (xy 168.372802 -133.55398)
			(xy 168.312834 -133.55398) (xy 168.253378 -133.546152) (xy 168.195453 -133.530631) (xy 168.140049 -133.507682)
			(xy 168.088115 -133.477698) (xy 168.040539 -133.441192) (xy 167.998134 -133.398787) (xy 167.961628 -133.351211)
			(xy 167.931644 -133.299277) (xy 167.908695 -133.243873) (xy 167.893174 -133.185948) (xy 167.885346 -133.126492)
			(xy 167.884856 -133.096508) (xy 154.325828 -133.096508) (xy 154.325828 -133.104382) (xy 154.325338 -133.134366)
			(xy 154.31751 -133.193822) (xy 154.301989 -133.251747) (xy 154.27904 -133.307151) (xy 154.249056 -133.359085)
			(xy 154.21255 -133.406661) (xy 154.170145 -133.449066) (xy 154.122569 -133.485572) (xy 154.070635 -133.515556)
			(xy 154.015231 -133.538505) (xy 153.957306 -133.554026) (xy 153.89785 -133.561854) (xy 153.837882 -133.561854)
			(xy 153.778426 -133.554026) (xy 153.720501 -133.538505) (xy 153.665097 -133.515556) (xy 153.613163 -133.485572)
			(xy 153.565587 -133.449066) (xy 153.523182 -133.406661) (xy 153.486676 -133.359085) (xy 153.456692 -133.307151)
			(xy 153.433743 -133.251747) (xy 153.418222 -133.193822) (xy 153.410394 -133.134366) (xy 153.409904 -133.104382)
			(xy 81.752059 -133.104382) (xy 81.786925 -133.124512) (xy 81.834501 -133.161018) (xy 81.876906 -133.203423)
			(xy 81.913412 -133.250999) (xy 81.943396 -133.302933) (xy 81.966345 -133.358337) (xy 81.981866 -133.416262)
			(xy 81.989694 -133.475718) (xy 81.990184 -133.505702) (xy 81.990184 -134.369302) (xy 81.989694 -134.399286)
			(xy 81.981866 -134.458742) (xy 81.966345 -134.516667) (xy 81.943396 -134.572071) (xy 81.913412 -134.624005)
			(xy 81.876906 -134.671581) (xy 81.834501 -134.713986) (xy 81.786925 -134.750492) (xy 81.734991 -134.780476)
			(xy 81.679587 -134.803425) (xy 81.621662 -134.818946) (xy 81.562206 -134.826774) (xy 81.502238 -134.826774)
			(xy 81.442782 -134.818946) (xy 81.384857 -134.803425) (xy 81.329453 -134.780476) (xy 81.277519 -134.750492)
			(xy 81.229943 -134.713986) (xy 81.187538 -134.671581) (xy 81.151032 -134.624005) (xy 81.121048 -134.572071)
			(xy 81.098099 -134.516667) (xy 81.082578 -134.458742) (xy 81.07475 -134.399286) (xy 81.07426 -134.369302)
			(xy 67.515232 -134.369302) (xy 67.515232 -134.377176) (xy 67.514742 -134.40716) (xy 67.506914 -134.466616)
			(xy 67.491393 -134.524541) (xy 67.468444 -134.579945) (xy 67.43846 -134.631879) (xy 67.401954 -134.679455)
			(xy 67.359549 -134.72186) (xy 67.311973 -134.758366) (xy 67.260039 -134.78835) (xy 67.204635 -134.811299)
			(xy 67.14671 -134.82682) (xy 67.087254 -134.834648) (xy 67.027286 -134.834648) (xy 66.96783 -134.82682)
			(xy 66.909905 -134.811299) (xy 66.854501 -134.78835) (xy 66.802567 -134.758366) (xy 66.754991 -134.72186)
			(xy 66.712586 -134.679455) (xy 66.67608 -134.631879) (xy 66.646096 -134.579945) (xy 66.623147 -134.524541)
			(xy 66.607626 -134.466616) (xy 66.599798 -134.40716) (xy 66.599308 -134.377176) (xy 54.554628 -134.377176)
			(xy 54.554628 -134.896352) (xy 54.554138 -134.92632) (xy 54.546315 -134.985742) (xy 54.530802 -135.043635)
			(xy 54.507866 -135.099008) (xy 54.477899 -135.150914) (xy 54.441412 -135.198464) (xy 54.399032 -135.240844)
			(xy 54.351482 -135.277331) (xy 54.299576 -135.307298) (xy 54.244203 -135.330234) (xy 54.18631 -135.345747)
			(xy 54.126888 -135.35357) (xy 54.066952 -135.35357) (xy 54.00753 -135.345747) (xy 53.949637 -135.330234)
			(xy 53.894264 -135.307298) (xy 53.842358 -135.277331) (xy 53.794808 -135.240844) (xy 53.752428 -135.198464)
			(xy 53.715941 -135.150914) (xy 53.685974 -135.099008) (xy 53.663038 -135.043635) (xy 53.647525 -134.985742)
			(xy 53.639702 -134.92632) (xy 53.639212 -134.896352) (xy 35.583368 -134.896352) (xy 35.583368 -134.897876)
			(xy 35.582878 -134.927844) (xy 35.575055 -134.987266) (xy 35.559542 -135.045159) (xy 35.536606 -135.100532)
			(xy 35.506639 -135.152438) (xy 35.470152 -135.199988) (xy 35.427772 -135.242368) (xy 35.380222 -135.278855)
			(xy 35.328316 -135.308822) (xy 35.272943 -135.331758) (xy 35.21505 -135.347271) (xy 35.155628 -135.355094)
			(xy 35.095692 -135.355094) (xy 35.03627 -135.347271) (xy 34.978377 -135.331758) (xy 34.923004 -135.308822)
			(xy 34.871098 -135.278855) (xy 34.823548 -135.242368) (xy 34.781168 -135.199988) (xy 34.744681 -135.152438)
			(xy 34.714714 -135.100532) (xy 34.691778 -135.045159) (xy 34.676265 -134.987266) (xy 34.668442 -134.927844)
			(xy 34.667952 -134.897876) (xy 4.308094 -134.897876) (xy 4.308094 -136.704324) (xy 37.31006 -136.704324)
			(xy 37.31006 -135.840724) (xy 37.31055 -135.810756) (xy 37.318373 -135.751334) (xy 37.333886 -135.693441)
			(xy 37.356822 -135.638068) (xy 37.386789 -135.586162) (xy 37.423276 -135.538612) (xy 37.465656 -135.496232)
			(xy 37.513206 -135.459745) (xy 37.565112 -135.429778) (xy 37.620485 -135.406842) (xy 37.678378 -135.391329)
			(xy 37.7378 -135.383506) (xy 37.797736 -135.383506) (xy 37.857158 -135.391329) (xy 37.915051 -135.406842)
			(xy 37.970424 -135.429778) (xy 38.02233 -135.459745) (xy 38.06988 -135.496232) (xy 38.11226 -135.538612)
			(xy 38.148747 -135.586162) (xy 38.178714 -135.638068) (xy 38.20165 -135.693441) (xy 38.217163 -135.751334)
			(xy 38.224986 -135.810756) (xy 38.225476 -135.840724) (xy 38.225476 -136.69645) (xy 51.785012 -136.69645)
			(xy 51.785012 -135.83285) (xy 51.785502 -135.802882) (xy 51.793325 -135.74346) (xy 51.808838 -135.685567)
			(xy 51.831774 -135.630194) (xy 51.861741 -135.578288) (xy 51.898228 -135.530738) (xy 51.940608 -135.488358)
			(xy 51.988158 -135.451871) (xy 52.040064 -135.421904) (xy 52.095437 -135.398968) (xy 52.15333 -135.383455)
			(xy 52.212752 -135.375632) (xy 52.272688 -135.375632) (xy 52.33211 -135.383455) (xy 52.390003 -135.398968)
			(xy 52.445376 -135.421904) (xy 52.497282 -135.451871) (xy 52.544832 -135.488358) (xy 52.587212 -135.530738)
			(xy 52.623699 -135.578288) (xy 52.653666 -135.630194) (xy 52.676602 -135.685567) (xy 52.692115 -135.74346)
			(xy 52.699938 -135.802882) (xy 52.700428 -135.83285) (xy 52.700428 -136.177274) (xy 64.745108 -136.177274)
			(xy 64.745108 -135.313674) (xy 64.745598 -135.28369) (xy 64.753426 -135.224234) (xy 64.768947 -135.166309)
			(xy 64.791896 -135.110905) (xy 64.82188 -135.058971) (xy 64.858386 -135.011395) (xy 64.900791 -134.96899)
			(xy 64.948367 -134.932484) (xy 65.000301 -134.9025) (xy 65.055705 -134.879551) (xy 65.11363 -134.86403)
			(xy 65.173086 -134.856202) (xy 65.233054 -134.856202) (xy 65.29251 -134.86403) (xy 65.350435 -134.879551)
			(xy 65.405839 -134.9025) (xy 65.457773 -134.932484) (xy 65.505349 -134.96899) (xy 65.547754 -135.011395)
			(xy 65.58426 -135.058971) (xy 65.614244 -135.110905) (xy 65.637193 -135.166309) (xy 65.652714 -135.224234)
			(xy 65.660542 -135.28369) (xy 65.661032 -135.313674) (xy 65.661032 -136.17575) (xy 83.716368 -136.17575)
			(xy 83.716368 -135.31215) (xy 83.716858 -135.282166) (xy 83.724686 -135.22271) (xy 83.740207 -135.164785)
			(xy 83.763156 -135.109381) (xy 83.79314 -135.057447) (xy 83.829646 -135.009871) (xy 83.872051 -134.967466)
			(xy 83.919627 -134.93096) (xy 83.971561 -134.900976) (xy 84.026965 -134.878027) (xy 84.08489 -134.862506)
			(xy 84.144346 -134.854678) (xy 84.204314 -134.854678) (xy 84.26377 -134.862506) (xy 84.321695 -134.878027)
			(xy 84.369615 -134.897876) (xy 150.767796 -134.897876) (xy 150.767796 -134.034276) (xy 150.768286 -134.004292)
			(xy 150.776114 -133.944836) (xy 150.791635 -133.886911) (xy 150.814584 -133.831507) (xy 150.844568 -133.779573)
			(xy 150.881074 -133.731997) (xy 150.923479 -133.689592) (xy 150.971055 -133.653086) (xy 151.022989 -133.623102)
			(xy 151.078393 -133.600153) (xy 151.136318 -133.584632) (xy 151.195774 -133.576804) (xy 151.255742 -133.576804)
			(xy 151.315198 -133.584632) (xy 151.373123 -133.600153) (xy 151.428527 -133.623102) (xy 151.480461 -133.653086)
			(xy 151.528037 -133.689592) (xy 151.570442 -133.731997) (xy 151.606948 -133.779573) (xy 151.636932 -133.831507)
			(xy 151.659881 -133.886911) (xy 151.675402 -133.944836) (xy 151.68323 -134.004292) (xy 151.68372 -134.034276)
			(xy 151.68372 -134.896352) (xy 169.739056 -134.896352) (xy 169.739056 -134.032752) (xy 169.739546 -134.002768)
			(xy 169.747374 -133.943312) (xy 169.762895 -133.885387) (xy 169.785844 -133.829983) (xy 169.815828 -133.778049)
			(xy 169.852334 -133.730473) (xy 169.894739 -133.688068) (xy 169.942315 -133.651562) (xy 169.994249 -133.621578)
			(xy 170.049653 -133.598629) (xy 170.107578 -133.583108) (xy 170.167034 -133.57528) (xy 170.227002 -133.57528)
			(xy 170.286458 -133.583108) (xy 170.344383 -133.598629) (xy 170.399787 -133.621578) (xy 170.451721 -133.651562)
			(xy 170.499297 -133.688068) (xy 170.541702 -133.730473) (xy 170.578208 -133.778049) (xy 170.608192 -133.829983)
			(xy 170.631141 -133.885387) (xy 170.646662 -133.943312) (xy 170.65449 -134.002768) (xy 170.65498 -134.032752)
			(xy 170.65498 -134.377176) (xy 182.69966 -134.377176) (xy 182.69966 -133.513576) (xy 182.70015 -133.483608)
			(xy 182.707973 -133.424186) (xy 182.723486 -133.366293) (xy 182.746422 -133.31092) (xy 182.776389 -133.259014)
			(xy 182.812876 -133.211464) (xy 182.855256 -133.169084) (xy 182.902806 -133.132597) (xy 182.954712 -133.10263)
			(xy 183.010085 -133.079694) (xy 183.067978 -133.064181) (xy 183.1274 -133.056358) (xy 183.187336 -133.056358)
			(xy 183.246758 -133.064181) (xy 183.304651 -133.079694) (xy 183.360024 -133.10263) (xy 183.41193 -133.132597)
			(xy 183.45948 -133.169084) (xy 183.50186 -133.211464) (xy 183.538347 -133.259014) (xy 183.568314 -133.31092)
			(xy 183.59125 -133.366293) (xy 183.606763 -133.424186) (xy 183.614586 -133.483608) (xy 183.615076 -133.513576)
			(xy 183.615076 -134.369302) (xy 197.174612 -134.369302) (xy 197.174612 -133.505702) (xy 197.175102 -133.475734)
			(xy 197.182925 -133.416312) (xy 197.198438 -133.358419) (xy 197.221374 -133.303046) (xy 197.251341 -133.25114)
			(xy 197.287828 -133.20359) (xy 197.330208 -133.16121) (xy 197.377758 -133.124723) (xy 197.429664 -133.094756)
			(xy 197.485037 -133.07182) (xy 197.54293 -133.056307) (xy 197.602352 -133.048484) (xy 197.662288 -133.048484)
			(xy 197.72171 -133.056307) (xy 197.779603 -133.07182) (xy 197.834976 -133.094756) (xy 197.851649 -133.104382)
			(xy 269.509748 -133.104382) (xy 269.509748 -132.240782) (xy 269.510238 -132.210798) (xy 269.518066 -132.151342)
			(xy 269.533587 -132.093417) (xy 269.556536 -132.038013) (xy 269.58652 -131.986079) (xy 269.623026 -131.938503)
			(xy 269.665431 -131.896098) (xy 269.713007 -131.859592) (xy 269.764941 -131.829608) (xy 269.820345 -131.806659)
			(xy 269.87827 -131.791138) (xy 269.937726 -131.78331) (xy 269.997694 -131.78331) (xy 270.05715 -131.791138)
			(xy 270.115075 -131.806659) (xy 270.170479 -131.829608) (xy 270.222413 -131.859592) (xy 270.269989 -131.896098)
			(xy 270.312394 -131.938503) (xy 270.3489 -131.986079) (xy 270.378884 -132.038013) (xy 270.401833 -132.093417)
			(xy 270.417354 -132.151342) (xy 270.425182 -132.210798) (xy 270.425672 -132.240782) (xy 270.425672 -133.096508)
			(xy 283.9847 -133.096508) (xy 283.9847 -132.232908) (xy 283.98519 -132.202924) (xy 283.993018 -132.143468)
			(xy 284.008539 -132.085543) (xy 284.031488 -132.030139) (xy 284.061472 -131.978205) (xy 284.097978 -131.930629)
			(xy 284.140383 -131.888224) (xy 284.187959 -131.851718) (xy 284.239893 -131.821734) (xy 284.295297 -131.798785)
			(xy 284.353222 -131.783264) (xy 284.412678 -131.775436) (xy 284.472646 -131.775436) (xy 284.532102 -131.783264)
			(xy 284.590027 -131.798785) (xy 284.645431 -131.821734) (xy 284.697365 -131.851718) (xy 284.744941 -131.888224)
			(xy 284.787346 -131.930629) (xy 284.823852 -131.978205) (xy 284.853836 -132.030139) (xy 284.876785 -132.085543)
			(xy 284.892306 -132.143468) (xy 284.900134 -132.202924) (xy 284.900624 -132.232908) (xy 284.900624 -132.577332)
			(xy 296.945304 -132.577332) (xy 296.945304 -131.713732) (xy 296.945794 -131.683764) (xy 296.953617 -131.624342)
			(xy 296.96913 -131.566449) (xy 296.992066 -131.511076) (xy 297.022033 -131.45917) (xy 297.05852 -131.41162)
			(xy 297.1009 -131.36924) (xy 297.14845 -131.332753) (xy 297.200356 -131.302786) (xy 297.255729 -131.27985)
			(xy 297.313622 -131.264337) (xy 297.373044 -131.256514) (xy 297.43298 -131.256514) (xy 297.492402 -131.264337)
			(xy 297.550295 -131.27985) (xy 297.605668 -131.302786) (xy 297.657574 -131.332753) (xy 297.705124 -131.36924)
			(xy 297.747504 -131.41162) (xy 297.783991 -131.45917) (xy 297.813958 -131.511076) (xy 297.836894 -131.566449)
			(xy 297.852407 -131.624342) (xy 297.86023 -131.683764) (xy 297.86072 -131.713732) (xy 297.86072 -132.575808)
			(xy 315.916564 -132.575808) (xy 315.916564 -131.712208) (xy 315.917054 -131.68224) (xy 315.924877 -131.622818)
			(xy 315.94039 -131.564925) (xy 315.963326 -131.509552) (xy 315.993293 -131.457646) (xy 316.02978 -131.410096)
			(xy 316.07216 -131.367716) (xy 316.11971 -131.331229) (xy 316.171616 -131.301262) (xy 316.226989 -131.278326)
			(xy 316.284882 -131.262813) (xy 316.344304 -131.25499) (xy 316.40424 -131.25499) (xy 316.463662 -131.262813)
			(xy 316.521555 -131.278326) (xy 316.568893 -131.297934) (xy 382.967992 -131.297934) (xy 382.967992 -130.434334)
			(xy 382.968482 -130.404366) (xy 382.976305 -130.344944) (xy 382.991818 -130.287051) (xy 383.014754 -130.231678)
			(xy 383.044721 -130.179772) (xy 383.081208 -130.132222) (xy 383.123588 -130.089842) (xy 383.171138 -130.053355)
			(xy 383.223044 -130.023388) (xy 383.278417 -130.000452) (xy 383.33631 -129.984939) (xy 383.395732 -129.977116)
			(xy 383.455668 -129.977116) (xy 383.51509 -129.984939) (xy 383.572983 -130.000452) (xy 383.628356 -130.023388)
			(xy 383.680262 -130.053355) (xy 383.727812 -130.089842) (xy 383.770192 -130.132222) (xy 383.806679 -130.179772)
			(xy 383.836646 -130.231678) (xy 383.859582 -130.287051) (xy 383.875095 -130.344944) (xy 383.882918 -130.404366)
			(xy 383.883408 -130.434334) (xy 383.883408 -131.29641) (xy 401.939252 -131.29641) (xy 401.939252 -130.43281)
			(xy 401.939742 -130.402842) (xy 401.947565 -130.34342) (xy 401.963078 -130.285527) (xy 401.986014 -130.230154)
			(xy 402.015981 -130.178248) (xy 402.052468 -130.130698) (xy 402.094848 -130.088318) (xy 402.142398 -130.051831)
			(xy 402.194304 -130.021864) (xy 402.249677 -129.998928) (xy 402.30757 -129.983415) (xy 402.366992 -129.975592)
			(xy 402.426928 -129.975592) (xy 402.48635 -129.983415) (xy 402.544243 -129.998928) (xy 402.599616 -130.021864)
			(xy 402.651522 -130.051831) (xy 402.699072 -130.088318) (xy 402.741452 -130.130698) (xy 402.777939 -130.178248)
			(xy 402.807906 -130.230154) (xy 402.830842 -130.285527) (xy 402.846355 -130.34342) (xy 402.854178 -130.402842)
			(xy 402.854668 -130.43281) (xy 402.854668 -130.777234) (xy 414.899348 -130.777234) (xy 414.899348 -129.913634)
			(xy 414.899838 -129.88365) (xy 414.907666 -129.824194) (xy 414.923187 -129.766269) (xy 414.946136 -129.710865)
			(xy 414.97612 -129.658931) (xy 415.012626 -129.611355) (xy 415.055031 -129.56895) (xy 415.102607 -129.532444)
			(xy 415.154541 -129.50246) (xy 415.209945 -129.479511) (xy 415.26787 -129.46399) (xy 415.327326 -129.456162)
			(xy 415.387294 -129.456162) (xy 415.44675 -129.46399) (xy 415.504675 -129.479511) (xy 415.560079 -129.50246)
			(xy 415.612013 -129.532444) (xy 415.659589 -129.56895) (xy 415.701994 -129.611355) (xy 415.7385 -129.658931)
			(xy 415.768484 -129.710865) (xy 415.791433 -129.766269) (xy 415.806954 -129.824194) (xy 415.814782 -129.88365)
			(xy 415.815272 -129.913634) (xy 415.815272 -130.769106) (xy 429.3743 -130.769106) (xy 429.3743 -129.905506)
			(xy 429.37479 -129.875522) (xy 429.382618 -129.816066) (xy 429.398139 -129.758141) (xy 429.421088 -129.702737)
			(xy 429.451072 -129.650803) (xy 429.487578 -129.603227) (xy 429.529983 -129.560822) (xy 429.577559 -129.524316)
			(xy 429.629493 -129.494332) (xy 429.684897 -129.471383) (xy 429.742822 -129.455862) (xy 429.802278 -129.448034)
			(xy 429.862246 -129.448034) (xy 429.921702 -129.455862) (xy 429.979627 -129.471383) (xy 430.035031 -129.494332)
			(xy 430.086965 -129.524316) (xy 430.134541 -129.560822) (xy 430.176946 -129.603227) (xy 430.213452 -129.650803)
			(xy 430.243436 -129.702737) (xy 430.266385 -129.758141) (xy 430.281906 -129.816066) (xy 430.289734 -129.875522)
			(xy 430.290224 -129.905506) (xy 430.290224 -130.769106) (xy 430.289734 -130.79909) (xy 430.281906 -130.858546)
			(xy 430.266385 -130.916471) (xy 430.243436 -130.971875) (xy 430.213452 -131.023809) (xy 430.176946 -131.071385)
			(xy 430.134541 -131.11379) (xy 430.086965 -131.150296) (xy 430.035031 -131.18028) (xy 429.979627 -131.203229)
			(xy 429.921702 -131.21875) (xy 429.862246 -131.226578) (xy 429.802278 -131.226578) (xy 429.742822 -131.21875)
			(xy 429.684897 -131.203229) (xy 429.629493 -131.18028) (xy 429.577559 -131.150296) (xy 429.529983 -131.11379)
			(xy 429.487578 -131.071385) (xy 429.451072 -131.023809) (xy 429.421088 -130.971875) (xy 429.398139 -130.916471)
			(xy 429.382618 -130.858546) (xy 429.37479 -130.79909) (xy 429.3743 -130.769106) (xy 415.815272 -130.769106)
			(xy 415.815272 -130.777234) (xy 415.814782 -130.807218) (xy 415.806954 -130.866674) (xy 415.791433 -130.924599)
			(xy 415.768484 -130.980003) (xy 415.7385 -131.031937) (xy 415.701994 -131.079513) (xy 415.659589 -131.121918)
			(xy 415.612013 -131.158424) (xy 415.560079 -131.188408) (xy 415.504675 -131.211357) (xy 415.44675 -131.226878)
			(xy 415.387294 -131.234706) (xy 415.327326 -131.234706) (xy 415.26787 -131.226878) (xy 415.209945 -131.211357)
			(xy 415.154541 -131.188408) (xy 415.102607 -131.158424) (xy 415.055031 -131.121918) (xy 415.012626 -131.079513)
			(xy 414.97612 -131.031937) (xy 414.946136 -130.980003) (xy 414.923187 -130.924599) (xy 414.907666 -130.866674)
			(xy 414.899838 -130.807218) (xy 414.899348 -130.777234) (xy 402.854668 -130.777234) (xy 402.854668 -131.29641)
			(xy 402.854178 -131.326378) (xy 402.846355 -131.3858) (xy 402.830842 -131.443693) (xy 402.807906 -131.499066)
			(xy 402.777939 -131.550972) (xy 402.741452 -131.598522) (xy 402.699072 -131.640902) (xy 402.651522 -131.677389)
			(xy 402.599616 -131.707356) (xy 402.544243 -131.730292) (xy 402.48635 -131.745805) (xy 402.426928 -131.753628)
			(xy 402.366992 -131.753628) (xy 402.30757 -131.745805) (xy 402.249677 -131.730292) (xy 402.194304 -131.707356)
			(xy 402.142398 -131.677389) (xy 402.094848 -131.640902) (xy 402.052468 -131.598522) (xy 402.015981 -131.550972)
			(xy 401.986014 -131.499066) (xy 401.963078 -131.443693) (xy 401.947565 -131.3858) (xy 401.939742 -131.326378)
			(xy 401.939252 -131.29641) (xy 383.883408 -131.29641) (xy 383.883408 -131.297934) (xy 383.882918 -131.327902)
			(xy 383.875095 -131.387324) (xy 383.859582 -131.445217) (xy 383.836646 -131.50059) (xy 383.806679 -131.552496)
			(xy 383.770192 -131.600046) (xy 383.727812 -131.642426) (xy 383.680262 -131.678913) (xy 383.628356 -131.70888)
			(xy 383.572983 -131.731816) (xy 383.51509 -131.747329) (xy 383.455668 -131.755152) (xy 383.395732 -131.755152)
			(xy 383.33631 -131.747329) (xy 383.278417 -131.731816) (xy 383.223044 -131.70888) (xy 383.171138 -131.678913)
			(xy 383.123588 -131.642426) (xy 383.081208 -131.600046) (xy 383.044721 -131.552496) (xy 383.014754 -131.50059)
			(xy 382.991818 -131.445217) (xy 382.976305 -131.387324) (xy 382.968482 -131.327902) (xy 382.967992 -131.297934)
			(xy 316.568893 -131.297934) (xy 316.576928 -131.301262) (xy 316.628834 -131.331229) (xy 316.676384 -131.367716)
			(xy 316.718764 -131.410096) (xy 316.755251 -131.457646) (xy 316.785218 -131.509552) (xy 316.808154 -131.564925)
			(xy 316.823667 -131.622818) (xy 316.83149 -131.68224) (xy 316.83198 -131.712208) (xy 316.83198 -132.575808)
			(xy 316.83149 -132.605776) (xy 316.823667 -132.665198) (xy 316.808154 -132.723091) (xy 316.785218 -132.778464)
			(xy 316.755251 -132.83037) (xy 316.718764 -132.87792) (xy 316.676384 -132.9203) (xy 316.628834 -132.956787)
			(xy 316.576928 -132.986754) (xy 316.521555 -133.00969) (xy 316.463662 -133.025203) (xy 316.40424 -133.033026)
			(xy 316.344304 -133.033026) (xy 316.284882 -133.025203) (xy 316.226989 -133.00969) (xy 316.171616 -132.986754)
			(xy 316.11971 -132.956787) (xy 316.07216 -132.9203) (xy 316.02978 -132.87792) (xy 315.993293 -132.83037)
			(xy 315.963326 -132.778464) (xy 315.94039 -132.723091) (xy 315.924877 -132.665198) (xy 315.917054 -132.605776)
			(xy 315.916564 -132.575808) (xy 297.86072 -132.575808) (xy 297.86072 -132.577332) (xy 297.86023 -132.6073)
			(xy 297.852407 -132.666722) (xy 297.836894 -132.724615) (xy 297.813958 -132.779988) (xy 297.783991 -132.831894)
			(xy 297.747504 -132.879444) (xy 297.705124 -132.921824) (xy 297.657574 -132.958311) (xy 297.605668 -132.988278)
			(xy 297.550295 -133.011214) (xy 297.492402 -133.026727) (xy 297.43298 -133.03455) (xy 297.373044 -133.03455)
			(xy 297.313622 -133.026727) (xy 297.255729 -133.011214) (xy 297.200356 -132.988278) (xy 297.14845 -132.958311)
			(xy 297.1009 -132.921824) (xy 297.05852 -132.879444) (xy 297.022033 -132.831894) (xy 296.992066 -132.779988)
			(xy 296.96913 -132.724615) (xy 296.953617 -132.666722) (xy 296.945794 -132.6073) (xy 296.945304 -132.577332)
			(xy 284.900624 -132.577332) (xy 284.900624 -133.096508) (xy 284.900134 -133.126492) (xy 284.892306 -133.185948)
			(xy 284.876785 -133.243873) (xy 284.853836 -133.299277) (xy 284.823852 -133.351211) (xy 284.787346 -133.398787)
			(xy 284.744941 -133.441192) (xy 284.697365 -133.477698) (xy 284.645431 -133.507682) (xy 284.590027 -133.530631)
			(xy 284.532102 -133.546152) (xy 284.472646 -133.55398) (xy 284.412678 -133.55398) (xy 284.353222 -133.546152)
			(xy 284.295297 -133.530631) (xy 284.239893 -133.507682) (xy 284.187959 -133.477698) (xy 284.140383 -133.441192)
			(xy 284.097978 -133.398787) (xy 284.061472 -133.351211) (xy 284.031488 -133.299277) (xy 284.008539 -133.243873)
			(xy 283.993018 -133.185948) (xy 283.98519 -133.126492) (xy 283.9847 -133.096508) (xy 270.425672 -133.096508)
			(xy 270.425672 -133.104382) (xy 270.425182 -133.134366) (xy 270.417354 -133.193822) (xy 270.401833 -133.251747)
			(xy 270.378884 -133.307151) (xy 270.3489 -133.359085) (xy 270.312394 -133.406661) (xy 270.269989 -133.449066)
			(xy 270.222413 -133.485572) (xy 270.170479 -133.515556) (xy 270.115075 -133.538505) (xy 270.05715 -133.554026)
			(xy 269.997694 -133.561854) (xy 269.937726 -133.561854) (xy 269.87827 -133.554026) (xy 269.820345 -133.538505)
			(xy 269.764941 -133.515556) (xy 269.713007 -133.485572) (xy 269.665431 -133.449066) (xy 269.623026 -133.406661)
			(xy 269.58652 -133.359085) (xy 269.556536 -133.307151) (xy 269.533587 -133.251747) (xy 269.518066 -133.193822)
			(xy 269.510238 -133.134366) (xy 269.509748 -133.104382) (xy 197.851649 -133.104382) (xy 197.886882 -133.124723)
			(xy 197.934432 -133.16121) (xy 197.976812 -133.20359) (xy 198.013299 -133.25114) (xy 198.043266 -133.303046)
			(xy 198.066202 -133.358419) (xy 198.081715 -133.416312) (xy 198.089538 -133.475734) (xy 198.090028 -133.505702)
			(xy 198.090028 -134.369302) (xy 198.089538 -134.39927) (xy 198.081715 -134.458692) (xy 198.066202 -134.516585)
			(xy 198.043266 -134.571958) (xy 198.013299 -134.623864) (xy 197.976812 -134.671414) (xy 197.934432 -134.713794)
			(xy 197.886882 -134.750281) (xy 197.834976 -134.780248) (xy 197.779603 -134.803184) (xy 197.72171 -134.818697)
			(xy 197.662288 -134.82652) (xy 197.602352 -134.82652) (xy 197.54293 -134.818697) (xy 197.485037 -134.803184)
			(xy 197.429664 -134.780248) (xy 197.377758 -134.750281) (xy 197.330208 -134.713794) (xy 197.287828 -134.671414)
			(xy 197.251341 -134.623864) (xy 197.221374 -134.571958) (xy 197.198438 -134.516585) (xy 197.182925 -134.458692)
			(xy 197.175102 -134.39927) (xy 197.174612 -134.369302) (xy 183.615076 -134.369302) (xy 183.615076 -134.377176)
			(xy 183.614586 -134.407144) (xy 183.606763 -134.466566) (xy 183.59125 -134.524459) (xy 183.568314 -134.579832)
			(xy 183.538347 -134.631738) (xy 183.50186 -134.679288) (xy 183.45948 -134.721668) (xy 183.41193 -134.758155)
			(xy 183.360024 -134.788122) (xy 183.304651 -134.811058) (xy 183.246758 -134.826571) (xy 183.187336 -134.834394)
			(xy 183.1274 -134.834394) (xy 183.067978 -134.826571) (xy 183.010085 -134.811058) (xy 182.954712 -134.788122)
			(xy 182.902806 -134.758155) (xy 182.855256 -134.721668) (xy 182.812876 -134.679288) (xy 182.776389 -134.631738)
			(xy 182.746422 -134.579832) (xy 182.723486 -134.524459) (xy 182.707973 -134.466566) (xy 182.70015 -134.407144)
			(xy 182.69966 -134.377176) (xy 170.65498 -134.377176) (xy 170.65498 -134.896352) (xy 170.65449 -134.926336)
			(xy 170.646662 -134.985792) (xy 170.631141 -135.043717) (xy 170.608192 -135.099121) (xy 170.578208 -135.151055)
			(xy 170.541702 -135.198631) (xy 170.499297 -135.241036) (xy 170.451721 -135.277542) (xy 170.399787 -135.307526)
			(xy 170.344383 -135.330475) (xy 170.286458 -135.345996) (xy 170.227002 -135.353824) (xy 170.167034 -135.353824)
			(xy 170.107578 -135.345996) (xy 170.049653 -135.330475) (xy 169.994249 -135.307526) (xy 169.942315 -135.277542)
			(xy 169.894739 -135.241036) (xy 169.852334 -135.198631) (xy 169.815828 -135.151055) (xy 169.785844 -135.099121)
			(xy 169.762895 -135.043717) (xy 169.747374 -134.985792) (xy 169.739546 -134.926336) (xy 169.739056 -134.896352)
			(xy 151.68372 -134.896352) (xy 151.68372 -134.897876) (xy 151.68323 -134.92786) (xy 151.675402 -134.987316)
			(xy 151.659881 -135.045241) (xy 151.636932 -135.100645) (xy 151.606948 -135.152579) (xy 151.570442 -135.200155)
			(xy 151.528037 -135.24256) (xy 151.480461 -135.279066) (xy 151.428527 -135.30905) (xy 151.373123 -135.331999)
			(xy 151.315198 -135.34752) (xy 151.255742 -135.355348) (xy 151.195774 -135.355348) (xy 151.136318 -135.34752)
			(xy 151.078393 -135.331999) (xy 151.022989 -135.30905) (xy 150.971055 -135.279066) (xy 150.923479 -135.24256)
			(xy 150.881074 -135.200155) (xy 150.844568 -135.152579) (xy 150.814584 -135.100645) (xy 150.791635 -135.045241)
			(xy 150.776114 -134.987316) (xy 150.768286 -134.92786) (xy 150.767796 -134.897876) (xy 84.369615 -134.897876)
			(xy 84.377099 -134.900976) (xy 84.429033 -134.93096) (xy 84.476609 -134.967466) (xy 84.519014 -135.009871)
			(xy 84.55552 -135.057447) (xy 84.585504 -135.109381) (xy 84.608453 -135.164785) (xy 84.623974 -135.22271)
			(xy 84.631802 -135.282166) (xy 84.632292 -135.31215) (xy 84.632292 -136.17575) (xy 84.631802 -136.205734)
			(xy 84.623974 -136.26519) (xy 84.608453 -136.323115) (xy 84.585504 -136.378519) (xy 84.55552 -136.430453)
			(xy 84.519014 -136.478029) (xy 84.476609 -136.520434) (xy 84.429033 -136.55694) (xy 84.377099 -136.586924)
			(xy 84.321695 -136.609873) (xy 84.26377 -136.625394) (xy 84.204314 -136.633222) (xy 84.144346 -136.633222)
			(xy 84.08489 -136.625394) (xy 84.026965 -136.609873) (xy 83.971561 -136.586924) (xy 83.919627 -136.55694)
			(xy 83.872051 -136.520434) (xy 83.829646 -136.478029) (xy 83.79314 -136.430453) (xy 83.763156 -136.378519)
			(xy 83.740207 -136.323115) (xy 83.724686 -136.26519) (xy 83.716858 -136.205734) (xy 83.716368 -136.17575)
			(xy 65.661032 -136.17575) (xy 65.661032 -136.177274) (xy 65.660542 -136.207258) (xy 65.652714 -136.266714)
			(xy 65.637193 -136.324639) (xy 65.614244 -136.380043) (xy 65.58426 -136.431977) (xy 65.547754 -136.479553)
			(xy 65.505349 -136.521958) (xy 65.457773 -136.558464) (xy 65.405839 -136.588448) (xy 65.350435 -136.611397)
			(xy 65.29251 -136.626918) (xy 65.233054 -136.634746) (xy 65.173086 -136.634746) (xy 65.11363 -136.626918)
			(xy 65.055705 -136.611397) (xy 65.000301 -136.588448) (xy 64.948367 -136.558464) (xy 64.900791 -136.521958)
			(xy 64.858386 -136.479553) (xy 64.82188 -136.431977) (xy 64.791896 -136.380043) (xy 64.768947 -136.324639)
			(xy 64.753426 -136.266714) (xy 64.745598 -136.207258) (xy 64.745108 -136.177274) (xy 52.700428 -136.177274)
			(xy 52.700428 -136.69645) (xy 52.700299 -136.704324) (xy 153.409904 -136.704324) (xy 153.409904 -135.840724)
			(xy 153.410394 -135.81074) (xy 153.418222 -135.751284) (xy 153.433743 -135.693359) (xy 153.456692 -135.637955)
			(xy 153.486676 -135.586021) (xy 153.523182 -135.538445) (xy 153.565587 -135.49604) (xy 153.613163 -135.459534)
			(xy 153.665097 -135.42955) (xy 153.720501 -135.406601) (xy 153.778426 -135.39108) (xy 153.837882 -135.383252)
			(xy 153.89785 -135.383252) (xy 153.957306 -135.39108) (xy 154.015231 -135.406601) (xy 154.070635 -135.42955)
			(xy 154.122569 -135.459534) (xy 154.170145 -135.49604) (xy 154.21255 -135.538445) (xy 154.249056 -135.586021)
			(xy 154.27904 -135.637955) (xy 154.301989 -135.693359) (xy 154.31751 -135.751284) (xy 154.325338 -135.81074)
			(xy 154.325828 -135.840724) (xy 154.325828 -136.69645) (xy 167.884856 -136.69645) (xy 167.884856 -135.83285)
			(xy 167.885346 -135.802866) (xy 167.893174 -135.74341) (xy 167.908695 -135.685485) (xy 167.931644 -135.630081)
			(xy 167.961628 -135.578147) (xy 167.998134 -135.530571) (xy 168.040539 -135.488166) (xy 168.088115 -135.45166)
			(xy 168.140049 -135.421676) (xy 168.195453 -135.398727) (xy 168.253378 -135.383206) (xy 168.312834 -135.375378)
			(xy 168.372802 -135.375378) (xy 168.432258 -135.383206) (xy 168.490183 -135.398727) (xy 168.545587 -135.421676)
			(xy 168.597521 -135.45166) (xy 168.645097 -135.488166) (xy 168.687502 -135.530571) (xy 168.724008 -135.578147)
			(xy 168.753992 -135.630081) (xy 168.776941 -135.685485) (xy 168.792462 -135.74341) (xy 168.80029 -135.802866)
			(xy 168.80078 -135.83285) (xy 168.80078 -136.177274) (xy 180.84546 -136.177274) (xy 180.84546 -135.313674)
			(xy 180.84595 -135.283706) (xy 180.853773 -135.224284) (xy 180.869286 -135.166391) (xy 180.892222 -135.111018)
			(xy 180.922189 -135.059112) (xy 180.958676 -135.011562) (xy 181.001056 -134.969182) (xy 181.048606 -134.932695)
			(xy 181.100512 -134.902728) (xy 181.155885 -134.879792) (xy 181.213778 -134.864279) (xy 181.2732 -134.856456)
			(xy 181.333136 -134.856456) (xy 181.392558 -134.864279) (xy 181.450451 -134.879792) (xy 181.505824 -134.902728)
			(xy 181.55773 -134.932695) (xy 181.60528 -134.969182) (xy 181.64766 -135.011562) (xy 181.684147 -135.059112)
			(xy 181.714114 -135.111018) (xy 181.73705 -135.166391) (xy 181.752563 -135.224284) (xy 181.760386 -135.283706)
			(xy 181.760876 -135.313674) (xy 181.760876 -136.17575) (xy 199.81672 -136.17575) (xy 199.81672 -135.31215)
			(xy 199.81721 -135.282182) (xy 199.825033 -135.22276) (xy 199.840546 -135.164867) (xy 199.863482 -135.109494)
			(xy 199.893449 -135.057588) (xy 199.929936 -135.010038) (xy 199.972316 -134.967658) (xy 200.019866 -134.931171)
			(xy 200.071772 -134.901204) (xy 200.127145 -134.878268) (xy 200.185038 -134.862755) (xy 200.24446 -134.854932)
			(xy 200.304396 -134.854932) (xy 200.363818 -134.862755) (xy 200.421711 -134.878268) (xy 200.469049 -134.897876)
			(xy 266.86764 -134.897876) (xy 266.86764 -134.034276) (xy 266.86813 -134.004292) (xy 266.875958 -133.944836)
			(xy 266.891479 -133.886911) (xy 266.914428 -133.831507) (xy 266.944412 -133.779573) (xy 266.980918 -133.731997)
			(xy 267.023323 -133.689592) (xy 267.070899 -133.653086) (xy 267.122833 -133.623102) (xy 267.178237 -133.600153)
			(xy 267.236162 -133.584632) (xy 267.295618 -133.576804) (xy 267.355586 -133.576804) (xy 267.415042 -133.584632)
			(xy 267.472967 -133.600153) (xy 267.528371 -133.623102) (xy 267.580305 -133.653086) (xy 267.627881 -133.689592)
			(xy 267.670286 -133.731997) (xy 267.706792 -133.779573) (xy 267.736776 -133.831507) (xy 267.759725 -133.886911)
			(xy 267.775246 -133.944836) (xy 267.783074 -134.004292) (xy 267.783564 -134.034276) (xy 267.783564 -134.896352)
			(xy 285.8389 -134.896352) (xy 285.8389 -134.032752) (xy 285.83939 -134.002768) (xy 285.847218 -133.943312)
			(xy 285.862739 -133.885387) (xy 285.885688 -133.829983) (xy 285.915672 -133.778049) (xy 285.952178 -133.730473)
			(xy 285.994583 -133.688068) (xy 286.042159 -133.651562) (xy 286.094093 -133.621578) (xy 286.149497 -133.598629)
			(xy 286.207422 -133.583108) (xy 286.266878 -133.57528) (xy 286.326846 -133.57528) (xy 286.386302 -133.583108)
			(xy 286.444227 -133.598629) (xy 286.499631 -133.621578) (xy 286.551565 -133.651562) (xy 286.599141 -133.688068)
			(xy 286.641546 -133.730473) (xy 286.678052 -133.778049) (xy 286.708036 -133.829983) (xy 286.730985 -133.885387)
			(xy 286.746506 -133.943312) (xy 286.754334 -134.002768) (xy 286.754824 -134.032752) (xy 286.754824 -134.377176)
			(xy 298.799504 -134.377176) (xy 298.799504 -133.513576) (xy 298.799994 -133.483608) (xy 298.807817 -133.424186)
			(xy 298.82333 -133.366293) (xy 298.846266 -133.31092) (xy 298.876233 -133.259014) (xy 298.91272 -133.211464)
			(xy 298.9551 -133.169084) (xy 299.00265 -133.132597) (xy 299.054556 -133.10263) (xy 299.109929 -133.079694)
			(xy 299.167822 -133.064181) (xy 299.227244 -133.056358) (xy 299.28718 -133.056358) (xy 299.346602 -133.064181)
			(xy 299.404495 -133.079694) (xy 299.459868 -133.10263) (xy 299.511774 -133.132597) (xy 299.559324 -133.169084)
			(xy 299.601704 -133.211464) (xy 299.638191 -133.259014) (xy 299.668158 -133.31092) (xy 299.691094 -133.366293)
			(xy 299.706607 -133.424186) (xy 299.71443 -133.483608) (xy 299.71492 -133.513576) (xy 299.71492 -134.369302)
			(xy 313.274456 -134.369302) (xy 313.274456 -133.505702) (xy 313.274946 -133.475734) (xy 313.282769 -133.416312)
			(xy 313.298282 -133.358419) (xy 313.321218 -133.303046) (xy 313.351185 -133.25114) (xy 313.387672 -133.20359)
			(xy 313.430052 -133.16121) (xy 313.477602 -133.124723) (xy 313.529508 -133.094756) (xy 313.584881 -133.07182)
			(xy 313.642774 -133.056307) (xy 313.702196 -133.048484) (xy 313.762132 -133.048484) (xy 313.821554 -133.056307)
			(xy 313.879447 -133.07182) (xy 313.93482 -133.094756) (xy 313.951493 -133.104382) (xy 385.6101 -133.104382)
			(xy 385.6101 -132.240782) (xy 385.61059 -132.210814) (xy 385.618413 -132.151392) (xy 385.633926 -132.093499)
			(xy 385.656862 -132.038126) (xy 385.686829 -131.98622) (xy 385.723316 -131.93867) (xy 385.765696 -131.89629)
			(xy 385.813246 -131.859803) (xy 385.865152 -131.829836) (xy 385.920525 -131.8069) (xy 385.978418 -131.791387)
			(xy 386.03784 -131.783564) (xy 386.097776 -131.783564) (xy 386.157198 -131.791387) (xy 386.215091 -131.8069)
			(xy 386.270464 -131.829836) (xy 386.32237 -131.859803) (xy 386.36992 -131.89629) (xy 386.4123 -131.93867)
			(xy 386.448787 -131.98622) (xy 386.478754 -132.038126) (xy 386.50169 -132.093499) (xy 386.517203 -132.151392)
			(xy 386.525026 -132.210814) (xy 386.525516 -132.240782) (xy 386.525516 -133.096508) (xy 400.085052 -133.096508)
			(xy 400.085052 -132.232908) (xy 400.085542 -132.20294) (xy 400.093365 -132.143518) (xy 400.108878 -132.085625)
			(xy 400.131814 -132.030252) (xy 400.161781 -131.978346) (xy 400.198268 -131.930796) (xy 400.240648 -131.888416)
			(xy 400.288198 -131.851929) (xy 400.340104 -131.821962) (xy 400.395477 -131.799026) (xy 400.45337 -131.783513)
			(xy 400.512792 -131.77569) (xy 400.572728 -131.77569) (xy 400.63215 -131.783513) (xy 400.690043 -131.799026)
			(xy 400.745416 -131.821962) (xy 400.797322 -131.851929) (xy 400.844872 -131.888416) (xy 400.887252 -131.930796)
			(xy 400.923739 -131.978346) (xy 400.953706 -132.030252) (xy 400.976642 -132.085625) (xy 400.992155 -132.143518)
			(xy 400.999978 -132.20294) (xy 401.000468 -132.232908) (xy 401.000468 -132.577332) (xy 413.045148 -132.577332)
			(xy 413.045148 -131.713732) (xy 413.045638 -131.683748) (xy 413.053466 -131.624292) (xy 413.068987 -131.566367)
			(xy 413.091936 -131.510963) (xy 413.12192 -131.459029) (xy 413.158426 -131.411453) (xy 413.200831 -131.369048)
			(xy 413.248407 -131.332542) (xy 413.300341 -131.302558) (xy 413.355745 -131.279609) (xy 413.41367 -131.264088)
			(xy 413.473126 -131.25626) (xy 413.533094 -131.25626) (xy 413.59255 -131.264088) (xy 413.650475 -131.279609)
			(xy 413.705879 -131.302558) (xy 413.757813 -131.332542) (xy 413.805389 -131.369048) (xy 413.847794 -131.411453)
			(xy 413.8843 -131.459029) (xy 413.914284 -131.510963) (xy 413.937233 -131.566367) (xy 413.952754 -131.624292)
			(xy 413.960582 -131.683748) (xy 413.961072 -131.713732) (xy 413.961072 -132.575808) (xy 432.016408 -132.575808)
			(xy 432.016408 -131.712208) (xy 432.016898 -131.682224) (xy 432.024726 -131.622768) (xy 432.040247 -131.564843)
			(xy 432.063196 -131.509439) (xy 432.09318 -131.457505) (xy 432.129686 -131.409929) (xy 432.172091 -131.367524)
			(xy 432.219667 -131.331018) (xy 432.271601 -131.301034) (xy 432.327005 -131.278085) (xy 432.38493 -131.262564)
			(xy 432.444386 -131.254736) (xy 432.504354 -131.254736) (xy 432.56381 -131.262564) (xy 432.621735 -131.278085)
			(xy 432.677139 -131.301034) (xy 432.729073 -131.331018) (xy 432.776649 -131.367524) (xy 432.819054 -131.409929)
			(xy 432.85556 -131.457505) (xy 432.885544 -131.509439) (xy 432.908493 -131.564843) (xy 432.924014 -131.622768)
			(xy 432.931842 -131.682224) (xy 432.932332 -131.712208) (xy 432.932332 -132.575808) (xy 432.931842 -132.605792)
			(xy 432.924014 -132.665248) (xy 432.908493 -132.723173) (xy 432.885544 -132.778577) (xy 432.85556 -132.830511)
			(xy 432.819054 -132.878087) (xy 432.776649 -132.920492) (xy 432.729073 -132.956998) (xy 432.677139 -132.986982)
			(xy 432.621735 -133.009931) (xy 432.56381 -133.025452) (xy 432.504354 -133.03328) (xy 432.444386 -133.03328)
			(xy 432.38493 -133.025452) (xy 432.327005 -133.009931) (xy 432.271601 -132.986982) (xy 432.219667 -132.956998)
			(xy 432.172091 -132.920492) (xy 432.129686 -132.878087) (xy 432.09318 -132.830511) (xy 432.063196 -132.778577)
			(xy 432.040247 -132.723173) (xy 432.024726 -132.665248) (xy 432.016898 -132.605792) (xy 432.016408 -132.575808)
			(xy 413.961072 -132.575808) (xy 413.961072 -132.577332) (xy 413.960582 -132.607316) (xy 413.952754 -132.666772)
			(xy 413.937233 -132.724697) (xy 413.914284 -132.780101) (xy 413.8843 -132.832035) (xy 413.847794 -132.879611)
			(xy 413.805389 -132.922016) (xy 413.757813 -132.958522) (xy 413.705879 -132.988506) (xy 413.650475 -133.011455)
			(xy 413.59255 -133.026976) (xy 413.533094 -133.034804) (xy 413.473126 -133.034804) (xy 413.41367 -133.026976)
			(xy 413.355745 -133.011455) (xy 413.300341 -132.988506) (xy 413.248407 -132.958522) (xy 413.200831 -132.922016)
			(xy 413.158426 -132.879611) (xy 413.12192 -132.832035) (xy 413.091936 -132.780101) (xy 413.068987 -132.724697)
			(xy 413.053466 -132.666772) (xy 413.045638 -132.607316) (xy 413.045148 -132.577332) (xy 401.000468 -132.577332)
			(xy 401.000468 -133.096508) (xy 400.999978 -133.126476) (xy 400.992155 -133.185898) (xy 400.976642 -133.243791)
			(xy 400.953706 -133.299164) (xy 400.923739 -133.35107) (xy 400.887252 -133.39862) (xy 400.844872 -133.441)
			(xy 400.797322 -133.477487) (xy 400.745416 -133.507454) (xy 400.690043 -133.53039) (xy 400.63215 -133.545903)
			(xy 400.572728 -133.553726) (xy 400.512792 -133.553726) (xy 400.45337 -133.545903) (xy 400.395477 -133.53039)
			(xy 400.340104 -133.507454) (xy 400.288198 -133.477487) (xy 400.240648 -133.441) (xy 400.198268 -133.39862)
			(xy 400.161781 -133.35107) (xy 400.131814 -133.299164) (xy 400.108878 -133.243791) (xy 400.093365 -133.185898)
			(xy 400.085542 -133.126476) (xy 400.085052 -133.096508) (xy 386.525516 -133.096508) (xy 386.525516 -133.104382)
			(xy 386.525026 -133.13435) (xy 386.517203 -133.193772) (xy 386.50169 -133.251665) (xy 386.478754 -133.307038)
			(xy 386.448787 -133.358944) (xy 386.4123 -133.406494) (xy 386.36992 -133.448874) (xy 386.32237 -133.485361)
			(xy 386.270464 -133.515328) (xy 386.215091 -133.538264) (xy 386.157198 -133.553777) (xy 386.097776 -133.5616)
			(xy 386.03784 -133.5616) (xy 385.978418 -133.553777) (xy 385.920525 -133.538264) (xy 385.865152 -133.515328)
			(xy 385.813246 -133.485361) (xy 385.765696 -133.448874) (xy 385.723316 -133.406494) (xy 385.686829 -133.358944)
			(xy 385.656862 -133.307038) (xy 385.633926 -133.251665) (xy 385.618413 -133.193772) (xy 385.61059 -133.13435)
			(xy 385.6101 -133.104382) (xy 313.951493 -133.104382) (xy 313.986726 -133.124723) (xy 314.034276 -133.16121)
			(xy 314.076656 -133.20359) (xy 314.113143 -133.25114) (xy 314.14311 -133.303046) (xy 314.166046 -133.358419)
			(xy 314.181559 -133.416312) (xy 314.189382 -133.475734) (xy 314.189872 -133.505702) (xy 314.189872 -134.369302)
			(xy 314.189382 -134.39927) (xy 314.181559 -134.458692) (xy 314.166046 -134.516585) (xy 314.14311 -134.571958)
			(xy 314.113143 -134.623864) (xy 314.076656 -134.671414) (xy 314.034276 -134.713794) (xy 313.986726 -134.750281)
			(xy 313.93482 -134.780248) (xy 313.879447 -134.803184) (xy 313.821554 -134.818697) (xy 313.762132 -134.82652)
			(xy 313.702196 -134.82652) (xy 313.642774 -134.818697) (xy 313.584881 -134.803184) (xy 313.529508 -134.780248)
			(xy 313.477602 -134.750281) (xy 313.430052 -134.713794) (xy 313.387672 -134.671414) (xy 313.351185 -134.623864)
			(xy 313.321218 -134.571958) (xy 313.298282 -134.516585) (xy 313.282769 -134.458692) (xy 313.274946 -134.39927)
			(xy 313.274456 -134.369302) (xy 299.71492 -134.369302) (xy 299.71492 -134.377176) (xy 299.71443 -134.407144)
			(xy 299.706607 -134.466566) (xy 299.691094 -134.524459) (xy 299.668158 -134.579832) (xy 299.638191 -134.631738)
			(xy 299.601704 -134.679288) (xy 299.559324 -134.721668) (xy 299.511774 -134.758155) (xy 299.459868 -134.788122)
			(xy 299.404495 -134.811058) (xy 299.346602 -134.826571) (xy 299.28718 -134.834394) (xy 299.227244 -134.834394)
			(xy 299.167822 -134.826571) (xy 299.109929 -134.811058) (xy 299.054556 -134.788122) (xy 299.00265 -134.758155)
			(xy 298.9551 -134.721668) (xy 298.91272 -134.679288) (xy 298.876233 -134.631738) (xy 298.846266 -134.579832)
			(xy 298.82333 -134.524459) (xy 298.807817 -134.466566) (xy 298.799994 -134.407144) (xy 298.799504 -134.377176)
			(xy 286.754824 -134.377176) (xy 286.754824 -134.896352) (xy 286.754334 -134.926336) (xy 286.746506 -134.985792)
			(xy 286.730985 -135.043717) (xy 286.708036 -135.099121) (xy 286.678052 -135.151055) (xy 286.641546 -135.198631)
			(xy 286.599141 -135.241036) (xy 286.551565 -135.277542) (xy 286.499631 -135.307526) (xy 286.444227 -135.330475)
			(xy 286.386302 -135.345996) (xy 286.326846 -135.353824) (xy 286.266878 -135.353824) (xy 286.207422 -135.345996)
			(xy 286.149497 -135.330475) (xy 286.094093 -135.307526) (xy 286.042159 -135.277542) (xy 285.994583 -135.241036)
			(xy 285.952178 -135.198631) (xy 285.915672 -135.151055) (xy 285.885688 -135.099121) (xy 285.862739 -135.043717)
			(xy 285.847218 -134.985792) (xy 285.83939 -134.926336) (xy 285.8389 -134.896352) (xy 267.783564 -134.896352)
			(xy 267.783564 -134.897876) (xy 267.783074 -134.92786) (xy 267.775246 -134.987316) (xy 267.759725 -135.045241)
			(xy 267.736776 -135.100645) (xy 267.706792 -135.152579) (xy 267.670286 -135.200155) (xy 267.627881 -135.24256)
			(xy 267.580305 -135.279066) (xy 267.528371 -135.30905) (xy 267.472967 -135.331999) (xy 267.415042 -135.34752)
			(xy 267.355586 -135.355348) (xy 267.295618 -135.355348) (xy 267.236162 -135.34752) (xy 267.178237 -135.331999)
			(xy 267.122833 -135.30905) (xy 267.070899 -135.279066) (xy 267.023323 -135.24256) (xy 266.980918 -135.200155)
			(xy 266.944412 -135.152579) (xy 266.914428 -135.100645) (xy 266.891479 -135.045241) (xy 266.875958 -134.987316)
			(xy 266.86813 -134.92786) (xy 266.86764 -134.897876) (xy 200.469049 -134.897876) (xy 200.477084 -134.901204)
			(xy 200.52899 -134.931171) (xy 200.57654 -134.967658) (xy 200.61892 -135.010038) (xy 200.655407 -135.057588)
			(xy 200.685374 -135.109494) (xy 200.70831 -135.164867) (xy 200.723823 -135.22276) (xy 200.731646 -135.282182)
			(xy 200.732136 -135.31215) (xy 200.732136 -136.17575) (xy 200.731646 -136.205718) (xy 200.723823 -136.26514)
			(xy 200.70831 -136.323033) (xy 200.685374 -136.378406) (xy 200.655407 -136.430312) (xy 200.61892 -136.477862)
			(xy 200.57654 -136.520242) (xy 200.52899 -136.556729) (xy 200.477084 -136.586696) (xy 200.421711 -136.609632)
			(xy 200.363818 -136.625145) (xy 200.304396 -136.632968) (xy 200.24446 -136.632968) (xy 200.185038 -136.625145)
			(xy 200.127145 -136.609632) (xy 200.071772 -136.586696) (xy 200.019866 -136.556729) (xy 199.972316 -136.520242)
			(xy 199.929936 -136.477862) (xy 199.893449 -136.430312) (xy 199.863482 -136.378406) (xy 199.840546 -136.323033)
			(xy 199.825033 -136.26514) (xy 199.81721 -136.205718) (xy 199.81672 -136.17575) (xy 181.760876 -136.17575)
			(xy 181.760876 -136.177274) (xy 181.760386 -136.207242) (xy 181.752563 -136.266664) (xy 181.73705 -136.324557)
			(xy 181.714114 -136.37993) (xy 181.684147 -136.431836) (xy 181.64766 -136.479386) (xy 181.60528 -136.521766)
			(xy 181.55773 -136.558253) (xy 181.505824 -136.58822) (xy 181.450451 -136.611156) (xy 181.392558 -136.626669)
			(xy 181.333136 -136.634492) (xy 181.2732 -136.634492) (xy 181.213778 -136.626669) (xy 181.155885 -136.611156)
			(xy 181.100512 -136.58822) (xy 181.048606 -136.558253) (xy 181.001056 -136.521766) (xy 180.958676 -136.479386)
			(xy 180.922189 -136.431836) (xy 180.892222 -136.37993) (xy 180.869286 -136.324557) (xy 180.853773 -136.266664)
			(xy 180.84595 -136.207242) (xy 180.84546 -136.177274) (xy 168.80078 -136.177274) (xy 168.80078 -136.69645)
			(xy 168.800651 -136.704324) (xy 269.509748 -136.704324) (xy 269.509748 -135.840724) (xy 269.510238 -135.81074)
			(xy 269.518066 -135.751284) (xy 269.533587 -135.693359) (xy 269.556536 -135.637955) (xy 269.58652 -135.586021)
			(xy 269.623026 -135.538445) (xy 269.665431 -135.49604) (xy 269.713007 -135.459534) (xy 269.764941 -135.42955)
			(xy 269.820345 -135.406601) (xy 269.87827 -135.39108) (xy 269.937726 -135.383252) (xy 269.997694 -135.383252)
			(xy 270.05715 -135.39108) (xy 270.115075 -135.406601) (xy 270.170479 -135.42955) (xy 270.222413 -135.459534)
			(xy 270.269989 -135.49604) (xy 270.312394 -135.538445) (xy 270.3489 -135.586021) (xy 270.378884 -135.637955)
			(xy 270.401833 -135.693359) (xy 270.417354 -135.751284) (xy 270.425182 -135.81074) (xy 270.425672 -135.840724)
			(xy 270.425672 -136.69645) (xy 283.9847 -136.69645) (xy 283.9847 -135.83285) (xy 283.98519 -135.802866)
			(xy 283.993018 -135.74341) (xy 284.008539 -135.685485) (xy 284.031488 -135.630081) (xy 284.061472 -135.578147)
			(xy 284.097978 -135.530571) (xy 284.140383 -135.488166) (xy 284.187959 -135.45166) (xy 284.239893 -135.421676)
			(xy 284.295297 -135.398727) (xy 284.353222 -135.383206) (xy 284.412678 -135.375378) (xy 284.472646 -135.375378)
			(xy 284.532102 -135.383206) (xy 284.590027 -135.398727) (xy 284.645431 -135.421676) (xy 284.697365 -135.45166)
			(xy 284.744941 -135.488166) (xy 284.787346 -135.530571) (xy 284.823852 -135.578147) (xy 284.853836 -135.630081)
			(xy 284.876785 -135.685485) (xy 284.892306 -135.74341) (xy 284.900134 -135.802866) (xy 284.900624 -135.83285)
			(xy 284.900624 -136.177274) (xy 296.945304 -136.177274) (xy 296.945304 -135.313674) (xy 296.945794 -135.283706)
			(xy 296.953617 -135.224284) (xy 296.96913 -135.166391) (xy 296.992066 -135.111018) (xy 297.022033 -135.059112)
			(xy 297.05852 -135.011562) (xy 297.1009 -134.969182) (xy 297.14845 -134.932695) (xy 297.200356 -134.902728)
			(xy 297.255729 -134.879792) (xy 297.313622 -134.864279) (xy 297.373044 -134.856456) (xy 297.43298 -134.856456)
			(xy 297.492402 -134.864279) (xy 297.550295 -134.879792) (xy 297.605668 -134.902728) (xy 297.657574 -134.932695)
			(xy 297.705124 -134.969182) (xy 297.747504 -135.011562) (xy 297.783991 -135.059112) (xy 297.813958 -135.111018)
			(xy 297.836894 -135.166391) (xy 297.852407 -135.224284) (xy 297.86023 -135.283706) (xy 297.86072 -135.313674)
			(xy 297.86072 -136.17575) (xy 315.916564 -136.17575) (xy 315.916564 -135.31215) (xy 315.917054 -135.282182)
			(xy 315.924877 -135.22276) (xy 315.94039 -135.164867) (xy 315.963326 -135.109494) (xy 315.993293 -135.057588)
			(xy 316.02978 -135.010038) (xy 316.07216 -134.967658) (xy 316.11971 -134.931171) (xy 316.171616 -134.901204)
			(xy 316.226989 -134.878268) (xy 316.284882 -134.862755) (xy 316.344304 -134.854932) (xy 316.40424 -134.854932)
			(xy 316.463662 -134.862755) (xy 316.521555 -134.878268) (xy 316.568893 -134.897876) (xy 382.967992 -134.897876)
			(xy 382.967992 -134.034276) (xy 382.968482 -134.004308) (xy 382.976305 -133.944886) (xy 382.991818 -133.886993)
			(xy 383.014754 -133.83162) (xy 383.044721 -133.779714) (xy 383.081208 -133.732164) (xy 383.123588 -133.689784)
			(xy 383.171138 -133.653297) (xy 383.223044 -133.62333) (xy 383.278417 -133.600394) (xy 383.33631 -133.584881)
			(xy 383.395732 -133.577058) (xy 383.455668 -133.577058) (xy 383.51509 -133.584881) (xy 383.572983 -133.600394)
			(xy 383.628356 -133.62333) (xy 383.680262 -133.653297) (xy 383.727812 -133.689784) (xy 383.770192 -133.732164)
			(xy 383.806679 -133.779714) (xy 383.836646 -133.83162) (xy 383.859582 -133.886993) (xy 383.875095 -133.944886)
			(xy 383.882918 -134.004308) (xy 383.883408 -134.034276) (xy 383.883408 -134.896352) (xy 401.939252 -134.896352)
			(xy 401.939252 -134.032752) (xy 401.939742 -134.002784) (xy 401.947565 -133.943362) (xy 401.963078 -133.885469)
			(xy 401.986014 -133.830096) (xy 402.015981 -133.77819) (xy 402.052468 -133.73064) (xy 402.094848 -133.68826)
			(xy 402.142398 -133.651773) (xy 402.194304 -133.621806) (xy 402.249677 -133.59887) (xy 402.30757 -133.583357)
			(xy 402.366992 -133.575534) (xy 402.426928 -133.575534) (xy 402.48635 -133.583357) (xy 402.544243 -133.59887)
			(xy 402.599616 -133.621806) (xy 402.651522 -133.651773) (xy 402.699072 -133.68826) (xy 402.741452 -133.73064)
			(xy 402.777939 -133.77819) (xy 402.807906 -133.830096) (xy 402.830842 -133.885469) (xy 402.846355 -133.943362)
			(xy 402.854178 -134.002784) (xy 402.854668 -134.032752) (xy 402.854668 -134.377176) (xy 414.899348 -134.377176)
			(xy 414.899348 -133.513576) (xy 414.899838 -133.483592) (xy 414.907666 -133.424136) (xy 414.923187 -133.366211)
			(xy 414.946136 -133.310807) (xy 414.97612 -133.258873) (xy 415.012626 -133.211297) (xy 415.055031 -133.168892)
			(xy 415.102607 -133.132386) (xy 415.154541 -133.102402) (xy 415.209945 -133.079453) (xy 415.26787 -133.063932)
			(xy 415.327326 -133.056104) (xy 415.387294 -133.056104) (xy 415.44675 -133.063932) (xy 415.504675 -133.079453)
			(xy 415.560079 -133.102402) (xy 415.612013 -133.132386) (xy 415.659589 -133.168892) (xy 415.701994 -133.211297)
			(xy 415.7385 -133.258873) (xy 415.768484 -133.310807) (xy 415.791433 -133.366211) (xy 415.806954 -133.424136)
			(xy 415.814782 -133.483592) (xy 415.815272 -133.513576) (xy 415.815272 -134.369302) (xy 429.3743 -134.369302)
			(xy 429.3743 -133.505702) (xy 429.37479 -133.475718) (xy 429.382618 -133.416262) (xy 429.398139 -133.358337)
			(xy 429.421088 -133.302933) (xy 429.451072 -133.250999) (xy 429.487578 -133.203423) (xy 429.529983 -133.161018)
			(xy 429.577559 -133.124512) (xy 429.629493 -133.094528) (xy 429.684897 -133.071579) (xy 429.742822 -133.056058)
			(xy 429.802278 -133.04823) (xy 429.862246 -133.04823) (xy 429.921702 -133.056058) (xy 429.979627 -133.071579)
			(xy 430.035031 -133.094528) (xy 430.086965 -133.124512) (xy 430.134541 -133.161018) (xy 430.176946 -133.203423)
			(xy 430.213452 -133.250999) (xy 430.243436 -133.302933) (xy 430.266385 -133.358337) (xy 430.281906 -133.416262)
			(xy 430.289734 -133.475718) (xy 430.290224 -133.505702) (xy 430.290224 -134.369302) (xy 430.289734 -134.399286)
			(xy 430.281906 -134.458742) (xy 430.266385 -134.516667) (xy 430.243436 -134.572071) (xy 430.213452 -134.624005)
			(xy 430.176946 -134.671581) (xy 430.134541 -134.713986) (xy 430.086965 -134.750492) (xy 430.035031 -134.780476)
			(xy 429.979627 -134.803425) (xy 429.921702 -134.818946) (xy 429.862246 -134.826774) (xy 429.802278 -134.826774)
			(xy 429.742822 -134.818946) (xy 429.684897 -134.803425) (xy 429.629493 -134.780476) (xy 429.577559 -134.750492)
			(xy 429.529983 -134.713986) (xy 429.487578 -134.671581) (xy 429.451072 -134.624005) (xy 429.421088 -134.572071)
			(xy 429.398139 -134.516667) (xy 429.382618 -134.458742) (xy 429.37479 -134.399286) (xy 429.3743 -134.369302)
			(xy 415.815272 -134.369302) (xy 415.815272 -134.377176) (xy 415.814782 -134.40716) (xy 415.806954 -134.466616)
			(xy 415.791433 -134.524541) (xy 415.768484 -134.579945) (xy 415.7385 -134.631879) (xy 415.701994 -134.679455)
			(xy 415.659589 -134.72186) (xy 415.612013 -134.758366) (xy 415.560079 -134.78835) (xy 415.504675 -134.811299)
			(xy 415.44675 -134.82682) (xy 415.387294 -134.834648) (xy 415.327326 -134.834648) (xy 415.26787 -134.82682)
			(xy 415.209945 -134.811299) (xy 415.154541 -134.78835) (xy 415.102607 -134.758366) (xy 415.055031 -134.72186)
			(xy 415.012626 -134.679455) (xy 414.97612 -134.631879) (xy 414.946136 -134.579945) (xy 414.923187 -134.524541)
			(xy 414.907666 -134.466616) (xy 414.899838 -134.40716) (xy 414.899348 -134.377176) (xy 402.854668 -134.377176)
			(xy 402.854668 -134.896352) (xy 402.854178 -134.92632) (xy 402.846355 -134.985742) (xy 402.830842 -135.043635)
			(xy 402.807906 -135.099008) (xy 402.777939 -135.150914) (xy 402.741452 -135.198464) (xy 402.699072 -135.240844)
			(xy 402.651522 -135.277331) (xy 402.599616 -135.307298) (xy 402.544243 -135.330234) (xy 402.48635 -135.345747)
			(xy 402.426928 -135.35357) (xy 402.366992 -135.35357) (xy 402.30757 -135.345747) (xy 402.249677 -135.330234)
			(xy 402.194304 -135.307298) (xy 402.142398 -135.277331) (xy 402.094848 -135.240844) (xy 402.052468 -135.198464)
			(xy 402.015981 -135.150914) (xy 401.986014 -135.099008) (xy 401.963078 -135.043635) (xy 401.947565 -134.985742)
			(xy 401.939742 -134.92632) (xy 401.939252 -134.896352) (xy 383.883408 -134.896352) (xy 383.883408 -134.897876)
			(xy 383.882918 -134.927844) (xy 383.875095 -134.987266) (xy 383.859582 -135.045159) (xy 383.836646 -135.100532)
			(xy 383.806679 -135.152438) (xy 383.770192 -135.199988) (xy 383.727812 -135.242368) (xy 383.680262 -135.278855)
			(xy 383.628356 -135.308822) (xy 383.572983 -135.331758) (xy 383.51509 -135.347271) (xy 383.455668 -135.355094)
			(xy 383.395732 -135.355094) (xy 383.33631 -135.347271) (xy 383.278417 -135.331758) (xy 383.223044 -135.308822)
			(xy 383.171138 -135.278855) (xy 383.123588 -135.242368) (xy 383.081208 -135.199988) (xy 383.044721 -135.152438)
			(xy 383.014754 -135.100532) (xy 382.991818 -135.045159) (xy 382.976305 -134.987266) (xy 382.968482 -134.927844)
			(xy 382.967992 -134.897876) (xy 316.568893 -134.897876) (xy 316.576928 -134.901204) (xy 316.628834 -134.931171)
			(xy 316.676384 -134.967658) (xy 316.718764 -135.010038) (xy 316.755251 -135.057588) (xy 316.785218 -135.109494)
			(xy 316.808154 -135.164867) (xy 316.823667 -135.22276) (xy 316.83149 -135.282182) (xy 316.83198 -135.31215)
			(xy 316.83198 -136.17575) (xy 316.83149 -136.205718) (xy 316.823667 -136.26514) (xy 316.808154 -136.323033)
			(xy 316.785218 -136.378406) (xy 316.755251 -136.430312) (xy 316.718764 -136.477862) (xy 316.676384 -136.520242)
			(xy 316.628834 -136.556729) (xy 316.576928 -136.586696) (xy 316.521555 -136.609632) (xy 316.463662 -136.625145)
			(xy 316.40424 -136.632968) (xy 316.344304 -136.632968) (xy 316.284882 -136.625145) (xy 316.226989 -136.609632)
			(xy 316.171616 -136.586696) (xy 316.11971 -136.556729) (xy 316.07216 -136.520242) (xy 316.02978 -136.477862)
			(xy 315.993293 -136.430312) (xy 315.963326 -136.378406) (xy 315.94039 -136.323033) (xy 315.924877 -136.26514)
			(xy 315.917054 -136.205718) (xy 315.916564 -136.17575) (xy 297.86072 -136.17575) (xy 297.86072 -136.177274)
			(xy 297.86023 -136.207242) (xy 297.852407 -136.266664) (xy 297.836894 -136.324557) (xy 297.813958 -136.37993)
			(xy 297.783991 -136.431836) (xy 297.747504 -136.479386) (xy 297.705124 -136.521766) (xy 297.657574 -136.558253)
			(xy 297.605668 -136.58822) (xy 297.550295 -136.611156) (xy 297.492402 -136.626669) (xy 297.43298 -136.634492)
			(xy 297.373044 -136.634492) (xy 297.313622 -136.626669) (xy 297.255729 -136.611156) (xy 297.200356 -136.58822)
			(xy 297.14845 -136.558253) (xy 297.1009 -136.521766) (xy 297.05852 -136.479386) (xy 297.022033 -136.431836)
			(xy 296.992066 -136.37993) (xy 296.96913 -136.324557) (xy 296.953617 -136.266664) (xy 296.945794 -136.207242)
			(xy 296.945304 -136.177274) (xy 284.900624 -136.177274) (xy 284.900624 -136.69645) (xy 284.900495 -136.704324)
			(xy 385.6101 -136.704324) (xy 385.6101 -135.840724) (xy 385.61059 -135.810756) (xy 385.618413 -135.751334)
			(xy 385.633926 -135.693441) (xy 385.656862 -135.638068) (xy 385.686829 -135.586162) (xy 385.723316 -135.538612)
			(xy 385.765696 -135.496232) (xy 385.813246 -135.459745) (xy 385.865152 -135.429778) (xy 385.920525 -135.406842)
			(xy 385.978418 -135.391329) (xy 386.03784 -135.383506) (xy 386.097776 -135.383506) (xy 386.157198 -135.391329)
			(xy 386.215091 -135.406842) (xy 386.270464 -135.429778) (xy 386.32237 -135.459745) (xy 386.36992 -135.496232)
			(xy 386.4123 -135.538612) (xy 386.448787 -135.586162) (xy 386.478754 -135.638068) (xy 386.50169 -135.693441)
			(xy 386.517203 -135.751334) (xy 386.525026 -135.810756) (xy 386.525516 -135.840724) (xy 386.525516 -136.69645)
			(xy 400.085052 -136.69645) (xy 400.085052 -135.83285) (xy 400.085542 -135.802882) (xy 400.093365 -135.74346)
			(xy 400.108878 -135.685567) (xy 400.131814 -135.630194) (xy 400.161781 -135.578288) (xy 400.198268 -135.530738)
			(xy 400.240648 -135.488358) (xy 400.288198 -135.451871) (xy 400.340104 -135.421904) (xy 400.395477 -135.398968)
			(xy 400.45337 -135.383455) (xy 400.512792 -135.375632) (xy 400.572728 -135.375632) (xy 400.63215 -135.383455)
			(xy 400.690043 -135.398968) (xy 400.745416 -135.421904) (xy 400.797322 -135.451871) (xy 400.844872 -135.488358)
			(xy 400.887252 -135.530738) (xy 400.923739 -135.578288) (xy 400.953706 -135.630194) (xy 400.976642 -135.685567)
			(xy 400.992155 -135.74346) (xy 400.999978 -135.802882) (xy 401.000468 -135.83285) (xy 401.000468 -136.177274)
			(xy 413.045148 -136.177274) (xy 413.045148 -135.313674) (xy 413.045638 -135.28369) (xy 413.053466 -135.224234)
			(xy 413.068987 -135.166309) (xy 413.091936 -135.110905) (xy 413.12192 -135.058971) (xy 413.158426 -135.011395)
			(xy 413.200831 -134.96899) (xy 413.248407 -134.932484) (xy 413.300341 -134.9025) (xy 413.355745 -134.879551)
			(xy 413.41367 -134.86403) (xy 413.473126 -134.856202) (xy 413.533094 -134.856202) (xy 413.59255 -134.86403)
			(xy 413.650475 -134.879551) (xy 413.705879 -134.9025) (xy 413.757813 -134.932484) (xy 413.805389 -134.96899)
			(xy 413.847794 -135.011395) (xy 413.8843 -135.058971) (xy 413.914284 -135.110905) (xy 413.937233 -135.166309)
			(xy 413.952754 -135.224234) (xy 413.960582 -135.28369) (xy 413.961072 -135.313674) (xy 413.961072 -136.17575)
			(xy 432.016408 -136.17575) (xy 432.016408 -135.31215) (xy 432.016898 -135.282166) (xy 432.024726 -135.22271)
			(xy 432.040247 -135.164785) (xy 432.063196 -135.109381) (xy 432.09318 -135.057447) (xy 432.129686 -135.009871)
			(xy 432.172091 -134.967466) (xy 432.219667 -134.93096) (xy 432.271601 -134.900976) (xy 432.327005 -134.878027)
			(xy 432.38493 -134.862506) (xy 432.444386 -134.854678) (xy 432.504354 -134.854678) (xy 432.56381 -134.862506)
			(xy 432.621735 -134.878027) (xy 432.677139 -134.900976) (xy 432.729073 -134.93096) (xy 432.776649 -134.967466)
			(xy 432.819054 -135.009871) (xy 432.85556 -135.057447) (xy 432.885544 -135.109381) (xy 432.908493 -135.164785)
			(xy 432.924014 -135.22271) (xy 432.931842 -135.282166) (xy 432.932332 -135.31215) (xy 432.932332 -136.17575)
			(xy 432.931842 -136.205734) (xy 432.924014 -136.26519) (xy 432.908493 -136.323115) (xy 432.885544 -136.378519)
			(xy 432.85556 -136.430453) (xy 432.819054 -136.478029) (xy 432.776649 -136.520434) (xy 432.729073 -136.55694)
			(xy 432.677139 -136.586924) (xy 432.621735 -136.609873) (xy 432.56381 -136.625394) (xy 432.504354 -136.633222)
			(xy 432.444386 -136.633222) (xy 432.38493 -136.625394) (xy 432.327005 -136.609873) (xy 432.271601 -136.586924)
			(xy 432.219667 -136.55694) (xy 432.172091 -136.520434) (xy 432.129686 -136.478029) (xy 432.09318 -136.430453)
			(xy 432.063196 -136.378519) (xy 432.040247 -136.323115) (xy 432.024726 -136.26519) (xy 432.016898 -136.205734)
			(xy 432.016408 -136.17575) (xy 413.961072 -136.17575) (xy 413.961072 -136.177274) (xy 413.960582 -136.207258)
			(xy 413.952754 -136.266714) (xy 413.937233 -136.324639) (xy 413.914284 -136.380043) (xy 413.8843 -136.431977)
			(xy 413.847794 -136.479553) (xy 413.805389 -136.521958) (xy 413.757813 -136.558464) (xy 413.705879 -136.588448)
			(xy 413.650475 -136.611397) (xy 413.59255 -136.626918) (xy 413.533094 -136.634746) (xy 413.473126 -136.634746)
			(xy 413.41367 -136.626918) (xy 413.355745 -136.611397) (xy 413.300341 -136.588448) (xy 413.248407 -136.558464)
			(xy 413.200831 -136.521958) (xy 413.158426 -136.479553) (xy 413.12192 -136.431977) (xy 413.091936 -136.380043)
			(xy 413.068987 -136.324639) (xy 413.053466 -136.266714) (xy 413.045638 -136.207258) (xy 413.045148 -136.177274)
			(xy 401.000468 -136.177274) (xy 401.000468 -136.69645) (xy 400.999978 -136.726418) (xy 400.992155 -136.78584)
			(xy 400.976642 -136.843733) (xy 400.953706 -136.899106) (xy 400.923739 -136.951012) (xy 400.887252 -136.998562)
			(xy 400.844872 -137.040942) (xy 400.797322 -137.077429) (xy 400.745416 -137.107396) (xy 400.690043 -137.130332)
			(xy 400.63215 -137.145845) (xy 400.572728 -137.153668) (xy 400.512792 -137.153668) (xy 400.45337 -137.145845)
			(xy 400.395477 -137.130332) (xy 400.340104 -137.107396) (xy 400.288198 -137.077429) (xy 400.240648 -137.040942)
			(xy 400.198268 -136.998562) (xy 400.161781 -136.951012) (xy 400.131814 -136.899106) (xy 400.108878 -136.843733)
			(xy 400.093365 -136.78584) (xy 400.085542 -136.726418) (xy 400.085052 -136.69645) (xy 386.525516 -136.69645)
			(xy 386.525516 -136.704324) (xy 386.525026 -136.734292) (xy 386.517203 -136.793714) (xy 386.50169 -136.851607)
			(xy 386.478754 -136.90698) (xy 386.448787 -136.958886) (xy 386.4123 -137.006436) (xy 386.36992 -137.048816)
			(xy 386.32237 -137.085303) (xy 386.270464 -137.11527) (xy 386.215091 -137.138206) (xy 386.157198 -137.153719)
			(xy 386.097776 -137.161542) (xy 386.03784 -137.161542) (xy 385.978418 -137.153719) (xy 385.920525 -137.138206)
			(xy 385.865152 -137.11527) (xy 385.813246 -137.085303) (xy 385.765696 -137.048816) (xy 385.723316 -137.006436)
			(xy 385.686829 -136.958886) (xy 385.656862 -136.90698) (xy 385.633926 -136.851607) (xy 385.618413 -136.793714)
			(xy 385.61059 -136.734292) (xy 385.6101 -136.704324) (xy 284.900495 -136.704324) (xy 284.900134 -136.726434)
			(xy 284.892306 -136.78589) (xy 284.876785 -136.843815) (xy 284.853836 -136.899219) (xy 284.823852 -136.951153)
			(xy 284.787346 -136.998729) (xy 284.744941 -137.041134) (xy 284.697365 -137.07764) (xy 284.645431 -137.107624)
			(xy 284.590027 -137.130573) (xy 284.532102 -137.146094) (xy 284.472646 -137.153922) (xy 284.412678 -137.153922)
			(xy 284.353222 -137.146094) (xy 284.295297 -137.130573) (xy 284.239893 -137.107624) (xy 284.187959 -137.07764)
			(xy 284.140383 -137.041134) (xy 284.097978 -136.998729) (xy 284.061472 -136.951153) (xy 284.031488 -136.899219)
			(xy 284.008539 -136.843815) (xy 283.993018 -136.78589) (xy 283.98519 -136.726434) (xy 283.9847 -136.69645)
			(xy 270.425672 -136.69645) (xy 270.425672 -136.704324) (xy 270.425182 -136.734308) (xy 270.417354 -136.793764)
			(xy 270.401833 -136.851689) (xy 270.378884 -136.907093) (xy 270.3489 -136.959027) (xy 270.312394 -137.006603)
			(xy 270.269989 -137.049008) (xy 270.222413 -137.085514) (xy 270.170479 -137.115498) (xy 270.115075 -137.138447)
			(xy 270.05715 -137.153968) (xy 269.997694 -137.161796) (xy 269.937726 -137.161796) (xy 269.87827 -137.153968)
			(xy 269.820345 -137.138447) (xy 269.764941 -137.115498) (xy 269.713007 -137.085514) (xy 269.665431 -137.049008)
			(xy 269.623026 -137.006603) (xy 269.58652 -136.959027) (xy 269.556536 -136.907093) (xy 269.533587 -136.851689)
			(xy 269.518066 -136.793764) (xy 269.510238 -136.734308) (xy 269.509748 -136.704324) (xy 168.800651 -136.704324)
			(xy 168.80029 -136.726434) (xy 168.792462 -136.78589) (xy 168.776941 -136.843815) (xy 168.753992 -136.899219)
			(xy 168.724008 -136.951153) (xy 168.687502 -136.998729) (xy 168.645097 -137.041134) (xy 168.597521 -137.07764)
			(xy 168.545587 -137.107624) (xy 168.490183 -137.130573) (xy 168.432258 -137.146094) (xy 168.372802 -137.153922)
			(xy 168.312834 -137.153922) (xy 168.253378 -137.146094) (xy 168.195453 -137.130573) (xy 168.140049 -137.107624)
			(xy 168.088115 -137.07764) (xy 168.040539 -137.041134) (xy 167.998134 -136.998729) (xy 167.961628 -136.951153)
			(xy 167.931644 -136.899219) (xy 167.908695 -136.843815) (xy 167.893174 -136.78589) (xy 167.885346 -136.726434)
			(xy 167.884856 -136.69645) (xy 154.325828 -136.69645) (xy 154.325828 -136.704324) (xy 154.325338 -136.734308)
			(xy 154.31751 -136.793764) (xy 154.301989 -136.851689) (xy 154.27904 -136.907093) (xy 154.249056 -136.959027)
			(xy 154.21255 -137.006603) (xy 154.170145 -137.049008) (xy 154.122569 -137.085514) (xy 154.070635 -137.115498)
			(xy 154.015231 -137.138447) (xy 153.957306 -137.153968) (xy 153.89785 -137.161796) (xy 153.837882 -137.161796)
			(xy 153.778426 -137.153968) (xy 153.720501 -137.138447) (xy 153.665097 -137.115498) (xy 153.613163 -137.085514)
			(xy 153.565587 -137.049008) (xy 153.523182 -137.006603) (xy 153.486676 -136.959027) (xy 153.456692 -136.907093)
			(xy 153.433743 -136.851689) (xy 153.418222 -136.793764) (xy 153.410394 -136.734308) (xy 153.409904 -136.704324)
			(xy 52.700299 -136.704324) (xy 52.699938 -136.726418) (xy 52.692115 -136.78584) (xy 52.676602 -136.843733)
			(xy 52.653666 -136.899106) (xy 52.623699 -136.951012) (xy 52.587212 -136.998562) (xy 52.544832 -137.040942)
			(xy 52.497282 -137.077429) (xy 52.445376 -137.107396) (xy 52.390003 -137.130332) (xy 52.33211 -137.145845)
			(xy 52.272688 -137.153668) (xy 52.212752 -137.153668) (xy 52.15333 -137.145845) (xy 52.095437 -137.130332)
			(xy 52.040064 -137.107396) (xy 51.988158 -137.077429) (xy 51.940608 -137.040942) (xy 51.898228 -136.998562)
			(xy 51.861741 -136.951012) (xy 51.831774 -136.899106) (xy 51.808838 -136.843733) (xy 51.793325 -136.78584)
			(xy 51.785502 -136.726418) (xy 51.785012 -136.69645) (xy 38.225476 -136.69645) (xy 38.225476 -136.704324)
			(xy 38.224986 -136.734292) (xy 38.217163 -136.793714) (xy 38.20165 -136.851607) (xy 38.178714 -136.90698)
			(xy 38.148747 -136.958886) (xy 38.11226 -137.006436) (xy 38.06988 -137.048816) (xy 38.02233 -137.085303)
			(xy 37.970424 -137.11527) (xy 37.915051 -137.138206) (xy 37.857158 -137.153719) (xy 37.797736 -137.161542)
			(xy 37.7378 -137.161542) (xy 37.678378 -137.153719) (xy 37.620485 -137.138206) (xy 37.565112 -137.11527)
			(xy 37.513206 -137.085303) (xy 37.465656 -137.048816) (xy 37.423276 -137.006436) (xy 37.386789 -136.958886)
			(xy 37.356822 -136.90698) (xy 37.333886 -136.851607) (xy 37.318373 -136.793714) (xy 37.31055 -136.734292)
			(xy 37.31006 -136.704324) (xy 4.308094 -136.704324) (xy 4.308094 -138.496548) (xy 43.97248 -138.496548)
			(xy 43.97248 -137.632948) (xy 43.97297 -137.602964) (xy 43.980798 -137.543508) (xy 43.996319 -137.485583)
			(xy 44.019268 -137.430179) (xy 44.049252 -137.378245) (xy 44.085758 -137.330669) (xy 44.128163 -137.288264)
			(xy 44.175739 -137.251758) (xy 44.227673 -137.221774) (xy 44.283077 -137.198825) (xy 44.341002 -137.183304)
			(xy 44.400458 -137.175476) (xy 44.460426 -137.175476) (xy 44.519882 -137.183304) (xy 44.577807 -137.198825)
			(xy 44.633211 -137.221774) (xy 44.685145 -137.251758) (xy 44.732721 -137.288264) (xy 44.775126 -137.330669)
			(xy 44.811632 -137.378245) (xy 44.841616 -137.430179) (xy 44.864565 -137.485583) (xy 44.880086 -137.543508)
			(xy 44.887914 -137.602964) (xy 44.888404 -137.632948) (xy 44.888404 -138.496548) (xy 160.072324 -138.496548)
			(xy 160.072324 -137.632948) (xy 160.072814 -137.602964) (xy 160.080642 -137.543508) (xy 160.096163 -137.485583)
			(xy 160.119112 -137.430179) (xy 160.149096 -137.378245) (xy 160.185602 -137.330669) (xy 160.228007 -137.288264)
			(xy 160.275583 -137.251758) (xy 160.327517 -137.221774) (xy 160.382921 -137.198825) (xy 160.440846 -137.183304)
			(xy 160.500302 -137.175476) (xy 160.56027 -137.175476) (xy 160.619726 -137.183304) (xy 160.677651 -137.198825)
			(xy 160.733055 -137.221774) (xy 160.784989 -137.251758) (xy 160.832565 -137.288264) (xy 160.87497 -137.330669)
			(xy 160.911476 -137.378245) (xy 160.94146 -137.430179) (xy 160.964409 -137.485583) (xy 160.97993 -137.543508)
			(xy 160.987758 -137.602964) (xy 160.988248 -137.632948) (xy 160.988248 -138.496548) (xy 276.172676 -138.496548)
			(xy 276.172676 -137.632948) (xy 276.173166 -137.60298) (xy 276.180989 -137.543558) (xy 276.196502 -137.485665)
			(xy 276.219438 -137.430292) (xy 276.249405 -137.378386) (xy 276.285892 -137.330836) (xy 276.328272 -137.288456)
			(xy 276.375822 -137.251969) (xy 276.427728 -137.222002) (xy 276.483101 -137.199066) (xy 276.540994 -137.183553)
			(xy 276.600416 -137.17573) (xy 276.660352 -137.17573) (xy 276.719774 -137.183553) (xy 276.777667 -137.199066)
			(xy 276.83304 -137.222002) (xy 276.884946 -137.251969) (xy 276.932496 -137.288456) (xy 276.974876 -137.330836)
			(xy 277.011363 -137.378386) (xy 277.04133 -137.430292) (xy 277.064266 -137.485665) (xy 277.079779 -137.543558)
			(xy 277.087602 -137.60298) (xy 277.088092 -137.632948) (xy 277.088092 -138.496548) (xy 277.088084 -138.497056)
			(xy 392.27252 -138.497056) (xy 392.27252 -137.633456) (xy 392.27301 -137.603472) (xy 392.280838 -137.544016)
			(xy 392.296359 -137.486091) (xy 392.319308 -137.430687) (xy 392.349292 -137.378753) (xy 392.385798 -137.331177)
			(xy 392.428203 -137.288772) (xy 392.475779 -137.252266) (xy 392.527713 -137.222282) (xy 392.583117 -137.199333)
			(xy 392.641042 -137.183812) (xy 392.700498 -137.175984) (xy 392.760466 -137.175984) (xy 392.819922 -137.183812)
			(xy 392.877847 -137.199333) (xy 392.933251 -137.222282) (xy 392.985185 -137.252266) (xy 393.032761 -137.288772)
			(xy 393.075166 -137.331177) (xy 393.111672 -137.378753) (xy 393.141656 -137.430687) (xy 393.164605 -137.486091)
			(xy 393.180126 -137.544016) (xy 393.187954 -137.603472) (xy 393.188444 -137.633456) (xy 393.188444 -138.497056)
			(xy 393.187954 -138.52704) (xy 393.180126 -138.586496) (xy 393.164605 -138.644421) (xy 393.141656 -138.699825)
			(xy 393.111672 -138.751759) (xy 393.075166 -138.799335) (xy 393.032761 -138.84174) (xy 392.985185 -138.878246)
			(xy 392.933251 -138.90823) (xy 392.877847 -138.931179) (xy 392.819922 -138.9467) (xy 392.760466 -138.954528)
			(xy 392.700498 -138.954528) (xy 392.641042 -138.9467) (xy 392.583117 -138.931179) (xy 392.527713 -138.90823)
			(xy 392.475779 -138.878246) (xy 392.428203 -138.84174) (xy 392.385798 -138.799335) (xy 392.349292 -138.751759)
			(xy 392.319308 -138.699825) (xy 392.296359 -138.644421) (xy 392.280838 -138.586496) (xy 392.27301 -138.52704)
			(xy 392.27252 -138.497056) (xy 277.088084 -138.497056) (xy 277.087602 -138.526516) (xy 277.079779 -138.585938)
			(xy 277.064266 -138.643831) (xy 277.04133 -138.699204) (xy 277.011363 -138.75111) (xy 276.974876 -138.79866)
			(xy 276.932496 -138.84104) (xy 276.884946 -138.877527) (xy 276.83304 -138.907494) (xy 276.777667 -138.93043)
			(xy 276.719774 -138.945943) (xy 276.660352 -138.953766) (xy 276.600416 -138.953766) (xy 276.540994 -138.945943)
			(xy 276.483101 -138.93043) (xy 276.427728 -138.907494) (xy 276.375822 -138.877527) (xy 276.328272 -138.84104)
			(xy 276.285892 -138.79866) (xy 276.249405 -138.75111) (xy 276.219438 -138.699204) (xy 276.196502 -138.643831)
			(xy 276.180989 -138.585938) (xy 276.173166 -138.526516) (xy 276.172676 -138.496548) (xy 160.988248 -138.496548)
			(xy 160.987758 -138.526532) (xy 160.97993 -138.585988) (xy 160.964409 -138.643913) (xy 160.94146 -138.699317)
			(xy 160.911476 -138.751251) (xy 160.87497 -138.798827) (xy 160.832565 -138.841232) (xy 160.784989 -138.877738)
			(xy 160.733055 -138.907722) (xy 160.677651 -138.930671) (xy 160.619726 -138.946192) (xy 160.56027 -138.95402)
			(xy 160.500302 -138.95402) (xy 160.440846 -138.946192) (xy 160.382921 -138.930671) (xy 160.327517 -138.907722)
			(xy 160.275583 -138.877738) (xy 160.228007 -138.841232) (xy 160.185602 -138.798827) (xy 160.149096 -138.751251)
			(xy 160.119112 -138.699317) (xy 160.096163 -138.643913) (xy 160.080642 -138.585988) (xy 160.072814 -138.526532)
			(xy 160.072324 -138.496548) (xy 44.888404 -138.496548) (xy 44.887914 -138.526532) (xy 44.880086 -138.585988)
			(xy 44.864565 -138.643913) (xy 44.841616 -138.699317) (xy 44.811632 -138.751251) (xy 44.775126 -138.798827)
			(xy 44.732721 -138.841232) (xy 44.685145 -138.877738) (xy 44.633211 -138.907722) (xy 44.577807 -138.930671)
			(xy 44.519882 -138.946192) (xy 44.460426 -138.95402) (xy 44.400458 -138.95402) (xy 44.341002 -138.946192)
			(xy 44.283077 -138.930671) (xy 44.227673 -138.907722) (xy 44.175739 -138.877738) (xy 44.128163 -138.841232)
			(xy 44.085758 -138.798827) (xy 44.049252 -138.751251) (xy 44.019268 -138.699317) (xy 43.996319 -138.643913)
			(xy 43.980798 -138.585988) (xy 43.97297 -138.526532) (xy 43.97248 -138.496548) (xy 4.308094 -138.496548)
			(xy 4.308094 -143.48714) (xy 66.599308 -143.48714) (xy 66.599308 -142.62354) (xy 66.599798 -142.593556)
			(xy 66.607626 -142.5341) (xy 66.623147 -142.476175) (xy 66.646096 -142.420771) (xy 66.67608 -142.368837)
			(xy 66.712586 -142.321261) (xy 66.754991 -142.278856) (xy 66.802567 -142.24235) (xy 66.854501 -142.212366)
			(xy 66.909905 -142.189417) (xy 66.96783 -142.173896) (xy 67.027286 -142.166068) (xy 67.087254 -142.166068)
			(xy 67.14671 -142.173896) (xy 67.204635 -142.189417) (xy 67.260039 -142.212366) (xy 67.311973 -142.24235)
			(xy 67.359549 -142.278856) (xy 67.401954 -142.321261) (xy 67.43846 -142.368837) (xy 67.468444 -142.420771)
			(xy 67.491393 -142.476175) (xy 67.506914 -142.5341) (xy 67.514742 -142.593556) (xy 67.515232 -142.62354)
			(xy 67.515232 -143.479266) (xy 81.07426 -143.479266) (xy 81.07426 -142.615666) (xy 81.07475 -142.585682)
			(xy 81.082578 -142.526226) (xy 81.098099 -142.468301) (xy 81.121048 -142.412897) (xy 81.151032 -142.360963)
			(xy 81.187538 -142.313387) (xy 81.229943 -142.270982) (xy 81.277519 -142.234476) (xy 81.329453 -142.204492)
			(xy 81.384857 -142.181543) (xy 81.442782 -142.166022) (xy 81.502238 -142.158194) (xy 81.562206 -142.158194)
			(xy 81.621662 -142.166022) (xy 81.679587 -142.181543) (xy 81.734991 -142.204492) (xy 81.786925 -142.234476)
			(xy 81.834501 -142.270982) (xy 81.876906 -142.313387) (xy 81.913412 -142.360963) (xy 81.943396 -142.412897)
			(xy 81.966345 -142.468301) (xy 81.981866 -142.526226) (xy 81.989694 -142.585682) (xy 81.990184 -142.615666)
			(xy 81.990184 -143.479266) (xy 81.990055 -143.48714) (xy 182.69966 -143.48714) (xy 182.69966 -142.62354)
			(xy 182.70015 -142.593572) (xy 182.707973 -142.53415) (xy 182.723486 -142.476257) (xy 182.746422 -142.420884)
			(xy 182.776389 -142.368978) (xy 182.812876 -142.321428) (xy 182.855256 -142.279048) (xy 182.902806 -142.242561)
			(xy 182.954712 -142.212594) (xy 183.010085 -142.189658) (xy 183.067978 -142.174145) (xy 183.1274 -142.166322)
			(xy 183.187336 -142.166322) (xy 183.246758 -142.174145) (xy 183.304651 -142.189658) (xy 183.360024 -142.212594)
			(xy 183.41193 -142.242561) (xy 183.45948 -142.279048) (xy 183.50186 -142.321428) (xy 183.538347 -142.368978)
			(xy 183.568314 -142.420884) (xy 183.59125 -142.476257) (xy 183.606763 -142.53415) (xy 183.614586 -142.593572)
			(xy 183.615076 -142.62354) (xy 183.615076 -143.479266) (xy 197.174612 -143.479266) (xy 197.174612 -142.615666)
			(xy 197.175102 -142.585698) (xy 197.182925 -142.526276) (xy 197.198438 -142.468383) (xy 197.221374 -142.41301)
			(xy 197.251341 -142.361104) (xy 197.287828 -142.313554) (xy 197.330208 -142.271174) (xy 197.377758 -142.234687)
			(xy 197.429664 -142.20472) (xy 197.485037 -142.181784) (xy 197.54293 -142.166271) (xy 197.602352 -142.158448)
			(xy 197.662288 -142.158448) (xy 197.72171 -142.166271) (xy 197.779603 -142.181784) (xy 197.834976 -142.20472)
			(xy 197.886882 -142.234687) (xy 197.934432 -142.271174) (xy 197.976812 -142.313554) (xy 198.013299 -142.361104)
			(xy 198.043266 -142.41301) (xy 198.066202 -142.468383) (xy 198.081715 -142.526276) (xy 198.089538 -142.585698)
			(xy 198.090028 -142.615666) (xy 198.090028 -143.479266) (xy 198.089899 -143.48714) (xy 298.799504 -143.48714)
			(xy 298.799504 -142.62354) (xy 298.799994 -142.593572) (xy 298.807817 -142.53415) (xy 298.82333 -142.476257)
			(xy 298.846266 -142.420884) (xy 298.876233 -142.368978) (xy 298.91272 -142.321428) (xy 298.9551 -142.279048)
			(xy 299.00265 -142.242561) (xy 299.054556 -142.212594) (xy 299.109929 -142.189658) (xy 299.167822 -142.174145)
			(xy 299.227244 -142.166322) (xy 299.28718 -142.166322) (xy 299.346602 -142.174145) (xy 299.404495 -142.189658)
			(xy 299.459868 -142.212594) (xy 299.511774 -142.242561) (xy 299.559324 -142.279048) (xy 299.601704 -142.321428)
			(xy 299.638191 -142.368978) (xy 299.668158 -142.420884) (xy 299.691094 -142.476257) (xy 299.706607 -142.53415)
			(xy 299.71443 -142.593572) (xy 299.71492 -142.62354) (xy 299.71492 -143.479266) (xy 313.274456 -143.479266)
			(xy 313.274456 -142.615666) (xy 313.274946 -142.585698) (xy 313.282769 -142.526276) (xy 313.298282 -142.468383)
			(xy 313.321218 -142.41301) (xy 313.351185 -142.361104) (xy 313.387672 -142.313554) (xy 313.430052 -142.271174)
			(xy 313.477602 -142.234687) (xy 313.529508 -142.20472) (xy 313.584881 -142.181784) (xy 313.642774 -142.166271)
			(xy 313.702196 -142.158448) (xy 313.762132 -142.158448) (xy 313.821554 -142.166271) (xy 313.879447 -142.181784)
			(xy 313.93482 -142.20472) (xy 313.986726 -142.234687) (xy 314.034276 -142.271174) (xy 314.076656 -142.313554)
			(xy 314.113143 -142.361104) (xy 314.14311 -142.41301) (xy 314.166046 -142.468383) (xy 314.181559 -142.526276)
			(xy 314.189382 -142.585698) (xy 314.189872 -142.615666) (xy 314.189872 -143.479266) (xy 314.189743 -143.48714)
			(xy 414.899348 -143.48714) (xy 414.899348 -142.62354) (xy 414.899838 -142.593556) (xy 414.907666 -142.5341)
			(xy 414.923187 -142.476175) (xy 414.946136 -142.420771) (xy 414.97612 -142.368837) (xy 415.012626 -142.321261)
			(xy 415.055031 -142.278856) (xy 415.102607 -142.24235) (xy 415.154541 -142.212366) (xy 415.209945 -142.189417)
			(xy 415.26787 -142.173896) (xy 415.327326 -142.166068) (xy 415.387294 -142.166068) (xy 415.44675 -142.173896)
			(xy 415.504675 -142.189417) (xy 415.560079 -142.212366) (xy 415.612013 -142.24235) (xy 415.659589 -142.278856)
			(xy 415.701994 -142.321261) (xy 415.7385 -142.368837) (xy 415.768484 -142.420771) (xy 415.791433 -142.476175)
			(xy 415.806954 -142.5341) (xy 415.814782 -142.593556) (xy 415.815272 -142.62354) (xy 415.815272 -143.479266)
			(xy 429.3743 -143.479266) (xy 429.3743 -142.615666) (xy 429.37479 -142.585682) (xy 429.382618 -142.526226)
			(xy 429.398139 -142.468301) (xy 429.421088 -142.412897) (xy 429.451072 -142.360963) (xy 429.487578 -142.313387)
			(xy 429.529983 -142.270982) (xy 429.577559 -142.234476) (xy 429.629493 -142.204492) (xy 429.684897 -142.181543)
			(xy 429.742822 -142.166022) (xy 429.802278 -142.158194) (xy 429.862246 -142.158194) (xy 429.921702 -142.166022)
			(xy 429.979627 -142.181543) (xy 430.035031 -142.204492) (xy 430.086965 -142.234476) (xy 430.134541 -142.270982)
			(xy 430.176946 -142.313387) (xy 430.213452 -142.360963) (xy 430.243436 -142.412897) (xy 430.266385 -142.468301)
			(xy 430.281906 -142.526226) (xy 430.289734 -142.585682) (xy 430.290224 -142.615666) (xy 430.290224 -143.479266)
			(xy 430.289734 -143.50925) (xy 430.281906 -143.568706) (xy 430.266385 -143.626631) (xy 430.243436 -143.682035)
			(xy 430.213452 -143.733969) (xy 430.176946 -143.781545) (xy 430.134541 -143.82395) (xy 430.086965 -143.860456)
			(xy 430.035031 -143.89044) (xy 429.979627 -143.913389) (xy 429.921702 -143.92891) (xy 429.862246 -143.936738)
			(xy 429.802278 -143.936738) (xy 429.742822 -143.92891) (xy 429.684897 -143.913389) (xy 429.629493 -143.89044)
			(xy 429.577559 -143.860456) (xy 429.529983 -143.82395) (xy 429.487578 -143.781545) (xy 429.451072 -143.733969)
			(xy 429.421088 -143.682035) (xy 429.398139 -143.626631) (xy 429.382618 -143.568706) (xy 429.37479 -143.50925)
			(xy 429.3743 -143.479266) (xy 415.815272 -143.479266) (xy 415.815272 -143.48714) (xy 415.814782 -143.517124)
			(xy 415.806954 -143.57658) (xy 415.791433 -143.634505) (xy 415.768484 -143.689909) (xy 415.7385 -143.741843)
			(xy 415.701994 -143.789419) (xy 415.659589 -143.831824) (xy 415.612013 -143.86833) (xy 415.560079 -143.898314)
			(xy 415.504675 -143.921263) (xy 415.44675 -143.936784) (xy 415.387294 -143.944612) (xy 415.327326 -143.944612)
			(xy 415.26787 -143.936784) (xy 415.209945 -143.921263) (xy 415.154541 -143.898314) (xy 415.102607 -143.86833)
			(xy 415.055031 -143.831824) (xy 415.012626 -143.789419) (xy 414.97612 -143.741843) (xy 414.946136 -143.689909)
			(xy 414.923187 -143.634505) (xy 414.907666 -143.57658) (xy 414.899838 -143.517124) (xy 414.899348 -143.48714)
			(xy 314.189743 -143.48714) (xy 314.189382 -143.509234) (xy 314.181559 -143.568656) (xy 314.166046 -143.626549)
			(xy 314.14311 -143.681922) (xy 314.113143 -143.733828) (xy 314.076656 -143.781378) (xy 314.034276 -143.823758)
			(xy 313.986726 -143.860245) (xy 313.93482 -143.890212) (xy 313.879447 -143.913148) (xy 313.821554 -143.928661)
			(xy 313.762132 -143.936484) (xy 313.702196 -143.936484) (xy 313.642774 -143.928661) (xy 313.584881 -143.913148)
			(xy 313.529508 -143.890212) (xy 313.477602 -143.860245) (xy 313.430052 -143.823758) (xy 313.387672 -143.781378)
			(xy 313.351185 -143.733828) (xy 313.321218 -143.681922) (xy 313.298282 -143.626549) (xy 313.282769 -143.568656)
			(xy 313.274946 -143.509234) (xy 313.274456 -143.479266) (xy 299.71492 -143.479266) (xy 299.71492 -143.48714)
			(xy 299.71443 -143.517108) (xy 299.706607 -143.57653) (xy 299.691094 -143.634423) (xy 299.668158 -143.689796)
			(xy 299.638191 -143.741702) (xy 299.601704 -143.789252) (xy 299.559324 -143.831632) (xy 299.511774 -143.868119)
			(xy 299.459868 -143.898086) (xy 299.404495 -143.921022) (xy 299.346602 -143.936535) (xy 299.28718 -143.944358)
			(xy 299.227244 -143.944358) (xy 299.167822 -143.936535) (xy 299.109929 -143.921022) (xy 299.054556 -143.898086)
			(xy 299.00265 -143.868119) (xy 298.9551 -143.831632) (xy 298.91272 -143.789252) (xy 298.876233 -143.741702)
			(xy 298.846266 -143.689796) (xy 298.82333 -143.634423) (xy 298.807817 -143.57653) (xy 298.799994 -143.517108)
			(xy 298.799504 -143.48714) (xy 198.089899 -143.48714) (xy 198.089538 -143.509234) (xy 198.081715 -143.568656)
			(xy 198.066202 -143.626549) (xy 198.043266 -143.681922) (xy 198.013299 -143.733828) (xy 197.976812 -143.781378)
			(xy 197.934432 -143.823758) (xy 197.886882 -143.860245) (xy 197.834976 -143.890212) (xy 197.779603 -143.913148)
			(xy 197.72171 -143.928661) (xy 197.662288 -143.936484) (xy 197.602352 -143.936484) (xy 197.54293 -143.928661)
			(xy 197.485037 -143.913148) (xy 197.429664 -143.890212) (xy 197.377758 -143.860245) (xy 197.330208 -143.823758)
			(xy 197.287828 -143.781378) (xy 197.251341 -143.733828) (xy 197.221374 -143.681922) (xy 197.198438 -143.626549)
			(xy 197.182925 -143.568656) (xy 197.175102 -143.509234) (xy 197.174612 -143.479266) (xy 183.615076 -143.479266)
			(xy 183.615076 -143.48714) (xy 183.614586 -143.517108) (xy 183.606763 -143.57653) (xy 183.59125 -143.634423)
			(xy 183.568314 -143.689796) (xy 183.538347 -143.741702) (xy 183.50186 -143.789252) (xy 183.45948 -143.831632)
			(xy 183.41193 -143.868119) (xy 183.360024 -143.898086) (xy 183.304651 -143.921022) (xy 183.246758 -143.936535)
			(xy 183.187336 -143.944358) (xy 183.1274 -143.944358) (xy 183.067978 -143.936535) (xy 183.010085 -143.921022)
			(xy 182.954712 -143.898086) (xy 182.902806 -143.868119) (xy 182.855256 -143.831632) (xy 182.812876 -143.789252)
			(xy 182.776389 -143.741702) (xy 182.746422 -143.689796) (xy 182.723486 -143.634423) (xy 182.707973 -143.57653)
			(xy 182.70015 -143.517108) (xy 182.69966 -143.48714) (xy 81.990055 -143.48714) (xy 81.989694 -143.50925)
			(xy 81.981866 -143.568706) (xy 81.966345 -143.626631) (xy 81.943396 -143.682035) (xy 81.913412 -143.733969)
			(xy 81.876906 -143.781545) (xy 81.834501 -143.82395) (xy 81.786925 -143.860456) (xy 81.734991 -143.89044)
			(xy 81.679587 -143.913389) (xy 81.621662 -143.92891) (xy 81.562206 -143.936738) (xy 81.502238 -143.936738)
			(xy 81.442782 -143.92891) (xy 81.384857 -143.913389) (xy 81.329453 -143.89044) (xy 81.277519 -143.860456)
			(xy 81.229943 -143.82395) (xy 81.187538 -143.781545) (xy 81.151032 -143.733969) (xy 81.121048 -143.682035)
			(xy 81.098099 -143.626631) (xy 81.082578 -143.568706) (xy 81.07475 -143.50925) (xy 81.07426 -143.479266)
			(xy 67.515232 -143.479266) (xy 67.515232 -143.48714) (xy 67.514742 -143.517124) (xy 67.506914 -143.57658)
			(xy 67.491393 -143.634505) (xy 67.468444 -143.689909) (xy 67.43846 -143.741843) (xy 67.401954 -143.789419)
			(xy 67.359549 -143.831824) (xy 67.311973 -143.86833) (xy 67.260039 -143.898314) (xy 67.204635 -143.921263)
			(xy 67.14671 -143.936784) (xy 67.087254 -143.944612) (xy 67.027286 -143.944612) (xy 66.96783 -143.936784)
			(xy 66.909905 -143.921263) (xy 66.854501 -143.898314) (xy 66.802567 -143.86833) (xy 66.754991 -143.831824)
			(xy 66.712586 -143.789419) (xy 66.67608 -143.741843) (xy 66.646096 -143.689909) (xy 66.623147 -143.634505)
			(xy 66.607626 -143.57658) (xy 66.599798 -143.517124) (xy 66.599308 -143.48714) (xy 4.308094 -143.48714)
			(xy 4.308094 -145.287238) (xy 64.745108 -145.287238) (xy 64.745108 -144.423638) (xy 64.745598 -144.393654)
			(xy 64.753426 -144.334198) (xy 64.768947 -144.276273) (xy 64.791896 -144.220869) (xy 64.82188 -144.168935)
			(xy 64.858386 -144.121359) (xy 64.900791 -144.078954) (xy 64.948367 -144.042448) (xy 65.000301 -144.012464)
			(xy 65.055705 -143.989515) (xy 65.11363 -143.973994) (xy 65.173086 -143.966166) (xy 65.233054 -143.966166)
			(xy 65.29251 -143.973994) (xy 65.350435 -143.989515) (xy 65.405839 -144.012464) (xy 65.457773 -144.042448)
			(xy 65.505349 -144.078954) (xy 65.547754 -144.121359) (xy 65.58426 -144.168935) (xy 65.614244 -144.220869)
			(xy 65.637193 -144.276273) (xy 65.652714 -144.334198) (xy 65.660542 -144.393654) (xy 65.661032 -144.423638)
			(xy 65.661032 -145.285714) (xy 83.716368 -145.285714) (xy 83.716368 -144.422114) (xy 83.716858 -144.39213)
			(xy 83.724686 -144.332674) (xy 83.740207 -144.274749) (xy 83.763156 -144.219345) (xy 83.79314 -144.167411)
			(xy 83.829646 -144.119835) (xy 83.872051 -144.07743) (xy 83.919627 -144.040924) (xy 83.971561 -144.01094)
			(xy 84.026965 -143.987991) (xy 84.08489 -143.97247) (xy 84.144346 -143.964642) (xy 84.204314 -143.964642)
			(xy 84.26377 -143.97247) (xy 84.321695 -143.987991) (xy 84.377099 -144.01094) (xy 84.429033 -144.040924)
			(xy 84.476609 -144.07743) (xy 84.519014 -144.119835) (xy 84.55552 -144.167411) (xy 84.585504 -144.219345)
			(xy 84.608453 -144.274749) (xy 84.623974 -144.332674) (xy 84.631802 -144.39213) (xy 84.632292 -144.422114)
			(xy 84.632292 -145.285714) (xy 84.632267 -145.287238) (xy 180.84546 -145.287238) (xy 180.84546 -144.423638)
			(xy 180.84595 -144.39367) (xy 180.853773 -144.334248) (xy 180.869286 -144.276355) (xy 180.892222 -144.220982)
			(xy 180.922189 -144.169076) (xy 180.958676 -144.121526) (xy 181.001056 -144.079146) (xy 181.048606 -144.042659)
			(xy 181.100512 -144.012692) (xy 181.155885 -143.989756) (xy 181.213778 -143.974243) (xy 181.2732 -143.96642)
			(xy 181.333136 -143.96642) (xy 181.392558 -143.974243) (xy 181.450451 -143.989756) (xy 181.505824 -144.012692)
			(xy 181.55773 -144.042659) (xy 181.60528 -144.079146) (xy 181.64766 -144.121526) (xy 181.684147 -144.169076)
			(xy 181.714114 -144.220982) (xy 181.73705 -144.276355) (xy 181.752563 -144.334248) (xy 181.760386 -144.39367)
			(xy 181.760876 -144.423638) (xy 181.760876 -145.285714) (xy 199.81672 -145.285714) (xy 199.81672 -144.422114)
			(xy 199.81721 -144.392146) (xy 199.825033 -144.332724) (xy 199.840546 -144.274831) (xy 199.863482 -144.219458)
			(xy 199.893449 -144.167552) (xy 199.929936 -144.120002) (xy 199.972316 -144.077622) (xy 200.019866 -144.041135)
			(xy 200.071772 -144.011168) (xy 200.127145 -143.988232) (xy 200.185038 -143.972719) (xy 200.24446 -143.964896)
			(xy 200.304396 -143.964896) (xy 200.363818 -143.972719) (xy 200.421711 -143.988232) (xy 200.477084 -144.011168)
			(xy 200.52899 -144.041135) (xy 200.57654 -144.077622) (xy 200.61892 -144.120002) (xy 200.655407 -144.167552)
			(xy 200.685374 -144.219458) (xy 200.70831 -144.274831) (xy 200.723823 -144.332724) (xy 200.731646 -144.392146)
			(xy 200.732136 -144.422114) (xy 200.732136 -145.285714) (xy 200.732111 -145.287238) (xy 296.945304 -145.287238)
			(xy 296.945304 -144.423638) (xy 296.945794 -144.39367) (xy 296.953617 -144.334248) (xy 296.96913 -144.276355)
			(xy 296.992066 -144.220982) (xy 297.022033 -144.169076) (xy 297.05852 -144.121526) (xy 297.1009 -144.079146)
			(xy 297.14845 -144.042659) (xy 297.200356 -144.012692) (xy 297.255729 -143.989756) (xy 297.313622 -143.974243)
			(xy 297.373044 -143.96642) (xy 297.43298 -143.96642) (xy 297.492402 -143.974243) (xy 297.550295 -143.989756)
			(xy 297.605668 -144.012692) (xy 297.657574 -144.042659) (xy 297.705124 -144.079146) (xy 297.747504 -144.121526)
			(xy 297.783991 -144.169076) (xy 297.813958 -144.220982) (xy 297.836894 -144.276355) (xy 297.852407 -144.334248)
			(xy 297.86023 -144.39367) (xy 297.86072 -144.423638) (xy 297.86072 -145.285714) (xy 315.916564 -145.285714)
			(xy 315.916564 -144.422114) (xy 315.917054 -144.392146) (xy 315.924877 -144.332724) (xy 315.94039 -144.274831)
			(xy 315.963326 -144.219458) (xy 315.993293 -144.167552) (xy 316.02978 -144.120002) (xy 316.07216 -144.077622)
			(xy 316.11971 -144.041135) (xy 316.171616 -144.011168) (xy 316.226989 -143.988232) (xy 316.284882 -143.972719)
			(xy 316.344304 -143.964896) (xy 316.40424 -143.964896) (xy 316.463662 -143.972719) (xy 316.521555 -143.988232)
			(xy 316.576928 -144.011168) (xy 316.628834 -144.041135) (xy 316.676384 -144.077622) (xy 316.718764 -144.120002)
			(xy 316.755251 -144.167552) (xy 316.785218 -144.219458) (xy 316.808154 -144.274831) (xy 316.823667 -144.332724)
			(xy 316.83149 -144.392146) (xy 316.83198 -144.422114) (xy 316.83198 -145.285714) (xy 316.831955 -145.287238)
			(xy 413.045148 -145.287238) (xy 413.045148 -144.423638) (xy 413.045638 -144.393654) (xy 413.053466 -144.334198)
			(xy 413.068987 -144.276273) (xy 413.091936 -144.220869) (xy 413.12192 -144.168935) (xy 413.158426 -144.121359)
			(xy 413.200831 -144.078954) (xy 413.248407 -144.042448) (xy 413.300341 -144.012464) (xy 413.355745 -143.989515)
			(xy 413.41367 -143.973994) (xy 413.473126 -143.966166) (xy 413.533094 -143.966166) (xy 413.59255 -143.973994)
			(xy 413.650475 -143.989515) (xy 413.705879 -144.012464) (xy 413.757813 -144.042448) (xy 413.805389 -144.078954)
			(xy 413.847794 -144.121359) (xy 413.8843 -144.168935) (xy 413.914284 -144.220869) (xy 413.937233 -144.276273)
			(xy 413.952754 -144.334198) (xy 413.960582 -144.393654) (xy 413.961072 -144.423638) (xy 413.961072 -145.285714)
			(xy 432.016408 -145.285714) (xy 432.016408 -144.422114) (xy 432.016898 -144.39213) (xy 432.024726 -144.332674)
			(xy 432.040247 -144.274749) (xy 432.063196 -144.219345) (xy 432.09318 -144.167411) (xy 432.129686 -144.119835)
			(xy 432.172091 -144.07743) (xy 432.219667 -144.040924) (xy 432.271601 -144.01094) (xy 432.327005 -143.987991)
			(xy 432.38493 -143.97247) (xy 432.444386 -143.964642) (xy 432.504354 -143.964642) (xy 432.56381 -143.97247)
			(xy 432.621735 -143.987991) (xy 432.677139 -144.01094) (xy 432.729073 -144.040924) (xy 432.776649 -144.07743)
			(xy 432.819054 -144.119835) (xy 432.85556 -144.167411) (xy 432.885544 -144.219345) (xy 432.908493 -144.274749)
			(xy 432.924014 -144.332674) (xy 432.931842 -144.39213) (xy 432.932332 -144.422114) (xy 432.932332 -145.285714)
			(xy 432.931842 -145.315698) (xy 432.924014 -145.375154) (xy 432.908493 -145.433079) (xy 432.885544 -145.488483)
			(xy 432.85556 -145.540417) (xy 432.819054 -145.587993) (xy 432.776649 -145.630398) (xy 432.729073 -145.666904)
			(xy 432.677139 -145.696888) (xy 432.621735 -145.719837) (xy 432.56381 -145.735358) (xy 432.504354 -145.743186)
			(xy 432.444386 -145.743186) (xy 432.38493 -145.735358) (xy 432.327005 -145.719837) (xy 432.271601 -145.696888)
			(xy 432.219667 -145.666904) (xy 432.172091 -145.630398) (xy 432.129686 -145.587993) (xy 432.09318 -145.540417)
			(xy 432.063196 -145.488483) (xy 432.040247 -145.433079) (xy 432.024726 -145.375154) (xy 432.016898 -145.315698)
			(xy 432.016408 -145.285714) (xy 413.961072 -145.285714) (xy 413.961072 -145.287238) (xy 413.960582 -145.317222)
			(xy 413.952754 -145.376678) (xy 413.937233 -145.434603) (xy 413.914284 -145.490007) (xy 413.8843 -145.541941)
			(xy 413.847794 -145.589517) (xy 413.805389 -145.631922) (xy 413.757813 -145.668428) (xy 413.705879 -145.698412)
			(xy 413.650475 -145.721361) (xy 413.59255 -145.736882) (xy 413.533094 -145.74471) (xy 413.473126 -145.74471)
			(xy 413.41367 -145.736882) (xy 413.355745 -145.721361) (xy 413.300341 -145.698412) (xy 413.248407 -145.668428)
			(xy 413.200831 -145.631922) (xy 413.158426 -145.589517) (xy 413.12192 -145.541941) (xy 413.091936 -145.490007)
			(xy 413.068987 -145.434603) (xy 413.053466 -145.376678) (xy 413.045638 -145.317222) (xy 413.045148 -145.287238)
			(xy 316.831955 -145.287238) (xy 316.83149 -145.315682) (xy 316.823667 -145.375104) (xy 316.808154 -145.432997)
			(xy 316.785218 -145.48837) (xy 316.755251 -145.540276) (xy 316.718764 -145.587826) (xy 316.676384 -145.630206)
			(xy 316.628834 -145.666693) (xy 316.576928 -145.69666) (xy 316.521555 -145.719596) (xy 316.463662 -145.735109)
			(xy 316.40424 -145.742932) (xy 316.344304 -145.742932) (xy 316.284882 -145.735109) (xy 316.226989 -145.719596)
			(xy 316.171616 -145.69666) (xy 316.11971 -145.666693) (xy 316.07216 -145.630206) (xy 316.02978 -145.587826)
			(xy 315.993293 -145.540276) (xy 315.963326 -145.48837) (xy 315.94039 -145.432997) (xy 315.924877 -145.375104)
			(xy 315.917054 -145.315682) (xy 315.916564 -145.285714) (xy 297.86072 -145.285714) (xy 297.86072 -145.287238)
			(xy 297.86023 -145.317206) (xy 297.852407 -145.376628) (xy 297.836894 -145.434521) (xy 297.813958 -145.489894)
			(xy 297.783991 -145.5418) (xy 297.747504 -145.58935) (xy 297.705124 -145.63173) (xy 297.657574 -145.668217)
			(xy 297.605668 -145.698184) (xy 297.550295 -145.72112) (xy 297.492402 -145.736633) (xy 297.43298 -145.744456)
			(xy 297.373044 -145.744456) (xy 297.313622 -145.736633) (xy 297.255729 -145.72112) (xy 297.200356 -145.698184)
			(xy 297.14845 -145.668217) (xy 297.1009 -145.63173) (xy 297.05852 -145.58935) (xy 297.022033 -145.5418)
			(xy 296.992066 -145.489894) (xy 296.96913 -145.434521) (xy 296.953617 -145.376628) (xy 296.945794 -145.317206)
			(xy 296.945304 -145.287238) (xy 200.732111 -145.287238) (xy 200.731646 -145.315682) (xy 200.723823 -145.375104)
			(xy 200.70831 -145.432997) (xy 200.685374 -145.48837) (xy 200.655407 -145.540276) (xy 200.61892 -145.587826)
			(xy 200.57654 -145.630206) (xy 200.52899 -145.666693) (xy 200.477084 -145.69666) (xy 200.421711 -145.719596)
			(xy 200.363818 -145.735109) (xy 200.304396 -145.742932) (xy 200.24446 -145.742932) (xy 200.185038 -145.735109)
			(xy 200.127145 -145.719596) (xy 200.071772 -145.69666) (xy 200.019866 -145.666693) (xy 199.972316 -145.630206)
			(xy 199.929936 -145.587826) (xy 199.893449 -145.540276) (xy 199.863482 -145.48837) (xy 199.840546 -145.432997)
			(xy 199.825033 -145.375104) (xy 199.81721 -145.315682) (xy 199.81672 -145.285714) (xy 181.760876 -145.285714)
			(xy 181.760876 -145.287238) (xy 181.760386 -145.317206) (xy 181.752563 -145.376628) (xy 181.73705 -145.434521)
			(xy 181.714114 -145.489894) (xy 181.684147 -145.5418) (xy 181.64766 -145.58935) (xy 181.60528 -145.63173)
			(xy 181.55773 -145.668217) (xy 181.505824 -145.698184) (xy 181.450451 -145.72112) (xy 181.392558 -145.736633)
			(xy 181.333136 -145.744456) (xy 181.2732 -145.744456) (xy 181.213778 -145.736633) (xy 181.155885 -145.72112)
			(xy 181.100512 -145.698184) (xy 181.048606 -145.668217) (xy 181.001056 -145.63173) (xy 180.958676 -145.58935)
			(xy 180.922189 -145.5418) (xy 180.892222 -145.489894) (xy 180.869286 -145.434521) (xy 180.853773 -145.376628)
			(xy 180.84595 -145.317206) (xy 180.84546 -145.287238) (xy 84.632267 -145.287238) (xy 84.631802 -145.315698)
			(xy 84.623974 -145.375154) (xy 84.608453 -145.433079) (xy 84.585504 -145.488483) (xy 84.55552 -145.540417)
			(xy 84.519014 -145.587993) (xy 84.476609 -145.630398) (xy 84.429033 -145.666904) (xy 84.377099 -145.696888)
			(xy 84.321695 -145.719837) (xy 84.26377 -145.735358) (xy 84.204314 -145.743186) (xy 84.144346 -145.743186)
			(xy 84.08489 -145.735358) (xy 84.026965 -145.719837) (xy 83.971561 -145.696888) (xy 83.919627 -145.666904)
			(xy 83.872051 -145.630398) (xy 83.829646 -145.587993) (xy 83.79314 -145.540417) (xy 83.763156 -145.488483)
			(xy 83.740207 -145.433079) (xy 83.724686 -145.375154) (xy 83.716858 -145.315698) (xy 83.716368 -145.285714)
			(xy 65.661032 -145.285714) (xy 65.661032 -145.287238) (xy 65.660542 -145.317222) (xy 65.652714 -145.376678)
			(xy 65.637193 -145.434603) (xy 65.614244 -145.490007) (xy 65.58426 -145.541941) (xy 65.547754 -145.589517)
			(xy 65.505349 -145.631922) (xy 65.457773 -145.668428) (xy 65.405839 -145.698412) (xy 65.350435 -145.721361)
			(xy 65.29251 -145.736882) (xy 65.233054 -145.74471) (xy 65.173086 -145.74471) (xy 65.11363 -145.736882)
			(xy 65.055705 -145.721361) (xy 65.000301 -145.698412) (xy 64.948367 -145.668428) (xy 64.900791 -145.631922)
			(xy 64.858386 -145.589517) (xy 64.82188 -145.541941) (xy 64.791896 -145.490007) (xy 64.768947 -145.434603)
			(xy 64.753426 -145.376678) (xy 64.745598 -145.317222) (xy 64.745108 -145.287238) (xy 4.308094 -145.287238)
			(xy 4.308094 -147.087336) (xy 66.599308 -147.087336) (xy 66.599308 -146.223736) (xy 66.599798 -146.193752)
			(xy 66.607626 -146.134296) (xy 66.623147 -146.076371) (xy 66.646096 -146.020967) (xy 66.67608 -145.969033)
			(xy 66.712586 -145.921457) (xy 66.754991 -145.879052) (xy 66.802567 -145.842546) (xy 66.854501 -145.812562)
			(xy 66.909905 -145.789613) (xy 66.96783 -145.774092) (xy 67.027286 -145.766264) (xy 67.087254 -145.766264)
			(xy 67.14671 -145.774092) (xy 67.204635 -145.789613) (xy 67.260039 -145.812562) (xy 67.311973 -145.842546)
			(xy 67.359549 -145.879052) (xy 67.401954 -145.921457) (xy 67.43846 -145.969033) (xy 67.468444 -146.020967)
			(xy 67.491393 -146.076371) (xy 67.506914 -146.134296) (xy 67.514742 -146.193752) (xy 67.515232 -146.223736)
			(xy 67.515232 -147.079208) (xy 81.07426 -147.079208) (xy 81.07426 -146.215608) (xy 81.07475 -146.185624)
			(xy 81.082578 -146.126168) (xy 81.098099 -146.068243) (xy 81.121048 -146.012839) (xy 81.151032 -145.960905)
			(xy 81.187538 -145.913329) (xy 81.229943 -145.870924) (xy 81.277519 -145.834418) (xy 81.329453 -145.804434)
			(xy 81.384857 -145.781485) (xy 81.442782 -145.765964) (xy 81.502238 -145.758136) (xy 81.562206 -145.758136)
			(xy 81.621662 -145.765964) (xy 81.679587 -145.781485) (xy 81.734991 -145.804434) (xy 81.786925 -145.834418)
			(xy 81.834501 -145.870924) (xy 81.876906 -145.913329) (xy 81.913412 -145.960905) (xy 81.943396 -146.012839)
			(xy 81.966345 -146.068243) (xy 81.981866 -146.126168) (xy 81.989694 -146.185624) (xy 81.990184 -146.215608)
			(xy 81.990184 -147.079208) (xy 81.990051 -147.087336) (xy 182.69966 -147.087336) (xy 182.69966 -146.223736)
			(xy 182.70015 -146.193768) (xy 182.707973 -146.134346) (xy 182.723486 -146.076453) (xy 182.746422 -146.02108)
			(xy 182.776389 -145.969174) (xy 182.812876 -145.921624) (xy 182.855256 -145.879244) (xy 182.902806 -145.842757)
			(xy 182.954712 -145.81279) (xy 183.010085 -145.789854) (xy 183.067978 -145.774341) (xy 183.1274 -145.766518)
			(xy 183.187336 -145.766518) (xy 183.246758 -145.774341) (xy 183.304651 -145.789854) (xy 183.360024 -145.81279)
			(xy 183.41193 -145.842757) (xy 183.45948 -145.879244) (xy 183.50186 -145.921624) (xy 183.538347 -145.969174)
			(xy 183.568314 -146.02108) (xy 183.59125 -146.076453) (xy 183.606763 -146.134346) (xy 183.614586 -146.193768)
			(xy 183.615076 -146.223736) (xy 183.615076 -147.079208) (xy 197.174612 -147.079208) (xy 197.174612 -146.215608)
			(xy 197.175102 -146.18564) (xy 197.182925 -146.126218) (xy 197.198438 -146.068325) (xy 197.221374 -146.012952)
			(xy 197.251341 -145.961046) (xy 197.287828 -145.913496) (xy 197.330208 -145.871116) (xy 197.377758 -145.834629)
			(xy 197.429664 -145.804662) (xy 197.485037 -145.781726) (xy 197.54293 -145.766213) (xy 197.602352 -145.75839)
			(xy 197.662288 -145.75839) (xy 197.72171 -145.766213) (xy 197.779603 -145.781726) (xy 197.834976 -145.804662)
			(xy 197.886882 -145.834629) (xy 197.934432 -145.871116) (xy 197.976812 -145.913496) (xy 198.013299 -145.961046)
			(xy 198.043266 -146.012952) (xy 198.066202 -146.068325) (xy 198.081715 -146.126218) (xy 198.089538 -146.18564)
			(xy 198.090028 -146.215608) (xy 198.090028 -147.079208) (xy 198.089895 -147.087336) (xy 298.799504 -147.087336)
			(xy 298.799504 -146.223736) (xy 298.799994 -146.193768) (xy 298.807817 -146.134346) (xy 298.82333 -146.076453)
			(xy 298.846266 -146.02108) (xy 298.876233 -145.969174) (xy 298.91272 -145.921624) (xy 298.9551 -145.879244)
			(xy 299.00265 -145.842757) (xy 299.054556 -145.81279) (xy 299.109929 -145.789854) (xy 299.167822 -145.774341)
			(xy 299.227244 -145.766518) (xy 299.28718 -145.766518) (xy 299.346602 -145.774341) (xy 299.404495 -145.789854)
			(xy 299.459868 -145.81279) (xy 299.511774 -145.842757) (xy 299.559324 -145.879244) (xy 299.601704 -145.921624)
			(xy 299.638191 -145.969174) (xy 299.668158 -146.02108) (xy 299.691094 -146.076453) (xy 299.706607 -146.134346)
			(xy 299.71443 -146.193768) (xy 299.71492 -146.223736) (xy 299.71492 -147.079208) (xy 313.274456 -147.079208)
			(xy 313.274456 -146.215608) (xy 313.274946 -146.18564) (xy 313.282769 -146.126218) (xy 313.298282 -146.068325)
			(xy 313.321218 -146.012952) (xy 313.351185 -145.961046) (xy 313.387672 -145.913496) (xy 313.430052 -145.871116)
			(xy 313.477602 -145.834629) (xy 313.529508 -145.804662) (xy 313.584881 -145.781726) (xy 313.642774 -145.766213)
			(xy 313.702196 -145.75839) (xy 313.762132 -145.75839) (xy 313.821554 -145.766213) (xy 313.879447 -145.781726)
			(xy 313.93482 -145.804662) (xy 313.986726 -145.834629) (xy 314.034276 -145.871116) (xy 314.076656 -145.913496)
			(xy 314.113143 -145.961046) (xy 314.14311 -146.012952) (xy 314.166046 -146.068325) (xy 314.181559 -146.126218)
			(xy 314.189382 -146.18564) (xy 314.189872 -146.215608) (xy 314.189872 -147.079208) (xy 314.189739 -147.087336)
			(xy 414.899348 -147.087336) (xy 414.899348 -146.223736) (xy 414.899838 -146.193752) (xy 414.907666 -146.134296)
			(xy 414.923187 -146.076371) (xy 414.946136 -146.020967) (xy 414.97612 -145.969033) (xy 415.012626 -145.921457)
			(xy 415.055031 -145.879052) (xy 415.102607 -145.842546) (xy 415.154541 -145.812562) (xy 415.209945 -145.789613)
			(xy 415.26787 -145.774092) (xy 415.327326 -145.766264) (xy 415.387294 -145.766264) (xy 415.44675 -145.774092)
			(xy 415.504675 -145.789613) (xy 415.560079 -145.812562) (xy 415.612013 -145.842546) (xy 415.659589 -145.879052)
			(xy 415.701994 -145.921457) (xy 415.7385 -145.969033) (xy 415.768484 -146.020967) (xy 415.791433 -146.076371)
			(xy 415.806954 -146.134296) (xy 415.814782 -146.193752) (xy 415.815272 -146.223736) (xy 415.815272 -147.079208)
			(xy 429.3743 -147.079208) (xy 429.3743 -146.215608) (xy 429.37479 -146.185624) (xy 429.382618 -146.126168)
			(xy 429.398139 -146.068243) (xy 429.421088 -146.012839) (xy 429.451072 -145.960905) (xy 429.487578 -145.913329)
			(xy 429.529983 -145.870924) (xy 429.577559 -145.834418) (xy 429.629493 -145.804434) (xy 429.684897 -145.781485)
			(xy 429.742822 -145.765964) (xy 429.802278 -145.758136) (xy 429.862246 -145.758136) (xy 429.921702 -145.765964)
			(xy 429.979627 -145.781485) (xy 430.035031 -145.804434) (xy 430.086965 -145.834418) (xy 430.134541 -145.870924)
			(xy 430.176946 -145.913329) (xy 430.213452 -145.960905) (xy 430.243436 -146.012839) (xy 430.266385 -146.068243)
			(xy 430.281906 -146.126168) (xy 430.289734 -146.185624) (xy 430.290224 -146.215608) (xy 430.290224 -147.079208)
			(xy 430.289734 -147.109192) (xy 430.281906 -147.168648) (xy 430.266385 -147.226573) (xy 430.243436 -147.281977)
			(xy 430.213452 -147.333911) (xy 430.176946 -147.381487) (xy 430.134541 -147.423892) (xy 430.086965 -147.460398)
			(xy 430.035031 -147.490382) (xy 429.979627 -147.513331) (xy 429.921702 -147.528852) (xy 429.862246 -147.53668)
			(xy 429.802278 -147.53668) (xy 429.742822 -147.528852) (xy 429.684897 -147.513331) (xy 429.629493 -147.490382)
			(xy 429.577559 -147.460398) (xy 429.529983 -147.423892) (xy 429.487578 -147.381487) (xy 429.451072 -147.333911)
			(xy 429.421088 -147.281977) (xy 429.398139 -147.226573) (xy 429.382618 -147.168648) (xy 429.37479 -147.109192)
			(xy 429.3743 -147.079208) (xy 415.815272 -147.079208) (xy 415.815272 -147.087336) (xy 415.814782 -147.11732)
			(xy 415.806954 -147.176776) (xy 415.791433 -147.234701) (xy 415.768484 -147.290105) (xy 415.7385 -147.342039)
			(xy 415.701994 -147.389615) (xy 415.659589 -147.43202) (xy 415.612013 -147.468526) (xy 415.560079 -147.49851)
			(xy 415.504675 -147.521459) (xy 415.44675 -147.53698) (xy 415.387294 -147.544808) (xy 415.327326 -147.544808)
			(xy 415.26787 -147.53698) (xy 415.209945 -147.521459) (xy 415.154541 -147.49851) (xy 415.102607 -147.468526)
			(xy 415.055031 -147.43202) (xy 415.012626 -147.389615) (xy 414.97612 -147.342039) (xy 414.946136 -147.290105)
			(xy 414.923187 -147.234701) (xy 414.907666 -147.176776) (xy 414.899838 -147.11732) (xy 414.899348 -147.087336)
			(xy 314.189739 -147.087336) (xy 314.189382 -147.109176) (xy 314.181559 -147.168598) (xy 314.166046 -147.226491)
			(xy 314.14311 -147.281864) (xy 314.113143 -147.33377) (xy 314.076656 -147.38132) (xy 314.034276 -147.4237)
			(xy 313.986726 -147.460187) (xy 313.93482 -147.490154) (xy 313.879447 -147.51309) (xy 313.821554 -147.528603)
			(xy 313.762132 -147.536426) (xy 313.702196 -147.536426) (xy 313.642774 -147.528603) (xy 313.584881 -147.51309)
			(xy 313.529508 -147.490154) (xy 313.477602 -147.460187) (xy 313.430052 -147.4237) (xy 313.387672 -147.38132)
			(xy 313.351185 -147.33377) (xy 313.321218 -147.281864) (xy 313.298282 -147.226491) (xy 313.282769 -147.168598)
			(xy 313.274946 -147.109176) (xy 313.274456 -147.079208) (xy 299.71492 -147.079208) (xy 299.71492 -147.087336)
			(xy 299.71443 -147.117304) (xy 299.706607 -147.176726) (xy 299.691094 -147.234619) (xy 299.668158 -147.289992)
			(xy 299.638191 -147.341898) (xy 299.601704 -147.389448) (xy 299.559324 -147.431828) (xy 299.511774 -147.468315)
			(xy 299.459868 -147.498282) (xy 299.404495 -147.521218) (xy 299.346602 -147.536731) (xy 299.28718 -147.544554)
			(xy 299.227244 -147.544554) (xy 299.167822 -147.536731) (xy 299.109929 -147.521218) (xy 299.054556 -147.498282)
			(xy 299.00265 -147.468315) (xy 298.9551 -147.431828) (xy 298.91272 -147.389448) (xy 298.876233 -147.341898)
			(xy 298.846266 -147.289992) (xy 298.82333 -147.234619) (xy 298.807817 -147.176726) (xy 298.799994 -147.117304)
			(xy 298.799504 -147.087336) (xy 198.089895 -147.087336) (xy 198.089538 -147.109176) (xy 198.081715 -147.168598)
			(xy 198.066202 -147.226491) (xy 198.043266 -147.281864) (xy 198.013299 -147.33377) (xy 197.976812 -147.38132)
			(xy 197.934432 -147.4237) (xy 197.886882 -147.460187) (xy 197.834976 -147.490154) (xy 197.779603 -147.51309)
			(xy 197.72171 -147.528603) (xy 197.662288 -147.536426) (xy 197.602352 -147.536426) (xy 197.54293 -147.528603)
			(xy 197.485037 -147.51309) (xy 197.429664 -147.490154) (xy 197.377758 -147.460187) (xy 197.330208 -147.4237)
			(xy 197.287828 -147.38132) (xy 197.251341 -147.33377) (xy 197.221374 -147.281864) (xy 197.198438 -147.226491)
			(xy 197.182925 -147.168598) (xy 197.175102 -147.109176) (xy 197.174612 -147.079208) (xy 183.615076 -147.079208)
			(xy 183.615076 -147.087336) (xy 183.614586 -147.117304) (xy 183.606763 -147.176726) (xy 183.59125 -147.234619)
			(xy 183.568314 -147.289992) (xy 183.538347 -147.341898) (xy 183.50186 -147.389448) (xy 183.45948 -147.431828)
			(xy 183.41193 -147.468315) (xy 183.360024 -147.498282) (xy 183.304651 -147.521218) (xy 183.246758 -147.536731)
			(xy 183.187336 -147.544554) (xy 183.1274 -147.544554) (xy 183.067978 -147.536731) (xy 183.010085 -147.521218)
			(xy 182.954712 -147.498282) (xy 182.902806 -147.468315) (xy 182.855256 -147.431828) (xy 182.812876 -147.389448)
			(xy 182.776389 -147.341898) (xy 182.746422 -147.289992) (xy 182.723486 -147.234619) (xy 182.707973 -147.176726)
			(xy 182.70015 -147.117304) (xy 182.69966 -147.087336) (xy 81.990051 -147.087336) (xy 81.989694 -147.109192)
			(xy 81.981866 -147.168648) (xy 81.966345 -147.226573) (xy 81.943396 -147.281977) (xy 81.913412 -147.333911)
			(xy 81.876906 -147.381487) (xy 81.834501 -147.423892) (xy 81.786925 -147.460398) (xy 81.734991 -147.490382)
			(xy 81.679587 -147.513331) (xy 81.621662 -147.528852) (xy 81.562206 -147.53668) (xy 81.502238 -147.53668)
			(xy 81.442782 -147.528852) (xy 81.384857 -147.513331) (xy 81.329453 -147.490382) (xy 81.277519 -147.460398)
			(xy 81.229943 -147.423892) (xy 81.187538 -147.381487) (xy 81.151032 -147.333911) (xy 81.121048 -147.281977)
			(xy 81.098099 -147.226573) (xy 81.082578 -147.168648) (xy 81.07475 -147.109192) (xy 81.07426 -147.079208)
			(xy 67.515232 -147.079208) (xy 67.515232 -147.087336) (xy 67.514742 -147.11732) (xy 67.506914 -147.176776)
			(xy 67.491393 -147.234701) (xy 67.468444 -147.290105) (xy 67.43846 -147.342039) (xy 67.401954 -147.389615)
			(xy 67.359549 -147.43202) (xy 67.311973 -147.468526) (xy 67.260039 -147.49851) (xy 67.204635 -147.521459)
			(xy 67.14671 -147.53698) (xy 67.087254 -147.544808) (xy 67.027286 -147.544808) (xy 66.96783 -147.53698)
			(xy 66.909905 -147.521459) (xy 66.854501 -147.49851) (xy 66.802567 -147.468526) (xy 66.754991 -147.43202)
			(xy 66.712586 -147.389615) (xy 66.67608 -147.342039) (xy 66.646096 -147.290105) (xy 66.623147 -147.234701)
			(xy 66.607626 -147.176776) (xy 66.599798 -147.11732) (xy 66.599308 -147.087336) (xy 4.308094 -147.087336)
			(xy 4.308094 -148.887434) (xy 64.745108 -148.887434) (xy 64.745108 -148.023834) (xy 64.745598 -147.99385)
			(xy 64.753426 -147.934394) (xy 64.768947 -147.876469) (xy 64.791896 -147.821065) (xy 64.82188 -147.769131)
			(xy 64.858386 -147.721555) (xy 64.900791 -147.67915) (xy 64.948367 -147.642644) (xy 65.000301 -147.61266)
			(xy 65.055705 -147.589711) (xy 65.11363 -147.57419) (xy 65.173086 -147.566362) (xy 65.233054 -147.566362)
			(xy 65.29251 -147.57419) (xy 65.350435 -147.589711) (xy 65.405839 -147.61266) (xy 65.457773 -147.642644)
			(xy 65.505349 -147.67915) (xy 65.547754 -147.721555) (xy 65.58426 -147.769131) (xy 65.614244 -147.821065)
			(xy 65.637193 -147.876469) (xy 65.652714 -147.934394) (xy 65.660542 -147.99385) (xy 65.661032 -148.023834)
			(xy 65.661032 -148.88591) (xy 83.716368 -148.88591) (xy 83.716368 -148.02231) (xy 83.716858 -147.992326)
			(xy 83.724686 -147.93287) (xy 83.740207 -147.874945) (xy 83.763156 -147.819541) (xy 83.79314 -147.767607)
			(xy 83.829646 -147.720031) (xy 83.872051 -147.677626) (xy 83.919627 -147.64112) (xy 83.971561 -147.611136)
			(xy 84.026965 -147.588187) (xy 84.08489 -147.572666) (xy 84.144346 -147.564838) (xy 84.204314 -147.564838)
			(xy 84.26377 -147.572666) (xy 84.321695 -147.588187) (xy 84.377099 -147.611136) (xy 84.429033 -147.64112)
			(xy 84.476609 -147.677626) (xy 84.519014 -147.720031) (xy 84.55552 -147.767607) (xy 84.585504 -147.819541)
			(xy 84.608453 -147.874945) (xy 84.623974 -147.93287) (xy 84.631802 -147.992326) (xy 84.632292 -148.02231)
			(xy 84.632292 -148.88591) (xy 84.632267 -148.887434) (xy 180.84546 -148.887434) (xy 180.84546 -148.023834)
			(xy 180.84595 -147.993866) (xy 180.853773 -147.934444) (xy 180.869286 -147.876551) (xy 180.892222 -147.821178)
			(xy 180.922189 -147.769272) (xy 180.958676 -147.721722) (xy 181.001056 -147.679342) (xy 181.048606 -147.642855)
			(xy 181.100512 -147.612888) (xy 181.155885 -147.589952) (xy 181.213778 -147.574439) (xy 181.2732 -147.566616)
			(xy 181.333136 -147.566616) (xy 181.392558 -147.574439) (xy 181.450451 -147.589952) (xy 181.505824 -147.612888)
			(xy 181.55773 -147.642855) (xy 181.60528 -147.679342) (xy 181.64766 -147.721722) (xy 181.684147 -147.769272)
			(xy 181.714114 -147.821178) (xy 181.73705 -147.876551) (xy 181.752563 -147.934444) (xy 181.760386 -147.993866)
			(xy 181.760876 -148.023834) (xy 181.760876 -148.88591) (xy 199.81672 -148.88591) (xy 199.81672 -148.02231)
			(xy 199.81721 -147.992342) (xy 199.825033 -147.93292) (xy 199.840546 -147.875027) (xy 199.863482 -147.819654)
			(xy 199.893449 -147.767748) (xy 199.929936 -147.720198) (xy 199.972316 -147.677818) (xy 200.019866 -147.641331)
			(xy 200.071772 -147.611364) (xy 200.127145 -147.588428) (xy 200.185038 -147.572915) (xy 200.24446 -147.565092)
			(xy 200.304396 -147.565092) (xy 200.363818 -147.572915) (xy 200.421711 -147.588428) (xy 200.477084 -147.611364)
			(xy 200.52899 -147.641331) (xy 200.57654 -147.677818) (xy 200.61892 -147.720198) (xy 200.655407 -147.767748)
			(xy 200.685374 -147.819654) (xy 200.70831 -147.875027) (xy 200.723823 -147.93292) (xy 200.731646 -147.992342)
			(xy 200.732136 -148.02231) (xy 200.732136 -148.88591) (xy 200.731646 -148.915878) (xy 200.723823 -148.9753)
			(xy 200.70831 -149.033193) (xy 200.685374 -149.088566) (xy 200.655407 -149.140472) (xy 200.61892 -149.188022)
			(xy 200.57654 -149.230402) (xy 200.52899 -149.266889) (xy 200.477084 -149.296856) (xy 200.421711 -149.319792)
			(xy 200.363818 -149.335305) (xy 200.304396 -149.343128) (xy 200.24446 -149.343128) (xy 200.185038 -149.335305)
			(xy 200.127145 -149.319792) (xy 200.071772 -149.296856) (xy 200.019866 -149.266889) (xy 199.972316 -149.230402)
			(xy 199.929936 -149.188022) (xy 199.893449 -149.140472) (xy 199.863482 -149.088566) (xy 199.840546 -149.033193)
			(xy 199.825033 -148.9753) (xy 199.81721 -148.915878) (xy 199.81672 -148.88591) (xy 181.760876 -148.88591)
			(xy 181.760876 -148.887434) (xy 181.760386 -148.917402) (xy 181.752563 -148.976824) (xy 181.73705 -149.034717)
			(xy 181.714114 -149.09009) (xy 181.684147 -149.141996) (xy 181.64766 -149.189546) (xy 181.60528 -149.231926)
			(xy 181.55773 -149.268413) (xy 181.505824 -149.29838) (xy 181.450451 -149.321316) (xy 181.392558 -149.336829)
			(xy 181.333136 -149.344652) (xy 181.2732 -149.344652) (xy 181.213778 -149.336829) (xy 181.155885 -149.321316)
			(xy 181.100512 -149.29838) (xy 181.048606 -149.268413) (xy 181.001056 -149.231926) (xy 180.958676 -149.189546)
			(xy 180.922189 -149.141996) (xy 180.892222 -149.09009) (xy 180.869286 -149.034717) (xy 180.853773 -148.976824)
			(xy 180.84595 -148.917402) (xy 180.84546 -148.887434) (xy 84.632267 -148.887434) (xy 84.631802 -148.915894)
			(xy 84.623974 -148.97535) (xy 84.608453 -149.033275) (xy 84.585504 -149.088679) (xy 84.55552 -149.140613)
			(xy 84.519014 -149.188189) (xy 84.476609 -149.230594) (xy 84.429033 -149.2671) (xy 84.377099 -149.297084)
			(xy 84.321695 -149.320033) (xy 84.26377 -149.335554) (xy 84.204314 -149.343382) (xy 84.144346 -149.343382)
			(xy 84.08489 -149.335554) (xy 84.026965 -149.320033) (xy 83.971561 -149.297084) (xy 83.919627 -149.2671)
			(xy 83.872051 -149.230594) (xy 83.829646 -149.188189) (xy 83.79314 -149.140613) (xy 83.763156 -149.088679)
			(xy 83.740207 -149.033275) (xy 83.724686 -148.97535) (xy 83.716858 -148.915894) (xy 83.716368 -148.88591)
			(xy 65.661032 -148.88591) (xy 65.661032 -148.887434) (xy 65.660542 -148.917418) (xy 65.652714 -148.976874)
			(xy 65.637193 -149.034799) (xy 65.614244 -149.090203) (xy 65.58426 -149.142137) (xy 65.547754 -149.189713)
			(xy 65.505349 -149.232118) (xy 65.457773 -149.268624) (xy 65.405839 -149.298608) (xy 65.350435 -149.321557)
			(xy 65.29251 -149.337078) (xy 65.233054 -149.344906) (xy 65.173086 -149.344906) (xy 65.11363 -149.337078)
			(xy 65.055705 -149.321557) (xy 65.000301 -149.298608) (xy 64.948367 -149.268624) (xy 64.900791 -149.232118)
			(xy 64.858386 -149.189713) (xy 64.82188 -149.142137) (xy 64.791896 -149.090203) (xy 64.768947 -149.034799)
			(xy 64.753426 -148.976874) (xy 64.745598 -148.917418) (xy 64.745108 -148.887434) (xy 4.308094 -148.887434)
			(xy 4.308094 -150.687278) (xy 66.599308 -150.687278) (xy 66.599308 -149.823678) (xy 66.599798 -149.793694)
			(xy 66.607626 -149.734238) (xy 66.623147 -149.676313) (xy 66.646096 -149.620909) (xy 66.67608 -149.568975)
			(xy 66.712586 -149.521399) (xy 66.754991 -149.478994) (xy 66.802567 -149.442488) (xy 66.854501 -149.412504)
			(xy 66.909905 -149.389555) (xy 66.96783 -149.374034) (xy 67.027286 -149.366206) (xy 67.087254 -149.366206)
			(xy 67.14671 -149.374034) (xy 67.204635 -149.389555) (xy 67.260039 -149.412504) (xy 67.311973 -149.442488)
			(xy 67.359549 -149.478994) (xy 67.401954 -149.521399) (xy 67.43846 -149.568975) (xy 67.468444 -149.620909)
			(xy 67.491393 -149.676313) (xy 67.506914 -149.734238) (xy 67.514742 -149.793694) (xy 67.515232 -149.823678)
			(xy 67.515232 -150.67915) (xy 81.07426 -150.67915) (xy 81.07426 -149.81555) (xy 81.07475 -149.785566)
			(xy 81.082578 -149.72611) (xy 81.098099 -149.668185) (xy 81.121048 -149.612781) (xy 81.151032 -149.560847)
			(xy 81.187538 -149.513271) (xy 81.229943 -149.470866) (xy 81.277519 -149.43436) (xy 81.329453 -149.404376)
			(xy 81.384857 -149.381427) (xy 81.442782 -149.365906) (xy 81.502238 -149.358078) (xy 81.562206 -149.358078)
			(xy 81.621662 -149.365906) (xy 81.679587 -149.381427) (xy 81.734991 -149.404376) (xy 81.786925 -149.43436)
			(xy 81.834501 -149.470866) (xy 81.876906 -149.513271) (xy 81.913412 -149.560847) (xy 81.943396 -149.612781)
			(xy 81.966345 -149.668185) (xy 81.981866 -149.72611) (xy 81.989694 -149.785566) (xy 81.990184 -149.81555)
			(xy 81.990184 -150.67915) (xy 81.990051 -150.687278) (xy 182.69966 -150.687278) (xy 182.69966 -149.823678)
			(xy 182.70015 -149.79371) (xy 182.707973 -149.734288) (xy 182.723486 -149.676395) (xy 182.746422 -149.621022)
			(xy 182.776389 -149.569116) (xy 182.812876 -149.521566) (xy 182.855256 -149.479186) (xy 182.902806 -149.442699)
			(xy 182.954712 -149.412732) (xy 183.010085 -149.389796) (xy 183.067978 -149.374283) (xy 183.1274 -149.36646)
			(xy 183.187336 -149.36646) (xy 183.246758 -149.374283) (xy 183.304651 -149.389796) (xy 183.360024 -149.412732)
			(xy 183.41193 -149.442699) (xy 183.45948 -149.479186) (xy 183.50186 -149.521566) (xy 183.538347 -149.569116)
			(xy 183.568314 -149.621022) (xy 183.59125 -149.676395) (xy 183.606763 -149.734288) (xy 183.614586 -149.79371)
			(xy 183.615076 -149.823678) (xy 183.615076 -150.67915) (xy 197.174612 -150.67915) (xy 197.174612 -149.81555)
			(xy 197.175102 -149.785582) (xy 197.182925 -149.72616) (xy 197.198438 -149.668267) (xy 197.221374 -149.612894)
			(xy 197.251341 -149.560988) (xy 197.287828 -149.513438) (xy 197.330208 -149.471058) (xy 197.377758 -149.434571)
			(xy 197.429664 -149.404604) (xy 197.485037 -149.381668) (xy 197.54293 -149.366155) (xy 197.602352 -149.358332)
			(xy 197.662288 -149.358332) (xy 197.72171 -149.366155) (xy 197.779603 -149.381668) (xy 197.834976 -149.404604)
			(xy 197.886882 -149.434571) (xy 197.934432 -149.471058) (xy 197.976812 -149.513438) (xy 198.013299 -149.560988)
			(xy 198.043266 -149.612894) (xy 198.066202 -149.668267) (xy 198.072386 -149.691344) (xy 236.708188 -149.691344)
			(xy 236.708188 -148.827744) (xy 236.708678 -148.79776) (xy 236.716506 -148.738304) (xy 236.732027 -148.680379)
			(xy 236.754976 -148.624975) (xy 236.78496 -148.573041) (xy 236.821466 -148.525465) (xy 236.863871 -148.48306)
			(xy 236.911447 -148.446554) (xy 236.963381 -148.41657) (xy 237.018785 -148.393621) (xy 237.07671 -148.3781)
			(xy 237.136166 -148.370272) (xy 237.196134 -148.370272) (xy 237.25559 -148.3781) (xy 237.313515 -148.393621)
			(xy 237.368919 -148.41657) (xy 237.420853 -148.446554) (xy 237.468429 -148.48306) (xy 237.510834 -148.525465)
			(xy 237.54734 -148.573041) (xy 237.577324 -148.624975) (xy 237.600273 -148.680379) (xy 237.615794 -148.738304)
			(xy 237.623622 -148.79776) (xy 237.624112 -148.827744) (xy 237.624112 -148.887434) (xy 296.945304 -148.887434)
			(xy 296.945304 -148.023834) (xy 296.945794 -147.993866) (xy 296.953617 -147.934444) (xy 296.96913 -147.876551)
			(xy 296.992066 -147.821178) (xy 297.022033 -147.769272) (xy 297.05852 -147.721722) (xy 297.1009 -147.679342)
			(xy 297.14845 -147.642855) (xy 297.200356 -147.612888) (xy 297.255729 -147.589952) (xy 297.313622 -147.574439)
			(xy 297.373044 -147.566616) (xy 297.43298 -147.566616) (xy 297.492402 -147.574439) (xy 297.550295 -147.589952)
			(xy 297.605668 -147.612888) (xy 297.657574 -147.642855) (xy 297.705124 -147.679342) (xy 297.747504 -147.721722)
			(xy 297.783991 -147.769272) (xy 297.813958 -147.821178) (xy 297.836894 -147.876551) (xy 297.852407 -147.934444)
			(xy 297.86023 -147.993866) (xy 297.86072 -148.023834) (xy 297.86072 -148.88591) (xy 315.916564 -148.88591)
			(xy 315.916564 -148.02231) (xy 315.917054 -147.992342) (xy 315.924877 -147.93292) (xy 315.94039 -147.875027)
			(xy 315.963326 -147.819654) (xy 315.993293 -147.767748) (xy 316.02978 -147.720198) (xy 316.07216 -147.677818)
			(xy 316.11971 -147.641331) (xy 316.171616 -147.611364) (xy 316.226989 -147.588428) (xy 316.284882 -147.572915)
			(xy 316.344304 -147.565092) (xy 316.40424 -147.565092) (xy 316.463662 -147.572915) (xy 316.521555 -147.588428)
			(xy 316.576928 -147.611364) (xy 316.628834 -147.641331) (xy 316.676384 -147.677818) (xy 316.718764 -147.720198)
			(xy 316.755251 -147.767748) (xy 316.785218 -147.819654) (xy 316.808154 -147.875027) (xy 316.823667 -147.93292)
			(xy 316.83149 -147.992342) (xy 316.83198 -148.02231) (xy 316.83198 -148.88591) (xy 316.831955 -148.887434)
			(xy 413.045148 -148.887434) (xy 413.045148 -148.023834) (xy 413.045638 -147.99385) (xy 413.053466 -147.934394)
			(xy 413.068987 -147.876469) (xy 413.091936 -147.821065) (xy 413.12192 -147.769131) (xy 413.158426 -147.721555)
			(xy 413.200831 -147.67915) (xy 413.248407 -147.642644) (xy 413.300341 -147.61266) (xy 413.355745 -147.589711)
			(xy 413.41367 -147.57419) (xy 413.473126 -147.566362) (xy 413.533094 -147.566362) (xy 413.59255 -147.57419)
			(xy 413.650475 -147.589711) (xy 413.705879 -147.61266) (xy 413.757813 -147.642644) (xy 413.805389 -147.67915)
			(xy 413.847794 -147.721555) (xy 413.8843 -147.769131) (xy 413.914284 -147.821065) (xy 413.937233 -147.876469)
			(xy 413.952754 -147.934394) (xy 413.960582 -147.99385) (xy 413.961072 -148.023834) (xy 413.961072 -148.88591)
			(xy 432.016408 -148.88591) (xy 432.016408 -148.02231) (xy 432.016898 -147.992326) (xy 432.024726 -147.93287)
			(xy 432.040247 -147.874945) (xy 432.063196 -147.819541) (xy 432.09318 -147.767607) (xy 432.129686 -147.720031)
			(xy 432.172091 -147.677626) (xy 432.219667 -147.64112) (xy 432.271601 -147.611136) (xy 432.327005 -147.588187)
			(xy 432.38493 -147.572666) (xy 432.444386 -147.564838) (xy 432.504354 -147.564838) (xy 432.56381 -147.572666)
			(xy 432.621735 -147.588187) (xy 432.677139 -147.611136) (xy 432.729073 -147.64112) (xy 432.776649 -147.677626)
			(xy 432.819054 -147.720031) (xy 432.85556 -147.767607) (xy 432.885544 -147.819541) (xy 432.908493 -147.874945)
			(xy 432.924014 -147.93287) (xy 432.931842 -147.992326) (xy 432.932332 -148.02231) (xy 432.932332 -148.88591)
			(xy 432.931842 -148.915894) (xy 432.924014 -148.97535) (xy 432.908493 -149.033275) (xy 432.885544 -149.088679)
			(xy 432.85556 -149.140613) (xy 432.819054 -149.188189) (xy 432.776649 -149.230594) (xy 432.729073 -149.2671)
			(xy 432.677139 -149.297084) (xy 432.621735 -149.320033) (xy 432.56381 -149.335554) (xy 432.504354 -149.343382)
			(xy 432.444386 -149.343382) (xy 432.38493 -149.335554) (xy 432.327005 -149.320033) (xy 432.271601 -149.297084)
			(xy 432.219667 -149.2671) (xy 432.172091 -149.230594) (xy 432.129686 -149.188189) (xy 432.09318 -149.140613)
			(xy 432.063196 -149.088679) (xy 432.040247 -149.033275) (xy 432.024726 -148.97535) (xy 432.016898 -148.915894)
			(xy 432.016408 -148.88591) (xy 413.961072 -148.88591) (xy 413.961072 -148.887434) (xy 413.960582 -148.917418)
			(xy 413.952754 -148.976874) (xy 413.937233 -149.034799) (xy 413.914284 -149.090203) (xy 413.8843 -149.142137)
			(xy 413.847794 -149.189713) (xy 413.805389 -149.232118) (xy 413.757813 -149.268624) (xy 413.705879 -149.298608)
			(xy 413.650475 -149.321557) (xy 413.59255 -149.337078) (xy 413.533094 -149.344906) (xy 413.473126 -149.344906)
			(xy 413.41367 -149.337078) (xy 413.355745 -149.321557) (xy 413.300341 -149.298608) (xy 413.248407 -149.268624)
			(xy 413.200831 -149.232118) (xy 413.158426 -149.189713) (xy 413.12192 -149.142137) (xy 413.091936 -149.090203)
			(xy 413.068987 -149.034799) (xy 413.053466 -148.976874) (xy 413.045638 -148.917418) (xy 413.045148 -148.887434)
			(xy 316.831955 -148.887434) (xy 316.83149 -148.915878) (xy 316.823667 -148.9753) (xy 316.808154 -149.033193)
			(xy 316.785218 -149.088566) (xy 316.755251 -149.140472) (xy 316.718764 -149.188022) (xy 316.676384 -149.230402)
			(xy 316.628834 -149.266889) (xy 316.576928 -149.296856) (xy 316.521555 -149.319792) (xy 316.463662 -149.335305)
			(xy 316.40424 -149.343128) (xy 316.344304 -149.343128) (xy 316.284882 -149.335305) (xy 316.226989 -149.319792)
			(xy 316.171616 -149.296856) (xy 316.11971 -149.266889) (xy 316.07216 -149.230402) (xy 316.02978 -149.188022)
			(xy 315.993293 -149.140472) (xy 315.963326 -149.088566) (xy 315.94039 -149.033193) (xy 315.924877 -148.9753)
			(xy 315.917054 -148.915878) (xy 315.916564 -148.88591) (xy 297.86072 -148.88591) (xy 297.86072 -148.887434)
			(xy 297.86023 -148.917402) (xy 297.852407 -148.976824) (xy 297.836894 -149.034717) (xy 297.813958 -149.09009)
			(xy 297.783991 -149.141996) (xy 297.747504 -149.189546) (xy 297.705124 -149.231926) (xy 297.657574 -149.268413)
			(xy 297.605668 -149.29838) (xy 297.550295 -149.321316) (xy 297.492402 -149.336829) (xy 297.43298 -149.344652)
			(xy 297.373044 -149.344652) (xy 297.313622 -149.336829) (xy 297.255729 -149.321316) (xy 297.200356 -149.29838)
			(xy 297.14845 -149.268413) (xy 297.1009 -149.231926) (xy 297.05852 -149.189546) (xy 297.022033 -149.141996)
			(xy 296.992066 -149.09009) (xy 296.96913 -149.034717) (xy 296.953617 -148.976824) (xy 296.945794 -148.917402)
			(xy 296.945304 -148.887434) (xy 237.624112 -148.887434) (xy 237.624112 -149.691344) (xy 237.623622 -149.721328)
			(xy 237.615794 -149.780784) (xy 237.600273 -149.838709) (xy 237.577324 -149.894113) (xy 237.54734 -149.946047)
			(xy 237.510834 -149.993623) (xy 237.468429 -150.036028) (xy 237.420853 -150.072534) (xy 237.368919 -150.102518)
			(xy 237.313515 -150.125467) (xy 237.25559 -150.140988) (xy 237.196134 -150.148816) (xy 237.136166 -150.148816)
			(xy 237.07671 -150.140988) (xy 237.018785 -150.125467) (xy 236.963381 -150.102518) (xy 236.911447 -150.072534)
			(xy 236.863871 -150.036028) (xy 236.821466 -149.993623) (xy 236.78496 -149.946047) (xy 236.754976 -149.894113)
			(xy 236.732027 -149.838709) (xy 236.716506 -149.780784) (xy 236.708678 -149.721328) (xy 236.708188 -149.691344)
			(xy 198.072386 -149.691344) (xy 198.081715 -149.72616) (xy 198.089538 -149.785582) (xy 198.090028 -149.81555)
			(xy 198.090028 -150.67915) (xy 198.089538 -150.709118) (xy 198.081715 -150.76854) (xy 198.066202 -150.826433)
			(xy 198.043266 -150.881806) (xy 198.013299 -150.933712) (xy 197.976812 -150.981262) (xy 197.934432 -151.023642)
			(xy 197.886882 -151.060129) (xy 197.834976 -151.090096) (xy 197.779603 -151.113032) (xy 197.72171 -151.128545)
			(xy 197.662288 -151.136368) (xy 197.602352 -151.136368) (xy 197.54293 -151.128545) (xy 197.485037 -151.113032)
			(xy 197.429664 -151.090096) (xy 197.377758 -151.060129) (xy 197.330208 -151.023642) (xy 197.287828 -150.981262)
			(xy 197.251341 -150.933712) (xy 197.221374 -150.881806) (xy 197.198438 -150.826433) (xy 197.182925 -150.76854)
			(xy 197.175102 -150.709118) (xy 197.174612 -150.67915) (xy 183.615076 -150.67915) (xy 183.615076 -150.687278)
			(xy 183.614586 -150.717246) (xy 183.606763 -150.776668) (xy 183.59125 -150.834561) (xy 183.568314 -150.889934)
			(xy 183.538347 -150.94184) (xy 183.50186 -150.98939) (xy 183.45948 -151.03177) (xy 183.41193 -151.068257)
			(xy 183.360024 -151.098224) (xy 183.304651 -151.12116) (xy 183.246758 -151.136673) (xy 183.187336 -151.144496)
			(xy 183.1274 -151.144496) (xy 183.067978 -151.136673) (xy 183.010085 -151.12116) (xy 182.954712 -151.098224)
			(xy 182.902806 -151.068257) (xy 182.855256 -151.03177) (xy 182.812876 -150.98939) (xy 182.776389 -150.94184)
			(xy 182.746422 -150.889934) (xy 182.723486 -150.834561) (xy 182.707973 -150.776668) (xy 182.70015 -150.717246)
			(xy 182.69966 -150.687278) (xy 81.990051 -150.687278) (xy 81.989694 -150.709134) (xy 81.981866 -150.76859)
			(xy 81.966345 -150.826515) (xy 81.943396 -150.881919) (xy 81.913412 -150.933853) (xy 81.876906 -150.981429)
			(xy 81.834501 -151.023834) (xy 81.786925 -151.06034) (xy 81.734991 -151.090324) (xy 81.679587 -151.113273)
			(xy 81.621662 -151.128794) (xy 81.562206 -151.136622) (xy 81.502238 -151.136622) (xy 81.442782 -151.128794)
			(xy 81.384857 -151.113273) (xy 81.329453 -151.090324) (xy 81.277519 -151.06034) (xy 81.229943 -151.023834)
			(xy 81.187538 -150.981429) (xy 81.151032 -150.933853) (xy 81.121048 -150.881919) (xy 81.098099 -150.826515)
			(xy 81.082578 -150.76859) (xy 81.07475 -150.709134) (xy 81.07426 -150.67915) (xy 67.515232 -150.67915)
			(xy 67.515232 -150.687278) (xy 67.514742 -150.717262) (xy 67.506914 -150.776718) (xy 67.491393 -150.834643)
			(xy 67.468444 -150.890047) (xy 67.43846 -150.941981) (xy 67.401954 -150.989557) (xy 67.359549 -151.031962)
			(xy 67.311973 -151.068468) (xy 67.260039 -151.098452) (xy 67.204635 -151.121401) (xy 67.14671 -151.136922)
			(xy 67.087254 -151.14475) (xy 67.027286 -151.14475) (xy 66.96783 -151.136922) (xy 66.909905 -151.121401)
			(xy 66.854501 -151.098452) (xy 66.802567 -151.068468) (xy 66.754991 -151.031962) (xy 66.712586 -150.989557)
			(xy 66.67608 -150.941981) (xy 66.646096 -150.890047) (xy 66.623147 -150.834643) (xy 66.607626 -150.776718)
			(xy 66.599798 -150.717262) (xy 66.599308 -150.687278) (xy 4.308094 -150.687278) (xy 4.308094 -152.487376)
			(xy 64.745108 -152.487376) (xy 64.745108 -151.623776) (xy 64.745598 -151.593792) (xy 64.753426 -151.534336)
			(xy 64.768947 -151.476411) (xy 64.791896 -151.421007) (xy 64.82188 -151.369073) (xy 64.858386 -151.321497)
			(xy 64.900791 -151.279092) (xy 64.948367 -151.242586) (xy 65.000301 -151.212602) (xy 65.055705 -151.189653)
			(xy 65.11363 -151.174132) (xy 65.173086 -151.166304) (xy 65.233054 -151.166304) (xy 65.29251 -151.174132)
			(xy 65.350435 -151.189653) (xy 65.405839 -151.212602) (xy 65.457773 -151.242586) (xy 65.505349 -151.279092)
			(xy 65.547754 -151.321497) (xy 65.58426 -151.369073) (xy 65.614244 -151.421007) (xy 65.637193 -151.476411)
			(xy 65.652714 -151.534336) (xy 65.660542 -151.593792) (xy 65.661032 -151.623776) (xy 65.661032 -152.485852)
			(xy 83.716368 -152.485852) (xy 83.716368 -151.622252) (xy 83.716858 -151.592268) (xy 83.724686 -151.532812)
			(xy 83.740207 -151.474887) (xy 83.763156 -151.419483) (xy 83.79314 -151.367549) (xy 83.829646 -151.319973)
			(xy 83.872051 -151.277568) (xy 83.919627 -151.241062) (xy 83.971561 -151.211078) (xy 84.026965 -151.188129)
			(xy 84.08489 -151.172608) (xy 84.144346 -151.16478) (xy 84.204314 -151.16478) (xy 84.26377 -151.172608)
			(xy 84.321695 -151.188129) (xy 84.377099 -151.211078) (xy 84.429033 -151.241062) (xy 84.476609 -151.277568)
			(xy 84.519014 -151.319973) (xy 84.55552 -151.367549) (xy 84.585504 -151.419483) (xy 84.608453 -151.474887)
			(xy 84.623974 -151.532812) (xy 84.631802 -151.592268) (xy 84.632292 -151.622252) (xy 84.632292 -152.485852)
			(xy 84.632267 -152.487376) (xy 180.84546 -152.487376) (xy 180.84546 -151.623776) (xy 180.84595 -151.593808)
			(xy 180.853773 -151.534386) (xy 180.869286 -151.476493) (xy 180.892222 -151.42112) (xy 180.922189 -151.369214)
			(xy 180.958676 -151.321664) (xy 181.001056 -151.279284) (xy 181.048606 -151.242797) (xy 181.100512 -151.21283)
			(xy 181.155885 -151.189894) (xy 181.213778 -151.174381) (xy 181.2732 -151.166558) (xy 181.333136 -151.166558)
			(xy 181.392558 -151.174381) (xy 181.450451 -151.189894) (xy 181.505824 -151.21283) (xy 181.55773 -151.242797)
			(xy 181.60528 -151.279284) (xy 181.64766 -151.321664) (xy 181.684147 -151.369214) (xy 181.714114 -151.42112)
			(xy 181.73705 -151.476493) (xy 181.752563 -151.534386) (xy 181.760386 -151.593808) (xy 181.760876 -151.623776)
			(xy 181.760876 -152.485852) (xy 199.81672 -152.485852) (xy 199.81672 -151.622252) (xy 199.81721 -151.592284)
			(xy 199.825033 -151.532862) (xy 199.840546 -151.474969) (xy 199.863482 -151.419596) (xy 199.893449 -151.36769)
			(xy 199.929936 -151.32014) (xy 199.972316 -151.27776) (xy 200.019866 -151.241273) (xy 200.071772 -151.211306)
			(xy 200.127145 -151.18837) (xy 200.185038 -151.172857) (xy 200.24446 -151.165034) (xy 200.304396 -151.165034)
			(xy 200.363818 -151.172857) (xy 200.421711 -151.18837) (xy 200.477084 -151.211306) (xy 200.52899 -151.241273)
			(xy 200.57654 -151.27776) (xy 200.61892 -151.32014) (xy 200.655407 -151.36769) (xy 200.685374 -151.419596)
			(xy 200.70831 -151.474969) (xy 200.723823 -151.532862) (xy 200.731646 -151.592284) (xy 200.732136 -151.622252)
			(xy 200.732136 -151.914098) (xy 236.712252 -151.914098) (xy 236.712252 -151.050498) (xy 236.712742 -151.020514)
			(xy 236.72057 -150.961058) (xy 236.736091 -150.903133) (xy 236.75904 -150.847729) (xy 236.789024 -150.795795)
			(xy 236.82553 -150.748219) (xy 236.867935 -150.705814) (xy 236.915511 -150.669308) (xy 236.967445 -150.639324)
			(xy 237.022849 -150.616375) (xy 237.080774 -150.600854) (xy 237.14023 -150.593026) (xy 237.200198 -150.593026)
			(xy 237.259654 -150.600854) (xy 237.317579 -150.616375) (xy 237.372983 -150.639324) (xy 237.424917 -150.669308)
			(xy 237.448336 -150.687278) (xy 298.799504 -150.687278) (xy 298.799504 -149.823678) (xy 298.799994 -149.79371)
			(xy 298.807817 -149.734288) (xy 298.82333 -149.676395) (xy 298.846266 -149.621022) (xy 298.876233 -149.569116)
			(xy 298.91272 -149.521566) (xy 298.9551 -149.479186) (xy 299.00265 -149.442699) (xy 299.054556 -149.412732)
			(xy 299.109929 -149.389796) (xy 299.167822 -149.374283) (xy 299.227244 -149.36646) (xy 299.28718 -149.36646)
			(xy 299.346602 -149.374283) (xy 299.404495 -149.389796) (xy 299.459868 -149.412732) (xy 299.511774 -149.442699)
			(xy 299.559324 -149.479186) (xy 299.601704 -149.521566) (xy 299.638191 -149.569116) (xy 299.668158 -149.621022)
			(xy 299.691094 -149.676395) (xy 299.706607 -149.734288) (xy 299.71443 -149.79371) (xy 299.71492 -149.823678)
			(xy 299.71492 -150.67915) (xy 313.274456 -150.67915) (xy 313.274456 -149.81555) (xy 313.274946 -149.785582)
			(xy 313.282769 -149.72616) (xy 313.298282 -149.668267) (xy 313.321218 -149.612894) (xy 313.351185 -149.560988)
			(xy 313.387672 -149.513438) (xy 313.430052 -149.471058) (xy 313.477602 -149.434571) (xy 313.529508 -149.404604)
			(xy 313.584881 -149.381668) (xy 313.642774 -149.366155) (xy 313.702196 -149.358332) (xy 313.762132 -149.358332)
			(xy 313.821554 -149.366155) (xy 313.879447 -149.381668) (xy 313.93482 -149.404604) (xy 313.986726 -149.434571)
			(xy 314.034276 -149.471058) (xy 314.076656 -149.513438) (xy 314.113143 -149.560988) (xy 314.14311 -149.612894)
			(xy 314.166046 -149.668267) (xy 314.181559 -149.72616) (xy 314.189382 -149.785582) (xy 314.189872 -149.81555)
			(xy 314.189872 -150.67915) (xy 314.189739 -150.687278) (xy 414.899348 -150.687278) (xy 414.899348 -149.823678)
			(xy 414.899838 -149.793694) (xy 414.907666 -149.734238) (xy 414.923187 -149.676313) (xy 414.946136 -149.620909)
			(xy 414.97612 -149.568975) (xy 415.012626 -149.521399) (xy 415.055031 -149.478994) (xy 415.102607 -149.442488)
			(xy 415.154541 -149.412504) (xy 415.209945 -149.389555) (xy 415.26787 -149.374034) (xy 415.327326 -149.366206)
			(xy 415.387294 -149.366206) (xy 415.44675 -149.374034) (xy 415.504675 -149.389555) (xy 415.560079 -149.412504)
			(xy 415.612013 -149.442488) (xy 415.659589 -149.478994) (xy 415.701994 -149.521399) (xy 415.7385 -149.568975)
			(xy 415.768484 -149.620909) (xy 415.791433 -149.676313) (xy 415.806954 -149.734238) (xy 415.814782 -149.793694)
			(xy 415.815272 -149.823678) (xy 415.815272 -150.67915) (xy 429.3743 -150.67915) (xy 429.3743 -149.81555)
			(xy 429.37479 -149.785566) (xy 429.382618 -149.72611) (xy 429.398139 -149.668185) (xy 429.421088 -149.612781)
			(xy 429.451072 -149.560847) (xy 429.487578 -149.513271) (xy 429.529983 -149.470866) (xy 429.577559 -149.43436)
			(xy 429.629493 -149.404376) (xy 429.684897 -149.381427) (xy 429.742822 -149.365906) (xy 429.802278 -149.358078)
			(xy 429.862246 -149.358078) (xy 429.921702 -149.365906) (xy 429.979627 -149.381427) (xy 430.035031 -149.404376)
			(xy 430.086965 -149.43436) (xy 430.134541 -149.470866) (xy 430.176946 -149.513271) (xy 430.213452 -149.560847)
			(xy 430.243436 -149.612781) (xy 430.266385 -149.668185) (xy 430.281906 -149.72611) (xy 430.289734 -149.785566)
			(xy 430.290224 -149.81555) (xy 430.290224 -150.67915) (xy 430.289734 -150.709134) (xy 430.281906 -150.76859)
			(xy 430.266385 -150.826515) (xy 430.243436 -150.881919) (xy 430.213452 -150.933853) (xy 430.176946 -150.981429)
			(xy 430.134541 -151.023834) (xy 430.086965 -151.06034) (xy 430.035031 -151.090324) (xy 429.979627 -151.113273)
			(xy 429.921702 -151.128794) (xy 429.862246 -151.136622) (xy 429.802278 -151.136622) (xy 429.742822 -151.128794)
			(xy 429.684897 -151.113273) (xy 429.629493 -151.090324) (xy 429.577559 -151.06034) (xy 429.529983 -151.023834)
			(xy 429.487578 -150.981429) (xy 429.451072 -150.933853) (xy 429.421088 -150.881919) (xy 429.398139 -150.826515)
			(xy 429.382618 -150.76859) (xy 429.37479 -150.709134) (xy 429.3743 -150.67915) (xy 415.815272 -150.67915)
			(xy 415.815272 -150.687278) (xy 415.814782 -150.717262) (xy 415.806954 -150.776718) (xy 415.791433 -150.834643)
			(xy 415.768484 -150.890047) (xy 415.7385 -150.941981) (xy 415.701994 -150.989557) (xy 415.659589 -151.031962)
			(xy 415.612013 -151.068468) (xy 415.560079 -151.098452) (xy 415.504675 -151.121401) (xy 415.44675 -151.136922)
			(xy 415.387294 -151.14475) (xy 415.327326 -151.14475) (xy 415.26787 -151.136922) (xy 415.209945 -151.121401)
			(xy 415.154541 -151.098452) (xy 415.102607 -151.068468) (xy 415.055031 -151.031962) (xy 415.012626 -150.989557)
			(xy 414.97612 -150.941981) (xy 414.946136 -150.890047) (xy 414.923187 -150.834643) (xy 414.907666 -150.776718)
			(xy 414.899838 -150.717262) (xy 414.899348 -150.687278) (xy 314.189739 -150.687278) (xy 314.189382 -150.709118)
			(xy 314.181559 -150.76854) (xy 314.166046 -150.826433) (xy 314.14311 -150.881806) (xy 314.113143 -150.933712)
			(xy 314.076656 -150.981262) (xy 314.034276 -151.023642) (xy 313.986726 -151.060129) (xy 313.93482 -151.090096)
			(xy 313.879447 -151.113032) (xy 313.821554 -151.128545) (xy 313.762132 -151.136368) (xy 313.702196 -151.136368)
			(xy 313.642774 -151.128545) (xy 313.584881 -151.113032) (xy 313.529508 -151.090096) (xy 313.477602 -151.060129)
			(xy 313.430052 -151.023642) (xy 313.387672 -150.981262) (xy 313.351185 -150.933712) (xy 313.321218 -150.881806)
			(xy 313.298282 -150.826433) (xy 313.282769 -150.76854) (xy 313.274946 -150.709118) (xy 313.274456 -150.67915)
			(xy 299.71492 -150.67915) (xy 299.71492 -150.687278) (xy 299.71443 -150.717246) (xy 299.706607 -150.776668)
			(xy 299.691094 -150.834561) (xy 299.668158 -150.889934) (xy 299.638191 -150.94184) (xy 299.601704 -150.98939)
			(xy 299.559324 -151.03177) (xy 299.511774 -151.068257) (xy 299.459868 -151.098224) (xy 299.404495 -151.12116)
			(xy 299.346602 -151.136673) (xy 299.28718 -151.144496) (xy 299.227244 -151.144496) (xy 299.167822 -151.136673)
			(xy 299.109929 -151.12116) (xy 299.054556 -151.098224) (xy 299.00265 -151.068257) (xy 298.9551 -151.03177)
			(xy 298.91272 -150.98939) (xy 298.876233 -150.94184) (xy 298.846266 -150.889934) (xy 298.82333 -150.834561)
			(xy 298.807817 -150.776668) (xy 298.799994 -150.717246) (xy 298.799504 -150.687278) (xy 237.448336 -150.687278)
			(xy 237.472493 -150.705814) (xy 237.514898 -150.748219) (xy 237.551404 -150.795795) (xy 237.581388 -150.847729)
			(xy 237.604337 -150.903133) (xy 237.619858 -150.961058) (xy 237.627686 -151.020514) (xy 237.628176 -151.050498)
			(xy 237.628176 -151.914098) (xy 237.627686 -151.944082) (xy 237.619858 -152.003538) (xy 237.604337 -152.061463)
			(xy 237.581388 -152.116867) (xy 237.551404 -152.168801) (xy 237.514898 -152.216377) (xy 237.472493 -152.258782)
			(xy 237.424917 -152.295288) (xy 237.372983 -152.325272) (xy 237.317579 -152.348221) (xy 237.259654 -152.363742)
			(xy 237.200198 -152.37157) (xy 237.14023 -152.37157) (xy 237.080774 -152.363742) (xy 237.022849 -152.348221)
			(xy 236.967445 -152.325272) (xy 236.915511 -152.295288) (xy 236.867935 -152.258782) (xy 236.82553 -152.216377)
			(xy 236.789024 -152.168801) (xy 236.75904 -152.116867) (xy 236.736091 -152.061463) (xy 236.72057 -152.003538)
			(xy 236.712742 -151.944082) (xy 236.712252 -151.914098) (xy 200.732136 -151.914098) (xy 200.732136 -152.485852)
			(xy 200.732111 -152.487376) (xy 296.945304 -152.487376) (xy 296.945304 -151.623776) (xy 296.945794 -151.593808)
			(xy 296.953617 -151.534386) (xy 296.96913 -151.476493) (xy 296.992066 -151.42112) (xy 297.022033 -151.369214)
			(xy 297.05852 -151.321664) (xy 297.1009 -151.279284) (xy 297.14845 -151.242797) (xy 297.200356 -151.21283)
			(xy 297.255729 -151.189894) (xy 297.313622 -151.174381) (xy 297.373044 -151.166558) (xy 297.43298 -151.166558)
			(xy 297.492402 -151.174381) (xy 297.550295 -151.189894) (xy 297.605668 -151.21283) (xy 297.657574 -151.242797)
			(xy 297.705124 -151.279284) (xy 297.747504 -151.321664) (xy 297.783991 -151.369214) (xy 297.813958 -151.42112)
			(xy 297.836894 -151.476493) (xy 297.852407 -151.534386) (xy 297.86023 -151.593808) (xy 297.86072 -151.623776)
			(xy 297.86072 -152.485852) (xy 315.916564 -152.485852) (xy 315.916564 -151.622252) (xy 315.917054 -151.592284)
			(xy 315.924877 -151.532862) (xy 315.94039 -151.474969) (xy 315.963326 -151.419596) (xy 315.993293 -151.36769)
			(xy 316.02978 -151.32014) (xy 316.07216 -151.27776) (xy 316.11971 -151.241273) (xy 316.171616 -151.211306)
			(xy 316.226989 -151.18837) (xy 316.284882 -151.172857) (xy 316.344304 -151.165034) (xy 316.40424 -151.165034)
			(xy 316.463662 -151.172857) (xy 316.521555 -151.18837) (xy 316.576928 -151.211306) (xy 316.628834 -151.241273)
			(xy 316.676384 -151.27776) (xy 316.718764 -151.32014) (xy 316.755251 -151.36769) (xy 316.785218 -151.419596)
			(xy 316.808154 -151.474969) (xy 316.823667 -151.532862) (xy 316.83149 -151.592284) (xy 316.83198 -151.622252)
			(xy 316.83198 -152.485852) (xy 316.831955 -152.487376) (xy 413.045148 -152.487376) (xy 413.045148 -151.623776)
			(xy 413.045638 -151.593792) (xy 413.053466 -151.534336) (xy 413.068987 -151.476411) (xy 413.091936 -151.421007)
			(xy 413.12192 -151.369073) (xy 413.158426 -151.321497) (xy 413.200831 -151.279092) (xy 413.248407 -151.242586)
			(xy 413.300341 -151.212602) (xy 413.355745 -151.189653) (xy 413.41367 -151.174132) (xy 413.473126 -151.166304)
			(xy 413.533094 -151.166304) (xy 413.59255 -151.174132) (xy 413.650475 -151.189653) (xy 413.705879 -151.212602)
			(xy 413.757813 -151.242586) (xy 413.805389 -151.279092) (xy 413.847794 -151.321497) (xy 413.8843 -151.369073)
			(xy 413.914284 -151.421007) (xy 413.937233 -151.476411) (xy 413.952754 -151.534336) (xy 413.960582 -151.593792)
			(xy 413.961072 -151.623776) (xy 413.961072 -152.485852) (xy 432.016408 -152.485852) (xy 432.016408 -151.622252)
			(xy 432.016898 -151.592268) (xy 432.024726 -151.532812) (xy 432.040247 -151.474887) (xy 432.063196 -151.419483)
			(xy 432.09318 -151.367549) (xy 432.129686 -151.319973) (xy 432.172091 -151.277568) (xy 432.219667 -151.241062)
			(xy 432.271601 -151.211078) (xy 432.327005 -151.188129) (xy 432.38493 -151.172608) (xy 432.444386 -151.16478)
			(xy 432.504354 -151.16478) (xy 432.56381 -151.172608) (xy 432.621735 -151.188129) (xy 432.677139 -151.211078)
			(xy 432.729073 -151.241062) (xy 432.776649 -151.277568) (xy 432.819054 -151.319973) (xy 432.85556 -151.367549)
			(xy 432.885544 -151.419483) (xy 432.908493 -151.474887) (xy 432.924014 -151.532812) (xy 432.931842 -151.592268)
			(xy 432.932332 -151.622252) (xy 432.932332 -152.485852) (xy 432.931842 -152.515836) (xy 432.924014 -152.575292)
			(xy 432.908493 -152.633217) (xy 432.885544 -152.688621) (xy 432.85556 -152.740555) (xy 432.819054 -152.788131)
			(xy 432.776649 -152.830536) (xy 432.729073 -152.867042) (xy 432.677139 -152.897026) (xy 432.621735 -152.919975)
			(xy 432.56381 -152.935496) (xy 432.504354 -152.943324) (xy 432.444386 -152.943324) (xy 432.38493 -152.935496)
			(xy 432.327005 -152.919975) (xy 432.271601 -152.897026) (xy 432.219667 -152.867042) (xy 432.172091 -152.830536)
			(xy 432.129686 -152.788131) (xy 432.09318 -152.740555) (xy 432.063196 -152.688621) (xy 432.040247 -152.633217)
			(xy 432.024726 -152.575292) (xy 432.016898 -152.515836) (xy 432.016408 -152.485852) (xy 413.961072 -152.485852)
			(xy 413.961072 -152.487376) (xy 413.960582 -152.51736) (xy 413.952754 -152.576816) (xy 413.937233 -152.634741)
			(xy 413.914284 -152.690145) (xy 413.8843 -152.742079) (xy 413.847794 -152.789655) (xy 413.805389 -152.83206)
			(xy 413.757813 -152.868566) (xy 413.705879 -152.89855) (xy 413.650475 -152.921499) (xy 413.59255 -152.93702)
			(xy 413.533094 -152.944848) (xy 413.473126 -152.944848) (xy 413.41367 -152.93702) (xy 413.355745 -152.921499)
			(xy 413.300341 -152.89855) (xy 413.248407 -152.868566) (xy 413.200831 -152.83206) (xy 413.158426 -152.789655)
			(xy 413.12192 -152.742079) (xy 413.091936 -152.690145) (xy 413.068987 -152.634741) (xy 413.053466 -152.576816)
			(xy 413.045638 -152.51736) (xy 413.045148 -152.487376) (xy 316.831955 -152.487376) (xy 316.83149 -152.51582)
			(xy 316.823667 -152.575242) (xy 316.808154 -152.633135) (xy 316.785218 -152.688508) (xy 316.755251 -152.740414)
			(xy 316.718764 -152.787964) (xy 316.676384 -152.830344) (xy 316.628834 -152.866831) (xy 316.576928 -152.896798)
			(xy 316.521555 -152.919734) (xy 316.463662 -152.935247) (xy 316.40424 -152.94307) (xy 316.344304 -152.94307)
			(xy 316.284882 -152.935247) (xy 316.226989 -152.919734) (xy 316.171616 -152.896798) (xy 316.11971 -152.866831)
			(xy 316.07216 -152.830344) (xy 316.02978 -152.787964) (xy 315.993293 -152.740414) (xy 315.963326 -152.688508)
			(xy 315.94039 -152.633135) (xy 315.924877 -152.575242) (xy 315.917054 -152.51582) (xy 315.916564 -152.485852)
			(xy 297.86072 -152.485852) (xy 297.86072 -152.487376) (xy 297.86023 -152.517344) (xy 297.852407 -152.576766)
			(xy 297.836894 -152.634659) (xy 297.813958 -152.690032) (xy 297.783991 -152.741938) (xy 297.747504 -152.789488)
			(xy 297.705124 -152.831868) (xy 297.657574 -152.868355) (xy 297.605668 -152.898322) (xy 297.550295 -152.921258)
			(xy 297.492402 -152.936771) (xy 297.43298 -152.944594) (xy 297.373044 -152.944594) (xy 297.313622 -152.936771)
			(xy 297.255729 -152.921258) (xy 297.200356 -152.898322) (xy 297.14845 -152.868355) (xy 297.1009 -152.831868)
			(xy 297.05852 -152.789488) (xy 297.022033 -152.741938) (xy 296.992066 -152.690032) (xy 296.96913 -152.634659)
			(xy 296.953617 -152.576766) (xy 296.945794 -152.517344) (xy 296.945304 -152.487376) (xy 200.732111 -152.487376)
			(xy 200.731646 -152.51582) (xy 200.723823 -152.575242) (xy 200.70831 -152.633135) (xy 200.685374 -152.688508)
			(xy 200.655407 -152.740414) (xy 200.61892 -152.787964) (xy 200.57654 -152.830344) (xy 200.52899 -152.866831)
			(xy 200.477084 -152.896798) (xy 200.421711 -152.919734) (xy 200.363818 -152.935247) (xy 200.304396 -152.94307)
			(xy 200.24446 -152.94307) (xy 200.185038 -152.935247) (xy 200.127145 -152.919734) (xy 200.071772 -152.896798)
			(xy 200.019866 -152.866831) (xy 199.972316 -152.830344) (xy 199.929936 -152.787964) (xy 199.893449 -152.740414)
			(xy 199.863482 -152.688508) (xy 199.840546 -152.633135) (xy 199.825033 -152.575242) (xy 199.81721 -152.51582)
			(xy 199.81672 -152.485852) (xy 181.760876 -152.485852) (xy 181.760876 -152.487376) (xy 181.760386 -152.517344)
			(xy 181.752563 -152.576766) (xy 181.73705 -152.634659) (xy 181.714114 -152.690032) (xy 181.684147 -152.741938)
			(xy 181.64766 -152.789488) (xy 181.60528 -152.831868) (xy 181.55773 -152.868355) (xy 181.505824 -152.898322)
			(xy 181.450451 -152.921258) (xy 181.392558 -152.936771) (xy 181.333136 -152.944594) (xy 181.2732 -152.944594)
			(xy 181.213778 -152.936771) (xy 181.155885 -152.921258) (xy 181.100512 -152.898322) (xy 181.048606 -152.868355)
			(xy 181.001056 -152.831868) (xy 180.958676 -152.789488) (xy 180.922189 -152.741938) (xy 180.892222 -152.690032)
			(xy 180.869286 -152.634659) (xy 180.853773 -152.576766) (xy 180.84595 -152.517344) (xy 180.84546 -152.487376)
			(xy 84.632267 -152.487376) (xy 84.631802 -152.515836) (xy 84.623974 -152.575292) (xy 84.608453 -152.633217)
			(xy 84.585504 -152.688621) (xy 84.55552 -152.740555) (xy 84.519014 -152.788131) (xy 84.476609 -152.830536)
			(xy 84.429033 -152.867042) (xy 84.377099 -152.897026) (xy 84.321695 -152.919975) (xy 84.26377 -152.935496)
			(xy 84.204314 -152.943324) (xy 84.144346 -152.943324) (xy 84.08489 -152.935496) (xy 84.026965 -152.919975)
			(xy 83.971561 -152.897026) (xy 83.919627 -152.867042) (xy 83.872051 -152.830536) (xy 83.829646 -152.788131)
			(xy 83.79314 -152.740555) (xy 83.763156 -152.688621) (xy 83.740207 -152.633217) (xy 83.724686 -152.575292)
			(xy 83.716858 -152.515836) (xy 83.716368 -152.485852) (xy 65.661032 -152.485852) (xy 65.661032 -152.487376)
			(xy 65.660542 -152.51736) (xy 65.652714 -152.576816) (xy 65.637193 -152.634741) (xy 65.614244 -152.690145)
			(xy 65.58426 -152.742079) (xy 65.547754 -152.789655) (xy 65.505349 -152.83206) (xy 65.457773 -152.868566)
			(xy 65.405839 -152.89855) (xy 65.350435 -152.921499) (xy 65.29251 -152.93702) (xy 65.233054 -152.944848)
			(xy 65.173086 -152.944848) (xy 65.11363 -152.93702) (xy 65.055705 -152.921499) (xy 65.000301 -152.89855)
			(xy 64.948367 -152.868566) (xy 64.900791 -152.83206) (xy 64.858386 -152.789655) (xy 64.82188 -152.742079)
			(xy 64.791896 -152.690145) (xy 64.768947 -152.634741) (xy 64.753426 -152.576816) (xy 64.745598 -152.51736)
			(xy 64.745108 -152.487376) (xy 4.308094 -152.487376) (xy 4.308094 -154.28722) (xy 66.599308 -154.28722)
			(xy 66.599308 -153.42362) (xy 66.599798 -153.393636) (xy 66.607626 -153.33418) (xy 66.623147 -153.276255)
			(xy 66.646096 -153.220851) (xy 66.67608 -153.168917) (xy 66.712586 -153.121341) (xy 66.754991 -153.078936)
			(xy 66.802567 -153.04243) (xy 66.854501 -153.012446) (xy 66.909905 -152.989497) (xy 66.96783 -152.973976)
			(xy 67.027286 -152.966148) (xy 67.087254 -152.966148) (xy 67.14671 -152.973976) (xy 67.204635 -152.989497)
			(xy 67.260039 -153.012446) (xy 67.311973 -153.04243) (xy 67.359549 -153.078936) (xy 67.401954 -153.121341)
			(xy 67.43846 -153.168917) (xy 67.468444 -153.220851) (xy 67.491393 -153.276255) (xy 67.506914 -153.33418)
			(xy 67.514742 -153.393636) (xy 67.515232 -153.42362) (xy 67.515232 -154.279346) (xy 81.07426 -154.279346)
			(xy 81.07426 -153.415746) (xy 81.07475 -153.385762) (xy 81.082578 -153.326306) (xy 81.098099 -153.268381)
			(xy 81.121048 -153.212977) (xy 81.151032 -153.161043) (xy 81.187538 -153.113467) (xy 81.229943 -153.071062)
			(xy 81.277519 -153.034556) (xy 81.329453 -153.004572) (xy 81.384857 -152.981623) (xy 81.442782 -152.966102)
			(xy 81.502238 -152.958274) (xy 81.562206 -152.958274) (xy 81.621662 -152.966102) (xy 81.679587 -152.981623)
			(xy 81.734991 -153.004572) (xy 81.786925 -153.034556) (xy 81.834501 -153.071062) (xy 81.876906 -153.113467)
			(xy 81.913412 -153.161043) (xy 81.943396 -153.212977) (xy 81.966345 -153.268381) (xy 81.981866 -153.326306)
			(xy 81.989694 -153.385762) (xy 81.990184 -153.415746) (xy 81.990184 -154.279346) (xy 81.990055 -154.28722)
			(xy 182.69966 -154.28722) (xy 182.69966 -153.42362) (xy 182.70015 -153.393652) (xy 182.707973 -153.33423)
			(xy 182.723486 -153.276337) (xy 182.746422 -153.220964) (xy 182.776389 -153.169058) (xy 182.812876 -153.121508)
			(xy 182.855256 -153.079128) (xy 182.902806 -153.042641) (xy 182.954712 -153.012674) (xy 183.010085 -152.989738)
			(xy 183.067978 -152.974225) (xy 183.1274 -152.966402) (xy 183.187336 -152.966402) (xy 183.246758 -152.974225)
			(xy 183.304651 -152.989738) (xy 183.360024 -153.012674) (xy 183.41193 -153.042641) (xy 183.45948 -153.079128)
			(xy 183.50186 -153.121508) (xy 183.538347 -153.169058) (xy 183.568314 -153.220964) (xy 183.59125 -153.276337)
			(xy 183.606763 -153.33423) (xy 183.614586 -153.393652) (xy 183.615076 -153.42362) (xy 183.615076 -154.279346)
			(xy 197.174612 -154.279346) (xy 197.174612 -153.415746) (xy 197.175102 -153.385778) (xy 197.182925 -153.326356)
			(xy 197.198438 -153.268463) (xy 197.221374 -153.21309) (xy 197.251341 -153.161184) (xy 197.287828 -153.113634)
			(xy 197.330208 -153.071254) (xy 197.377758 -153.034767) (xy 197.429664 -153.0048) (xy 197.485037 -152.981864)
			(xy 197.54293 -152.966351) (xy 197.602352 -152.958528) (xy 197.662288 -152.958528) (xy 197.72171 -152.966351)
			(xy 197.779603 -152.981864) (xy 197.834976 -153.0048) (xy 197.886882 -153.034767) (xy 197.934432 -153.071254)
			(xy 197.976812 -153.113634) (xy 198.013299 -153.161184) (xy 198.043266 -153.21309) (xy 198.066202 -153.268463)
			(xy 198.081715 -153.326356) (xy 198.089538 -153.385778) (xy 198.090028 -153.415746) (xy 198.090028 -154.279346)
			(xy 198.089899 -154.28722) (xy 298.799504 -154.28722) (xy 298.799504 -153.42362) (xy 298.799994 -153.393652)
			(xy 298.807817 -153.33423) (xy 298.82333 -153.276337) (xy 298.846266 -153.220964) (xy 298.876233 -153.169058)
			(xy 298.91272 -153.121508) (xy 298.9551 -153.079128) (xy 299.00265 -153.042641) (xy 299.054556 -153.012674)
			(xy 299.109929 -152.989738) (xy 299.167822 -152.974225) (xy 299.227244 -152.966402) (xy 299.28718 -152.966402)
			(xy 299.346602 -152.974225) (xy 299.404495 -152.989738) (xy 299.459868 -153.012674) (xy 299.511774 -153.042641)
			(xy 299.559324 -153.079128) (xy 299.601704 -153.121508) (xy 299.638191 -153.169058) (xy 299.668158 -153.220964)
			(xy 299.691094 -153.276337) (xy 299.706607 -153.33423) (xy 299.71443 -153.393652) (xy 299.71492 -153.42362)
			(xy 299.71492 -154.279346) (xy 313.274456 -154.279346) (xy 313.274456 -153.415746) (xy 313.274946 -153.385778)
			(xy 313.282769 -153.326356) (xy 313.298282 -153.268463) (xy 313.321218 -153.21309) (xy 313.351185 -153.161184)
			(xy 313.387672 -153.113634) (xy 313.430052 -153.071254) (xy 313.477602 -153.034767) (xy 313.529508 -153.0048)
			(xy 313.584881 -152.981864) (xy 313.642774 -152.966351) (xy 313.702196 -152.958528) (xy 313.762132 -152.958528)
			(xy 313.821554 -152.966351) (xy 313.879447 -152.981864) (xy 313.93482 -153.0048) (xy 313.986726 -153.034767)
			(xy 314.034276 -153.071254) (xy 314.076656 -153.113634) (xy 314.113143 -153.161184) (xy 314.14311 -153.21309)
			(xy 314.166046 -153.268463) (xy 314.181559 -153.326356) (xy 314.189382 -153.385778) (xy 314.189872 -153.415746)
			(xy 314.189872 -154.279346) (xy 314.189743 -154.28722) (xy 414.899348 -154.28722) (xy 414.899348 -153.42362)
			(xy 414.899838 -153.393636) (xy 414.907666 -153.33418) (xy 414.923187 -153.276255) (xy 414.946136 -153.220851)
			(xy 414.97612 -153.168917) (xy 415.012626 -153.121341) (xy 415.055031 -153.078936) (xy 415.102607 -153.04243)
			(xy 415.154541 -153.012446) (xy 415.209945 -152.989497) (xy 415.26787 -152.973976) (xy 415.327326 -152.966148)
			(xy 415.387294 -152.966148) (xy 415.44675 -152.973976) (xy 415.504675 -152.989497) (xy 415.560079 -153.012446)
			(xy 415.612013 -153.04243) (xy 415.659589 -153.078936) (xy 415.701994 -153.121341) (xy 415.7385 -153.168917)
			(xy 415.768484 -153.220851) (xy 415.791433 -153.276255) (xy 415.806954 -153.33418) (xy 415.814782 -153.393636)
			(xy 415.815272 -153.42362) (xy 415.815272 -154.279346) (xy 429.3743 -154.279346) (xy 429.3743 -153.415746)
			(xy 429.37479 -153.385762) (xy 429.382618 -153.326306) (xy 429.398139 -153.268381) (xy 429.421088 -153.212977)
			(xy 429.451072 -153.161043) (xy 429.487578 -153.113467) (xy 429.529983 -153.071062) (xy 429.577559 -153.034556)
			(xy 429.629493 -153.004572) (xy 429.684897 -152.981623) (xy 429.742822 -152.966102) (xy 429.802278 -152.958274)
			(xy 429.862246 -152.958274) (xy 429.921702 -152.966102) (xy 429.979627 -152.981623) (xy 430.035031 -153.004572)
			(xy 430.086965 -153.034556) (xy 430.134541 -153.071062) (xy 430.176946 -153.113467) (xy 430.213452 -153.161043)
			(xy 430.243436 -153.212977) (xy 430.266385 -153.268381) (xy 430.281906 -153.326306) (xy 430.289734 -153.385762)
			(xy 430.290224 -153.415746) (xy 430.290224 -154.279346) (xy 430.289734 -154.30933) (xy 430.281906 -154.368786)
			(xy 430.266385 -154.426711) (xy 430.243436 -154.482115) (xy 430.213452 -154.534049) (xy 430.176946 -154.581625)
			(xy 430.134541 -154.62403) (xy 430.086965 -154.660536) (xy 430.035031 -154.69052) (xy 429.979627 -154.713469)
			(xy 429.921702 -154.72899) (xy 429.862246 -154.736818) (xy 429.802278 -154.736818) (xy 429.742822 -154.72899)
			(xy 429.684897 -154.713469) (xy 429.629493 -154.69052) (xy 429.577559 -154.660536) (xy 429.529983 -154.62403)
			(xy 429.487578 -154.581625) (xy 429.451072 -154.534049) (xy 429.421088 -154.482115) (xy 429.398139 -154.426711)
			(xy 429.382618 -154.368786) (xy 429.37479 -154.30933) (xy 429.3743 -154.279346) (xy 415.815272 -154.279346)
			(xy 415.815272 -154.28722) (xy 415.814782 -154.317204) (xy 415.806954 -154.37666) (xy 415.791433 -154.434585)
			(xy 415.768484 -154.489989) (xy 415.7385 -154.541923) (xy 415.701994 -154.589499) (xy 415.659589 -154.631904)
			(xy 415.612013 -154.66841) (xy 415.560079 -154.698394) (xy 415.504675 -154.721343) (xy 415.44675 -154.736864)
			(xy 415.387294 -154.744692) (xy 415.327326 -154.744692) (xy 415.26787 -154.736864) (xy 415.209945 -154.721343)
			(xy 415.154541 -154.698394) (xy 415.102607 -154.66841) (xy 415.055031 -154.631904) (xy 415.012626 -154.589499)
			(xy 414.97612 -154.541923) (xy 414.946136 -154.489989) (xy 414.923187 -154.434585) (xy 414.907666 -154.37666)
			(xy 414.899838 -154.317204) (xy 414.899348 -154.28722) (xy 314.189743 -154.28722) (xy 314.189382 -154.309314)
			(xy 314.181559 -154.368736) (xy 314.166046 -154.426629) (xy 314.14311 -154.482002) (xy 314.113143 -154.533908)
			(xy 314.076656 -154.581458) (xy 314.034276 -154.623838) (xy 313.986726 -154.660325) (xy 313.93482 -154.690292)
			(xy 313.879447 -154.713228) (xy 313.821554 -154.728741) (xy 313.762132 -154.736564) (xy 313.702196 -154.736564)
			(xy 313.642774 -154.728741) (xy 313.584881 -154.713228) (xy 313.529508 -154.690292) (xy 313.477602 -154.660325)
			(xy 313.430052 -154.623838) (xy 313.387672 -154.581458) (xy 313.351185 -154.533908) (xy 313.321218 -154.482002)
			(xy 313.298282 -154.426629) (xy 313.282769 -154.368736) (xy 313.274946 -154.309314) (xy 313.274456 -154.279346)
			(xy 299.71492 -154.279346) (xy 299.71492 -154.28722) (xy 299.71443 -154.317188) (xy 299.706607 -154.37661)
			(xy 299.691094 -154.434503) (xy 299.668158 -154.489876) (xy 299.638191 -154.541782) (xy 299.601704 -154.589332)
			(xy 299.559324 -154.631712) (xy 299.511774 -154.668199) (xy 299.459868 -154.698166) (xy 299.404495 -154.721102)
			(xy 299.346602 -154.736615) (xy 299.28718 -154.744438) (xy 299.227244 -154.744438) (xy 299.167822 -154.736615)
			(xy 299.109929 -154.721102) (xy 299.054556 -154.698166) (xy 299.00265 -154.668199) (xy 298.9551 -154.631712)
			(xy 298.91272 -154.589332) (xy 298.876233 -154.541782) (xy 298.846266 -154.489876) (xy 298.82333 -154.434503)
			(xy 298.807817 -154.37661) (xy 298.799994 -154.317188) (xy 298.799504 -154.28722) (xy 198.089899 -154.28722)
			(xy 198.089538 -154.309314) (xy 198.081715 -154.368736) (xy 198.066202 -154.426629) (xy 198.043266 -154.482002)
			(xy 198.013299 -154.533908) (xy 197.976812 -154.581458) (xy 197.934432 -154.623838) (xy 197.886882 -154.660325)
			(xy 197.834976 -154.690292) (xy 197.779603 -154.713228) (xy 197.72171 -154.728741) (xy 197.662288 -154.736564)
			(xy 197.602352 -154.736564) (xy 197.54293 -154.728741) (xy 197.485037 -154.713228) (xy 197.429664 -154.690292)
			(xy 197.377758 -154.660325) (xy 197.330208 -154.623838) (xy 197.287828 -154.581458) (xy 197.251341 -154.533908)
			(xy 197.221374 -154.482002) (xy 197.198438 -154.426629) (xy 197.182925 -154.368736) (xy 197.175102 -154.309314)
			(xy 197.174612 -154.279346) (xy 183.615076 -154.279346) (xy 183.615076 -154.28722) (xy 183.614586 -154.317188)
			(xy 183.606763 -154.37661) (xy 183.59125 -154.434503) (xy 183.568314 -154.489876) (xy 183.538347 -154.541782)
			(xy 183.50186 -154.589332) (xy 183.45948 -154.631712) (xy 183.41193 -154.668199) (xy 183.360024 -154.698166)
			(xy 183.304651 -154.721102) (xy 183.246758 -154.736615) (xy 183.187336 -154.744438) (xy 183.1274 -154.744438)
			(xy 183.067978 -154.736615) (xy 183.010085 -154.721102) (xy 182.954712 -154.698166) (xy 182.902806 -154.668199)
			(xy 182.855256 -154.631712) (xy 182.812876 -154.589332) (xy 182.776389 -154.541782) (xy 182.746422 -154.489876)
			(xy 182.723486 -154.434503) (xy 182.707973 -154.37661) (xy 182.70015 -154.317188) (xy 182.69966 -154.28722)
			(xy 81.990055 -154.28722) (xy 81.989694 -154.30933) (xy 81.981866 -154.368786) (xy 81.966345 -154.426711)
			(xy 81.943396 -154.482115) (xy 81.913412 -154.534049) (xy 81.876906 -154.581625) (xy 81.834501 -154.62403)
			(xy 81.786925 -154.660536) (xy 81.734991 -154.69052) (xy 81.679587 -154.713469) (xy 81.621662 -154.72899)
			(xy 81.562206 -154.736818) (xy 81.502238 -154.736818) (xy 81.442782 -154.72899) (xy 81.384857 -154.713469)
			(xy 81.329453 -154.69052) (xy 81.277519 -154.660536) (xy 81.229943 -154.62403) (xy 81.187538 -154.581625)
			(xy 81.151032 -154.534049) (xy 81.121048 -154.482115) (xy 81.098099 -154.426711) (xy 81.082578 -154.368786)
			(xy 81.07475 -154.30933) (xy 81.07426 -154.279346) (xy 67.515232 -154.279346) (xy 67.515232 -154.28722)
			(xy 67.514742 -154.317204) (xy 67.506914 -154.37666) (xy 67.491393 -154.434585) (xy 67.468444 -154.489989)
			(xy 67.43846 -154.541923) (xy 67.401954 -154.589499) (xy 67.359549 -154.631904) (xy 67.311973 -154.66841)
			(xy 67.260039 -154.698394) (xy 67.204635 -154.721343) (xy 67.14671 -154.736864) (xy 67.087254 -154.744692)
			(xy 67.027286 -154.744692) (xy 66.96783 -154.736864) (xy 66.909905 -154.721343) (xy 66.854501 -154.698394)
			(xy 66.802567 -154.66841) (xy 66.754991 -154.631904) (xy 66.712586 -154.589499) (xy 66.67608 -154.541923)
			(xy 66.646096 -154.489989) (xy 66.623147 -154.434585) (xy 66.607626 -154.37666) (xy 66.599798 -154.317204)
			(xy 66.599308 -154.28722) (xy 4.308094 -154.28722) (xy 4.308094 -156.087318) (xy 64.745108 -156.087318)
			(xy 64.745108 -155.223718) (xy 64.745598 -155.193734) (xy 64.753426 -155.134278) (xy 64.768947 -155.076353)
			(xy 64.791896 -155.020949) (xy 64.82188 -154.969015) (xy 64.858386 -154.921439) (xy 64.900791 -154.879034)
			(xy 64.948367 -154.842528) (xy 65.000301 -154.812544) (xy 65.055705 -154.789595) (xy 65.11363 -154.774074)
			(xy 65.173086 -154.766246) (xy 65.233054 -154.766246) (xy 65.29251 -154.774074) (xy 65.350435 -154.789595)
			(xy 65.405839 -154.812544) (xy 65.457773 -154.842528) (xy 65.505349 -154.879034) (xy 65.547754 -154.921439)
			(xy 65.58426 -154.969015) (xy 65.614244 -155.020949) (xy 65.637193 -155.076353) (xy 65.652714 -155.134278)
			(xy 65.660542 -155.193734) (xy 65.661032 -155.223718) (xy 65.661032 -156.085794) (xy 83.716368 -156.085794)
			(xy 83.716368 -155.222194) (xy 83.716858 -155.19221) (xy 83.724686 -155.132754) (xy 83.740207 -155.074829)
			(xy 83.763156 -155.019425) (xy 83.79314 -154.967491) (xy 83.829646 -154.919915) (xy 83.872051 -154.87751)
			(xy 83.919627 -154.841004) (xy 83.971561 -154.81102) (xy 84.026965 -154.788071) (xy 84.08489 -154.77255)
			(xy 84.144346 -154.764722) (xy 84.204314 -154.764722) (xy 84.26377 -154.77255) (xy 84.321695 -154.788071)
			(xy 84.377099 -154.81102) (xy 84.429033 -154.841004) (xy 84.476609 -154.87751) (xy 84.519014 -154.919915)
			(xy 84.55552 -154.967491) (xy 84.585504 -155.019425) (xy 84.608453 -155.074829) (xy 84.623974 -155.132754)
			(xy 84.631802 -155.19221) (xy 84.632292 -155.222194) (xy 84.632292 -156.085794) (xy 84.632267 -156.087318)
			(xy 180.84546 -156.087318) (xy 180.84546 -155.223718) (xy 180.84595 -155.19375) (xy 180.853773 -155.134328)
			(xy 180.869286 -155.076435) (xy 180.892222 -155.021062) (xy 180.922189 -154.969156) (xy 180.958676 -154.921606)
			(xy 181.001056 -154.879226) (xy 181.048606 -154.842739) (xy 181.100512 -154.812772) (xy 181.155885 -154.789836)
			(xy 181.213778 -154.774323) (xy 181.2732 -154.7665) (xy 181.333136 -154.7665) (xy 181.392558 -154.774323)
			(xy 181.450451 -154.789836) (xy 181.505824 -154.812772) (xy 181.55773 -154.842739) (xy 181.60528 -154.879226)
			(xy 181.64766 -154.921606) (xy 181.684147 -154.969156) (xy 181.714114 -155.021062) (xy 181.73705 -155.076435)
			(xy 181.752563 -155.134328) (xy 181.760386 -155.19375) (xy 181.760876 -155.223718) (xy 181.760876 -156.085794)
			(xy 199.81672 -156.085794) (xy 199.81672 -155.222194) (xy 199.81721 -155.192226) (xy 199.825033 -155.132804)
			(xy 199.840546 -155.074911) (xy 199.863482 -155.019538) (xy 199.893449 -154.967632) (xy 199.929936 -154.920082)
			(xy 199.972316 -154.877702) (xy 200.019866 -154.841215) (xy 200.071772 -154.811248) (xy 200.127145 -154.788312)
			(xy 200.185038 -154.772799) (xy 200.24446 -154.764976) (xy 200.304396 -154.764976) (xy 200.363818 -154.772799)
			(xy 200.421711 -154.788312) (xy 200.477084 -154.811248) (xy 200.52899 -154.841215) (xy 200.57654 -154.877702)
			(xy 200.61892 -154.920082) (xy 200.655407 -154.967632) (xy 200.685374 -155.019538) (xy 200.70831 -155.074911)
			(xy 200.723823 -155.132804) (xy 200.731646 -155.192226) (xy 200.732136 -155.222194) (xy 200.732136 -156.085794)
			(xy 200.732111 -156.087318) (xy 296.945304 -156.087318) (xy 296.945304 -155.223718) (xy 296.945794 -155.19375)
			(xy 296.953617 -155.134328) (xy 296.96913 -155.076435) (xy 296.992066 -155.021062) (xy 297.022033 -154.969156)
			(xy 297.05852 -154.921606) (xy 297.1009 -154.879226) (xy 297.14845 -154.842739) (xy 297.200356 -154.812772)
			(xy 297.255729 -154.789836) (xy 297.313622 -154.774323) (xy 297.373044 -154.7665) (xy 297.43298 -154.7665)
			(xy 297.492402 -154.774323) (xy 297.550295 -154.789836) (xy 297.605668 -154.812772) (xy 297.657574 -154.842739)
			(xy 297.705124 -154.879226) (xy 297.747504 -154.921606) (xy 297.783991 -154.969156) (xy 297.813958 -155.021062)
			(xy 297.836894 -155.076435) (xy 297.852407 -155.134328) (xy 297.86023 -155.19375) (xy 297.86072 -155.223718)
			(xy 297.86072 -156.085794) (xy 315.916564 -156.085794) (xy 315.916564 -155.222194) (xy 315.917054 -155.192226)
			(xy 315.924877 -155.132804) (xy 315.94039 -155.074911) (xy 315.963326 -155.019538) (xy 315.993293 -154.967632)
			(xy 316.02978 -154.920082) (xy 316.07216 -154.877702) (xy 316.11971 -154.841215) (xy 316.171616 -154.811248)
			(xy 316.226989 -154.788312) (xy 316.284882 -154.772799) (xy 316.344304 -154.764976) (xy 316.40424 -154.764976)
			(xy 316.463662 -154.772799) (xy 316.521555 -154.788312) (xy 316.576928 -154.811248) (xy 316.628834 -154.841215)
			(xy 316.676384 -154.877702) (xy 316.718764 -154.920082) (xy 316.755251 -154.967632) (xy 316.785218 -155.019538)
			(xy 316.808154 -155.074911) (xy 316.823667 -155.132804) (xy 316.83149 -155.192226) (xy 316.83198 -155.222194)
			(xy 316.83198 -156.085794) (xy 316.831955 -156.087318) (xy 413.045148 -156.087318) (xy 413.045148 -155.223718)
			(xy 413.045638 -155.193734) (xy 413.053466 -155.134278) (xy 413.068987 -155.076353) (xy 413.091936 -155.020949)
			(xy 413.12192 -154.969015) (xy 413.158426 -154.921439) (xy 413.200831 -154.879034) (xy 413.248407 -154.842528)
			(xy 413.300341 -154.812544) (xy 413.355745 -154.789595) (xy 413.41367 -154.774074) (xy 413.473126 -154.766246)
			(xy 413.533094 -154.766246) (xy 413.59255 -154.774074) (xy 413.650475 -154.789595) (xy 413.705879 -154.812544)
			(xy 413.757813 -154.842528) (xy 413.805389 -154.879034) (xy 413.847794 -154.921439) (xy 413.8843 -154.969015)
			(xy 413.914284 -155.020949) (xy 413.937233 -155.076353) (xy 413.952754 -155.134278) (xy 413.960582 -155.193734)
			(xy 413.961072 -155.223718) (xy 413.961072 -156.085794) (xy 432.016408 -156.085794) (xy 432.016408 -155.222194)
			(xy 432.016898 -155.19221) (xy 432.024726 -155.132754) (xy 432.040247 -155.074829) (xy 432.063196 -155.019425)
			(xy 432.09318 -154.967491) (xy 432.129686 -154.919915) (xy 432.172091 -154.87751) (xy 432.219667 -154.841004)
			(xy 432.271601 -154.81102) (xy 432.327005 -154.788071) (xy 432.38493 -154.77255) (xy 432.444386 -154.764722)
			(xy 432.504354 -154.764722) (xy 432.56381 -154.77255) (xy 432.621735 -154.788071) (xy 432.677139 -154.81102)
			(xy 432.729073 -154.841004) (xy 432.776649 -154.87751) (xy 432.819054 -154.919915) (xy 432.85556 -154.967491)
			(xy 432.885544 -155.019425) (xy 432.908493 -155.074829) (xy 432.924014 -155.132754) (xy 432.931842 -155.19221)
			(xy 432.932332 -155.222194) (xy 432.932332 -156.085794) (xy 432.931842 -156.115778) (xy 432.924014 -156.175234)
			(xy 432.908493 -156.233159) (xy 432.885544 -156.288563) (xy 432.85556 -156.340497) (xy 432.819054 -156.388073)
			(xy 432.776649 -156.430478) (xy 432.729073 -156.466984) (xy 432.677139 -156.496968) (xy 432.621735 -156.519917)
			(xy 432.56381 -156.535438) (xy 432.504354 -156.543266) (xy 432.444386 -156.543266) (xy 432.38493 -156.535438)
			(xy 432.327005 -156.519917) (xy 432.271601 -156.496968) (xy 432.219667 -156.466984) (xy 432.172091 -156.430478)
			(xy 432.129686 -156.388073) (xy 432.09318 -156.340497) (xy 432.063196 -156.288563) (xy 432.040247 -156.233159)
			(xy 432.024726 -156.175234) (xy 432.016898 -156.115778) (xy 432.016408 -156.085794) (xy 413.961072 -156.085794)
			(xy 413.961072 -156.087318) (xy 413.960582 -156.117302) (xy 413.952754 -156.176758) (xy 413.937233 -156.234683)
			(xy 413.914284 -156.290087) (xy 413.8843 -156.342021) (xy 413.847794 -156.389597) (xy 413.805389 -156.432002)
			(xy 413.757813 -156.468508) (xy 413.705879 -156.498492) (xy 413.650475 -156.521441) (xy 413.59255 -156.536962)
			(xy 413.533094 -156.54479) (xy 413.473126 -156.54479) (xy 413.41367 -156.536962) (xy 413.355745 -156.521441)
			(xy 413.300341 -156.498492) (xy 413.248407 -156.468508) (xy 413.200831 -156.432002) (xy 413.158426 -156.389597)
			(xy 413.12192 -156.342021) (xy 413.091936 -156.290087) (xy 413.068987 -156.234683) (xy 413.053466 -156.176758)
			(xy 413.045638 -156.117302) (xy 413.045148 -156.087318) (xy 316.831955 -156.087318) (xy 316.83149 -156.115762)
			(xy 316.823667 -156.175184) (xy 316.808154 -156.233077) (xy 316.785218 -156.28845) (xy 316.755251 -156.340356)
			(xy 316.718764 -156.387906) (xy 316.676384 -156.430286) (xy 316.628834 -156.466773) (xy 316.576928 -156.49674)
			(xy 316.521555 -156.519676) (xy 316.463662 -156.535189) (xy 316.40424 -156.543012) (xy 316.344304 -156.543012)
			(xy 316.284882 -156.535189) (xy 316.226989 -156.519676) (xy 316.171616 -156.49674) (xy 316.11971 -156.466773)
			(xy 316.07216 -156.430286) (xy 316.02978 -156.387906) (xy 315.993293 -156.340356) (xy 315.963326 -156.28845)
			(xy 315.94039 -156.233077) (xy 315.924877 -156.175184) (xy 315.917054 -156.115762) (xy 315.916564 -156.085794)
			(xy 297.86072 -156.085794) (xy 297.86072 -156.087318) (xy 297.86023 -156.117286) (xy 297.852407 -156.176708)
			(xy 297.836894 -156.234601) (xy 297.813958 -156.289974) (xy 297.783991 -156.34188) (xy 297.747504 -156.38943)
			(xy 297.705124 -156.43181) (xy 297.657574 -156.468297) (xy 297.605668 -156.498264) (xy 297.550295 -156.5212)
			(xy 297.492402 -156.536713) (xy 297.43298 -156.544536) (xy 297.373044 -156.544536) (xy 297.313622 -156.536713)
			(xy 297.255729 -156.5212) (xy 297.200356 -156.498264) (xy 297.14845 -156.468297) (xy 297.1009 -156.43181)
			(xy 297.05852 -156.38943) (xy 297.022033 -156.34188) (xy 296.992066 -156.289974) (xy 296.96913 -156.234601)
			(xy 296.953617 -156.176708) (xy 296.945794 -156.117286) (xy 296.945304 -156.087318) (xy 200.732111 -156.087318)
			(xy 200.731646 -156.115762) (xy 200.723823 -156.175184) (xy 200.70831 -156.233077) (xy 200.685374 -156.28845)
			(xy 200.655407 -156.340356) (xy 200.61892 -156.387906) (xy 200.57654 -156.430286) (xy 200.52899 -156.466773)
			(xy 200.477084 -156.49674) (xy 200.421711 -156.519676) (xy 200.363818 -156.535189) (xy 200.304396 -156.543012)
			(xy 200.24446 -156.543012) (xy 200.185038 -156.535189) (xy 200.127145 -156.519676) (xy 200.071772 -156.49674)
			(xy 200.019866 -156.466773) (xy 199.972316 -156.430286) (xy 199.929936 -156.387906) (xy 199.893449 -156.340356)
			(xy 199.863482 -156.28845) (xy 199.840546 -156.233077) (xy 199.825033 -156.175184) (xy 199.81721 -156.115762)
			(xy 199.81672 -156.085794) (xy 181.760876 -156.085794) (xy 181.760876 -156.087318) (xy 181.760386 -156.117286)
			(xy 181.752563 -156.176708) (xy 181.73705 -156.234601) (xy 181.714114 -156.289974) (xy 181.684147 -156.34188)
			(xy 181.64766 -156.38943) (xy 181.60528 -156.43181) (xy 181.55773 -156.468297) (xy 181.505824 -156.498264)
			(xy 181.450451 -156.5212) (xy 181.392558 -156.536713) (xy 181.333136 -156.544536) (xy 181.2732 -156.544536)
			(xy 181.213778 -156.536713) (xy 181.155885 -156.5212) (xy 181.100512 -156.498264) (xy 181.048606 -156.468297)
			(xy 181.001056 -156.43181) (xy 180.958676 -156.38943) (xy 180.922189 -156.34188) (xy 180.892222 -156.289974)
			(xy 180.869286 -156.234601) (xy 180.853773 -156.176708) (xy 180.84595 -156.117286) (xy 180.84546 -156.087318)
			(xy 84.632267 -156.087318) (xy 84.631802 -156.115778) (xy 84.623974 -156.175234) (xy 84.608453 -156.233159)
			(xy 84.585504 -156.288563) (xy 84.55552 -156.340497) (xy 84.519014 -156.388073) (xy 84.476609 -156.430478)
			(xy 84.429033 -156.466984) (xy 84.377099 -156.496968) (xy 84.321695 -156.519917) (xy 84.26377 -156.535438)
			(xy 84.204314 -156.543266) (xy 84.144346 -156.543266) (xy 84.08489 -156.535438) (xy 84.026965 -156.519917)
			(xy 83.971561 -156.496968) (xy 83.919627 -156.466984) (xy 83.872051 -156.430478) (xy 83.829646 -156.388073)
			(xy 83.79314 -156.340497) (xy 83.763156 -156.288563) (xy 83.740207 -156.233159) (xy 83.724686 -156.175234)
			(xy 83.716858 -156.115778) (xy 83.716368 -156.085794) (xy 65.661032 -156.085794) (xy 65.661032 -156.087318)
			(xy 65.660542 -156.117302) (xy 65.652714 -156.176758) (xy 65.637193 -156.234683) (xy 65.614244 -156.290087)
			(xy 65.58426 -156.342021) (xy 65.547754 -156.389597) (xy 65.505349 -156.432002) (xy 65.457773 -156.468508)
			(xy 65.405839 -156.498492) (xy 65.350435 -156.521441) (xy 65.29251 -156.536962) (xy 65.233054 -156.54479)
			(xy 65.173086 -156.54479) (xy 65.11363 -156.536962) (xy 65.055705 -156.521441) (xy 65.000301 -156.498492)
			(xy 64.948367 -156.468508) (xy 64.900791 -156.432002) (xy 64.858386 -156.389597) (xy 64.82188 -156.342021)
			(xy 64.791896 -156.290087) (xy 64.768947 -156.234683) (xy 64.753426 -156.176758) (xy 64.745598 -156.117302)
			(xy 64.745108 -156.087318) (xy 4.308094 -156.087318) (xy 4.308094 -157.900066) (xy 228.314505 -157.900066)
			(xy 228.314505 -157.840134) (xy 228.322328 -157.780714) (xy 228.33784 -157.722823) (xy 228.360775 -157.667453)
			(xy 228.390741 -157.61555) (xy 228.427226 -157.568002) (xy 228.469605 -157.525624) (xy 228.517153 -157.489139)
			(xy 228.569056 -157.459173) (xy 228.624427 -157.436238) (xy 228.682318 -157.420727) (xy 228.741738 -157.412905)
			(xy 228.771704 -157.412436) (xy 229.635304 -157.412436) (xy 229.665274 -157.412838) (xy 229.724702 -157.420663)
			(xy 229.7826 -157.436177) (xy 229.837978 -157.459116) (xy 229.889888 -157.489086) (xy 229.937442 -157.525576)
			(xy 229.979827 -157.567961) (xy 230.016316 -157.615515) (xy 230.046286 -157.667425) (xy 230.069224 -157.722803)
			(xy 230.084738 -157.780702) (xy 230.092562 -157.84013) (xy 230.092562 -157.90007) (xy 230.089876 -157.920473)
			(xy 230.557725 -157.920473) (xy 230.557725 -157.860527) (xy 230.56555 -157.801095) (xy 230.581066 -157.743192)
			(xy 230.604007 -157.68781) (xy 230.633981 -157.635897) (xy 230.670475 -157.58834) (xy 230.712864 -157.545953)
			(xy 230.760423 -157.509463) (xy 230.812339 -157.479493) (xy 230.867722 -157.456555) (xy 230.925626 -157.441044)
			(xy 230.985059 -157.433223) (xy 231.015032 -157.432756) (xy 231.878632 -157.432756) (xy 231.908596 -157.43332)
			(xy 231.968011 -157.441146) (xy 232.025896 -157.45666) (xy 232.081261 -157.479596) (xy 232.133158 -157.509563)
			(xy 232.180701 -157.546046) (xy 232.223075 -157.588423) (xy 232.259555 -157.635968) (xy 232.289518 -157.687868)
			(xy 232.31245 -157.743235) (xy 232.32796 -157.801121) (xy 232.335782 -157.860536) (xy 232.335782 -157.920464)
			(xy 232.32796 -157.979879) (xy 232.31245 -158.037765) (xy 232.289518 -158.093132) (xy 232.259555 -158.145032)
			(xy 232.223075 -158.192577) (xy 232.180701 -158.234954) (xy 232.133158 -158.271437) (xy 232.081261 -158.301404)
			(xy 232.025896 -158.32434) (xy 231.968011 -158.339854) (xy 231.908596 -158.34768) (xy 231.878632 -158.348172)
			(xy 231.015032 -158.348172) (xy 230.985059 -158.347777) (xy 230.925626 -158.339956) (xy 230.867722 -158.324445)
			(xy 230.812339 -158.301507) (xy 230.760423 -158.271537) (xy 230.712864 -158.235047) (xy 230.670475 -158.19266)
			(xy 230.633981 -158.145103) (xy 230.604007 -158.09319) (xy 230.581066 -158.037808) (xy 230.56555 -157.979905)
			(xy 230.557725 -157.920473) (xy 230.089876 -157.920473) (xy 230.084738 -157.959498) (xy 230.069224 -158.017397)
			(xy 230.046286 -158.072775) (xy 230.016316 -158.124685) (xy 229.979827 -158.172239) (xy 229.937442 -158.214624)
			(xy 229.889888 -158.251114) (xy 229.837978 -158.281084) (xy 229.7826 -158.304023) (xy 229.724702 -158.319537)
			(xy 229.665274 -158.327362) (xy 229.635304 -158.327852) (xy 228.771704 -158.327852) (xy 228.741738 -158.327295)
			(xy 228.682318 -158.319473) (xy 228.624427 -158.303962) (xy 228.569056 -158.281027) (xy 228.517153 -158.251061)
			(xy 228.469605 -158.214576) (xy 228.427226 -158.172198) (xy 228.390741 -158.12465) (xy 228.360775 -158.072747)
			(xy 228.33784 -158.017377) (xy 228.322328 -157.959486) (xy 228.314505 -157.900066) (xy 4.308094 -157.900066)
			(xy 4.308094 -160.1851) (xy 45.524179 -160.1851) (xy 45.528134 -160.093263) (xy 45.539969 -160.002106)
			(xy 45.559596 -159.912303) (xy 45.58687 -159.824521) (xy 45.62159 -159.739407) (xy 45.663498 -159.657594)
			(xy 45.712284 -159.579686) (xy 45.767587 -159.506261) (xy 45.828997 -159.437861) (xy 45.896059 -159.374994)
			(xy 45.968278 -159.318124) (xy 46.045118 -159.267673) (xy 46.126011 -159.224014) (xy 46.210357 -159.187471)
			(xy 46.297533 -159.158314) (xy 46.386892 -159.13676) (xy 46.477773 -159.122966) (xy 46.569504 -159.117036)
			(xy 46.661405 -159.119014) (xy 46.752796 -159.128885) (xy 46.843 -159.146575) (xy 46.931349 -159.171955)
			(xy 47.017189 -159.204835) (xy 47.099885 -159.244973) (xy 47.178825 -159.292072) (xy 47.253423 -159.345782)
			(xy 47.323129 -159.405706) (xy 47.387424 -159.4714) (xy 47.445835 -159.542378) (xy 47.497927 -159.618115)
			(xy 47.543316 -159.69805) (xy 47.581666 -159.78159) (xy 47.612691 -159.868118) (xy 47.636164 -159.956993)
			(xy 47.65191 -160.047557) (xy 47.659812 -160.139139) (xy 47.660306 -160.1851) (xy 69.888875 -160.1851)
			(xy 69.892831 -160.093241) (xy 69.904668 -160.002062) (xy 69.9243 -159.912238) (xy 69.951581 -159.824435)
			(xy 69.986309 -159.739302) (xy 70.028227 -159.657469) (xy 70.077025 -159.579542) (xy 70.13234 -159.506099)
			(xy 70.193765 -159.437683) (xy 70.260844 -159.374801) (xy 70.333079 -159.317918) (xy 70.409938 -159.267455)
			(xy 70.49085 -159.223786) (xy 70.575216 -159.187234) (xy 70.662412 -159.15807) (xy 70.751793 -159.13651)
			(xy 70.842696 -159.122714) (xy 70.934449 -159.116782) (xy 71.026371 -159.118761) (xy 71.117784 -159.128634)
			(xy 71.208009 -159.146329) (xy 71.29638 -159.171714) (xy 71.38224 -159.204602) (xy 71.464956 -159.24475)
			(xy 71.543914 -159.291859) (xy 71.618531 -159.345582) (xy 71.688252 -159.40552) (xy 71.752563 -159.47123)
			(xy 71.810988 -159.542226) (xy 71.863093 -159.61798) (xy 71.908492 -159.697934) (xy 71.946851 -159.781494)
			(xy 71.977884 -159.868043) (xy 72.001362 -159.956939) (xy 72.017112 -160.047524) (xy 72.025016 -160.139128)
			(xy 72.02551 -160.1851) (xy 161.624277 -160.1851) (xy 161.628232 -160.093263) (xy 161.640067 -160.002106)
			(xy 161.659694 -159.912303) (xy 161.686968 -159.824521) (xy 161.721688 -159.739407) (xy 161.763596 -159.657594)
			(xy 161.812382 -159.579686) (xy 161.867685 -159.506261) (xy 161.929095 -159.437861) (xy 161.996157 -159.374994)
			(xy 162.068376 -159.318124) (xy 162.145216 -159.267673) (xy 162.226109 -159.224014) (xy 162.310455 -159.187471)
			(xy 162.397631 -159.158314) (xy 162.48699 -159.13676) (xy 162.577871 -159.122966) (xy 162.669602 -159.117036)
			(xy 162.761503 -159.119014) (xy 162.852894 -159.128885) (xy 162.943098 -159.146575) (xy 163.031447 -159.171955)
			(xy 163.117287 -159.204835) (xy 163.199983 -159.244973) (xy 163.278923 -159.292072) (xy 163.353521 -159.345782)
			(xy 163.423227 -159.405706) (xy 163.487522 -159.4714) (xy 163.545933 -159.542378) (xy 163.598025 -159.618115)
			(xy 163.643414 -159.69805) (xy 163.681764 -159.78159) (xy 163.712789 -159.868118) (xy 163.736262 -159.956993)
			(xy 163.752008 -160.047557) (xy 163.75991 -160.139139) (xy 163.760404 -160.1851) (xy 185.988973 -160.1851)
			(xy 185.992929 -160.093241) (xy 186.004766 -160.002062) (xy 186.024398 -159.912238) (xy 186.051679 -159.824435)
			(xy 186.086407 -159.739302) (xy 186.128325 -159.657469) (xy 186.177123 -159.579542) (xy 186.232438 -159.506099)
			(xy 186.293863 -159.437683) (xy 186.360942 -159.374801) (xy 186.433177 -159.317918) (xy 186.510036 -159.267455)
			(xy 186.590948 -159.223786) (xy 186.675314 -159.187234) (xy 186.76251 -159.15807) (xy 186.851891 -159.13651)
			(xy 186.942794 -159.122714) (xy 187.034547 -159.116782) (xy 187.126469 -159.118761) (xy 187.217882 -159.128634)
			(xy 187.308107 -159.146329) (xy 187.396478 -159.171714) (xy 187.482338 -159.204602) (xy 187.565054 -159.24475)
			(xy 187.644012 -159.291859) (xy 187.718629 -159.345582) (xy 187.78835 -159.40552) (xy 187.852661 -159.47123)
			(xy 187.911086 -159.542226) (xy 187.963191 -159.61798) (xy 188.00859 -159.697934) (xy 188.046949 -159.781494)
			(xy 188.077982 -159.868043) (xy 188.10146 -159.956939) (xy 188.11721 -160.047524) (xy 188.125114 -160.139128)
			(xy 188.125608 -160.1851) (xy 277.724121 -160.1851) (xy 277.728076 -160.093263) (xy 277.739911 -160.002106)
			(xy 277.759538 -159.912303) (xy 277.786812 -159.824521) (xy 277.821532 -159.739407) (xy 277.86344 -159.657594)
			(xy 277.912226 -159.579686) (xy 277.967529 -159.506261) (xy 278.028939 -159.437861) (xy 278.096001 -159.374994)
			(xy 278.16822 -159.318124) (xy 278.24506 -159.267673) (xy 278.325953 -159.224014) (xy 278.410299 -159.187471)
			(xy 278.497475 -159.158314) (xy 278.586834 -159.13676) (xy 278.677715 -159.122966) (xy 278.769446 -159.117036)
			(xy 278.861347 -159.119014) (xy 278.952738 -159.128885) (xy 279.042942 -159.146575) (xy 279.131291 -159.171955)
			(xy 279.217131 -159.204835) (xy 279.299827 -159.244973) (xy 279.378767 -159.292072) (xy 279.453365 -159.345782)
			(xy 279.523071 -159.405706) (xy 279.587366 -159.4714) (xy 279.645777 -159.542378) (xy 279.697869 -159.618115)
			(xy 279.743258 -159.69805) (xy 279.781608 -159.78159) (xy 279.812633 -159.868118) (xy 279.836106 -159.956993)
			(xy 279.851852 -160.047557) (xy 279.859754 -160.139139) (xy 279.860248 -160.1851) (xy 302.088817 -160.1851)
			(xy 302.092773 -160.093241) (xy 302.10461 -160.002062) (xy 302.124242 -159.912238) (xy 302.151523 -159.824435)
			(xy 302.186251 -159.739302) (xy 302.228169 -159.657469) (xy 302.276967 -159.579542) (xy 302.332282 -159.506099)
			(xy 302.393707 -159.437683) (xy 302.460786 -159.374801) (xy 302.533021 -159.317918) (xy 302.60988 -159.267455)
			(xy 302.690792 -159.223786) (xy 302.775158 -159.187234) (xy 302.862354 -159.15807) (xy 302.951735 -159.13651)
			(xy 303.042638 -159.122714) (xy 303.134391 -159.116782) (xy 303.226313 -159.118761) (xy 303.317726 -159.128634)
			(xy 303.407951 -159.146329) (xy 303.496322 -159.171714) (xy 303.582182 -159.204602) (xy 303.664898 -159.24475)
			(xy 303.743856 -159.291859) (xy 303.818473 -159.345582) (xy 303.888194 -159.40552) (xy 303.952505 -159.47123)
			(xy 304.01093 -159.542226) (xy 304.063035 -159.61798) (xy 304.108434 -159.697934) (xy 304.146793 -159.781494)
			(xy 304.177826 -159.868043) (xy 304.201304 -159.956939) (xy 304.217054 -160.047524) (xy 304.224958 -160.139128)
			(xy 304.225452 -160.1851) (xy 393.824219 -160.1851) (xy 393.828174 -160.093263) (xy 393.840009 -160.002106)
			(xy 393.859636 -159.912303) (xy 393.88691 -159.824521) (xy 393.92163 -159.739407) (xy 393.963538 -159.657594)
			(xy 394.012324 -159.579686) (xy 394.067627 -159.506261) (xy 394.129037 -159.437861) (xy 394.196099 -159.374994)
			(xy 394.268318 -159.318124) (xy 394.345158 -159.267673) (xy 394.426051 -159.224014) (xy 394.510397 -159.187471)
			(xy 394.597573 -159.158314) (xy 394.686932 -159.13676) (xy 394.777813 -159.122966) (xy 394.869544 -159.117036)
			(xy 394.961445 -159.119014) (xy 395.052836 -159.128885) (xy 395.14304 -159.146575) (xy 395.231389 -159.171955)
			(xy 395.317229 -159.204835) (xy 395.399925 -159.244973) (xy 395.478865 -159.292072) (xy 395.553463 -159.345782)
			(xy 395.623169 -159.405706) (xy 395.687464 -159.4714) (xy 395.745875 -159.542378) (xy 395.797967 -159.618115)
			(xy 395.843356 -159.69805) (xy 395.881706 -159.78159) (xy 395.912731 -159.868118) (xy 395.936204 -159.956993)
			(xy 395.95195 -160.047557) (xy 395.959852 -160.139139) (xy 395.960346 -160.1851) (xy 418.188915 -160.1851)
			(xy 418.192871 -160.093241) (xy 418.204708 -160.002062) (xy 418.22434 -159.912238) (xy 418.251621 -159.824435)
			(xy 418.286349 -159.739302) (xy 418.328267 -159.657469) (xy 418.377065 -159.579542) (xy 418.43238 -159.506099)
			(xy 418.493805 -159.437683) (xy 418.560884 -159.374801) (xy 418.633119 -159.317918) (xy 418.709978 -159.267455)
			(xy 418.79089 -159.223786) (xy 418.875256 -159.187234) (xy 418.962452 -159.15807) (xy 419.051833 -159.13651)
			(xy 419.142736 -159.122714) (xy 419.234489 -159.116782) (xy 419.326411 -159.118761) (xy 419.417824 -159.128634)
			(xy 419.508049 -159.146329) (xy 419.59642 -159.171714) (xy 419.68228 -159.204602) (xy 419.764996 -159.24475)
			(xy 419.843954 -159.291859) (xy 419.918571 -159.345582) (xy 419.988292 -159.40552) (xy 420.052603 -159.47123)
			(xy 420.111028 -159.542226) (xy 420.163133 -159.61798) (xy 420.208532 -159.697934) (xy 420.246891 -159.781494)
			(xy 420.277924 -159.868043) (xy 420.301402 -159.956939) (xy 420.317152 -160.047524) (xy 420.325056 -160.139128)
			(xy 420.32555 -160.1851) (xy 420.325056 -160.231072) (xy 420.317152 -160.322676) (xy 420.301402 -160.413261)
			(xy 420.277924 -160.502157) (xy 420.246891 -160.588706) (xy 420.208532 -160.672266) (xy 420.163133 -160.75222)
			(xy 420.111028 -160.827974) (xy 420.052603 -160.89897) (xy 419.988292 -160.96468) (xy 419.918571 -161.024618)
			(xy 419.843954 -161.078341) (xy 419.764996 -161.12545) (xy 419.68228 -161.165598) (xy 419.59642 -161.198486)
			(xy 419.508049 -161.223871) (xy 419.417824 -161.241566) (xy 419.326411 -161.251439) (xy 419.234489 -161.253418)
			(xy 419.142736 -161.247486) (xy 419.051833 -161.23369) (xy 418.962452 -161.21213) (xy 418.875256 -161.182966)
			(xy 418.79089 -161.146414) (xy 418.709978 -161.102745) (xy 418.633119 -161.052282) (xy 418.560884 -160.995399)
			(xy 418.493805 -160.932517) (xy 418.43238 -160.864101) (xy 418.377065 -160.790658) (xy 418.328267 -160.712731)
			(xy 418.286349 -160.630898) (xy 418.251621 -160.545765) (xy 418.22434 -160.457962) (xy 418.204708 -160.368138)
			(xy 418.192871 -160.276959) (xy 418.188915 -160.1851) (xy 395.960346 -160.1851) (xy 395.959852 -160.231061)
			(xy 395.95195 -160.322643) (xy 395.936204 -160.413207) (xy 395.912731 -160.502082) (xy 395.881706 -160.58861)
			(xy 395.843356 -160.67215) (xy 395.797967 -160.752085) (xy 395.745875 -160.827822) (xy 395.687464 -160.8988)
			(xy 395.623169 -160.964494) (xy 395.553463 -161.024418) (xy 395.478865 -161.078128) (xy 395.399925 -161.125227)
			(xy 395.317229 -161.165365) (xy 395.231389 -161.198245) (xy 395.14304 -161.223625) (xy 395.052836 -161.241315)
			(xy 394.961445 -161.251186) (xy 394.869544 -161.253164) (xy 394.777813 -161.247234) (xy 394.686932 -161.23344)
			(xy 394.597573 -161.211886) (xy 394.510397 -161.182729) (xy 394.426051 -161.146186) (xy 394.345158 -161.102527)
			(xy 394.268318 -161.052076) (xy 394.196099 -160.995206) (xy 394.129037 -160.932339) (xy 394.067627 -160.863939)
			(xy 394.012324 -160.790514) (xy 393.963538 -160.712606) (xy 393.92163 -160.630793) (xy 393.88691 -160.545679)
			(xy 393.859636 -160.457897) (xy 393.840009 -160.368094) (xy 393.828174 -160.276937) (xy 393.824219 -160.1851)
			(xy 304.225452 -160.1851) (xy 304.224958 -160.231072) (xy 304.217054 -160.322676) (xy 304.201304 -160.413261)
			(xy 304.177826 -160.502157) (xy 304.146793 -160.588706) (xy 304.108434 -160.672266) (xy 304.063035 -160.75222)
			(xy 304.01093 -160.827974) (xy 303.952505 -160.89897) (xy 303.888194 -160.96468) (xy 303.818473 -161.024618)
			(xy 303.743856 -161.078341) (xy 303.664898 -161.12545) (xy 303.582182 -161.165598) (xy 303.496322 -161.198486)
			(xy 303.407951 -161.223871) (xy 303.317726 -161.241566) (xy 303.226313 -161.251439) (xy 303.134391 -161.253418)
			(xy 303.042638 -161.247486) (xy 302.951735 -161.23369) (xy 302.862354 -161.21213) (xy 302.775158 -161.182966)
			(xy 302.690792 -161.146414) (xy 302.60988 -161.102745) (xy 302.533021 -161.052282) (xy 302.460786 -160.995399)
			(xy 302.393707 -160.932517) (xy 302.332282 -160.864101) (xy 302.276967 -160.790658) (xy 302.228169 -160.712731)
			(xy 302.186251 -160.630898) (xy 302.151523 -160.545765) (xy 302.124242 -160.457962) (xy 302.10461 -160.368138)
			(xy 302.092773 -160.276959) (xy 302.088817 -160.1851) (xy 279.860248 -160.1851) (xy 279.859754 -160.231061)
			(xy 279.851852 -160.322643) (xy 279.836106 -160.413207) (xy 279.812633 -160.502082) (xy 279.781608 -160.58861)
			(xy 279.743258 -160.67215) (xy 279.697869 -160.752085) (xy 279.645777 -160.827822) (xy 279.587366 -160.8988)
			(xy 279.523071 -160.964494) (xy 279.453365 -161.024418) (xy 279.378767 -161.078128) (xy 279.299827 -161.125227)
			(xy 279.217131 -161.165365) (xy 279.131291 -161.198245) (xy 279.042942 -161.223625) (xy 278.952738 -161.241315)
			(xy 278.861347 -161.251186) (xy 278.769446 -161.253164) (xy 278.677715 -161.247234) (xy 278.586834 -161.23344)
			(xy 278.497475 -161.211886) (xy 278.410299 -161.182729) (xy 278.325953 -161.146186) (xy 278.24506 -161.102527)
			(xy 278.16822 -161.052076) (xy 278.096001 -160.995206) (xy 278.028939 -160.932339) (xy 277.967529 -160.863939)
			(xy 277.912226 -160.790514) (xy 277.86344 -160.712606) (xy 277.821532 -160.630793) (xy 277.786812 -160.545679)
			(xy 277.759538 -160.457897) (xy 277.739911 -160.368094) (xy 277.728076 -160.276937) (xy 277.724121 -160.1851)
			(xy 188.125608 -160.1851) (xy 188.125114 -160.231072) (xy 188.11721 -160.322676) (xy 188.10146 -160.413261)
			(xy 188.077982 -160.502157) (xy 188.046949 -160.588706) (xy 188.00859 -160.672266) (xy 187.963191 -160.75222)
			(xy 187.911086 -160.827974) (xy 187.852661 -160.89897) (xy 187.78835 -160.96468) (xy 187.718629 -161.024618)
			(xy 187.644012 -161.078341) (xy 187.565054 -161.12545) (xy 187.482338 -161.165598) (xy 187.396478 -161.198486)
			(xy 187.308107 -161.223871) (xy 187.217882 -161.241566) (xy 187.126469 -161.251439) (xy 187.034547 -161.253418)
			(xy 186.942794 -161.247486) (xy 186.851891 -161.23369) (xy 186.76251 -161.21213) (xy 186.675314 -161.182966)
			(xy 186.590948 -161.146414) (xy 186.510036 -161.102745) (xy 186.433177 -161.052282) (xy 186.360942 -160.995399)
			(xy 186.293863 -160.932517) (xy 186.232438 -160.864101) (xy 186.177123 -160.790658) (xy 186.128325 -160.712731)
			(xy 186.086407 -160.630898) (xy 186.051679 -160.545765) (xy 186.024398 -160.457962) (xy 186.004766 -160.368138)
			(xy 185.992929 -160.276959) (xy 185.988973 -160.1851) (xy 163.760404 -160.1851) (xy 163.75991 -160.231061)
			(xy 163.752008 -160.322643) (xy 163.736262 -160.413207) (xy 163.712789 -160.502082) (xy 163.681764 -160.58861)
			(xy 163.643414 -160.67215) (xy 163.598025 -160.752085) (xy 163.545933 -160.827822) (xy 163.487522 -160.8988)
			(xy 163.423227 -160.964494) (xy 163.353521 -161.024418) (xy 163.278923 -161.078128) (xy 163.199983 -161.125227)
			(xy 163.117287 -161.165365) (xy 163.031447 -161.198245) (xy 162.943098 -161.223625) (xy 162.852894 -161.241315)
			(xy 162.761503 -161.251186) (xy 162.669602 -161.253164) (xy 162.577871 -161.247234) (xy 162.48699 -161.23344)
			(xy 162.397631 -161.211886) (xy 162.310455 -161.182729) (xy 162.226109 -161.146186) (xy 162.145216 -161.102527)
			(xy 162.068376 -161.052076) (xy 161.996157 -160.995206) (xy 161.929095 -160.932339) (xy 161.867685 -160.863939)
			(xy 161.812382 -160.790514) (xy 161.763596 -160.712606) (xy 161.721688 -160.630793) (xy 161.686968 -160.545679)
			(xy 161.659694 -160.457897) (xy 161.640067 -160.368094) (xy 161.628232 -160.276937) (xy 161.624277 -160.1851)
			(xy 72.02551 -160.1851) (xy 72.025016 -160.231072) (xy 72.017112 -160.322676) (xy 72.001362 -160.413261)
			(xy 71.977884 -160.502157) (xy 71.946851 -160.588706) (xy 71.908492 -160.672266) (xy 71.863093 -160.75222)
			(xy 71.810988 -160.827974) (xy 71.752563 -160.89897) (xy 71.688252 -160.96468) (xy 71.618531 -161.024618)
			(xy 71.543914 -161.078341) (xy 71.464956 -161.12545) (xy 71.38224 -161.165598) (xy 71.29638 -161.198486)
			(xy 71.208009 -161.223871) (xy 71.117784 -161.241566) (xy 71.026371 -161.251439) (xy 70.934449 -161.253418)
			(xy 70.842696 -161.247486) (xy 70.751793 -161.23369) (xy 70.662412 -161.21213) (xy 70.575216 -161.182966)
			(xy 70.49085 -161.146414) (xy 70.409938 -161.102745) (xy 70.333079 -161.052282) (xy 70.260844 -160.995399)
			(xy 70.193765 -160.932517) (xy 70.13234 -160.864101) (xy 70.077025 -160.790658) (xy 70.028227 -160.712731)
			(xy 69.986309 -160.630898) (xy 69.951581 -160.545765) (xy 69.9243 -160.457962) (xy 69.904668 -160.368138)
			(xy 69.892831 -160.276959) (xy 69.888875 -160.1851) (xy 47.660306 -160.1851) (xy 47.659812 -160.231061)
			(xy 47.65191 -160.322643) (xy 47.636164 -160.413207) (xy 47.612691 -160.502082) (xy 47.581666 -160.58861)
			(xy 47.543316 -160.67215) (xy 47.497927 -160.752085) (xy 47.445835 -160.827822) (xy 47.387424 -160.8988)
			(xy 47.323129 -160.964494) (xy 47.253423 -161.024418) (xy 47.178825 -161.078128) (xy 47.099885 -161.125227)
			(xy 47.017189 -161.165365) (xy 46.931349 -161.198245) (xy 46.843 -161.223625) (xy 46.752796 -161.241315)
			(xy 46.661405 -161.251186) (xy 46.569504 -161.253164) (xy 46.477773 -161.247234) (xy 46.386892 -161.23344)
			(xy 46.297533 -161.211886) (xy 46.210357 -161.182729) (xy 46.126011 -161.146186) (xy 46.045118 -161.102527)
			(xy 45.968278 -161.052076) (xy 45.896059 -160.995206) (xy 45.828997 -160.932339) (xy 45.767587 -160.863939)
			(xy 45.712284 -160.790514) (xy 45.663498 -160.712606) (xy 45.62159 -160.630793) (xy 45.58687 -160.545679)
			(xy 45.559596 -160.457897) (xy 45.539969 -160.368094) (xy 45.528134 -160.276937) (xy 45.524179 -160.1851)
			(xy 4.308094 -160.1851) (xy 4.308094 -168.065164) (xy 135.245906 -168.065164) (xy 135.245906 -168.005236)
			(xy 135.253728 -167.94582) (xy 135.269237 -167.887933) (xy 135.29217 -167.832566) (xy 135.322132 -167.780665)
			(xy 135.358612 -167.733119) (xy 135.400986 -167.690742) (xy 135.448529 -167.654257) (xy 135.500426 -167.624289)
			(xy 135.555791 -167.601351) (xy 135.613677 -167.585836) (xy 135.673092 -167.578009) (xy 135.703056 -167.577516)
			(xy 136.566656 -167.577516) (xy 136.596628 -167.577934) (xy 136.656061 -167.585754) (xy 136.713965 -167.601264)
			(xy 136.769348 -167.6242) (xy 136.821264 -167.654169) (xy 136.868823 -167.690658) (xy 136.911213 -167.733044)
			(xy 136.947707 -167.7806) (xy 136.977681 -167.832512) (xy 137.000622 -167.887894) (xy 137.016138 -167.945796)
			(xy 137.023963 -168.005228) (xy 137.023963 -168.065172) (xy 137.016138 -168.124604) (xy 137.000622 -168.182506)
			(xy 136.977681 -168.237888) (xy 136.947707 -168.2898) (xy 136.911213 -168.337356) (xy 136.868823 -168.379742)
			(xy 136.821264 -168.416231) (xy 136.769348 -168.4462) (xy 136.713965 -168.469136) (xy 136.656061 -168.484646)
			(xy 136.596628 -168.492466) (xy 136.566656 -168.492932) (xy 135.703056 -168.492932) (xy 135.673092 -168.492391)
			(xy 135.613677 -168.484564) (xy 135.555791 -168.469049) (xy 135.500426 -168.446111) (xy 135.448529 -168.416143)
			(xy 135.400986 -168.379658) (xy 135.358612 -168.337281) (xy 135.322132 -168.289735) (xy 135.29217 -168.237834)
			(xy 135.269237 -168.182467) (xy 135.253728 -168.12458) (xy 135.245906 -168.065164) (xy 4.308094 -168.065164)
			(xy 4.308094 -168.700164) (xy 133.213906 -168.700164) (xy 133.213906 -168.640236) (xy 133.221728 -168.58082)
			(xy 133.237237 -168.522933) (xy 133.26017 -168.467566) (xy 133.290132 -168.415665) (xy 133.326612 -168.368119)
			(xy 133.368986 -168.325742) (xy 133.416529 -168.289257) (xy 133.468426 -168.259289) (xy 133.523791 -168.236351)
			(xy 133.581677 -168.220836) (xy 133.641092 -168.213009) (xy 133.671056 -168.212516) (xy 134.534656 -168.212516)
			(xy 134.564628 -168.212934) (xy 134.624061 -168.220754) (xy 134.681965 -168.236264) (xy 134.737348 -168.2592)
			(xy 134.789264 -168.289169) (xy 134.836823 -168.325658) (xy 134.879213 -168.368044) (xy 134.915707 -168.4156)
			(xy 134.945681 -168.467512) (xy 134.968622 -168.522894) (xy 134.984138 -168.580796) (xy 134.991963 -168.640228)
			(xy 134.991963 -168.700172) (xy 134.984138 -168.759604) (xy 134.968622 -168.817506) (xy 134.945681 -168.872888)
			(xy 134.915707 -168.9248) (xy 134.879213 -168.972356) (xy 134.836823 -169.014742) (xy 134.789264 -169.051231)
			(xy 134.737348 -169.0812) (xy 134.681965 -169.104136) (xy 134.624061 -169.119646) (xy 134.564628 -169.127466)
			(xy 134.534656 -169.127932) (xy 133.671056 -169.127932) (xy 133.641092 -169.127391) (xy 133.581677 -169.119564)
			(xy 133.523791 -169.104049) (xy 133.468426 -169.081111) (xy 133.416529 -169.051143) (xy 133.368986 -169.014658)
			(xy 133.326612 -168.972281) (xy 133.290132 -168.924735) (xy 133.26017 -168.872834) (xy 133.237237 -168.817467)
			(xy 133.221728 -168.75958) (xy 133.213906 -168.700164) (xy 4.308094 -168.700164) (xy 4.308094 -169.61389)
			(xy 245.108869 -169.61389) (xy 245.108869 -169.55391) (xy 245.116699 -169.494444) (xy 245.132223 -169.436508)
			(xy 245.155178 -169.381095) (xy 245.185169 -169.329152) (xy 245.221684 -169.281569) (xy 245.264097 -169.239158)
			(xy 245.311684 -169.202648) (xy 245.363629 -169.172661) (xy 245.419045 -169.149711) (xy 245.476981 -169.134191)
			(xy 245.536448 -169.126367) (xy 245.566438 -169.1259) (xy 246.430038 -169.1259) (xy 246.460018 -169.126468)
			(xy 246.519465 -169.134299) (xy 246.577381 -169.149822) (xy 246.632776 -169.172772) (xy 246.684702 -169.202755)
			(xy 246.73227 -169.239259) (xy 246.774667 -169.281659) (xy 246.811166 -169.32923) (xy 246.841145 -169.381158)
			(xy 246.86409 -169.436555) (xy 246.879608 -169.494472) (xy 246.887434 -169.55392) (xy 246.887434 -169.61388)
			(xy 246.879608 -169.673328) (xy 246.86409 -169.731245) (xy 246.841145 -169.786642) (xy 246.811166 -169.83857)
			(xy 246.774667 -169.886141) (xy 246.73227 -169.928541) (xy 246.684702 -169.965045) (xy 246.632776 -169.995028)
			(xy 246.577381 -170.017978) (xy 246.519465 -170.033501) (xy 246.460018 -170.041332) (xy 246.430038 -170.041824)
			(xy 245.566438 -170.041824) (xy 245.536448 -170.041433) (xy 245.476981 -170.033609) (xy 245.419045 -170.018089)
			(xy 245.363629 -169.995139) (xy 245.311684 -169.965152) (xy 245.264097 -169.928642) (xy 245.221684 -169.886231)
			(xy 245.185169 -169.838648) (xy 245.155178 -169.786705) (xy 245.132223 -169.731292) (xy 245.116699 -169.673356)
			(xy 245.108869 -169.61389) (xy 4.308094 -169.61389) (xy 4.308094 -174.805086) (xy 141.546072 -174.805086)
			(xy 141.546072 -173.941486) (xy 141.546562 -173.911518) (xy 141.554385 -173.852096) (xy 141.569898 -173.794203)
			(xy 141.592834 -173.73883) (xy 141.622801 -173.686924) (xy 141.659288 -173.639374) (xy 141.701668 -173.596994)
			(xy 141.749218 -173.560507) (xy 141.801124 -173.53054) (xy 141.856497 -173.507604) (xy 141.91439 -173.492091)
			(xy 141.973812 -173.484268) (xy 142.033748 -173.484268) (xy 142.09317 -173.492091) (xy 142.106698 -173.495716)
			(xy 257.519424 -173.495716) (xy 257.519424 -172.632116) (xy 257.519914 -172.602132) (xy 257.527742 -172.542676)
			(xy 257.543263 -172.484751) (xy 257.566212 -172.429347) (xy 257.596196 -172.377413) (xy 257.632702 -172.329837)
			(xy 257.675107 -172.287432) (xy 257.722683 -172.250926) (xy 257.774617 -172.220942) (xy 257.830021 -172.197993)
			(xy 257.887946 -172.182472) (xy 257.947402 -172.174644) (xy 258.00737 -172.174644) (xy 258.066826 -172.182472)
			(xy 258.124751 -172.197993) (xy 258.180155 -172.220942) (xy 258.232089 -172.250926) (xy 258.279665 -172.287432)
			(xy 258.32207 -172.329837) (xy 258.358576 -172.377413) (xy 258.38856 -172.429347) (xy 258.411509 -172.484751)
			(xy 258.42703 -172.542676) (xy 258.434858 -172.602132) (xy 258.435348 -172.632116) (xy 258.435348 -173.495716)
			(xy 258.434858 -173.5257) (xy 258.42703 -173.585156) (xy 258.411509 -173.643081) (xy 258.38856 -173.698485)
			(xy 258.358576 -173.750419) (xy 258.32207 -173.797995) (xy 258.279665 -173.8404) (xy 258.232089 -173.876906)
			(xy 258.180155 -173.90689) (xy 258.124751 -173.929839) (xy 258.066826 -173.94536) (xy 258.00737 -173.953188)
			(xy 257.947402 -173.953188) (xy 257.887946 -173.94536) (xy 257.830021 -173.929839) (xy 257.774617 -173.90689)
			(xy 257.722683 -173.876906) (xy 257.675107 -173.8404) (xy 257.632702 -173.797995) (xy 257.596196 -173.750419)
			(xy 257.566212 -173.698485) (xy 257.543263 -173.643081) (xy 257.527742 -173.585156) (xy 257.519914 -173.5257)
			(xy 257.519424 -173.495716) (xy 142.106698 -173.495716) (xy 142.151063 -173.507604) (xy 142.206436 -173.53054)
			(xy 142.258342 -173.560507) (xy 142.305892 -173.596994) (xy 142.348272 -173.639374) (xy 142.384759 -173.686924)
			(xy 142.414726 -173.73883) (xy 142.437662 -173.794203) (xy 142.453175 -173.852096) (xy 142.460998 -173.911518)
			(xy 142.461488 -173.941486) (xy 142.461488 -174.805086) (xy 142.460998 -174.835054) (xy 142.453175 -174.894476)
			(xy 142.437662 -174.952369) (xy 142.414726 -175.007742) (xy 142.384759 -175.059648) (xy 142.348272 -175.107198)
			(xy 142.305892 -175.149578) (xy 142.258342 -175.186065) (xy 142.206436 -175.216032) (xy 142.151063 -175.238968)
			(xy 142.09317 -175.254481) (xy 142.033748 -175.262304) (xy 141.973812 -175.262304) (xy 141.91439 -175.254481)
			(xy 141.856497 -175.238968) (xy 141.801124 -175.216032) (xy 141.749218 -175.186065) (xy 141.701668 -175.149578)
			(xy 141.659288 -175.107198) (xy 141.622801 -175.059648) (xy 141.592834 -175.007742) (xy 141.569898 -174.952369)
			(xy 141.554385 -174.894476) (xy 141.546562 -174.835054) (xy 141.546072 -174.805086) (xy 4.308094 -174.805086)
			(xy 4.308094 -176.837086) (xy 142.181072 -176.837086) (xy 142.181072 -175.973486) (xy 142.181562 -175.943518)
			(xy 142.189385 -175.884096) (xy 142.204898 -175.826203) (xy 142.227834 -175.77083) (xy 142.257801 -175.718924)
			(xy 142.294288 -175.671374) (xy 142.336668 -175.628994) (xy 142.384218 -175.592507) (xy 142.436124 -175.56254)
			(xy 142.491497 -175.539604) (xy 142.54939 -175.524091) (xy 142.608812 -175.516268) (xy 142.668748 -175.516268)
			(xy 142.72817 -175.524091) (xy 142.786063 -175.539604) (xy 142.841436 -175.56254) (xy 142.893342 -175.592507)
			(xy 142.940892 -175.628994) (xy 142.983272 -175.671374) (xy 143.019759 -175.718924) (xy 143.049726 -175.77083)
			(xy 143.072662 -175.826203) (xy 143.088175 -175.884096) (xy 143.095998 -175.943518) (xy 143.096488 -175.973486)
			(xy 143.096488 -176.837086) (xy 143.095998 -176.867054) (xy 143.088175 -176.926476) (xy 143.072662 -176.984369)
			(xy 143.049726 -177.039742) (xy 143.019759 -177.091648) (xy 142.983272 -177.139198) (xy 142.940892 -177.181578)
			(xy 142.893342 -177.218065) (xy 142.841436 -177.248032) (xy 142.786063 -177.270968) (xy 142.72817 -177.286481)
			(xy 142.668748 -177.294304) (xy 142.608812 -177.294304) (xy 142.54939 -177.286481) (xy 142.491497 -177.270968)
			(xy 142.436124 -177.248032) (xy 142.384218 -177.218065) (xy 142.336668 -177.181578) (xy 142.294288 -177.139198)
			(xy 142.257801 -177.091648) (xy 142.227834 -177.039742) (xy 142.204898 -176.984369) (xy 142.189385 -176.926476)
			(xy 142.181562 -176.867054) (xy 142.181072 -176.837086) (xy 4.308094 -176.837086) (xy 4.308094 -178.995324)
			(xy 123.198636 -178.995324) (xy 123.198636 -178.131724) (xy 123.199126 -178.10174) (xy 123.206954 -178.042284)
			(xy 123.222475 -177.984359) (xy 123.245424 -177.928955) (xy 123.275408 -177.877021) (xy 123.311914 -177.829445)
			(xy 123.354319 -177.78704) (xy 123.401895 -177.750534) (xy 123.453829 -177.72055) (xy 123.509233 -177.697601)
			(xy 123.567158 -177.68208) (xy 123.626614 -177.674252) (xy 123.686582 -177.674252) (xy 123.746038 -177.68208)
			(xy 123.803963 -177.697601) (xy 123.859367 -177.72055) (xy 123.911301 -177.750534) (xy 123.958877 -177.78704)
			(xy 124.001282 -177.829445) (xy 124.037788 -177.877021) (xy 124.067772 -177.928955) (xy 124.090721 -177.984359)
			(xy 124.106242 -178.042284) (xy 124.11407 -178.10174) (xy 124.11456 -178.131724) (xy 124.11456 -178.869086)
			(xy 141.546072 -178.869086) (xy 141.546072 -178.005486) (xy 141.546562 -177.975518) (xy 141.554385 -177.916096)
			(xy 141.569898 -177.858203) (xy 141.592834 -177.80283) (xy 141.622801 -177.750924) (xy 141.659288 -177.703374)
			(xy 141.701668 -177.660994) (xy 141.749218 -177.624507) (xy 141.801124 -177.59454) (xy 141.856497 -177.571604)
			(xy 141.91439 -177.556091) (xy 141.973812 -177.548268) (xy 142.033748 -177.548268) (xy 142.09317 -177.556091)
			(xy 142.151063 -177.571604) (xy 142.206436 -177.59454) (xy 142.258342 -177.624507) (xy 142.305892 -177.660994)
			(xy 142.348272 -177.703374) (xy 142.384759 -177.750924) (xy 142.414726 -177.80283) (xy 142.437662 -177.858203)
			(xy 142.453175 -177.916096) (xy 142.460998 -177.975518) (xy 142.461488 -178.005486) (xy 142.461488 -178.869086)
			(xy 142.460998 -178.899054) (xy 142.453175 -178.958476) (xy 142.437662 -179.016369) (xy 142.414726 -179.071742)
			(xy 142.384759 -179.123648) (xy 142.348272 -179.171198) (xy 142.305892 -179.213578) (xy 142.258342 -179.250065)
			(xy 142.206436 -179.280032) (xy 142.151063 -179.302968) (xy 142.09317 -179.318481) (xy 142.033748 -179.326304)
			(xy 141.973812 -179.326304) (xy 141.91439 -179.318481) (xy 141.856497 -179.302968) (xy 141.801124 -179.280032)
			(xy 141.749218 -179.250065) (xy 141.701668 -179.213578) (xy 141.659288 -179.171198) (xy 141.622801 -179.123648)
			(xy 141.592834 -179.071742) (xy 141.569898 -179.016369) (xy 141.554385 -178.958476) (xy 141.546562 -178.899054)
			(xy 141.546072 -178.869086) (xy 124.11456 -178.869086) (xy 124.11456 -178.995324) (xy 124.11407 -179.025308)
			(xy 124.106242 -179.084764) (xy 124.090721 -179.142689) (xy 124.067772 -179.198093) (xy 124.037788 -179.250027)
			(xy 124.001282 -179.297603) (xy 123.958877 -179.340008) (xy 123.911301 -179.376514) (xy 123.859367 -179.406498)
			(xy 123.803963 -179.429447) (xy 123.746038 -179.444968) (xy 123.686582 -179.452796) (xy 123.626614 -179.452796)
			(xy 123.567158 -179.444968) (xy 123.509233 -179.429447) (xy 123.453829 -179.406498) (xy 123.401895 -179.376514)
			(xy 123.354319 -179.340008) (xy 123.311914 -179.297603) (xy 123.275408 -179.250027) (xy 123.245424 -179.198093)
			(xy 123.222475 -179.142689) (xy 123.206954 -179.084764) (xy 123.199126 -179.025308) (xy 123.198636 -178.995324)
			(xy 4.308094 -178.995324) (xy 4.308094 -180.901086) (xy 142.181072 -180.901086) (xy 142.181072 -180.037486)
			(xy 142.181562 -180.007518) (xy 142.189385 -179.948096) (xy 142.204898 -179.890203) (xy 142.227834 -179.83483)
			(xy 142.257801 -179.782924) (xy 142.294288 -179.735374) (xy 142.336668 -179.692994) (xy 142.384218 -179.656507)
			(xy 142.436124 -179.62654) (xy 142.491497 -179.603604) (xy 142.54939 -179.588091) (xy 142.608812 -179.580268)
			(xy 142.668748 -179.580268) (xy 142.72817 -179.588091) (xy 142.786063 -179.603604) (xy 142.841436 -179.62654)
			(xy 142.893342 -179.656507) (xy 142.940892 -179.692994) (xy 142.983272 -179.735374) (xy 143.019759 -179.782924)
			(xy 143.049726 -179.83483) (xy 143.072662 -179.890203) (xy 143.088175 -179.948096) (xy 143.095998 -180.007518)
			(xy 143.096488 -180.037486) (xy 143.096488 -180.901086) (xy 143.095998 -180.931054) (xy 143.088175 -180.990476)
			(xy 143.072662 -181.048369) (xy 143.049726 -181.103742) (xy 143.019759 -181.155648) (xy 142.983272 -181.203198)
			(xy 142.940892 -181.245578) (xy 142.893342 -181.282065) (xy 142.841436 -181.312032) (xy 142.786063 -181.334968)
			(xy 142.72817 -181.350481) (xy 142.668748 -181.358304) (xy 142.608812 -181.358304) (xy 142.54939 -181.350481)
			(xy 142.491497 -181.334968) (xy 142.436124 -181.312032) (xy 142.384218 -181.282065) (xy 142.336668 -181.245578)
			(xy 142.294288 -181.203198) (xy 142.257801 -181.155648) (xy 142.227834 -181.103742) (xy 142.204898 -181.048369)
			(xy 142.189385 -180.990476) (xy 142.181562 -180.931054) (xy 142.181072 -180.901086) (xy 4.308094 -180.901086)
			(xy 4.308094 -182.933086) (xy 141.546072 -182.933086) (xy 141.546072 -182.069486) (xy 141.546562 -182.039518)
			(xy 141.554385 -181.980096) (xy 141.569898 -181.922203) (xy 141.592834 -181.86683) (xy 141.622801 -181.814924)
			(xy 141.659288 -181.767374) (xy 141.701668 -181.724994) (xy 141.749218 -181.688507) (xy 141.801124 -181.65854)
			(xy 141.856497 -181.635604) (xy 141.91439 -181.620091) (xy 141.973812 -181.612268) (xy 142.033748 -181.612268)
			(xy 142.09317 -181.620091) (xy 142.151063 -181.635604) (xy 142.206436 -181.65854) (xy 142.258342 -181.688507)
			(xy 142.305892 -181.724994) (xy 142.348272 -181.767374) (xy 142.384759 -181.814924) (xy 142.414726 -181.86683)
			(xy 142.437662 -181.922203) (xy 142.453175 -181.980096) (xy 142.460998 -182.039518) (xy 142.461488 -182.069486)
			(xy 142.461488 -182.933086) (xy 142.460998 -182.963054) (xy 142.453175 -183.022476) (xy 142.437662 -183.080369)
			(xy 142.414726 -183.135742) (xy 142.384759 -183.187648) (xy 142.348272 -183.235198) (xy 142.305892 -183.277578)
			(xy 142.258342 -183.314065) (xy 142.206436 -183.344032) (xy 142.151063 -183.366968) (xy 142.09317 -183.382481)
			(xy 142.033748 -183.390304) (xy 141.973812 -183.390304) (xy 141.91439 -183.382481) (xy 141.856497 -183.366968)
			(xy 141.801124 -183.344032) (xy 141.749218 -183.314065) (xy 141.701668 -183.277578) (xy 141.659288 -183.235198)
			(xy 141.622801 -183.187648) (xy 141.592834 -183.135742) (xy 141.569898 -183.080369) (xy 141.554385 -183.022476)
			(xy 141.546562 -182.963054) (xy 141.546072 -182.933086) (xy 4.308094 -182.933086) (xy 4.308094 -187.124582)
			(xy 135.58115 -187.124582) (xy 135.58115 -187.064618) (xy 135.588977 -187.005166) (xy 135.604497 -186.947244)
			(xy 135.627444 -186.891844) (xy 135.657426 -186.839912) (xy 135.69393 -186.792339) (xy 135.736331 -186.749937)
			(xy 135.783904 -186.713432) (xy 135.835835 -186.683448) (xy 135.891235 -186.6605) (xy 135.949156 -186.644979)
			(xy 136.008608 -186.637151) (xy 136.03859 -186.63666) (xy 136.90219 -186.63666) (xy 136.932178 -186.637085)
			(xy 136.99164 -186.644912) (xy 137.049571 -186.660433) (xy 137.104981 -186.683384) (xy 137.156922 -186.713371)
			(xy 137.204504 -186.749881) (xy 137.246913 -186.792289) (xy 137.283424 -186.83987) (xy 137.313412 -186.89181)
			(xy 137.336363 -186.947219) (xy 137.351886 -187.005151) (xy 137.359715 -187.064612) (xy 137.359715 -187.124588)
			(xy 137.351886 -187.184049) (xy 137.336363 -187.241981) (xy 137.313412 -187.29739) (xy 137.283424 -187.34933)
			(xy 137.246913 -187.396911) (xy 137.204504 -187.439319) (xy 137.156922 -187.475829) (xy 137.104981 -187.505816)
			(xy 137.049571 -187.528767) (xy 136.99164 -187.544288) (xy 136.932178 -187.552115) (xy 136.90219 -187.552584)
			(xy 136.03859 -187.552584) (xy 136.008608 -187.552049) (xy 135.949156 -187.544221) (xy 135.891235 -187.5287)
			(xy 135.835835 -187.505752) (xy 135.783904 -187.475768) (xy 135.736331 -187.439263) (xy 135.69393 -187.396861)
			(xy 135.657426 -187.349288) (xy 135.627444 -187.297356) (xy 135.604497 -187.241956) (xy 135.588977 -187.184034)
			(xy 135.58115 -187.124582) (xy 4.308094 -187.124582) (xy 4.308094 -188.252885) (xy 128.656818 -188.252885)
			(xy 128.656818 -188.192915) (xy 128.664646 -188.133459) (xy 128.680167 -188.075533) (xy 128.703116 -188.020128)
			(xy 128.733101 -187.968193) (xy 128.769608 -187.920615) (xy 128.812012 -187.87821) (xy 128.859589 -187.841703)
			(xy 128.911524 -187.811718) (xy 128.966929 -187.788768) (xy 129.024855 -187.773246) (xy 129.084311 -187.765418)
			(xy 129.114296 -187.764928) (xy 129.977896 -187.764928) (xy 130.007881 -187.765417) (xy 130.067339 -187.773244)
			(xy 130.125266 -187.788765) (xy 130.180671 -187.811714) (xy 130.232607 -187.841699) (xy 130.280185 -187.878207)
			(xy 130.322591 -187.920612) (xy 130.359098 -187.96819) (xy 130.389084 -188.020125) (xy 130.412034 -188.075531)
			(xy 130.427555 -188.133458) (xy 130.435383 -188.192915) (xy 130.435383 -188.252885) (xy 130.434185 -188.261981)
			(xy 131.046262 -188.261981) (xy 131.046262 -188.202019) (xy 131.054088 -188.14257) (xy 131.069607 -188.084651)
			(xy 131.092553 -188.029253) (xy 131.122533 -187.977324) (xy 131.159034 -187.929752) (xy 131.201432 -187.887351)
			(xy 131.249002 -187.850847) (xy 131.30093 -187.820864) (xy 131.356326 -187.797915) (xy 131.414244 -187.782393)
			(xy 131.473693 -187.774564) (xy 131.503674 -187.774072) (xy 132.367274 -187.774072) (xy 132.397263 -187.774472)
			(xy 132.456728 -187.782297) (xy 132.514663 -187.797818) (xy 132.570077 -187.820768) (xy 132.62202 -187.850755)
			(xy 132.669605 -187.887266) (xy 132.712017 -187.929675) (xy 132.74853 -187.977258) (xy 132.77852 -188.0292)
			(xy 132.801474 -188.084612) (xy 132.816998 -188.142546) (xy 132.824827 -188.202011) (xy 132.824827 -188.261989)
			(xy 132.816998 -188.321454) (xy 132.801474 -188.379388) (xy 132.79518 -188.394582) (xy 133.54915 -188.394582)
			(xy 133.54915 -188.334618) (xy 133.556977 -188.275166) (xy 133.572497 -188.217244) (xy 133.595444 -188.161844)
			(xy 133.625426 -188.109912) (xy 133.66193 -188.062339) (xy 133.704331 -188.019937) (xy 133.751904 -187.983432)
			(xy 133.803835 -187.953448) (xy 133.859235 -187.9305) (xy 133.917156 -187.914979) (xy 133.976608 -187.907151)
			(xy 134.00659 -187.90666) (xy 134.87019 -187.90666) (xy 134.900178 -187.907085) (xy 134.95964 -187.914912)
			(xy 135.017571 -187.930433) (xy 135.072981 -187.953384) (xy 135.124922 -187.983371) (xy 135.172504 -188.019881)
			(xy 135.214913 -188.062289) (xy 135.251424 -188.10987) (xy 135.281412 -188.16181) (xy 135.304363 -188.217219)
			(xy 135.319886 -188.275151) (xy 135.327715 -188.334612) (xy 135.327715 -188.394588) (xy 135.319886 -188.454049)
			(xy 135.304363 -188.511981) (xy 135.281412 -188.56739) (xy 135.251424 -188.61933) (xy 135.214913 -188.666911)
			(xy 135.172504 -188.709319) (xy 135.124922 -188.745829) (xy 135.072981 -188.775816) (xy 135.017571 -188.798767)
			(xy 134.95964 -188.814288) (xy 134.900178 -188.822115) (xy 134.87019 -188.822584) (xy 134.00659 -188.822584)
			(xy 133.976608 -188.822049) (xy 133.917156 -188.814221) (xy 133.859235 -188.7987) (xy 133.803835 -188.775752)
			(xy 133.751904 -188.745768) (xy 133.704331 -188.709263) (xy 133.66193 -188.666861) (xy 133.625426 -188.619288)
			(xy 133.595444 -188.567356) (xy 133.572497 -188.511956) (xy 133.556977 -188.454034) (xy 133.54915 -188.394582)
			(xy 132.79518 -188.394582) (xy 132.77852 -188.4348) (xy 132.74853 -188.486742) (xy 132.712017 -188.534325)
			(xy 132.669605 -188.576734) (xy 132.62202 -188.613245) (xy 132.570077 -188.643232) (xy 132.514663 -188.666182)
			(xy 132.456728 -188.681703) (xy 132.397263 -188.689528) (xy 132.367274 -188.689996) (xy 131.503674 -188.689996)
			(xy 131.473693 -188.689436) (xy 131.414244 -188.681607) (xy 131.356326 -188.666085) (xy 131.30093 -188.643136)
			(xy 131.249002 -188.613153) (xy 131.201432 -188.576649) (xy 131.159034 -188.534248) (xy 131.122533 -188.486676)
			(xy 131.092553 -188.434747) (xy 131.069607 -188.379349) (xy 131.054088 -188.32143) (xy 131.046262 -188.261981)
			(xy 130.434185 -188.261981) (xy 130.427555 -188.312342) (xy 130.412034 -188.370269) (xy 130.389084 -188.425675)
			(xy 130.359098 -188.47761) (xy 130.322591 -188.525188) (xy 130.280185 -188.567593) (xy 130.232607 -188.604101)
			(xy 130.180671 -188.634086) (xy 130.125266 -188.657035) (xy 130.067339 -188.672556) (xy 130.007881 -188.680383)
			(xy 129.977896 -188.680852) (xy 129.114296 -188.680852) (xy 129.084311 -188.680382) (xy 129.024855 -188.672554)
			(xy 128.966929 -188.657032) (xy 128.911524 -188.634082) (xy 128.859589 -188.604097) (xy 128.812012 -188.56759)
			(xy 128.769608 -188.525185) (xy 128.733101 -188.477607) (xy 128.703116 -188.425672) (xy 128.680167 -188.370267)
			(xy 128.664646 -188.312341) (xy 128.656818 -188.252885) (xy 4.308094 -188.252885) (xy 4.308094 -195.726088)
			(xy 126.922185 -195.726088) (xy 126.922185 -195.666112) (xy 126.930014 -195.606648) (xy 126.945538 -195.548715)
			(xy 126.968491 -195.493304) (xy 126.99848 -195.441364) (xy 127.034993 -195.393782) (xy 127.077404 -195.351373)
			(xy 127.124989 -195.314864) (xy 127.176931 -195.284878) (xy 127.232344 -195.261928) (xy 127.290278 -195.246408)
			(xy 127.349742 -195.238583) (xy 127.37973 -195.238116) (xy 128.24333 -195.238116) (xy 128.273312 -195.238652)
			(xy 128.332761 -195.246482) (xy 128.39068 -195.262005) (xy 128.446078 -195.284955) (xy 128.498007 -195.314939)
			(xy 128.545577 -195.351444) (xy 128.587976 -195.393845) (xy 128.624478 -195.441418) (xy 128.654459 -195.493349)
			(xy 128.677405 -195.548748) (xy 128.692924 -195.606668) (xy 128.70075 -195.666118) (xy 128.70075 -195.726082)
			(xy 128.692924 -195.785532) (xy 128.677405 -195.843452) (xy 128.654459 -195.898851) (xy 128.624478 -195.950782)
			(xy 128.587976 -195.998355) (xy 128.545577 -196.040756) (xy 128.498007 -196.077261) (xy 128.446078 -196.107245)
			(xy 128.39068 -196.130195) (xy 128.332761 -196.145718) (xy 128.273312 -196.153548) (xy 128.24333 -196.15404)
			(xy 127.37973 -196.15404) (xy 127.349742 -196.153617) (xy 127.290278 -196.145792) (xy 127.232344 -196.130272)
			(xy 127.176931 -196.107322) (xy 127.124989 -196.077336) (xy 127.077404 -196.040827) (xy 127.034993 -195.998418)
			(xy 126.99848 -195.950836) (xy 126.968491 -195.898896) (xy 126.945538 -195.843485) (xy 126.930014 -195.785552)
			(xy 126.922185 -195.726088) (xy 4.308094 -195.726088) (xy 4.308094 -198.543743) (xy 138.243774 -198.543743)
			(xy 138.24519 -198.489257) (xy 138.254343 -198.435528) (xy 138.271047 -198.383647) (xy 138.294963 -198.33467)
			(xy 138.325603 -198.289594) (xy 138.362344 -198.249336) (xy 138.40444 -198.214715) (xy 138.451033 -198.186434)
			(xy 138.501175 -198.165071) (xy 138.553847 -198.151058) (xy 138.607977 -198.144682) (xy 138.635232 -198.144892)
			(xy 138.636502 -198.144892) (xy 139.488672 -198.144892) (xy 139.515926 -198.145353) (xy 139.56988 -198.153107)
			(xy 139.622181 -198.168461) (xy 139.671765 -198.191102) (xy 139.717622 -198.220569) (xy 139.758818 -198.256263)
			(xy 139.794514 -198.297456) (xy 139.823985 -198.34331) (xy 139.846629 -198.392892) (xy 139.861987 -198.445192)
			(xy 139.869745 -198.499146) (xy 139.869745 -198.553654) (xy 139.861987 -198.607608) (xy 139.846629 -198.659908)
			(xy 139.823985 -198.70949) (xy 139.794514 -198.755344) (xy 139.758818 -198.796537) (xy 139.717622 -198.832231)
			(xy 139.671765 -198.861698) (xy 139.622181 -198.884339) (xy 139.56988 -198.899693) (xy 139.515926 -198.907447)
			(xy 139.488672 -198.907908) (xy 139.477343 -198.907862) (xy 139.454723 -198.90659) (xy 139.44346 -198.905368)
			(xy 139.440412 -198.90486) (xy 138.672824 -198.90486) (xy 138.669776 -198.905368) (xy 138.642662 -198.908134)
			(xy 138.588177 -198.906693) (xy 138.534452 -198.897514) (xy 138.482579 -198.880785) (xy 138.433613 -198.856847)
			(xy 138.388552 -198.826185) (xy 138.348311 -198.789424) (xy 138.31371 -198.747312) (xy 138.285452 -198.700706)
			(xy 138.264112 -198.650554) (xy 138.250125 -198.597875) (xy 138.243774 -198.543743) (xy 4.308094 -198.543743)
			(xy 4.308094 -201.379368) (xy 98.428551 -201.379368) (xy 98.428551 -201.324832) (xy 98.436313 -201.270851)
			(xy 98.451678 -201.218525) (xy 98.474333 -201.168917) (xy 98.503818 -201.123039) (xy 98.539531 -201.081824)
			(xy 98.580747 -201.046112) (xy 98.626626 -201.016628) (xy 98.676234 -200.993974) (xy 98.728561 -200.978611)
			(xy 98.782542 -200.970851) (xy 98.80981 -200.970388) (xy 99.67341 -200.970388) (xy 99.700682 -200.970775)
			(xy 99.754672 -200.978539) (xy 99.807007 -200.993907) (xy 99.856623 -201.016567) (xy 99.902508 -201.046057)
			(xy 99.94373 -201.081777) (xy 99.979449 -201.123) (xy 100.008938 -201.168886) (xy 100.031596 -201.218502)
			(xy 100.046963 -201.270838) (xy 100.054725 -201.324828) (xy 100.054725 -201.379372) (xy 100.046963 -201.433362)
			(xy 100.031596 -201.485698) (xy 100.008938 -201.535314) (xy 99.979449 -201.5812) (xy 99.94373 -201.622423)
			(xy 99.902508 -201.658143) (xy 99.856623 -201.687633) (xy 99.807007 -201.710293) (xy 99.754672 -201.725661)
			(xy 99.700682 -201.733425) (xy 99.67341 -201.733912) (xy 98.80981 -201.733912) (xy 98.782542 -201.733349)
			(xy 98.728561 -201.725589) (xy 98.676234 -201.710226) (xy 98.626626 -201.687572) (xy 98.580747 -201.658088)
			(xy 98.539531 -201.622376) (xy 98.503818 -201.581161) (xy 98.474333 -201.535283) (xy 98.451678 -201.485675)
			(xy 98.436313 -201.433349) (xy 98.428551 -201.379368) (xy 4.308094 -201.379368) (xy 4.308094 -209.380836)
			(xy 445.288416 -209.380836) (xy 445.288416 -208.517236) (xy 445.288906 -208.487268) (xy 445.296729 -208.427846)
			(xy 445.312242 -208.369953) (xy 445.335178 -208.31458) (xy 445.365145 -208.262674) (xy 445.401632 -208.215124)
			(xy 445.444012 -208.172744) (xy 445.491562 -208.136257) (xy 445.543468 -208.10629) (xy 445.598841 -208.083354)
			(xy 445.656734 -208.067841) (xy 445.716156 -208.060018) (xy 445.776092 -208.060018) (xy 445.835514 -208.067841)
			(xy 445.893407 -208.083354) (xy 445.94878 -208.10629) (xy 446.000686 -208.136257) (xy 446.048236 -208.172744)
			(xy 446.090616 -208.215124) (xy 446.127103 -208.262674) (xy 446.15707 -208.31458) (xy 446.180006 -208.369953)
			(xy 446.195519 -208.427846) (xy 446.203342 -208.487268) (xy 446.203832 -208.517236) (xy 446.203832 -209.380836)
			(xy 446.203342 -209.410804) (xy 446.195519 -209.470226) (xy 446.180006 -209.528119) (xy 446.15707 -209.583492)
			(xy 446.127103 -209.635398) (xy 446.090616 -209.682948) (xy 446.048236 -209.725328) (xy 446.000686 -209.761815)
			(xy 445.94878 -209.791782) (xy 445.893407 -209.814718) (xy 445.835514 -209.830231) (xy 445.776092 -209.838054)
			(xy 445.716156 -209.838054) (xy 445.656734 -209.830231) (xy 445.598841 -209.814718) (xy 445.543468 -209.791782)
			(xy 445.491562 -209.761815) (xy 445.444012 -209.725328) (xy 445.401632 -209.682948) (xy 445.365145 -209.635398)
			(xy 445.335178 -209.583492) (xy 445.312242 -209.528119) (xy 445.296729 -209.470226) (xy 445.288906 -209.410804)
			(xy 445.288416 -209.380836) (xy 4.308094 -209.380836) (xy 4.308094 -225.261473) (xy 239.822113 -225.261473)
			(xy 239.822113 -225.201527) (xy 239.829938 -225.142093) (xy 239.845454 -225.084189) (xy 239.868395 -225.028806)
			(xy 239.89837 -224.976891) (xy 239.934864 -224.929333) (xy 239.977254 -224.886945) (xy 240.024814 -224.850454)
			(xy 240.076731 -224.820483) (xy 240.132115 -224.797545) (xy 240.19002 -224.782032) (xy 240.249455 -224.774211)
			(xy 240.279428 -224.773744) (xy 241.143028 -224.773744) (xy 241.172991 -224.774332) (xy 241.232405 -224.782157)
			(xy 241.290289 -224.79767) (xy 241.345653 -224.820606) (xy 241.39755 -224.850571) (xy 241.445091 -224.887054)
			(xy 241.487465 -224.92943) (xy 241.523944 -224.976974) (xy 241.553907 -225.028872) (xy 241.576839 -225.084238)
			(xy 241.592348 -225.142123) (xy 241.60017 -225.201537) (xy 241.60017 -225.261463) (xy 241.592348 -225.320877)
			(xy 241.576839 -225.378762) (xy 241.553907 -225.434128) (xy 241.523944 -225.486026) (xy 241.487465 -225.53357)
			(xy 241.445091 -225.575946) (xy 241.39755 -225.612429) (xy 241.345653 -225.642394) (xy 241.290289 -225.66533)
			(xy 241.232405 -225.680843) (xy 241.172991 -225.688668) (xy 241.143028 -225.68916) (xy 240.279428 -225.68916)
			(xy 240.249455 -225.688789) (xy 240.19002 -225.680968) (xy 240.132115 -225.665455) (xy 240.076731 -225.642517)
			(xy 240.024814 -225.612546) (xy 239.977254 -225.576055) (xy 239.934864 -225.533667) (xy 239.89837 -225.486109)
			(xy 239.868395 -225.434194) (xy 239.845454 -225.378811) (xy 239.829938 -225.320907) (xy 239.822113 -225.261473)
			(xy 4.308094 -225.261473) (xy 4.308094 -230.903589) (xy 383.216061 -230.903589) (xy 383.216061 -230.843611)
			(xy 383.22389 -230.784147) (xy 383.239413 -230.726213) (xy 383.262366 -230.670801) (xy 383.292355 -230.618858)
			(xy 383.328867 -230.571275) (xy 383.371278 -230.528865) (xy 383.418862 -230.492353) (xy 383.470804 -230.462364)
			(xy 383.526216 -230.439412) (xy 383.584151 -230.423889) (xy 383.643615 -230.416061) (xy 383.673604 -230.415592)
			(xy 384.537204 -230.415592) (xy 384.567185 -230.416174) (xy 384.626634 -230.424001) (xy 384.684553 -230.439521)
			(xy 384.739951 -230.462468) (xy 384.79188 -230.492449) (xy 384.839451 -230.528952) (xy 384.88185 -230.571352)
			(xy 384.918353 -230.618924) (xy 384.948334 -230.670853) (xy 384.97128 -230.726251) (xy 384.986799 -230.78417)
			(xy 384.994626 -230.843619) (xy 384.994626 -230.903581) (xy 384.986799 -230.96303) (xy 384.97128 -231.020949)
			(xy 384.948334 -231.076347) (xy 384.918353 -231.128276) (xy 384.88185 -231.175848) (xy 384.839451 -231.218248)
			(xy 384.79188 -231.254751) (xy 384.739951 -231.284732) (xy 384.684553 -231.307679) (xy 384.626634 -231.323199)
			(xy 384.567185 -231.331026) (xy 384.537204 -231.331516) (xy 383.673604 -231.331516) (xy 383.643615 -231.331139)
			(xy 383.584151 -231.323311) (xy 383.526216 -231.307788) (xy 383.470804 -231.284836) (xy 383.418862 -231.254847)
			(xy 383.371278 -231.218335) (xy 383.328867 -231.175925) (xy 383.292355 -231.128342) (xy 383.262366 -231.076399)
			(xy 383.239413 -231.020987) (xy 383.22389 -230.963053) (xy 383.216061 -230.903589) (xy 4.308094 -230.903589)
			(xy 4.308094 -234.655869) (xy 448.021157 -234.655869) (xy 448.021157 -234.595931) (xy 448.028981 -234.536505)
			(xy 448.044494 -234.478608) (xy 448.067432 -234.423232) (xy 448.097401 -234.371324) (xy 448.13389 -234.323771)
			(xy 448.176273 -234.281388) (xy 448.223825 -234.2449) (xy 448.275734 -234.214931) (xy 448.33111 -234.191993)
			(xy 448.389007 -234.17648) (xy 448.448433 -234.168657) (xy 448.478402 -234.168188) (xy 449.342002 -234.168188)
			(xy 449.371969 -234.168686) (xy 449.431391 -234.176509) (xy 449.489283 -234.192022) (xy 449.544656 -234.214958)
			(xy 449.596561 -234.244925) (xy 449.64411 -234.281411) (xy 449.68649 -234.323792) (xy 449.722976 -234.371341)
			(xy 449.752943 -234.423246) (xy 449.775879 -234.478618) (xy 449.791391 -234.536511) (xy 449.799214 -234.595933)
			(xy 449.799214 -234.655867) (xy 449.791391 -234.715289) (xy 449.775879 -234.773182) (xy 449.752943 -234.828554)
			(xy 449.722976 -234.880459) (xy 449.68649 -234.928008) (xy 449.64411 -234.970389) (xy 449.596561 -235.006875)
			(xy 449.544656 -235.036842) (xy 449.489283 -235.059778) (xy 449.431391 -235.075291) (xy 449.371969 -235.083114)
			(xy 449.342002 -235.083604) (xy 448.478402 -235.083604) (xy 448.448433 -235.083143) (xy 448.389007 -235.07532)
			(xy 448.33111 -235.059807) (xy 448.275734 -235.036869) (xy 448.223825 -235.0069) (xy 448.176273 -234.970412)
			(xy 448.13389 -234.928029) (xy 448.097401 -234.880476) (xy 448.067432 -234.828568) (xy 448.044494 -234.773192)
			(xy 448.028981 -234.715295) (xy 448.021157 -234.655869) (xy 4.308094 -234.655869) (xy 4.308094 -239.07907)
			(xy 153.398934 -239.07907) (xy 153.398934 -239.01913) (xy 153.406758 -238.959703) (xy 153.422271 -238.901805)
			(xy 153.445208 -238.846427) (xy 153.475178 -238.794517) (xy 153.511666 -238.746963) (xy 153.554049 -238.704578)
			(xy 153.601602 -238.668088) (xy 153.653511 -238.638116) (xy 153.708888 -238.615177) (xy 153.766785 -238.599661)
			(xy 153.826212 -238.591835) (xy 153.856182 -238.591344) (xy 154.719782 -238.591344) (xy 154.749749 -238.591908)
			(xy 154.809169 -238.599729) (xy 154.867061 -238.615239) (xy 154.922433 -238.638172) (xy 154.974337 -238.668138)
			(xy 155.021886 -238.704622) (xy 155.064267 -238.747) (xy 155.100752 -238.794548) (xy 155.13072 -238.846451)
			(xy 155.153656 -238.901822) (xy 155.169168 -238.959713) (xy 155.176991 -239.019133) (xy 155.176991 -239.079067)
			(xy 155.169168 -239.138487) (xy 155.153656 -239.196378) (xy 155.13072 -239.251749) (xy 155.100752 -239.303652)
			(xy 155.064267 -239.3512) (xy 155.021886 -239.393578) (xy 154.974337 -239.430062) (xy 154.922433 -239.460028)
			(xy 154.867061 -239.482961) (xy 154.809169 -239.498471) (xy 154.749749 -239.506292) (xy 154.719782 -239.50676)
			(xy 153.856182 -239.50676) (xy 153.826212 -239.506365) (xy 153.766785 -239.498539) (xy 153.708888 -239.483023)
			(xy 153.653511 -239.460084) (xy 153.601602 -239.430112) (xy 153.554049 -239.393622) (xy 153.511666 -239.351237)
			(xy 153.475178 -239.303683) (xy 153.445208 -239.251773) (xy 153.422271 -239.196395) (xy 153.406758 -239.138497)
			(xy 153.398934 -239.07907) (xy 4.308094 -239.07907) (xy 4.308094 -241.031522) (xy 4.307605 -241.10188)
			(xy 4.299704 -241.242374) (xy 4.283937 -241.382205) (xy 4.260354 -241.52093) (xy 4.229028 -241.658116)
			(xy 4.190059 -241.793328) (xy 4.143568 -241.926143) (xy 4.089703 -242.056141) (xy 4.028633 -242.182915)
			(xy 3.960549 -242.306064) (xy 3.885667 -242.425201) (xy 3.804222 -242.539952) (xy 3.71647 -242.649955)
			(xy 3.622687 -242.754863) (xy 3.573272 -242.80495) (xy 0.94488 -245.433342) (xy 0.907568 -245.471336)
			(xy 0.837834 -245.55183) (xy 0.774017 -245.637091) (xy 0.716442 -245.726686) (xy 0.665403 -245.820159)
			(xy 0.62116 -245.917033) (xy 0.583936 -246.016815) (xy 0.553923 -246.118998) (xy 0.531273 -246.223061)
			(xy 0.5161 -246.328474) (xy 0.508483 -246.4347) (xy 0.508 -246.48795) (xy 0.508 -270.89989) (xy 26.882353 -270.89989)
			(xy 26.886342 -270.75135) (xy 26.898299 -270.603237) (xy 26.918189 -270.45598) (xy 26.945954 -270.310004)
			(xy 26.981515 -270.165727) (xy 27.024769 -270.023568) (xy 27.075591 -269.883935) (xy 27.133835 -269.747232)
			(xy 27.199333 -269.613852) (xy 27.271896 -269.48418) (xy 27.351314 -269.35859) (xy 27.437359 -269.237443)
			(xy 27.529783 -269.12109) (xy 27.628319 -269.009866) (xy 27.732683 -268.904091) (xy 27.842575 -268.804071)
			(xy 27.957676 -268.710093) (xy 28.077656 -268.622429) (xy 28.202169 -268.541332) (xy 28.330855 -268.467035)
			(xy 28.463344 -268.399753) (xy 28.599253 -268.339679) (xy 28.738191 -268.286987) (xy 28.879757 -268.241828)
			(xy 29.023543 -268.204333) (xy 29.169134 -268.174611) (xy 29.31611 -268.152746) (xy 29.464049 -268.138802)
			(xy 29.612522 -268.132818) (xy 29.761103 -268.134813) (xy 29.909362 -268.144781) (xy 30.056873 -268.162692)
			(xy 30.203209 -268.188495) (xy 30.34795 -268.222115) (xy 30.490677 -268.263457) (xy 30.63098 -268.3124)
			(xy 30.768453 -268.368803) (xy 30.9027 -268.432504) (xy 31.033335 -268.50332) (xy 31.15998 -268.581045)
			(xy 31.28227 -268.665456) (xy 31.399853 -268.756309) (xy 31.51239 -268.853343) (xy 31.619557 -268.956278)
			(xy 31.721044 -269.064817) (xy 31.816558 -269.178646) (xy 31.905825 -269.297439) (xy 31.988586 -269.420851)
			(xy 32.064604 -269.548529) (xy 32.133659 -269.680102) (xy 32.195552 -269.815193) (xy 32.250105 -269.95341)
			(xy 32.29716 -270.094357) (xy 32.336582 -270.237627) (xy 32.368256 -270.382806) (xy 32.392092 -270.529475)
			(xy 32.408021 -270.677213) (xy 32.415997 -270.825593) (xy 32.416496 -270.89989) (xy 86.882487 -270.89989)
			(xy 86.886476 -270.75135) (xy 86.898433 -270.603237) (xy 86.918323 -270.45598) (xy 86.946088 -270.310004)
			(xy 86.981649 -270.165727) (xy 87.024903 -270.023568) (xy 87.075725 -269.883935) (xy 87.133969 -269.747232)
			(xy 87.199467 -269.613852) (xy 87.27203 -269.48418) (xy 87.351448 -269.35859) (xy 87.437493 -269.237443)
			(xy 87.529917 -269.12109) (xy 87.628453 -269.009866) (xy 87.732817 -268.904091) (xy 87.842709 -268.804071)
			(xy 87.95781 -268.710093) (xy 88.07779 -268.622429) (xy 88.202303 -268.541332) (xy 88.330989 -268.467035)
			(xy 88.463478 -268.399753) (xy 88.599387 -268.339679) (xy 88.738325 -268.286987) (xy 88.879891 -268.241828)
			(xy 89.023677 -268.204333) (xy 89.169268 -268.174611) (xy 89.316244 -268.152746) (xy 89.464183 -268.138802)
			(xy 89.612656 -268.132818) (xy 89.761237 -268.134813) (xy 89.909496 -268.144781) (xy 90.057007 -268.162692)
			(xy 90.203343 -268.188495) (xy 90.348084 -268.222115) (xy 90.490811 -268.263457) (xy 90.631114 -268.3124)
			(xy 90.768587 -268.368803) (xy 90.902834 -268.432504) (xy 91.033469 -268.50332) (xy 91.160114 -268.581045)
			(xy 91.282404 -268.665456) (xy 91.399987 -268.756309) (xy 91.512524 -268.853343) (xy 91.619691 -268.956278)
			(xy 91.721178 -269.064817) (xy 91.816692 -269.178646) (xy 91.905959 -269.297439) (xy 91.98872 -269.420851)
			(xy 92.064738 -269.548529) (xy 92.133793 -269.680102) (xy 92.195686 -269.815193) (xy 92.250239 -269.95341)
			(xy 92.297294 -270.094357) (xy 92.336716 -270.237627) (xy 92.36839 -270.382806) (xy 92.392226 -270.529475)
			(xy 92.408155 -270.677213) (xy 92.416131 -270.825593) (xy 92.41663 -270.89989) (xy 142.982451 -270.89989)
			(xy 142.98644 -270.75135) (xy 142.998397 -270.603237) (xy 143.018287 -270.45598) (xy 143.046052 -270.310004)
			(xy 143.081613 -270.165727) (xy 143.124867 -270.023568) (xy 143.175689 -269.883935) (xy 143.233933 -269.747232)
			(xy 143.299431 -269.613852) (xy 143.371994 -269.48418) (xy 143.451412 -269.35859) (xy 143.537457 -269.237443)
			(xy 143.629881 -269.12109) (xy 143.728417 -269.009866) (xy 143.832781 -268.904091) (xy 143.942673 -268.804071)
			(xy 144.057774 -268.710093) (xy 144.177754 -268.622429) (xy 144.302267 -268.541332) (xy 144.430953 -268.467035)
			(xy 144.563442 -268.399753) (xy 144.699351 -268.339679) (xy 144.838289 -268.286987) (xy 144.979855 -268.241828)
			(xy 145.123641 -268.204333) (xy 145.269232 -268.174611) (xy 145.416208 -268.152746) (xy 145.564147 -268.138802)
			(xy 145.71262 -268.132818) (xy 145.861201 -268.134813) (xy 146.00946 -268.144781) (xy 146.156971 -268.162692)
			(xy 146.303307 -268.188495) (xy 146.448048 -268.222115) (xy 146.590775 -268.263457) (xy 146.731078 -268.3124)
			(xy 146.868551 -268.368803) (xy 147.002798 -268.432504) (xy 147.133433 -268.50332) (xy 147.260078 -268.581045)
			(xy 147.382368 -268.665456) (xy 147.499951 -268.756309) (xy 147.612488 -268.853343) (xy 147.719655 -268.956278)
			(xy 147.821142 -269.064817) (xy 147.916656 -269.178646) (xy 148.005923 -269.297439) (xy 148.088684 -269.420851)
			(xy 148.164702 -269.548529) (xy 148.233757 -269.680102) (xy 148.29565 -269.815193) (xy 148.350203 -269.95341)
			(xy 148.397258 -270.094357) (xy 148.43668 -270.237627) (xy 148.468354 -270.382806) (xy 148.49219 -270.529475)
			(xy 148.508119 -270.677213) (xy 148.516095 -270.825593) (xy 148.516594 -270.89989) (xy 202.982331 -270.89989)
			(xy 202.98632 -270.75135) (xy 202.998277 -270.603237) (xy 203.018167 -270.45598) (xy 203.045932 -270.310004)
			(xy 203.081493 -270.165727) (xy 203.124747 -270.023568) (xy 203.175569 -269.883935) (xy 203.233813 -269.747232)
			(xy 203.299311 -269.613852) (xy 203.371874 -269.48418) (xy 203.451292 -269.35859) (xy 203.537337 -269.237443)
			(xy 203.629761 -269.12109) (xy 203.728297 -269.009866) (xy 203.832661 -268.904091) (xy 203.942553 -268.804071)
			(xy 204.057654 -268.710093) (xy 204.177634 -268.622429) (xy 204.302147 -268.541332) (xy 204.430833 -268.467035)
			(xy 204.563322 -268.399753) (xy 204.699231 -268.339679) (xy 204.838169 -268.286987) (xy 204.979735 -268.241828)
			(xy 205.123521 -268.204333) (xy 205.269112 -268.174611) (xy 205.416088 -268.152746) (xy 205.564027 -268.138802)
			(xy 205.7125 -268.132818) (xy 205.861081 -268.134813) (xy 206.00934 -268.144781) (xy 206.156851 -268.162692)
			(xy 206.303187 -268.188495) (xy 206.447928 -268.222115) (xy 206.590655 -268.263457) (xy 206.730958 -268.3124)
			(xy 206.868431 -268.368803) (xy 207.002678 -268.432504) (xy 207.133313 -268.50332) (xy 207.259958 -268.581045)
			(xy 207.382248 -268.665456) (xy 207.499831 -268.756309) (xy 207.612368 -268.853343) (xy 207.719535 -268.956278)
			(xy 207.821022 -269.064817) (xy 207.916536 -269.178646) (xy 208.005803 -269.297439) (xy 208.088564 -269.420851)
			(xy 208.164582 -269.548529) (xy 208.233637 -269.680102) (xy 208.29553 -269.815193) (xy 208.350083 -269.95341)
			(xy 208.397138 -270.094357) (xy 208.43656 -270.237627) (xy 208.468234 -270.382806) (xy 208.49207 -270.529475)
			(xy 208.507999 -270.677213) (xy 208.515975 -270.825593) (xy 208.516474 -270.89989) (xy 259.082549 -270.89989)
			(xy 259.086538 -270.75135) (xy 259.098495 -270.603237) (xy 259.118385 -270.45598) (xy 259.14615 -270.310004)
			(xy 259.181711 -270.165727) (xy 259.224965 -270.023568) (xy 259.275787 -269.883935) (xy 259.334031 -269.747232)
			(xy 259.399529 -269.613852) (xy 259.472092 -269.48418) (xy 259.55151 -269.35859) (xy 259.637555 -269.237443)
			(xy 259.729979 -269.12109) (xy 259.828515 -269.009866) (xy 259.932879 -268.904091) (xy 260.042771 -268.804071)
			(xy 260.157872 -268.710093) (xy 260.277852 -268.622429) (xy 260.402365 -268.541332) (xy 260.531051 -268.467035)
			(xy 260.66354 -268.399753) (xy 260.799449 -268.339679) (xy 260.938387 -268.286987) (xy 261.079953 -268.241828)
			(xy 261.223739 -268.204333) (xy 261.36933 -268.174611) (xy 261.516306 -268.152746) (xy 261.664245 -268.138802)
			(xy 261.812718 -268.132818) (xy 261.961299 -268.134813) (xy 262.109558 -268.144781) (xy 262.257069 -268.162692)
			(xy 262.403405 -268.188495) (xy 262.548146 -268.222115) (xy 262.690873 -268.263457) (xy 262.831176 -268.3124)
			(xy 262.968649 -268.368803) (xy 263.102896 -268.432504) (xy 263.233531 -268.50332) (xy 263.360176 -268.581045)
			(xy 263.482466 -268.665456) (xy 263.600049 -268.756309) (xy 263.712586 -268.853343) (xy 263.819753 -268.956278)
			(xy 263.92124 -269.064817) (xy 264.016754 -269.178646) (xy 264.106021 -269.297439) (xy 264.188782 -269.420851)
			(xy 264.2648 -269.548529) (xy 264.333855 -269.680102) (xy 264.395748 -269.815193) (xy 264.450301 -269.95341)
			(xy 264.497356 -270.094357) (xy 264.536778 -270.237627) (xy 264.568452 -270.382806) (xy 264.592288 -270.529475)
			(xy 264.608217 -270.677213) (xy 264.616193 -270.825593) (xy 264.616692 -270.89989) (xy 319.082429 -270.89989)
			(xy 319.086418 -270.75135) (xy 319.098375 -270.603237) (xy 319.118265 -270.45598) (xy 319.14603 -270.310004)
			(xy 319.181591 -270.165727) (xy 319.224845 -270.023568) (xy 319.275667 -269.883935) (xy 319.333911 -269.747232)
			(xy 319.399409 -269.613852) (xy 319.471972 -269.48418) (xy 319.55139 -269.35859) (xy 319.637435 -269.237443)
			(xy 319.729859 -269.12109) (xy 319.828395 -269.009866) (xy 319.932759 -268.904091) (xy 320.042651 -268.804071)
			(xy 320.157752 -268.710093) (xy 320.277732 -268.622429) (xy 320.402245 -268.541332) (xy 320.530931 -268.467035)
			(xy 320.66342 -268.399753) (xy 320.799329 -268.339679) (xy 320.938267 -268.286987) (xy 321.079833 -268.241828)
			(xy 321.223619 -268.204333) (xy 321.36921 -268.174611) (xy 321.516186 -268.152746) (xy 321.664125 -268.138802)
			(xy 321.812598 -268.132818) (xy 321.961179 -268.134813) (xy 322.109438 -268.144781) (xy 322.256949 -268.162692)
			(xy 322.403285 -268.188495) (xy 322.548026 -268.222115) (xy 322.690753 -268.263457) (xy 322.831056 -268.3124)
			(xy 322.968529 -268.368803) (xy 323.102776 -268.432504) (xy 323.233411 -268.50332) (xy 323.360056 -268.581045)
			(xy 323.482346 -268.665456) (xy 323.599929 -268.756309) (xy 323.712466 -268.853343) (xy 323.819633 -268.956278)
			(xy 323.92112 -269.064817) (xy 324.016634 -269.178646) (xy 324.105901 -269.297439) (xy 324.188662 -269.420851)
			(xy 324.26468 -269.548529) (xy 324.333735 -269.680102) (xy 324.395628 -269.815193) (xy 324.450181 -269.95341)
			(xy 324.497236 -270.094357) (xy 324.536658 -270.237627) (xy 324.568332 -270.382806) (xy 324.592168 -270.529475)
			(xy 324.608097 -270.677213) (xy 324.616073 -270.825593) (xy 324.616572 -270.89989) (xy 375.182393 -270.89989)
			(xy 375.186382 -270.75135) (xy 375.198339 -270.603237) (xy 375.218229 -270.45598) (xy 375.245994 -270.310004)
			(xy 375.281555 -270.165727) (xy 375.324809 -270.023568) (xy 375.375631 -269.883935) (xy 375.433875 -269.747232)
			(xy 375.499373 -269.613852) (xy 375.571936 -269.48418) (xy 375.651354 -269.35859) (xy 375.737399 -269.237443)
			(xy 375.829823 -269.12109) (xy 375.928359 -269.009866) (xy 376.032723 -268.904091) (xy 376.142615 -268.804071)
			(xy 376.257716 -268.710093) (xy 376.377696 -268.622429) (xy 376.502209 -268.541332) (xy 376.630895 -268.467035)
			(xy 376.763384 -268.399753) (xy 376.899293 -268.339679) (xy 377.038231 -268.286987) (xy 377.179797 -268.241828)
			(xy 377.323583 -268.204333) (xy 377.469174 -268.174611) (xy 377.61615 -268.152746) (xy 377.764089 -268.138802)
			(xy 377.912562 -268.132818) (xy 378.061143 -268.134813) (xy 378.209402 -268.144781) (xy 378.356913 -268.162692)
			(xy 378.503249 -268.188495) (xy 378.64799 -268.222115) (xy 378.790717 -268.263457) (xy 378.93102 -268.3124)
			(xy 379.068493 -268.368803) (xy 379.20274 -268.432504) (xy 379.333375 -268.50332) (xy 379.46002 -268.581045)
			(xy 379.58231 -268.665456) (xy 379.699893 -268.756309) (xy 379.81243 -268.853343) (xy 379.919597 -268.956278)
			(xy 380.021084 -269.064817) (xy 380.116598 -269.178646) (xy 380.205865 -269.297439) (xy 380.288626 -269.420851)
			(xy 380.364644 -269.548529) (xy 380.433699 -269.680102) (xy 380.495592 -269.815193) (xy 380.550145 -269.95341)
			(xy 380.5972 -270.094357) (xy 380.636622 -270.237627) (xy 380.668296 -270.382806) (xy 380.692132 -270.529475)
			(xy 380.708061 -270.677213) (xy 380.716037 -270.825593) (xy 380.716536 -270.89989) (xy 435.182527 -270.89989)
			(xy 435.186516 -270.75135) (xy 435.198473 -270.603237) (xy 435.218363 -270.45598) (xy 435.246128 -270.310004)
			(xy 435.281689 -270.165727) (xy 435.324943 -270.023568) (xy 435.375765 -269.883935) (xy 435.434009 -269.747232)
			(xy 435.499507 -269.613852) (xy 435.57207 -269.48418) (xy 435.651488 -269.35859) (xy 435.737533 -269.237443)
			(xy 435.829957 -269.12109) (xy 435.928493 -269.009866) (xy 436.032857 -268.904091) (xy 436.142749 -268.804071)
			(xy 436.25785 -268.710093) (xy 436.37783 -268.622429) (xy 436.502343 -268.541332) (xy 436.631029 -268.467035)
			(xy 436.763518 -268.399753) (xy 436.899427 -268.339679) (xy 437.038365 -268.286987) (xy 437.179931 -268.241828)
			(xy 437.323717 -268.204333) (xy 437.469308 -268.174611) (xy 437.616284 -268.152746) (xy 437.764223 -268.138802)
			(xy 437.912696 -268.132818) (xy 438.061277 -268.134813) (xy 438.209536 -268.144781) (xy 438.357047 -268.162692)
			(xy 438.503383 -268.188495) (xy 438.648124 -268.222115) (xy 438.790851 -268.263457) (xy 438.931154 -268.3124)
			(xy 439.068627 -268.368803) (xy 439.202874 -268.432504) (xy 439.333509 -268.50332) (xy 439.460154 -268.581045)
			(xy 439.582444 -268.665456) (xy 439.700027 -268.756309) (xy 439.812564 -268.853343) (xy 439.919731 -268.956278)
			(xy 440.021218 -269.064817) (xy 440.116732 -269.178646) (xy 440.205999 -269.297439) (xy 440.28876 -269.420851)
			(xy 440.364778 -269.548529) (xy 440.433833 -269.680102) (xy 440.495726 -269.815193) (xy 440.550279 -269.95341)
			(xy 440.597334 -270.094357) (xy 440.636756 -270.237627) (xy 440.66843 -270.382806) (xy 440.692266 -270.529475)
			(xy 440.708195 -270.677213) (xy 440.716171 -270.825593) (xy 440.71667 -270.89989) (xy 440.716171 -270.974187)
			(xy 440.708195 -271.122567) (xy 440.692266 -271.270305) (xy 440.66843 -271.416974) (xy 440.636756 -271.562153)
			(xy 440.597334 -271.705423) (xy 440.550279 -271.84637) (xy 440.495726 -271.984587) (xy 440.433833 -272.119678)
			(xy 440.364778 -272.251251) (xy 440.28876 -272.378929) (xy 440.205999 -272.502341) (xy 440.116732 -272.621134)
			(xy 440.021218 -272.734963) (xy 439.919731 -272.843502) (xy 439.812564 -272.946437) (xy 439.700027 -273.043471)
			(xy 439.582444 -273.134324) (xy 439.460154 -273.218735) (xy 439.333509 -273.29646) (xy 439.202874 -273.367276)
			(xy 439.068627 -273.430977) (xy 438.931154 -273.48738) (xy 438.790851 -273.536323) (xy 438.648124 -273.577665)
			(xy 438.503383 -273.611285) (xy 438.357047 -273.637088) (xy 438.209536 -273.654999) (xy 438.061277 -273.664967)
			(xy 437.912696 -273.666962) (xy 437.764223 -273.660978) (xy 437.616284 -273.647034) (xy 437.469308 -273.625169)
			(xy 437.323717 -273.595447) (xy 437.179931 -273.557952) (xy 437.038365 -273.512793) (xy 436.899427 -273.460101)
			(xy 436.763518 -273.400027) (xy 436.631029 -273.332745) (xy 436.502343 -273.258448) (xy 436.37783 -273.177351)
			(xy 436.25785 -273.089687) (xy 436.142749 -272.995709) (xy 436.032857 -272.895689) (xy 435.928493 -272.789914)
			(xy 435.829957 -272.67869) (xy 435.737533 -272.562337) (xy 435.651488 -272.44119) (xy 435.57207 -272.3156)
			(xy 435.499507 -272.185928) (xy 435.434009 -272.052548) (xy 435.375765 -271.915845) (xy 435.324943 -271.776212)
			(xy 435.281689 -271.634053) (xy 435.246128 -271.489776) (xy 435.218363 -271.3438) (xy 435.198473 -271.196543)
			(xy 435.186516 -271.04843) (xy 435.182527 -270.89989) (xy 380.716536 -270.89989) (xy 380.716037 -270.974187)
			(xy 380.708061 -271.122567) (xy 380.692132 -271.270305) (xy 380.668296 -271.416974) (xy 380.636622 -271.562153)
			(xy 380.5972 -271.705423) (xy 380.550145 -271.84637) (xy 380.495592 -271.984587) (xy 380.433699 -272.119678)
			(xy 380.364644 -272.251251) (xy 380.288626 -272.378929) (xy 380.205865 -272.502341) (xy 380.116598 -272.621134)
			(xy 380.021084 -272.734963) (xy 379.919597 -272.843502) (xy 379.81243 -272.946437) (xy 379.699893 -273.043471)
			(xy 379.58231 -273.134324) (xy 379.46002 -273.218735) (xy 379.333375 -273.29646) (xy 379.20274 -273.367276)
			(xy 379.068493 -273.430977) (xy 378.93102 -273.48738) (xy 378.790717 -273.536323) (xy 378.64799 -273.577665)
			(xy 378.503249 -273.611285) (xy 378.356913 -273.637088) (xy 378.209402 -273.654999) (xy 378.061143 -273.664967)
			(xy 377.912562 -273.666962) (xy 377.764089 -273.660978) (xy 377.61615 -273.647034) (xy 377.469174 -273.625169)
			(xy 377.323583 -273.595447) (xy 377.179797 -273.557952) (xy 377.038231 -273.512793) (xy 376.899293 -273.460101)
			(xy 376.763384 -273.400027) (xy 376.630895 -273.332745) (xy 376.502209 -273.258448) (xy 376.377696 -273.177351)
			(xy 376.257716 -273.089687) (xy 376.142615 -272.995709) (xy 376.032723 -272.895689) (xy 375.928359 -272.789914)
			(xy 375.829823 -272.67869) (xy 375.737399 -272.562337) (xy 375.651354 -272.44119) (xy 375.571936 -272.3156)
			(xy 375.499373 -272.185928) (xy 375.433875 -272.052548) (xy 375.375631 -271.915845) (xy 375.324809 -271.776212)
			(xy 375.281555 -271.634053) (xy 375.245994 -271.489776) (xy 375.218229 -271.3438) (xy 375.198339 -271.196543)
			(xy 375.186382 -271.04843) (xy 375.182393 -270.89989) (xy 324.616572 -270.89989) (xy 324.616073 -270.974187)
			(xy 324.608097 -271.122567) (xy 324.592168 -271.270305) (xy 324.568332 -271.416974) (xy 324.536658 -271.562153)
			(xy 324.497236 -271.705423) (xy 324.450181 -271.84637) (xy 324.395628 -271.984587) (xy 324.333735 -272.119678)
			(xy 324.26468 -272.251251) (xy 324.188662 -272.378929) (xy 324.105901 -272.502341) (xy 324.016634 -272.621134)
			(xy 323.92112 -272.734963) (xy 323.819633 -272.843502) (xy 323.712466 -272.946437) (xy 323.599929 -273.043471)
			(xy 323.482346 -273.134324) (xy 323.360056 -273.218735) (xy 323.233411 -273.29646) (xy 323.102776 -273.367276)
			(xy 322.968529 -273.430977) (xy 322.831056 -273.48738) (xy 322.690753 -273.536323) (xy 322.548026 -273.577665)
			(xy 322.403285 -273.611285) (xy 322.256949 -273.637088) (xy 322.109438 -273.654999) (xy 321.961179 -273.664967)
			(xy 321.812598 -273.666962) (xy 321.664125 -273.660978) (xy 321.516186 -273.647034) (xy 321.36921 -273.625169)
			(xy 321.223619 -273.595447) (xy 321.079833 -273.557952) (xy 320.938267 -273.512793) (xy 320.799329 -273.460101)
			(xy 320.66342 -273.400027) (xy 320.530931 -273.332745) (xy 320.402245 -273.258448) (xy 320.277732 -273.177351)
			(xy 320.157752 -273.089687) (xy 320.042651 -272.995709) (xy 319.932759 -272.895689) (xy 319.828395 -272.789914)
			(xy 319.729859 -272.67869) (xy 319.637435 -272.562337) (xy 319.55139 -272.44119) (xy 319.471972 -272.3156)
			(xy 319.399409 -272.185928) (xy 319.333911 -272.052548) (xy 319.275667 -271.915845) (xy 319.224845 -271.776212)
			(xy 319.181591 -271.634053) (xy 319.14603 -271.489776) (xy 319.118265 -271.3438) (xy 319.098375 -271.196543)
			(xy 319.086418 -271.04843) (xy 319.082429 -270.89989) (xy 264.616692 -270.89989) (xy 264.616193 -270.974187)
			(xy 264.608217 -271.122567) (xy 264.592288 -271.270305) (xy 264.568452 -271.416974) (xy 264.536778 -271.562153)
			(xy 264.497356 -271.705423) (xy 264.450301 -271.84637) (xy 264.395748 -271.984587) (xy 264.333855 -272.119678)
			(xy 264.2648 -272.251251) (xy 264.188782 -272.378929) (xy 264.106021 -272.502341) (xy 264.016754 -272.621134)
			(xy 263.92124 -272.734963) (xy 263.819753 -272.843502) (xy 263.712586 -272.946437) (xy 263.600049 -273.043471)
			(xy 263.482466 -273.134324) (xy 263.360176 -273.218735) (xy 263.233531 -273.29646) (xy 263.102896 -273.367276)
			(xy 262.968649 -273.430977) (xy 262.831176 -273.48738) (xy 262.690873 -273.536323) (xy 262.548146 -273.577665)
			(xy 262.403405 -273.611285) (xy 262.257069 -273.637088) (xy 262.109558 -273.654999) (xy 261.961299 -273.664967)
			(xy 261.812718 -273.666962) (xy 261.664245 -273.660978) (xy 261.516306 -273.647034) (xy 261.36933 -273.625169)
			(xy 261.223739 -273.595447) (xy 261.079953 -273.557952) (xy 260.938387 -273.512793) (xy 260.799449 -273.460101)
			(xy 260.66354 -273.400027) (xy 260.531051 -273.332745) (xy 260.402365 -273.258448) (xy 260.277852 -273.177351)
			(xy 260.157872 -273.089687) (xy 260.042771 -272.995709) (xy 259.932879 -272.895689) (xy 259.828515 -272.789914)
			(xy 259.729979 -272.67869) (xy 259.637555 -272.562337) (xy 259.55151 -272.44119) (xy 259.472092 -272.3156)
			(xy 259.399529 -272.185928) (xy 259.334031 -272.052548) (xy 259.275787 -271.915845) (xy 259.224965 -271.776212)
			(xy 259.181711 -271.634053) (xy 259.14615 -271.489776) (xy 259.118385 -271.3438) (xy 259.098495 -271.196543)
			(xy 259.086538 -271.04843) (xy 259.082549 -270.89989) (xy 208.516474 -270.89989) (xy 208.515975 -270.974187)
			(xy 208.507999 -271.122567) (xy 208.49207 -271.270305) (xy 208.468234 -271.416974) (xy 208.43656 -271.562153)
			(xy 208.397138 -271.705423) (xy 208.350083 -271.84637) (xy 208.29553 -271.984587) (xy 208.233637 -272.119678)
			(xy 208.164582 -272.251251) (xy 208.088564 -272.378929) (xy 208.005803 -272.502341) (xy 207.916536 -272.621134)
			(xy 207.821022 -272.734963) (xy 207.719535 -272.843502) (xy 207.612368 -272.946437) (xy 207.499831 -273.043471)
			(xy 207.382248 -273.134324) (xy 207.259958 -273.218735) (xy 207.133313 -273.29646) (xy 207.002678 -273.367276)
			(xy 206.868431 -273.430977) (xy 206.730958 -273.48738) (xy 206.590655 -273.536323) (xy 206.447928 -273.577665)
			(xy 206.303187 -273.611285) (xy 206.156851 -273.637088) (xy 206.00934 -273.654999) (xy 205.861081 -273.664967)
			(xy 205.7125 -273.666962) (xy 205.564027 -273.660978) (xy 205.416088 -273.647034) (xy 205.269112 -273.625169)
			(xy 205.123521 -273.595447) (xy 204.979735 -273.557952) (xy 204.838169 -273.512793) (xy 204.699231 -273.460101)
			(xy 204.563322 -273.400027) (xy 204.430833 -273.332745) (xy 204.302147 -273.258448) (xy 204.177634 -273.177351)
			(xy 204.057654 -273.089687) (xy 203.942553 -272.995709) (xy 203.832661 -272.895689) (xy 203.728297 -272.789914)
			(xy 203.629761 -272.67869) (xy 203.537337 -272.562337) (xy 203.451292 -272.44119) (xy 203.371874 -272.3156)
			(xy 203.299311 -272.185928) (xy 203.233813 -272.052548) (xy 203.175569 -271.915845) (xy 203.124747 -271.776212)
			(xy 203.081493 -271.634053) (xy 203.045932 -271.489776) (xy 203.018167 -271.3438) (xy 202.998277 -271.196543)
			(xy 202.98632 -271.04843) (xy 202.982331 -270.89989) (xy 148.516594 -270.89989) (xy 148.516095 -270.974187)
			(xy 148.508119 -271.122567) (xy 148.49219 -271.270305) (xy 148.468354 -271.416974) (xy 148.43668 -271.562153)
			(xy 148.397258 -271.705423) (xy 148.350203 -271.84637) (xy 148.29565 -271.984587) (xy 148.233757 -272.119678)
			(xy 148.164702 -272.251251) (xy 148.088684 -272.378929) (xy 148.005923 -272.502341) (xy 147.916656 -272.621134)
			(xy 147.821142 -272.734963) (xy 147.719655 -272.843502) (xy 147.612488 -272.946437) (xy 147.499951 -273.043471)
			(xy 147.382368 -273.134324) (xy 147.260078 -273.218735) (xy 147.133433 -273.29646) (xy 147.002798 -273.367276)
			(xy 146.868551 -273.430977) (xy 146.731078 -273.48738) (xy 146.590775 -273.536323) (xy 146.448048 -273.577665)
			(xy 146.303307 -273.611285) (xy 146.156971 -273.637088) (xy 146.00946 -273.654999) (xy 145.861201 -273.664967)
			(xy 145.71262 -273.666962) (xy 145.564147 -273.660978) (xy 145.416208 -273.647034) (xy 145.269232 -273.625169)
			(xy 145.123641 -273.595447) (xy 144.979855 -273.557952) (xy 144.838289 -273.512793) (xy 144.699351 -273.460101)
			(xy 144.563442 -273.400027) (xy 144.430953 -273.332745) (xy 144.302267 -273.258448) (xy 144.177754 -273.177351)
			(xy 144.057774 -273.089687) (xy 143.942673 -272.995709) (xy 143.832781 -272.895689) (xy 143.728417 -272.789914)
			(xy 143.629881 -272.67869) (xy 143.537457 -272.562337) (xy 143.451412 -272.44119) (xy 143.371994 -272.3156)
			(xy 143.299431 -272.185928) (xy 143.233933 -272.052548) (xy 143.175689 -271.915845) (xy 143.124867 -271.776212)
			(xy 143.081613 -271.634053) (xy 143.046052 -271.489776) (xy 143.018287 -271.3438) (xy 142.998397 -271.196543)
			(xy 142.98644 -271.04843) (xy 142.982451 -270.89989) (xy 92.41663 -270.89989) (xy 92.416131 -270.974187)
			(xy 92.408155 -271.122567) (xy 92.392226 -271.270305) (xy 92.36839 -271.416974) (xy 92.336716 -271.562153)
			(xy 92.297294 -271.705423) (xy 92.250239 -271.84637) (xy 92.195686 -271.984587) (xy 92.133793 -272.119678)
			(xy 92.064738 -272.251251) (xy 91.98872 -272.378929) (xy 91.905959 -272.502341) (xy 91.816692 -272.621134)
			(xy 91.721178 -272.734963) (xy 91.619691 -272.843502) (xy 91.512524 -272.946437) (xy 91.399987 -273.043471)
			(xy 91.282404 -273.134324) (xy 91.160114 -273.218735) (xy 91.033469 -273.29646) (xy 90.902834 -273.367276)
			(xy 90.768587 -273.430977) (xy 90.631114 -273.48738) (xy 90.490811 -273.536323) (xy 90.348084 -273.577665)
			(xy 90.203343 -273.611285) (xy 90.057007 -273.637088) (xy 89.909496 -273.654999) (xy 89.761237 -273.664967)
			(xy 89.612656 -273.666962) (xy 89.464183 -273.660978) (xy 89.316244 -273.647034) (xy 89.169268 -273.625169)
			(xy 89.023677 -273.595447) (xy 88.879891 -273.557952) (xy 88.738325 -273.512793) (xy 88.599387 -273.460101)
			(xy 88.463478 -273.400027) (xy 88.330989 -273.332745) (xy 88.202303 -273.258448) (xy 88.07779 -273.177351)
			(xy 87.95781 -273.089687) (xy 87.842709 -272.995709) (xy 87.732817 -272.895689) (xy 87.628453 -272.789914)
			(xy 87.529917 -272.67869) (xy 87.437493 -272.562337) (xy 87.351448 -272.44119) (xy 87.27203 -272.3156)
			(xy 87.199467 -272.185928) (xy 87.133969 -272.052548) (xy 87.075725 -271.915845) (xy 87.024903 -271.776212)
			(xy 86.981649 -271.634053) (xy 86.946088 -271.489776) (xy 86.918323 -271.3438) (xy 86.898433 -271.196543)
			(xy 86.886476 -271.04843) (xy 86.882487 -270.89989) (xy 32.416496 -270.89989) (xy 32.415997 -270.974187)
			(xy 32.408021 -271.122567) (xy 32.392092 -271.270305) (xy 32.368256 -271.416974) (xy 32.336582 -271.562153)
			(xy 32.29716 -271.705423) (xy 32.250105 -271.84637) (xy 32.195552 -271.984587) (xy 32.133659 -272.119678)
			(xy 32.064604 -272.251251) (xy 31.988586 -272.378929) (xy 31.905825 -272.502341) (xy 31.816558 -272.621134)
			(xy 31.721044 -272.734963) (xy 31.619557 -272.843502) (xy 31.51239 -272.946437) (xy 31.399853 -273.043471)
			(xy 31.28227 -273.134324) (xy 31.15998 -273.218735) (xy 31.033335 -273.29646) (xy 30.9027 -273.367276)
			(xy 30.768453 -273.430977) (xy 30.63098 -273.48738) (xy 30.490677 -273.536323) (xy 30.34795 -273.577665)
			(xy 30.203209 -273.611285) (xy 30.056873 -273.637088) (xy 29.909362 -273.654999) (xy 29.761103 -273.664967)
			(xy 29.612522 -273.666962) (xy 29.464049 -273.660978) (xy 29.31611 -273.647034) (xy 29.169134 -273.625169)
			(xy 29.023543 -273.595447) (xy 28.879757 -273.557952) (xy 28.738191 -273.512793) (xy 28.599253 -273.460101)
			(xy 28.463344 -273.400027) (xy 28.330855 -273.332745) (xy 28.202169 -273.258448) (xy 28.077656 -273.177351)
			(xy 27.957676 -273.089687) (xy 27.842575 -272.995709) (xy 27.732683 -272.895689) (xy 27.628319 -272.789914)
			(xy 27.529783 -272.67869) (xy 27.437359 -272.562337) (xy 27.351314 -272.44119) (xy 27.271896 -272.3156)
			(xy 27.199333 -272.185928) (xy 27.133835 -272.052548) (xy 27.075591 -271.915845) (xy 27.024769 -271.776212)
			(xy 26.981515 -271.634053) (xy 26.945954 -271.489776) (xy 26.918189 -271.3438) (xy 26.898299 -271.196543)
			(xy 26.886342 -271.04843) (xy 26.882353 -270.89989) (xy 0.508 -270.89989) (xy 0.508 -277.849838)
			(xy 44.143942 -277.849838) (xy 44.147902 -277.800784) (xy 44.159679 -277.753) (xy 44.17897 -277.707724)
			(xy 44.205273 -277.666128) (xy 44.237908 -277.629291) (xy 44.276029 -277.598166) (xy 44.31865 -277.573559)
			(xy 44.364666 -277.556107) (xy 44.412885 -277.546263) (xy 44.46206 -277.544282) (xy 44.510915 -277.550214)
			(xy 44.558186 -277.563906) (xy 44.602648 -277.585004) (xy 44.643151 -277.61296) (xy 44.678644 -277.647052)
			(xy 44.708209 -277.686396) (xy 44.73108 -277.729973) (xy 44.746664 -277.776654) (xy 44.754559 -277.825231)
			(xy 44.755054 -277.849838) (xy 46.044116 -277.849838) (xy 46.048076 -277.800784) (xy 46.059853 -277.753)
			(xy 46.079144 -277.707724) (xy 46.105447 -277.666128) (xy 46.138082 -277.629291) (xy 46.176203 -277.598166)
			(xy 46.218824 -277.573559) (xy 46.26484 -277.556107) (xy 46.313059 -277.546263) (xy 46.362234 -277.544282)
			(xy 46.411089 -277.550214) (xy 46.45836 -277.563906) (xy 46.502822 -277.585004) (xy 46.543325 -277.61296)
			(xy 46.578818 -277.647052) (xy 46.608383 -277.686396) (xy 46.631254 -277.729973) (xy 46.646838 -277.776654)
			(xy 46.654733 -277.825231) (xy 46.655228 -277.849838) (xy 47.944036 -277.849838) (xy 47.947996 -277.800784)
			(xy 47.959773 -277.753) (xy 47.979064 -277.707724) (xy 48.005367 -277.666128) (xy 48.038002 -277.629291)
			(xy 48.076123 -277.598166) (xy 48.118744 -277.573559) (xy 48.16476 -277.556107) (xy 48.212979 -277.546263)
			(xy 48.262154 -277.544282) (xy 48.311009 -277.550214) (xy 48.35828 -277.563906) (xy 48.402742 -277.585004)
			(xy 48.443245 -277.61296) (xy 48.478738 -277.647052) (xy 48.508303 -277.686396) (xy 48.531174 -277.729973)
			(xy 48.546758 -277.776654) (xy 48.554653 -277.825231) (xy 48.555148 -277.849838) (xy 49.843956 -277.849838)
			(xy 49.847916 -277.800784) (xy 49.859693 -277.753) (xy 49.878984 -277.707724) (xy 49.905287 -277.666128)
			(xy 49.937922 -277.629291) (xy 49.976043 -277.598166) (xy 50.018664 -277.573559) (xy 50.06468 -277.556107)
			(xy 50.112899 -277.546263) (xy 50.162074 -277.544282) (xy 50.210929 -277.550214) (xy 50.2582 -277.563906)
			(xy 50.302662 -277.585004) (xy 50.343165 -277.61296) (xy 50.378658 -277.647052) (xy 50.408223 -277.686396)
			(xy 50.431094 -277.729973) (xy 50.446678 -277.776654) (xy 50.454573 -277.825231) (xy 50.455068 -277.849838)
			(xy 51.74413 -277.849838) (xy 51.74809 -277.800784) (xy 51.759867 -277.753) (xy 51.779158 -277.707724)
			(xy 51.805461 -277.666128) (xy 51.838096 -277.629291) (xy 51.876217 -277.598166) (xy 51.918838 -277.573559)
			(xy 51.964854 -277.556107) (xy 52.013073 -277.546263) (xy 52.062248 -277.544282) (xy 52.111103 -277.550214)
			(xy 52.158374 -277.563906) (xy 52.202836 -277.585004) (xy 52.243339 -277.61296) (xy 52.278832 -277.647052)
			(xy 52.308397 -277.686396) (xy 52.331268 -277.729973) (xy 52.346852 -277.776654) (xy 52.354747 -277.825231)
			(xy 52.355242 -277.849838) (xy 53.64405 -277.849838) (xy 53.64801 -277.800784) (xy 53.659787 -277.753)
			(xy 53.679078 -277.707724) (xy 53.705381 -277.666128) (xy 53.738016 -277.629291) (xy 53.776137 -277.598166)
			(xy 53.818758 -277.573559) (xy 53.864774 -277.556107) (xy 53.912993 -277.546263) (xy 53.962168 -277.544282)
			(xy 54.011023 -277.550214) (xy 54.058294 -277.563906) (xy 54.102756 -277.585004) (xy 54.143259 -277.61296)
			(xy 54.178752 -277.647052) (xy 54.208317 -277.686396) (xy 54.231188 -277.729973) (xy 54.246772 -277.776654)
			(xy 54.254667 -277.825231) (xy 54.255162 -277.849838) (xy 55.54397 -277.849838) (xy 55.54793 -277.800784)
			(xy 55.559707 -277.753) (xy 55.578998 -277.707724) (xy 55.605301 -277.666128) (xy 55.637936 -277.629291)
			(xy 55.676057 -277.598166) (xy 55.718678 -277.573559) (xy 55.764694 -277.556107) (xy 55.812913 -277.546263)
			(xy 55.862088 -277.544282) (xy 55.910943 -277.550214) (xy 55.958214 -277.563906) (xy 56.002676 -277.585004)
			(xy 56.043179 -277.61296) (xy 56.078672 -277.647052) (xy 56.108237 -277.686396) (xy 56.131108 -277.729973)
			(xy 56.146692 -277.776654) (xy 56.154587 -277.825231) (xy 56.155082 -277.849838) (xy 57.444144 -277.849838)
			(xy 57.448104 -277.800784) (xy 57.459881 -277.753) (xy 57.479172 -277.707724) (xy 57.505475 -277.666128)
			(xy 57.53811 -277.629291) (xy 57.576231 -277.598166) (xy 57.618852 -277.573559) (xy 57.664868 -277.556107)
			(xy 57.713087 -277.546263) (xy 57.762262 -277.544282) (xy 57.811117 -277.550214) (xy 57.858388 -277.563906)
			(xy 57.90285 -277.585004) (xy 57.943353 -277.61296) (xy 57.978846 -277.647052) (xy 58.008411 -277.686396)
			(xy 58.031282 -277.729973) (xy 58.046866 -277.776654) (xy 58.054761 -277.825231) (xy 58.055256 -277.849838)
			(xy 160.24404 -277.849838) (xy 160.248 -277.800784) (xy 160.259777 -277.753) (xy 160.279068 -277.707724)
			(xy 160.305371 -277.666128) (xy 160.338006 -277.629291) (xy 160.376127 -277.598166) (xy 160.418748 -277.573559)
			(xy 160.464764 -277.556107) (xy 160.512983 -277.546263) (xy 160.562158 -277.544282) (xy 160.611013 -277.550214)
			(xy 160.658284 -277.563906) (xy 160.702746 -277.585004) (xy 160.743249 -277.61296) (xy 160.778742 -277.647052)
			(xy 160.808307 -277.686396) (xy 160.831178 -277.729973) (xy 160.846762 -277.776654) (xy 160.854657 -277.825231)
			(xy 160.855152 -277.849838) (xy 162.144214 -277.849838) (xy 162.148174 -277.800784) (xy 162.159951 -277.753)
			(xy 162.179242 -277.707724) (xy 162.205545 -277.666128) (xy 162.23818 -277.629291) (xy 162.276301 -277.598166)
			(xy 162.318922 -277.573559) (xy 162.364938 -277.556107) (xy 162.413157 -277.546263) (xy 162.462332 -277.544282)
			(xy 162.511187 -277.550214) (xy 162.558458 -277.563906) (xy 162.60292 -277.585004) (xy 162.643423 -277.61296)
			(xy 162.678916 -277.647052) (xy 162.708481 -277.686396) (xy 162.731352 -277.729973) (xy 162.746936 -277.776654)
			(xy 162.754831 -277.825231) (xy 162.755326 -277.849838) (xy 164.044134 -277.849838) (xy 164.048094 -277.800784)
			(xy 164.059871 -277.753) (xy 164.079162 -277.707724) (xy 164.105465 -277.666128) (xy 164.1381 -277.629291)
			(xy 164.176221 -277.598166) (xy 164.218842 -277.573559) (xy 164.264858 -277.556107) (xy 164.313077 -277.546263)
			(xy 164.362252 -277.544282) (xy 164.411107 -277.550214) (xy 164.458378 -277.563906) (xy 164.50284 -277.585004)
			(xy 164.543343 -277.61296) (xy 164.578836 -277.647052) (xy 164.608401 -277.686396) (xy 164.631272 -277.729973)
			(xy 164.646856 -277.776654) (xy 164.654751 -277.825231) (xy 164.655246 -277.849838) (xy 165.944054 -277.849838)
			(xy 165.948014 -277.800784) (xy 165.959791 -277.753) (xy 165.979082 -277.707724) (xy 166.005385 -277.666128)
			(xy 166.03802 -277.629291) (xy 166.076141 -277.598166) (xy 166.118762 -277.573559) (xy 166.164778 -277.556107)
			(xy 166.212997 -277.546263) (xy 166.262172 -277.544282) (xy 166.311027 -277.550214) (xy 166.358298 -277.563906)
			(xy 166.40276 -277.585004) (xy 166.443263 -277.61296) (xy 166.478756 -277.647052) (xy 166.508321 -277.686396)
			(xy 166.531192 -277.729973) (xy 166.546776 -277.776654) (xy 166.554671 -277.825231) (xy 166.555166 -277.849838)
			(xy 167.844228 -277.849838) (xy 167.848188 -277.800784) (xy 167.859965 -277.753) (xy 167.879256 -277.707724)
			(xy 167.905559 -277.666128) (xy 167.938194 -277.629291) (xy 167.976315 -277.598166) (xy 168.018936 -277.573559)
			(xy 168.064952 -277.556107) (xy 168.113171 -277.546263) (xy 168.162346 -277.544282) (xy 168.211201 -277.550214)
			(xy 168.258472 -277.563906) (xy 168.302934 -277.585004) (xy 168.343437 -277.61296) (xy 168.37893 -277.647052)
			(xy 168.408495 -277.686396) (xy 168.431366 -277.729973) (xy 168.44695 -277.776654) (xy 168.454845 -277.825231)
			(xy 168.45534 -277.849838) (xy 169.744148 -277.849838) (xy 169.748108 -277.800784) (xy 169.759885 -277.753)
			(xy 169.779176 -277.707724) (xy 169.805479 -277.666128) (xy 169.838114 -277.629291) (xy 169.876235 -277.598166)
			(xy 169.918856 -277.573559) (xy 169.964872 -277.556107) (xy 170.013091 -277.546263) (xy 170.062266 -277.544282)
			(xy 170.111121 -277.550214) (xy 170.158392 -277.563906) (xy 170.202854 -277.585004) (xy 170.243357 -277.61296)
			(xy 170.27885 -277.647052) (xy 170.308415 -277.686396) (xy 170.331286 -277.729973) (xy 170.34687 -277.776654)
			(xy 170.354765 -277.825231) (xy 170.35526 -277.849838) (xy 171.644068 -277.849838) (xy 171.648028 -277.800784)
			(xy 171.659805 -277.753) (xy 171.679096 -277.707724) (xy 171.705399 -277.666128) (xy 171.738034 -277.629291)
			(xy 171.776155 -277.598166) (xy 171.818776 -277.573559) (xy 171.864792 -277.556107) (xy 171.913011 -277.546263)
			(xy 171.962186 -277.544282) (xy 172.011041 -277.550214) (xy 172.058312 -277.563906) (xy 172.102774 -277.585004)
			(xy 172.143277 -277.61296) (xy 172.17877 -277.647052) (xy 172.208335 -277.686396) (xy 172.231206 -277.729973)
			(xy 172.24679 -277.776654) (xy 172.254685 -277.825231) (xy 172.25518 -277.849838) (xy 173.544242 -277.849838)
			(xy 173.548202 -277.800784) (xy 173.559979 -277.753) (xy 173.57927 -277.707724) (xy 173.605573 -277.666128)
			(xy 173.638208 -277.629291) (xy 173.676329 -277.598166) (xy 173.71895 -277.573559) (xy 173.764966 -277.556107)
			(xy 173.813185 -277.546263) (xy 173.86236 -277.544282) (xy 173.911215 -277.550214) (xy 173.958486 -277.563906)
			(xy 174.002948 -277.585004) (xy 174.043451 -277.61296) (xy 174.078944 -277.647052) (xy 174.108509 -277.686396)
			(xy 174.13138 -277.729973) (xy 174.146964 -277.776654) (xy 174.154859 -277.825231) (xy 174.155354 -277.849838)
			(xy 276.343884 -277.849838) (xy 276.347844 -277.800784) (xy 276.359621 -277.753) (xy 276.378912 -277.707724)
			(xy 276.405215 -277.666128) (xy 276.43785 -277.629291) (xy 276.475971 -277.598166) (xy 276.518592 -277.573559)
			(xy 276.564608 -277.556107) (xy 276.612827 -277.546263) (xy 276.662002 -277.544282) (xy 276.710857 -277.550214)
			(xy 276.758128 -277.563906) (xy 276.80259 -277.585004) (xy 276.843093 -277.61296) (xy 276.878586 -277.647052)
			(xy 276.908151 -277.686396) (xy 276.931022 -277.729973) (xy 276.946606 -277.776654) (xy 276.954501 -277.825231)
			(xy 276.954996 -277.849838) (xy 278.244058 -277.849838) (xy 278.248018 -277.800784) (xy 278.259795 -277.753)
			(xy 278.279086 -277.707724) (xy 278.305389 -277.666128) (xy 278.338024 -277.629291) (xy 278.376145 -277.598166)
			(xy 278.418766 -277.573559) (xy 278.464782 -277.556107) (xy 278.513001 -277.546263) (xy 278.562176 -277.544282)
			(xy 278.611031 -277.550214) (xy 278.658302 -277.563906) (xy 278.702764 -277.585004) (xy 278.743267 -277.61296)
			(xy 278.77876 -277.647052) (xy 278.808325 -277.686396) (xy 278.831196 -277.729973) (xy 278.84678 -277.776654)
			(xy 278.854675 -277.825231) (xy 278.85517 -277.849838) (xy 280.143978 -277.849838) (xy 280.147938 -277.800784)
			(xy 280.159715 -277.753) (xy 280.179006 -277.707724) (xy 280.205309 -277.666128) (xy 280.237944 -277.629291)
			(xy 280.276065 -277.598166) (xy 280.318686 -277.573559) (xy 280.364702 -277.556107) (xy 280.412921 -277.546263)
			(xy 280.462096 -277.544282) (xy 280.510951 -277.550214) (xy 280.558222 -277.563906) (xy 280.602684 -277.585004)
			(xy 280.643187 -277.61296) (xy 280.67868 -277.647052) (xy 280.708245 -277.686396) (xy 280.731116 -277.729973)
			(xy 280.7467 -277.776654) (xy 280.754595 -277.825231) (xy 280.75509 -277.849838) (xy 282.043898 -277.849838)
			(xy 282.047858 -277.800784) (xy 282.059635 -277.753) (xy 282.078926 -277.707724) (xy 282.105229 -277.666128)
			(xy 282.137864 -277.629291) (xy 282.175985 -277.598166) (xy 282.218606 -277.573559) (xy 282.264622 -277.556107)
			(xy 282.312841 -277.546263) (xy 282.362016 -277.544282) (xy 282.410871 -277.550214) (xy 282.458142 -277.563906)
			(xy 282.502604 -277.585004) (xy 282.543107 -277.61296) (xy 282.5786 -277.647052) (xy 282.608165 -277.686396)
			(xy 282.631036 -277.729973) (xy 282.64662 -277.776654) (xy 282.654515 -277.825231) (xy 282.65501 -277.849838)
			(xy 283.944072 -277.849838) (xy 283.948032 -277.800784) (xy 283.959809 -277.753) (xy 283.9791 -277.707724)
			(xy 284.005403 -277.666128) (xy 284.038038 -277.629291) (xy 284.076159 -277.598166) (xy 284.11878 -277.573559)
			(xy 284.164796 -277.556107) (xy 284.213015 -277.546263) (xy 284.26219 -277.544282) (xy 284.311045 -277.550214)
			(xy 284.358316 -277.563906) (xy 284.402778 -277.585004) (xy 284.443281 -277.61296) (xy 284.478774 -277.647052)
			(xy 284.508339 -277.686396) (xy 284.53121 -277.729973) (xy 284.546794 -277.776654) (xy 284.554689 -277.825231)
			(xy 284.555184 -277.849838) (xy 285.843992 -277.849838) (xy 285.847952 -277.800784) (xy 285.859729 -277.753)
			(xy 285.87902 -277.707724) (xy 285.905323 -277.666128) (xy 285.937958 -277.629291) (xy 285.976079 -277.598166)
			(xy 286.0187 -277.573559) (xy 286.064716 -277.556107) (xy 286.112935 -277.546263) (xy 286.16211 -277.544282)
			(xy 286.210965 -277.550214) (xy 286.258236 -277.563906) (xy 286.302698 -277.585004) (xy 286.343201 -277.61296)
			(xy 286.378694 -277.647052) (xy 286.408259 -277.686396) (xy 286.43113 -277.729973) (xy 286.446714 -277.776654)
			(xy 286.454609 -277.825231) (xy 286.455104 -277.849838) (xy 287.743912 -277.849838) (xy 287.747872 -277.800784)
			(xy 287.759649 -277.753) (xy 287.77894 -277.707724) (xy 287.805243 -277.666128) (xy 287.837878 -277.629291)
			(xy 287.875999 -277.598166) (xy 287.91862 -277.573559) (xy 287.964636 -277.556107) (xy 288.012855 -277.546263)
			(xy 288.06203 -277.544282) (xy 288.110885 -277.550214) (xy 288.158156 -277.563906) (xy 288.202618 -277.585004)
			(xy 288.243121 -277.61296) (xy 288.278614 -277.647052) (xy 288.308179 -277.686396) (xy 288.33105 -277.729973)
			(xy 288.346634 -277.776654) (xy 288.354529 -277.825231) (xy 288.355024 -277.849838) (xy 289.644086 -277.849838)
			(xy 289.648046 -277.800784) (xy 289.659823 -277.753) (xy 289.679114 -277.707724) (xy 289.705417 -277.666128)
			(xy 289.738052 -277.629291) (xy 289.776173 -277.598166) (xy 289.818794 -277.573559) (xy 289.86481 -277.556107)
			(xy 289.913029 -277.546263) (xy 289.962204 -277.544282) (xy 290.011059 -277.550214) (xy 290.05833 -277.563906)
			(xy 290.102792 -277.585004) (xy 290.143295 -277.61296) (xy 290.178788 -277.647052) (xy 290.208353 -277.686396)
			(xy 290.231224 -277.729973) (xy 290.246808 -277.776654) (xy 290.254703 -277.825231) (xy 290.255198 -277.849838)
			(xy 392.443982 -277.849838) (xy 392.447942 -277.800784) (xy 392.459719 -277.753) (xy 392.47901 -277.707724)
			(xy 392.505313 -277.666128) (xy 392.537948 -277.629291) (xy 392.576069 -277.598166) (xy 392.61869 -277.573559)
			(xy 392.664706 -277.556107) (xy 392.712925 -277.546263) (xy 392.7621 -277.544282) (xy 392.810955 -277.550214)
			(xy 392.858226 -277.563906) (xy 392.902688 -277.585004) (xy 392.943191 -277.61296) (xy 392.978684 -277.647052)
			(xy 393.008249 -277.686396) (xy 393.03112 -277.729973) (xy 393.046704 -277.776654) (xy 393.054599 -277.825231)
			(xy 393.055094 -277.849838) (xy 394.344156 -277.849838) (xy 394.348116 -277.800784) (xy 394.359893 -277.753)
			(xy 394.379184 -277.707724) (xy 394.405487 -277.666128) (xy 394.438122 -277.629291) (xy 394.476243 -277.598166)
			(xy 394.518864 -277.573559) (xy 394.56488 -277.556107) (xy 394.613099 -277.546263) (xy 394.662274 -277.544282)
			(xy 394.711129 -277.550214) (xy 394.7584 -277.563906) (xy 394.802862 -277.585004) (xy 394.843365 -277.61296)
			(xy 394.878858 -277.647052) (xy 394.908423 -277.686396) (xy 394.931294 -277.729973) (xy 394.946878 -277.776654)
			(xy 394.954773 -277.825231) (xy 394.955268 -277.849838) (xy 396.244076 -277.849838) (xy 396.248036 -277.800784)
			(xy 396.259813 -277.753) (xy 396.279104 -277.707724) (xy 396.305407 -277.666128) (xy 396.338042 -277.629291)
			(xy 396.376163 -277.598166) (xy 396.418784 -277.573559) (xy 396.4648 -277.556107) (xy 396.513019 -277.546263)
			(xy 396.562194 -277.544282) (xy 396.611049 -277.550214) (xy 396.65832 -277.563906) (xy 396.702782 -277.585004)
			(xy 396.743285 -277.61296) (xy 396.778778 -277.647052) (xy 396.808343 -277.686396) (xy 396.831214 -277.729973)
			(xy 396.846798 -277.776654) (xy 396.854693 -277.825231) (xy 396.855188 -277.849838) (xy 398.143996 -277.849838)
			(xy 398.147956 -277.800784) (xy 398.159733 -277.753) (xy 398.179024 -277.707724) (xy 398.205327 -277.666128)
			(xy 398.237962 -277.629291) (xy 398.276083 -277.598166) (xy 398.318704 -277.573559) (xy 398.36472 -277.556107)
			(xy 398.412939 -277.546263) (xy 398.462114 -277.544282) (xy 398.510969 -277.550214) (xy 398.55824 -277.563906)
			(xy 398.602702 -277.585004) (xy 398.643205 -277.61296) (xy 398.678698 -277.647052) (xy 398.708263 -277.686396)
			(xy 398.731134 -277.729973) (xy 398.746718 -277.776654) (xy 398.754613 -277.825231) (xy 398.755108 -277.849838)
			(xy 400.04417 -277.849838) (xy 400.04813 -277.800784) (xy 400.059907 -277.753) (xy 400.079198 -277.707724)
			(xy 400.105501 -277.666128) (xy 400.138136 -277.629291) (xy 400.176257 -277.598166) (xy 400.218878 -277.573559)
			(xy 400.264894 -277.556107) (xy 400.313113 -277.546263) (xy 400.362288 -277.544282) (xy 400.411143 -277.550214)
			(xy 400.458414 -277.563906) (xy 400.502876 -277.585004) (xy 400.543379 -277.61296) (xy 400.578872 -277.647052)
			(xy 400.608437 -277.686396) (xy 400.631308 -277.729973) (xy 400.646892 -277.776654) (xy 400.654787 -277.825231)
			(xy 400.655282 -277.849838) (xy 401.94409 -277.849838) (xy 401.94805 -277.800784) (xy 401.959827 -277.753)
			(xy 401.979118 -277.707724) (xy 402.005421 -277.666128) (xy 402.038056 -277.629291) (xy 402.076177 -277.598166)
			(xy 402.118798 -277.573559) (xy 402.164814 -277.556107) (xy 402.213033 -277.546263) (xy 402.262208 -277.544282)
			(xy 402.311063 -277.550214) (xy 402.358334 -277.563906) (xy 402.402796 -277.585004) (xy 402.443299 -277.61296)
			(xy 402.478792 -277.647052) (xy 402.508357 -277.686396) (xy 402.531228 -277.729973) (xy 402.546812 -277.776654)
			(xy 402.554707 -277.825231) (xy 402.555202 -277.849838) (xy 403.84401 -277.849838) (xy 403.84797 -277.800784)
			(xy 403.859747 -277.753) (xy 403.879038 -277.707724) (xy 403.905341 -277.666128) (xy 403.937976 -277.629291)
			(xy 403.976097 -277.598166) (xy 404.018718 -277.573559) (xy 404.064734 -277.556107) (xy 404.112953 -277.546263)
			(xy 404.162128 -277.544282) (xy 404.210983 -277.550214) (xy 404.258254 -277.563906) (xy 404.302716 -277.585004)
			(xy 404.343219 -277.61296) (xy 404.378712 -277.647052) (xy 404.408277 -277.686396) (xy 404.431148 -277.729973)
			(xy 404.446732 -277.776654) (xy 404.454627 -277.825231) (xy 404.455122 -277.849838) (xy 405.744184 -277.849838)
			(xy 405.748144 -277.800784) (xy 405.759921 -277.753) (xy 405.779212 -277.707724) (xy 405.805515 -277.666128)
			(xy 405.83815 -277.629291) (xy 405.876271 -277.598166) (xy 405.918892 -277.573559) (xy 405.964908 -277.556107)
			(xy 406.013127 -277.546263) (xy 406.062302 -277.544282) (xy 406.111157 -277.550214) (xy 406.158428 -277.563906)
			(xy 406.20289 -277.585004) (xy 406.243393 -277.61296) (xy 406.278886 -277.647052) (xy 406.308451 -277.686396)
			(xy 406.331322 -277.729973) (xy 406.346906 -277.776654) (xy 406.354801 -277.825231) (xy 406.355296 -277.849838)
			(xy 406.354801 -277.874445) (xy 406.346906 -277.923022) (xy 406.331322 -277.969703) (xy 406.308451 -278.01328)
			(xy 406.278886 -278.052624) (xy 406.243393 -278.086716) (xy 406.20289 -278.114672) (xy 406.158428 -278.13577)
			(xy 406.111157 -278.149462) (xy 406.062302 -278.155394) (xy 406.013127 -278.153413) (xy 405.964908 -278.143569)
			(xy 405.918892 -278.126117) (xy 405.876271 -278.10151) (xy 405.83815 -278.070385) (xy 405.805515 -278.033548)
			(xy 405.779212 -277.991952) (xy 405.759921 -277.946676) (xy 405.748144 -277.898892) (xy 405.744184 -277.849838)
			(xy 404.455122 -277.849838) (xy 404.454627 -277.874445) (xy 404.446732 -277.923022) (xy 404.431148 -277.969703)
			(xy 404.408277 -278.01328) (xy 404.378712 -278.052624) (xy 404.343219 -278.086716) (xy 404.302716 -278.114672)
			(xy 404.258254 -278.13577) (xy 404.210983 -278.149462) (xy 404.162128 -278.155394) (xy 404.112953 -278.153413)
			(xy 404.064734 -278.143569) (xy 404.018718 -278.126117) (xy 403.976097 -278.10151) (xy 403.937976 -278.070385)
			(xy 403.905341 -278.033548) (xy 403.879038 -277.991952) (xy 403.859747 -277.946676) (xy 403.84797 -277.898892)
			(xy 403.84401 -277.849838) (xy 402.555202 -277.849838) (xy 402.554707 -277.874445) (xy 402.546812 -277.923022)
			(xy 402.531228 -277.969703) (xy 402.508357 -278.01328) (xy 402.478792 -278.052624) (xy 402.443299 -278.086716)
			(xy 402.402796 -278.114672) (xy 402.358334 -278.13577) (xy 402.311063 -278.149462) (xy 402.262208 -278.155394)
			(xy 402.213033 -278.153413) (xy 402.164814 -278.143569) (xy 402.118798 -278.126117) (xy 402.076177 -278.10151)
			(xy 402.038056 -278.070385) (xy 402.005421 -278.033548) (xy 401.979118 -277.991952) (xy 401.959827 -277.946676)
			(xy 401.94805 -277.898892) (xy 401.94409 -277.849838) (xy 400.655282 -277.849838) (xy 400.654787 -277.874445)
			(xy 400.646892 -277.923022) (xy 400.631308 -277.969703) (xy 400.608437 -278.01328) (xy 400.578872 -278.052624)
			(xy 400.543379 -278.086716) (xy 400.502876 -278.114672) (xy 400.458414 -278.13577) (xy 400.411143 -278.149462)
			(xy 400.362288 -278.155394) (xy 400.313113 -278.153413) (xy 400.264894 -278.143569) (xy 400.218878 -278.126117)
			(xy 400.176257 -278.10151) (xy 400.138136 -278.070385) (xy 400.105501 -278.033548) (xy 400.079198 -277.991952)
			(xy 400.059907 -277.946676) (xy 400.04813 -277.898892) (xy 400.04417 -277.849838) (xy 398.755108 -277.849838)
			(xy 398.754613 -277.874445) (xy 398.746718 -277.923022) (xy 398.731134 -277.969703) (xy 398.708263 -278.01328)
			(xy 398.678698 -278.052624) (xy 398.643205 -278.086716) (xy 398.602702 -278.114672) (xy 398.55824 -278.13577)
			(xy 398.510969 -278.149462) (xy 398.462114 -278.155394) (xy 398.412939 -278.153413) (xy 398.36472 -278.143569)
			(xy 398.318704 -278.126117) (xy 398.276083 -278.10151) (xy 398.237962 -278.070385) (xy 398.205327 -278.033548)
			(xy 398.179024 -277.991952) (xy 398.159733 -277.946676) (xy 398.147956 -277.898892) (xy 398.143996 -277.849838)
			(xy 396.855188 -277.849838) (xy 396.854693 -277.874445) (xy 396.846798 -277.923022) (xy 396.831214 -277.969703)
			(xy 396.808343 -278.01328) (xy 396.778778 -278.052624) (xy 396.743285 -278.086716) (xy 396.702782 -278.114672)
			(xy 396.65832 -278.13577) (xy 396.611049 -278.149462) (xy 396.562194 -278.155394) (xy 396.513019 -278.153413)
			(xy 396.4648 -278.143569) (xy 396.418784 -278.126117) (xy 396.376163 -278.10151) (xy 396.338042 -278.070385)
			(xy 396.305407 -278.033548) (xy 396.279104 -277.991952) (xy 396.259813 -277.946676) (xy 396.248036 -277.898892)
			(xy 396.244076 -277.849838) (xy 394.955268 -277.849838) (xy 394.954773 -277.874445) (xy 394.946878 -277.923022)
			(xy 394.931294 -277.969703) (xy 394.908423 -278.01328) (xy 394.878858 -278.052624) (xy 394.843365 -278.086716)
			(xy 394.802862 -278.114672) (xy 394.7584 -278.13577) (xy 394.711129 -278.149462) (xy 394.662274 -278.155394)
			(xy 394.613099 -278.153413) (xy 394.56488 -278.143569) (xy 394.518864 -278.126117) (xy 394.476243 -278.10151)
			(xy 394.438122 -278.070385) (xy 394.405487 -278.033548) (xy 394.379184 -277.991952) (xy 394.359893 -277.946676)
			(xy 394.348116 -277.898892) (xy 394.344156 -277.849838) (xy 393.055094 -277.849838) (xy 393.054599 -277.874445)
			(xy 393.046704 -277.923022) (xy 393.03112 -277.969703) (xy 393.008249 -278.01328) (xy 392.978684 -278.052624)
			(xy 392.943191 -278.086716) (xy 392.902688 -278.114672) (xy 392.858226 -278.13577) (xy 392.810955 -278.149462)
			(xy 392.7621 -278.155394) (xy 392.712925 -278.153413) (xy 392.664706 -278.143569) (xy 392.61869 -278.126117)
			(xy 392.576069 -278.10151) (xy 392.537948 -278.070385) (xy 392.505313 -278.033548) (xy 392.47901 -277.991952)
			(xy 392.459719 -277.946676) (xy 392.447942 -277.898892) (xy 392.443982 -277.849838) (xy 290.255198 -277.849838)
			(xy 290.254703 -277.874445) (xy 290.246808 -277.923022) (xy 290.231224 -277.969703) (xy 290.208353 -278.01328)
			(xy 290.178788 -278.052624) (xy 290.143295 -278.086716) (xy 290.102792 -278.114672) (xy 290.05833 -278.13577)
			(xy 290.011059 -278.149462) (xy 289.962204 -278.155394) (xy 289.913029 -278.153413) (xy 289.86481 -278.143569)
			(xy 289.818794 -278.126117) (xy 289.776173 -278.10151) (xy 289.738052 -278.070385) (xy 289.705417 -278.033548)
			(xy 289.679114 -277.991952) (xy 289.659823 -277.946676) (xy 289.648046 -277.898892) (xy 289.644086 -277.849838)
			(xy 288.355024 -277.849838) (xy 288.354529 -277.874445) (xy 288.346634 -277.923022) (xy 288.33105 -277.969703)
			(xy 288.308179 -278.01328) (xy 288.278614 -278.052624) (xy 288.243121 -278.086716) (xy 288.202618 -278.114672)
			(xy 288.158156 -278.13577) (xy 288.110885 -278.149462) (xy 288.06203 -278.155394) (xy 288.012855 -278.153413)
			(xy 287.964636 -278.143569) (xy 287.91862 -278.126117) (xy 287.875999 -278.10151) (xy 287.837878 -278.070385)
			(xy 287.805243 -278.033548) (xy 287.77894 -277.991952) (xy 287.759649 -277.946676) (xy 287.747872 -277.898892)
			(xy 287.743912 -277.849838) (xy 286.455104 -277.849838) (xy 286.454609 -277.874445) (xy 286.446714 -277.923022)
			(xy 286.43113 -277.969703) (xy 286.408259 -278.01328) (xy 286.378694 -278.052624) (xy 286.343201 -278.086716)
			(xy 286.302698 -278.114672) (xy 286.258236 -278.13577) (xy 286.210965 -278.149462) (xy 286.16211 -278.155394)
			(xy 286.112935 -278.153413) (xy 286.064716 -278.143569) (xy 286.0187 -278.126117) (xy 285.976079 -278.10151)
			(xy 285.937958 -278.070385) (xy 285.905323 -278.033548) (xy 285.87902 -277.991952) (xy 285.859729 -277.946676)
			(xy 285.847952 -277.898892) (xy 285.843992 -277.849838) (xy 284.555184 -277.849838) (xy 284.554689 -277.874445)
			(xy 284.546794 -277.923022) (xy 284.53121 -277.969703) (xy 284.508339 -278.01328) (xy 284.478774 -278.052624)
			(xy 284.443281 -278.086716) (xy 284.402778 -278.114672) (xy 284.358316 -278.13577) (xy 284.311045 -278.149462)
			(xy 284.26219 -278.155394) (xy 284.213015 -278.153413) (xy 284.164796 -278.143569) (xy 284.11878 -278.126117)
			(xy 284.076159 -278.10151) (xy 284.038038 -278.070385) (xy 284.005403 -278.033548) (xy 283.9791 -277.991952)
			(xy 283.959809 -277.946676) (xy 283.948032 -277.898892) (xy 283.944072 -277.849838) (xy 282.65501 -277.849838)
			(xy 282.654515 -277.874445) (xy 282.64662 -277.923022) (xy 282.631036 -277.969703) (xy 282.608165 -278.01328)
			(xy 282.5786 -278.052624) (xy 282.543107 -278.086716) (xy 282.502604 -278.114672) (xy 282.458142 -278.13577)
			(xy 282.410871 -278.149462) (xy 282.362016 -278.155394) (xy 282.312841 -278.153413) (xy 282.264622 -278.143569)
			(xy 282.218606 -278.126117) (xy 282.175985 -278.10151) (xy 282.137864 -278.070385) (xy 282.105229 -278.033548)
			(xy 282.078926 -277.991952) (xy 282.059635 -277.946676) (xy 282.047858 -277.898892) (xy 282.043898 -277.849838)
			(xy 280.75509 -277.849838) (xy 280.754595 -277.874445) (xy 280.7467 -277.923022) (xy 280.731116 -277.969703)
			(xy 280.708245 -278.01328) (xy 280.67868 -278.052624) (xy 280.643187 -278.086716) (xy 280.602684 -278.114672)
			(xy 280.558222 -278.13577) (xy 280.510951 -278.149462) (xy 280.462096 -278.155394) (xy 280.412921 -278.153413)
			(xy 280.364702 -278.143569) (xy 280.318686 -278.126117) (xy 280.276065 -278.10151) (xy 280.237944 -278.070385)
			(xy 280.205309 -278.033548) (xy 280.179006 -277.991952) (xy 280.159715 -277.946676) (xy 280.147938 -277.898892)
			(xy 280.143978 -277.849838) (xy 278.85517 -277.849838) (xy 278.854675 -277.874445) (xy 278.84678 -277.923022)
			(xy 278.831196 -277.969703) (xy 278.808325 -278.01328) (xy 278.77876 -278.052624) (xy 278.743267 -278.086716)
			(xy 278.702764 -278.114672) (xy 278.658302 -278.13577) (xy 278.611031 -278.149462) (xy 278.562176 -278.155394)
			(xy 278.513001 -278.153413) (xy 278.464782 -278.143569) (xy 278.418766 -278.126117) (xy 278.376145 -278.10151)
			(xy 278.338024 -278.070385) (xy 278.305389 -278.033548) (xy 278.279086 -277.991952) (xy 278.259795 -277.946676)
			(xy 278.248018 -277.898892) (xy 278.244058 -277.849838) (xy 276.954996 -277.849838) (xy 276.954501 -277.874445)
			(xy 276.946606 -277.923022) (xy 276.931022 -277.969703) (xy 276.908151 -278.01328) (xy 276.878586 -278.052624)
			(xy 276.843093 -278.086716) (xy 276.80259 -278.114672) (xy 276.758128 -278.13577) (xy 276.710857 -278.149462)
			(xy 276.662002 -278.155394) (xy 276.612827 -278.153413) (xy 276.564608 -278.143569) (xy 276.518592 -278.126117)
			(xy 276.475971 -278.10151) (xy 276.43785 -278.070385) (xy 276.405215 -278.033548) (xy 276.378912 -277.991952)
			(xy 276.359621 -277.946676) (xy 276.347844 -277.898892) (xy 276.343884 -277.849838) (xy 174.155354 -277.849838)
			(xy 174.154859 -277.874445) (xy 174.146964 -277.923022) (xy 174.13138 -277.969703) (xy 174.108509 -278.01328)
			(xy 174.078944 -278.052624) (xy 174.043451 -278.086716) (xy 174.002948 -278.114672) (xy 173.958486 -278.13577)
			(xy 173.911215 -278.149462) (xy 173.86236 -278.155394) (xy 173.813185 -278.153413) (xy 173.764966 -278.143569)
			(xy 173.71895 -278.126117) (xy 173.676329 -278.10151) (xy 173.638208 -278.070385) (xy 173.605573 -278.033548)
			(xy 173.57927 -277.991952) (xy 173.559979 -277.946676) (xy 173.548202 -277.898892) (xy 173.544242 -277.849838)
			(xy 172.25518 -277.849838) (xy 172.254685 -277.874445) (xy 172.24679 -277.923022) (xy 172.231206 -277.969703)
			(xy 172.208335 -278.01328) (xy 172.17877 -278.052624) (xy 172.143277 -278.086716) (xy 172.102774 -278.114672)
			(xy 172.058312 -278.13577) (xy 172.011041 -278.149462) (xy 171.962186 -278.155394) (xy 171.913011 -278.153413)
			(xy 171.864792 -278.143569) (xy 171.818776 -278.126117) (xy 171.776155 -278.10151) (xy 171.738034 -278.070385)
			(xy 171.705399 -278.033548) (xy 171.679096 -277.991952) (xy 171.659805 -277.946676) (xy 171.648028 -277.898892)
			(xy 171.644068 -277.849838) (xy 170.35526 -277.849838) (xy 170.354765 -277.874445) (xy 170.34687 -277.923022)
			(xy 170.331286 -277.969703) (xy 170.308415 -278.01328) (xy 170.27885 -278.052624) (xy 170.243357 -278.086716)
			(xy 170.202854 -278.114672) (xy 170.158392 -278.13577) (xy 170.111121 -278.149462) (xy 170.062266 -278.155394)
			(xy 170.013091 -278.153413) (xy 169.964872 -278.143569) (xy 169.918856 -278.126117) (xy 169.876235 -278.10151)
			(xy 169.838114 -278.070385) (xy 169.805479 -278.033548) (xy 169.779176 -277.991952) (xy 169.759885 -277.946676)
			(xy 169.748108 -277.898892) (xy 169.744148 -277.849838) (xy 168.45534 -277.849838) (xy 168.454845 -277.874445)
			(xy 168.44695 -277.923022) (xy 168.431366 -277.969703) (xy 168.408495 -278.01328) (xy 168.37893 -278.052624)
			(xy 168.343437 -278.086716) (xy 168.302934 -278.114672) (xy 168.258472 -278.13577) (xy 168.211201 -278.149462)
			(xy 168.162346 -278.155394) (xy 168.113171 -278.153413) (xy 168.064952 -278.143569) (xy 168.018936 -278.126117)
			(xy 167.976315 -278.10151) (xy 167.938194 -278.070385) (xy 167.905559 -278.033548) (xy 167.879256 -277.991952)
			(xy 167.859965 -277.946676) (xy 167.848188 -277.898892) (xy 167.844228 -277.849838) (xy 166.555166 -277.849838)
			(xy 166.554671 -277.874445) (xy 166.546776 -277.923022) (xy 166.531192 -277.969703) (xy 166.508321 -278.01328)
			(xy 166.478756 -278.052624) (xy 166.443263 -278.086716) (xy 166.40276 -278.114672) (xy 166.358298 -278.13577)
			(xy 166.311027 -278.149462) (xy 166.262172 -278.155394) (xy 166.212997 -278.153413) (xy 166.164778 -278.143569)
			(xy 166.118762 -278.126117) (xy 166.076141 -278.10151) (xy 166.03802 -278.070385) (xy 166.005385 -278.033548)
			(xy 165.979082 -277.991952) (xy 165.959791 -277.946676) (xy 165.948014 -277.898892) (xy 165.944054 -277.849838)
			(xy 164.655246 -277.849838) (xy 164.654751 -277.874445) (xy 164.646856 -277.923022) (xy 164.631272 -277.969703)
			(xy 164.608401 -278.01328) (xy 164.578836 -278.052624) (xy 164.543343 -278.086716) (xy 164.50284 -278.114672)
			(xy 164.458378 -278.13577) (xy 164.411107 -278.149462) (xy 164.362252 -278.155394) (xy 164.313077 -278.153413)
			(xy 164.264858 -278.143569) (xy 164.218842 -278.126117) (xy 164.176221 -278.10151) (xy 164.1381 -278.070385)
			(xy 164.105465 -278.033548) (xy 164.079162 -277.991952) (xy 164.059871 -277.946676) (xy 164.048094 -277.898892)
			(xy 164.044134 -277.849838) (xy 162.755326 -277.849838) (xy 162.754831 -277.874445) (xy 162.746936 -277.923022)
			(xy 162.731352 -277.969703) (xy 162.708481 -278.01328) (xy 162.678916 -278.052624) (xy 162.643423 -278.086716)
			(xy 162.60292 -278.114672) (xy 162.558458 -278.13577) (xy 162.511187 -278.149462) (xy 162.462332 -278.155394)
			(xy 162.413157 -278.153413) (xy 162.364938 -278.143569) (xy 162.318922 -278.126117) (xy 162.276301 -278.10151)
			(xy 162.23818 -278.070385) (xy 162.205545 -278.033548) (xy 162.179242 -277.991952) (xy 162.159951 -277.946676)
			(xy 162.148174 -277.898892) (xy 162.144214 -277.849838) (xy 160.855152 -277.849838) (xy 160.854657 -277.874445)
			(xy 160.846762 -277.923022) (xy 160.831178 -277.969703) (xy 160.808307 -278.01328) (xy 160.778742 -278.052624)
			(xy 160.743249 -278.086716) (xy 160.702746 -278.114672) (xy 160.658284 -278.13577) (xy 160.611013 -278.149462)
			(xy 160.562158 -278.155394) (xy 160.512983 -278.153413) (xy 160.464764 -278.143569) (xy 160.418748 -278.126117)
			(xy 160.376127 -278.10151) (xy 160.338006 -278.070385) (xy 160.305371 -278.033548) (xy 160.279068 -277.991952)
			(xy 160.259777 -277.946676) (xy 160.248 -277.898892) (xy 160.24404 -277.849838) (xy 58.055256 -277.849838)
			(xy 58.054761 -277.874445) (xy 58.046866 -277.923022) (xy 58.031282 -277.969703) (xy 58.008411 -278.01328)
			(xy 57.978846 -278.052624) (xy 57.943353 -278.086716) (xy 57.90285 -278.114672) (xy 57.858388 -278.13577)
			(xy 57.811117 -278.149462) (xy 57.762262 -278.155394) (xy 57.713087 -278.153413) (xy 57.664868 -278.143569)
			(xy 57.618852 -278.126117) (xy 57.576231 -278.10151) (xy 57.53811 -278.070385) (xy 57.505475 -278.033548)
			(xy 57.479172 -277.991952) (xy 57.459881 -277.946676) (xy 57.448104 -277.898892) (xy 57.444144 -277.849838)
			(xy 56.155082 -277.849838) (xy 56.154587 -277.874445) (xy 56.146692 -277.923022) (xy 56.131108 -277.969703)
			(xy 56.108237 -278.01328) (xy 56.078672 -278.052624) (xy 56.043179 -278.086716) (xy 56.002676 -278.114672)
			(xy 55.958214 -278.13577) (xy 55.910943 -278.149462) (xy 55.862088 -278.155394) (xy 55.812913 -278.153413)
			(xy 55.764694 -278.143569) (xy 55.718678 -278.126117) (xy 55.676057 -278.10151) (xy 55.637936 -278.070385)
			(xy 55.605301 -278.033548) (xy 55.578998 -277.991952) (xy 55.559707 -277.946676) (xy 55.54793 -277.898892)
			(xy 55.54397 -277.849838) (xy 54.255162 -277.849838) (xy 54.254667 -277.874445) (xy 54.246772 -277.923022)
			(xy 54.231188 -277.969703) (xy 54.208317 -278.01328) (xy 54.178752 -278.052624) (xy 54.143259 -278.086716)
			(xy 54.102756 -278.114672) (xy 54.058294 -278.13577) (xy 54.011023 -278.149462) (xy 53.962168 -278.155394)
			(xy 53.912993 -278.153413) (xy 53.864774 -278.143569) (xy 53.818758 -278.126117) (xy 53.776137 -278.10151)
			(xy 53.738016 -278.070385) (xy 53.705381 -278.033548) (xy 53.679078 -277.991952) (xy 53.659787 -277.946676)
			(xy 53.64801 -277.898892) (xy 53.64405 -277.849838) (xy 52.355242 -277.849838) (xy 52.354747 -277.874445)
			(xy 52.346852 -277.923022) (xy 52.331268 -277.969703) (xy 52.308397 -278.01328) (xy 52.278832 -278.052624)
			(xy 52.243339 -278.086716) (xy 52.202836 -278.114672) (xy 52.158374 -278.13577) (xy 52.111103 -278.149462)
			(xy 52.062248 -278.155394) (xy 52.013073 -278.153413) (xy 51.964854 -278.143569) (xy 51.918838 -278.126117)
			(xy 51.876217 -278.10151) (xy 51.838096 -278.070385) (xy 51.805461 -278.033548) (xy 51.779158 -277.991952)
			(xy 51.759867 -277.946676) (xy 51.74809 -277.898892) (xy 51.74413 -277.849838) (xy 50.455068 -277.849838)
			(xy 50.454573 -277.874445) (xy 50.446678 -277.923022) (xy 50.431094 -277.969703) (xy 50.408223 -278.01328)
			(xy 50.378658 -278.052624) (xy 50.343165 -278.086716) (xy 50.302662 -278.114672) (xy 50.2582 -278.13577)
			(xy 50.210929 -278.149462) (xy 50.162074 -278.155394) (xy 50.112899 -278.153413) (xy 50.06468 -278.143569)
			(xy 50.018664 -278.126117) (xy 49.976043 -278.10151) (xy 49.937922 -278.070385) (xy 49.905287 -278.033548)
			(xy 49.878984 -277.991952) (xy 49.859693 -277.946676) (xy 49.847916 -277.898892) (xy 49.843956 -277.849838)
			(xy 48.555148 -277.849838) (xy 48.554653 -277.874445) (xy 48.546758 -277.923022) (xy 48.531174 -277.969703)
			(xy 48.508303 -278.01328) (xy 48.478738 -278.052624) (xy 48.443245 -278.086716) (xy 48.402742 -278.114672)
			(xy 48.35828 -278.13577) (xy 48.311009 -278.149462) (xy 48.262154 -278.155394) (xy 48.212979 -278.153413)
			(xy 48.16476 -278.143569) (xy 48.118744 -278.126117) (xy 48.076123 -278.10151) (xy 48.038002 -278.070385)
			(xy 48.005367 -278.033548) (xy 47.979064 -277.991952) (xy 47.959773 -277.946676) (xy 47.947996 -277.898892)
			(xy 47.944036 -277.849838) (xy 46.655228 -277.849838) (xy 46.654733 -277.874445) (xy 46.646838 -277.923022)
			(xy 46.631254 -277.969703) (xy 46.608383 -278.01328) (xy 46.578818 -278.052624) (xy 46.543325 -278.086716)
			(xy 46.502822 -278.114672) (xy 46.45836 -278.13577) (xy 46.411089 -278.149462) (xy 46.362234 -278.155394)
			(xy 46.313059 -278.153413) (xy 46.26484 -278.143569) (xy 46.218824 -278.126117) (xy 46.176203 -278.10151)
			(xy 46.138082 -278.070385) (xy 46.105447 -278.033548) (xy 46.079144 -277.991952) (xy 46.059853 -277.946676)
			(xy 46.048076 -277.898892) (xy 46.044116 -277.849838) (xy 44.755054 -277.849838) (xy 44.754559 -277.874445)
			(xy 44.746664 -277.923022) (xy 44.73108 -277.969703) (xy 44.708209 -278.01328) (xy 44.678644 -278.052624)
			(xy 44.643151 -278.086716) (xy 44.602648 -278.114672) (xy 44.558186 -278.13577) (xy 44.510915 -278.149462)
			(xy 44.46206 -278.155394) (xy 44.412885 -278.153413) (xy 44.364666 -278.143569) (xy 44.31865 -278.126117)
			(xy 44.276029 -278.10151) (xy 44.237908 -278.070385) (xy 44.205273 -278.033548) (xy 44.17897 -277.991952)
			(xy 44.159679 -277.946676) (xy 44.147902 -277.898892) (xy 44.143942 -277.849838) (xy 0.508 -277.849838)
			(xy 0.508 -278.799798) (xy 44.143942 -278.799798) (xy 44.147902 -278.750744) (xy 44.159679 -278.70296)
			(xy 44.17897 -278.657684) (xy 44.205273 -278.616088) (xy 44.237908 -278.579251) (xy 44.276029 -278.548126)
			(xy 44.31865 -278.523519) (xy 44.364666 -278.506067) (xy 44.412885 -278.496223) (xy 44.46206 -278.494242)
			(xy 44.510915 -278.500174) (xy 44.558186 -278.513866) (xy 44.602648 -278.534964) (xy 44.643151 -278.56292)
			(xy 44.678644 -278.597012) (xy 44.708209 -278.636356) (xy 44.73108 -278.679933) (xy 44.746664 -278.726614)
			(xy 44.754559 -278.775191) (xy 44.755054 -278.799798) (xy 46.044116 -278.799798) (xy 46.048076 -278.750744)
			(xy 46.059853 -278.70296) (xy 46.079144 -278.657684) (xy 46.105447 -278.616088) (xy 46.138082 -278.579251)
			(xy 46.176203 -278.548126) (xy 46.218824 -278.523519) (xy 46.26484 -278.506067) (xy 46.313059 -278.496223)
			(xy 46.362234 -278.494242) (xy 46.411089 -278.500174) (xy 46.45836 -278.513866) (xy 46.502822 -278.534964)
			(xy 46.543325 -278.56292) (xy 46.578818 -278.597012) (xy 46.608383 -278.636356) (xy 46.631254 -278.679933)
			(xy 46.646838 -278.726614) (xy 46.654733 -278.775191) (xy 46.655228 -278.799798) (xy 47.944036 -278.799798)
			(xy 47.947996 -278.750744) (xy 47.959773 -278.70296) (xy 47.979064 -278.657684) (xy 48.005367 -278.616088)
			(xy 48.038002 -278.579251) (xy 48.076123 -278.548126) (xy 48.118744 -278.523519) (xy 48.16476 -278.506067)
			(xy 48.212979 -278.496223) (xy 48.262154 -278.494242) (xy 48.311009 -278.500174) (xy 48.35828 -278.513866)
			(xy 48.402742 -278.534964) (xy 48.443245 -278.56292) (xy 48.478738 -278.597012) (xy 48.508303 -278.636356)
			(xy 48.531174 -278.679933) (xy 48.546758 -278.726614) (xy 48.554653 -278.775191) (xy 48.555148 -278.799798)
			(xy 49.843956 -278.799798) (xy 49.847916 -278.750744) (xy 49.859693 -278.70296) (xy 49.878984 -278.657684)
			(xy 49.905287 -278.616088) (xy 49.937922 -278.579251) (xy 49.976043 -278.548126) (xy 50.018664 -278.523519)
			(xy 50.06468 -278.506067) (xy 50.112899 -278.496223) (xy 50.162074 -278.494242) (xy 50.210929 -278.500174)
			(xy 50.2582 -278.513866) (xy 50.302662 -278.534964) (xy 50.343165 -278.56292) (xy 50.378658 -278.597012)
			(xy 50.408223 -278.636356) (xy 50.431094 -278.679933) (xy 50.446678 -278.726614) (xy 50.454573 -278.775191)
			(xy 50.455068 -278.799798) (xy 51.74413 -278.799798) (xy 51.74809 -278.750744) (xy 51.759867 -278.70296)
			(xy 51.779158 -278.657684) (xy 51.805461 -278.616088) (xy 51.838096 -278.579251) (xy 51.876217 -278.548126)
			(xy 51.918838 -278.523519) (xy 51.964854 -278.506067) (xy 52.013073 -278.496223) (xy 52.062248 -278.494242)
			(xy 52.111103 -278.500174) (xy 52.158374 -278.513866) (xy 52.202836 -278.534964) (xy 52.243339 -278.56292)
			(xy 52.278832 -278.597012) (xy 52.308397 -278.636356) (xy 52.331268 -278.679933) (xy 52.346852 -278.726614)
			(xy 52.354747 -278.775191) (xy 52.355242 -278.799798) (xy 53.64405 -278.799798) (xy 53.64801 -278.750744)
			(xy 53.659787 -278.70296) (xy 53.679078 -278.657684) (xy 53.705381 -278.616088) (xy 53.738016 -278.579251)
			(xy 53.776137 -278.548126) (xy 53.818758 -278.523519) (xy 53.864774 -278.506067) (xy 53.912993 -278.496223)
			(xy 53.962168 -278.494242) (xy 54.011023 -278.500174) (xy 54.058294 -278.513866) (xy 54.102756 -278.534964)
			(xy 54.143259 -278.56292) (xy 54.178752 -278.597012) (xy 54.208317 -278.636356) (xy 54.231188 -278.679933)
			(xy 54.246772 -278.726614) (xy 54.254667 -278.775191) (xy 54.255162 -278.799798) (xy 55.54397 -278.799798)
			(xy 55.54793 -278.750744) (xy 55.559707 -278.70296) (xy 55.578998 -278.657684) (xy 55.605301 -278.616088)
			(xy 55.637936 -278.579251) (xy 55.676057 -278.548126) (xy 55.718678 -278.523519) (xy 55.764694 -278.506067)
			(xy 55.812913 -278.496223) (xy 55.862088 -278.494242) (xy 55.910943 -278.500174) (xy 55.958214 -278.513866)
			(xy 56.002676 -278.534964) (xy 56.043179 -278.56292) (xy 56.078672 -278.597012) (xy 56.108237 -278.636356)
			(xy 56.131108 -278.679933) (xy 56.146692 -278.726614) (xy 56.154587 -278.775191) (xy 56.155082 -278.799798)
			(xy 57.444144 -278.799798) (xy 57.448104 -278.750744) (xy 57.459881 -278.70296) (xy 57.479172 -278.657684)
			(xy 57.505475 -278.616088) (xy 57.53811 -278.579251) (xy 57.576231 -278.548126) (xy 57.618852 -278.523519)
			(xy 57.664868 -278.506067) (xy 57.713087 -278.496223) (xy 57.762262 -278.494242) (xy 57.811117 -278.500174)
			(xy 57.858388 -278.513866) (xy 57.90285 -278.534964) (xy 57.943353 -278.56292) (xy 57.978846 -278.597012)
			(xy 58.008411 -278.636356) (xy 58.031282 -278.679933) (xy 58.046866 -278.726614) (xy 58.054761 -278.775191)
			(xy 58.055256 -278.799798) (xy 160.24404 -278.799798) (xy 160.248 -278.750744) (xy 160.259777 -278.70296)
			(xy 160.279068 -278.657684) (xy 160.305371 -278.616088) (xy 160.338006 -278.579251) (xy 160.376127 -278.548126)
			(xy 160.418748 -278.523519) (xy 160.464764 -278.506067) (xy 160.512983 -278.496223) (xy 160.562158 -278.494242)
			(xy 160.611013 -278.500174) (xy 160.658284 -278.513866) (xy 160.702746 -278.534964) (xy 160.743249 -278.56292)
			(xy 160.778742 -278.597012) (xy 160.808307 -278.636356) (xy 160.831178 -278.679933) (xy 160.846762 -278.726614)
			(xy 160.854657 -278.775191) (xy 160.855152 -278.799798) (xy 162.144214 -278.799798) (xy 162.148174 -278.750744)
			(xy 162.159951 -278.70296) (xy 162.179242 -278.657684) (xy 162.205545 -278.616088) (xy 162.23818 -278.579251)
			(xy 162.276301 -278.548126) (xy 162.318922 -278.523519) (xy 162.364938 -278.506067) (xy 162.413157 -278.496223)
			(xy 162.462332 -278.494242) (xy 162.511187 -278.500174) (xy 162.558458 -278.513866) (xy 162.60292 -278.534964)
			(xy 162.643423 -278.56292) (xy 162.678916 -278.597012) (xy 162.708481 -278.636356) (xy 162.731352 -278.679933)
			(xy 162.746936 -278.726614) (xy 162.754831 -278.775191) (xy 162.755326 -278.799798) (xy 164.044134 -278.799798)
			(xy 164.048094 -278.750744) (xy 164.059871 -278.70296) (xy 164.079162 -278.657684) (xy 164.105465 -278.616088)
			(xy 164.1381 -278.579251) (xy 164.176221 -278.548126) (xy 164.218842 -278.523519) (xy 164.264858 -278.506067)
			(xy 164.313077 -278.496223) (xy 164.362252 -278.494242) (xy 164.411107 -278.500174) (xy 164.458378 -278.513866)
			(xy 164.50284 -278.534964) (xy 164.543343 -278.56292) (xy 164.578836 -278.597012) (xy 164.608401 -278.636356)
			(xy 164.631272 -278.679933) (xy 164.646856 -278.726614) (xy 164.654751 -278.775191) (xy 164.655246 -278.799798)
			(xy 165.944054 -278.799798) (xy 165.948014 -278.750744) (xy 165.959791 -278.70296) (xy 165.979082 -278.657684)
			(xy 166.005385 -278.616088) (xy 166.03802 -278.579251) (xy 166.076141 -278.548126) (xy 166.118762 -278.523519)
			(xy 166.164778 -278.506067) (xy 166.212997 -278.496223) (xy 166.262172 -278.494242) (xy 166.311027 -278.500174)
			(xy 166.358298 -278.513866) (xy 166.40276 -278.534964) (xy 166.443263 -278.56292) (xy 166.478756 -278.597012)
			(xy 166.508321 -278.636356) (xy 166.531192 -278.679933) (xy 166.546776 -278.726614) (xy 166.554671 -278.775191)
			(xy 166.555166 -278.799798) (xy 167.844228 -278.799798) (xy 167.848188 -278.750744) (xy 167.859965 -278.70296)
			(xy 167.879256 -278.657684) (xy 167.905559 -278.616088) (xy 167.938194 -278.579251) (xy 167.976315 -278.548126)
			(xy 168.018936 -278.523519) (xy 168.064952 -278.506067) (xy 168.113171 -278.496223) (xy 168.162346 -278.494242)
			(xy 168.211201 -278.500174) (xy 168.258472 -278.513866) (xy 168.302934 -278.534964) (xy 168.343437 -278.56292)
			(xy 168.37893 -278.597012) (xy 168.408495 -278.636356) (xy 168.431366 -278.679933) (xy 168.44695 -278.726614)
			(xy 168.454845 -278.775191) (xy 168.45534 -278.799798) (xy 169.744148 -278.799798) (xy 169.748108 -278.750744)
			(xy 169.759885 -278.70296) (xy 169.779176 -278.657684) (xy 169.805479 -278.616088) (xy 169.838114 -278.579251)
			(xy 169.876235 -278.548126) (xy 169.918856 -278.523519) (xy 169.964872 -278.506067) (xy 170.013091 -278.496223)
			(xy 170.062266 -278.494242) (xy 170.111121 -278.500174) (xy 170.158392 -278.513866) (xy 170.202854 -278.534964)
			(xy 170.243357 -278.56292) (xy 170.27885 -278.597012) (xy 170.308415 -278.636356) (xy 170.331286 -278.679933)
			(xy 170.34687 -278.726614) (xy 170.354765 -278.775191) (xy 170.35526 -278.799798) (xy 171.644068 -278.799798)
			(xy 171.648028 -278.750744) (xy 171.659805 -278.70296) (xy 171.679096 -278.657684) (xy 171.705399 -278.616088)
			(xy 171.738034 -278.579251) (xy 171.776155 -278.548126) (xy 171.818776 -278.523519) (xy 171.864792 -278.506067)
			(xy 171.913011 -278.496223) (xy 171.962186 -278.494242) (xy 172.011041 -278.500174) (xy 172.058312 -278.513866)
			(xy 172.102774 -278.534964) (xy 172.143277 -278.56292) (xy 172.17877 -278.597012) (xy 172.208335 -278.636356)
			(xy 172.231206 -278.679933) (xy 172.24679 -278.726614) (xy 172.254685 -278.775191) (xy 172.25518 -278.799798)
			(xy 173.544242 -278.799798) (xy 173.548202 -278.750744) (xy 173.559979 -278.70296) (xy 173.57927 -278.657684)
			(xy 173.605573 -278.616088) (xy 173.638208 -278.579251) (xy 173.676329 -278.548126) (xy 173.71895 -278.523519)
			(xy 173.764966 -278.506067) (xy 173.813185 -278.496223) (xy 173.86236 -278.494242) (xy 173.911215 -278.500174)
			(xy 173.958486 -278.513866) (xy 174.002948 -278.534964) (xy 174.043451 -278.56292) (xy 174.078944 -278.597012)
			(xy 174.108509 -278.636356) (xy 174.13138 -278.679933) (xy 174.146964 -278.726614) (xy 174.154859 -278.775191)
			(xy 174.155354 -278.799798) (xy 276.343884 -278.799798) (xy 276.347844 -278.750744) (xy 276.359621 -278.70296)
			(xy 276.378912 -278.657684) (xy 276.405215 -278.616088) (xy 276.43785 -278.579251) (xy 276.475971 -278.548126)
			(xy 276.518592 -278.523519) (xy 276.564608 -278.506067) (xy 276.612827 -278.496223) (xy 276.662002 -278.494242)
			(xy 276.710857 -278.500174) (xy 276.758128 -278.513866) (xy 276.80259 -278.534964) (xy 276.843093 -278.56292)
			(xy 276.878586 -278.597012) (xy 276.908151 -278.636356) (xy 276.931022 -278.679933) (xy 276.946606 -278.726614)
			(xy 276.954501 -278.775191) (xy 276.954996 -278.799798) (xy 278.244058 -278.799798) (xy 278.248018 -278.750744)
			(xy 278.259795 -278.70296) (xy 278.279086 -278.657684) (xy 278.305389 -278.616088) (xy 278.338024 -278.579251)
			(xy 278.376145 -278.548126) (xy 278.418766 -278.523519) (xy 278.464782 -278.506067) (xy 278.513001 -278.496223)
			(xy 278.562176 -278.494242) (xy 278.611031 -278.500174) (xy 278.658302 -278.513866) (xy 278.702764 -278.534964)
			(xy 278.743267 -278.56292) (xy 278.77876 -278.597012) (xy 278.808325 -278.636356) (xy 278.831196 -278.679933)
			(xy 278.84678 -278.726614) (xy 278.854675 -278.775191) (xy 278.85517 -278.799798) (xy 280.143978 -278.799798)
			(xy 280.147938 -278.750744) (xy 280.159715 -278.70296) (xy 280.179006 -278.657684) (xy 280.205309 -278.616088)
			(xy 280.237944 -278.579251) (xy 280.276065 -278.548126) (xy 280.318686 -278.523519) (xy 280.364702 -278.506067)
			(xy 280.412921 -278.496223) (xy 280.462096 -278.494242) (xy 280.510951 -278.500174) (xy 280.558222 -278.513866)
			(xy 280.602684 -278.534964) (xy 280.643187 -278.56292) (xy 280.67868 -278.597012) (xy 280.708245 -278.636356)
			(xy 280.731116 -278.679933) (xy 280.7467 -278.726614) (xy 280.754595 -278.775191) (xy 280.75509 -278.799798)
			(xy 282.043898 -278.799798) (xy 282.047858 -278.750744) (xy 282.059635 -278.70296) (xy 282.078926 -278.657684)
			(xy 282.105229 -278.616088) (xy 282.137864 -278.579251) (xy 282.175985 -278.548126) (xy 282.218606 -278.523519)
			(xy 282.264622 -278.506067) (xy 282.312841 -278.496223) (xy 282.362016 -278.494242) (xy 282.410871 -278.500174)
			(xy 282.458142 -278.513866) (xy 282.502604 -278.534964) (xy 282.543107 -278.56292) (xy 282.5786 -278.597012)
			(xy 282.608165 -278.636356) (xy 282.631036 -278.679933) (xy 282.64662 -278.726614) (xy 282.654515 -278.775191)
			(xy 282.65501 -278.799798) (xy 283.944072 -278.799798) (xy 283.948032 -278.750744) (xy 283.959809 -278.70296)
			(xy 283.9791 -278.657684) (xy 284.005403 -278.616088) (xy 284.038038 -278.579251) (xy 284.076159 -278.548126)
			(xy 284.11878 -278.523519) (xy 284.164796 -278.506067) (xy 284.213015 -278.496223) (xy 284.26219 -278.494242)
			(xy 284.311045 -278.500174) (xy 284.358316 -278.513866) (xy 284.402778 -278.534964) (xy 284.443281 -278.56292)
			(xy 284.478774 -278.597012) (xy 284.508339 -278.636356) (xy 284.53121 -278.679933) (xy 284.546794 -278.726614)
			(xy 284.554689 -278.775191) (xy 284.555184 -278.799798) (xy 285.843992 -278.799798) (xy 285.847952 -278.750744)
			(xy 285.859729 -278.70296) (xy 285.87902 -278.657684) (xy 285.905323 -278.616088) (xy 285.937958 -278.579251)
			(xy 285.976079 -278.548126) (xy 286.0187 -278.523519) (xy 286.064716 -278.506067) (xy 286.112935 -278.496223)
			(xy 286.16211 -278.494242) (xy 286.210965 -278.500174) (xy 286.258236 -278.513866) (xy 286.302698 -278.534964)
			(xy 286.343201 -278.56292) (xy 286.378694 -278.597012) (xy 286.408259 -278.636356) (xy 286.43113 -278.679933)
			(xy 286.446714 -278.726614) (xy 286.454609 -278.775191) (xy 286.455104 -278.799798) (xy 287.743912 -278.799798)
			(xy 287.747872 -278.750744) (xy 287.759649 -278.70296) (xy 287.77894 -278.657684) (xy 287.805243 -278.616088)
			(xy 287.837878 -278.579251) (xy 287.875999 -278.548126) (xy 287.91862 -278.523519) (xy 287.964636 -278.506067)
			(xy 288.012855 -278.496223) (xy 288.06203 -278.494242) (xy 288.110885 -278.500174) (xy 288.158156 -278.513866)
			(xy 288.202618 -278.534964) (xy 288.243121 -278.56292) (xy 288.278614 -278.597012) (xy 288.308179 -278.636356)
			(xy 288.33105 -278.679933) (xy 288.346634 -278.726614) (xy 288.354529 -278.775191) (xy 288.355024 -278.799798)
			(xy 289.644086 -278.799798) (xy 289.648046 -278.750744) (xy 289.659823 -278.70296) (xy 289.679114 -278.657684)
			(xy 289.705417 -278.616088) (xy 289.738052 -278.579251) (xy 289.776173 -278.548126) (xy 289.818794 -278.523519)
			(xy 289.86481 -278.506067) (xy 289.913029 -278.496223) (xy 289.962204 -278.494242) (xy 290.011059 -278.500174)
			(xy 290.05833 -278.513866) (xy 290.102792 -278.534964) (xy 290.143295 -278.56292) (xy 290.178788 -278.597012)
			(xy 290.208353 -278.636356) (xy 290.231224 -278.679933) (xy 290.246808 -278.726614) (xy 290.254703 -278.775191)
			(xy 290.255198 -278.799798) (xy 392.443982 -278.799798) (xy 392.447942 -278.750744) (xy 392.459719 -278.70296)
			(xy 392.47901 -278.657684) (xy 392.505313 -278.616088) (xy 392.537948 -278.579251) (xy 392.576069 -278.548126)
			(xy 392.61869 -278.523519) (xy 392.664706 -278.506067) (xy 392.712925 -278.496223) (xy 392.7621 -278.494242)
			(xy 392.810955 -278.500174) (xy 392.858226 -278.513866) (xy 392.902688 -278.534964) (xy 392.943191 -278.56292)
			(xy 392.978684 -278.597012) (xy 393.008249 -278.636356) (xy 393.03112 -278.679933) (xy 393.046704 -278.726614)
			(xy 393.054599 -278.775191) (xy 393.055094 -278.799798) (xy 394.344156 -278.799798) (xy 394.348116 -278.750744)
			(xy 394.359893 -278.70296) (xy 394.379184 -278.657684) (xy 394.405487 -278.616088) (xy 394.438122 -278.579251)
			(xy 394.476243 -278.548126) (xy 394.518864 -278.523519) (xy 394.56488 -278.506067) (xy 394.613099 -278.496223)
			(xy 394.662274 -278.494242) (xy 394.711129 -278.500174) (xy 394.7584 -278.513866) (xy 394.802862 -278.534964)
			(xy 394.843365 -278.56292) (xy 394.878858 -278.597012) (xy 394.908423 -278.636356) (xy 394.931294 -278.679933)
			(xy 394.946878 -278.726614) (xy 394.954773 -278.775191) (xy 394.955268 -278.799798) (xy 396.244076 -278.799798)
			(xy 396.248036 -278.750744) (xy 396.259813 -278.70296) (xy 396.279104 -278.657684) (xy 396.305407 -278.616088)
			(xy 396.338042 -278.579251) (xy 396.376163 -278.548126) (xy 396.418784 -278.523519) (xy 396.4648 -278.506067)
			(xy 396.513019 -278.496223) (xy 396.562194 -278.494242) (xy 396.611049 -278.500174) (xy 396.65832 -278.513866)
			(xy 396.702782 -278.534964) (xy 396.743285 -278.56292) (xy 396.778778 -278.597012) (xy 396.808343 -278.636356)
			(xy 396.831214 -278.679933) (xy 396.846798 -278.726614) (xy 396.854693 -278.775191) (xy 396.855188 -278.799798)
			(xy 398.143996 -278.799798) (xy 398.147956 -278.750744) (xy 398.159733 -278.70296) (xy 398.179024 -278.657684)
			(xy 398.205327 -278.616088) (xy 398.237962 -278.579251) (xy 398.276083 -278.548126) (xy 398.318704 -278.523519)
			(xy 398.36472 -278.506067) (xy 398.412939 -278.496223) (xy 398.462114 -278.494242) (xy 398.510969 -278.500174)
			(xy 398.55824 -278.513866) (xy 398.602702 -278.534964) (xy 398.643205 -278.56292) (xy 398.678698 -278.597012)
			(xy 398.708263 -278.636356) (xy 398.731134 -278.679933) (xy 398.746718 -278.726614) (xy 398.754613 -278.775191)
			(xy 398.755108 -278.799798) (xy 400.04417 -278.799798) (xy 400.04813 -278.750744) (xy 400.059907 -278.70296)
			(xy 400.079198 -278.657684) (xy 400.105501 -278.616088) (xy 400.138136 -278.579251) (xy 400.176257 -278.548126)
			(xy 400.218878 -278.523519) (xy 400.264894 -278.506067) (xy 400.313113 -278.496223) (xy 400.362288 -278.494242)
			(xy 400.411143 -278.500174) (xy 400.458414 -278.513866) (xy 400.502876 -278.534964) (xy 400.543379 -278.56292)
			(xy 400.578872 -278.597012) (xy 400.608437 -278.636356) (xy 400.631308 -278.679933) (xy 400.646892 -278.726614)
			(xy 400.654787 -278.775191) (xy 400.655282 -278.799798) (xy 401.94409 -278.799798) (xy 401.94805 -278.750744)
			(xy 401.959827 -278.70296) (xy 401.979118 -278.657684) (xy 402.005421 -278.616088) (xy 402.038056 -278.579251)
			(xy 402.076177 -278.548126) (xy 402.118798 -278.523519) (xy 402.164814 -278.506067) (xy 402.213033 -278.496223)
			(xy 402.262208 -278.494242) (xy 402.311063 -278.500174) (xy 402.358334 -278.513866) (xy 402.402796 -278.534964)
			(xy 402.443299 -278.56292) (xy 402.478792 -278.597012) (xy 402.508357 -278.636356) (xy 402.531228 -278.679933)
			(xy 402.546812 -278.726614) (xy 402.554707 -278.775191) (xy 402.555202 -278.799798) (xy 403.84401 -278.799798)
			(xy 403.84797 -278.750744) (xy 403.859747 -278.70296) (xy 403.879038 -278.657684) (xy 403.905341 -278.616088)
			(xy 403.937976 -278.579251) (xy 403.976097 -278.548126) (xy 404.018718 -278.523519) (xy 404.064734 -278.506067)
			(xy 404.112953 -278.496223) (xy 404.162128 -278.494242) (xy 404.210983 -278.500174) (xy 404.258254 -278.513866)
			(xy 404.302716 -278.534964) (xy 404.343219 -278.56292) (xy 404.378712 -278.597012) (xy 404.408277 -278.636356)
			(xy 404.431148 -278.679933) (xy 404.446732 -278.726614) (xy 404.454627 -278.775191) (xy 404.455122 -278.799798)
			(xy 405.744184 -278.799798) (xy 405.748144 -278.750744) (xy 405.759921 -278.70296) (xy 405.779212 -278.657684)
			(xy 405.805515 -278.616088) (xy 405.83815 -278.579251) (xy 405.876271 -278.548126) (xy 405.918892 -278.523519)
			(xy 405.964908 -278.506067) (xy 406.013127 -278.496223) (xy 406.062302 -278.494242) (xy 406.111157 -278.500174)
			(xy 406.158428 -278.513866) (xy 406.20289 -278.534964) (xy 406.243393 -278.56292) (xy 406.278886 -278.597012)
			(xy 406.308451 -278.636356) (xy 406.331322 -278.679933) (xy 406.346906 -278.726614) (xy 406.354801 -278.775191)
			(xy 406.355296 -278.799798) (xy 406.354801 -278.824405) (xy 406.346906 -278.872982) (xy 406.331322 -278.919663)
			(xy 406.308451 -278.96324) (xy 406.278886 -279.002584) (xy 406.243393 -279.036676) (xy 406.20289 -279.064632)
			(xy 406.158428 -279.08573) (xy 406.111157 -279.099422) (xy 406.062302 -279.105354) (xy 406.013127 -279.103373)
			(xy 405.964908 -279.093529) (xy 405.918892 -279.076077) (xy 405.876271 -279.05147) (xy 405.83815 -279.020345)
			(xy 405.805515 -278.983508) (xy 405.779212 -278.941912) (xy 405.759921 -278.896636) (xy 405.748144 -278.848852)
			(xy 405.744184 -278.799798) (xy 404.455122 -278.799798) (xy 404.454627 -278.824405) (xy 404.446732 -278.872982)
			(xy 404.431148 -278.919663) (xy 404.408277 -278.96324) (xy 404.378712 -279.002584) (xy 404.343219 -279.036676)
			(xy 404.302716 -279.064632) (xy 404.258254 -279.08573) (xy 404.210983 -279.099422) (xy 404.162128 -279.105354)
			(xy 404.112953 -279.103373) (xy 404.064734 -279.093529) (xy 404.018718 -279.076077) (xy 403.976097 -279.05147)
			(xy 403.937976 -279.020345) (xy 403.905341 -278.983508) (xy 403.879038 -278.941912) (xy 403.859747 -278.896636)
			(xy 403.84797 -278.848852) (xy 403.84401 -278.799798) (xy 402.555202 -278.799798) (xy 402.554707 -278.824405)
			(xy 402.546812 -278.872982) (xy 402.531228 -278.919663) (xy 402.508357 -278.96324) (xy 402.478792 -279.002584)
			(xy 402.443299 -279.036676) (xy 402.402796 -279.064632) (xy 402.358334 -279.08573) (xy 402.311063 -279.099422)
			(xy 402.262208 -279.105354) (xy 402.213033 -279.103373) (xy 402.164814 -279.093529) (xy 402.118798 -279.076077)
			(xy 402.076177 -279.05147) (xy 402.038056 -279.020345) (xy 402.005421 -278.983508) (xy 401.979118 -278.941912)
			(xy 401.959827 -278.896636) (xy 401.94805 -278.848852) (xy 401.94409 -278.799798) (xy 400.655282 -278.799798)
			(xy 400.654787 -278.824405) (xy 400.646892 -278.872982) (xy 400.631308 -278.919663) (xy 400.608437 -278.96324)
			(xy 400.578872 -279.002584) (xy 400.543379 -279.036676) (xy 400.502876 -279.064632) (xy 400.458414 -279.08573)
			(xy 400.411143 -279.099422) (xy 400.362288 -279.105354) (xy 400.313113 -279.103373) (xy 400.264894 -279.093529)
			(xy 400.218878 -279.076077) (xy 400.176257 -279.05147) (xy 400.138136 -279.020345) (xy 400.105501 -278.983508)
			(xy 400.079198 -278.941912) (xy 400.059907 -278.896636) (xy 400.04813 -278.848852) (xy 400.04417 -278.799798)
			(xy 398.755108 -278.799798) (xy 398.754613 -278.824405) (xy 398.746718 -278.872982) (xy 398.731134 -278.919663)
			(xy 398.708263 -278.96324) (xy 398.678698 -279.002584) (xy 398.643205 -279.036676) (xy 398.602702 -279.064632)
			(xy 398.55824 -279.08573) (xy 398.510969 -279.099422) (xy 398.462114 -279.105354) (xy 398.412939 -279.103373)
			(xy 398.36472 -279.093529) (xy 398.318704 -279.076077) (xy 398.276083 -279.05147) (xy 398.237962 -279.020345)
			(xy 398.205327 -278.983508) (xy 398.179024 -278.941912) (xy 398.159733 -278.896636) (xy 398.147956 -278.848852)
			(xy 398.143996 -278.799798) (xy 396.855188 -278.799798) (xy 396.854693 -278.824405) (xy 396.846798 -278.872982)
			(xy 396.831214 -278.919663) (xy 396.808343 -278.96324) (xy 396.778778 -279.002584) (xy 396.743285 -279.036676)
			(xy 396.702782 -279.064632) (xy 396.65832 -279.08573) (xy 396.611049 -279.099422) (xy 396.562194 -279.105354)
			(xy 396.513019 -279.103373) (xy 396.4648 -279.093529) (xy 396.418784 -279.076077) (xy 396.376163 -279.05147)
			(xy 396.338042 -279.020345) (xy 396.305407 -278.983508) (xy 396.279104 -278.941912) (xy 396.259813 -278.896636)
			(xy 396.248036 -278.848852) (xy 396.244076 -278.799798) (xy 394.955268 -278.799798) (xy 394.954773 -278.824405)
			(xy 394.946878 -278.872982) (xy 394.931294 -278.919663) (xy 394.908423 -278.96324) (xy 394.878858 -279.002584)
			(xy 394.843365 -279.036676) (xy 394.802862 -279.064632) (xy 394.7584 -279.08573) (xy 394.711129 -279.099422)
			(xy 394.662274 -279.105354) (xy 394.613099 -279.103373) (xy 394.56488 -279.093529) (xy 394.518864 -279.076077)
			(xy 394.476243 -279.05147) (xy 394.438122 -279.020345) (xy 394.405487 -278.983508) (xy 394.379184 -278.941912)
			(xy 394.359893 -278.896636) (xy 394.348116 -278.848852) (xy 394.344156 -278.799798) (xy 393.055094 -278.799798)
			(xy 393.054599 -278.824405) (xy 393.046704 -278.872982) (xy 393.03112 -278.919663) (xy 393.008249 -278.96324)
			(xy 392.978684 -279.002584) (xy 392.943191 -279.036676) (xy 392.902688 -279.064632) (xy 392.858226 -279.08573)
			(xy 392.810955 -279.099422) (xy 392.7621 -279.105354) (xy 392.712925 -279.103373) (xy 392.664706 -279.093529)
			(xy 392.61869 -279.076077) (xy 392.576069 -279.05147) (xy 392.537948 -279.020345) (xy 392.505313 -278.983508)
			(xy 392.47901 -278.941912) (xy 392.459719 -278.896636) (xy 392.447942 -278.848852) (xy 392.443982 -278.799798)
			(xy 290.255198 -278.799798) (xy 290.254703 -278.824405) (xy 290.246808 -278.872982) (xy 290.231224 -278.919663)
			(xy 290.208353 -278.96324) (xy 290.178788 -279.002584) (xy 290.143295 -279.036676) (xy 290.102792 -279.064632)
			(xy 290.05833 -279.08573) (xy 290.011059 -279.099422) (xy 289.962204 -279.105354) (xy 289.913029 -279.103373)
			(xy 289.86481 -279.093529) (xy 289.818794 -279.076077) (xy 289.776173 -279.05147) (xy 289.738052 -279.020345)
			(xy 289.705417 -278.983508) (xy 289.679114 -278.941912) (xy 289.659823 -278.896636) (xy 289.648046 -278.848852)
			(xy 289.644086 -278.799798) (xy 288.355024 -278.799798) (xy 288.354529 -278.824405) (xy 288.346634 -278.872982)
			(xy 288.33105 -278.919663) (xy 288.308179 -278.96324) (xy 288.278614 -279.002584) (xy 288.243121 -279.036676)
			(xy 288.202618 -279.064632) (xy 288.158156 -279.08573) (xy 288.110885 -279.099422) (xy 288.06203 -279.105354)
			(xy 288.012855 -279.103373) (xy 287.964636 -279.093529) (xy 287.91862 -279.076077) (xy 287.875999 -279.05147)
			(xy 287.837878 -279.020345) (xy 287.805243 -278.983508) (xy 287.77894 -278.941912) (xy 287.759649 -278.896636)
			(xy 287.747872 -278.848852) (xy 287.743912 -278.799798) (xy 286.455104 -278.799798) (xy 286.454609 -278.824405)
			(xy 286.446714 -278.872982) (xy 286.43113 -278.919663) (xy 286.408259 -278.96324) (xy 286.378694 -279.002584)
			(xy 286.343201 -279.036676) (xy 286.302698 -279.064632) (xy 286.258236 -279.08573) (xy 286.210965 -279.099422)
			(xy 286.16211 -279.105354) (xy 286.112935 -279.103373) (xy 286.064716 -279.093529) (xy 286.0187 -279.076077)
			(xy 285.976079 -279.05147) (xy 285.937958 -279.020345) (xy 285.905323 -278.983508) (xy 285.87902 -278.941912)
			(xy 285.859729 -278.896636) (xy 285.847952 -278.848852) (xy 285.843992 -278.799798) (xy 284.555184 -278.799798)
			(xy 284.554689 -278.824405) (xy 284.546794 -278.872982) (xy 284.53121 -278.919663) (xy 284.508339 -278.96324)
			(xy 284.478774 -279.002584) (xy 284.443281 -279.036676) (xy 284.402778 -279.064632) (xy 284.358316 -279.08573)
			(xy 284.311045 -279.099422) (xy 284.26219 -279.105354) (xy 284.213015 -279.103373) (xy 284.164796 -279.093529)
			(xy 284.11878 -279.076077) (xy 284.076159 -279.05147) (xy 284.038038 -279.020345) (xy 284.005403 -278.983508)
			(xy 283.9791 -278.941912) (xy 283.959809 -278.896636) (xy 283.948032 -278.848852) (xy 283.944072 -278.799798)
			(xy 282.65501 -278.799798) (xy 282.654515 -278.824405) (xy 282.64662 -278.872982) (xy 282.631036 -278.919663)
			(xy 282.608165 -278.96324) (xy 282.5786 -279.002584) (xy 282.543107 -279.036676) (xy 282.502604 -279.064632)
			(xy 282.458142 -279.08573) (xy 282.410871 -279.099422) (xy 282.362016 -279.105354) (xy 282.312841 -279.103373)
			(xy 282.264622 -279.093529) (xy 282.218606 -279.076077) (xy 282.175985 -279.05147) (xy 282.137864 -279.020345)
			(xy 282.105229 -278.983508) (xy 282.078926 -278.941912) (xy 282.059635 -278.896636) (xy 282.047858 -278.848852)
			(xy 282.043898 -278.799798) (xy 280.75509 -278.799798) (xy 280.754595 -278.824405) (xy 280.7467 -278.872982)
			(xy 280.731116 -278.919663) (xy 280.708245 -278.96324) (xy 280.67868 -279.002584) (xy 280.643187 -279.036676)
			(xy 280.602684 -279.064632) (xy 280.558222 -279.08573) (xy 280.510951 -279.099422) (xy 280.462096 -279.105354)
			(xy 280.412921 -279.103373) (xy 280.364702 -279.093529) (xy 280.318686 -279.076077) (xy 280.276065 -279.05147)
			(xy 280.237944 -279.020345) (xy 280.205309 -278.983508) (xy 280.179006 -278.941912) (xy 280.159715 -278.896636)
			(xy 280.147938 -278.848852) (xy 280.143978 -278.799798) (xy 278.85517 -278.799798) (xy 278.854675 -278.824405)
			(xy 278.84678 -278.872982) (xy 278.831196 -278.919663) (xy 278.808325 -278.96324) (xy 278.77876 -279.002584)
			(xy 278.743267 -279.036676) (xy 278.702764 -279.064632) (xy 278.658302 -279.08573) (xy 278.611031 -279.099422)
			(xy 278.562176 -279.105354) (xy 278.513001 -279.103373) (xy 278.464782 -279.093529) (xy 278.418766 -279.076077)
			(xy 278.376145 -279.05147) (xy 278.338024 -279.020345) (xy 278.305389 -278.983508) (xy 278.279086 -278.941912)
			(xy 278.259795 -278.896636) (xy 278.248018 -278.848852) (xy 278.244058 -278.799798) (xy 276.954996 -278.799798)
			(xy 276.954501 -278.824405) (xy 276.946606 -278.872982) (xy 276.931022 -278.919663) (xy 276.908151 -278.96324)
			(xy 276.878586 -279.002584) (xy 276.843093 -279.036676) (xy 276.80259 -279.064632) (xy 276.758128 -279.08573)
			(xy 276.710857 -279.099422) (xy 276.662002 -279.105354) (xy 276.612827 -279.103373) (xy 276.564608 -279.093529)
			(xy 276.518592 -279.076077) (xy 276.475971 -279.05147) (xy 276.43785 -279.020345) (xy 276.405215 -278.983508)
			(xy 276.378912 -278.941912) (xy 276.359621 -278.896636) (xy 276.347844 -278.848852) (xy 276.343884 -278.799798)
			(xy 174.155354 -278.799798) (xy 174.154859 -278.824405) (xy 174.146964 -278.872982) (xy 174.13138 -278.919663)
			(xy 174.108509 -278.96324) (xy 174.078944 -279.002584) (xy 174.043451 -279.036676) (xy 174.002948 -279.064632)
			(xy 173.958486 -279.08573) (xy 173.911215 -279.099422) (xy 173.86236 -279.105354) (xy 173.813185 -279.103373)
			(xy 173.764966 -279.093529) (xy 173.71895 -279.076077) (xy 173.676329 -279.05147) (xy 173.638208 -279.020345)
			(xy 173.605573 -278.983508) (xy 173.57927 -278.941912) (xy 173.559979 -278.896636) (xy 173.548202 -278.848852)
			(xy 173.544242 -278.799798) (xy 172.25518 -278.799798) (xy 172.254685 -278.824405) (xy 172.24679 -278.872982)
			(xy 172.231206 -278.919663) (xy 172.208335 -278.96324) (xy 172.17877 -279.002584) (xy 172.143277 -279.036676)
			(xy 172.102774 -279.064632) (xy 172.058312 -279.08573) (xy 172.011041 -279.099422) (xy 171.962186 -279.105354)
			(xy 171.913011 -279.103373) (xy 171.864792 -279.093529) (xy 171.818776 -279.076077) (xy 171.776155 -279.05147)
			(xy 171.738034 -279.020345) (xy 171.705399 -278.983508) (xy 171.679096 -278.941912) (xy 171.659805 -278.896636)
			(xy 171.648028 -278.848852) (xy 171.644068 -278.799798) (xy 170.35526 -278.799798) (xy 170.354765 -278.824405)
			(xy 170.34687 -278.872982) (xy 170.331286 -278.919663) (xy 170.308415 -278.96324) (xy 170.27885 -279.002584)
			(xy 170.243357 -279.036676) (xy 170.202854 -279.064632) (xy 170.158392 -279.08573) (xy 170.111121 -279.099422)
			(xy 170.062266 -279.105354) (xy 170.013091 -279.103373) (xy 169.964872 -279.093529) (xy 169.918856 -279.076077)
			(xy 169.876235 -279.05147) (xy 169.838114 -279.020345) (xy 169.805479 -278.983508) (xy 169.779176 -278.941912)
			(xy 169.759885 -278.896636) (xy 169.748108 -278.848852) (xy 169.744148 -278.799798) (xy 168.45534 -278.799798)
			(xy 168.454845 -278.824405) (xy 168.44695 -278.872982) (xy 168.431366 -278.919663) (xy 168.408495 -278.96324)
			(xy 168.37893 -279.002584) (xy 168.343437 -279.036676) (xy 168.302934 -279.064632) (xy 168.258472 -279.08573)
			(xy 168.211201 -279.099422) (xy 168.162346 -279.105354) (xy 168.113171 -279.103373) (xy 168.064952 -279.093529)
			(xy 168.018936 -279.076077) (xy 167.976315 -279.05147) (xy 167.938194 -279.020345) (xy 167.905559 -278.983508)
			(xy 167.879256 -278.941912) (xy 167.859965 -278.896636) (xy 167.848188 -278.848852) (xy 167.844228 -278.799798)
			(xy 166.555166 -278.799798) (xy 166.554671 -278.824405) (xy 166.546776 -278.872982) (xy 166.531192 -278.919663)
			(xy 166.508321 -278.96324) (xy 166.478756 -279.002584) (xy 166.443263 -279.036676) (xy 166.40276 -279.064632)
			(xy 166.358298 -279.08573) (xy 166.311027 -279.099422) (xy 166.262172 -279.105354) (xy 166.212997 -279.103373)
			(xy 166.164778 -279.093529) (xy 166.118762 -279.076077) (xy 166.076141 -279.05147) (xy 166.03802 -279.020345)
			(xy 166.005385 -278.983508) (xy 165.979082 -278.941912) (xy 165.959791 -278.896636) (xy 165.948014 -278.848852)
			(xy 165.944054 -278.799798) (xy 164.655246 -278.799798) (xy 164.654751 -278.824405) (xy 164.646856 -278.872982)
			(xy 164.631272 -278.919663) (xy 164.608401 -278.96324) (xy 164.578836 -279.002584) (xy 164.543343 -279.036676)
			(xy 164.50284 -279.064632) (xy 164.458378 -279.08573) (xy 164.411107 -279.099422) (xy 164.362252 -279.105354)
			(xy 164.313077 -279.103373) (xy 164.264858 -279.093529) (xy 164.218842 -279.076077) (xy 164.176221 -279.05147)
			(xy 164.1381 -279.020345) (xy 164.105465 -278.983508) (xy 164.079162 -278.941912) (xy 164.059871 -278.896636)
			(xy 164.048094 -278.848852) (xy 164.044134 -278.799798) (xy 162.755326 -278.799798) (xy 162.754831 -278.824405)
			(xy 162.746936 -278.872982) (xy 162.731352 -278.919663) (xy 162.708481 -278.96324) (xy 162.678916 -279.002584)
			(xy 162.643423 -279.036676) (xy 162.60292 -279.064632) (xy 162.558458 -279.08573) (xy 162.511187 -279.099422)
			(xy 162.462332 -279.105354) (xy 162.413157 -279.103373) (xy 162.364938 -279.093529) (xy 162.318922 -279.076077)
			(xy 162.276301 -279.05147) (xy 162.23818 -279.020345) (xy 162.205545 -278.983508) (xy 162.179242 -278.941912)
			(xy 162.159951 -278.896636) (xy 162.148174 -278.848852) (xy 162.144214 -278.799798) (xy 160.855152 -278.799798)
			(xy 160.854657 -278.824405) (xy 160.846762 -278.872982) (xy 160.831178 -278.919663) (xy 160.808307 -278.96324)
			(xy 160.778742 -279.002584) (xy 160.743249 -279.036676) (xy 160.702746 -279.064632) (xy 160.658284 -279.08573)
			(xy 160.611013 -279.099422) (xy 160.562158 -279.105354) (xy 160.512983 -279.103373) (xy 160.464764 -279.093529)
			(xy 160.418748 -279.076077) (xy 160.376127 -279.05147) (xy 160.338006 -279.020345) (xy 160.305371 -278.983508)
			(xy 160.279068 -278.941912) (xy 160.259777 -278.896636) (xy 160.248 -278.848852) (xy 160.24404 -278.799798)
			(xy 58.055256 -278.799798) (xy 58.054761 -278.824405) (xy 58.046866 -278.872982) (xy 58.031282 -278.919663)
			(xy 58.008411 -278.96324) (xy 57.978846 -279.002584) (xy 57.943353 -279.036676) (xy 57.90285 -279.064632)
			(xy 57.858388 -279.08573) (xy 57.811117 -279.099422) (xy 57.762262 -279.105354) (xy 57.713087 -279.103373)
			(xy 57.664868 -279.093529) (xy 57.618852 -279.076077) (xy 57.576231 -279.05147) (xy 57.53811 -279.020345)
			(xy 57.505475 -278.983508) (xy 57.479172 -278.941912) (xy 57.459881 -278.896636) (xy 57.448104 -278.848852)
			(xy 57.444144 -278.799798) (xy 56.155082 -278.799798) (xy 56.154587 -278.824405) (xy 56.146692 -278.872982)
			(xy 56.131108 -278.919663) (xy 56.108237 -278.96324) (xy 56.078672 -279.002584) (xy 56.043179 -279.036676)
			(xy 56.002676 -279.064632) (xy 55.958214 -279.08573) (xy 55.910943 -279.099422) (xy 55.862088 -279.105354)
			(xy 55.812913 -279.103373) (xy 55.764694 -279.093529) (xy 55.718678 -279.076077) (xy 55.676057 -279.05147)
			(xy 55.637936 -279.020345) (xy 55.605301 -278.983508) (xy 55.578998 -278.941912) (xy 55.559707 -278.896636)
			(xy 55.54793 -278.848852) (xy 55.54397 -278.799798) (xy 54.255162 -278.799798) (xy 54.254667 -278.824405)
			(xy 54.246772 -278.872982) (xy 54.231188 -278.919663) (xy 54.208317 -278.96324) (xy 54.178752 -279.002584)
			(xy 54.143259 -279.036676) (xy 54.102756 -279.064632) (xy 54.058294 -279.08573) (xy 54.011023 -279.099422)
			(xy 53.962168 -279.105354) (xy 53.912993 -279.103373) (xy 53.864774 -279.093529) (xy 53.818758 -279.076077)
			(xy 53.776137 -279.05147) (xy 53.738016 -279.020345) (xy 53.705381 -278.983508) (xy 53.679078 -278.941912)
			(xy 53.659787 -278.896636) (xy 53.64801 -278.848852) (xy 53.64405 -278.799798) (xy 52.355242 -278.799798)
			(xy 52.354747 -278.824405) (xy 52.346852 -278.872982) (xy 52.331268 -278.919663) (xy 52.308397 -278.96324)
			(xy 52.278832 -279.002584) (xy 52.243339 -279.036676) (xy 52.202836 -279.064632) (xy 52.158374 -279.08573)
			(xy 52.111103 -279.099422) (xy 52.062248 -279.105354) (xy 52.013073 -279.103373) (xy 51.964854 -279.093529)
			(xy 51.918838 -279.076077) (xy 51.876217 -279.05147) (xy 51.838096 -279.020345) (xy 51.805461 -278.983508)
			(xy 51.779158 -278.941912) (xy 51.759867 -278.896636) (xy 51.74809 -278.848852) (xy 51.74413 -278.799798)
			(xy 50.455068 -278.799798) (xy 50.454573 -278.824405) (xy 50.446678 -278.872982) (xy 50.431094 -278.919663)
			(xy 50.408223 -278.96324) (xy 50.378658 -279.002584) (xy 50.343165 -279.036676) (xy 50.302662 -279.064632)
			(xy 50.2582 -279.08573) (xy 50.210929 -279.099422) (xy 50.162074 -279.105354) (xy 50.112899 -279.103373)
			(xy 50.06468 -279.093529) (xy 50.018664 -279.076077) (xy 49.976043 -279.05147) (xy 49.937922 -279.020345)
			(xy 49.905287 -278.983508) (xy 49.878984 -278.941912) (xy 49.859693 -278.896636) (xy 49.847916 -278.848852)
			(xy 49.843956 -278.799798) (xy 48.555148 -278.799798) (xy 48.554653 -278.824405) (xy 48.546758 -278.872982)
			(xy 48.531174 -278.919663) (xy 48.508303 -278.96324) (xy 48.478738 -279.002584) (xy 48.443245 -279.036676)
			(xy 48.402742 -279.064632) (xy 48.35828 -279.08573) (xy 48.311009 -279.099422) (xy 48.262154 -279.105354)
			(xy 48.212979 -279.103373) (xy 48.16476 -279.093529) (xy 48.118744 -279.076077) (xy 48.076123 -279.05147)
			(xy 48.038002 -279.020345) (xy 48.005367 -278.983508) (xy 47.979064 -278.941912) (xy 47.959773 -278.896636)
			(xy 47.947996 -278.848852) (xy 47.944036 -278.799798) (xy 46.655228 -278.799798) (xy 46.654733 -278.824405)
			(xy 46.646838 -278.872982) (xy 46.631254 -278.919663) (xy 46.608383 -278.96324) (xy 46.578818 -279.002584)
			(xy 46.543325 -279.036676) (xy 46.502822 -279.064632) (xy 46.45836 -279.08573) (xy 46.411089 -279.099422)
			(xy 46.362234 -279.105354) (xy 46.313059 -279.103373) (xy 46.26484 -279.093529) (xy 46.218824 -279.076077)
			(xy 46.176203 -279.05147) (xy 46.138082 -279.020345) (xy 46.105447 -278.983508) (xy 46.079144 -278.941912)
			(xy 46.059853 -278.896636) (xy 46.048076 -278.848852) (xy 46.044116 -278.799798) (xy 44.755054 -278.799798)
			(xy 44.754559 -278.824405) (xy 44.746664 -278.872982) (xy 44.73108 -278.919663) (xy 44.708209 -278.96324)
			(xy 44.678644 -279.002584) (xy 44.643151 -279.036676) (xy 44.602648 -279.064632) (xy 44.558186 -279.08573)
			(xy 44.510915 -279.099422) (xy 44.46206 -279.105354) (xy 44.412885 -279.103373) (xy 44.364666 -279.093529)
			(xy 44.31865 -279.076077) (xy 44.276029 -279.05147) (xy 44.237908 -279.020345) (xy 44.205273 -278.983508)
			(xy 44.17897 -278.941912) (xy 44.159679 -278.896636) (xy 44.147902 -278.848852) (xy 44.143942 -278.799798)
			(xy 0.508 -278.799798) (xy 0.508 -279.749504) (xy 45.094156 -279.749504) (xy 45.098116 -279.70045)
			(xy 45.109893 -279.652666) (xy 45.129184 -279.60739) (xy 45.155487 -279.565794) (xy 45.188122 -279.528957)
			(xy 45.226243 -279.497832) (xy 45.268864 -279.473225) (xy 45.31488 -279.455773) (xy 45.363099 -279.445929)
			(xy 45.412274 -279.443948) (xy 45.461129 -279.44988) (xy 45.5084 -279.463572) (xy 45.552862 -279.48467)
			(xy 45.593365 -279.512626) (xy 45.628858 -279.546718) (xy 45.658423 -279.586062) (xy 45.681294 -279.629639)
			(xy 45.696878 -279.67632) (xy 45.704773 -279.724897) (xy 45.705268 -279.749504) (xy 46.994076 -279.749504)
			(xy 46.998036 -279.70045) (xy 47.009813 -279.652666) (xy 47.029104 -279.60739) (xy 47.055407 -279.565794)
			(xy 47.088042 -279.528957) (xy 47.126163 -279.497832) (xy 47.168784 -279.473225) (xy 47.2148 -279.455773)
			(xy 47.263019 -279.445929) (xy 47.312194 -279.443948) (xy 47.361049 -279.44988) (xy 47.40832 -279.463572)
			(xy 47.452782 -279.48467) (xy 47.493285 -279.512626) (xy 47.528778 -279.546718) (xy 47.558343 -279.586062)
			(xy 47.581214 -279.629639) (xy 47.596798 -279.67632) (xy 47.604693 -279.724897) (xy 47.605188 -279.749504)
			(xy 48.893996 -279.749504) (xy 48.897956 -279.70045) (xy 48.909733 -279.652666) (xy 48.929024 -279.60739)
			(xy 48.955327 -279.565794) (xy 48.987962 -279.528957) (xy 49.026083 -279.497832) (xy 49.068704 -279.473225)
			(xy 49.11472 -279.455773) (xy 49.162939 -279.445929) (xy 49.212114 -279.443948) (xy 49.260969 -279.44988)
			(xy 49.30824 -279.463572) (xy 49.352702 -279.48467) (xy 49.393205 -279.512626) (xy 49.428698 -279.546718)
			(xy 49.458263 -279.586062) (xy 49.481134 -279.629639) (xy 49.496718 -279.67632) (xy 49.504613 -279.724897)
			(xy 49.505108 -279.749504) (xy 50.79417 -279.749504) (xy 50.79813 -279.70045) (xy 50.809907 -279.652666)
			(xy 50.829198 -279.60739) (xy 50.855501 -279.565794) (xy 50.888136 -279.528957) (xy 50.926257 -279.497832)
			(xy 50.968878 -279.473225) (xy 51.014894 -279.455773) (xy 51.063113 -279.445929) (xy 51.112288 -279.443948)
			(xy 51.161143 -279.44988) (xy 51.208414 -279.463572) (xy 51.252876 -279.48467) (xy 51.293379 -279.512626)
			(xy 51.328872 -279.546718) (xy 51.358437 -279.586062) (xy 51.381308 -279.629639) (xy 51.396892 -279.67632)
			(xy 51.404787 -279.724897) (xy 51.405282 -279.749504) (xy 52.69409 -279.749504) (xy 52.69805 -279.70045)
			(xy 52.709827 -279.652666) (xy 52.729118 -279.60739) (xy 52.755421 -279.565794) (xy 52.788056 -279.528957)
			(xy 52.826177 -279.497832) (xy 52.868798 -279.473225) (xy 52.914814 -279.455773) (xy 52.963033 -279.445929)
			(xy 53.012208 -279.443948) (xy 53.061063 -279.44988) (xy 53.108334 -279.463572) (xy 53.152796 -279.48467)
			(xy 53.193299 -279.512626) (xy 53.228792 -279.546718) (xy 53.258357 -279.586062) (xy 53.281228 -279.629639)
			(xy 53.296812 -279.67632) (xy 53.304707 -279.724897) (xy 53.305202 -279.749504) (xy 54.59401 -279.749504)
			(xy 54.59797 -279.70045) (xy 54.609747 -279.652666) (xy 54.629038 -279.60739) (xy 54.655341 -279.565794)
			(xy 54.687976 -279.528957) (xy 54.726097 -279.497832) (xy 54.768718 -279.473225) (xy 54.814734 -279.455773)
			(xy 54.862953 -279.445929) (xy 54.912128 -279.443948) (xy 54.960983 -279.44988) (xy 55.008254 -279.463572)
			(xy 55.052716 -279.48467) (xy 55.093219 -279.512626) (xy 55.128712 -279.546718) (xy 55.158277 -279.586062)
			(xy 55.181148 -279.629639) (xy 55.196732 -279.67632) (xy 55.204627 -279.724897) (xy 55.205122 -279.749504)
			(xy 56.49393 -279.749504) (xy 56.49789 -279.70045) (xy 56.509667 -279.652666) (xy 56.528958 -279.60739)
			(xy 56.555261 -279.565794) (xy 56.587896 -279.528957) (xy 56.626017 -279.497832) (xy 56.668638 -279.473225)
			(xy 56.714654 -279.455773) (xy 56.762873 -279.445929) (xy 56.812048 -279.443948) (xy 56.860903 -279.44988)
			(xy 56.908174 -279.463572) (xy 56.952636 -279.48467) (xy 56.993139 -279.512626) (xy 57.028632 -279.546718)
			(xy 57.058197 -279.586062) (xy 57.081068 -279.629639) (xy 57.096652 -279.67632) (xy 57.104547 -279.724897)
			(xy 57.105042 -279.749504) (xy 58.394104 -279.749504) (xy 58.398064 -279.70045) (xy 58.409841 -279.652666)
			(xy 58.429132 -279.60739) (xy 58.455435 -279.565794) (xy 58.48807 -279.528957) (xy 58.526191 -279.497832)
			(xy 58.568812 -279.473225) (xy 58.614828 -279.455773) (xy 58.663047 -279.445929) (xy 58.712222 -279.443948)
			(xy 58.761077 -279.44988) (xy 58.808348 -279.463572) (xy 58.85281 -279.48467) (xy 58.893313 -279.512626)
			(xy 58.928806 -279.546718) (xy 58.958371 -279.586062) (xy 58.981242 -279.629639) (xy 58.996826 -279.67632)
			(xy 59.004721 -279.724897) (xy 59.005216 -279.749504) (xy 161.194254 -279.749504) (xy 161.198214 -279.70045)
			(xy 161.209991 -279.652666) (xy 161.229282 -279.60739) (xy 161.255585 -279.565794) (xy 161.28822 -279.528957)
			(xy 161.326341 -279.497832) (xy 161.368962 -279.473225) (xy 161.414978 -279.455773) (xy 161.463197 -279.445929)
			(xy 161.512372 -279.443948) (xy 161.561227 -279.44988) (xy 161.608498 -279.463572) (xy 161.65296 -279.48467)
			(xy 161.693463 -279.512626) (xy 161.728956 -279.546718) (xy 161.758521 -279.586062) (xy 161.781392 -279.629639)
			(xy 161.796976 -279.67632) (xy 161.804871 -279.724897) (xy 161.805366 -279.749504) (xy 163.094174 -279.749504)
			(xy 163.098134 -279.70045) (xy 163.109911 -279.652666) (xy 163.129202 -279.60739) (xy 163.155505 -279.565794)
			(xy 163.18814 -279.528957) (xy 163.226261 -279.497832) (xy 163.268882 -279.473225) (xy 163.314898 -279.455773)
			(xy 163.363117 -279.445929) (xy 163.412292 -279.443948) (xy 163.461147 -279.44988) (xy 163.508418 -279.463572)
			(xy 163.55288 -279.48467) (xy 163.593383 -279.512626) (xy 163.628876 -279.546718) (xy 163.658441 -279.586062)
			(xy 163.681312 -279.629639) (xy 163.696896 -279.67632) (xy 163.704791 -279.724897) (xy 163.705286 -279.749504)
			(xy 164.994094 -279.749504) (xy 164.998054 -279.70045) (xy 165.009831 -279.652666) (xy 165.029122 -279.60739)
			(xy 165.055425 -279.565794) (xy 165.08806 -279.528957) (xy 165.126181 -279.497832) (xy 165.168802 -279.473225)
			(xy 165.214818 -279.455773) (xy 165.263037 -279.445929) (xy 165.312212 -279.443948) (xy 165.361067 -279.44988)
			(xy 165.408338 -279.463572) (xy 165.4528 -279.48467) (xy 165.493303 -279.512626) (xy 165.528796 -279.546718)
			(xy 165.558361 -279.586062) (xy 165.581232 -279.629639) (xy 165.596816 -279.67632) (xy 165.604711 -279.724897)
			(xy 165.605206 -279.749504) (xy 166.894268 -279.749504) (xy 166.898228 -279.70045) (xy 166.910005 -279.652666)
			(xy 166.929296 -279.60739) (xy 166.955599 -279.565794) (xy 166.988234 -279.528957) (xy 167.026355 -279.497832)
			(xy 167.068976 -279.473225) (xy 167.114992 -279.455773) (xy 167.163211 -279.445929) (xy 167.212386 -279.443948)
			(xy 167.261241 -279.44988) (xy 167.308512 -279.463572) (xy 167.352974 -279.48467) (xy 167.393477 -279.512626)
			(xy 167.42897 -279.546718) (xy 167.458535 -279.586062) (xy 167.481406 -279.629639) (xy 167.49699 -279.67632)
			(xy 167.504885 -279.724897) (xy 167.50538 -279.749504) (xy 168.794188 -279.749504) (xy 168.798148 -279.70045)
			(xy 168.809925 -279.652666) (xy 168.829216 -279.60739) (xy 168.855519 -279.565794) (xy 168.888154 -279.528957)
			(xy 168.926275 -279.497832) (xy 168.968896 -279.473225) (xy 169.014912 -279.455773) (xy 169.063131 -279.445929)
			(xy 169.112306 -279.443948) (xy 169.161161 -279.44988) (xy 169.208432 -279.463572) (xy 169.252894 -279.48467)
			(xy 169.293397 -279.512626) (xy 169.32889 -279.546718) (xy 169.358455 -279.586062) (xy 169.381326 -279.629639)
			(xy 169.39691 -279.67632) (xy 169.404805 -279.724897) (xy 169.4053 -279.749504) (xy 170.694108 -279.749504)
			(xy 170.698068 -279.70045) (xy 170.709845 -279.652666) (xy 170.729136 -279.60739) (xy 170.755439 -279.565794)
			(xy 170.788074 -279.528957) (xy 170.826195 -279.497832) (xy 170.868816 -279.473225) (xy 170.914832 -279.455773)
			(xy 170.963051 -279.445929) (xy 171.012226 -279.443948) (xy 171.061081 -279.44988) (xy 171.108352 -279.463572)
			(xy 171.152814 -279.48467) (xy 171.193317 -279.512626) (xy 171.22881 -279.546718) (xy 171.258375 -279.586062)
			(xy 171.281246 -279.629639) (xy 171.29683 -279.67632) (xy 171.304725 -279.724897) (xy 171.30522 -279.749504)
			(xy 172.594028 -279.749504) (xy 172.597988 -279.70045) (xy 172.609765 -279.652666) (xy 172.629056 -279.60739)
			(xy 172.655359 -279.565794) (xy 172.687994 -279.528957) (xy 172.726115 -279.497832) (xy 172.768736 -279.473225)
			(xy 172.814752 -279.455773) (xy 172.862971 -279.445929) (xy 172.912146 -279.443948) (xy 172.961001 -279.44988)
			(xy 173.008272 -279.463572) (xy 173.052734 -279.48467) (xy 173.093237 -279.512626) (xy 173.12873 -279.546718)
			(xy 173.158295 -279.586062) (xy 173.181166 -279.629639) (xy 173.19675 -279.67632) (xy 173.204645 -279.724897)
			(xy 173.20514 -279.749504) (xy 174.494202 -279.749504) (xy 174.498162 -279.70045) (xy 174.509939 -279.652666)
			(xy 174.52923 -279.60739) (xy 174.555533 -279.565794) (xy 174.588168 -279.528957) (xy 174.626289 -279.497832)
			(xy 174.66891 -279.473225) (xy 174.714926 -279.455773) (xy 174.763145 -279.445929) (xy 174.81232 -279.443948)
			(xy 174.861175 -279.44988) (xy 174.908446 -279.463572) (xy 174.952908 -279.48467) (xy 174.993411 -279.512626)
			(xy 175.028904 -279.546718) (xy 175.058469 -279.586062) (xy 175.08134 -279.629639) (xy 175.096924 -279.67632)
			(xy 175.104819 -279.724897) (xy 175.105314 -279.749504) (xy 277.294098 -279.749504) (xy 277.298058 -279.70045)
			(xy 277.309835 -279.652666) (xy 277.329126 -279.60739) (xy 277.355429 -279.565794) (xy 277.388064 -279.528957)
			(xy 277.426185 -279.497832) (xy 277.468806 -279.473225) (xy 277.514822 -279.455773) (xy 277.563041 -279.445929)
			(xy 277.612216 -279.443948) (xy 277.661071 -279.44988) (xy 277.708342 -279.463572) (xy 277.752804 -279.48467)
			(xy 277.793307 -279.512626) (xy 277.8288 -279.546718) (xy 277.858365 -279.586062) (xy 277.881236 -279.629639)
			(xy 277.89682 -279.67632) (xy 277.904715 -279.724897) (xy 277.90521 -279.749504) (xy 279.194018 -279.749504)
			(xy 279.197978 -279.70045) (xy 279.209755 -279.652666) (xy 279.229046 -279.60739) (xy 279.255349 -279.565794)
			(xy 279.287984 -279.528957) (xy 279.326105 -279.497832) (xy 279.368726 -279.473225) (xy 279.414742 -279.455773)
			(xy 279.462961 -279.445929) (xy 279.512136 -279.443948) (xy 279.560991 -279.44988) (xy 279.608262 -279.463572)
			(xy 279.652724 -279.48467) (xy 279.693227 -279.512626) (xy 279.72872 -279.546718) (xy 279.758285 -279.586062)
			(xy 279.781156 -279.629639) (xy 279.79674 -279.67632) (xy 279.804635 -279.724897) (xy 279.80513 -279.749504)
			(xy 281.093938 -279.749504) (xy 281.097898 -279.70045) (xy 281.109675 -279.652666) (xy 281.128966 -279.60739)
			(xy 281.155269 -279.565794) (xy 281.187904 -279.528957) (xy 281.226025 -279.497832) (xy 281.268646 -279.473225)
			(xy 281.314662 -279.455773) (xy 281.362881 -279.445929) (xy 281.412056 -279.443948) (xy 281.460911 -279.44988)
			(xy 281.508182 -279.463572) (xy 281.552644 -279.48467) (xy 281.593147 -279.512626) (xy 281.62864 -279.546718)
			(xy 281.658205 -279.586062) (xy 281.681076 -279.629639) (xy 281.69666 -279.67632) (xy 281.704555 -279.724897)
			(xy 281.70505 -279.749504) (xy 282.994112 -279.749504) (xy 282.998072 -279.70045) (xy 283.009849 -279.652666)
			(xy 283.02914 -279.60739) (xy 283.055443 -279.565794) (xy 283.088078 -279.528957) (xy 283.126199 -279.497832)
			(xy 283.16882 -279.473225) (xy 283.214836 -279.455773) (xy 283.263055 -279.445929) (xy 283.31223 -279.443948)
			(xy 283.361085 -279.44988) (xy 283.408356 -279.463572) (xy 283.452818 -279.48467) (xy 283.493321 -279.512626)
			(xy 283.528814 -279.546718) (xy 283.558379 -279.586062) (xy 283.58125 -279.629639) (xy 283.596834 -279.67632)
			(xy 283.604729 -279.724897) (xy 283.605224 -279.749504) (xy 284.894032 -279.749504) (xy 284.897992 -279.70045)
			(xy 284.909769 -279.652666) (xy 284.92906 -279.60739) (xy 284.955363 -279.565794) (xy 284.987998 -279.528957)
			(xy 285.026119 -279.497832) (xy 285.06874 -279.473225) (xy 285.114756 -279.455773) (xy 285.162975 -279.445929)
			(xy 285.21215 -279.443948) (xy 285.261005 -279.44988) (xy 285.308276 -279.463572) (xy 285.352738 -279.48467)
			(xy 285.393241 -279.512626) (xy 285.428734 -279.546718) (xy 285.458299 -279.586062) (xy 285.48117 -279.629639)
			(xy 285.496754 -279.67632) (xy 285.504649 -279.724897) (xy 285.505144 -279.749504) (xy 286.793952 -279.749504)
			(xy 286.797912 -279.70045) (xy 286.809689 -279.652666) (xy 286.82898 -279.60739) (xy 286.855283 -279.565794)
			(xy 286.887918 -279.528957) (xy 286.926039 -279.497832) (xy 286.96866 -279.473225) (xy 287.014676 -279.455773)
			(xy 287.062895 -279.445929) (xy 287.11207 -279.443948) (xy 287.160925 -279.44988) (xy 287.208196 -279.463572)
			(xy 287.252658 -279.48467) (xy 287.293161 -279.512626) (xy 287.328654 -279.546718) (xy 287.358219 -279.586062)
			(xy 287.38109 -279.629639) (xy 287.396674 -279.67632) (xy 287.404569 -279.724897) (xy 287.405064 -279.749504)
			(xy 288.693872 -279.749504) (xy 288.697832 -279.70045) (xy 288.709609 -279.652666) (xy 288.7289 -279.60739)
			(xy 288.755203 -279.565794) (xy 288.787838 -279.528957) (xy 288.825959 -279.497832) (xy 288.86858 -279.473225)
			(xy 288.914596 -279.455773) (xy 288.962815 -279.445929) (xy 289.01199 -279.443948) (xy 289.060845 -279.44988)
			(xy 289.108116 -279.463572) (xy 289.152578 -279.48467) (xy 289.193081 -279.512626) (xy 289.228574 -279.546718)
			(xy 289.258139 -279.586062) (xy 289.28101 -279.629639) (xy 289.296594 -279.67632) (xy 289.304489 -279.724897)
			(xy 289.304984 -279.749504) (xy 290.594046 -279.749504) (xy 290.598006 -279.70045) (xy 290.609783 -279.652666)
			(xy 290.629074 -279.60739) (xy 290.655377 -279.565794) (xy 290.688012 -279.528957) (xy 290.726133 -279.497832)
			(xy 290.768754 -279.473225) (xy 290.81477 -279.455773) (xy 290.862989 -279.445929) (xy 290.912164 -279.443948)
			(xy 290.961019 -279.44988) (xy 291.00829 -279.463572) (xy 291.052752 -279.48467) (xy 291.093255 -279.512626)
			(xy 291.128748 -279.546718) (xy 291.158313 -279.586062) (xy 291.181184 -279.629639) (xy 291.196768 -279.67632)
			(xy 291.204663 -279.724897) (xy 291.205158 -279.749504) (xy 393.394196 -279.749504) (xy 393.398156 -279.70045)
			(xy 393.409933 -279.652666) (xy 393.429224 -279.60739) (xy 393.455527 -279.565794) (xy 393.488162 -279.528957)
			(xy 393.526283 -279.497832) (xy 393.568904 -279.473225) (xy 393.61492 -279.455773) (xy 393.663139 -279.445929)
			(xy 393.712314 -279.443948) (xy 393.761169 -279.44988) (xy 393.80844 -279.463572) (xy 393.852902 -279.48467)
			(xy 393.893405 -279.512626) (xy 393.928898 -279.546718) (xy 393.958463 -279.586062) (xy 393.981334 -279.629639)
			(xy 393.996918 -279.67632) (xy 394.004813 -279.724897) (xy 394.005308 -279.749504) (xy 395.294116 -279.749504)
			(xy 395.298076 -279.70045) (xy 395.309853 -279.652666) (xy 395.329144 -279.60739) (xy 395.355447 -279.565794)
			(xy 395.388082 -279.528957) (xy 395.426203 -279.497832) (xy 395.468824 -279.473225) (xy 395.51484 -279.455773)
			(xy 395.563059 -279.445929) (xy 395.612234 -279.443948) (xy 395.661089 -279.44988) (xy 395.70836 -279.463572)
			(xy 395.752822 -279.48467) (xy 395.793325 -279.512626) (xy 395.828818 -279.546718) (xy 395.858383 -279.586062)
			(xy 395.881254 -279.629639) (xy 395.896838 -279.67632) (xy 395.904733 -279.724897) (xy 395.905228 -279.749504)
			(xy 397.194036 -279.749504) (xy 397.197996 -279.70045) (xy 397.209773 -279.652666) (xy 397.229064 -279.60739)
			(xy 397.255367 -279.565794) (xy 397.288002 -279.528957) (xy 397.326123 -279.497832) (xy 397.368744 -279.473225)
			(xy 397.41476 -279.455773) (xy 397.462979 -279.445929) (xy 397.512154 -279.443948) (xy 397.561009 -279.44988)
			(xy 397.60828 -279.463572) (xy 397.652742 -279.48467) (xy 397.693245 -279.512626) (xy 397.728738 -279.546718)
			(xy 397.758303 -279.586062) (xy 397.781174 -279.629639) (xy 397.796758 -279.67632) (xy 397.804653 -279.724897)
			(xy 397.805148 -279.749504) (xy 399.09421 -279.749504) (xy 399.09817 -279.70045) (xy 399.109947 -279.652666)
			(xy 399.129238 -279.60739) (xy 399.155541 -279.565794) (xy 399.188176 -279.528957) (xy 399.226297 -279.497832)
			(xy 399.268918 -279.473225) (xy 399.314934 -279.455773) (xy 399.363153 -279.445929) (xy 399.412328 -279.443948)
			(xy 399.461183 -279.44988) (xy 399.508454 -279.463572) (xy 399.552916 -279.48467) (xy 399.593419 -279.512626)
			(xy 399.628912 -279.546718) (xy 399.658477 -279.586062) (xy 399.681348 -279.629639) (xy 399.696932 -279.67632)
			(xy 399.704827 -279.724897) (xy 399.705322 -279.749504) (xy 400.99413 -279.749504) (xy 400.99809 -279.70045)
			(xy 401.009867 -279.652666) (xy 401.029158 -279.60739) (xy 401.055461 -279.565794) (xy 401.088096 -279.528957)
			(xy 401.126217 -279.497832) (xy 401.168838 -279.473225) (xy 401.214854 -279.455773) (xy 401.263073 -279.445929)
			(xy 401.312248 -279.443948) (xy 401.361103 -279.44988) (xy 401.408374 -279.463572) (xy 401.452836 -279.48467)
			(xy 401.493339 -279.512626) (xy 401.528832 -279.546718) (xy 401.558397 -279.586062) (xy 401.581268 -279.629639)
			(xy 401.596852 -279.67632) (xy 401.604747 -279.724897) (xy 401.605242 -279.749504) (xy 402.89405 -279.749504)
			(xy 402.89801 -279.70045) (xy 402.909787 -279.652666) (xy 402.929078 -279.60739) (xy 402.955381 -279.565794)
			(xy 402.988016 -279.528957) (xy 403.026137 -279.497832) (xy 403.068758 -279.473225) (xy 403.114774 -279.455773)
			(xy 403.162993 -279.445929) (xy 403.212168 -279.443948) (xy 403.261023 -279.44988) (xy 403.308294 -279.463572)
			(xy 403.352756 -279.48467) (xy 403.393259 -279.512626) (xy 403.428752 -279.546718) (xy 403.458317 -279.586062)
			(xy 403.481188 -279.629639) (xy 403.496772 -279.67632) (xy 403.504667 -279.724897) (xy 403.505162 -279.749504)
			(xy 404.79397 -279.749504) (xy 404.79793 -279.70045) (xy 404.809707 -279.652666) (xy 404.828998 -279.60739)
			(xy 404.855301 -279.565794) (xy 404.887936 -279.528957) (xy 404.926057 -279.497832) (xy 404.968678 -279.473225)
			(xy 405.014694 -279.455773) (xy 405.062913 -279.445929) (xy 405.112088 -279.443948) (xy 405.160943 -279.44988)
			(xy 405.208214 -279.463572) (xy 405.252676 -279.48467) (xy 405.293179 -279.512626) (xy 405.328672 -279.546718)
			(xy 405.358237 -279.586062) (xy 405.381108 -279.629639) (xy 405.396692 -279.67632) (xy 405.404587 -279.724897)
			(xy 405.405082 -279.749504) (xy 406.694144 -279.749504) (xy 406.698104 -279.70045) (xy 406.709881 -279.652666)
			(xy 406.729172 -279.60739) (xy 406.755475 -279.565794) (xy 406.78811 -279.528957) (xy 406.826231 -279.497832)
			(xy 406.868852 -279.473225) (xy 406.914868 -279.455773) (xy 406.963087 -279.445929) (xy 407.012262 -279.443948)
			(xy 407.061117 -279.44988) (xy 407.108388 -279.463572) (xy 407.15285 -279.48467) (xy 407.193353 -279.512626)
			(xy 407.228846 -279.546718) (xy 407.258411 -279.586062) (xy 407.281282 -279.629639) (xy 407.296866 -279.67632)
			(xy 407.304761 -279.724897) (xy 407.305256 -279.749504) (xy 407.304761 -279.774111) (xy 407.296866 -279.822688)
			(xy 407.281282 -279.869369) (xy 407.258411 -279.912946) (xy 407.228846 -279.95229) (xy 407.193353 -279.986382)
			(xy 407.15285 -280.014338) (xy 407.108388 -280.035436) (xy 407.061117 -280.049128) (xy 407.012262 -280.05506)
			(xy 406.963087 -280.053079) (xy 406.914868 -280.043235) (xy 406.868852 -280.025783) (xy 406.826231 -280.001176)
			(xy 406.78811 -279.970051) (xy 406.755475 -279.933214) (xy 406.729172 -279.891618) (xy 406.709881 -279.846342)
			(xy 406.698104 -279.798558) (xy 406.694144 -279.749504) (xy 405.405082 -279.749504) (xy 405.404587 -279.774111)
			(xy 405.396692 -279.822688) (xy 405.381108 -279.869369) (xy 405.358237 -279.912946) (xy 405.328672 -279.95229)
			(xy 405.293179 -279.986382) (xy 405.252676 -280.014338) (xy 405.208214 -280.035436) (xy 405.160943 -280.049128)
			(xy 405.112088 -280.05506) (xy 405.062913 -280.053079) (xy 405.014694 -280.043235) (xy 404.968678 -280.025783)
			(xy 404.926057 -280.001176) (xy 404.887936 -279.970051) (xy 404.855301 -279.933214) (xy 404.828998 -279.891618)
			(xy 404.809707 -279.846342) (xy 404.79793 -279.798558) (xy 404.79397 -279.749504) (xy 403.505162 -279.749504)
			(xy 403.504667 -279.774111) (xy 403.496772 -279.822688) (xy 403.481188 -279.869369) (xy 403.458317 -279.912946)
			(xy 403.428752 -279.95229) (xy 403.393259 -279.986382) (xy 403.352756 -280.014338) (xy 403.308294 -280.035436)
			(xy 403.261023 -280.049128) (xy 403.212168 -280.05506) (xy 403.162993 -280.053079) (xy 403.114774 -280.043235)
			(xy 403.068758 -280.025783) (xy 403.026137 -280.001176) (xy 402.988016 -279.970051) (xy 402.955381 -279.933214)
			(xy 402.929078 -279.891618) (xy 402.909787 -279.846342) (xy 402.89801 -279.798558) (xy 402.89405 -279.749504)
			(xy 401.605242 -279.749504) (xy 401.604747 -279.774111) (xy 401.596852 -279.822688) (xy 401.581268 -279.869369)
			(xy 401.558397 -279.912946) (xy 401.528832 -279.95229) (xy 401.493339 -279.986382) (xy 401.452836 -280.014338)
			(xy 401.408374 -280.035436) (xy 401.361103 -280.049128) (xy 401.312248 -280.05506) (xy 401.263073 -280.053079)
			(xy 401.214854 -280.043235) (xy 401.168838 -280.025783) (xy 401.126217 -280.001176) (xy 401.088096 -279.970051)
			(xy 401.055461 -279.933214) (xy 401.029158 -279.891618) (xy 401.009867 -279.846342) (xy 400.99809 -279.798558)
			(xy 400.99413 -279.749504) (xy 399.705322 -279.749504) (xy 399.704827 -279.774111) (xy 399.696932 -279.822688)
			(xy 399.681348 -279.869369) (xy 399.658477 -279.912946) (xy 399.628912 -279.95229) (xy 399.593419 -279.986382)
			(xy 399.552916 -280.014338) (xy 399.508454 -280.035436) (xy 399.461183 -280.049128) (xy 399.412328 -280.05506)
			(xy 399.363153 -280.053079) (xy 399.314934 -280.043235) (xy 399.268918 -280.025783) (xy 399.226297 -280.001176)
			(xy 399.188176 -279.970051) (xy 399.155541 -279.933214) (xy 399.129238 -279.891618) (xy 399.109947 -279.846342)
			(xy 399.09817 -279.798558) (xy 399.09421 -279.749504) (xy 397.805148 -279.749504) (xy 397.804653 -279.774111)
			(xy 397.796758 -279.822688) (xy 397.781174 -279.869369) (xy 397.758303 -279.912946) (xy 397.728738 -279.95229)
			(xy 397.693245 -279.986382) (xy 397.652742 -280.014338) (xy 397.60828 -280.035436) (xy 397.561009 -280.049128)
			(xy 397.512154 -280.05506) (xy 397.462979 -280.053079) (xy 397.41476 -280.043235) (xy 397.368744 -280.025783)
			(xy 397.326123 -280.001176) (xy 397.288002 -279.970051) (xy 397.255367 -279.933214) (xy 397.229064 -279.891618)
			(xy 397.209773 -279.846342) (xy 397.197996 -279.798558) (xy 397.194036 -279.749504) (xy 395.905228 -279.749504)
			(xy 395.904733 -279.774111) (xy 395.896838 -279.822688) (xy 395.881254 -279.869369) (xy 395.858383 -279.912946)
			(xy 395.828818 -279.95229) (xy 395.793325 -279.986382) (xy 395.752822 -280.014338) (xy 395.70836 -280.035436)
			(xy 395.661089 -280.049128) (xy 395.612234 -280.05506) (xy 395.563059 -280.053079) (xy 395.51484 -280.043235)
			(xy 395.468824 -280.025783) (xy 395.426203 -280.001176) (xy 395.388082 -279.970051) (xy 395.355447 -279.933214)
			(xy 395.329144 -279.891618) (xy 395.309853 -279.846342) (xy 395.298076 -279.798558) (xy 395.294116 -279.749504)
			(xy 394.005308 -279.749504) (xy 394.004813 -279.774111) (xy 393.996918 -279.822688) (xy 393.981334 -279.869369)
			(xy 393.958463 -279.912946) (xy 393.928898 -279.95229) (xy 393.893405 -279.986382) (xy 393.852902 -280.014338)
			(xy 393.80844 -280.035436) (xy 393.761169 -280.049128) (xy 393.712314 -280.05506) (xy 393.663139 -280.053079)
			(xy 393.61492 -280.043235) (xy 393.568904 -280.025783) (xy 393.526283 -280.001176) (xy 393.488162 -279.970051)
			(xy 393.455527 -279.933214) (xy 393.429224 -279.891618) (xy 393.409933 -279.846342) (xy 393.398156 -279.798558)
			(xy 393.394196 -279.749504) (xy 291.205158 -279.749504) (xy 291.204663 -279.774111) (xy 291.196768 -279.822688)
			(xy 291.181184 -279.869369) (xy 291.158313 -279.912946) (xy 291.128748 -279.95229) (xy 291.093255 -279.986382)
			(xy 291.052752 -280.014338) (xy 291.00829 -280.035436) (xy 290.961019 -280.049128) (xy 290.912164 -280.05506)
			(xy 290.862989 -280.053079) (xy 290.81477 -280.043235) (xy 290.768754 -280.025783) (xy 290.726133 -280.001176)
			(xy 290.688012 -279.970051) (xy 290.655377 -279.933214) (xy 290.629074 -279.891618) (xy 290.609783 -279.846342)
			(xy 290.598006 -279.798558) (xy 290.594046 -279.749504) (xy 289.304984 -279.749504) (xy 289.304489 -279.774111)
			(xy 289.296594 -279.822688) (xy 289.28101 -279.869369) (xy 289.258139 -279.912946) (xy 289.228574 -279.95229)
			(xy 289.193081 -279.986382) (xy 289.152578 -280.014338) (xy 289.108116 -280.035436) (xy 289.060845 -280.049128)
			(xy 289.01199 -280.05506) (xy 288.962815 -280.053079) (xy 288.914596 -280.043235) (xy 288.86858 -280.025783)
			(xy 288.825959 -280.001176) (xy 288.787838 -279.970051) (xy 288.755203 -279.933214) (xy 288.7289 -279.891618)
			(xy 288.709609 -279.846342) (xy 288.697832 -279.798558) (xy 288.693872 -279.749504) (xy 287.405064 -279.749504)
			(xy 287.404569 -279.774111) (xy 287.396674 -279.822688) (xy 287.38109 -279.869369) (xy 287.358219 -279.912946)
			(xy 287.328654 -279.95229) (xy 287.293161 -279.986382) (xy 287.252658 -280.014338) (xy 287.208196 -280.035436)
			(xy 287.160925 -280.049128) (xy 287.11207 -280.05506) (xy 287.062895 -280.053079) (xy 287.014676 -280.043235)
			(xy 286.96866 -280.025783) (xy 286.926039 -280.001176) (xy 286.887918 -279.970051) (xy 286.855283 -279.933214)
			(xy 286.82898 -279.891618) (xy 286.809689 -279.846342) (xy 286.797912 -279.798558) (xy 286.793952 -279.749504)
			(xy 285.505144 -279.749504) (xy 285.504649 -279.774111) (xy 285.496754 -279.822688) (xy 285.48117 -279.869369)
			(xy 285.458299 -279.912946) (xy 285.428734 -279.95229) (xy 285.393241 -279.986382) (xy 285.352738 -280.014338)
			(xy 285.308276 -280.035436) (xy 285.261005 -280.049128) (xy 285.21215 -280.05506) (xy 285.162975 -280.053079)
			(xy 285.114756 -280.043235) (xy 285.06874 -280.025783) (xy 285.026119 -280.001176) (xy 284.987998 -279.970051)
			(xy 284.955363 -279.933214) (xy 284.92906 -279.891618) (xy 284.909769 -279.846342) (xy 284.897992 -279.798558)
			(xy 284.894032 -279.749504) (xy 283.605224 -279.749504) (xy 283.604729 -279.774111) (xy 283.596834 -279.822688)
			(xy 283.58125 -279.869369) (xy 283.558379 -279.912946) (xy 283.528814 -279.95229) (xy 283.493321 -279.986382)
			(xy 283.452818 -280.014338) (xy 283.408356 -280.035436) (xy 283.361085 -280.049128) (xy 283.31223 -280.05506)
			(xy 283.263055 -280.053079) (xy 283.214836 -280.043235) (xy 283.16882 -280.025783) (xy 283.126199 -280.001176)
			(xy 283.088078 -279.970051) (xy 283.055443 -279.933214) (xy 283.02914 -279.891618) (xy 283.009849 -279.846342)
			(xy 282.998072 -279.798558) (xy 282.994112 -279.749504) (xy 281.70505 -279.749504) (xy 281.704555 -279.774111)
			(xy 281.69666 -279.822688) (xy 281.681076 -279.869369) (xy 281.658205 -279.912946) (xy 281.62864 -279.95229)
			(xy 281.593147 -279.986382) (xy 281.552644 -280.014338) (xy 281.508182 -280.035436) (xy 281.460911 -280.049128)
			(xy 281.412056 -280.05506) (xy 281.362881 -280.053079) (xy 281.314662 -280.043235) (xy 281.268646 -280.025783)
			(xy 281.226025 -280.001176) (xy 281.187904 -279.970051) (xy 281.155269 -279.933214) (xy 281.128966 -279.891618)
			(xy 281.109675 -279.846342) (xy 281.097898 -279.798558) (xy 281.093938 -279.749504) (xy 279.80513 -279.749504)
			(xy 279.804635 -279.774111) (xy 279.79674 -279.822688) (xy 279.781156 -279.869369) (xy 279.758285 -279.912946)
			(xy 279.72872 -279.95229) (xy 279.693227 -279.986382) (xy 279.652724 -280.014338) (xy 279.608262 -280.035436)
			(xy 279.560991 -280.049128) (xy 279.512136 -280.05506) (xy 279.462961 -280.053079) (xy 279.414742 -280.043235)
			(xy 279.368726 -280.025783) (xy 279.326105 -280.001176) (xy 279.287984 -279.970051) (xy 279.255349 -279.933214)
			(xy 279.229046 -279.891618) (xy 279.209755 -279.846342) (xy 279.197978 -279.798558) (xy 279.194018 -279.749504)
			(xy 277.90521 -279.749504) (xy 277.904715 -279.774111) (xy 277.89682 -279.822688) (xy 277.881236 -279.869369)
			(xy 277.858365 -279.912946) (xy 277.8288 -279.95229) (xy 277.793307 -279.986382) (xy 277.752804 -280.014338)
			(xy 277.708342 -280.035436) (xy 277.661071 -280.049128) (xy 277.612216 -280.05506) (xy 277.563041 -280.053079)
			(xy 277.514822 -280.043235) (xy 277.468806 -280.025783) (xy 277.426185 -280.001176) (xy 277.388064 -279.970051)
			(xy 277.355429 -279.933214) (xy 277.329126 -279.891618) (xy 277.309835 -279.846342) (xy 277.298058 -279.798558)
			(xy 277.294098 -279.749504) (xy 175.105314 -279.749504) (xy 175.104819 -279.774111) (xy 175.096924 -279.822688)
			(xy 175.08134 -279.869369) (xy 175.058469 -279.912946) (xy 175.028904 -279.95229) (xy 174.993411 -279.986382)
			(xy 174.952908 -280.014338) (xy 174.908446 -280.035436) (xy 174.861175 -280.049128) (xy 174.81232 -280.05506)
			(xy 174.763145 -280.053079) (xy 174.714926 -280.043235) (xy 174.66891 -280.025783) (xy 174.626289 -280.001176)
			(xy 174.588168 -279.970051) (xy 174.555533 -279.933214) (xy 174.52923 -279.891618) (xy 174.509939 -279.846342)
			(xy 174.498162 -279.798558) (xy 174.494202 -279.749504) (xy 173.20514 -279.749504) (xy 173.204645 -279.774111)
			(xy 173.19675 -279.822688) (xy 173.181166 -279.869369) (xy 173.158295 -279.912946) (xy 173.12873 -279.95229)
			(xy 173.093237 -279.986382) (xy 173.052734 -280.014338) (xy 173.008272 -280.035436) (xy 172.961001 -280.049128)
			(xy 172.912146 -280.05506) (xy 172.862971 -280.053079) (xy 172.814752 -280.043235) (xy 172.768736 -280.025783)
			(xy 172.726115 -280.001176) (xy 172.687994 -279.970051) (xy 172.655359 -279.933214) (xy 172.629056 -279.891618)
			(xy 172.609765 -279.846342) (xy 172.597988 -279.798558) (xy 172.594028 -279.749504) (xy 171.30522 -279.749504)
			(xy 171.304725 -279.774111) (xy 171.29683 -279.822688) (xy 171.281246 -279.869369) (xy 171.258375 -279.912946)
			(xy 171.22881 -279.95229) (xy 171.193317 -279.986382) (xy 171.152814 -280.014338) (xy 171.108352 -280.035436)
			(xy 171.061081 -280.049128) (xy 171.012226 -280.05506) (xy 170.963051 -280.053079) (xy 170.914832 -280.043235)
			(xy 170.868816 -280.025783) (xy 170.826195 -280.001176) (xy 170.788074 -279.970051) (xy 170.755439 -279.933214)
			(xy 170.729136 -279.891618) (xy 170.709845 -279.846342) (xy 170.698068 -279.798558) (xy 170.694108 -279.749504)
			(xy 169.4053 -279.749504) (xy 169.404805 -279.774111) (xy 169.39691 -279.822688) (xy 169.381326 -279.869369)
			(xy 169.358455 -279.912946) (xy 169.32889 -279.95229) (xy 169.293397 -279.986382) (xy 169.252894 -280.014338)
			(xy 169.208432 -280.035436) (xy 169.161161 -280.049128) (xy 169.112306 -280.05506) (xy 169.063131 -280.053079)
			(xy 169.014912 -280.043235) (xy 168.968896 -280.025783) (xy 168.926275 -280.001176) (xy 168.888154 -279.970051)
			(xy 168.855519 -279.933214) (xy 168.829216 -279.891618) (xy 168.809925 -279.846342) (xy 168.798148 -279.798558)
			(xy 168.794188 -279.749504) (xy 167.50538 -279.749504) (xy 167.504885 -279.774111) (xy 167.49699 -279.822688)
			(xy 167.481406 -279.869369) (xy 167.458535 -279.912946) (xy 167.42897 -279.95229) (xy 167.393477 -279.986382)
			(xy 167.352974 -280.014338) (xy 167.308512 -280.035436) (xy 167.261241 -280.049128) (xy 167.212386 -280.05506)
			(xy 167.163211 -280.053079) (xy 167.114992 -280.043235) (xy 167.068976 -280.025783) (xy 167.026355 -280.001176)
			(xy 166.988234 -279.970051) (xy 166.955599 -279.933214) (xy 166.929296 -279.891618) (xy 166.910005 -279.846342)
			(xy 166.898228 -279.798558) (xy 166.894268 -279.749504) (xy 165.605206 -279.749504) (xy 165.604711 -279.774111)
			(xy 165.596816 -279.822688) (xy 165.581232 -279.869369) (xy 165.558361 -279.912946) (xy 165.528796 -279.95229)
			(xy 165.493303 -279.986382) (xy 165.4528 -280.014338) (xy 165.408338 -280.035436) (xy 165.361067 -280.049128)
			(xy 165.312212 -280.05506) (xy 165.263037 -280.053079) (xy 165.214818 -280.043235) (xy 165.168802 -280.025783)
			(xy 165.126181 -280.001176) (xy 165.08806 -279.970051) (xy 165.055425 -279.933214) (xy 165.029122 -279.891618)
			(xy 165.009831 -279.846342) (xy 164.998054 -279.798558) (xy 164.994094 -279.749504) (xy 163.705286 -279.749504)
			(xy 163.704791 -279.774111) (xy 163.696896 -279.822688) (xy 163.681312 -279.869369) (xy 163.658441 -279.912946)
			(xy 163.628876 -279.95229) (xy 163.593383 -279.986382) (xy 163.55288 -280.014338) (xy 163.508418 -280.035436)
			(xy 163.461147 -280.049128) (xy 163.412292 -280.05506) (xy 163.363117 -280.053079) (xy 163.314898 -280.043235)
			(xy 163.268882 -280.025783) (xy 163.226261 -280.001176) (xy 163.18814 -279.970051) (xy 163.155505 -279.933214)
			(xy 163.129202 -279.891618) (xy 163.109911 -279.846342) (xy 163.098134 -279.798558) (xy 163.094174 -279.749504)
			(xy 161.805366 -279.749504) (xy 161.804871 -279.774111) (xy 161.796976 -279.822688) (xy 161.781392 -279.869369)
			(xy 161.758521 -279.912946) (xy 161.728956 -279.95229) (xy 161.693463 -279.986382) (xy 161.65296 -280.014338)
			(xy 161.608498 -280.035436) (xy 161.561227 -280.049128) (xy 161.512372 -280.05506) (xy 161.463197 -280.053079)
			(xy 161.414978 -280.043235) (xy 161.368962 -280.025783) (xy 161.326341 -280.001176) (xy 161.28822 -279.970051)
			(xy 161.255585 -279.933214) (xy 161.229282 -279.891618) (xy 161.209991 -279.846342) (xy 161.198214 -279.798558)
			(xy 161.194254 -279.749504) (xy 59.005216 -279.749504) (xy 59.004721 -279.774111) (xy 58.996826 -279.822688)
			(xy 58.981242 -279.869369) (xy 58.958371 -279.912946) (xy 58.928806 -279.95229) (xy 58.893313 -279.986382)
			(xy 58.85281 -280.014338) (xy 58.808348 -280.035436) (xy 58.761077 -280.049128) (xy 58.712222 -280.05506)
			(xy 58.663047 -280.053079) (xy 58.614828 -280.043235) (xy 58.568812 -280.025783) (xy 58.526191 -280.001176)
			(xy 58.48807 -279.970051) (xy 58.455435 -279.933214) (xy 58.429132 -279.891618) (xy 58.409841 -279.846342)
			(xy 58.398064 -279.798558) (xy 58.394104 -279.749504) (xy 57.105042 -279.749504) (xy 57.104547 -279.774111)
			(xy 57.096652 -279.822688) (xy 57.081068 -279.869369) (xy 57.058197 -279.912946) (xy 57.028632 -279.95229)
			(xy 56.993139 -279.986382) (xy 56.952636 -280.014338) (xy 56.908174 -280.035436) (xy 56.860903 -280.049128)
			(xy 56.812048 -280.05506) (xy 56.762873 -280.053079) (xy 56.714654 -280.043235) (xy 56.668638 -280.025783)
			(xy 56.626017 -280.001176) (xy 56.587896 -279.970051) (xy 56.555261 -279.933214) (xy 56.528958 -279.891618)
			(xy 56.509667 -279.846342) (xy 56.49789 -279.798558) (xy 56.49393 -279.749504) (xy 55.205122 -279.749504)
			(xy 55.204627 -279.774111) (xy 55.196732 -279.822688) (xy 55.181148 -279.869369) (xy 55.158277 -279.912946)
			(xy 55.128712 -279.95229) (xy 55.093219 -279.986382) (xy 55.052716 -280.014338) (xy 55.008254 -280.035436)
			(xy 54.960983 -280.049128) (xy 54.912128 -280.05506) (xy 54.862953 -280.053079) (xy 54.814734 -280.043235)
			(xy 54.768718 -280.025783) (xy 54.726097 -280.001176) (xy 54.687976 -279.970051) (xy 54.655341 -279.933214)
			(xy 54.629038 -279.891618) (xy 54.609747 -279.846342) (xy 54.59797 -279.798558) (xy 54.59401 -279.749504)
			(xy 53.305202 -279.749504) (xy 53.304707 -279.774111) (xy 53.296812 -279.822688) (xy 53.281228 -279.869369)
			(xy 53.258357 -279.912946) (xy 53.228792 -279.95229) (xy 53.193299 -279.986382) (xy 53.152796 -280.014338)
			(xy 53.108334 -280.035436) (xy 53.061063 -280.049128) (xy 53.012208 -280.05506) (xy 52.963033 -280.053079)
			(xy 52.914814 -280.043235) (xy 52.868798 -280.025783) (xy 52.826177 -280.001176) (xy 52.788056 -279.970051)
			(xy 52.755421 -279.933214) (xy 52.729118 -279.891618) (xy 52.709827 -279.846342) (xy 52.69805 -279.798558)
			(xy 52.69409 -279.749504) (xy 51.405282 -279.749504) (xy 51.404787 -279.774111) (xy 51.396892 -279.822688)
			(xy 51.381308 -279.869369) (xy 51.358437 -279.912946) (xy 51.328872 -279.95229) (xy 51.293379 -279.986382)
			(xy 51.252876 -280.014338) (xy 51.208414 -280.035436) (xy 51.161143 -280.049128) (xy 51.112288 -280.05506)
			(xy 51.063113 -280.053079) (xy 51.014894 -280.043235) (xy 50.968878 -280.025783) (xy 50.926257 -280.001176)
			(xy 50.888136 -279.970051) (xy 50.855501 -279.933214) (xy 50.829198 -279.891618) (xy 50.809907 -279.846342)
			(xy 50.79813 -279.798558) (xy 50.79417 -279.749504) (xy 49.505108 -279.749504) (xy 49.504613 -279.774111)
			(xy 49.496718 -279.822688) (xy 49.481134 -279.869369) (xy 49.458263 -279.912946) (xy 49.428698 -279.95229)
			(xy 49.393205 -279.986382) (xy 49.352702 -280.014338) (xy 49.30824 -280.035436) (xy 49.260969 -280.049128)
			(xy 49.212114 -280.05506) (xy 49.162939 -280.053079) (xy 49.11472 -280.043235) (xy 49.068704 -280.025783)
			(xy 49.026083 -280.001176) (xy 48.987962 -279.970051) (xy 48.955327 -279.933214) (xy 48.929024 -279.891618)
			(xy 48.909733 -279.846342) (xy 48.897956 -279.798558) (xy 48.893996 -279.749504) (xy 47.605188 -279.749504)
			(xy 47.604693 -279.774111) (xy 47.596798 -279.822688) (xy 47.581214 -279.869369) (xy 47.558343 -279.912946)
			(xy 47.528778 -279.95229) (xy 47.493285 -279.986382) (xy 47.452782 -280.014338) (xy 47.40832 -280.035436)
			(xy 47.361049 -280.049128) (xy 47.312194 -280.05506) (xy 47.263019 -280.053079) (xy 47.2148 -280.043235)
			(xy 47.168784 -280.025783) (xy 47.126163 -280.001176) (xy 47.088042 -279.970051) (xy 47.055407 -279.933214)
			(xy 47.029104 -279.891618) (xy 47.009813 -279.846342) (xy 46.998036 -279.798558) (xy 46.994076 -279.749504)
			(xy 45.705268 -279.749504) (xy 45.704773 -279.774111) (xy 45.696878 -279.822688) (xy 45.681294 -279.869369)
			(xy 45.658423 -279.912946) (xy 45.628858 -279.95229) (xy 45.593365 -279.986382) (xy 45.552862 -280.014338)
			(xy 45.5084 -280.035436) (xy 45.461129 -280.049128) (xy 45.412274 -280.05506) (xy 45.363099 -280.053079)
			(xy 45.31488 -280.043235) (xy 45.268864 -280.025783) (xy 45.226243 -280.001176) (xy 45.188122 -279.970051)
			(xy 45.155487 -279.933214) (xy 45.129184 -279.891618) (xy 45.109893 -279.846342) (xy 45.098116 -279.798558)
			(xy 45.094156 -279.749504) (xy 0.508 -279.749504) (xy 0.508 -280.699718) (xy 45.094156 -280.699718)
			(xy 45.098116 -280.650664) (xy 45.109893 -280.60288) (xy 45.129184 -280.557604) (xy 45.155487 -280.516008)
			(xy 45.188122 -280.479171) (xy 45.226243 -280.448046) (xy 45.268864 -280.423439) (xy 45.31488 -280.405987)
			(xy 45.363099 -280.396143) (xy 45.412274 -280.394162) (xy 45.461129 -280.400094) (xy 45.5084 -280.413786)
			(xy 45.552862 -280.434884) (xy 45.593365 -280.46284) (xy 45.628858 -280.496932) (xy 45.658423 -280.536276)
			(xy 45.681294 -280.579853) (xy 45.696878 -280.626534) (xy 45.704773 -280.675111) (xy 45.705268 -280.699718)
			(xy 46.994076 -280.699718) (xy 46.998036 -280.650664) (xy 47.009813 -280.60288) (xy 47.029104 -280.557604)
			(xy 47.055407 -280.516008) (xy 47.088042 -280.479171) (xy 47.126163 -280.448046) (xy 47.168784 -280.423439)
			(xy 47.2148 -280.405987) (xy 47.263019 -280.396143) (xy 47.312194 -280.394162) (xy 47.361049 -280.400094)
			(xy 47.40832 -280.413786) (xy 47.452782 -280.434884) (xy 47.493285 -280.46284) (xy 47.528778 -280.496932)
			(xy 47.558343 -280.536276) (xy 47.581214 -280.579853) (xy 47.596798 -280.626534) (xy 47.604693 -280.675111)
			(xy 47.605188 -280.699718) (xy 48.893996 -280.699718) (xy 48.897956 -280.650664) (xy 48.909733 -280.60288)
			(xy 48.929024 -280.557604) (xy 48.955327 -280.516008) (xy 48.987962 -280.479171) (xy 49.026083 -280.448046)
			(xy 49.068704 -280.423439) (xy 49.11472 -280.405987) (xy 49.162939 -280.396143) (xy 49.212114 -280.394162)
			(xy 49.260969 -280.400094) (xy 49.30824 -280.413786) (xy 49.352702 -280.434884) (xy 49.393205 -280.46284)
			(xy 49.428698 -280.496932) (xy 49.458263 -280.536276) (xy 49.481134 -280.579853) (xy 49.496718 -280.626534)
			(xy 49.504613 -280.675111) (xy 49.505108 -280.699718) (xy 50.79417 -280.699718) (xy 50.79813 -280.650664)
			(xy 50.809907 -280.60288) (xy 50.829198 -280.557604) (xy 50.855501 -280.516008) (xy 50.888136 -280.479171)
			(xy 50.926257 -280.448046) (xy 50.968878 -280.423439) (xy 51.014894 -280.405987) (xy 51.063113 -280.396143)
			(xy 51.112288 -280.394162) (xy 51.161143 -280.400094) (xy 51.208414 -280.413786) (xy 51.252876 -280.434884)
			(xy 51.293379 -280.46284) (xy 51.328872 -280.496932) (xy 51.358437 -280.536276) (xy 51.381308 -280.579853)
			(xy 51.396892 -280.626534) (xy 51.404787 -280.675111) (xy 51.405282 -280.699718) (xy 52.69409 -280.699718)
			(xy 52.69805 -280.650664) (xy 52.709827 -280.60288) (xy 52.729118 -280.557604) (xy 52.755421 -280.516008)
			(xy 52.788056 -280.479171) (xy 52.826177 -280.448046) (xy 52.868798 -280.423439) (xy 52.914814 -280.405987)
			(xy 52.963033 -280.396143) (xy 53.012208 -280.394162) (xy 53.061063 -280.400094) (xy 53.108334 -280.413786)
			(xy 53.152796 -280.434884) (xy 53.193299 -280.46284) (xy 53.228792 -280.496932) (xy 53.258357 -280.536276)
			(xy 53.281228 -280.579853) (xy 53.296812 -280.626534) (xy 53.304707 -280.675111) (xy 53.305202 -280.699718)
			(xy 54.59401 -280.699718) (xy 54.59797 -280.650664) (xy 54.609747 -280.60288) (xy 54.629038 -280.557604)
			(xy 54.655341 -280.516008) (xy 54.687976 -280.479171) (xy 54.726097 -280.448046) (xy 54.768718 -280.423439)
			(xy 54.814734 -280.405987) (xy 54.862953 -280.396143) (xy 54.912128 -280.394162) (xy 54.960983 -280.400094)
			(xy 55.008254 -280.413786) (xy 55.052716 -280.434884) (xy 55.093219 -280.46284) (xy 55.128712 -280.496932)
			(xy 55.158277 -280.536276) (xy 55.181148 -280.579853) (xy 55.196732 -280.626534) (xy 55.204627 -280.675111)
			(xy 55.205122 -280.699718) (xy 56.49393 -280.699718) (xy 56.49789 -280.650664) (xy 56.509667 -280.60288)
			(xy 56.528958 -280.557604) (xy 56.555261 -280.516008) (xy 56.587896 -280.479171) (xy 56.626017 -280.448046)
			(xy 56.668638 -280.423439) (xy 56.714654 -280.405987) (xy 56.762873 -280.396143) (xy 56.812048 -280.394162)
			(xy 56.860903 -280.400094) (xy 56.908174 -280.413786) (xy 56.952636 -280.434884) (xy 56.993139 -280.46284)
			(xy 57.028632 -280.496932) (xy 57.058197 -280.536276) (xy 57.081068 -280.579853) (xy 57.096652 -280.626534)
			(xy 57.104547 -280.675111) (xy 57.105042 -280.699718) (xy 58.394104 -280.699718) (xy 58.398064 -280.650664)
			(xy 58.409841 -280.60288) (xy 58.429132 -280.557604) (xy 58.455435 -280.516008) (xy 58.48807 -280.479171)
			(xy 58.526191 -280.448046) (xy 58.568812 -280.423439) (xy 58.614828 -280.405987) (xy 58.663047 -280.396143)
			(xy 58.712222 -280.394162) (xy 58.761077 -280.400094) (xy 58.808348 -280.413786) (xy 58.85281 -280.434884)
			(xy 58.893313 -280.46284) (xy 58.928806 -280.496932) (xy 58.958371 -280.536276) (xy 58.981242 -280.579853)
			(xy 58.996826 -280.626534) (xy 59.004721 -280.675111) (xy 59.005216 -280.699718) (xy 161.194254 -280.699718)
			(xy 161.198214 -280.650664) (xy 161.209991 -280.60288) (xy 161.229282 -280.557604) (xy 161.255585 -280.516008)
			(xy 161.28822 -280.479171) (xy 161.326341 -280.448046) (xy 161.368962 -280.423439) (xy 161.414978 -280.405987)
			(xy 161.463197 -280.396143) (xy 161.512372 -280.394162) (xy 161.561227 -280.400094) (xy 161.608498 -280.413786)
			(xy 161.65296 -280.434884) (xy 161.693463 -280.46284) (xy 161.728956 -280.496932) (xy 161.758521 -280.536276)
			(xy 161.781392 -280.579853) (xy 161.796976 -280.626534) (xy 161.804871 -280.675111) (xy 161.805366 -280.699718)
			(xy 163.094174 -280.699718) (xy 163.098134 -280.650664) (xy 163.109911 -280.60288) (xy 163.129202 -280.557604)
			(xy 163.155505 -280.516008) (xy 163.18814 -280.479171) (xy 163.226261 -280.448046) (xy 163.268882 -280.423439)
			(xy 163.314898 -280.405987) (xy 163.363117 -280.396143) (xy 163.412292 -280.394162) (xy 163.461147 -280.400094)
			(xy 163.508418 -280.413786) (xy 163.55288 -280.434884) (xy 163.593383 -280.46284) (xy 163.628876 -280.496932)
			(xy 163.658441 -280.536276) (xy 163.681312 -280.579853) (xy 163.696896 -280.626534) (xy 163.704791 -280.675111)
			(xy 163.705286 -280.699718) (xy 164.994094 -280.699718) (xy 164.998054 -280.650664) (xy 165.009831 -280.60288)
			(xy 165.029122 -280.557604) (xy 165.055425 -280.516008) (xy 165.08806 -280.479171) (xy 165.126181 -280.448046)
			(xy 165.168802 -280.423439) (xy 165.214818 -280.405987) (xy 165.263037 -280.396143) (xy 165.312212 -280.394162)
			(xy 165.361067 -280.400094) (xy 165.408338 -280.413786) (xy 165.4528 -280.434884) (xy 165.493303 -280.46284)
			(xy 165.528796 -280.496932) (xy 165.558361 -280.536276) (xy 165.581232 -280.579853) (xy 165.596816 -280.626534)
			(xy 165.604711 -280.675111) (xy 165.605206 -280.699718) (xy 166.894268 -280.699718) (xy 166.898228 -280.650664)
			(xy 166.910005 -280.60288) (xy 166.929296 -280.557604) (xy 166.955599 -280.516008) (xy 166.988234 -280.479171)
			(xy 167.026355 -280.448046) (xy 167.068976 -280.423439) (xy 167.114992 -280.405987) (xy 167.163211 -280.396143)
			(xy 167.212386 -280.394162) (xy 167.261241 -280.400094) (xy 167.308512 -280.413786) (xy 167.352974 -280.434884)
			(xy 167.393477 -280.46284) (xy 167.42897 -280.496932) (xy 167.458535 -280.536276) (xy 167.481406 -280.579853)
			(xy 167.49699 -280.626534) (xy 167.504885 -280.675111) (xy 167.50538 -280.699718) (xy 168.794188 -280.699718)
			(xy 168.798148 -280.650664) (xy 168.809925 -280.60288) (xy 168.829216 -280.557604) (xy 168.855519 -280.516008)
			(xy 168.888154 -280.479171) (xy 168.926275 -280.448046) (xy 168.968896 -280.423439) (xy 169.014912 -280.405987)
			(xy 169.063131 -280.396143) (xy 169.112306 -280.394162) (xy 169.161161 -280.400094) (xy 169.208432 -280.413786)
			(xy 169.252894 -280.434884) (xy 169.293397 -280.46284) (xy 169.32889 -280.496932) (xy 169.358455 -280.536276)
			(xy 169.381326 -280.579853) (xy 169.39691 -280.626534) (xy 169.404805 -280.675111) (xy 169.4053 -280.699718)
			(xy 170.694108 -280.699718) (xy 170.698068 -280.650664) (xy 170.709845 -280.60288) (xy 170.729136 -280.557604)
			(xy 170.755439 -280.516008) (xy 170.788074 -280.479171) (xy 170.826195 -280.448046) (xy 170.868816 -280.423439)
			(xy 170.914832 -280.405987) (xy 170.963051 -280.396143) (xy 171.012226 -280.394162) (xy 171.061081 -280.400094)
			(xy 171.108352 -280.413786) (xy 171.152814 -280.434884) (xy 171.193317 -280.46284) (xy 171.22881 -280.496932)
			(xy 171.258375 -280.536276) (xy 171.281246 -280.579853) (xy 171.29683 -280.626534) (xy 171.304725 -280.675111)
			(xy 171.30522 -280.699718) (xy 172.594028 -280.699718) (xy 172.597988 -280.650664) (xy 172.609765 -280.60288)
			(xy 172.629056 -280.557604) (xy 172.655359 -280.516008) (xy 172.687994 -280.479171) (xy 172.726115 -280.448046)
			(xy 172.768736 -280.423439) (xy 172.814752 -280.405987) (xy 172.862971 -280.396143) (xy 172.912146 -280.394162)
			(xy 172.961001 -280.400094) (xy 173.008272 -280.413786) (xy 173.052734 -280.434884) (xy 173.093237 -280.46284)
			(xy 173.12873 -280.496932) (xy 173.158295 -280.536276) (xy 173.181166 -280.579853) (xy 173.19675 -280.626534)
			(xy 173.204645 -280.675111) (xy 173.20514 -280.699718) (xy 174.494202 -280.699718) (xy 174.498162 -280.650664)
			(xy 174.509939 -280.60288) (xy 174.52923 -280.557604) (xy 174.555533 -280.516008) (xy 174.588168 -280.479171)
			(xy 174.626289 -280.448046) (xy 174.66891 -280.423439) (xy 174.714926 -280.405987) (xy 174.763145 -280.396143)
			(xy 174.81232 -280.394162) (xy 174.861175 -280.400094) (xy 174.908446 -280.413786) (xy 174.952908 -280.434884)
			(xy 174.993411 -280.46284) (xy 175.028904 -280.496932) (xy 175.058469 -280.536276) (xy 175.08134 -280.579853)
			(xy 175.096924 -280.626534) (xy 175.104819 -280.675111) (xy 175.105309 -280.699464) (xy 277.294098 -280.699464)
			(xy 277.298058 -280.65041) (xy 277.309835 -280.602626) (xy 277.329126 -280.55735) (xy 277.355429 -280.515754)
			(xy 277.388064 -280.478917) (xy 277.426185 -280.447792) (xy 277.468806 -280.423185) (xy 277.514822 -280.405733)
			(xy 277.563041 -280.395889) (xy 277.612216 -280.393908) (xy 277.661071 -280.39984) (xy 277.708342 -280.413532)
			(xy 277.752804 -280.43463) (xy 277.793307 -280.462586) (xy 277.8288 -280.496678) (xy 277.858365 -280.536022)
			(xy 277.881236 -280.579599) (xy 277.89682 -280.62628) (xy 277.904715 -280.674857) (xy 277.90521 -280.699464)
			(xy 279.194018 -280.699464) (xy 279.197978 -280.65041) (xy 279.209755 -280.602626) (xy 279.229046 -280.55735)
			(xy 279.255349 -280.515754) (xy 279.287984 -280.478917) (xy 279.326105 -280.447792) (xy 279.368726 -280.423185)
			(xy 279.414742 -280.405733) (xy 279.462961 -280.395889) (xy 279.512136 -280.393908) (xy 279.560991 -280.39984)
			(xy 279.608262 -280.413532) (xy 279.652724 -280.43463) (xy 279.693227 -280.462586) (xy 279.72872 -280.496678)
			(xy 279.758285 -280.536022) (xy 279.781156 -280.579599) (xy 279.79674 -280.62628) (xy 279.804635 -280.674857)
			(xy 279.80513 -280.699464) (xy 281.093938 -280.699464) (xy 281.097898 -280.65041) (xy 281.109675 -280.602626)
			(xy 281.128966 -280.55735) (xy 281.155269 -280.515754) (xy 281.187904 -280.478917) (xy 281.226025 -280.447792)
			(xy 281.268646 -280.423185) (xy 281.314662 -280.405733) (xy 281.362881 -280.395889) (xy 281.412056 -280.393908)
			(xy 281.460911 -280.39984) (xy 281.508182 -280.413532) (xy 281.552644 -280.43463) (xy 281.593147 -280.462586)
			(xy 281.62864 -280.496678) (xy 281.658205 -280.536022) (xy 281.681076 -280.579599) (xy 281.69666 -280.62628)
			(xy 281.704555 -280.674857) (xy 281.70505 -280.699464) (xy 282.994112 -280.699464) (xy 282.998072 -280.65041)
			(xy 283.009849 -280.602626) (xy 283.02914 -280.55735) (xy 283.055443 -280.515754) (xy 283.088078 -280.478917)
			(xy 283.126199 -280.447792) (xy 283.16882 -280.423185) (xy 283.214836 -280.405733) (xy 283.263055 -280.395889)
			(xy 283.31223 -280.393908) (xy 283.361085 -280.39984) (xy 283.408356 -280.413532) (xy 283.452818 -280.43463)
			(xy 283.493321 -280.462586) (xy 283.528814 -280.496678) (xy 283.558379 -280.536022) (xy 283.58125 -280.579599)
			(xy 283.596834 -280.62628) (xy 283.604729 -280.674857) (xy 283.605224 -280.699464) (xy 284.894032 -280.699464)
			(xy 284.897992 -280.65041) (xy 284.909769 -280.602626) (xy 284.92906 -280.55735) (xy 284.955363 -280.515754)
			(xy 284.987998 -280.478917) (xy 285.026119 -280.447792) (xy 285.06874 -280.423185) (xy 285.114756 -280.405733)
			(xy 285.162975 -280.395889) (xy 285.21215 -280.393908) (xy 285.261005 -280.39984) (xy 285.308276 -280.413532)
			(xy 285.352738 -280.43463) (xy 285.393241 -280.462586) (xy 285.428734 -280.496678) (xy 285.458299 -280.536022)
			(xy 285.48117 -280.579599) (xy 285.496754 -280.62628) (xy 285.504649 -280.674857) (xy 285.505144 -280.699464)
			(xy 286.793952 -280.699464) (xy 286.797912 -280.65041) (xy 286.809689 -280.602626) (xy 286.82898 -280.55735)
			(xy 286.855283 -280.515754) (xy 286.887918 -280.478917) (xy 286.926039 -280.447792) (xy 286.96866 -280.423185)
			(xy 287.014676 -280.405733) (xy 287.062895 -280.395889) (xy 287.11207 -280.393908) (xy 287.160925 -280.39984)
			(xy 287.208196 -280.413532) (xy 287.252658 -280.43463) (xy 287.293161 -280.462586) (xy 287.328654 -280.496678)
			(xy 287.358219 -280.536022) (xy 287.38109 -280.579599) (xy 287.396674 -280.62628) (xy 287.404569 -280.674857)
			(xy 287.405064 -280.699464) (xy 288.693872 -280.699464) (xy 288.697832 -280.65041) (xy 288.709609 -280.602626)
			(xy 288.7289 -280.55735) (xy 288.755203 -280.515754) (xy 288.787838 -280.478917) (xy 288.825959 -280.447792)
			(xy 288.86858 -280.423185) (xy 288.914596 -280.405733) (xy 288.962815 -280.395889) (xy 289.01199 -280.393908)
			(xy 289.060845 -280.39984) (xy 289.108116 -280.413532) (xy 289.152578 -280.43463) (xy 289.193081 -280.462586)
			(xy 289.228574 -280.496678) (xy 289.258139 -280.536022) (xy 289.28101 -280.579599) (xy 289.296594 -280.62628)
			(xy 289.304489 -280.674857) (xy 289.304984 -280.699464) (xy 290.594046 -280.699464) (xy 290.598006 -280.65041)
			(xy 290.609783 -280.602626) (xy 290.629074 -280.55735) (xy 290.655377 -280.515754) (xy 290.688012 -280.478917)
			(xy 290.726133 -280.447792) (xy 290.768754 -280.423185) (xy 290.81477 -280.405733) (xy 290.862989 -280.395889)
			(xy 290.912164 -280.393908) (xy 290.961019 -280.39984) (xy 291.00829 -280.413532) (xy 291.052752 -280.43463)
			(xy 291.093255 -280.462586) (xy 291.128748 -280.496678) (xy 291.158313 -280.536022) (xy 291.181184 -280.579599)
			(xy 291.196768 -280.62628) (xy 291.204663 -280.674857) (xy 291.205158 -280.699464) (xy 393.394196 -280.699464)
			(xy 393.398156 -280.65041) (xy 393.409933 -280.602626) (xy 393.429224 -280.55735) (xy 393.455527 -280.515754)
			(xy 393.488162 -280.478917) (xy 393.526283 -280.447792) (xy 393.568904 -280.423185) (xy 393.61492 -280.405733)
			(xy 393.663139 -280.395889) (xy 393.712314 -280.393908) (xy 393.761169 -280.39984) (xy 393.80844 -280.413532)
			(xy 393.852902 -280.43463) (xy 393.893405 -280.462586) (xy 393.928898 -280.496678) (xy 393.958463 -280.536022)
			(xy 393.981334 -280.579599) (xy 393.996918 -280.62628) (xy 394.004813 -280.674857) (xy 394.005308 -280.699464)
			(xy 395.294116 -280.699464) (xy 395.298076 -280.65041) (xy 395.309853 -280.602626) (xy 395.329144 -280.55735)
			(xy 395.355447 -280.515754) (xy 395.388082 -280.478917) (xy 395.426203 -280.447792) (xy 395.468824 -280.423185)
			(xy 395.51484 -280.405733) (xy 395.563059 -280.395889) (xy 395.612234 -280.393908) (xy 395.661089 -280.39984)
			(xy 395.70836 -280.413532) (xy 395.752822 -280.43463) (xy 395.793325 -280.462586) (xy 395.828818 -280.496678)
			(xy 395.858383 -280.536022) (xy 395.881254 -280.579599) (xy 395.896838 -280.62628) (xy 395.904733 -280.674857)
			(xy 395.905228 -280.699464) (xy 397.194036 -280.699464) (xy 397.197996 -280.65041) (xy 397.209773 -280.602626)
			(xy 397.229064 -280.55735) (xy 397.255367 -280.515754) (xy 397.288002 -280.478917) (xy 397.326123 -280.447792)
			(xy 397.368744 -280.423185) (xy 397.41476 -280.405733) (xy 397.462979 -280.395889) (xy 397.512154 -280.393908)
			(xy 397.561009 -280.39984) (xy 397.60828 -280.413532) (xy 397.652742 -280.43463) (xy 397.693245 -280.462586)
			(xy 397.728738 -280.496678) (xy 397.758303 -280.536022) (xy 397.781174 -280.579599) (xy 397.796758 -280.62628)
			(xy 397.804653 -280.674857) (xy 397.805148 -280.699464) (xy 399.09421 -280.699464) (xy 399.09817 -280.65041)
			(xy 399.109947 -280.602626) (xy 399.129238 -280.55735) (xy 399.155541 -280.515754) (xy 399.188176 -280.478917)
			(xy 399.226297 -280.447792) (xy 399.268918 -280.423185) (xy 399.314934 -280.405733) (xy 399.363153 -280.395889)
			(xy 399.412328 -280.393908) (xy 399.461183 -280.39984) (xy 399.508454 -280.413532) (xy 399.552916 -280.43463)
			(xy 399.593419 -280.462586) (xy 399.628912 -280.496678) (xy 399.658477 -280.536022) (xy 399.681348 -280.579599)
			(xy 399.696932 -280.62628) (xy 399.704827 -280.674857) (xy 399.705322 -280.699464) (xy 400.99413 -280.699464)
			(xy 400.99809 -280.65041) (xy 401.009867 -280.602626) (xy 401.029158 -280.55735) (xy 401.055461 -280.515754)
			(xy 401.088096 -280.478917) (xy 401.126217 -280.447792) (xy 401.168838 -280.423185) (xy 401.214854 -280.405733)
			(xy 401.263073 -280.395889) (xy 401.312248 -280.393908) (xy 401.361103 -280.39984) (xy 401.408374 -280.413532)
			(xy 401.452836 -280.43463) (xy 401.493339 -280.462586) (xy 401.528832 -280.496678) (xy 401.558397 -280.536022)
			(xy 401.581268 -280.579599) (xy 401.596852 -280.62628) (xy 401.604747 -280.674857) (xy 401.605242 -280.699464)
			(xy 402.89405 -280.699464) (xy 402.89801 -280.65041) (xy 402.909787 -280.602626) (xy 402.929078 -280.55735)
			(xy 402.955381 -280.515754) (xy 402.988016 -280.478917) (xy 403.026137 -280.447792) (xy 403.068758 -280.423185)
			(xy 403.114774 -280.405733) (xy 403.162993 -280.395889) (xy 403.212168 -280.393908) (xy 403.261023 -280.39984)
			(xy 403.308294 -280.413532) (xy 403.352756 -280.43463) (xy 403.393259 -280.462586) (xy 403.428752 -280.496678)
			(xy 403.458317 -280.536022) (xy 403.481188 -280.579599) (xy 403.496772 -280.62628) (xy 403.504667 -280.674857)
			(xy 403.505162 -280.699464) (xy 404.79397 -280.699464) (xy 404.79793 -280.65041) (xy 404.809707 -280.602626)
			(xy 404.828998 -280.55735) (xy 404.855301 -280.515754) (xy 404.887936 -280.478917) (xy 404.926057 -280.447792)
			(xy 404.968678 -280.423185) (xy 405.014694 -280.405733) (xy 405.062913 -280.395889) (xy 405.112088 -280.393908)
			(xy 405.160943 -280.39984) (xy 405.208214 -280.413532) (xy 405.252676 -280.43463) (xy 405.293179 -280.462586)
			(xy 405.328672 -280.496678) (xy 405.358237 -280.536022) (xy 405.381108 -280.579599) (xy 405.396692 -280.62628)
			(xy 405.404587 -280.674857) (xy 405.405082 -280.699464) (xy 406.694144 -280.699464) (xy 406.698104 -280.65041)
			(xy 406.709881 -280.602626) (xy 406.729172 -280.55735) (xy 406.755475 -280.515754) (xy 406.78811 -280.478917)
			(xy 406.826231 -280.447792) (xy 406.868852 -280.423185) (xy 406.914868 -280.405733) (xy 406.963087 -280.395889)
			(xy 407.012262 -280.393908) (xy 407.061117 -280.39984) (xy 407.108388 -280.413532) (xy 407.15285 -280.43463)
			(xy 407.193353 -280.462586) (xy 407.228846 -280.496678) (xy 407.258411 -280.536022) (xy 407.281282 -280.579599)
			(xy 407.296866 -280.62628) (xy 407.304761 -280.674857) (xy 407.305256 -280.699464) (xy 407.304761 -280.724071)
			(xy 407.296866 -280.772648) (xy 407.281282 -280.819329) (xy 407.258411 -280.862906) (xy 407.228846 -280.90225)
			(xy 407.193353 -280.936342) (xy 407.15285 -280.964298) (xy 407.108388 -280.985396) (xy 407.061117 -280.999088)
			(xy 407.012262 -281.00502) (xy 406.963087 -281.003039) (xy 406.914868 -280.993195) (xy 406.868852 -280.975743)
			(xy 406.826231 -280.951136) (xy 406.78811 -280.920011) (xy 406.755475 -280.883174) (xy 406.729172 -280.841578)
			(xy 406.709881 -280.796302) (xy 406.698104 -280.748518) (xy 406.694144 -280.699464) (xy 405.405082 -280.699464)
			(xy 405.404587 -280.724071) (xy 405.396692 -280.772648) (xy 405.381108 -280.819329) (xy 405.358237 -280.862906)
			(xy 405.328672 -280.90225) (xy 405.293179 -280.936342) (xy 405.252676 -280.964298) (xy 405.208214 -280.985396)
			(xy 405.160943 -280.999088) (xy 405.112088 -281.00502) (xy 405.062913 -281.003039) (xy 405.014694 -280.993195)
			(xy 404.968678 -280.975743) (xy 404.926057 -280.951136) (xy 404.887936 -280.920011) (xy 404.855301 -280.883174)
			(xy 404.828998 -280.841578) (xy 404.809707 -280.796302) (xy 404.79793 -280.748518) (xy 404.79397 -280.699464)
			(xy 403.505162 -280.699464) (xy 403.504667 -280.724071) (xy 403.496772 -280.772648) (xy 403.481188 -280.819329)
			(xy 403.458317 -280.862906) (xy 403.428752 -280.90225) (xy 403.393259 -280.936342) (xy 403.352756 -280.964298)
			(xy 403.308294 -280.985396) (xy 403.261023 -280.999088) (xy 403.212168 -281.00502) (xy 403.162993 -281.003039)
			(xy 403.114774 -280.993195) (xy 403.068758 -280.975743) (xy 403.026137 -280.951136) (xy 402.988016 -280.920011)
			(xy 402.955381 -280.883174) (xy 402.929078 -280.841578) (xy 402.909787 -280.796302) (xy 402.89801 -280.748518)
			(xy 402.89405 -280.699464) (xy 401.605242 -280.699464) (xy 401.604747 -280.724071) (xy 401.596852 -280.772648)
			(xy 401.581268 -280.819329) (xy 401.558397 -280.862906) (xy 401.528832 -280.90225) (xy 401.493339 -280.936342)
			(xy 401.452836 -280.964298) (xy 401.408374 -280.985396) (xy 401.361103 -280.999088) (xy 401.312248 -281.00502)
			(xy 401.263073 -281.003039) (xy 401.214854 -280.993195) (xy 401.168838 -280.975743) (xy 401.126217 -280.951136)
			(xy 401.088096 -280.920011) (xy 401.055461 -280.883174) (xy 401.029158 -280.841578) (xy 401.009867 -280.796302)
			(xy 400.99809 -280.748518) (xy 400.99413 -280.699464) (xy 399.705322 -280.699464) (xy 399.704827 -280.724071)
			(xy 399.696932 -280.772648) (xy 399.681348 -280.819329) (xy 399.658477 -280.862906) (xy 399.628912 -280.90225)
			(xy 399.593419 -280.936342) (xy 399.552916 -280.964298) (xy 399.508454 -280.985396) (xy 399.461183 -280.999088)
			(xy 399.412328 -281.00502) (xy 399.363153 -281.003039) (xy 399.314934 -280.993195) (xy 399.268918 -280.975743)
			(xy 399.226297 -280.951136) (xy 399.188176 -280.920011) (xy 399.155541 -280.883174) (xy 399.129238 -280.841578)
			(xy 399.109947 -280.796302) (xy 399.09817 -280.748518) (xy 399.09421 -280.699464) (xy 397.805148 -280.699464)
			(xy 397.804653 -280.724071) (xy 397.796758 -280.772648) (xy 397.781174 -280.819329) (xy 397.758303 -280.862906)
			(xy 397.728738 -280.90225) (xy 397.693245 -280.936342) (xy 397.652742 -280.964298) (xy 397.60828 -280.985396)
			(xy 397.561009 -280.999088) (xy 397.512154 -281.00502) (xy 397.462979 -281.003039) (xy 397.41476 -280.993195)
			(xy 397.368744 -280.975743) (xy 397.326123 -280.951136) (xy 397.288002 -280.920011) (xy 397.255367 -280.883174)
			(xy 397.229064 -280.841578) (xy 397.209773 -280.796302) (xy 397.197996 -280.748518) (xy 397.194036 -280.699464)
			(xy 395.905228 -280.699464) (xy 395.904733 -280.724071) (xy 395.896838 -280.772648) (xy 395.881254 -280.819329)
			(xy 395.858383 -280.862906) (xy 395.828818 -280.90225) (xy 395.793325 -280.936342) (xy 395.752822 -280.964298)
			(xy 395.70836 -280.985396) (xy 395.661089 -280.999088) (xy 395.612234 -281.00502) (xy 395.563059 -281.003039)
			(xy 395.51484 -280.993195) (xy 395.468824 -280.975743) (xy 395.426203 -280.951136) (xy 395.388082 -280.920011)
			(xy 395.355447 -280.883174) (xy 395.329144 -280.841578) (xy 395.309853 -280.796302) (xy 395.298076 -280.748518)
			(xy 395.294116 -280.699464) (xy 394.005308 -280.699464) (xy 394.004813 -280.724071) (xy 393.996918 -280.772648)
			(xy 393.981334 -280.819329) (xy 393.958463 -280.862906) (xy 393.928898 -280.90225) (xy 393.893405 -280.936342)
			(xy 393.852902 -280.964298) (xy 393.80844 -280.985396) (xy 393.761169 -280.999088) (xy 393.712314 -281.00502)
			(xy 393.663139 -281.003039) (xy 393.61492 -280.993195) (xy 393.568904 -280.975743) (xy 393.526283 -280.951136)
			(xy 393.488162 -280.920011) (xy 393.455527 -280.883174) (xy 393.429224 -280.841578) (xy 393.409933 -280.796302)
			(xy 393.398156 -280.748518) (xy 393.394196 -280.699464) (xy 291.205158 -280.699464) (xy 291.204663 -280.724071)
			(xy 291.196768 -280.772648) (xy 291.181184 -280.819329) (xy 291.158313 -280.862906) (xy 291.128748 -280.90225)
			(xy 291.093255 -280.936342) (xy 291.052752 -280.964298) (xy 291.00829 -280.985396) (xy 290.961019 -280.999088)
			(xy 290.912164 -281.00502) (xy 290.862989 -281.003039) (xy 290.81477 -280.993195) (xy 290.768754 -280.975743)
			(xy 290.726133 -280.951136) (xy 290.688012 -280.920011) (xy 290.655377 -280.883174) (xy 290.629074 -280.841578)
			(xy 290.609783 -280.796302) (xy 290.598006 -280.748518) (xy 290.594046 -280.699464) (xy 289.304984 -280.699464)
			(xy 289.304489 -280.724071) (xy 289.296594 -280.772648) (xy 289.28101 -280.819329) (xy 289.258139 -280.862906)
			(xy 289.228574 -280.90225) (xy 289.193081 -280.936342) (xy 289.152578 -280.964298) (xy 289.108116 -280.985396)
			(xy 289.060845 -280.999088) (xy 289.01199 -281.00502) (xy 288.962815 -281.003039) (xy 288.914596 -280.993195)
			(xy 288.86858 -280.975743) (xy 288.825959 -280.951136) (xy 288.787838 -280.920011) (xy 288.755203 -280.883174)
			(xy 288.7289 -280.841578) (xy 288.709609 -280.796302) (xy 288.697832 -280.748518) (xy 288.693872 -280.699464)
			(xy 287.405064 -280.699464) (xy 287.404569 -280.724071) (xy 287.396674 -280.772648) (xy 287.38109 -280.819329)
			(xy 287.358219 -280.862906) (xy 287.328654 -280.90225) (xy 287.293161 -280.936342) (xy 287.252658 -280.964298)
			(xy 287.208196 -280.985396) (xy 287.160925 -280.999088) (xy 287.11207 -281.00502) (xy 287.062895 -281.003039)
			(xy 287.014676 -280.993195) (xy 286.96866 -280.975743) (xy 286.926039 -280.951136) (xy 286.887918 -280.920011)
			(xy 286.855283 -280.883174) (xy 286.82898 -280.841578) (xy 286.809689 -280.796302) (xy 286.797912 -280.748518)
			(xy 286.793952 -280.699464) (xy 285.505144 -280.699464) (xy 285.504649 -280.724071) (xy 285.496754 -280.772648)
			(xy 285.48117 -280.819329) (xy 285.458299 -280.862906) (xy 285.428734 -280.90225) (xy 285.393241 -280.936342)
			(xy 285.352738 -280.964298) (xy 285.308276 -280.985396) (xy 285.261005 -280.999088) (xy 285.21215 -281.00502)
			(xy 285.162975 -281.003039) (xy 285.114756 -280.993195) (xy 285.06874 -280.975743) (xy 285.026119 -280.951136)
			(xy 284.987998 -280.920011) (xy 284.955363 -280.883174) (xy 284.92906 -280.841578) (xy 284.909769 -280.796302)
			(xy 284.897992 -280.748518) (xy 284.894032 -280.699464) (xy 283.605224 -280.699464) (xy 283.604729 -280.724071)
			(xy 283.596834 -280.772648) (xy 283.58125 -280.819329) (xy 283.558379 -280.862906) (xy 283.528814 -280.90225)
			(xy 283.493321 -280.936342) (xy 283.452818 -280.964298) (xy 283.408356 -280.985396) (xy 283.361085 -280.999088)
			(xy 283.31223 -281.00502) (xy 283.263055 -281.003039) (xy 283.214836 -280.993195) (xy 283.16882 -280.975743)
			(xy 283.126199 -280.951136) (xy 283.088078 -280.920011) (xy 283.055443 -280.883174) (xy 283.02914 -280.841578)
			(xy 283.009849 -280.796302) (xy 282.998072 -280.748518) (xy 282.994112 -280.699464) (xy 281.70505 -280.699464)
			(xy 281.704555 -280.724071) (xy 281.69666 -280.772648) (xy 281.681076 -280.819329) (xy 281.658205 -280.862906)
			(xy 281.62864 -280.90225) (xy 281.593147 -280.936342) (xy 281.552644 -280.964298) (xy 281.508182 -280.985396)
			(xy 281.460911 -280.999088) (xy 281.412056 -281.00502) (xy 281.362881 -281.003039) (xy 281.314662 -280.993195)
			(xy 281.268646 -280.975743) (xy 281.226025 -280.951136) (xy 281.187904 -280.920011) (xy 281.155269 -280.883174)
			(xy 281.128966 -280.841578) (xy 281.109675 -280.796302) (xy 281.097898 -280.748518) (xy 281.093938 -280.699464)
			(xy 279.80513 -280.699464) (xy 279.804635 -280.724071) (xy 279.79674 -280.772648) (xy 279.781156 -280.819329)
			(xy 279.758285 -280.862906) (xy 279.72872 -280.90225) (xy 279.693227 -280.936342) (xy 279.652724 -280.964298)
			(xy 279.608262 -280.985396) (xy 279.560991 -280.999088) (xy 279.512136 -281.00502) (xy 279.462961 -281.003039)
			(xy 279.414742 -280.993195) (xy 279.368726 -280.975743) (xy 279.326105 -280.951136) (xy 279.287984 -280.920011)
			(xy 279.255349 -280.883174) (xy 279.229046 -280.841578) (xy 279.209755 -280.796302) (xy 279.197978 -280.748518)
			(xy 279.194018 -280.699464) (xy 277.90521 -280.699464) (xy 277.904715 -280.724071) (xy 277.89682 -280.772648)
			(xy 277.881236 -280.819329) (xy 277.858365 -280.862906) (xy 277.8288 -280.90225) (xy 277.793307 -280.936342)
			(xy 277.752804 -280.964298) (xy 277.708342 -280.985396) (xy 277.661071 -280.999088) (xy 277.612216 -281.00502)
			(xy 277.563041 -281.003039) (xy 277.514822 -280.993195) (xy 277.468806 -280.975743) (xy 277.426185 -280.951136)
			(xy 277.388064 -280.920011) (xy 277.355429 -280.883174) (xy 277.329126 -280.841578) (xy 277.309835 -280.796302)
			(xy 277.298058 -280.748518) (xy 277.294098 -280.699464) (xy 175.105309 -280.699464) (xy 175.105314 -280.699718)
			(xy 175.104819 -280.724325) (xy 175.096924 -280.772902) (xy 175.08134 -280.819583) (xy 175.058469 -280.86316)
			(xy 175.028904 -280.902504) (xy 174.993411 -280.936596) (xy 174.952908 -280.964552) (xy 174.908446 -280.98565)
			(xy 174.861175 -280.999342) (xy 174.81232 -281.005274) (xy 174.763145 -281.003293) (xy 174.714926 -280.993449)
			(xy 174.66891 -280.975997) (xy 174.626289 -280.95139) (xy 174.588168 -280.920265) (xy 174.555533 -280.883428)
			(xy 174.52923 -280.841832) (xy 174.509939 -280.796556) (xy 174.498162 -280.748772) (xy 174.494202 -280.699718)
			(xy 173.20514 -280.699718) (xy 173.204645 -280.724325) (xy 173.19675 -280.772902) (xy 173.181166 -280.819583)
			(xy 173.158295 -280.86316) (xy 173.12873 -280.902504) (xy 173.093237 -280.936596) (xy 173.052734 -280.964552)
			(xy 173.008272 -280.98565) (xy 172.961001 -280.999342) (xy 172.912146 -281.005274) (xy 172.862971 -281.003293)
			(xy 172.814752 -280.993449) (xy 172.768736 -280.975997) (xy 172.726115 -280.95139) (xy 172.687994 -280.920265)
			(xy 172.655359 -280.883428) (xy 172.629056 -280.841832) (xy 172.609765 -280.796556) (xy 172.597988 -280.748772)
			(xy 172.594028 -280.699718) (xy 171.30522 -280.699718) (xy 171.304725 -280.724325) (xy 171.29683 -280.772902)
			(xy 171.281246 -280.819583) (xy 171.258375 -280.86316) (xy 171.22881 -280.902504) (xy 171.193317 -280.936596)
			(xy 171.152814 -280.964552) (xy 171.108352 -280.98565) (xy 171.061081 -280.999342) (xy 171.012226 -281.005274)
			(xy 170.963051 -281.003293) (xy 170.914832 -280.993449) (xy 170.868816 -280.975997) (xy 170.826195 -280.95139)
			(xy 170.788074 -280.920265) (xy 170.755439 -280.883428) (xy 170.729136 -280.841832) (xy 170.709845 -280.796556)
			(xy 170.698068 -280.748772) (xy 170.694108 -280.699718) (xy 169.4053 -280.699718) (xy 169.404805 -280.724325)
			(xy 169.39691 -280.772902) (xy 169.381326 -280.819583) (xy 169.358455 -280.86316) (xy 169.32889 -280.902504)
			(xy 169.293397 -280.936596) (xy 169.252894 -280.964552) (xy 169.208432 -280.98565) (xy 169.161161 -280.999342)
			(xy 169.112306 -281.005274) (xy 169.063131 -281.003293) (xy 169.014912 -280.993449) (xy 168.968896 -280.975997)
			(xy 168.926275 -280.95139) (xy 168.888154 -280.920265) (xy 168.855519 -280.883428) (xy 168.829216 -280.841832)
			(xy 168.809925 -280.796556) (xy 168.798148 -280.748772) (xy 168.794188 -280.699718) (xy 167.50538 -280.699718)
			(xy 167.504885 -280.724325) (xy 167.49699 -280.772902) (xy 167.481406 -280.819583) (xy 167.458535 -280.86316)
			(xy 167.42897 -280.902504) (xy 167.393477 -280.936596) (xy 167.352974 -280.964552) (xy 167.308512 -280.98565)
			(xy 167.261241 -280.999342) (xy 167.212386 -281.005274) (xy 167.163211 -281.003293) (xy 167.114992 -280.993449)
			(xy 167.068976 -280.975997) (xy 167.026355 -280.95139) (xy 166.988234 -280.920265) (xy 166.955599 -280.883428)
			(xy 166.929296 -280.841832) (xy 166.910005 -280.796556) (xy 166.898228 -280.748772) (xy 166.894268 -280.699718)
			(xy 165.605206 -280.699718) (xy 165.604711 -280.724325) (xy 165.596816 -280.772902) (xy 165.581232 -280.819583)
			(xy 165.558361 -280.86316) (xy 165.528796 -280.902504) (xy 165.493303 -280.936596) (xy 165.4528 -280.964552)
			(xy 165.408338 -280.98565) (xy 165.361067 -280.999342) (xy 165.312212 -281.005274) (xy 165.263037 -281.003293)
			(xy 165.214818 -280.993449) (xy 165.168802 -280.975997) (xy 165.126181 -280.95139) (xy 165.08806 -280.920265)
			(xy 165.055425 -280.883428) (xy 165.029122 -280.841832) (xy 165.009831 -280.796556) (xy 164.998054 -280.748772)
			(xy 164.994094 -280.699718) (xy 163.705286 -280.699718) (xy 163.704791 -280.724325) (xy 163.696896 -280.772902)
			(xy 163.681312 -280.819583) (xy 163.658441 -280.86316) (xy 163.628876 -280.902504) (xy 163.593383 -280.936596)
			(xy 163.55288 -280.964552) (xy 163.508418 -280.98565) (xy 163.461147 -280.999342) (xy 163.412292 -281.005274)
			(xy 163.363117 -281.003293) (xy 163.314898 -280.993449) (xy 163.268882 -280.975997) (xy 163.226261 -280.95139)
			(xy 163.18814 -280.920265) (xy 163.155505 -280.883428) (xy 163.129202 -280.841832) (xy 163.109911 -280.796556)
			(xy 163.098134 -280.748772) (xy 163.094174 -280.699718) (xy 161.805366 -280.699718) (xy 161.804871 -280.724325)
			(xy 161.796976 -280.772902) (xy 161.781392 -280.819583) (xy 161.758521 -280.86316) (xy 161.728956 -280.902504)
			(xy 161.693463 -280.936596) (xy 161.65296 -280.964552) (xy 161.608498 -280.98565) (xy 161.561227 -280.999342)
			(xy 161.512372 -281.005274) (xy 161.463197 -281.003293) (xy 161.414978 -280.993449) (xy 161.368962 -280.975997)
			(xy 161.326341 -280.95139) (xy 161.28822 -280.920265) (xy 161.255585 -280.883428) (xy 161.229282 -280.841832)
			(xy 161.209991 -280.796556) (xy 161.198214 -280.748772) (xy 161.194254 -280.699718) (xy 59.005216 -280.699718)
			(xy 59.004721 -280.724325) (xy 58.996826 -280.772902) (xy 58.981242 -280.819583) (xy 58.958371 -280.86316)
			(xy 58.928806 -280.902504) (xy 58.893313 -280.936596) (xy 58.85281 -280.964552) (xy 58.808348 -280.98565)
			(xy 58.761077 -280.999342) (xy 58.712222 -281.005274) (xy 58.663047 -281.003293) (xy 58.614828 -280.993449)
			(xy 58.568812 -280.975997) (xy 58.526191 -280.95139) (xy 58.48807 -280.920265) (xy 58.455435 -280.883428)
			(xy 58.429132 -280.841832) (xy 58.409841 -280.796556) (xy 58.398064 -280.748772) (xy 58.394104 -280.699718)
			(xy 57.105042 -280.699718) (xy 57.104547 -280.724325) (xy 57.096652 -280.772902) (xy 57.081068 -280.819583)
			(xy 57.058197 -280.86316) (xy 57.028632 -280.902504) (xy 56.993139 -280.936596) (xy 56.952636 -280.964552)
			(xy 56.908174 -280.98565) (xy 56.860903 -280.999342) (xy 56.812048 -281.005274) (xy 56.762873 -281.003293)
			(xy 56.714654 -280.993449) (xy 56.668638 -280.975997) (xy 56.626017 -280.95139) (xy 56.587896 -280.920265)
			(xy 56.555261 -280.883428) (xy 56.528958 -280.841832) (xy 56.509667 -280.796556) (xy 56.49789 -280.748772)
			(xy 56.49393 -280.699718) (xy 55.205122 -280.699718) (xy 55.204627 -280.724325) (xy 55.196732 -280.772902)
			(xy 55.181148 -280.819583) (xy 55.158277 -280.86316) (xy 55.128712 -280.902504) (xy 55.093219 -280.936596)
			(xy 55.052716 -280.964552) (xy 55.008254 -280.98565) (xy 54.960983 -280.999342) (xy 54.912128 -281.005274)
			(xy 54.862953 -281.003293) (xy 54.814734 -280.993449) (xy 54.768718 -280.975997) (xy 54.726097 -280.95139)
			(xy 54.687976 -280.920265) (xy 54.655341 -280.883428) (xy 54.629038 -280.841832) (xy 54.609747 -280.796556)
			(xy 54.59797 -280.748772) (xy 54.59401 -280.699718) (xy 53.305202 -280.699718) (xy 53.304707 -280.724325)
			(xy 53.296812 -280.772902) (xy 53.281228 -280.819583) (xy 53.258357 -280.86316) (xy 53.228792 -280.902504)
			(xy 53.193299 -280.936596) (xy 53.152796 -280.964552) (xy 53.108334 -280.98565) (xy 53.061063 -280.999342)
			(xy 53.012208 -281.005274) (xy 52.963033 -281.003293) (xy 52.914814 -280.993449) (xy 52.868798 -280.975997)
			(xy 52.826177 -280.95139) (xy 52.788056 -280.920265) (xy 52.755421 -280.883428) (xy 52.729118 -280.841832)
			(xy 52.709827 -280.796556) (xy 52.69805 -280.748772) (xy 52.69409 -280.699718) (xy 51.405282 -280.699718)
			(xy 51.404787 -280.724325) (xy 51.396892 -280.772902) (xy 51.381308 -280.819583) (xy 51.358437 -280.86316)
			(xy 51.328872 -280.902504) (xy 51.293379 -280.936596) (xy 51.252876 -280.964552) (xy 51.208414 -280.98565)
			(xy 51.161143 -280.999342) (xy 51.112288 -281.005274) (xy 51.063113 -281.003293) (xy 51.014894 -280.993449)
			(xy 50.968878 -280.975997) (xy 50.926257 -280.95139) (xy 50.888136 -280.920265) (xy 50.855501 -280.883428)
			(xy 50.829198 -280.841832) (xy 50.809907 -280.796556) (xy 50.79813 -280.748772) (xy 50.79417 -280.699718)
			(xy 49.505108 -280.699718) (xy 49.504613 -280.724325) (xy 49.496718 -280.772902) (xy 49.481134 -280.819583)
			(xy 49.458263 -280.86316) (xy 49.428698 -280.902504) (xy 49.393205 -280.936596) (xy 49.352702 -280.964552)
			(xy 49.30824 -280.98565) (xy 49.260969 -280.999342) (xy 49.212114 -281.005274) (xy 49.162939 -281.003293)
			(xy 49.11472 -280.993449) (xy 49.068704 -280.975997) (xy 49.026083 -280.95139) (xy 48.987962 -280.920265)
			(xy 48.955327 -280.883428) (xy 48.929024 -280.841832) (xy 48.909733 -280.796556) (xy 48.897956 -280.748772)
			(xy 48.893996 -280.699718) (xy 47.605188 -280.699718) (xy 47.604693 -280.724325) (xy 47.596798 -280.772902)
			(xy 47.581214 -280.819583) (xy 47.558343 -280.86316) (xy 47.528778 -280.902504) (xy 47.493285 -280.936596)
			(xy 47.452782 -280.964552) (xy 47.40832 -280.98565) (xy 47.361049 -280.999342) (xy 47.312194 -281.005274)
			(xy 47.263019 -281.003293) (xy 47.2148 -280.993449) (xy 47.168784 -280.975997) (xy 47.126163 -280.95139)
			(xy 47.088042 -280.920265) (xy 47.055407 -280.883428) (xy 47.029104 -280.841832) (xy 47.009813 -280.796556)
			(xy 46.998036 -280.748772) (xy 46.994076 -280.699718) (xy 45.705268 -280.699718) (xy 45.704773 -280.724325)
			(xy 45.696878 -280.772902) (xy 45.681294 -280.819583) (xy 45.658423 -280.86316) (xy 45.628858 -280.902504)
			(xy 45.593365 -280.936596) (xy 45.552862 -280.964552) (xy 45.5084 -280.98565) (xy 45.461129 -280.999342)
			(xy 45.412274 -281.005274) (xy 45.363099 -281.003293) (xy 45.31488 -280.993449) (xy 45.268864 -280.975997)
			(xy 45.226243 -280.95139) (xy 45.188122 -280.920265) (xy 45.155487 -280.883428) (xy 45.129184 -280.841832)
			(xy 45.109893 -280.796556) (xy 45.098116 -280.748772) (xy 45.094156 -280.699718) (xy 0.508 -280.699718)
			(xy 0.508 -287.850408) (xy 37.944539 -287.850408) (xy 37.944539 -287.798392) (xy 37.952677 -287.747016)
			(xy 37.968751 -287.697546) (xy 37.992366 -287.651199) (xy 38.02294 -287.609117) (xy 38.059722 -287.572337)
			(xy 38.101804 -287.541763) (xy 38.148151 -287.518148) (xy 38.197622 -287.502075) (xy 38.248998 -287.493939)
			(xy 38.275006 -287.493456) (xy 39.224966 -287.493456) (xy 39.250978 -287.493901) (xy 39.302363 -287.502035)
			(xy 39.351843 -287.518107) (xy 39.398199 -287.541722) (xy 39.44029 -287.572299) (xy 39.477079 -287.609084)
			(xy 39.50766 -287.651172) (xy 39.53128 -287.697525) (xy 39.547357 -287.747004) (xy 39.555496 -287.798388)
			(xy 39.555496 -287.850405) (xy 40.794466 -287.850405) (xy 40.794466 -287.798395) (xy 40.802602 -287.747025)
			(xy 40.818674 -287.697561) (xy 40.842285 -287.651219) (xy 40.872855 -287.609142) (xy 40.909631 -287.572364)
			(xy 40.951707 -287.541792) (xy 40.998048 -287.518179) (xy 41.047512 -287.502105) (xy 41.098881 -287.493967)
			(xy 41.124886 -287.493456) (xy 42.074846 -287.493456) (xy 42.100852 -287.493934) (xy 42.152223 -287.502077)
			(xy 42.201688 -287.518155) (xy 42.248029 -287.541773) (xy 42.290106 -287.572348) (xy 42.326882 -287.609129)
			(xy 42.357451 -287.65121) (xy 42.381063 -287.697554) (xy 42.397134 -287.747022) (xy 42.40527 -287.798394)
			(xy 42.40527 -287.850406) (xy 42.397134 -287.901778) (xy 42.381063 -287.951246) (xy 42.357451 -287.99759)
			(xy 42.326882 -288.039671) (xy 42.290106 -288.076452) (xy 42.248029 -288.107027) (xy 42.201688 -288.130645)
			(xy 42.152223 -288.146723) (xy 42.100852 -288.154866) (xy 42.074846 -288.15538) (xy 41.124886 -288.15538)
			(xy 41.098881 -288.154833) (xy 41.047512 -288.146695) (xy 40.998048 -288.130621) (xy 40.951707 -288.107008)
			(xy 40.909631 -288.076436) (xy 40.872855 -288.039658) (xy 40.842285 -287.997581) (xy 40.818674 -287.951239)
			(xy 40.802602 -287.901775) (xy 40.794466 -287.850405) (xy 39.555496 -287.850405) (xy 39.555496 -287.850412)
			(xy 39.547357 -287.901796) (xy 39.53128 -287.951275) (xy 39.50766 -287.997628) (xy 39.477079 -288.039716)
			(xy 39.44029 -288.076501) (xy 39.398199 -288.107078) (xy 39.351843 -288.130693) (xy 39.302363 -288.146765)
			(xy 39.250978 -288.154899) (xy 39.224966 -288.15538) (xy 38.275006 -288.15538) (xy 38.248998 -288.154861)
			(xy 38.197622 -288.146725) (xy 38.148151 -288.130652) (xy 38.101804 -288.107037) (xy 38.059722 -288.076463)
			(xy 38.02294 -288.039683) (xy 37.992366 -287.997601) (xy 37.968751 -287.951254) (xy 37.952677 -287.901784)
			(xy 37.944539 -287.850408) (xy 0.508 -287.850408) (xy 0.508 -288.800413) (xy 36.0443 -288.800413)
			(xy 36.0443 -288.748387) (xy 36.052439 -288.697003) (xy 36.068516 -288.647524) (xy 36.092136 -288.60117)
			(xy 36.122718 -288.559082) (xy 36.159507 -288.522297) (xy 36.201598 -288.49172) (xy 36.247954 -288.468104)
			(xy 36.297434 -288.452031) (xy 36.348819 -288.443897) (xy 36.374832 -288.443416) (xy 37.324792 -288.443416)
			(xy 37.3508 -288.443943) (xy 37.402175 -288.452079) (xy 37.451646 -288.468151) (xy 37.497993 -288.491765)
			(xy 37.540075 -288.522339) (xy 37.576856 -288.559119) (xy 37.60743 -288.601201) (xy 37.631045 -288.647547)
			(xy 37.647119 -288.697017) (xy 37.655257 -288.748392) (xy 37.655257 -288.800408) (xy 37.655257 -288.800411)
			(xy 42.694299 -288.800411) (xy 42.694299 -288.748389) (xy 42.702438 -288.697007) (xy 42.718514 -288.64753)
			(xy 42.742132 -288.601178) (xy 42.77271 -288.559091) (xy 42.809496 -288.522306) (xy 42.851583 -288.491729)
			(xy 42.897936 -288.468111) (xy 42.947413 -288.452036) (xy 42.998795 -288.443899) (xy 43.024806 -288.443416)
			(xy 43.974766 -288.443416) (xy 44.000775 -288.443941) (xy 44.052154 -288.452074) (xy 44.101628 -288.468144)
			(xy 44.147978 -288.491757) (xy 44.190064 -288.52233) (xy 44.226848 -288.55911) (xy 44.257426 -288.601193)
			(xy 44.281043 -288.647541) (xy 44.297119 -288.697013) (xy 44.305257 -288.748391) (xy 44.305257 -288.800409)
			(xy 44.297119 -288.851787) (xy 44.281043 -288.901259) (xy 44.257426 -288.947607) (xy 44.226848 -288.98969)
			(xy 44.190064 -289.02647) (xy 44.147978 -289.057043) (xy 44.101628 -289.080656) (xy 44.052154 -289.096726)
			(xy 44.000775 -289.104859) (xy 43.974766 -289.10534) (xy 43.024806 -289.10534) (xy 42.998795 -289.104901)
			(xy 42.947413 -289.096764) (xy 42.897936 -289.080689) (xy 42.851583 -289.057071) (xy 42.809496 -289.026494)
			(xy 42.77271 -288.989709) (xy 42.742132 -288.947622) (xy 42.718514 -288.90127) (xy 42.702438 -288.851793)
			(xy 42.694299 -288.800411) (xy 37.655257 -288.800411) (xy 37.647119 -288.851783) (xy 37.631045 -288.901253)
			(xy 37.60743 -288.947599) (xy 37.576856 -288.989681) (xy 37.540075 -289.026461) (xy 37.497993 -289.057035)
			(xy 37.451646 -289.080649) (xy 37.402175 -289.096721) (xy 37.3508 -289.104857) (xy 37.324792 -289.10534)
			(xy 36.374832 -289.10534) (xy 36.348819 -289.104903) (xy 36.297434 -289.096769) (xy 36.247954 -289.080696)
			(xy 36.201598 -289.05708) (xy 36.159507 -289.026503) (xy 36.122718 -288.989718) (xy 36.092136 -288.94763)
			(xy 36.068516 -288.901276) (xy 36.052439 -288.851797) (xy 36.0443 -288.800413) (xy 0.508 -288.800413)
			(xy 0.508 -297.350788) (xy 36.044382 -297.350788) (xy 36.044382 -297.298812) (xy 36.052512 -297.247477)
			(xy 36.068572 -297.198045) (xy 36.092168 -297.151734) (xy 36.122717 -297.109685) (xy 36.159468 -297.072931)
			(xy 36.201516 -297.042379) (xy 36.247825 -297.018781) (xy 36.297255 -297.002717) (xy 36.34859 -296.994583)
			(xy 36.374578 -296.994072) (xy 37.324538 -296.994072) (xy 37.350522 -296.994624) (xy 37.401848 -297.002759)
			(xy 37.451271 -297.018822) (xy 37.497572 -297.042419) (xy 37.539613 -297.072968) (xy 37.576357 -297.109716)
			(xy 37.606901 -297.15176) (xy 37.630492 -297.198064) (xy 37.64655 -297.247489) (xy 37.654679 -297.298816)
			(xy 37.654679 -297.350784) (xy 37.654678 -297.350788) (xy 152.144482 -297.350788) (xy 152.144482 -297.298812)
			(xy 152.152612 -297.247477) (xy 152.168672 -297.198046) (xy 152.192268 -297.151735) (xy 152.222816 -297.109685)
			(xy 152.259567 -297.072932) (xy 152.301615 -297.04238) (xy 152.347923 -297.018782) (xy 152.397354 -297.002717)
			(xy 152.448688 -296.994583) (xy 152.474676 -296.994072) (xy 153.424636 -296.994072) (xy 153.45062 -296.994624)
			(xy 153.501947 -297.002759) (xy 153.55137 -297.018822) (xy 153.597671 -297.042418) (xy 153.639712 -297.072967)
			(xy 153.676457 -297.109715) (xy 153.707001 -297.151759) (xy 153.730592 -297.198064) (xy 153.74665 -297.247488)
			(xy 153.754779 -297.298816) (xy 153.754779 -297.350784) (xy 153.754778 -297.350792) (xy 268.244255 -297.350792)
			(xy 268.244255 -297.298808) (xy 268.252388 -297.247465) (xy 268.268452 -297.198025) (xy 268.292053 -297.151708)
			(xy 268.322609 -297.109653) (xy 268.359368 -297.072896) (xy 268.401425 -297.042342) (xy 268.447744 -297.018744)
			(xy 268.497184 -297.002683) (xy 268.548528 -296.994554) (xy 268.57452 -296.994072) (xy 269.52448 -296.994072)
			(xy 269.550469 -296.994594) (xy 269.601807 -297.002722) (xy 269.651241 -297.018781) (xy 269.697554 -297.042377)
			(xy 269.739606 -297.072927) (xy 269.77636 -297.109679) (xy 269.806913 -297.151729) (xy 269.830511 -297.198041)
			(xy 269.846573 -297.247474) (xy 269.854705 -297.298811) (xy 269.854705 -297.350789) (xy 269.854705 -297.350792)
			(xy 384.344355 -297.350792) (xy 384.344355 -297.298808) (xy 384.352488 -297.247465) (xy 384.368552 -297.198026)
			(xy 384.392153 -297.151709) (xy 384.422709 -297.109654) (xy 384.459467 -297.072897) (xy 384.501524 -297.042343)
			(xy 384.547842 -297.018745) (xy 384.597282 -297.002683) (xy 384.648626 -296.994554) (xy 384.674618 -296.994072)
			(xy 385.624578 -296.994072) (xy 385.650567 -296.994593) (xy 385.701905 -297.002721) (xy 385.751339 -297.018781)
			(xy 385.797653 -297.042376) (xy 385.839705 -297.072926) (xy 385.87646 -297.109678) (xy 385.907013 -297.151728)
			(xy 385.930611 -297.19804) (xy 385.946673 -297.247474) (xy 385.954805 -297.298811) (xy 385.954805 -297.350789)
			(xy 385.946673 -297.402126) (xy 385.930611 -297.45156) (xy 385.907013 -297.497872) (xy 385.87646 -297.539922)
			(xy 385.839705 -297.576674) (xy 385.797653 -297.607224) (xy 385.751339 -297.630819) (xy 385.701905 -297.646879)
			(xy 385.650567 -297.655007) (xy 385.624578 -297.655488) (xy 384.674618 -297.655488) (xy 384.648626 -297.655046)
			(xy 384.597282 -297.646917) (xy 384.547842 -297.630855) (xy 384.501524 -297.607257) (xy 384.459467 -297.576703)
			(xy 384.422709 -297.539946) (xy 384.392153 -297.497891) (xy 384.368552 -297.451574) (xy 384.352488 -297.402135)
			(xy 384.344355 -297.350792) (xy 269.854705 -297.350792) (xy 269.846573 -297.402126) (xy 269.830511 -297.451559)
			(xy 269.806913 -297.497871) (xy 269.77636 -297.539921) (xy 269.739606 -297.576673) (xy 269.697554 -297.607223)
			(xy 269.651241 -297.630819) (xy 269.601807 -297.646878) (xy 269.550469 -297.655006) (xy 269.52448 -297.655488)
			(xy 268.57452 -297.655488) (xy 268.548528 -297.655046) (xy 268.497184 -297.646917) (xy 268.447744 -297.630856)
			(xy 268.401425 -297.607258) (xy 268.359368 -297.576704) (xy 268.322609 -297.539947) (xy 268.292053 -297.497892)
			(xy 268.268452 -297.451575) (xy 268.252388 -297.402135) (xy 268.244255 -297.350792) (xy 153.754778 -297.350792)
			(xy 153.74665 -297.402112) (xy 153.730592 -297.451536) (xy 153.707001 -297.497841) (xy 153.676457 -297.539885)
			(xy 153.639712 -297.576633) (xy 153.597671 -297.607182) (xy 153.55137 -297.630778) (xy 153.501947 -297.646841)
			(xy 153.45062 -297.654976) (xy 153.424636 -297.655488) (xy 152.474676 -297.655488) (xy 152.448688 -297.655017)
			(xy 152.397354 -297.646883) (xy 152.347923 -297.630818) (xy 152.301615 -297.60722) (xy 152.259567 -297.576668)
			(xy 152.222816 -297.539915) (xy 152.192268 -297.497865) (xy 152.168672 -297.451554) (xy 152.152612 -297.402123)
			(xy 152.144482 -297.350788) (xy 37.654678 -297.350788) (xy 37.64655 -297.402111) (xy 37.630492 -297.451536)
			(xy 37.606901 -297.49784) (xy 37.576357 -297.539884) (xy 37.539613 -297.576632) (xy 37.497572 -297.607181)
			(xy 37.451271 -297.630778) (xy 37.401848 -297.646841) (xy 37.350522 -297.654976) (xy 37.324538 -297.655488)
			(xy 36.374578 -297.655488) (xy 36.34859 -297.655017) (xy 36.297255 -297.646883) (xy 36.247825 -297.630819)
			(xy 36.201516 -297.607221) (xy 36.159468 -297.576669) (xy 36.122717 -297.539915) (xy 36.092168 -297.497866)
			(xy 36.068572 -297.451555) (xy 36.052512 -297.402123) (xy 36.044382 -297.350788) (xy 0.508 -297.350788)
			(xy 0.508 -298.77569) (xy 39.369695 -298.77569) (xy 39.369695 -298.72371) (xy 39.377827 -298.67237)
			(xy 39.393891 -298.622935) (xy 39.417492 -298.576621) (xy 39.448047 -298.53457) (xy 39.484805 -298.497817)
			(xy 39.52686 -298.467268) (xy 39.573177 -298.443674) (xy 39.622615 -298.427617) (xy 39.673956 -298.419492)
			(xy 39.699946 -298.419012) (xy 40.649906 -298.419012) (xy 40.675894 -298.419482) (xy 40.727231 -298.427614)
			(xy 40.776664 -298.443676) (xy 40.822975 -298.467274) (xy 40.865025 -298.497826) (xy 40.901778 -298.534579)
			(xy 40.932329 -298.57663) (xy 40.955926 -298.622942) (xy 40.971988 -298.672375) (xy 40.980118 -298.723712)
			(xy 40.980118 -298.775685) (xy 387.669821 -298.775685) (xy 387.669821 -298.723715) (xy 387.677951 -298.672385)
			(xy 387.69401 -298.622959) (xy 387.717603 -298.576653) (xy 387.74815 -298.534608) (xy 387.784897 -298.497859)
			(xy 387.826941 -298.467311) (xy 387.873246 -298.443716) (xy 387.922671 -298.427654) (xy 387.974001 -298.419523)
			(xy 387.999986 -298.419012) (xy 388.949946 -298.419012) (xy 388.975932 -298.419485) (xy 389.027264 -298.427622)
			(xy 389.076692 -298.443688) (xy 389.122998 -298.467288) (xy 389.165042 -298.49784) (xy 389.20179 -298.534593)
			(xy 389.232337 -298.576642) (xy 389.25593 -298.622951) (xy 389.271989 -298.67238) (xy 389.280119 -298.723714)
			(xy 389.280119 -298.775686) (xy 389.271989 -298.82702) (xy 389.25593 -298.876449) (xy 389.232337 -298.922758)
			(xy 389.20179 -298.964807) (xy 389.165042 -299.00156) (xy 389.122998 -299.032112) (xy 389.076692 -299.055712)
			(xy 389.027264 -299.071778) (xy 388.975932 -299.079915) (xy 388.949946 -299.080428) (xy 387.999986 -299.080428)
			(xy 387.974001 -299.079877) (xy 387.922671 -299.071746) (xy 387.873246 -299.055684) (xy 387.826941 -299.032089)
			(xy 387.784897 -299.001541) (xy 387.74815 -298.964792) (xy 387.717603 -298.922747) (xy 387.69401 -298.876441)
			(xy 387.677951 -298.827015) (xy 387.669821 -298.775685) (xy 40.980118 -298.775685) (xy 40.980118 -298.775688)
			(xy 40.971988 -298.827025) (xy 40.955926 -298.876458) (xy 40.932329 -298.92277) (xy 40.901778 -298.964821)
			(xy 40.865025 -299.001574) (xy 40.822975 -299.032126) (xy 40.776664 -299.055724) (xy 40.727231 -299.071786)
			(xy 40.675894 -299.079918) (xy 40.649906 -299.080428) (xy 39.699946 -299.080428) (xy 39.673956 -299.079908)
			(xy 39.622615 -299.071783) (xy 39.573177 -299.055726) (xy 39.52686 -299.032132) (xy 39.484805 -299.001583)
			(xy 39.448047 -298.96483) (xy 39.417492 -298.922779) (xy 39.393891 -298.876465) (xy 39.377827 -298.82703)
			(xy 39.369695 -298.77569) (xy 0.508 -298.77569) (xy 0.508 -299.25101) (xy 36.044102 -299.25101) (xy 36.044102 -299.19899)
			(xy 36.052239 -299.147611) (xy 36.068313 -299.098138) (xy 36.091929 -299.051788) (xy 36.122504 -299.009703)
			(xy 36.159286 -298.972918) (xy 36.201369 -298.94234) (xy 36.247718 -298.918722) (xy 36.29719 -298.902644)
			(xy 36.348568 -298.894504) (xy 36.374578 -298.893992) (xy 37.324538 -298.893992) (xy 37.35054 -298.894597)
			(xy 37.401902 -298.902737) (xy 37.451358 -298.918812) (xy 37.497691 -298.942425) (xy 37.539761 -298.972994)
			(xy 37.576531 -299.009768) (xy 37.607095 -299.051841) (xy 37.630703 -299.098177) (xy 37.646771 -299.147635)
			(xy 37.654906 -299.198998) (xy 37.654906 -299.251002) (xy 37.654905 -299.25101) (xy 152.144202 -299.25101)
			(xy 152.144202 -299.19899) (xy 152.152339 -299.147612) (xy 152.168413 -299.098138) (xy 152.192028 -299.051788)
			(xy 152.222603 -299.009703) (xy 152.259385 -298.972919) (xy 152.301468 -298.942341) (xy 152.347816 -298.918722)
			(xy 152.397288 -298.902645) (xy 152.448666 -298.894504) (xy 152.474676 -298.893992) (xy 153.424636 -298.893992)
			(xy 153.450638 -298.894597) (xy 153.502 -298.902737) (xy 153.551457 -298.918811) (xy 153.59779 -298.942424)
			(xy 153.63986 -298.972993) (xy 153.67663 -299.009767) (xy 153.707195 -299.05184) (xy 153.730803 -299.098177)
			(xy 153.746871 -299.147635) (xy 153.755006 -299.198998) (xy 153.755006 -299.251002) (xy 153.755005 -299.251009)
			(xy 154.994602 -299.251009) (xy 154.994602 -299.198991) (xy 155.002739 -299.147613) (xy 155.018812 -299.098141)
			(xy 155.042426 -299.051792) (xy 155.073 -299.009707) (xy 155.10978 -298.972923) (xy 155.151861 -298.942345)
			(xy 155.198208 -298.918726) (xy 155.247678 -298.902647) (xy 155.299055 -298.894505) (xy 155.325064 -298.893992)
			(xy 156.275024 -298.893992) (xy 156.301026 -298.894596) (xy 156.35239 -298.902735) (xy 156.401848 -298.918808)
			(xy 156.448184 -298.94242) (xy 156.490255 -298.972989) (xy 156.527026 -299.009763) (xy 156.557593 -299.051837)
			(xy 156.581201 -299.098174) (xy 156.597271 -299.147633) (xy 156.605406 -299.198998) (xy 156.605406 -299.251002)
			(xy 156.605404 -299.251014) (xy 268.243976 -299.251014) (xy 268.243976 -299.198986) (xy 268.252115 -299.147599)
			(xy 268.268193 -299.098118) (xy 268.291814 -299.051761) (xy 268.322396 -299.009671) (xy 268.359186 -298.972883)
			(xy 268.401279 -298.942303) (xy 268.447637 -298.918685) (xy 268.497119 -298.90261) (xy 268.548506 -298.894474)
			(xy 268.57452 -298.893992) (xy 269.52448 -298.893992) (xy 269.550487 -298.894566) (xy 269.60186 -298.9027)
			(xy 269.651328 -298.91877) (xy 269.697673 -298.942382) (xy 269.739754 -298.972953) (xy 269.776534 -299.009731)
			(xy 269.807108 -299.05181) (xy 269.830722 -299.098153) (xy 269.846796 -299.147621) (xy 269.854933 -299.198993)
			(xy 269.854933 -299.251007) (xy 269.854932 -299.251013) (xy 271.094376 -299.251013) (xy 271.094376 -299.198987)
			(xy 271.102514 -299.147601) (xy 271.118592 -299.098121) (xy 271.142212 -299.051765) (xy 271.172792 -299.009675)
			(xy 271.209581 -298.972887) (xy 271.251672 -298.942307) (xy 271.298028 -298.918689) (xy 271.347509 -298.902613)
			(xy 271.398895 -298.894475) (xy 271.424908 -298.893992) (xy 272.374868 -298.893992) (xy 272.400875 -298.894565)
			(xy 272.45225 -298.902697) (xy 272.50172 -298.918767) (xy 272.548067 -298.942378) (xy 272.590149 -298.972949)
			(xy 272.626931 -299.009727) (xy 272.657506 -299.051806) (xy 272.681121 -299.09815) (xy 272.697195 -299.147619)
			(xy 272.705333 -299.198993) (xy 272.705333 -299.251007) (xy 272.705332 -299.251014) (xy 384.344076 -299.251014)
			(xy 384.344076 -299.198986) (xy 384.352215 -299.147599) (xy 384.368293 -299.098118) (xy 384.391913 -299.051762)
			(xy 384.422495 -299.009672) (xy 384.459285 -298.972884) (xy 384.501377 -298.942304) (xy 384.547735 -298.918686)
			(xy 384.597217 -298.902611) (xy 384.648604 -298.894474) (xy 384.674618 -298.893992) (xy 385.624578 -298.893992)
			(xy 385.650585 -298.894566) (xy 385.701958 -298.902699) (xy 385.751427 -298.91877) (xy 385.797772 -298.942381)
			(xy 385.839853 -298.972952) (xy 385.876634 -299.00973) (xy 385.907207 -299.051809) (xy 385.930822 -299.098153)
			(xy 385.946896 -299.14762) (xy 385.955033 -299.198993) (xy 385.955033 -299.251007) (xy 385.946896 -299.30238)
			(xy 385.930822 -299.351847) (xy 385.907207 -299.398191) (xy 385.876634 -299.44027) (xy 385.839853 -299.477048)
			(xy 385.797772 -299.507619) (xy 385.751427 -299.53123) (xy 385.701958 -299.547301) (xy 385.650585 -299.555434)
			(xy 385.624578 -299.555916) (xy 384.674618 -299.555916) (xy 384.648604 -299.555526) (xy 384.597217 -299.547389)
			(xy 384.547735 -299.531314) (xy 384.501377 -299.507696) (xy 384.459285 -299.477116) (xy 384.422495 -299.440328)
			(xy 384.391913 -299.398238) (xy 384.368293 -299.351882) (xy 384.352215 -299.302401) (xy 384.344076 -299.251014)
			(xy 272.705332 -299.251014) (xy 272.697195 -299.302381) (xy 272.681121 -299.35185) (xy 272.657506 -299.398194)
			(xy 272.626931 -299.440273) (xy 272.590149 -299.477051) (xy 272.548067 -299.507622) (xy 272.50172 -299.531233)
			(xy 272.45225 -299.547303) (xy 272.400875 -299.555435) (xy 272.374868 -299.555916) (xy 271.424908 -299.555916)
			(xy 271.398895 -299.555525) (xy 271.347509 -299.547387) (xy 271.298028 -299.531311) (xy 271.251672 -299.507693)
			(xy 271.209581 -299.477113) (xy 271.172792 -299.440325) (xy 271.142212 -299.398235) (xy 271.118592 -299.351879)
			(xy 271.102514 -299.302399) (xy 271.094376 -299.251013) (xy 269.854932 -299.251013) (xy 269.846796 -299.302379)
			(xy 269.830722 -299.351847) (xy 269.807108 -299.39819) (xy 269.776534 -299.440269) (xy 269.739754 -299.477047)
			(xy 269.697673 -299.507618) (xy 269.651328 -299.53123) (xy 269.60186 -299.5473) (xy 269.550487 -299.555434)
			(xy 269.52448 -299.555916) (xy 268.57452 -299.555916) (xy 268.548506 -299.555526) (xy 268.497119 -299.54739)
			(xy 268.447637 -299.531315) (xy 268.401279 -299.507697) (xy 268.359186 -299.477117) (xy 268.322396 -299.440329)
			(xy 268.291814 -299.398239) (xy 268.268193 -299.351882) (xy 268.252115 -299.302401) (xy 268.243976 -299.251014)
			(xy 156.605404 -299.251014) (xy 156.597271 -299.302367) (xy 156.581201 -299.351826) (xy 156.557593 -299.398163)
			(xy 156.527026 -299.440237) (xy 156.490255 -299.477011) (xy 156.448184 -299.50758) (xy 156.401848 -299.531192)
			(xy 156.35239 -299.547265) (xy 156.301026 -299.555404) (xy 156.275024 -299.555916) (xy 155.325064 -299.555916)
			(xy 155.299055 -299.555495) (xy 155.247678 -299.547353) (xy 155.198208 -299.531274) (xy 155.151861 -299.507655)
			(xy 155.10978 -299.477077) (xy 155.073 -299.440293) (xy 155.042426 -299.398208) (xy 155.018812 -299.351859)
			(xy 155.002739 -299.302387) (xy 154.994602 -299.251009) (xy 153.755005 -299.251009) (xy 153.746871 -299.302365)
			(xy 153.730803 -299.351823) (xy 153.707195 -299.39816) (xy 153.67663 -299.440233) (xy 153.63986 -299.477007)
			(xy 153.59779 -299.507576) (xy 153.551457 -299.531189) (xy 153.502 -299.547263) (xy 153.450638 -299.555403)
			(xy 153.424636 -299.555916) (xy 152.474676 -299.555916) (xy 152.448666 -299.555496) (xy 152.397288 -299.547355)
			(xy 152.347816 -299.531278) (xy 152.301468 -299.507659) (xy 152.259385 -299.477081) (xy 152.222603 -299.440297)
			(xy 152.192028 -299.398212) (xy 152.168413 -299.351862) (xy 152.152339 -299.302388) (xy 152.144202 -299.25101)
			(xy 37.654905 -299.25101) (xy 37.646771 -299.302365) (xy 37.630703 -299.351823) (xy 37.607095 -299.398159)
			(xy 37.576531 -299.440232) (xy 37.539761 -299.477006) (xy 37.497691 -299.507575) (xy 37.451358 -299.531188)
			(xy 37.401902 -299.547263) (xy 37.35054 -299.555403) (xy 37.324538 -299.555916) (xy 36.374578 -299.555916)
			(xy 36.348568 -299.555496) (xy 36.29719 -299.547356) (xy 36.247718 -299.531278) (xy 36.201369 -299.50766)
			(xy 36.159286 -299.477082) (xy 36.122504 -299.440297) (xy 36.091929 -299.398212) (xy 36.068313 -299.351862)
			(xy 36.052239 -299.302389) (xy 36.044102 -299.25101) (xy 0.508 -299.25101) (xy 0.508 -301.599854)
			(xy 157.39416 -301.599854) (xy 157.39812 -301.5508) (xy 157.409897 -301.503016) (xy 157.429188 -301.45774)
			(xy 157.455491 -301.416144) (xy 157.488126 -301.379307) (xy 157.526247 -301.348182) (xy 157.568868 -301.323575)
			(xy 157.614884 -301.306123) (xy 157.663103 -301.296279) (xy 157.712278 -301.294298) (xy 157.761133 -301.30023)
			(xy 157.808404 -301.313922) (xy 157.852866 -301.33502) (xy 157.893369 -301.362976) (xy 157.928862 -301.397068)
			(xy 157.958427 -301.436412) (xy 157.981298 -301.479989) (xy 157.996882 -301.52667) (xy 158.004777 -301.575247)
			(xy 158.005272 -301.599854) (xy 158.34412 -301.599854) (xy 158.34808 -301.5508) (xy 158.359857 -301.503016)
			(xy 158.379148 -301.45774) (xy 158.405451 -301.416144) (xy 158.438086 -301.379307) (xy 158.476207 -301.348182)
			(xy 158.518828 -301.323575) (xy 158.564844 -301.306123) (xy 158.613063 -301.296279) (xy 158.662238 -301.294298)
			(xy 158.711093 -301.30023) (xy 158.758364 -301.313922) (xy 158.802826 -301.33502) (xy 158.843329 -301.362976)
			(xy 158.878822 -301.397068) (xy 158.908387 -301.436412) (xy 158.931258 -301.479989) (xy 158.946842 -301.52667)
			(xy 158.954737 -301.575247) (xy 158.955232 -301.599854) (xy 389.594102 -301.599854) (xy 389.598062 -301.5508)
			(xy 389.609839 -301.503016) (xy 389.62913 -301.45774) (xy 389.655433 -301.416144) (xy 389.688068 -301.379307)
			(xy 389.726189 -301.348182) (xy 389.76881 -301.323575) (xy 389.814826 -301.306123) (xy 389.863045 -301.296279)
			(xy 389.91222 -301.294298) (xy 389.961075 -301.30023) (xy 390.008346 -301.313922) (xy 390.052808 -301.33502)
			(xy 390.093311 -301.362976) (xy 390.128804 -301.397068) (xy 390.158369 -301.436412) (xy 390.18124 -301.479989)
			(xy 390.196824 -301.52667) (xy 390.204719 -301.575247) (xy 390.205214 -301.599854) (xy 390.544062 -301.599854)
			(xy 390.548022 -301.5508) (xy 390.559799 -301.503016) (xy 390.57909 -301.45774) (xy 390.605393 -301.416144)
			(xy 390.638028 -301.379307) (xy 390.676149 -301.348182) (xy 390.71877 -301.323575) (xy 390.764786 -301.306123)
			(xy 390.813005 -301.296279) (xy 390.86218 -301.294298) (xy 390.911035 -301.30023) (xy 390.958306 -301.313922)
			(xy 391.002768 -301.33502) (xy 391.043271 -301.362976) (xy 391.078764 -301.397068) (xy 391.108329 -301.436412)
			(xy 391.1312 -301.479989) (xy 391.146784 -301.52667) (xy 391.154679 -301.575247) (xy 391.155174 -301.599854)
			(xy 391.154679 -301.624461) (xy 391.146784 -301.673038) (xy 391.1312 -301.719719) (xy 391.108329 -301.763296)
			(xy 391.078764 -301.80264) (xy 391.043271 -301.836732) (xy 391.002768 -301.864688) (xy 390.958306 -301.885786)
			(xy 390.911035 -301.899478) (xy 390.86218 -301.90541) (xy 390.813005 -301.903429) (xy 390.764786 -301.893585)
			(xy 390.71877 -301.876133) (xy 390.676149 -301.851526) (xy 390.638028 -301.820401) (xy 390.605393 -301.783564)
			(xy 390.57909 -301.741968) (xy 390.559799 -301.696692) (xy 390.548022 -301.648908) (xy 390.544062 -301.599854)
			(xy 390.205214 -301.599854) (xy 390.204719 -301.624461) (xy 390.196824 -301.673038) (xy 390.18124 -301.719719)
			(xy 390.158369 -301.763296) (xy 390.128804 -301.80264) (xy 390.093311 -301.836732) (xy 390.052808 -301.864688)
			(xy 390.008346 -301.885786) (xy 389.961075 -301.899478) (xy 389.91222 -301.90541) (xy 389.863045 -301.903429)
			(xy 389.814826 -301.893585) (xy 389.76881 -301.876133) (xy 389.726189 -301.851526) (xy 389.688068 -301.820401)
			(xy 389.655433 -301.783564) (xy 389.62913 -301.741968) (xy 389.609839 -301.696692) (xy 389.598062 -301.648908)
			(xy 389.594102 -301.599854) (xy 158.955232 -301.599854) (xy 158.954737 -301.624461) (xy 158.946842 -301.673038)
			(xy 158.931258 -301.719719) (xy 158.908387 -301.763296) (xy 158.878822 -301.80264) (xy 158.843329 -301.836732)
			(xy 158.802826 -301.864688) (xy 158.758364 -301.885786) (xy 158.711093 -301.899478) (xy 158.662238 -301.90541)
			(xy 158.613063 -301.903429) (xy 158.564844 -301.893585) (xy 158.518828 -301.876133) (xy 158.476207 -301.851526)
			(xy 158.438086 -301.820401) (xy 158.405451 -301.783564) (xy 158.379148 -301.741968) (xy 158.359857 -301.696692)
			(xy 158.34808 -301.648908) (xy 158.34412 -301.599854) (xy 158.005272 -301.599854) (xy 158.004777 -301.624461)
			(xy 157.996882 -301.673038) (xy 157.981298 -301.719719) (xy 157.958427 -301.763296) (xy 157.928862 -301.80264)
			(xy 157.893369 -301.836732) (xy 157.852866 -301.864688) (xy 157.808404 -301.885786) (xy 157.761133 -301.899478)
			(xy 157.712278 -301.90541) (xy 157.663103 -301.903429) (xy 157.614884 -301.893585) (xy 157.568868 -301.876133)
			(xy 157.526247 -301.851526) (xy 157.488126 -301.820401) (xy 157.455491 -301.783564) (xy 157.429188 -301.741968)
			(xy 157.409897 -301.696692) (xy 157.39812 -301.648908) (xy 157.39416 -301.599854) (xy 0.508 -301.599854)
			(xy 0.508 -302.549814) (xy 159.29408 -302.549814) (xy 159.29804 -302.50076) (xy 159.309817 -302.452976)
			(xy 159.329108 -302.4077) (xy 159.355411 -302.366104) (xy 159.388046 -302.329267) (xy 159.426167 -302.298142)
			(xy 159.468788 -302.273535) (xy 159.514804 -302.256083) (xy 159.563023 -302.246239) (xy 159.612198 -302.244258)
			(xy 159.661053 -302.25019) (xy 159.708324 -302.263882) (xy 159.752786 -302.28498) (xy 159.793289 -302.312936)
			(xy 159.828782 -302.347028) (xy 159.858347 -302.386372) (xy 159.881218 -302.429949) (xy 159.896802 -302.47663)
			(xy 159.904697 -302.525207) (xy 159.905192 -302.549814) (xy 160.24404 -302.549814) (xy 160.248 -302.50076)
			(xy 160.259777 -302.452976) (xy 160.279068 -302.4077) (xy 160.305371 -302.366104) (xy 160.338006 -302.329267)
			(xy 160.376127 -302.298142) (xy 160.418748 -302.273535) (xy 160.464764 -302.256083) (xy 160.512983 -302.246239)
			(xy 160.562158 -302.244258) (xy 160.611013 -302.25019) (xy 160.658284 -302.263882) (xy 160.702746 -302.28498)
			(xy 160.743249 -302.312936) (xy 160.778742 -302.347028) (xy 160.808307 -302.386372) (xy 160.831178 -302.429949)
			(xy 160.846762 -302.47663) (xy 160.854657 -302.525207) (xy 160.855152 -302.549814) (xy 391.494022 -302.549814)
			(xy 391.497982 -302.50076) (xy 391.509759 -302.452976) (xy 391.52905 -302.4077) (xy 391.555353 -302.366104)
			(xy 391.587988 -302.329267) (xy 391.626109 -302.298142) (xy 391.66873 -302.273535) (xy 391.714746 -302.256083)
			(xy 391.762965 -302.246239) (xy 391.81214 -302.244258) (xy 391.860995 -302.25019) (xy 391.908266 -302.263882)
			(xy 391.952728 -302.28498) (xy 391.993231 -302.312936) (xy 392.028724 -302.347028) (xy 392.058289 -302.386372)
			(xy 392.08116 -302.429949) (xy 392.096744 -302.47663) (xy 392.104639 -302.525207) (xy 392.105134 -302.549814)
			(xy 392.443982 -302.549814) (xy 392.447942 -302.50076) (xy 392.459719 -302.452976) (xy 392.47901 -302.4077)
			(xy 392.505313 -302.366104) (xy 392.537948 -302.329267) (xy 392.576069 -302.298142) (xy 392.61869 -302.273535)
			(xy 392.664706 -302.256083) (xy 392.712925 -302.246239) (xy 392.7621 -302.244258) (xy 392.810955 -302.25019)
			(xy 392.858226 -302.263882) (xy 392.902688 -302.28498) (xy 392.943191 -302.312936) (xy 392.978684 -302.347028)
			(xy 393.008249 -302.386372) (xy 393.03112 -302.429949) (xy 393.046704 -302.47663) (xy 393.054599 -302.525207)
			(xy 393.055094 -302.549814) (xy 393.054599 -302.574421) (xy 393.046704 -302.622998) (xy 393.03112 -302.669679)
			(xy 393.008249 -302.713256) (xy 392.978684 -302.7526) (xy 392.943191 -302.786692) (xy 392.902688 -302.814648)
			(xy 392.858226 -302.835746) (xy 392.810955 -302.849438) (xy 392.7621 -302.85537) (xy 392.712925 -302.853389)
			(xy 392.664706 -302.843545) (xy 392.61869 -302.826093) (xy 392.576069 -302.801486) (xy 392.537948 -302.770361)
			(xy 392.505313 -302.733524) (xy 392.47901 -302.691928) (xy 392.459719 -302.646652) (xy 392.447942 -302.598868)
			(xy 392.443982 -302.549814) (xy 392.105134 -302.549814) (xy 392.104639 -302.574421) (xy 392.096744 -302.622998)
			(xy 392.08116 -302.669679) (xy 392.058289 -302.713256) (xy 392.028724 -302.7526) (xy 391.993231 -302.786692)
			(xy 391.952728 -302.814648) (xy 391.908266 -302.835746) (xy 391.860995 -302.849438) (xy 391.81214 -302.85537)
			(xy 391.762965 -302.853389) (xy 391.714746 -302.843545) (xy 391.66873 -302.826093) (xy 391.626109 -302.801486)
			(xy 391.587988 -302.770361) (xy 391.555353 -302.733524) (xy 391.52905 -302.691928) (xy 391.509759 -302.646652)
			(xy 391.497982 -302.598868) (xy 391.494022 -302.549814) (xy 160.855152 -302.549814) (xy 160.854657 -302.574421)
			(xy 160.846762 -302.622998) (xy 160.831178 -302.669679) (xy 160.808307 -302.713256) (xy 160.778742 -302.7526)
			(xy 160.743249 -302.786692) (xy 160.702746 -302.814648) (xy 160.658284 -302.835746) (xy 160.611013 -302.849438)
			(xy 160.562158 -302.85537) (xy 160.512983 -302.853389) (xy 160.464764 -302.843545) (xy 160.418748 -302.826093)
			(xy 160.376127 -302.801486) (xy 160.338006 -302.770361) (xy 160.305371 -302.733524) (xy 160.279068 -302.691928)
			(xy 160.259777 -302.646652) (xy 160.248 -302.598868) (xy 160.24404 -302.549814) (xy 159.905192 -302.549814)
			(xy 159.904697 -302.574421) (xy 159.896802 -302.622998) (xy 159.881218 -302.669679) (xy 159.858347 -302.713256)
			(xy 159.828782 -302.7526) (xy 159.793289 -302.786692) (xy 159.752786 -302.814648) (xy 159.708324 -302.835746)
			(xy 159.661053 -302.849438) (xy 159.612198 -302.85537) (xy 159.563023 -302.853389) (xy 159.514804 -302.843545)
			(xy 159.468788 -302.826093) (xy 159.426167 -302.801486) (xy 159.388046 -302.770361) (xy 159.355411 -302.733524)
			(xy 159.329108 -302.691928) (xy 159.309817 -302.646652) (xy 159.29804 -302.598868) (xy 159.29408 -302.549814)
			(xy 0.508 -302.549814) (xy 0.508 -303.499774) (xy 157.39416 -303.499774) (xy 157.39812 -303.45072)
			(xy 157.409897 -303.402936) (xy 157.429188 -303.35766) (xy 157.455491 -303.316064) (xy 157.488126 -303.279227)
			(xy 157.526247 -303.248102) (xy 157.568868 -303.223495) (xy 157.614884 -303.206043) (xy 157.663103 -303.196199)
			(xy 157.712278 -303.194218) (xy 157.761133 -303.20015) (xy 157.808404 -303.213842) (xy 157.852866 -303.23494)
			(xy 157.893369 -303.262896) (xy 157.928862 -303.296988) (xy 157.958427 -303.336332) (xy 157.981298 -303.379909)
			(xy 157.996882 -303.42659) (xy 158.004777 -303.475167) (xy 158.005272 -303.499774) (xy 158.34412 -303.499774)
			(xy 158.34808 -303.45072) (xy 158.359857 -303.402936) (xy 158.379148 -303.35766) (xy 158.405451 -303.316064)
			(xy 158.438086 -303.279227) (xy 158.476207 -303.248102) (xy 158.518828 -303.223495) (xy 158.564844 -303.206043)
			(xy 158.613063 -303.196199) (xy 158.662238 -303.194218) (xy 158.711093 -303.20015) (xy 158.758364 -303.213842)
			(xy 158.802826 -303.23494) (xy 158.843329 -303.262896) (xy 158.878822 -303.296988) (xy 158.908387 -303.336332)
			(xy 158.931258 -303.379909) (xy 158.946842 -303.42659) (xy 158.954737 -303.475167) (xy 158.955232 -303.499774)
			(xy 389.594102 -303.499774) (xy 389.598062 -303.45072) (xy 389.609839 -303.402936) (xy 389.62913 -303.35766)
			(xy 389.655433 -303.316064) (xy 389.688068 -303.279227) (xy 389.726189 -303.248102) (xy 389.76881 -303.223495)
			(xy 389.814826 -303.206043) (xy 389.863045 -303.196199) (xy 389.91222 -303.194218) (xy 389.961075 -303.20015)
			(xy 390.008346 -303.213842) (xy 390.052808 -303.23494) (xy 390.093311 -303.262896) (xy 390.128804 -303.296988)
			(xy 390.158369 -303.336332) (xy 390.18124 -303.379909) (xy 390.196824 -303.42659) (xy 390.204719 -303.475167)
			(xy 390.205214 -303.499774) (xy 390.544062 -303.499774) (xy 390.548022 -303.45072) (xy 390.559799 -303.402936)
			(xy 390.57909 -303.35766) (xy 390.605393 -303.316064) (xy 390.638028 -303.279227) (xy 390.676149 -303.248102)
			(xy 390.71877 -303.223495) (xy 390.764786 -303.206043) (xy 390.813005 -303.196199) (xy 390.86218 -303.194218)
			(xy 390.911035 -303.20015) (xy 390.958306 -303.213842) (xy 391.002768 -303.23494) (xy 391.043271 -303.262896)
			(xy 391.078764 -303.296988) (xy 391.108329 -303.336332) (xy 391.1312 -303.379909) (xy 391.146784 -303.42659)
			(xy 391.154679 -303.475167) (xy 391.155174 -303.499774) (xy 391.154679 -303.524381) (xy 391.146784 -303.572958)
			(xy 391.1312 -303.619639) (xy 391.108329 -303.663216) (xy 391.078764 -303.70256) (xy 391.043271 -303.736652)
			(xy 391.002768 -303.764608) (xy 390.958306 -303.785706) (xy 390.911035 -303.799398) (xy 390.86218 -303.80533)
			(xy 390.813005 -303.803349) (xy 390.764786 -303.793505) (xy 390.71877 -303.776053) (xy 390.676149 -303.751446)
			(xy 390.638028 -303.720321) (xy 390.605393 -303.683484) (xy 390.57909 -303.641888) (xy 390.559799 -303.596612)
			(xy 390.548022 -303.548828) (xy 390.544062 -303.499774) (xy 390.205214 -303.499774) (xy 390.204719 -303.524381)
			(xy 390.196824 -303.572958) (xy 390.18124 -303.619639) (xy 390.158369 -303.663216) (xy 390.128804 -303.70256)
			(xy 390.093311 -303.736652) (xy 390.052808 -303.764608) (xy 390.008346 -303.785706) (xy 389.961075 -303.799398)
			(xy 389.91222 -303.80533) (xy 389.863045 -303.803349) (xy 389.814826 -303.793505) (xy 389.76881 -303.776053)
			(xy 389.726189 -303.751446) (xy 389.688068 -303.720321) (xy 389.655433 -303.683484) (xy 389.62913 -303.641888)
			(xy 389.609839 -303.596612) (xy 389.598062 -303.548828) (xy 389.594102 -303.499774) (xy 158.955232 -303.499774)
			(xy 158.954737 -303.524381) (xy 158.946842 -303.572958) (xy 158.931258 -303.619639) (xy 158.908387 -303.663216)
			(xy 158.878822 -303.70256) (xy 158.843329 -303.736652) (xy 158.802826 -303.764608) (xy 158.758364 -303.785706)
			(xy 158.711093 -303.799398) (xy 158.662238 -303.80533) (xy 158.613063 -303.803349) (xy 158.564844 -303.793505)
			(xy 158.518828 -303.776053) (xy 158.476207 -303.751446) (xy 158.438086 -303.720321) (xy 158.405451 -303.683484)
			(xy 158.379148 -303.641888) (xy 158.359857 -303.596612) (xy 158.34808 -303.548828) (xy 158.34412 -303.499774)
			(xy 158.005272 -303.499774) (xy 158.004777 -303.524381) (xy 157.996882 -303.572958) (xy 157.981298 -303.619639)
			(xy 157.958427 -303.663216) (xy 157.928862 -303.70256) (xy 157.893369 -303.736652) (xy 157.852866 -303.764608)
			(xy 157.808404 -303.785706) (xy 157.761133 -303.799398) (xy 157.712278 -303.80533) (xy 157.663103 -303.803349)
			(xy 157.614884 -303.793505) (xy 157.568868 -303.776053) (xy 157.526247 -303.751446) (xy 157.488126 -303.720321)
			(xy 157.455491 -303.683484) (xy 157.429188 -303.641888) (xy 157.409897 -303.596612) (xy 157.39812 -303.548828)
			(xy 157.39416 -303.499774) (xy 0.508 -303.499774) (xy 0.508 -304.449734) (xy 74.544186 -304.449734)
			(xy 74.548146 -304.40068) (xy 74.559923 -304.352896) (xy 74.579214 -304.30762) (xy 74.605517 -304.266024)
			(xy 74.638152 -304.229187) (xy 74.676273 -304.198062) (xy 74.718894 -304.173455) (xy 74.76491 -304.156003)
			(xy 74.813129 -304.146159) (xy 74.862304 -304.144178) (xy 74.911159 -304.15011) (xy 74.95843 -304.163802)
			(xy 75.002892 -304.1849) (xy 75.043395 -304.212856) (xy 75.078888 -304.246948) (xy 75.108453 -304.286292)
			(xy 75.131324 -304.329869) (xy 75.146908 -304.37655) (xy 75.154803 -304.425127) (xy 75.155298 -304.449734)
			(xy 75.494146 -304.449734) (xy 75.498106 -304.40068) (xy 75.509883 -304.352896) (xy 75.529174 -304.30762)
			(xy 75.555477 -304.266024) (xy 75.588112 -304.229187) (xy 75.626233 -304.198062) (xy 75.668854 -304.173455)
			(xy 75.71487 -304.156003) (xy 75.763089 -304.146159) (xy 75.812264 -304.144178) (xy 75.861119 -304.15011)
			(xy 75.90839 -304.163802) (xy 75.952852 -304.1849) (xy 75.993355 -304.212856) (xy 76.028848 -304.246948)
			(xy 76.058413 -304.286292) (xy 76.081284 -304.329869) (xy 76.096868 -304.37655) (xy 76.104763 -304.425127)
			(xy 76.105258 -304.449734) (xy 81.19416 -304.449734) (xy 81.19812 -304.40068) (xy 81.209897 -304.352896)
			(xy 81.229188 -304.30762) (xy 81.255491 -304.266024) (xy 81.288126 -304.229187) (xy 81.326247 -304.198062)
			(xy 81.368868 -304.173455) (xy 81.414884 -304.156003) (xy 81.463103 -304.146159) (xy 81.512278 -304.144178)
			(xy 81.561133 -304.15011) (xy 81.608404 -304.163802) (xy 81.652866 -304.1849) (xy 81.693369 -304.212856)
			(xy 81.728862 -304.246948) (xy 81.758427 -304.286292) (xy 81.781298 -304.329869) (xy 81.796882 -304.37655)
			(xy 81.804777 -304.425127) (xy 81.805272 -304.449734) (xy 82.14412 -304.449734) (xy 82.14808 -304.40068)
			(xy 82.159857 -304.352896) (xy 82.179148 -304.30762) (xy 82.205451 -304.266024) (xy 82.238086 -304.229187)
			(xy 82.276207 -304.198062) (xy 82.318828 -304.173455) (xy 82.364844 -304.156003) (xy 82.413063 -304.146159)
			(xy 82.462238 -304.144178) (xy 82.511093 -304.15011) (xy 82.558364 -304.163802) (xy 82.602826 -304.1849)
			(xy 82.643329 -304.212856) (xy 82.678822 -304.246948) (xy 82.708387 -304.286292) (xy 82.731258 -304.329869)
			(xy 82.746842 -304.37655) (xy 82.754737 -304.425127) (xy 82.755232 -304.449734) (xy 159.29408 -304.449734)
			(xy 159.29804 -304.40068) (xy 159.309817 -304.352896) (xy 159.329108 -304.30762) (xy 159.355411 -304.266024)
			(xy 159.388046 -304.229187) (xy 159.426167 -304.198062) (xy 159.468788 -304.173455) (xy 159.514804 -304.156003)
			(xy 159.563023 -304.146159) (xy 159.612198 -304.144178) (xy 159.661053 -304.15011) (xy 159.708324 -304.163802)
			(xy 159.752786 -304.1849) (xy 159.793289 -304.212856) (xy 159.828782 -304.246948) (xy 159.858347 -304.286292)
			(xy 159.881218 -304.329869) (xy 159.896802 -304.37655) (xy 159.904697 -304.425127) (xy 159.905192 -304.449734)
			(xy 160.24404 -304.449734) (xy 160.248 -304.40068) (xy 160.259777 -304.352896) (xy 160.279068 -304.30762)
			(xy 160.305371 -304.266024) (xy 160.338006 -304.229187) (xy 160.376127 -304.198062) (xy 160.418748 -304.173455)
			(xy 160.464764 -304.156003) (xy 160.512983 -304.146159) (xy 160.562158 -304.144178) (xy 160.611013 -304.15011)
			(xy 160.658284 -304.163802) (xy 160.702746 -304.1849) (xy 160.743249 -304.212856) (xy 160.778742 -304.246948)
			(xy 160.808307 -304.286292) (xy 160.831178 -304.329869) (xy 160.846762 -304.37655) (xy 160.854657 -304.425127)
			(xy 160.855152 -304.449734) (xy 306.744128 -304.449734) (xy 306.748088 -304.40068) (xy 306.759865 -304.352896)
			(xy 306.779156 -304.30762) (xy 306.805459 -304.266024) (xy 306.838094 -304.229187) (xy 306.876215 -304.198062)
			(xy 306.918836 -304.173455) (xy 306.964852 -304.156003) (xy 307.013071 -304.146159) (xy 307.062246 -304.144178)
			(xy 307.111101 -304.15011) (xy 307.158372 -304.163802) (xy 307.202834 -304.1849) (xy 307.243337 -304.212856)
			(xy 307.27883 -304.246948) (xy 307.308395 -304.286292) (xy 307.331266 -304.329869) (xy 307.34685 -304.37655)
			(xy 307.354745 -304.425127) (xy 307.35524 -304.449734) (xy 307.694088 -304.449734) (xy 307.698048 -304.40068)
			(xy 307.709825 -304.352896) (xy 307.729116 -304.30762) (xy 307.755419 -304.266024) (xy 307.788054 -304.229187)
			(xy 307.826175 -304.198062) (xy 307.868796 -304.173455) (xy 307.914812 -304.156003) (xy 307.963031 -304.146159)
			(xy 308.012206 -304.144178) (xy 308.061061 -304.15011) (xy 308.108332 -304.163802) (xy 308.152794 -304.1849)
			(xy 308.193297 -304.212856) (xy 308.22879 -304.246948) (xy 308.258355 -304.286292) (xy 308.281226 -304.329869)
			(xy 308.29681 -304.37655) (xy 308.304705 -304.425127) (xy 308.3052 -304.449734) (xy 313.394102 -304.449734)
			(xy 313.398062 -304.40068) (xy 313.409839 -304.352896) (xy 313.42913 -304.30762) (xy 313.455433 -304.266024)
			(xy 313.488068 -304.229187) (xy 313.526189 -304.198062) (xy 313.56881 -304.173455) (xy 313.614826 -304.156003)
			(xy 313.663045 -304.146159) (xy 313.71222 -304.144178) (xy 313.761075 -304.15011) (xy 313.808346 -304.163802)
			(xy 313.852808 -304.1849) (xy 313.893311 -304.212856) (xy 313.928804 -304.246948) (xy 313.958369 -304.286292)
			(xy 313.98124 -304.329869) (xy 313.996824 -304.37655) (xy 314.004719 -304.425127) (xy 314.005214 -304.449734)
			(xy 314.344062 -304.449734) (xy 314.348022 -304.40068) (xy 314.359799 -304.352896) (xy 314.37909 -304.30762)
			(xy 314.405393 -304.266024) (xy 314.438028 -304.229187) (xy 314.476149 -304.198062) (xy 314.51877 -304.173455)
			(xy 314.564786 -304.156003) (xy 314.613005 -304.146159) (xy 314.66218 -304.144178) (xy 314.711035 -304.15011)
			(xy 314.758306 -304.163802) (xy 314.802768 -304.1849) (xy 314.843271 -304.212856) (xy 314.878764 -304.246948)
			(xy 314.908329 -304.286292) (xy 314.9312 -304.329869) (xy 314.946784 -304.37655) (xy 314.954679 -304.425127)
			(xy 314.955174 -304.449734) (xy 391.494022 -304.449734) (xy 391.497982 -304.40068) (xy 391.509759 -304.352896)
			(xy 391.52905 -304.30762) (xy 391.555353 -304.266024) (xy 391.587988 -304.229187) (xy 391.626109 -304.198062)
			(xy 391.66873 -304.173455) (xy 391.714746 -304.156003) (xy 391.762965 -304.146159) (xy 391.81214 -304.144178)
			(xy 391.860995 -304.15011) (xy 391.908266 -304.163802) (xy 391.952728 -304.1849) (xy 391.993231 -304.212856)
			(xy 392.028724 -304.246948) (xy 392.058289 -304.286292) (xy 392.08116 -304.329869) (xy 392.096744 -304.37655)
			(xy 392.104639 -304.425127) (xy 392.105134 -304.449734) (xy 392.443982 -304.449734) (xy 392.447942 -304.40068)
			(xy 392.459719 -304.352896) (xy 392.47901 -304.30762) (xy 392.505313 -304.266024) (xy 392.537948 -304.229187)
			(xy 392.576069 -304.198062) (xy 392.61869 -304.173455) (xy 392.664706 -304.156003) (xy 392.712925 -304.146159)
			(xy 392.7621 -304.144178) (xy 392.810955 -304.15011) (xy 392.858226 -304.163802) (xy 392.902688 -304.1849)
			(xy 392.943191 -304.212856) (xy 392.978684 -304.246948) (xy 393.008249 -304.286292) (xy 393.03112 -304.329869)
			(xy 393.046704 -304.37655) (xy 393.054599 -304.425127) (xy 393.055094 -304.449734) (xy 393.054599 -304.474341)
			(xy 393.046704 -304.522918) (xy 393.03112 -304.569599) (xy 393.008249 -304.613176) (xy 392.978684 -304.65252)
			(xy 392.943191 -304.686612) (xy 392.902688 -304.714568) (xy 392.858226 -304.735666) (xy 392.810955 -304.749358)
			(xy 392.7621 -304.75529) (xy 392.712925 -304.753309) (xy 392.664706 -304.743465) (xy 392.61869 -304.726013)
			(xy 392.576069 -304.701406) (xy 392.537948 -304.670281) (xy 392.505313 -304.633444) (xy 392.47901 -304.591848)
			(xy 392.459719 -304.546572) (xy 392.447942 -304.498788) (xy 392.443982 -304.449734) (xy 392.105134 -304.449734)
			(xy 392.104639 -304.474341) (xy 392.096744 -304.522918) (xy 392.08116 -304.569599) (xy 392.058289 -304.613176)
			(xy 392.028724 -304.65252) (xy 391.993231 -304.686612) (xy 391.952728 -304.714568) (xy 391.908266 -304.735666)
			(xy 391.860995 -304.749358) (xy 391.81214 -304.75529) (xy 391.762965 -304.753309) (xy 391.714746 -304.743465)
			(xy 391.66873 -304.726013) (xy 391.626109 -304.701406) (xy 391.587988 -304.670281) (xy 391.555353 -304.633444)
			(xy 391.52905 -304.591848) (xy 391.509759 -304.546572) (xy 391.497982 -304.498788) (xy 391.494022 -304.449734)
			(xy 314.955174 -304.449734) (xy 314.954679 -304.474341) (xy 314.946784 -304.522918) (xy 314.9312 -304.569599)
			(xy 314.908329 -304.613176) (xy 314.878764 -304.65252) (xy 314.843271 -304.686612) (xy 314.802768 -304.714568)
			(xy 314.758306 -304.735666) (xy 314.711035 -304.749358) (xy 314.66218 -304.75529) (xy 314.613005 -304.753309)
			(xy 314.564786 -304.743465) (xy 314.51877 -304.726013) (xy 314.476149 -304.701406) (xy 314.438028 -304.670281)
			(xy 314.405393 -304.633444) (xy 314.37909 -304.591848) (xy 314.359799 -304.546572) (xy 314.348022 -304.498788)
			(xy 314.344062 -304.449734) (xy 314.005214 -304.449734) (xy 314.004719 -304.474341) (xy 313.996824 -304.522918)
			(xy 313.98124 -304.569599) (xy 313.958369 -304.613176) (xy 313.928804 -304.65252) (xy 313.893311 -304.686612)
			(xy 313.852808 -304.714568) (xy 313.808346 -304.735666) (xy 313.761075 -304.749358) (xy 313.71222 -304.75529)
			(xy 313.663045 -304.753309) (xy 313.614826 -304.743465) (xy 313.56881 -304.726013) (xy 313.526189 -304.701406)
			(xy 313.488068 -304.670281) (xy 313.455433 -304.633444) (xy 313.42913 -304.591848) (xy 313.409839 -304.546572)
			(xy 313.398062 -304.498788) (xy 313.394102 -304.449734) (xy 308.3052 -304.449734) (xy 308.304705 -304.474341)
			(xy 308.29681 -304.522918) (xy 308.281226 -304.569599) (xy 308.258355 -304.613176) (xy 308.22879 -304.65252)
			(xy 308.193297 -304.686612) (xy 308.152794 -304.714568) (xy 308.108332 -304.735666) (xy 308.061061 -304.749358)
			(xy 308.012206 -304.75529) (xy 307.963031 -304.753309) (xy 307.914812 -304.743465) (xy 307.868796 -304.726013)
			(xy 307.826175 -304.701406) (xy 307.788054 -304.670281) (xy 307.755419 -304.633444) (xy 307.729116 -304.591848)
			(xy 307.709825 -304.546572) (xy 307.698048 -304.498788) (xy 307.694088 -304.449734) (xy 307.35524 -304.449734)
			(xy 307.354745 -304.474341) (xy 307.34685 -304.522918) (xy 307.331266 -304.569599) (xy 307.308395 -304.613176)
			(xy 307.27883 -304.65252) (xy 307.243337 -304.686612) (xy 307.202834 -304.714568) (xy 307.158372 -304.735666)
			(xy 307.111101 -304.749358) (xy 307.062246 -304.75529) (xy 307.013071 -304.753309) (xy 306.964852 -304.743465)
			(xy 306.918836 -304.726013) (xy 306.876215 -304.701406) (xy 306.838094 -304.670281) (xy 306.805459 -304.633444)
			(xy 306.779156 -304.591848) (xy 306.759865 -304.546572) (xy 306.748088 -304.498788) (xy 306.744128 -304.449734)
			(xy 160.855152 -304.449734) (xy 160.854657 -304.474341) (xy 160.846762 -304.522918) (xy 160.831178 -304.569599)
			(xy 160.808307 -304.613176) (xy 160.778742 -304.65252) (xy 160.743249 -304.686612) (xy 160.702746 -304.714568)
			(xy 160.658284 -304.735666) (xy 160.611013 -304.749358) (xy 160.562158 -304.75529) (xy 160.512983 -304.753309)
			(xy 160.464764 -304.743465) (xy 160.418748 -304.726013) (xy 160.376127 -304.701406) (xy 160.338006 -304.670281)
			(xy 160.305371 -304.633444) (xy 160.279068 -304.591848) (xy 160.259777 -304.546572) (xy 160.248 -304.498788)
			(xy 160.24404 -304.449734) (xy 159.905192 -304.449734) (xy 159.904697 -304.474341) (xy 159.896802 -304.522918)
			(xy 159.881218 -304.569599) (xy 159.858347 -304.613176) (xy 159.828782 -304.65252) (xy 159.793289 -304.686612)
			(xy 159.752786 -304.714568) (xy 159.708324 -304.735666) (xy 159.661053 -304.749358) (xy 159.612198 -304.75529)
			(xy 159.563023 -304.753309) (xy 159.514804 -304.743465) (xy 159.468788 -304.726013) (xy 159.426167 -304.701406)
			(xy 159.388046 -304.670281) (xy 159.355411 -304.633444) (xy 159.329108 -304.591848) (xy 159.309817 -304.546572)
			(xy 159.29804 -304.498788) (xy 159.29408 -304.449734) (xy 82.755232 -304.449734) (xy 82.754737 -304.474341)
			(xy 82.746842 -304.522918) (xy 82.731258 -304.569599) (xy 82.708387 -304.613176) (xy 82.678822 -304.65252)
			(xy 82.643329 -304.686612) (xy 82.602826 -304.714568) (xy 82.558364 -304.735666) (xy 82.511093 -304.749358)
			(xy 82.462238 -304.75529) (xy 82.413063 -304.753309) (xy 82.364844 -304.743465) (xy 82.318828 -304.726013)
			(xy 82.276207 -304.701406) (xy 82.238086 -304.670281) (xy 82.205451 -304.633444) (xy 82.179148 -304.591848)
			(xy 82.159857 -304.546572) (xy 82.14808 -304.498788) (xy 82.14412 -304.449734) (xy 81.805272 -304.449734)
			(xy 81.804777 -304.474341) (xy 81.796882 -304.522918) (xy 81.781298 -304.569599) (xy 81.758427 -304.613176)
			(xy 81.728862 -304.65252) (xy 81.693369 -304.686612) (xy 81.652866 -304.714568) (xy 81.608404 -304.735666)
			(xy 81.561133 -304.749358) (xy 81.512278 -304.75529) (xy 81.463103 -304.753309) (xy 81.414884 -304.743465)
			(xy 81.368868 -304.726013) (xy 81.326247 -304.701406) (xy 81.288126 -304.670281) (xy 81.255491 -304.633444)
			(xy 81.229188 -304.591848) (xy 81.209897 -304.546572) (xy 81.19812 -304.498788) (xy 81.19416 -304.449734)
			(xy 76.105258 -304.449734) (xy 76.104763 -304.474341) (xy 76.096868 -304.522918) (xy 76.081284 -304.569599)
			(xy 76.058413 -304.613176) (xy 76.028848 -304.65252) (xy 75.993355 -304.686612) (xy 75.952852 -304.714568)
			(xy 75.90839 -304.735666) (xy 75.861119 -304.749358) (xy 75.812264 -304.75529) (xy 75.763089 -304.753309)
			(xy 75.71487 -304.743465) (xy 75.668854 -304.726013) (xy 75.626233 -304.701406) (xy 75.588112 -304.670281)
			(xy 75.555477 -304.633444) (xy 75.529174 -304.591848) (xy 75.509883 -304.546572) (xy 75.498106 -304.498788)
			(xy 75.494146 -304.449734) (xy 75.155298 -304.449734) (xy 75.154803 -304.474341) (xy 75.146908 -304.522918)
			(xy 75.131324 -304.569599) (xy 75.108453 -304.613176) (xy 75.078888 -304.65252) (xy 75.043395 -304.686612)
			(xy 75.002892 -304.714568) (xy 74.95843 -304.735666) (xy 74.911159 -304.749358) (xy 74.862304 -304.75529)
			(xy 74.813129 -304.753309) (xy 74.76491 -304.743465) (xy 74.718894 -304.726013) (xy 74.676273 -304.701406)
			(xy 74.638152 -304.670281) (xy 74.605517 -304.633444) (xy 74.579214 -304.591848) (xy 74.559923 -304.546572)
			(xy 74.548146 -304.498788) (xy 74.544186 -304.449734) (xy 0.508 -304.449734) (xy 0.508 -305.19751)
			(xy 17.638266 -305.19751) (xy 17.642339 -305.141851) (xy 17.654474 -305.087378) (xy 17.67441 -305.035252)
			(xy 17.701724 -304.986584) (xy 17.735832 -304.942412) (xy 17.776009 -304.903677) (xy 17.821397 -304.871205)
			(xy 17.871029 -304.845687) (xy 17.923849 -304.827668) (xy 17.978728 -304.817531) (xy 18.034499 -304.815493)
			(xy 18.089973 -304.821596) (xy 18.143966 -304.835712) (xy 18.195329 -304.857539) (xy 18.242967 -304.886612)
			(xy 18.285863 -304.922311) (xy 18.323105 -304.963875) (xy 18.353899 -305.010419) (xy 18.377587 -305.06095)
			(xy 18.393665 -305.114392) (xy 18.401791 -305.169606) (xy 18.4023 -305.19751) (xy 18.401791 -305.225414)
			(xy 18.393665 -305.280628) (xy 18.377587 -305.33407) (xy 18.353899 -305.384601) (xy 18.343745 -305.399948)
			(xy 76.444106 -305.399948) (xy 76.448066 -305.350894) (xy 76.459843 -305.30311) (xy 76.479134 -305.257834)
			(xy 76.505437 -305.216238) (xy 76.538072 -305.179401) (xy 76.576193 -305.148276) (xy 76.618814 -305.123669)
			(xy 76.66483 -305.106217) (xy 76.713049 -305.096373) (xy 76.762224 -305.094392) (xy 76.811079 -305.100324)
			(xy 76.85835 -305.114016) (xy 76.902812 -305.135114) (xy 76.943315 -305.16307) (xy 76.978808 -305.197162)
			(xy 77.008373 -305.236506) (xy 77.031244 -305.280083) (xy 77.046828 -305.326764) (xy 77.054723 -305.375341)
			(xy 77.055218 -305.399948) (xy 77.394066 -305.399948) (xy 77.398026 -305.350894) (xy 77.409803 -305.30311)
			(xy 77.429094 -305.257834) (xy 77.455397 -305.216238) (xy 77.488032 -305.179401) (xy 77.526153 -305.148276)
			(xy 77.568774 -305.123669) (xy 77.61479 -305.106217) (xy 77.663009 -305.096373) (xy 77.712184 -305.094392)
			(xy 77.761039 -305.100324) (xy 77.80831 -305.114016) (xy 77.852772 -305.135114) (xy 77.893275 -305.16307)
			(xy 77.928768 -305.197162) (xy 77.958333 -305.236506) (xy 77.981204 -305.280083) (xy 77.996788 -305.326764)
			(xy 78.004683 -305.375341) (xy 78.005178 -305.399948) (xy 79.293986 -305.399948) (xy 79.297946 -305.350894)
			(xy 79.309723 -305.30311) (xy 79.329014 -305.257834) (xy 79.355317 -305.216238) (xy 79.387952 -305.179401)
			(xy 79.426073 -305.148276) (xy 79.468694 -305.123669) (xy 79.51471 -305.106217) (xy 79.562929 -305.096373)
			(xy 79.612104 -305.094392) (xy 79.660959 -305.100324) (xy 79.70823 -305.114016) (xy 79.752692 -305.135114)
			(xy 79.793195 -305.16307) (xy 79.828688 -305.197162) (xy 79.858253 -305.236506) (xy 79.881124 -305.280083)
			(xy 79.896708 -305.326764) (xy 79.904603 -305.375341) (xy 79.905098 -305.399948) (xy 80.243946 -305.399948)
			(xy 80.247906 -305.350894) (xy 80.259683 -305.30311) (xy 80.278974 -305.257834) (xy 80.305277 -305.216238)
			(xy 80.337912 -305.179401) (xy 80.376033 -305.148276) (xy 80.418654 -305.123669) (xy 80.46467 -305.106217)
			(xy 80.512889 -305.096373) (xy 80.562064 -305.094392) (xy 80.610919 -305.100324) (xy 80.65819 -305.114016)
			(xy 80.702652 -305.135114) (xy 80.743155 -305.16307) (xy 80.778648 -305.197162) (xy 80.808213 -305.236506)
			(xy 80.831084 -305.280083) (xy 80.846668 -305.326764) (xy 80.854563 -305.375341) (xy 80.855058 -305.399948)
			(xy 157.39416 -305.399948) (xy 157.39812 -305.350894) (xy 157.409897 -305.30311) (xy 157.429188 -305.257834)
			(xy 157.455491 -305.216238) (xy 157.488126 -305.179401) (xy 157.526247 -305.148276) (xy 157.568868 -305.123669)
			(xy 157.614884 -305.106217) (xy 157.663103 -305.096373) (xy 157.712278 -305.094392) (xy 157.761133 -305.100324)
			(xy 157.808404 -305.114016) (xy 157.852866 -305.135114) (xy 157.893369 -305.16307) (xy 157.928862 -305.197162)
			(xy 157.958427 -305.236506) (xy 157.981298 -305.280083) (xy 157.996882 -305.326764) (xy 158.004777 -305.375341)
			(xy 158.005272 -305.399948) (xy 158.34412 -305.399948) (xy 158.34808 -305.350894) (xy 158.359857 -305.30311)
			(xy 158.379148 -305.257834) (xy 158.405451 -305.216238) (xy 158.438086 -305.179401) (xy 158.476207 -305.148276)
			(xy 158.518828 -305.123669) (xy 158.564844 -305.106217) (xy 158.613063 -305.096373) (xy 158.662238 -305.094392)
			(xy 158.711093 -305.100324) (xy 158.758364 -305.114016) (xy 158.802826 -305.135114) (xy 158.843329 -305.16307)
			(xy 158.878822 -305.197162) (xy 158.908387 -305.236506) (xy 158.931258 -305.280083) (xy 158.946842 -305.326764)
			(xy 158.954737 -305.375341) (xy 158.955232 -305.399948) (xy 308.644048 -305.399948) (xy 308.648008 -305.350894)
			(xy 308.659785 -305.30311) (xy 308.679076 -305.257834) (xy 308.705379 -305.216238) (xy 308.738014 -305.179401)
			(xy 308.776135 -305.148276) (xy 308.818756 -305.123669) (xy 308.864772 -305.106217) (xy 308.912991 -305.096373)
			(xy 308.962166 -305.094392) (xy 309.011021 -305.100324) (xy 309.058292 -305.114016) (xy 309.102754 -305.135114)
			(xy 309.143257 -305.16307) (xy 309.17875 -305.197162) (xy 309.208315 -305.236506) (xy 309.231186 -305.280083)
			(xy 309.24677 -305.326764) (xy 309.254665 -305.375341) (xy 309.25516 -305.399948) (xy 309.594008 -305.399948)
			(xy 309.597968 -305.350894) (xy 309.609745 -305.30311) (xy 309.629036 -305.257834) (xy 309.655339 -305.216238)
			(xy 309.687974 -305.179401) (xy 309.726095 -305.148276) (xy 309.768716 -305.123669) (xy 309.814732 -305.106217)
			(xy 309.862951 -305.096373) (xy 309.912126 -305.094392) (xy 309.960981 -305.100324) (xy 310.008252 -305.114016)
			(xy 310.052714 -305.135114) (xy 310.093217 -305.16307) (xy 310.12871 -305.197162) (xy 310.158275 -305.236506)
			(xy 310.181146 -305.280083) (xy 310.19673 -305.326764) (xy 310.204625 -305.375341) (xy 310.20512 -305.399948)
			(xy 311.493928 -305.399948) (xy 311.497888 -305.350894) (xy 311.509665 -305.30311) (xy 311.528956 -305.257834)
			(xy 311.555259 -305.216238) (xy 311.587894 -305.179401) (xy 311.626015 -305.148276) (xy 311.668636 -305.123669)
			(xy 311.714652 -305.106217) (xy 311.762871 -305.096373) (xy 311.812046 -305.094392) (xy 311.860901 -305.100324)
			(xy 311.908172 -305.114016) (xy 311.952634 -305.135114) (xy 311.993137 -305.16307) (xy 312.02863 -305.197162)
			(xy 312.058195 -305.236506) (xy 312.081066 -305.280083) (xy 312.09665 -305.326764) (xy 312.104545 -305.375341)
			(xy 312.10504 -305.399948) (xy 312.443888 -305.399948) (xy 312.447848 -305.350894) (xy 312.459625 -305.30311)
			(xy 312.478916 -305.257834) (xy 312.505219 -305.216238) (xy 312.537854 -305.179401) (xy 312.575975 -305.148276)
			(xy 312.618596 -305.123669) (xy 312.664612 -305.106217) (xy 312.712831 -305.096373) (xy 312.762006 -305.094392)
			(xy 312.810861 -305.100324) (xy 312.858132 -305.114016) (xy 312.902594 -305.135114) (xy 312.943097 -305.16307)
			(xy 312.97859 -305.197162) (xy 313.008155 -305.236506) (xy 313.031026 -305.280083) (xy 313.04661 -305.326764)
			(xy 313.054505 -305.375341) (xy 313.055 -305.399948) (xy 389.594102 -305.399948) (xy 389.598062 -305.350894)
			(xy 389.609839 -305.30311) (xy 389.62913 -305.257834) (xy 389.655433 -305.216238) (xy 389.688068 -305.179401)
			(xy 389.726189 -305.148276) (xy 389.76881 -305.123669) (xy 389.814826 -305.106217) (xy 389.863045 -305.096373)
			(xy 389.91222 -305.094392) (xy 389.961075 -305.100324) (xy 390.008346 -305.114016) (xy 390.052808 -305.135114)
			(xy 390.093311 -305.16307) (xy 390.128804 -305.197162) (xy 390.158369 -305.236506) (xy 390.18124 -305.280083)
			(xy 390.196824 -305.326764) (xy 390.204719 -305.375341) (xy 390.205214 -305.399948) (xy 390.544062 -305.399948)
			(xy 390.548022 -305.350894) (xy 390.559799 -305.30311) (xy 390.57909 -305.257834) (xy 390.605393 -305.216238)
			(xy 390.638028 -305.179401) (xy 390.676149 -305.148276) (xy 390.71877 -305.123669) (xy 390.764786 -305.106217)
			(xy 390.813005 -305.096373) (xy 390.86218 -305.094392) (xy 390.911035 -305.100324) (xy 390.958306 -305.114016)
			(xy 391.002768 -305.135114) (xy 391.043271 -305.16307) (xy 391.078764 -305.197162) (xy 391.108329 -305.236506)
			(xy 391.1312 -305.280083) (xy 391.146784 -305.326764) (xy 391.154679 -305.375341) (xy 391.155174 -305.399948)
			(xy 391.154679 -305.424555) (xy 391.146784 -305.473132) (xy 391.1312 -305.519813) (xy 391.108329 -305.56339)
			(xy 391.078764 -305.602734) (xy 391.043271 -305.636826) (xy 391.002768 -305.664782) (xy 390.958306 -305.68588)
			(xy 390.911035 -305.699572) (xy 390.86218 -305.705504) (xy 390.813005 -305.703523) (xy 390.764786 -305.693679)
			(xy 390.71877 -305.676227) (xy 390.676149 -305.65162) (xy 390.638028 -305.620495) (xy 390.605393 -305.583658)
			(xy 390.57909 -305.542062) (xy 390.559799 -305.496786) (xy 390.548022 -305.449002) (xy 390.544062 -305.399948)
			(xy 390.205214 -305.399948) (xy 390.204719 -305.424555) (xy 390.196824 -305.473132) (xy 390.18124 -305.519813)
			(xy 390.158369 -305.56339) (xy 390.128804 -305.602734) (xy 390.093311 -305.636826) (xy 390.052808 -305.664782)
			(xy 390.008346 -305.68588) (xy 389.961075 -305.699572) (xy 389.91222 -305.705504) (xy 389.863045 -305.703523)
			(xy 389.814826 -305.693679) (xy 389.76881 -305.676227) (xy 389.726189 -305.65162) (xy 389.688068 -305.620495)
			(xy 389.655433 -305.583658) (xy 389.62913 -305.542062) (xy 389.609839 -305.496786) (xy 389.598062 -305.449002)
			(xy 389.594102 -305.399948) (xy 313.055 -305.399948) (xy 313.054505 -305.424555) (xy 313.04661 -305.473132)
			(xy 313.031026 -305.519813) (xy 313.008155 -305.56339) (xy 312.97859 -305.602734) (xy 312.943097 -305.636826)
			(xy 312.902594 -305.664782) (xy 312.858132 -305.68588) (xy 312.810861 -305.699572) (xy 312.762006 -305.705504)
			(xy 312.712831 -305.703523) (xy 312.664612 -305.693679) (xy 312.618596 -305.676227) (xy 312.575975 -305.65162)
			(xy 312.537854 -305.620495) (xy 312.505219 -305.583658) (xy 312.478916 -305.542062) (xy 312.459625 -305.496786)
			(xy 312.447848 -305.449002) (xy 312.443888 -305.399948) (xy 312.10504 -305.399948) (xy 312.104545 -305.424555)
			(xy 312.09665 -305.473132) (xy 312.081066 -305.519813) (xy 312.058195 -305.56339) (xy 312.02863 -305.602734)
			(xy 311.993137 -305.636826) (xy 311.952634 -305.664782) (xy 311.908172 -305.68588) (xy 311.860901 -305.699572)
			(xy 311.812046 -305.705504) (xy 311.762871 -305.703523) (xy 311.714652 -305.693679) (xy 311.668636 -305.676227)
			(xy 311.626015 -305.65162) (xy 311.587894 -305.620495) (xy 311.555259 -305.583658) (xy 311.528956 -305.542062)
			(xy 311.509665 -305.496786) (xy 311.497888 -305.449002) (xy 311.493928 -305.399948) (xy 310.20512 -305.399948)
			(xy 310.204625 -305.424555) (xy 310.19673 -305.473132) (xy 310.181146 -305.519813) (xy 310.158275 -305.56339)
			(xy 310.12871 -305.602734) (xy 310.093217 -305.636826) (xy 310.052714 -305.664782) (xy 310.008252 -305.68588)
			(xy 309.960981 -305.699572) (xy 309.912126 -305.705504) (xy 309.862951 -305.703523) (xy 309.814732 -305.693679)
			(xy 309.768716 -305.676227) (xy 309.726095 -305.65162) (xy 309.687974 -305.620495) (xy 309.655339 -305.583658)
			(xy 309.629036 -305.542062) (xy 309.609745 -305.496786) (xy 309.597968 -305.449002) (xy 309.594008 -305.399948)
			(xy 309.25516 -305.399948) (xy 309.254665 -305.424555) (xy 309.24677 -305.473132) (xy 309.231186 -305.519813)
			(xy 309.208315 -305.56339) (xy 309.17875 -305.602734) (xy 309.143257 -305.636826) (xy 309.102754 -305.664782)
			(xy 309.058292 -305.68588) (xy 309.011021 -305.699572) (xy 308.962166 -305.705504) (xy 308.912991 -305.703523)
			(xy 308.864772 -305.693679) (xy 308.818756 -305.676227) (xy 308.776135 -305.65162) (xy 308.738014 -305.620495)
			(xy 308.705379 -305.583658) (xy 308.679076 -305.542062) (xy 308.659785 -305.496786) (xy 308.648008 -305.449002)
			(xy 308.644048 -305.399948) (xy 158.955232 -305.399948) (xy 158.954737 -305.424555) (xy 158.946842 -305.473132)
			(xy 158.931258 -305.519813) (xy 158.908387 -305.56339) (xy 158.878822 -305.602734) (xy 158.843329 -305.636826)
			(xy 158.802826 -305.664782) (xy 158.758364 -305.68588) (xy 158.711093 -305.699572) (xy 158.662238 -305.705504)
			(xy 158.613063 -305.703523) (xy 158.564844 -305.693679) (xy 158.518828 -305.676227) (xy 158.476207 -305.65162)
			(xy 158.438086 -305.620495) (xy 158.405451 -305.583658) (xy 158.379148 -305.542062) (xy 158.359857 -305.496786)
			(xy 158.34808 -305.449002) (xy 158.34412 -305.399948) (xy 158.005272 -305.399948) (xy 158.004777 -305.424555)
			(xy 157.996882 -305.473132) (xy 157.981298 -305.519813) (xy 157.958427 -305.56339) (xy 157.928862 -305.602734)
			(xy 157.893369 -305.636826) (xy 157.852866 -305.664782) (xy 157.808404 -305.68588) (xy 157.761133 -305.699572)
			(xy 157.712278 -305.705504) (xy 157.663103 -305.703523) (xy 157.614884 -305.693679) (xy 157.568868 -305.676227)
			(xy 157.526247 -305.65162) (xy 157.488126 -305.620495) (xy 157.455491 -305.583658) (xy 157.429188 -305.542062)
			(xy 157.409897 -305.496786) (xy 157.39812 -305.449002) (xy 157.39416 -305.399948) (xy 80.855058 -305.399948)
			(xy 80.854563 -305.424555) (xy 80.846668 -305.473132) (xy 80.831084 -305.519813) (xy 80.808213 -305.56339)
			(xy 80.778648 -305.602734) (xy 80.743155 -305.636826) (xy 80.702652 -305.664782) (xy 80.65819 -305.68588)
			(xy 80.610919 -305.699572) (xy 80.562064 -305.705504) (xy 80.512889 -305.703523) (xy 80.46467 -305.693679)
			(xy 80.418654 -305.676227) (xy 80.376033 -305.65162) (xy 80.337912 -305.620495) (xy 80.305277 -305.583658)
			(xy 80.278974 -305.542062) (xy 80.259683 -305.496786) (xy 80.247906 -305.449002) (xy 80.243946 -305.399948)
			(xy 79.905098 -305.399948) (xy 79.904603 -305.424555) (xy 79.896708 -305.473132) (xy 79.881124 -305.519813)
			(xy 79.858253 -305.56339) (xy 79.828688 -305.602734) (xy 79.793195 -305.636826) (xy 79.752692 -305.664782)
			(xy 79.70823 -305.68588) (xy 79.660959 -305.699572) (xy 79.612104 -305.705504) (xy 79.562929 -305.703523)
			(xy 79.51471 -305.693679) (xy 79.468694 -305.676227) (xy 79.426073 -305.65162) (xy 79.387952 -305.620495)
			(xy 79.355317 -305.583658) (xy 79.329014 -305.542062) (xy 79.309723 -305.496786) (xy 79.297946 -305.449002)
			(xy 79.293986 -305.399948) (xy 78.005178 -305.399948) (xy 78.004683 -305.424555) (xy 77.996788 -305.473132)
			(xy 77.981204 -305.519813) (xy 77.958333 -305.56339) (xy 77.928768 -305.602734) (xy 77.893275 -305.636826)
			(xy 77.852772 -305.664782) (xy 77.80831 -305.68588) (xy 77.761039 -305.699572) (xy 77.712184 -305.705504)
			(xy 77.663009 -305.703523) (xy 77.61479 -305.693679) (xy 77.568774 -305.676227) (xy 77.526153 -305.65162)
			(xy 77.488032 -305.620495) (xy 77.455397 -305.583658) (xy 77.429094 -305.542062) (xy 77.409803 -305.496786)
			(xy 77.398026 -305.449002) (xy 77.394066 -305.399948) (xy 77.055218 -305.399948) (xy 77.054723 -305.424555)
			(xy 77.046828 -305.473132) (xy 77.031244 -305.519813) (xy 77.008373 -305.56339) (xy 76.978808 -305.602734)
			(xy 76.943315 -305.636826) (xy 76.902812 -305.664782) (xy 76.85835 -305.68588) (xy 76.811079 -305.699572)
			(xy 76.762224 -305.705504) (xy 76.713049 -305.703523) (xy 76.66483 -305.693679) (xy 76.618814 -305.676227)
			(xy 76.576193 -305.65162) (xy 76.538072 -305.620495) (xy 76.505437 -305.583658) (xy 76.479134 -305.542062)
			(xy 76.459843 -305.496786) (xy 76.448066 -305.449002) (xy 76.444106 -305.399948) (xy 18.343745 -305.399948)
			(xy 18.323105 -305.431145) (xy 18.285863 -305.472709) (xy 18.242967 -305.508408) (xy 18.195329 -305.537481)
			(xy 18.143966 -305.559308) (xy 18.089973 -305.573424) (xy 18.034499 -305.579527) (xy 17.978728 -305.577489)
			(xy 17.923849 -305.567352) (xy 17.871029 -305.549333) (xy 17.821397 -305.523815) (xy 17.776009 -305.491343)
			(xy 17.735832 -305.452608) (xy 17.701724 -305.408436) (xy 17.67441 -305.359768) (xy 17.654474 -305.307642)
			(xy 17.642339 -305.253169) (xy 17.638266 -305.19751) (xy 0.508 -305.19751) (xy 0.508 -306.28209)
			(xy 17.638266 -306.28209) (xy 17.642339 -306.226431) (xy 17.654474 -306.171958) (xy 17.67441 -306.119832)
			(xy 17.701724 -306.071164) (xy 17.735832 -306.026992) (xy 17.776009 -305.988257) (xy 17.821397 -305.955785)
			(xy 17.871029 -305.930267) (xy 17.923849 -305.912248) (xy 17.978728 -305.902111) (xy 18.034499 -305.900073)
			(xy 18.089973 -305.906176) (xy 18.143966 -305.920292) (xy 18.195329 -305.942119) (xy 18.242967 -305.971192)
			(xy 18.285863 -306.006891) (xy 18.323105 -306.048455) (xy 18.353899 -306.094999) (xy 18.377587 -306.14553)
			(xy 18.393665 -306.198972) (xy 18.401791 -306.254186) (xy 18.4023 -306.28209) (xy 18.401791 -306.309994)
			(xy 18.395917 -306.349908) (xy 74.544186 -306.349908) (xy 74.548146 -306.300854) (xy 74.559923 -306.25307)
			(xy 74.579214 -306.207794) (xy 74.605517 -306.166198) (xy 74.638152 -306.129361) (xy 74.676273 -306.098236)
			(xy 74.718894 -306.073629) (xy 74.76491 -306.056177) (xy 74.813129 -306.046333) (xy 74.862304 -306.044352)
			(xy 74.911159 -306.050284) (xy 74.95843 -306.063976) (xy 75.002892 -306.085074) (xy 75.043395 -306.11303)
			(xy 75.078888 -306.147122) (xy 75.108453 -306.186466) (xy 75.131324 -306.230043) (xy 75.146908 -306.276724)
			(xy 75.154803 -306.325301) (xy 75.155298 -306.349908) (xy 75.494146 -306.349908) (xy 75.498106 -306.300854)
			(xy 75.509883 -306.25307) (xy 75.529174 -306.207794) (xy 75.555477 -306.166198) (xy 75.588112 -306.129361)
			(xy 75.626233 -306.098236) (xy 75.668854 -306.073629) (xy 75.71487 -306.056177) (xy 75.763089 -306.046333)
			(xy 75.812264 -306.044352) (xy 75.861119 -306.050284) (xy 75.90839 -306.063976) (xy 75.952852 -306.085074)
			(xy 75.993355 -306.11303) (xy 76.028848 -306.147122) (xy 76.058413 -306.186466) (xy 76.081284 -306.230043)
			(xy 76.096868 -306.276724) (xy 76.104763 -306.325301) (xy 76.105258 -306.349908) (xy 81.19416 -306.349908)
			(xy 81.19812 -306.300854) (xy 81.209897 -306.25307) (xy 81.229188 -306.207794) (xy 81.255491 -306.166198)
			(xy 81.288126 -306.129361) (xy 81.326247 -306.098236) (xy 81.368868 -306.073629) (xy 81.414884 -306.056177)
			(xy 81.463103 -306.046333) (xy 81.512278 -306.044352) (xy 81.561133 -306.050284) (xy 81.608404 -306.063976)
			(xy 81.652866 -306.085074) (xy 81.693369 -306.11303) (xy 81.728862 -306.147122) (xy 81.758427 -306.186466)
			(xy 81.781298 -306.230043) (xy 81.796882 -306.276724) (xy 81.804777 -306.325301) (xy 81.805272 -306.349908)
			(xy 82.14412 -306.349908) (xy 82.14808 -306.300854) (xy 82.159857 -306.25307) (xy 82.179148 -306.207794)
			(xy 82.205451 -306.166198) (xy 82.238086 -306.129361) (xy 82.276207 -306.098236) (xy 82.318828 -306.073629)
			(xy 82.364844 -306.056177) (xy 82.413063 -306.046333) (xy 82.462238 -306.044352) (xy 82.511093 -306.050284)
			(xy 82.558364 -306.063976) (xy 82.602826 -306.085074) (xy 82.643329 -306.11303) (xy 82.678822 -306.147122)
			(xy 82.708387 -306.186466) (xy 82.731258 -306.230043) (xy 82.746842 -306.276724) (xy 82.754737 -306.325301)
			(xy 82.755232 -306.349908) (xy 159.29408 -306.349908) (xy 159.29804 -306.300854) (xy 159.309817 -306.25307)
			(xy 159.329108 -306.207794) (xy 159.355411 -306.166198) (xy 159.388046 -306.129361) (xy 159.426167 -306.098236)
			(xy 159.468788 -306.073629) (xy 159.514804 -306.056177) (xy 159.563023 -306.046333) (xy 159.612198 -306.044352)
			(xy 159.661053 -306.050284) (xy 159.708324 -306.063976) (xy 159.752786 -306.085074) (xy 159.793289 -306.11303)
			(xy 159.828782 -306.147122) (xy 159.858347 -306.186466) (xy 159.881218 -306.230043) (xy 159.896802 -306.276724)
			(xy 159.904697 -306.325301) (xy 159.905192 -306.349908) (xy 160.24404 -306.349908) (xy 160.248 -306.300854)
			(xy 160.259777 -306.25307) (xy 160.279068 -306.207794) (xy 160.305371 -306.166198) (xy 160.338006 -306.129361)
			(xy 160.376127 -306.098236) (xy 160.418748 -306.073629) (xy 160.464764 -306.056177) (xy 160.512983 -306.046333)
			(xy 160.562158 -306.044352) (xy 160.611013 -306.050284) (xy 160.658284 -306.063976) (xy 160.702746 -306.085074)
			(xy 160.743249 -306.11303) (xy 160.778742 -306.147122) (xy 160.808307 -306.186466) (xy 160.831178 -306.230043)
			(xy 160.846762 -306.276724) (xy 160.854657 -306.325301) (xy 160.855152 -306.349908) (xy 306.744128 -306.349908)
			(xy 306.748088 -306.300854) (xy 306.759865 -306.25307) (xy 306.779156 -306.207794) (xy 306.805459 -306.166198)
			(xy 306.838094 -306.129361) (xy 306.876215 -306.098236) (xy 306.918836 -306.073629) (xy 306.964852 -306.056177)
			(xy 307.013071 -306.046333) (xy 307.062246 -306.044352) (xy 307.111101 -306.050284) (xy 307.158372 -306.063976)
			(xy 307.202834 -306.085074) (xy 307.243337 -306.11303) (xy 307.27883 -306.147122) (xy 307.308395 -306.186466)
			(xy 307.331266 -306.230043) (xy 307.34685 -306.276724) (xy 307.354745 -306.325301) (xy 307.35524 -306.349908)
			(xy 307.694088 -306.349908) (xy 307.698048 -306.300854) (xy 307.709825 -306.25307) (xy 307.729116 -306.207794)
			(xy 307.755419 -306.166198) (xy 307.788054 -306.129361) (xy 307.826175 -306.098236) (xy 307.868796 -306.073629)
			(xy 307.914812 -306.056177) (xy 307.963031 -306.046333) (xy 308.012206 -306.044352) (xy 308.061061 -306.050284)
			(xy 308.108332 -306.063976) (xy 308.152794 -306.085074) (xy 308.193297 -306.11303) (xy 308.22879 -306.147122)
			(xy 308.258355 -306.186466) (xy 308.281226 -306.230043) (xy 308.29681 -306.276724) (xy 308.304705 -306.325301)
			(xy 308.3052 -306.349908) (xy 313.394102 -306.349908) (xy 313.398062 -306.300854) (xy 313.409839 -306.25307)
			(xy 313.42913 -306.207794) (xy 313.455433 -306.166198) (xy 313.488068 -306.129361) (xy 313.526189 -306.098236)
			(xy 313.56881 -306.073629) (xy 313.614826 -306.056177) (xy 313.663045 -306.046333) (xy 313.71222 -306.044352)
			(xy 313.761075 -306.050284) (xy 313.808346 -306.063976) (xy 313.852808 -306.085074) (xy 313.893311 -306.11303)
			(xy 313.928804 -306.147122) (xy 313.958369 -306.186466) (xy 313.98124 -306.230043) (xy 313.996824 -306.276724)
			(xy 314.004719 -306.325301) (xy 314.005214 -306.349908) (xy 314.344062 -306.349908) (xy 314.348022 -306.300854)
			(xy 314.359799 -306.25307) (xy 314.37909 -306.207794) (xy 314.405393 -306.166198) (xy 314.438028 -306.129361)
			(xy 314.476149 -306.098236) (xy 314.51877 -306.073629) (xy 314.564786 -306.056177) (xy 314.613005 -306.046333)
			(xy 314.66218 -306.044352) (xy 314.711035 -306.050284) (xy 314.758306 -306.063976) (xy 314.802768 -306.085074)
			(xy 314.843271 -306.11303) (xy 314.878764 -306.147122) (xy 314.908329 -306.186466) (xy 314.9312 -306.230043)
			(xy 314.946784 -306.276724) (xy 314.954679 -306.325301) (xy 314.955174 -306.349908) (xy 391.494022 -306.349908)
			(xy 391.497982 -306.300854) (xy 391.509759 -306.25307) (xy 391.52905 -306.207794) (xy 391.555353 -306.166198)
			(xy 391.587988 -306.129361) (xy 391.626109 -306.098236) (xy 391.66873 -306.073629) (xy 391.714746 -306.056177)
			(xy 391.762965 -306.046333) (xy 391.81214 -306.044352) (xy 391.860995 -306.050284) (xy 391.908266 -306.063976)
			(xy 391.952728 -306.085074) (xy 391.993231 -306.11303) (xy 392.028724 -306.147122) (xy 392.058289 -306.186466)
			(xy 392.08116 -306.230043) (xy 392.096744 -306.276724) (xy 392.104639 -306.325301) (xy 392.105134 -306.349908)
			(xy 392.443982 -306.349908) (xy 392.447942 -306.300854) (xy 392.459719 -306.25307) (xy 392.47901 -306.207794)
			(xy 392.505313 -306.166198) (xy 392.537948 -306.129361) (xy 392.576069 -306.098236) (xy 392.61869 -306.073629)
			(xy 392.664706 -306.056177) (xy 392.712925 -306.046333) (xy 392.7621 -306.044352) (xy 392.810955 -306.050284)
			(xy 392.858226 -306.063976) (xy 392.902688 -306.085074) (xy 392.943191 -306.11303) (xy 392.978684 -306.147122)
			(xy 393.008249 -306.186466) (xy 393.03112 -306.230043) (xy 393.046704 -306.276724) (xy 393.054599 -306.325301)
			(xy 393.055094 -306.349908) (xy 393.054599 -306.374515) (xy 393.046704 -306.423092) (xy 393.03112 -306.469773)
			(xy 393.008249 -306.51335) (xy 392.978684 -306.552694) (xy 392.943191 -306.586786) (xy 392.902688 -306.614742)
			(xy 392.858226 -306.63584) (xy 392.810955 -306.649532) (xy 392.7621 -306.655464) (xy 392.712925 -306.653483)
			(xy 392.664706 -306.643639) (xy 392.61869 -306.626187) (xy 392.576069 -306.60158) (xy 392.537948 -306.570455)
			(xy 392.505313 -306.533618) (xy 392.47901 -306.492022) (xy 392.459719 -306.446746) (xy 392.447942 -306.398962)
			(xy 392.443982 -306.349908) (xy 392.105134 -306.349908) (xy 392.104639 -306.374515) (xy 392.096744 -306.423092)
			(xy 392.08116 -306.469773) (xy 392.058289 -306.51335) (xy 392.028724 -306.552694) (xy 391.993231 -306.586786)
			(xy 391.952728 -306.614742) (xy 391.908266 -306.63584) (xy 391.860995 -306.649532) (xy 391.81214 -306.655464)
			(xy 391.762965 -306.653483) (xy 391.714746 -306.643639) (xy 391.66873 -306.626187) (xy 391.626109 -306.60158)
			(xy 391.587988 -306.570455) (xy 391.555353 -306.533618) (xy 391.52905 -306.492022) (xy 391.509759 -306.446746)
			(xy 391.497982 -306.398962) (xy 391.494022 -306.349908) (xy 314.955174 -306.349908) (xy 314.954679 -306.374515)
			(xy 314.946784 -306.423092) (xy 314.9312 -306.469773) (xy 314.908329 -306.51335) (xy 314.878764 -306.552694)
			(xy 314.843271 -306.586786) (xy 314.802768 -306.614742) (xy 314.758306 -306.63584) (xy 314.711035 -306.649532)
			(xy 314.66218 -306.655464) (xy 314.613005 -306.653483) (xy 314.564786 -306.643639) (xy 314.51877 -306.626187)
			(xy 314.476149 -306.60158) (xy 314.438028 -306.570455) (xy 314.405393 -306.533618) (xy 314.37909 -306.492022)
			(xy 314.359799 -306.446746) (xy 314.348022 -306.398962) (xy 314.344062 -306.349908) (xy 314.005214 -306.349908)
			(xy 314.004719 -306.374515) (xy 313.996824 -306.423092) (xy 313.98124 -306.469773) (xy 313.958369 -306.51335)
			(xy 313.928804 -306.552694) (xy 313.893311 -306.586786) (xy 313.852808 -306.614742) (xy 313.808346 -306.63584)
			(xy 313.761075 -306.649532) (xy 313.71222 -306.655464) (xy 313.663045 -306.653483) (xy 313.614826 -306.643639)
			(xy 313.56881 -306.626187) (xy 313.526189 -306.60158) (xy 313.488068 -306.570455) (xy 313.455433 -306.533618)
			(xy 313.42913 -306.492022) (xy 313.409839 -306.446746) (xy 313.398062 -306.398962) (xy 313.394102 -306.349908)
			(xy 308.3052 -306.349908) (xy 308.304705 -306.374515) (xy 308.29681 -306.423092) (xy 308.281226 -306.469773)
			(xy 308.258355 -306.51335) (xy 308.22879 -306.552694) (xy 308.193297 -306.586786) (xy 308.152794 -306.614742)
			(xy 308.108332 -306.63584) (xy 308.061061 -306.649532) (xy 308.012206 -306.655464) (xy 307.963031 -306.653483)
			(xy 307.914812 -306.643639) (xy 307.868796 -306.626187) (xy 307.826175 -306.60158) (xy 307.788054 -306.570455)
			(xy 307.755419 -306.533618) (xy 307.729116 -306.492022) (xy 307.709825 -306.446746) (xy 307.698048 -306.398962)
			(xy 307.694088 -306.349908) (xy 307.35524 -306.349908) (xy 307.354745 -306.374515) (xy 307.34685 -306.423092)
			(xy 307.331266 -306.469773) (xy 307.308395 -306.51335) (xy 307.27883 -306.552694) (xy 307.243337 -306.586786)
			(xy 307.202834 -306.614742) (xy 307.158372 -306.63584) (xy 307.111101 -306.649532) (xy 307.062246 -306.655464)
			(xy 307.013071 -306.653483) (xy 306.964852 -306.643639) (xy 306.918836 -306.626187) (xy 306.876215 -306.60158)
			(xy 306.838094 -306.570455) (xy 306.805459 -306.533618) (xy 306.779156 -306.492022) (xy 306.759865 -306.446746)
			(xy 306.748088 -306.398962) (xy 306.744128 -306.349908) (xy 160.855152 -306.349908) (xy 160.854657 -306.374515)
			(xy 160.846762 -306.423092) (xy 160.831178 -306.469773) (xy 160.808307 -306.51335) (xy 160.778742 -306.552694)
			(xy 160.743249 -306.586786) (xy 160.702746 -306.614742) (xy 160.658284 -306.63584) (xy 160.611013 -306.649532)
			(xy 160.562158 -306.655464) (xy 160.512983 -306.653483) (xy 160.464764 -306.643639) (xy 160.418748 -306.626187)
			(xy 160.376127 -306.60158) (xy 160.338006 -306.570455) (xy 160.305371 -306.533618) (xy 160.279068 -306.492022)
			(xy 160.259777 -306.446746) (xy 160.248 -306.398962) (xy 160.24404 -306.349908) (xy 159.905192 -306.349908)
			(xy 159.904697 -306.374515) (xy 159.896802 -306.423092) (xy 159.881218 -306.469773) (xy 159.858347 -306.51335)
			(xy 159.828782 -306.552694) (xy 159.793289 -306.586786) (xy 159.752786 -306.614742) (xy 159.708324 -306.63584)
			(xy 159.661053 -306.649532) (xy 159.612198 -306.655464) (xy 159.563023 -306.653483) (xy 159.514804 -306.643639)
			(xy 159.468788 -306.626187) (xy 159.426167 -306.60158) (xy 159.388046 -306.570455) (xy 159.355411 -306.533618)
			(xy 159.329108 -306.492022) (xy 159.309817 -306.446746) (xy 159.29804 -306.398962) (xy 159.29408 -306.349908)
			(xy 82.755232 -306.349908) (xy 82.754737 -306.374515) (xy 82.746842 -306.423092) (xy 82.731258 -306.469773)
			(xy 82.708387 -306.51335) (xy 82.678822 -306.552694) (xy 82.643329 -306.586786) (xy 82.602826 -306.614742)
			(xy 82.558364 -306.63584) (xy 82.511093 -306.649532) (xy 82.462238 -306.655464) (xy 82.413063 -306.653483)
			(xy 82.364844 -306.643639) (xy 82.318828 -306.626187) (xy 82.276207 -306.60158) (xy 82.238086 -306.570455)
			(xy 82.205451 -306.533618) (xy 82.179148 -306.492022) (xy 82.159857 -306.446746) (xy 82.14808 -306.398962)
			(xy 82.14412 -306.349908) (xy 81.805272 -306.349908) (xy 81.804777 -306.374515) (xy 81.796882 -306.423092)
			(xy 81.781298 -306.469773) (xy 81.758427 -306.51335) (xy 81.728862 -306.552694) (xy 81.693369 -306.586786)
			(xy 81.652866 -306.614742) (xy 81.608404 -306.63584) (xy 81.561133 -306.649532) (xy 81.512278 -306.655464)
			(xy 81.463103 -306.653483) (xy 81.414884 -306.643639) (xy 81.368868 -306.626187) (xy 81.326247 -306.60158)
			(xy 81.288126 -306.570455) (xy 81.255491 -306.533618) (xy 81.229188 -306.492022) (xy 81.209897 -306.446746)
			(xy 81.19812 -306.398962) (xy 81.19416 -306.349908) (xy 76.105258 -306.349908) (xy 76.104763 -306.374515)
			(xy 76.096868 -306.423092) (xy 76.081284 -306.469773) (xy 76.058413 -306.51335) (xy 76.028848 -306.552694)
			(xy 75.993355 -306.586786) (xy 75.952852 -306.614742) (xy 75.90839 -306.63584) (xy 75.861119 -306.649532)
			(xy 75.812264 -306.655464) (xy 75.763089 -306.653483) (xy 75.71487 -306.643639) (xy 75.668854 -306.626187)
			(xy 75.626233 -306.60158) (xy 75.588112 -306.570455) (xy 75.555477 -306.533618) (xy 75.529174 -306.492022)
			(xy 75.509883 -306.446746) (xy 75.498106 -306.398962) (xy 75.494146 -306.349908) (xy 75.155298 -306.349908)
			(xy 75.154803 -306.374515) (xy 75.146908 -306.423092) (xy 75.131324 -306.469773) (xy 75.108453 -306.51335)
			(xy 75.078888 -306.552694) (xy 75.043395 -306.586786) (xy 75.002892 -306.614742) (xy 74.95843 -306.63584)
			(xy 74.911159 -306.649532) (xy 74.862304 -306.655464) (xy 74.813129 -306.653483) (xy 74.76491 -306.643639)
			(xy 74.718894 -306.626187) (xy 74.676273 -306.60158) (xy 74.638152 -306.570455) (xy 74.605517 -306.533618)
			(xy 74.579214 -306.492022) (xy 74.559923 -306.446746) (xy 74.548146 -306.398962) (xy 74.544186 -306.349908)
			(xy 18.395917 -306.349908) (xy 18.393665 -306.365208) (xy 18.377587 -306.41865) (xy 18.353899 -306.469181)
			(xy 18.323105 -306.515725) (xy 18.285863 -306.557289) (xy 18.242967 -306.592988) (xy 18.195329 -306.622061)
			(xy 18.143966 -306.643888) (xy 18.089973 -306.658004) (xy 18.034499 -306.664107) (xy 17.978728 -306.662069)
			(xy 17.923849 -306.651932) (xy 17.871029 -306.633913) (xy 17.821397 -306.608395) (xy 17.776009 -306.575923)
			(xy 17.735832 -306.537188) (xy 17.701724 -306.493016) (xy 17.67441 -306.444348) (xy 17.654474 -306.392222)
			(xy 17.642339 -306.337749) (xy 17.638266 -306.28209) (xy 0.508 -306.28209) (xy 0.508 -307.299868)
			(xy 76.444106 -307.299868) (xy 76.448066 -307.250814) (xy 76.459843 -307.20303) (xy 76.479134 -307.157754)
			(xy 76.505437 -307.116158) (xy 76.538072 -307.079321) (xy 76.576193 -307.048196) (xy 76.618814 -307.023589)
			(xy 76.66483 -307.006137) (xy 76.713049 -306.996293) (xy 76.762224 -306.994312) (xy 76.811079 -307.000244)
			(xy 76.85835 -307.013936) (xy 76.902812 -307.035034) (xy 76.943315 -307.06299) (xy 76.978808 -307.097082)
			(xy 77.008373 -307.136426) (xy 77.031244 -307.180003) (xy 77.046828 -307.226684) (xy 77.054723 -307.275261)
			(xy 77.055218 -307.299868) (xy 77.394066 -307.299868) (xy 77.398026 -307.250814) (xy 77.409803 -307.20303)
			(xy 77.429094 -307.157754) (xy 77.455397 -307.116158) (xy 77.488032 -307.079321) (xy 77.526153 -307.048196)
			(xy 77.568774 -307.023589) (xy 77.61479 -307.006137) (xy 77.663009 -306.996293) (xy 77.712184 -306.994312)
			(xy 77.761039 -307.000244) (xy 77.80831 -307.013936) (xy 77.852772 -307.035034) (xy 77.893275 -307.06299)
			(xy 77.928768 -307.097082) (xy 77.958333 -307.136426) (xy 77.981204 -307.180003) (xy 77.996788 -307.226684)
			(xy 78.004683 -307.275261) (xy 78.005178 -307.299868) (xy 79.293986 -307.299868) (xy 79.297946 -307.250814)
			(xy 79.309723 -307.20303) (xy 79.329014 -307.157754) (xy 79.355317 -307.116158) (xy 79.387952 -307.079321)
			(xy 79.426073 -307.048196) (xy 79.468694 -307.023589) (xy 79.51471 -307.006137) (xy 79.562929 -306.996293)
			(xy 79.612104 -306.994312) (xy 79.660959 -307.000244) (xy 79.70823 -307.013936) (xy 79.752692 -307.035034)
			(xy 79.793195 -307.06299) (xy 79.828688 -307.097082) (xy 79.858253 -307.136426) (xy 79.881124 -307.180003)
			(xy 79.896708 -307.226684) (xy 79.904603 -307.275261) (xy 79.905098 -307.299868) (xy 80.243946 -307.299868)
			(xy 80.247906 -307.250814) (xy 80.259683 -307.20303) (xy 80.278974 -307.157754) (xy 80.305277 -307.116158)
			(xy 80.337912 -307.079321) (xy 80.376033 -307.048196) (xy 80.418654 -307.023589) (xy 80.46467 -307.006137)
			(xy 80.512889 -306.996293) (xy 80.562064 -306.994312) (xy 80.610919 -307.000244) (xy 80.65819 -307.013936)
			(xy 80.702652 -307.035034) (xy 80.743155 -307.06299) (xy 80.778648 -307.097082) (xy 80.808213 -307.136426)
			(xy 80.831084 -307.180003) (xy 80.846668 -307.226684) (xy 80.854563 -307.275261) (xy 80.855058 -307.299868)
			(xy 157.39416 -307.299868) (xy 157.39812 -307.250814) (xy 157.409897 -307.20303) (xy 157.429188 -307.157754)
			(xy 157.455491 -307.116158) (xy 157.488126 -307.079321) (xy 157.526247 -307.048196) (xy 157.568868 -307.023589)
			(xy 157.614884 -307.006137) (xy 157.663103 -306.996293) (xy 157.712278 -306.994312) (xy 157.761133 -307.000244)
			(xy 157.808404 -307.013936) (xy 157.852866 -307.035034) (xy 157.893369 -307.06299) (xy 157.928862 -307.097082)
			(xy 157.958427 -307.136426) (xy 157.981298 -307.180003) (xy 157.996882 -307.226684) (xy 158.004777 -307.275261)
			(xy 158.005272 -307.299868) (xy 158.34412 -307.299868) (xy 158.34808 -307.250814) (xy 158.359857 -307.20303)
			(xy 158.379148 -307.157754) (xy 158.405451 -307.116158) (xy 158.438086 -307.079321) (xy 158.476207 -307.048196)
			(xy 158.518828 -307.023589) (xy 158.564844 -307.006137) (xy 158.613063 -306.996293) (xy 158.662238 -306.994312)
			(xy 158.711093 -307.000244) (xy 158.758364 -307.013936) (xy 158.802826 -307.035034) (xy 158.843329 -307.06299)
			(xy 158.878822 -307.097082) (xy 158.908387 -307.136426) (xy 158.931258 -307.180003) (xy 158.946842 -307.226684)
			(xy 158.954737 -307.275261) (xy 158.955232 -307.299868) (xy 158.954737 -307.324475) (xy 158.946842 -307.373052)
			(xy 158.931258 -307.419733) (xy 158.908387 -307.46331) (xy 158.892635 -307.484272) (xy 231.935526 -307.484272)
			(xy 231.939599 -307.428613) (xy 231.951734 -307.37414) (xy 231.97167 -307.322014) (xy 231.998984 -307.273346)
			(xy 232.033092 -307.229174) (xy 232.073269 -307.190439) (xy 232.118657 -307.157967) (xy 232.168289 -307.132449)
			(xy 232.221109 -307.11443) (xy 232.275988 -307.104293) (xy 232.331759 -307.102255) (xy 232.387233 -307.108358)
			(xy 232.441226 -307.122474) (xy 232.492589 -307.144301) (xy 232.540227 -307.173374) (xy 232.583123 -307.209073)
			(xy 232.620365 -307.250637) (xy 232.651159 -307.297181) (xy 232.674847 -307.347712) (xy 232.690925 -307.401154)
			(xy 232.699051 -307.456368) (xy 232.69956 -307.484272) (xy 248.185684 -307.484272) (xy 248.189757 -307.428613)
			(xy 248.201892 -307.37414) (xy 248.221828 -307.322014) (xy 248.249142 -307.273346) (xy 248.28325 -307.229174)
			(xy 248.323427 -307.190439) (xy 248.368815 -307.157967) (xy 248.418447 -307.132449) (xy 248.471267 -307.11443)
			(xy 248.526146 -307.104293) (xy 248.581917 -307.102255) (xy 248.637391 -307.108358) (xy 248.691384 -307.122474)
			(xy 248.742747 -307.144301) (xy 248.790385 -307.173374) (xy 248.833281 -307.209073) (xy 248.870523 -307.250637)
			(xy 248.901317 -307.297181) (xy 248.902577 -307.299868) (xy 308.644048 -307.299868) (xy 308.648008 -307.250814)
			(xy 308.659785 -307.20303) (xy 308.679076 -307.157754) (xy 308.705379 -307.116158) (xy 308.738014 -307.079321)
			(xy 308.776135 -307.048196) (xy 308.818756 -307.023589) (xy 308.864772 -307.006137) (xy 308.912991 -306.996293)
			(xy 308.962166 -306.994312) (xy 309.011021 -307.000244) (xy 309.058292 -307.013936) (xy 309.102754 -307.035034)
			(xy 309.143257 -307.06299) (xy 309.17875 -307.097082) (xy 309.208315 -307.136426) (xy 309.231186 -307.180003)
			(xy 309.24677 -307.226684) (xy 309.254665 -307.275261) (xy 309.25516 -307.299868) (xy 309.594008 -307.299868)
			(xy 309.597968 -307.250814) (xy 309.609745 -307.20303) (xy 309.629036 -307.157754) (xy 309.655339 -307.116158)
			(xy 309.687974 -307.079321) (xy 309.726095 -307.048196) (xy 309.768716 -307.023589) (xy 309.814732 -307.006137)
			(xy 309.862951 -306.996293) (xy 309.912126 -306.994312) (xy 309.960981 -307.000244) (xy 310.008252 -307.013936)
			(xy 310.052714 -307.035034) (xy 310.093217 -307.06299) (xy 310.12871 -307.097082) (xy 310.158275 -307.136426)
			(xy 310.181146 -307.180003) (xy 310.19673 -307.226684) (xy 310.204625 -307.275261) (xy 310.20512 -307.299868)
			(xy 311.493928 -307.299868) (xy 311.497888 -307.250814) (xy 311.509665 -307.20303) (xy 311.528956 -307.157754)
			(xy 311.555259 -307.116158) (xy 311.587894 -307.079321) (xy 311.626015 -307.048196) (xy 311.668636 -307.023589)
			(xy 311.714652 -307.006137) (xy 311.762871 -306.996293) (xy 311.812046 -306.994312) (xy 311.860901 -307.000244)
			(xy 311.908172 -307.013936) (xy 311.952634 -307.035034) (xy 311.993137 -307.06299) (xy 312.02863 -307.097082)
			(xy 312.058195 -307.136426) (xy 312.081066 -307.180003) (xy 312.09665 -307.226684) (xy 312.104545 -307.275261)
			(xy 312.10504 -307.299868) (xy 312.443888 -307.299868) (xy 312.447848 -307.250814) (xy 312.459625 -307.20303)
			(xy 312.478916 -307.157754) (xy 312.505219 -307.116158) (xy 312.537854 -307.079321) (xy 312.575975 -307.048196)
			(xy 312.618596 -307.023589) (xy 312.664612 -307.006137) (xy 312.712831 -306.996293) (xy 312.762006 -306.994312)
			(xy 312.810861 -307.000244) (xy 312.858132 -307.013936) (xy 312.902594 -307.035034) (xy 312.943097 -307.06299)
			(xy 312.97859 -307.097082) (xy 313.008155 -307.136426) (xy 313.031026 -307.180003) (xy 313.04661 -307.226684)
			(xy 313.054505 -307.275261) (xy 313.055 -307.299868) (xy 389.594102 -307.299868) (xy 389.598062 -307.250814)
			(xy 389.609839 -307.20303) (xy 389.62913 -307.157754) (xy 389.655433 -307.116158) (xy 389.688068 -307.079321)
			(xy 389.726189 -307.048196) (xy 389.76881 -307.023589) (xy 389.814826 -307.006137) (xy 389.863045 -306.996293)
			(xy 389.91222 -306.994312) (xy 389.961075 -307.000244) (xy 390.008346 -307.013936) (xy 390.052808 -307.035034)
			(xy 390.093311 -307.06299) (xy 390.128804 -307.097082) (xy 390.158369 -307.136426) (xy 390.18124 -307.180003)
			(xy 390.196824 -307.226684) (xy 390.204719 -307.275261) (xy 390.205214 -307.299868) (xy 390.544062 -307.299868)
			(xy 390.548022 -307.250814) (xy 390.559799 -307.20303) (xy 390.57909 -307.157754) (xy 390.605393 -307.116158)
			(xy 390.638028 -307.079321) (xy 390.676149 -307.048196) (xy 390.71877 -307.023589) (xy 390.764786 -307.006137)
			(xy 390.813005 -306.996293) (xy 390.86218 -306.994312) (xy 390.911035 -307.000244) (xy 390.958306 -307.013936)
			(xy 391.002768 -307.035034) (xy 391.043271 -307.06299) (xy 391.078764 -307.097082) (xy 391.108329 -307.136426)
			(xy 391.1312 -307.180003) (xy 391.146784 -307.226684) (xy 391.154679 -307.275261) (xy 391.155174 -307.299868)
			(xy 391.154679 -307.324475) (xy 391.146784 -307.373052) (xy 391.1312 -307.419733) (xy 391.108329 -307.46331)
			(xy 391.078764 -307.502654) (xy 391.043271 -307.536746) (xy 391.002768 -307.564702) (xy 390.958306 -307.5858)
			(xy 390.911035 -307.599492) (xy 390.86218 -307.605424) (xy 390.813005 -307.603443) (xy 390.764786 -307.593599)
			(xy 390.71877 -307.576147) (xy 390.676149 -307.55154) (xy 390.638028 -307.520415) (xy 390.605393 -307.483578)
			(xy 390.57909 -307.441982) (xy 390.559799 -307.396706) (xy 390.548022 -307.348922) (xy 390.544062 -307.299868)
			(xy 390.205214 -307.299868) (xy 390.204719 -307.324475) (xy 390.196824 -307.373052) (xy 390.18124 -307.419733)
			(xy 390.158369 -307.46331) (xy 390.128804 -307.502654) (xy 390.093311 -307.536746) (xy 390.052808 -307.564702)
			(xy 390.008346 -307.5858) (xy 389.961075 -307.599492) (xy 389.91222 -307.605424) (xy 389.863045 -307.603443)
			(xy 389.814826 -307.593599) (xy 389.76881 -307.576147) (xy 389.726189 -307.55154) (xy 389.688068 -307.520415)
			(xy 389.655433 -307.483578) (xy 389.62913 -307.441982) (xy 389.609839 -307.396706) (xy 389.598062 -307.348922)
			(xy 389.594102 -307.299868) (xy 313.055 -307.299868) (xy 313.054505 -307.324475) (xy 313.04661 -307.373052)
			(xy 313.031026 -307.419733) (xy 313.008155 -307.46331) (xy 312.97859 -307.502654) (xy 312.943097 -307.536746)
			(xy 312.902594 -307.564702) (xy 312.858132 -307.5858) (xy 312.810861 -307.599492) (xy 312.762006 -307.605424)
			(xy 312.712831 -307.603443) (xy 312.664612 -307.593599) (xy 312.618596 -307.576147) (xy 312.575975 -307.55154)
			(xy 312.537854 -307.520415) (xy 312.505219 -307.483578) (xy 312.478916 -307.441982) (xy 312.459625 -307.396706)
			(xy 312.447848 -307.348922) (xy 312.443888 -307.299868) (xy 312.10504 -307.299868) (xy 312.104545 -307.324475)
			(xy 312.09665 -307.373052) (xy 312.081066 -307.419733) (xy 312.058195 -307.46331) (xy 312.02863 -307.502654)
			(xy 311.993137 -307.536746) (xy 311.952634 -307.564702) (xy 311.908172 -307.5858) (xy 311.860901 -307.599492)
			(xy 311.812046 -307.605424) (xy 311.762871 -307.603443) (xy 311.714652 -307.593599) (xy 311.668636 -307.576147)
			(xy 311.626015 -307.55154) (xy 311.587894 -307.520415) (xy 311.555259 -307.483578) (xy 311.528956 -307.441982)
			(xy 311.509665 -307.396706) (xy 311.497888 -307.348922) (xy 311.493928 -307.299868) (xy 310.20512 -307.299868)
			(xy 310.204625 -307.324475) (xy 310.19673 -307.373052) (xy 310.181146 -307.419733) (xy 310.158275 -307.46331)
			(xy 310.12871 -307.502654) (xy 310.093217 -307.536746) (xy 310.052714 -307.564702) (xy 310.008252 -307.5858)
			(xy 309.960981 -307.599492) (xy 309.912126 -307.605424) (xy 309.862951 -307.603443) (xy 309.814732 -307.593599)
			(xy 309.768716 -307.576147) (xy 309.726095 -307.55154) (xy 309.687974 -307.520415) (xy 309.655339 -307.483578)
			(xy 309.629036 -307.441982) (xy 309.609745 -307.396706) (xy 309.597968 -307.348922) (xy 309.594008 -307.299868)
			(xy 309.25516 -307.299868) (xy 309.254665 -307.324475) (xy 309.24677 -307.373052) (xy 309.231186 -307.419733)
			(xy 309.208315 -307.46331) (xy 309.17875 -307.502654) (xy 309.143257 -307.536746) (xy 309.102754 -307.564702)
			(xy 309.058292 -307.5858) (xy 309.011021 -307.599492) (xy 308.962166 -307.605424) (xy 308.912991 -307.603443)
			(xy 308.864772 -307.593599) (xy 308.818756 -307.576147) (xy 308.776135 -307.55154) (xy 308.738014 -307.520415)
			(xy 308.705379 -307.483578) (xy 308.679076 -307.441982) (xy 308.659785 -307.396706) (xy 308.648008 -307.348922)
			(xy 308.644048 -307.299868) (xy 248.902577 -307.299868) (xy 248.925005 -307.347712) (xy 248.941083 -307.401154)
			(xy 248.949209 -307.456368) (xy 248.949718 -307.484272) (xy 248.949209 -307.512176) (xy 248.941083 -307.56739)
			(xy 248.928951 -307.607716) (xy 462.556604 -307.607716) (xy 462.560677 -307.552057) (xy 462.572812 -307.497584)
			(xy 462.592748 -307.445458) (xy 462.620062 -307.39679) (xy 462.65417 -307.352618) (xy 462.694347 -307.313883)
			(xy 462.739735 -307.281411) (xy 462.789367 -307.255893) (xy 462.842187 -307.237874) (xy 462.897066 -307.227737)
			(xy 462.952837 -307.225699) (xy 463.008311 -307.231802) (xy 463.062304 -307.245918) (xy 463.113667 -307.267745)
			(xy 463.161305 -307.296818) (xy 463.204201 -307.332517) (xy 463.241443 -307.374081) (xy 463.272237 -307.420625)
			(xy 463.295925 -307.471156) (xy 463.312003 -307.524598) (xy 463.320129 -307.579812) (xy 463.320638 -307.607716)
			(xy 463.320129 -307.63562) (xy 463.312003 -307.690834) (xy 463.295925 -307.744276) (xy 463.272237 -307.794807)
			(xy 463.241443 -307.841351) (xy 463.204201 -307.882915) (xy 463.161305 -307.918614) (xy 463.113667 -307.947687)
			(xy 463.062304 -307.969514) (xy 463.008311 -307.98363) (xy 462.952837 -307.989733) (xy 462.897066 -307.987695)
			(xy 462.842187 -307.977558) (xy 462.789367 -307.959539) (xy 462.739735 -307.934021) (xy 462.694347 -307.901549)
			(xy 462.65417 -307.862814) (xy 462.620062 -307.818642) (xy 462.592748 -307.769974) (xy 462.572812 -307.717848)
			(xy 462.560677 -307.663375) (xy 462.556604 -307.607716) (xy 248.928951 -307.607716) (xy 248.925005 -307.620832)
			(xy 248.901317 -307.671363) (xy 248.870523 -307.717907) (xy 248.833281 -307.759471) (xy 248.790385 -307.79517)
			(xy 248.742747 -307.824243) (xy 248.691384 -307.84607) (xy 248.637391 -307.860186) (xy 248.581917 -307.866289)
			(xy 248.526146 -307.864251) (xy 248.471267 -307.854114) (xy 248.418447 -307.836095) (xy 248.368815 -307.810577)
			(xy 248.323427 -307.778105) (xy 248.28325 -307.73937) (xy 248.249142 -307.695198) (xy 248.221828 -307.64653)
			(xy 248.201892 -307.594404) (xy 248.189757 -307.539931) (xy 248.185684 -307.484272) (xy 232.69956 -307.484272)
			(xy 232.699051 -307.512176) (xy 232.690925 -307.56739) (xy 232.674847 -307.620832) (xy 232.651159 -307.671363)
			(xy 232.620365 -307.717907) (xy 232.583123 -307.759471) (xy 232.540227 -307.79517) (xy 232.492589 -307.824243)
			(xy 232.441226 -307.84607) (xy 232.387233 -307.860186) (xy 232.331759 -307.866289) (xy 232.275988 -307.864251)
			(xy 232.221109 -307.854114) (xy 232.168289 -307.836095) (xy 232.118657 -307.810577) (xy 232.073269 -307.778105)
			(xy 232.033092 -307.73937) (xy 231.998984 -307.695198) (xy 231.97167 -307.64653) (xy 231.951734 -307.594404)
			(xy 231.939599 -307.539931) (xy 231.935526 -307.484272) (xy 158.892635 -307.484272) (xy 158.878822 -307.502654)
			(xy 158.843329 -307.536746) (xy 158.802826 -307.564702) (xy 158.758364 -307.5858) (xy 158.711093 -307.599492)
			(xy 158.662238 -307.605424) (xy 158.613063 -307.603443) (xy 158.564844 -307.593599) (xy 158.518828 -307.576147)
			(xy 158.476207 -307.55154) (xy 158.438086 -307.520415) (xy 158.405451 -307.483578) (xy 158.379148 -307.441982)
			(xy 158.359857 -307.396706) (xy 158.34808 -307.348922) (xy 158.34412 -307.299868) (xy 158.005272 -307.299868)
			(xy 158.004777 -307.324475) (xy 157.996882 -307.373052) (xy 157.981298 -307.419733) (xy 157.958427 -307.46331)
			(xy 157.928862 -307.502654) (xy 157.893369 -307.536746) (xy 157.852866 -307.564702) (xy 157.808404 -307.5858)
			(xy 157.761133 -307.599492) (xy 157.712278 -307.605424) (xy 157.663103 -307.603443) (xy 157.614884 -307.593599)
			(xy 157.568868 -307.576147) (xy 157.526247 -307.55154) (xy 157.488126 -307.520415) (xy 157.455491 -307.483578)
			(xy 157.429188 -307.441982) (xy 157.409897 -307.396706) (xy 157.39812 -307.348922) (xy 157.39416 -307.299868)
			(xy 80.855058 -307.299868) (xy 80.854563 -307.324475) (xy 80.846668 -307.373052) (xy 80.831084 -307.419733)
			(xy 80.808213 -307.46331) (xy 80.778648 -307.502654) (xy 80.743155 -307.536746) (xy 80.702652 -307.564702)
			(xy 80.65819 -307.5858) (xy 80.610919 -307.599492) (xy 80.562064 -307.605424) (xy 80.512889 -307.603443)
			(xy 80.46467 -307.593599) (xy 80.418654 -307.576147) (xy 80.376033 -307.55154) (xy 80.337912 -307.520415)
			(xy 80.305277 -307.483578) (xy 80.278974 -307.441982) (xy 80.259683 -307.396706) (xy 80.247906 -307.348922)
			(xy 80.243946 -307.299868) (xy 79.905098 -307.299868) (xy 79.904603 -307.324475) (xy 79.896708 -307.373052)
			(xy 79.881124 -307.419733) (xy 79.858253 -307.46331) (xy 79.828688 -307.502654) (xy 79.793195 -307.536746)
			(xy 79.752692 -307.564702) (xy 79.70823 -307.5858) (xy 79.660959 -307.599492) (xy 79.612104 -307.605424)
			(xy 79.562929 -307.603443) (xy 79.51471 -307.593599) (xy 79.468694 -307.576147) (xy 79.426073 -307.55154)
			(xy 79.387952 -307.520415) (xy 79.355317 -307.483578) (xy 79.329014 -307.441982) (xy 79.309723 -307.396706)
			(xy 79.297946 -307.348922) (xy 79.293986 -307.299868) (xy 78.005178 -307.299868) (xy 78.004683 -307.324475)
			(xy 77.996788 -307.373052) (xy 77.981204 -307.419733) (xy 77.958333 -307.46331) (xy 77.928768 -307.502654)
			(xy 77.893275 -307.536746) (xy 77.852772 -307.564702) (xy 77.80831 -307.5858) (xy 77.761039 -307.599492)
			(xy 77.712184 -307.605424) (xy 77.663009 -307.603443) (xy 77.61479 -307.593599) (xy 77.568774 -307.576147)
			(xy 77.526153 -307.55154) (xy 77.488032 -307.520415) (xy 77.455397 -307.483578) (xy 77.429094 -307.441982)
			(xy 77.409803 -307.396706) (xy 77.398026 -307.348922) (xy 77.394066 -307.299868) (xy 77.055218 -307.299868)
			(xy 77.054723 -307.324475) (xy 77.046828 -307.373052) (xy 77.031244 -307.419733) (xy 77.008373 -307.46331)
			(xy 76.978808 -307.502654) (xy 76.943315 -307.536746) (xy 76.902812 -307.564702) (xy 76.85835 -307.5858)
			(xy 76.811079 -307.599492) (xy 76.762224 -307.605424) (xy 76.713049 -307.603443) (xy 76.66483 -307.593599)
			(xy 76.618814 -307.576147) (xy 76.576193 -307.55154) (xy 76.538072 -307.520415) (xy 76.505437 -307.483578)
			(xy 76.479134 -307.441982) (xy 76.459843 -307.396706) (xy 76.448066 -307.348922) (xy 76.444106 -307.299868)
			(xy 0.508 -307.299868) (xy 0.508 -308.249828) (xy 74.544186 -308.249828) (xy 74.548146 -308.200774)
			(xy 74.559923 -308.15299) (xy 74.579214 -308.107714) (xy 74.605517 -308.066118) (xy 74.638152 -308.029281)
			(xy 74.676273 -307.998156) (xy 74.718894 -307.973549) (xy 74.76491 -307.956097) (xy 74.813129 -307.946253)
			(xy 74.862304 -307.944272) (xy 74.911159 -307.950204) (xy 74.95843 -307.963896) (xy 75.002892 -307.984994)
			(xy 75.043395 -308.01295) (xy 75.078888 -308.047042) (xy 75.108453 -308.086386) (xy 75.131324 -308.129963)
			(xy 75.146908 -308.176644) (xy 75.154803 -308.225221) (xy 75.155298 -308.249828) (xy 75.494146 -308.249828)
			(xy 75.498106 -308.200774) (xy 75.509883 -308.15299) (xy 75.529174 -308.107714) (xy 75.555477 -308.066118)
			(xy 75.588112 -308.029281) (xy 75.626233 -307.998156) (xy 75.668854 -307.973549) (xy 75.71487 -307.956097)
			(xy 75.763089 -307.946253) (xy 75.812264 -307.944272) (xy 75.861119 -307.950204) (xy 75.90839 -307.963896)
			(xy 75.952852 -307.984994) (xy 75.993355 -308.01295) (xy 76.028848 -308.047042) (xy 76.058413 -308.086386)
			(xy 76.081284 -308.129963) (xy 76.096868 -308.176644) (xy 76.104763 -308.225221) (xy 76.105258 -308.249828)
			(xy 81.19416 -308.249828) (xy 81.19812 -308.200774) (xy 81.209897 -308.15299) (xy 81.229188 -308.107714)
			(xy 81.255491 -308.066118) (xy 81.288126 -308.029281) (xy 81.326247 -307.998156) (xy 81.368868 -307.973549)
			(xy 81.414884 -307.956097) (xy 81.463103 -307.946253) (xy 81.512278 -307.944272) (xy 81.561133 -307.950204)
			(xy 81.608404 -307.963896) (xy 81.652866 -307.984994) (xy 81.693369 -308.01295) (xy 81.728862 -308.047042)
			(xy 81.758427 -308.086386) (xy 81.781298 -308.129963) (xy 81.796882 -308.176644) (xy 81.804777 -308.225221)
			(xy 81.805272 -308.249828) (xy 82.14412 -308.249828) (xy 82.14808 -308.200774) (xy 82.159857 -308.15299)
			(xy 82.179148 -308.107714) (xy 82.205451 -308.066118) (xy 82.238086 -308.029281) (xy 82.276207 -307.998156)
			(xy 82.318828 -307.973549) (xy 82.364844 -307.956097) (xy 82.413063 -307.946253) (xy 82.462238 -307.944272)
			(xy 82.511093 -307.950204) (xy 82.558364 -307.963896) (xy 82.602826 -307.984994) (xy 82.643329 -308.01295)
			(xy 82.678822 -308.047042) (xy 82.708387 -308.086386) (xy 82.731258 -308.129963) (xy 82.746842 -308.176644)
			(xy 82.754737 -308.225221) (xy 82.755232 -308.249828) (xy 159.29408 -308.249828) (xy 159.29804 -308.200774)
			(xy 159.309817 -308.15299) (xy 159.329108 -308.107714) (xy 159.355411 -308.066118) (xy 159.388046 -308.029281)
			(xy 159.426167 -307.998156) (xy 159.468788 -307.973549) (xy 159.514804 -307.956097) (xy 159.563023 -307.946253)
			(xy 159.612198 -307.944272) (xy 159.661053 -307.950204) (xy 159.708324 -307.963896) (xy 159.752786 -307.984994)
			(xy 159.793289 -308.01295) (xy 159.828782 -308.047042) (xy 159.858347 -308.086386) (xy 159.881218 -308.129963)
			(xy 159.896802 -308.176644) (xy 159.904697 -308.225221) (xy 159.905192 -308.249828) (xy 160.24404 -308.249828)
			(xy 160.248 -308.200774) (xy 160.259777 -308.15299) (xy 160.279068 -308.107714) (xy 160.305371 -308.066118)
			(xy 160.338006 -308.029281) (xy 160.376127 -307.998156) (xy 160.418748 -307.973549) (xy 160.464764 -307.956097)
			(xy 160.512983 -307.946253) (xy 160.562158 -307.944272) (xy 160.611013 -307.950204) (xy 160.658284 -307.963896)
			(xy 160.702746 -307.984994) (xy 160.743249 -308.01295) (xy 160.778742 -308.047042) (xy 160.808307 -308.086386)
			(xy 160.831178 -308.129963) (xy 160.846762 -308.176644) (xy 160.854657 -308.225221) (xy 160.855152 -308.249828)
			(xy 160.854657 -308.274435) (xy 160.846762 -308.323012) (xy 160.831178 -308.369693) (xy 160.808307 -308.41327)
			(xy 160.778742 -308.452614) (xy 160.743249 -308.486706) (xy 160.702746 -308.514662) (xy 160.658284 -308.53576)
			(xy 160.611013 -308.549452) (xy 160.562158 -308.555384) (xy 160.512983 -308.553403) (xy 160.464764 -308.543559)
			(xy 160.418748 -308.526107) (xy 160.376127 -308.5015) (xy 160.338006 -308.470375) (xy 160.305371 -308.433538)
			(xy 160.279068 -308.391942) (xy 160.259777 -308.346666) (xy 160.248 -308.298882) (xy 160.24404 -308.249828)
			(xy 159.905192 -308.249828) (xy 159.904697 -308.274435) (xy 159.896802 -308.323012) (xy 159.881218 -308.369693)
			(xy 159.858347 -308.41327) (xy 159.828782 -308.452614) (xy 159.793289 -308.486706) (xy 159.752786 -308.514662)
			(xy 159.708324 -308.53576) (xy 159.661053 -308.549452) (xy 159.612198 -308.555384) (xy 159.563023 -308.553403)
			(xy 159.514804 -308.543559) (xy 159.468788 -308.526107) (xy 159.426167 -308.5015) (xy 159.388046 -308.470375)
			(xy 159.355411 -308.433538) (xy 159.329108 -308.391942) (xy 159.309817 -308.346666) (xy 159.29804 -308.298882)
			(xy 159.29408 -308.249828) (xy 82.755232 -308.249828) (xy 82.754737 -308.274435) (xy 82.746842 -308.323012)
			(xy 82.731258 -308.369693) (xy 82.708387 -308.41327) (xy 82.678822 -308.452614) (xy 82.643329 -308.486706)
			(xy 82.602826 -308.514662) (xy 82.558364 -308.53576) (xy 82.511093 -308.549452) (xy 82.462238 -308.555384)
			(xy 82.413063 -308.553403) (xy 82.364844 -308.543559) (xy 82.318828 -308.526107) (xy 82.276207 -308.5015)
			(xy 82.238086 -308.470375) (xy 82.205451 -308.433538) (xy 82.179148 -308.391942) (xy 82.159857 -308.346666)
			(xy 82.14808 -308.298882) (xy 82.14412 -308.249828) (xy 81.805272 -308.249828) (xy 81.804777 -308.274435)
			(xy 81.796882 -308.323012) (xy 81.781298 -308.369693) (xy 81.758427 -308.41327) (xy 81.728862 -308.452614)
			(xy 81.693369 -308.486706) (xy 81.652866 -308.514662) (xy 81.608404 -308.53576) (xy 81.561133 -308.549452)
			(xy 81.512278 -308.555384) (xy 81.463103 -308.553403) (xy 81.414884 -308.543559) (xy 81.368868 -308.526107)
			(xy 81.326247 -308.5015) (xy 81.288126 -308.470375) (xy 81.255491 -308.433538) (xy 81.229188 -308.391942)
			(xy 81.209897 -308.346666) (xy 81.19812 -308.298882) (xy 81.19416 -308.249828) (xy 76.105258 -308.249828)
			(xy 76.104763 -308.274435) (xy 76.096868 -308.323012) (xy 76.081284 -308.369693) (xy 76.058413 -308.41327)
			(xy 76.028848 -308.452614) (xy 75.993355 -308.486706) (xy 75.952852 -308.514662) (xy 75.90839 -308.53576)
			(xy 75.861119 -308.549452) (xy 75.812264 -308.555384) (xy 75.763089 -308.553403) (xy 75.71487 -308.543559)
			(xy 75.668854 -308.526107) (xy 75.626233 -308.5015) (xy 75.588112 -308.470375) (xy 75.555477 -308.433538)
			(xy 75.529174 -308.391942) (xy 75.509883 -308.346666) (xy 75.498106 -308.298882) (xy 75.494146 -308.249828)
			(xy 75.155298 -308.249828) (xy 75.154803 -308.274435) (xy 75.146908 -308.323012) (xy 75.131324 -308.369693)
			(xy 75.108453 -308.41327) (xy 75.078888 -308.452614) (xy 75.043395 -308.486706) (xy 75.002892 -308.514662)
			(xy 74.95843 -308.53576) (xy 74.911159 -308.549452) (xy 74.862304 -308.555384) (xy 74.813129 -308.553403)
			(xy 74.76491 -308.543559) (xy 74.718894 -308.526107) (xy 74.676273 -308.5015) (xy 74.638152 -308.470375)
			(xy 74.605517 -308.433538) (xy 74.579214 -308.391942) (xy 74.559923 -308.346666) (xy 74.548146 -308.298882)
			(xy 74.544186 -308.249828) (xy 0.508 -308.249828) (xy 0.508 -308.568852) (xy 231.935526 -308.568852)
			(xy 231.939599 -308.513193) (xy 231.951734 -308.45872) (xy 231.97167 -308.406594) (xy 231.998984 -308.357926)
			(xy 232.033092 -308.313754) (xy 232.073269 -308.275019) (xy 232.118657 -308.242547) (xy 232.168289 -308.217029)
			(xy 232.221109 -308.19901) (xy 232.275988 -308.188873) (xy 232.331759 -308.186835) (xy 232.387233 -308.192938)
			(xy 232.441226 -308.207054) (xy 232.492589 -308.228881) (xy 232.540227 -308.257954) (xy 232.583123 -308.293653)
			(xy 232.620365 -308.335217) (xy 232.651159 -308.381761) (xy 232.674847 -308.432292) (xy 232.690925 -308.485734)
			(xy 232.699051 -308.540948) (xy 232.69956 -308.568852) (xy 248.185684 -308.568852) (xy 248.189757 -308.513193)
			(xy 248.201892 -308.45872) (xy 248.221828 -308.406594) (xy 248.249142 -308.357926) (xy 248.28325 -308.313754)
			(xy 248.323427 -308.275019) (xy 248.368815 -308.242547) (xy 248.418447 -308.217029) (xy 248.471267 -308.19901)
			(xy 248.526146 -308.188873) (xy 248.581917 -308.186835) (xy 248.637391 -308.192938) (xy 248.691384 -308.207054)
			(xy 248.742747 -308.228881) (xy 248.77707 -308.249828) (xy 306.744128 -308.249828) (xy 306.748088 -308.200774)
			(xy 306.759865 -308.15299) (xy 306.779156 -308.107714) (xy 306.805459 -308.066118) (xy 306.838094 -308.029281)
			(xy 306.876215 -307.998156) (xy 306.918836 -307.973549) (xy 306.964852 -307.956097) (xy 307.013071 -307.946253)
			(xy 307.062246 -307.944272) (xy 307.111101 -307.950204) (xy 307.158372 -307.963896) (xy 307.202834 -307.984994)
			(xy 307.243337 -308.01295) (xy 307.27883 -308.047042) (xy 307.308395 -308.086386) (xy 307.331266 -308.129963)
			(xy 307.34685 -308.176644) (xy 307.354745 -308.225221) (xy 307.35524 -308.249828) (xy 307.694088 -308.249828)
			(xy 307.698048 -308.200774) (xy 307.709825 -308.15299) (xy 307.729116 -308.107714) (xy 307.755419 -308.066118)
			(xy 307.788054 -308.029281) (xy 307.826175 -307.998156) (xy 307.868796 -307.973549) (xy 307.914812 -307.956097)
			(xy 307.963031 -307.946253) (xy 308.012206 -307.944272) (xy 308.061061 -307.950204) (xy 308.108332 -307.963896)
			(xy 308.152794 -307.984994) (xy 308.193297 -308.01295) (xy 308.22879 -308.047042) (xy 308.258355 -308.086386)
			(xy 308.281226 -308.129963) (xy 308.29681 -308.176644) (xy 308.304705 -308.225221) (xy 308.3052 -308.249828)
			(xy 313.394102 -308.249828) (xy 313.398062 -308.200774) (xy 313.409839 -308.15299) (xy 313.42913 -308.107714)
			(xy 313.455433 -308.066118) (xy 313.488068 -308.029281) (xy 313.526189 -307.998156) (xy 313.56881 -307.973549)
			(xy 313.614826 -307.956097) (xy 313.663045 -307.946253) (xy 313.71222 -307.944272) (xy 313.761075 -307.950204)
			(xy 313.808346 -307.963896) (xy 313.852808 -307.984994) (xy 313.893311 -308.01295) (xy 313.928804 -308.047042)
			(xy 313.958369 -308.086386) (xy 313.98124 -308.129963) (xy 313.996824 -308.176644) (xy 314.004719 -308.225221)
			(xy 314.005214 -308.249828) (xy 314.344062 -308.249828) (xy 314.348022 -308.200774) (xy 314.359799 -308.15299)
			(xy 314.37909 -308.107714) (xy 314.405393 -308.066118) (xy 314.438028 -308.029281) (xy 314.476149 -307.998156)
			(xy 314.51877 -307.973549) (xy 314.564786 -307.956097) (xy 314.613005 -307.946253) (xy 314.66218 -307.944272)
			(xy 314.711035 -307.950204) (xy 314.758306 -307.963896) (xy 314.802768 -307.984994) (xy 314.843271 -308.01295)
			(xy 314.878764 -308.047042) (xy 314.908329 -308.086386) (xy 314.9312 -308.129963) (xy 314.946784 -308.176644)
			(xy 314.954679 -308.225221) (xy 314.955174 -308.249828) (xy 391.494022 -308.249828) (xy 391.497982 -308.200774)
			(xy 391.509759 -308.15299) (xy 391.52905 -308.107714) (xy 391.555353 -308.066118) (xy 391.587988 -308.029281)
			(xy 391.626109 -307.998156) (xy 391.66873 -307.973549) (xy 391.714746 -307.956097) (xy 391.762965 -307.946253)
			(xy 391.81214 -307.944272) (xy 391.860995 -307.950204) (xy 391.908266 -307.963896) (xy 391.952728 -307.984994)
			(xy 391.993231 -308.01295) (xy 392.028724 -308.047042) (xy 392.058289 -308.086386) (xy 392.08116 -308.129963)
			(xy 392.096744 -308.176644) (xy 392.104639 -308.225221) (xy 392.105134 -308.249828) (xy 392.443982 -308.249828)
			(xy 392.447942 -308.200774) (xy 392.459719 -308.15299) (xy 392.47901 -308.107714) (xy 392.505313 -308.066118)
			(xy 392.537948 -308.029281) (xy 392.576069 -307.998156) (xy 392.61869 -307.973549) (xy 392.664706 -307.956097)
			(xy 392.712925 -307.946253) (xy 392.7621 -307.944272) (xy 392.810955 -307.950204) (xy 392.858226 -307.963896)
			(xy 392.902688 -307.984994) (xy 392.943191 -308.01295) (xy 392.978684 -308.047042) (xy 393.008249 -308.086386)
			(xy 393.03112 -308.129963) (xy 393.046704 -308.176644) (xy 393.054599 -308.225221) (xy 393.055094 -308.249828)
			(xy 393.054599 -308.274435) (xy 393.046704 -308.323012) (xy 393.03112 -308.369693) (xy 393.008249 -308.41327)
			(xy 392.978684 -308.452614) (xy 392.943191 -308.486706) (xy 392.902688 -308.514662) (xy 392.858226 -308.53576)
			(xy 392.810955 -308.549452) (xy 392.7621 -308.555384) (xy 392.712925 -308.553403) (xy 392.664706 -308.543559)
			(xy 392.61869 -308.526107) (xy 392.576069 -308.5015) (xy 392.537948 -308.470375) (xy 392.505313 -308.433538)
			(xy 392.47901 -308.391942) (xy 392.459719 -308.346666) (xy 392.447942 -308.298882) (xy 392.443982 -308.249828)
			(xy 392.105134 -308.249828) (xy 392.104639 -308.274435) (xy 392.096744 -308.323012) (xy 392.08116 -308.369693)
			(xy 392.058289 -308.41327) (xy 392.028724 -308.452614) (xy 391.993231 -308.486706) (xy 391.952728 -308.514662)
			(xy 391.908266 -308.53576) (xy 391.860995 -308.549452) (xy 391.81214 -308.555384) (xy 391.762965 -308.553403)
			(xy 391.714746 -308.543559) (xy 391.66873 -308.526107) (xy 391.626109 -308.5015) (xy 391.587988 -308.470375)
			(xy 391.555353 -308.433538) (xy 391.52905 -308.391942) (xy 391.509759 -308.346666) (xy 391.497982 -308.298882)
			(xy 391.494022 -308.249828) (xy 314.955174 -308.249828) (xy 314.954679 -308.274435) (xy 314.946784 -308.323012)
			(xy 314.9312 -308.369693) (xy 314.908329 -308.41327) (xy 314.878764 -308.452614) (xy 314.843271 -308.486706)
			(xy 314.802768 -308.514662) (xy 314.758306 -308.53576) (xy 314.711035 -308.549452) (xy 314.66218 -308.555384)
			(xy 314.613005 -308.553403) (xy 314.564786 -308.543559) (xy 314.51877 -308.526107) (xy 314.476149 -308.5015)
			(xy 314.438028 -308.470375) (xy 314.405393 -308.433538) (xy 314.37909 -308.391942) (xy 314.359799 -308.346666)
			(xy 314.348022 -308.298882) (xy 314.344062 -308.249828) (xy 314.005214 -308.249828) (xy 314.004719 -308.274435)
			(xy 313.996824 -308.323012) (xy 313.98124 -308.369693) (xy 313.958369 -308.41327) (xy 313.928804 -308.452614)
			(xy 313.893311 -308.486706) (xy 313.852808 -308.514662) (xy 313.808346 -308.53576) (xy 313.761075 -308.549452)
			(xy 313.71222 -308.555384) (xy 313.663045 -308.553403) (xy 313.614826 -308.543559) (xy 313.56881 -308.526107)
			(xy 313.526189 -308.5015) (xy 313.488068 -308.470375) (xy 313.455433 -308.433538) (xy 313.42913 -308.391942)
			(xy 313.409839 -308.346666) (xy 313.398062 -308.298882) (xy 313.394102 -308.249828) (xy 308.3052 -308.249828)
			(xy 308.304705 -308.274435) (xy 308.29681 -308.323012) (xy 308.281226 -308.369693) (xy 308.258355 -308.41327)
			(xy 308.22879 -308.452614) (xy 308.193297 -308.486706) (xy 308.152794 -308.514662) (xy 308.108332 -308.53576)
			(xy 308.061061 -308.549452) (xy 308.012206 -308.555384) (xy 307.963031 -308.553403) (xy 307.914812 -308.543559)
			(xy 307.868796 -308.526107) (xy 307.826175 -308.5015) (xy 307.788054 -308.470375) (xy 307.755419 -308.433538)
			(xy 307.729116 -308.391942) (xy 307.709825 -308.346666) (xy 307.698048 -308.298882) (xy 307.694088 -308.249828)
			(xy 307.35524 -308.249828) (xy 307.354745 -308.274435) (xy 307.34685 -308.323012) (xy 307.331266 -308.369693)
			(xy 307.308395 -308.41327) (xy 307.27883 -308.452614) (xy 307.243337 -308.486706) (xy 307.202834 -308.514662)
			(xy 307.158372 -308.53576) (xy 307.111101 -308.549452) (xy 307.062246 -308.555384) (xy 307.013071 -308.553403)
			(xy 306.964852 -308.543559) (xy 306.918836 -308.526107) (xy 306.876215 -308.5015) (xy 306.838094 -308.470375)
			(xy 306.805459 -308.433538) (xy 306.779156 -308.391942) (xy 306.759865 -308.346666) (xy 306.748088 -308.298882)
			(xy 306.744128 -308.249828) (xy 248.77707 -308.249828) (xy 248.790385 -308.257954) (xy 248.833281 -308.293653)
			(xy 248.870523 -308.335217) (xy 248.901317 -308.381761) (xy 248.925005 -308.432292) (xy 248.941083 -308.485734)
			(xy 248.949209 -308.540948) (xy 248.949718 -308.568852) (xy 248.949209 -308.596756) (xy 248.941083 -308.65197)
			(xy 248.928951 -308.692296) (xy 462.556604 -308.692296) (xy 462.560677 -308.636637) (xy 462.572812 -308.582164)
			(xy 462.592748 -308.530038) (xy 462.620062 -308.48137) (xy 462.65417 -308.437198) (xy 462.694347 -308.398463)
			(xy 462.739735 -308.365991) (xy 462.789367 -308.340473) (xy 462.842187 -308.322454) (xy 462.897066 -308.312317)
			(xy 462.952837 -308.310279) (xy 463.008311 -308.316382) (xy 463.062304 -308.330498) (xy 463.113667 -308.352325)
			(xy 463.161305 -308.381398) (xy 463.204201 -308.417097) (xy 463.241443 -308.458661) (xy 463.272237 -308.505205)
			(xy 463.295925 -308.555736) (xy 463.312003 -308.609178) (xy 463.320129 -308.664392) (xy 463.320638 -308.692296)
			(xy 463.320129 -308.7202) (xy 463.312003 -308.775414) (xy 463.295925 -308.828856) (xy 463.272237 -308.879387)
			(xy 463.241443 -308.925931) (xy 463.204201 -308.967495) (xy 463.161305 -309.003194) (xy 463.113667 -309.032267)
			(xy 463.062304 -309.054094) (xy 463.008311 -309.06821) (xy 462.952837 -309.074313) (xy 462.897066 -309.072275)
			(xy 462.842187 -309.062138) (xy 462.789367 -309.044119) (xy 462.739735 -309.018601) (xy 462.694347 -308.986129)
			(xy 462.65417 -308.947394) (xy 462.620062 -308.903222) (xy 462.592748 -308.854554) (xy 462.572812 -308.802428)
			(xy 462.560677 -308.747955) (xy 462.556604 -308.692296) (xy 248.928951 -308.692296) (xy 248.925005 -308.705412)
			(xy 248.901317 -308.755943) (xy 248.870523 -308.802487) (xy 248.833281 -308.844051) (xy 248.790385 -308.87975)
			(xy 248.742747 -308.908823) (xy 248.691384 -308.93065) (xy 248.637391 -308.944766) (xy 248.581917 -308.950869)
			(xy 248.526146 -308.948831) (xy 248.471267 -308.938694) (xy 248.418447 -308.920675) (xy 248.368815 -308.895157)
			(xy 248.323427 -308.862685) (xy 248.28325 -308.82395) (xy 248.249142 -308.779778) (xy 248.221828 -308.73111)
			(xy 248.201892 -308.678984) (xy 248.189757 -308.624511) (xy 248.185684 -308.568852) (xy 232.69956 -308.568852)
			(xy 232.699051 -308.596756) (xy 232.690925 -308.65197) (xy 232.674847 -308.705412) (xy 232.651159 -308.755943)
			(xy 232.620365 -308.802487) (xy 232.583123 -308.844051) (xy 232.540227 -308.87975) (xy 232.492589 -308.908823)
			(xy 232.441226 -308.93065) (xy 232.387233 -308.944766) (xy 232.331759 -308.950869) (xy 232.275988 -308.948831)
			(xy 232.221109 -308.938694) (xy 232.168289 -308.920675) (xy 232.118657 -308.895157) (xy 232.073269 -308.862685)
			(xy 232.033092 -308.82395) (xy 231.998984 -308.779778) (xy 231.97167 -308.73111) (xy 231.951734 -308.678984)
			(xy 231.939599 -308.624511) (xy 231.935526 -308.568852) (xy 0.508 -308.568852) (xy 0.508 -309.199788)
			(xy 76.444106 -309.199788) (xy 76.448066 -309.150734) (xy 76.459843 -309.10295) (xy 76.479134 -309.057674)
			(xy 76.505437 -309.016078) (xy 76.538072 -308.979241) (xy 76.576193 -308.948116) (xy 76.618814 -308.923509)
			(xy 76.66483 -308.906057) (xy 76.713049 -308.896213) (xy 76.762224 -308.894232) (xy 76.811079 -308.900164)
			(xy 76.85835 -308.913856) (xy 76.902812 -308.934954) (xy 76.943315 -308.96291) (xy 76.978808 -308.997002)
			(xy 77.008373 -309.036346) (xy 77.031244 -309.079923) (xy 77.046828 -309.126604) (xy 77.054723 -309.175181)
			(xy 77.055218 -309.199788) (xy 77.394066 -309.199788) (xy 77.398026 -309.150734) (xy 77.409803 -309.10295)
			(xy 77.429094 -309.057674) (xy 77.455397 -309.016078) (xy 77.488032 -308.979241) (xy 77.526153 -308.948116)
			(xy 77.568774 -308.923509) (xy 77.61479 -308.906057) (xy 77.663009 -308.896213) (xy 77.712184 -308.894232)
			(xy 77.761039 -308.900164) (xy 77.80831 -308.913856) (xy 77.852772 -308.934954) (xy 77.893275 -308.96291)
			(xy 77.928768 -308.997002) (xy 77.958333 -309.036346) (xy 77.981204 -309.079923) (xy 77.996788 -309.126604)
			(xy 78.004683 -309.175181) (xy 78.005178 -309.199788) (xy 79.293986 -309.199788) (xy 79.297946 -309.150734)
			(xy 79.309723 -309.10295) (xy 79.329014 -309.057674) (xy 79.355317 -309.016078) (xy 79.387952 -308.979241)
			(xy 79.426073 -308.948116) (xy 79.468694 -308.923509) (xy 79.51471 -308.906057) (xy 79.562929 -308.896213)
			(xy 79.612104 -308.894232) (xy 79.660959 -308.900164) (xy 79.70823 -308.913856) (xy 79.752692 -308.934954)
			(xy 79.793195 -308.96291) (xy 79.828688 -308.997002) (xy 79.858253 -309.036346) (xy 79.881124 -309.079923)
			(xy 79.896708 -309.126604) (xy 79.904603 -309.175181) (xy 79.905098 -309.199788) (xy 80.243946 -309.199788)
			(xy 80.247906 -309.150734) (xy 80.259683 -309.10295) (xy 80.278974 -309.057674) (xy 80.305277 -309.016078)
			(xy 80.337912 -308.979241) (xy 80.376033 -308.948116) (xy 80.418654 -308.923509) (xy 80.46467 -308.906057)
			(xy 80.512889 -308.896213) (xy 80.562064 -308.894232) (xy 80.610919 -308.900164) (xy 80.65819 -308.913856)
			(xy 80.702652 -308.934954) (xy 80.743155 -308.96291) (xy 80.778648 -308.997002) (xy 80.808213 -309.036346)
			(xy 80.831084 -309.079923) (xy 80.846668 -309.126604) (xy 80.854563 -309.175181) (xy 80.855058 -309.199788)
			(xy 157.39416 -309.199788) (xy 157.39812 -309.150734) (xy 157.409897 -309.10295) (xy 157.429188 -309.057674)
			(xy 157.455491 -309.016078) (xy 157.488126 -308.979241) (xy 157.526247 -308.948116) (xy 157.568868 -308.923509)
			(xy 157.614884 -308.906057) (xy 157.663103 -308.896213) (xy 157.712278 -308.894232) (xy 157.761133 -308.900164)
			(xy 157.808404 -308.913856) (xy 157.852866 -308.934954) (xy 157.893369 -308.96291) (xy 157.928862 -308.997002)
			(xy 157.958427 -309.036346) (xy 157.981298 -309.079923) (xy 157.996882 -309.126604) (xy 158.004777 -309.175181)
			(xy 158.005272 -309.199788) (xy 158.34412 -309.199788) (xy 158.34808 -309.150734) (xy 158.359857 -309.10295)
			(xy 158.379148 -309.057674) (xy 158.405451 -309.016078) (xy 158.438086 -308.979241) (xy 158.476207 -308.948116)
			(xy 158.518828 -308.923509) (xy 158.564844 -308.906057) (xy 158.613063 -308.896213) (xy 158.662238 -308.894232)
			(xy 158.711093 -308.900164) (xy 158.758364 -308.913856) (xy 158.802826 -308.934954) (xy 158.843329 -308.96291)
			(xy 158.878822 -308.997002) (xy 158.908387 -309.036346) (xy 158.931258 -309.079923) (xy 158.946842 -309.126604)
			(xy 158.954737 -309.175181) (xy 158.955232 -309.199788) (xy 308.644048 -309.199788) (xy 308.648008 -309.150734)
			(xy 308.659785 -309.10295) (xy 308.679076 -309.057674) (xy 308.705379 -309.016078) (xy 308.738014 -308.979241)
			(xy 308.776135 -308.948116) (xy 308.818756 -308.923509) (xy 308.864772 -308.906057) (xy 308.912991 -308.896213)
			(xy 308.962166 -308.894232) (xy 309.011021 -308.900164) (xy 309.058292 -308.913856) (xy 309.102754 -308.934954)
			(xy 309.143257 -308.96291) (xy 309.17875 -308.997002) (xy 309.208315 -309.036346) (xy 309.231186 -309.079923)
			(xy 309.24677 -309.126604) (xy 309.254665 -309.175181) (xy 309.25516 -309.199788) (xy 309.594008 -309.199788)
			(xy 309.597968 -309.150734) (xy 309.609745 -309.10295) (xy 309.629036 -309.057674) (xy 309.655339 -309.016078)
			(xy 309.687974 -308.979241) (xy 309.726095 -308.948116) (xy 309.768716 -308.923509) (xy 309.814732 -308.906057)
			(xy 309.862951 -308.896213) (xy 309.912126 -308.894232) (xy 309.960981 -308.900164) (xy 310.008252 -308.913856)
			(xy 310.052714 -308.934954) (xy 310.093217 -308.96291) (xy 310.12871 -308.997002) (xy 310.158275 -309.036346)
			(xy 310.181146 -309.079923) (xy 310.19673 -309.126604) (xy 310.204625 -309.175181) (xy 310.20512 -309.199788)
			(xy 311.493928 -309.199788) (xy 311.497888 -309.150734) (xy 311.509665 -309.10295) (xy 311.528956 -309.057674)
			(xy 311.555259 -309.016078) (xy 311.587894 -308.979241) (xy 311.626015 -308.948116) (xy 311.668636 -308.923509)
			(xy 311.714652 -308.906057) (xy 311.762871 -308.896213) (xy 311.812046 -308.894232) (xy 311.860901 -308.900164)
			(xy 311.908172 -308.913856) (xy 311.952634 -308.934954) (xy 311.993137 -308.96291) (xy 312.02863 -308.997002)
			(xy 312.058195 -309.036346) (xy 312.081066 -309.079923) (xy 312.09665 -309.126604) (xy 312.104545 -309.175181)
			(xy 312.10504 -309.199788) (xy 312.443888 -309.199788) (xy 312.447848 -309.150734) (xy 312.459625 -309.10295)
			(xy 312.478916 -309.057674) (xy 312.505219 -309.016078) (xy 312.537854 -308.979241) (xy 312.575975 -308.948116)
			(xy 312.618596 -308.923509) (xy 312.664612 -308.906057) (xy 312.712831 -308.896213) (xy 312.762006 -308.894232)
			(xy 312.810861 -308.900164) (xy 312.858132 -308.913856) (xy 312.902594 -308.934954) (xy 312.943097 -308.96291)
			(xy 312.97859 -308.997002) (xy 313.008155 -309.036346) (xy 313.031026 -309.079923) (xy 313.04661 -309.126604)
			(xy 313.054505 -309.175181) (xy 313.055 -309.199788) (xy 389.594102 -309.199788) (xy 389.598062 -309.150734)
			(xy 389.609839 -309.10295) (xy 389.62913 -309.057674) (xy 389.655433 -309.016078) (xy 389.688068 -308.979241)
			(xy 389.726189 -308.948116) (xy 389.76881 -308.923509) (xy 389.814826 -308.906057) (xy 389.863045 -308.896213)
			(xy 389.91222 -308.894232) (xy 389.961075 -308.900164) (xy 390.008346 -308.913856) (xy 390.052808 -308.934954)
			(xy 390.093311 -308.96291) (xy 390.128804 -308.997002) (xy 390.158369 -309.036346) (xy 390.18124 -309.079923)
			(xy 390.196824 -309.126604) (xy 390.204719 -309.175181) (xy 390.205214 -309.199788) (xy 390.544062 -309.199788)
			(xy 390.548022 -309.150734) (xy 390.559799 -309.10295) (xy 390.57909 -309.057674) (xy 390.605393 -309.016078)
			(xy 390.638028 -308.979241) (xy 390.676149 -308.948116) (xy 390.71877 -308.923509) (xy 390.764786 -308.906057)
			(xy 390.813005 -308.896213) (xy 390.86218 -308.894232) (xy 390.911035 -308.900164) (xy 390.958306 -308.913856)
			(xy 391.002768 -308.934954) (xy 391.043271 -308.96291) (xy 391.078764 -308.997002) (xy 391.108329 -309.036346)
			(xy 391.1312 -309.079923) (xy 391.146784 -309.126604) (xy 391.154679 -309.175181) (xy 391.155174 -309.199788)
			(xy 391.154679 -309.224395) (xy 391.146784 -309.272972) (xy 391.1312 -309.319653) (xy 391.108329 -309.36323)
			(xy 391.078764 -309.402574) (xy 391.043271 -309.436666) (xy 391.002768 -309.464622) (xy 390.958306 -309.48572)
			(xy 390.911035 -309.499412) (xy 390.86218 -309.505344) (xy 390.813005 -309.503363) (xy 390.764786 -309.493519)
			(xy 390.71877 -309.476067) (xy 390.676149 -309.45146) (xy 390.638028 -309.420335) (xy 390.605393 -309.383498)
			(xy 390.57909 -309.341902) (xy 390.559799 -309.296626) (xy 390.548022 -309.248842) (xy 390.544062 -309.199788)
			(xy 390.205214 -309.199788) (xy 390.204719 -309.224395) (xy 390.196824 -309.272972) (xy 390.18124 -309.319653)
			(xy 390.158369 -309.36323) (xy 390.128804 -309.402574) (xy 390.093311 -309.436666) (xy 390.052808 -309.464622)
			(xy 390.008346 -309.48572) (xy 389.961075 -309.499412) (xy 389.91222 -309.505344) (xy 389.863045 -309.503363)
			(xy 389.814826 -309.493519) (xy 389.76881 -309.476067) (xy 389.726189 -309.45146) (xy 389.688068 -309.420335)
			(xy 389.655433 -309.383498) (xy 389.62913 -309.341902) (xy 389.609839 -309.296626) (xy 389.598062 -309.248842)
			(xy 389.594102 -309.199788) (xy 313.055 -309.199788) (xy 313.054505 -309.224395) (xy 313.04661 -309.272972)
			(xy 313.031026 -309.319653) (xy 313.008155 -309.36323) (xy 312.97859 -309.402574) (xy 312.943097 -309.436666)
			(xy 312.902594 -309.464622) (xy 312.858132 -309.48572) (xy 312.810861 -309.499412) (xy 312.762006 -309.505344)
			(xy 312.712831 -309.503363) (xy 312.664612 -309.493519) (xy 312.618596 -309.476067) (xy 312.575975 -309.45146)
			(xy 312.537854 -309.420335) (xy 312.505219 -309.383498) (xy 312.478916 -309.341902) (xy 312.459625 -309.296626)
			(xy 312.447848 -309.248842) (xy 312.443888 -309.199788) (xy 312.10504 -309.199788) (xy 312.104545 -309.224395)
			(xy 312.09665 -309.272972) (xy 312.081066 -309.319653) (xy 312.058195 -309.36323) (xy 312.02863 -309.402574)
			(xy 311.993137 -309.436666) (xy 311.952634 -309.464622) (xy 311.908172 -309.48572) (xy 311.860901 -309.499412)
			(xy 311.812046 -309.505344) (xy 311.762871 -309.503363) (xy 311.714652 -309.493519) (xy 311.668636 -309.476067)
			(xy 311.626015 -309.45146) (xy 311.587894 -309.420335) (xy 311.555259 -309.383498) (xy 311.528956 -309.341902)
			(xy 311.509665 -309.296626) (xy 311.497888 -309.248842) (xy 311.493928 -309.199788) (xy 310.20512 -309.199788)
			(xy 310.204625 -309.224395) (xy 310.19673 -309.272972) (xy 310.181146 -309.319653) (xy 310.158275 -309.36323)
			(xy 310.12871 -309.402574) (xy 310.093217 -309.436666) (xy 310.052714 -309.464622) (xy 310.008252 -309.48572)
			(xy 309.960981 -309.499412) (xy 309.912126 -309.505344) (xy 309.862951 -309.503363) (xy 309.814732 -309.493519)
			(xy 309.768716 -309.476067) (xy 309.726095 -309.45146) (xy 309.687974 -309.420335) (xy 309.655339 -309.383498)
			(xy 309.629036 -309.341902) (xy 309.609745 -309.296626) (xy 309.597968 -309.248842) (xy 309.594008 -309.199788)
			(xy 309.25516 -309.199788) (xy 309.254665 -309.224395) (xy 309.24677 -309.272972) (xy 309.231186 -309.319653)
			(xy 309.208315 -309.36323) (xy 309.17875 -309.402574) (xy 309.143257 -309.436666) (xy 309.102754 -309.464622)
			(xy 309.058292 -309.48572) (xy 309.011021 -309.499412) (xy 308.962166 -309.505344) (xy 308.912991 -309.503363)
			(xy 308.864772 -309.493519) (xy 308.818756 -309.476067) (xy 308.776135 -309.45146) (xy 308.738014 -309.420335)
			(xy 308.705379 -309.383498) (xy 308.679076 -309.341902) (xy 308.659785 -309.296626) (xy 308.648008 -309.248842)
			(xy 308.644048 -309.199788) (xy 158.955232 -309.199788) (xy 158.954737 -309.224395) (xy 158.946842 -309.272972)
			(xy 158.931258 -309.319653) (xy 158.908387 -309.36323) (xy 158.878822 -309.402574) (xy 158.843329 -309.436666)
			(xy 158.802826 -309.464622) (xy 158.758364 -309.48572) (xy 158.711093 -309.499412) (xy 158.662238 -309.505344)
			(xy 158.613063 -309.503363) (xy 158.564844 -309.493519) (xy 158.518828 -309.476067) (xy 158.476207 -309.45146)
			(xy 158.438086 -309.420335) (xy 158.405451 -309.383498) (xy 158.379148 -309.341902) (xy 158.359857 -309.296626)
			(xy 158.34808 -309.248842) (xy 158.34412 -309.199788) (xy 158.005272 -309.199788) (xy 158.004777 -309.224395)
			(xy 157.996882 -309.272972) (xy 157.981298 -309.319653) (xy 157.958427 -309.36323) (xy 157.928862 -309.402574)
			(xy 157.893369 -309.436666) (xy 157.852866 -309.464622) (xy 157.808404 -309.48572) (xy 157.761133 -309.499412)
			(xy 157.712278 -309.505344) (xy 157.663103 -309.503363) (xy 157.614884 -309.493519) (xy 157.568868 -309.476067)
			(xy 157.526247 -309.45146) (xy 157.488126 -309.420335) (xy 157.455491 -309.383498) (xy 157.429188 -309.341902)
			(xy 157.409897 -309.296626) (xy 157.39812 -309.248842) (xy 157.39416 -309.199788) (xy 80.855058 -309.199788)
			(xy 80.854563 -309.224395) (xy 80.846668 -309.272972) (xy 80.831084 -309.319653) (xy 80.808213 -309.36323)
			(xy 80.778648 -309.402574) (xy 80.743155 -309.436666) (xy 80.702652 -309.464622) (xy 80.65819 -309.48572)
			(xy 80.610919 -309.499412) (xy 80.562064 -309.505344) (xy 80.512889 -309.503363) (xy 80.46467 -309.493519)
			(xy 80.418654 -309.476067) (xy 80.376033 -309.45146) (xy 80.337912 -309.420335) (xy 80.305277 -309.383498)
			(xy 80.278974 -309.341902) (xy 80.259683 -309.296626) (xy 80.247906 -309.248842) (xy 80.243946 -309.199788)
			(xy 79.905098 -309.199788) (xy 79.904603 -309.224395) (xy 79.896708 -309.272972) (xy 79.881124 -309.319653)
			(xy 79.858253 -309.36323) (xy 79.828688 -309.402574) (xy 79.793195 -309.436666) (xy 79.752692 -309.464622)
			(xy 79.70823 -309.48572) (xy 79.660959 -309.499412) (xy 79.612104 -309.505344) (xy 79.562929 -309.503363)
			(xy 79.51471 -309.493519) (xy 79.468694 -309.476067) (xy 79.426073 -309.45146) (xy 79.387952 -309.420335)
			(xy 79.355317 -309.383498) (xy 79.329014 -309.341902) (xy 79.309723 -309.296626) (xy 79.297946 -309.248842)
			(xy 79.293986 -309.199788) (xy 78.005178 -309.199788) (xy 78.004683 -309.224395) (xy 77.996788 -309.272972)
			(xy 77.981204 -309.319653) (xy 77.958333 -309.36323) (xy 77.928768 -309.402574) (xy 77.893275 -309.436666)
			(xy 77.852772 -309.464622) (xy 77.80831 -309.48572) (xy 77.761039 -309.499412) (xy 77.712184 -309.505344)
			(xy 77.663009 -309.503363) (xy 77.61479 -309.493519) (xy 77.568774 -309.476067) (xy 77.526153 -309.45146)
			(xy 77.488032 -309.420335) (xy 77.455397 -309.383498) (xy 77.429094 -309.341902) (xy 77.409803 -309.296626)
			(xy 77.398026 -309.248842) (xy 77.394066 -309.199788) (xy 77.055218 -309.199788) (xy 77.054723 -309.224395)
			(xy 77.046828 -309.272972) (xy 77.031244 -309.319653) (xy 77.008373 -309.36323) (xy 76.978808 -309.402574)
			(xy 76.943315 -309.436666) (xy 76.902812 -309.464622) (xy 76.85835 -309.48572) (xy 76.811079 -309.499412)
			(xy 76.762224 -309.505344) (xy 76.713049 -309.503363) (xy 76.66483 -309.493519) (xy 76.618814 -309.476067)
			(xy 76.576193 -309.45146) (xy 76.538072 -309.420335) (xy 76.505437 -309.383498) (xy 76.479134 -309.341902)
			(xy 76.459843 -309.296626) (xy 76.448066 -309.248842) (xy 76.444106 -309.199788) (xy 0.508 -309.199788)
			(xy 0.508 -310.149748) (xy 81.19416 -310.149748) (xy 81.19812 -310.100694) (xy 81.209897 -310.05291)
			(xy 81.229188 -310.007634) (xy 81.255491 -309.966038) (xy 81.288126 -309.929201) (xy 81.326247 -309.898076)
			(xy 81.368868 -309.873469) (xy 81.414884 -309.856017) (xy 81.463103 -309.846173) (xy 81.512278 -309.844192)
			(xy 81.561133 -309.850124) (xy 81.608404 -309.863816) (xy 81.652866 -309.884914) (xy 81.693369 -309.91287)
			(xy 81.728862 -309.946962) (xy 81.758427 -309.986306) (xy 81.781298 -310.029883) (xy 81.796882 -310.076564)
			(xy 81.804777 -310.125141) (xy 81.805272 -310.149748) (xy 82.14412 -310.149748) (xy 82.14808 -310.100694)
			(xy 82.159857 -310.05291) (xy 82.179148 -310.007634) (xy 82.205451 -309.966038) (xy 82.238086 -309.929201)
			(xy 82.276207 -309.898076) (xy 82.318828 -309.873469) (xy 82.364844 -309.856017) (xy 82.413063 -309.846173)
			(xy 82.462238 -309.844192) (xy 82.511093 -309.850124) (xy 82.558364 -309.863816) (xy 82.602826 -309.884914)
			(xy 82.643329 -309.91287) (xy 82.678822 -309.946962) (xy 82.708387 -309.986306) (xy 82.731258 -310.029883)
			(xy 82.746842 -310.076564) (xy 82.754737 -310.125141) (xy 82.755232 -310.149748) (xy 313.394102 -310.149748)
			(xy 313.398062 -310.100694) (xy 313.409839 -310.05291) (xy 313.42913 -310.007634) (xy 313.455433 -309.966038)
			(xy 313.488068 -309.929201) (xy 313.526189 -309.898076) (xy 313.56881 -309.873469) (xy 313.614826 -309.856017)
			(xy 313.663045 -309.846173) (xy 313.71222 -309.844192) (xy 313.761075 -309.850124) (xy 313.808346 -309.863816)
			(xy 313.852808 -309.884914) (xy 313.893311 -309.91287) (xy 313.928804 -309.946962) (xy 313.958369 -309.986306)
			(xy 313.98124 -310.029883) (xy 313.996824 -310.076564) (xy 314.004719 -310.125141) (xy 314.005214 -310.149748)
			(xy 314.344062 -310.149748) (xy 314.348022 -310.100694) (xy 314.359799 -310.05291) (xy 314.37909 -310.007634)
			(xy 314.405393 -309.966038) (xy 314.438028 -309.929201) (xy 314.476149 -309.898076) (xy 314.51877 -309.873469)
			(xy 314.564786 -309.856017) (xy 314.613005 -309.846173) (xy 314.66218 -309.844192) (xy 314.711035 -309.850124)
			(xy 314.758306 -309.863816) (xy 314.802768 -309.884914) (xy 314.843271 -309.91287) (xy 314.878764 -309.946962)
			(xy 314.908329 -309.986306) (xy 314.9312 -310.029883) (xy 314.946784 -310.076564) (xy 314.954679 -310.125141)
			(xy 314.955174 -310.149748) (xy 314.954679 -310.174355) (xy 314.946784 -310.222932) (xy 314.9312 -310.269613)
			(xy 314.908329 -310.31319) (xy 314.878764 -310.352534) (xy 314.843271 -310.386626) (xy 314.802768 -310.414582)
			(xy 314.758306 -310.43568) (xy 314.711035 -310.449372) (xy 314.66218 -310.455304) (xy 314.613005 -310.453323)
			(xy 314.564786 -310.443479) (xy 314.51877 -310.426027) (xy 314.476149 -310.40142) (xy 314.438028 -310.370295)
			(xy 314.405393 -310.333458) (xy 314.37909 -310.291862) (xy 314.359799 -310.246586) (xy 314.348022 -310.198802)
			(xy 314.344062 -310.149748) (xy 314.005214 -310.149748) (xy 314.004719 -310.174355) (xy 313.996824 -310.222932)
			(xy 313.98124 -310.269613) (xy 313.958369 -310.31319) (xy 313.928804 -310.352534) (xy 313.893311 -310.386626)
			(xy 313.852808 -310.414582) (xy 313.808346 -310.43568) (xy 313.761075 -310.449372) (xy 313.71222 -310.455304)
			(xy 313.663045 -310.453323) (xy 313.614826 -310.443479) (xy 313.56881 -310.426027) (xy 313.526189 -310.40142)
			(xy 313.488068 -310.370295) (xy 313.455433 -310.333458) (xy 313.42913 -310.291862) (xy 313.409839 -310.246586)
			(xy 313.398062 -310.198802) (xy 313.394102 -310.149748) (xy 82.755232 -310.149748) (xy 82.754737 -310.174355)
			(xy 82.746842 -310.222932) (xy 82.731258 -310.269613) (xy 82.708387 -310.31319) (xy 82.678822 -310.352534)
			(xy 82.643329 -310.386626) (xy 82.602826 -310.414582) (xy 82.558364 -310.43568) (xy 82.511093 -310.449372)
			(xy 82.462238 -310.455304) (xy 82.413063 -310.453323) (xy 82.364844 -310.443479) (xy 82.318828 -310.426027)
			(xy 82.276207 -310.40142) (xy 82.238086 -310.370295) (xy 82.205451 -310.333458) (xy 82.179148 -310.291862)
			(xy 82.159857 -310.246586) (xy 82.14808 -310.198802) (xy 82.14412 -310.149748) (xy 81.805272 -310.149748)
			(xy 81.804777 -310.174355) (xy 81.796882 -310.222932) (xy 81.781298 -310.269613) (xy 81.758427 -310.31319)
			(xy 81.728862 -310.352534) (xy 81.693369 -310.386626) (xy 81.652866 -310.414582) (xy 81.608404 -310.43568)
			(xy 81.561133 -310.449372) (xy 81.512278 -310.455304) (xy 81.463103 -310.453323) (xy 81.414884 -310.443479)
			(xy 81.368868 -310.426027) (xy 81.326247 -310.40142) (xy 81.288126 -310.370295) (xy 81.255491 -310.333458)
			(xy 81.229188 -310.291862) (xy 81.209897 -310.246586) (xy 81.19812 -310.198802) (xy 81.19416 -310.149748)
			(xy 0.508 -310.149748) (xy 0.508 -311.099962) (xy 43.193982 -311.099962) (xy 43.197942 -311.050908)
			(xy 43.209719 -311.003124) (xy 43.22901 -310.957848) (xy 43.255313 -310.916252) (xy 43.287948 -310.879415)
			(xy 43.326069 -310.84829) (xy 43.36869 -310.823683) (xy 43.414706 -310.806231) (xy 43.462925 -310.796387)
			(xy 43.5121 -310.794406) (xy 43.560955 -310.800338) (xy 43.608226 -310.81403) (xy 43.652688 -310.835128)
			(xy 43.693191 -310.863084) (xy 43.728684 -310.897176) (xy 43.758249 -310.93652) (xy 43.78112 -310.980097)
			(xy 43.796704 -311.026778) (xy 43.804599 -311.075355) (xy 43.805094 -311.099962) (xy 45.094156 -311.099962)
			(xy 45.098116 -311.050908) (xy 45.109893 -311.003124) (xy 45.129184 -310.957848) (xy 45.155487 -310.916252)
			(xy 45.188122 -310.879415) (xy 45.226243 -310.84829) (xy 45.268864 -310.823683) (xy 45.31488 -310.806231)
			(xy 45.363099 -310.796387) (xy 45.412274 -310.794406) (xy 45.461129 -310.800338) (xy 45.5084 -310.81403)
			(xy 45.552862 -310.835128) (xy 45.593365 -310.863084) (xy 45.628858 -310.897176) (xy 45.658423 -310.93652)
			(xy 45.681294 -310.980097) (xy 45.696878 -311.026778) (xy 45.704773 -311.075355) (xy 45.705268 -311.099962)
			(xy 46.994076 -311.099962) (xy 46.998036 -311.050908) (xy 47.009813 -311.003124) (xy 47.029104 -310.957848)
			(xy 47.055407 -310.916252) (xy 47.088042 -310.879415) (xy 47.126163 -310.84829) (xy 47.168784 -310.823683)
			(xy 47.2148 -310.806231) (xy 47.263019 -310.796387) (xy 47.312194 -310.794406) (xy 47.361049 -310.800338)
			(xy 47.40832 -310.81403) (xy 47.452782 -310.835128) (xy 47.493285 -310.863084) (xy 47.528778 -310.897176)
			(xy 47.558343 -310.93652) (xy 47.581214 -310.980097) (xy 47.596798 -311.026778) (xy 47.604693 -311.075355)
			(xy 47.605188 -311.099962) (xy 48.893996 -311.099962) (xy 48.897956 -311.050908) (xy 48.909733 -311.003124)
			(xy 48.929024 -310.957848) (xy 48.955327 -310.916252) (xy 48.987962 -310.879415) (xy 49.026083 -310.84829)
			(xy 49.068704 -310.823683) (xy 49.11472 -310.806231) (xy 49.162939 -310.796387) (xy 49.212114 -310.794406)
			(xy 49.260969 -310.800338) (xy 49.30824 -310.81403) (xy 49.352702 -310.835128) (xy 49.393205 -310.863084)
			(xy 49.428698 -310.897176) (xy 49.458263 -310.93652) (xy 49.481134 -310.980097) (xy 49.496718 -311.026778)
			(xy 49.504613 -311.075355) (xy 49.505108 -311.099962) (xy 50.79417 -311.099962) (xy 50.79813 -311.050908)
			(xy 50.809907 -311.003124) (xy 50.829198 -310.957848) (xy 50.855501 -310.916252) (xy 50.888136 -310.879415)
			(xy 50.926257 -310.84829) (xy 50.968878 -310.823683) (xy 51.014894 -310.806231) (xy 51.063113 -310.796387)
			(xy 51.112288 -310.794406) (xy 51.161143 -310.800338) (xy 51.208414 -310.81403) (xy 51.252876 -310.835128)
			(xy 51.293379 -310.863084) (xy 51.328872 -310.897176) (xy 51.358437 -310.93652) (xy 51.381308 -310.980097)
			(xy 51.396892 -311.026778) (xy 51.404787 -311.075355) (xy 51.405282 -311.099962) (xy 52.69409 -311.099962)
			(xy 52.69805 -311.050908) (xy 52.709827 -311.003124) (xy 52.729118 -310.957848) (xy 52.755421 -310.916252)
			(xy 52.788056 -310.879415) (xy 52.826177 -310.84829) (xy 52.868798 -310.823683) (xy 52.914814 -310.806231)
			(xy 52.963033 -310.796387) (xy 53.012208 -310.794406) (xy 53.061063 -310.800338) (xy 53.108334 -310.81403)
			(xy 53.152796 -310.835128) (xy 53.193299 -310.863084) (xy 53.228792 -310.897176) (xy 53.258357 -310.93652)
			(xy 53.281228 -310.980097) (xy 53.296812 -311.026778) (xy 53.304707 -311.075355) (xy 53.305202 -311.099962)
			(xy 54.59401 -311.099962) (xy 54.59797 -311.050908) (xy 54.609747 -311.003124) (xy 54.629038 -310.957848)
			(xy 54.655341 -310.916252) (xy 54.687976 -310.879415) (xy 54.726097 -310.84829) (xy 54.768718 -310.823683)
			(xy 54.814734 -310.806231) (xy 54.862953 -310.796387) (xy 54.912128 -310.794406) (xy 54.960983 -310.800338)
			(xy 55.008254 -310.81403) (xy 55.052716 -310.835128) (xy 55.093219 -310.863084) (xy 55.128712 -310.897176)
			(xy 55.158277 -310.93652) (xy 55.181148 -310.980097) (xy 55.196732 -311.026778) (xy 55.204627 -311.075355)
			(xy 55.205122 -311.099962) (xy 56.494184 -311.099962) (xy 56.498144 -311.050908) (xy 56.509921 -311.003124)
			(xy 56.529212 -310.957848) (xy 56.555515 -310.916252) (xy 56.58815 -310.879415) (xy 56.626271 -310.84829)
			(xy 56.668892 -310.823683) (xy 56.714908 -310.806231) (xy 56.763127 -310.796387) (xy 56.812302 -310.794406)
			(xy 56.861157 -310.800338) (xy 56.908428 -310.81403) (xy 56.95289 -310.835128) (xy 56.993393 -310.863084)
			(xy 57.028886 -310.897176) (xy 57.058451 -310.93652) (xy 57.081322 -310.980097) (xy 57.096906 -311.026778)
			(xy 57.104801 -311.075355) (xy 57.105296 -311.099962) (xy 73.593972 -311.099962) (xy 73.597932 -311.050908)
			(xy 73.609709 -311.003124) (xy 73.629 -310.957848) (xy 73.655303 -310.916252) (xy 73.687938 -310.879415)
			(xy 73.726059 -310.84829) (xy 73.76868 -310.823683) (xy 73.814696 -310.806231) (xy 73.862915 -310.796387)
			(xy 73.91209 -310.794406) (xy 73.960945 -310.800338) (xy 74.008216 -310.81403) (xy 74.052678 -310.835128)
			(xy 74.093181 -310.863084) (xy 74.128674 -310.897176) (xy 74.158239 -310.93652) (xy 74.18111 -310.980097)
			(xy 74.196694 -311.026778) (xy 74.204589 -311.075355) (xy 74.205084 -311.099962) (xy 75.494146 -311.099962)
			(xy 75.498106 -311.050908) (xy 75.509883 -311.003124) (xy 75.529174 -310.957848) (xy 75.555477 -310.916252)
			(xy 75.588112 -310.879415) (xy 75.626233 -310.84829) (xy 75.668854 -310.823683) (xy 75.71487 -310.806231)
			(xy 75.763089 -310.796387) (xy 75.812264 -310.794406) (xy 75.861119 -310.800338) (xy 75.90839 -310.81403)
			(xy 75.952852 -310.835128) (xy 75.993355 -310.863084) (xy 76.028848 -310.897176) (xy 76.058413 -310.93652)
			(xy 76.081284 -310.980097) (xy 76.096868 -311.026778) (xy 76.104763 -311.075355) (xy 76.105258 -311.099962)
			(xy 77.394066 -311.099962) (xy 77.398026 -311.050908) (xy 77.409803 -311.003124) (xy 77.429094 -310.957848)
			(xy 77.455397 -310.916252) (xy 77.488032 -310.879415) (xy 77.526153 -310.84829) (xy 77.568774 -310.823683)
			(xy 77.61479 -310.806231) (xy 77.663009 -310.796387) (xy 77.712184 -310.794406) (xy 77.761039 -310.800338)
			(xy 77.80831 -310.81403) (xy 77.852772 -310.835128) (xy 77.893275 -310.863084) (xy 77.928768 -310.897176)
			(xy 77.958333 -310.93652) (xy 77.981204 -310.980097) (xy 77.996788 -311.026778) (xy 78.004683 -311.075355)
			(xy 78.005178 -311.099962) (xy 79.293986 -311.099962) (xy 79.297946 -311.050908) (xy 79.309723 -311.003124)
			(xy 79.329014 -310.957848) (xy 79.355317 -310.916252) (xy 79.387952 -310.879415) (xy 79.426073 -310.84829)
			(xy 79.468694 -310.823683) (xy 79.51471 -310.806231) (xy 79.562929 -310.796387) (xy 79.612104 -310.794406)
			(xy 79.660959 -310.800338) (xy 79.70823 -310.81403) (xy 79.752692 -310.835128) (xy 79.793195 -310.863084)
			(xy 79.828688 -310.897176) (xy 79.858253 -310.93652) (xy 79.881124 -310.980097) (xy 79.896708 -311.026778)
			(xy 79.904603 -311.075355) (xy 79.905098 -311.099962) (xy 155.49424 -311.099962) (xy 155.4982 -311.050908)
			(xy 155.509977 -311.003124) (xy 155.529268 -310.957848) (xy 155.555571 -310.916252) (xy 155.588206 -310.879415)
			(xy 155.626327 -310.84829) (xy 155.668948 -310.823683) (xy 155.714964 -310.806231) (xy 155.763183 -310.796387)
			(xy 155.812358 -310.794406) (xy 155.861213 -310.800338) (xy 155.908484 -310.81403) (xy 155.952946 -310.835128)
			(xy 155.993449 -310.863084) (xy 156.028942 -310.897176) (xy 156.058507 -310.93652) (xy 156.081378 -310.980097)
			(xy 156.096962 -311.026778) (xy 156.104857 -311.075355) (xy 156.105352 -311.099962) (xy 157.39416 -311.099962)
			(xy 157.39812 -311.050908) (xy 157.409897 -311.003124) (xy 157.429188 -310.957848) (xy 157.455491 -310.916252)
			(xy 157.488126 -310.879415) (xy 157.526247 -310.84829) (xy 157.568868 -310.823683) (xy 157.614884 -310.806231)
			(xy 157.663103 -310.796387) (xy 157.712278 -310.794406) (xy 157.761133 -310.800338) (xy 157.808404 -310.81403)
			(xy 157.852866 -310.835128) (xy 157.893369 -310.863084) (xy 157.928862 -310.897176) (xy 157.958427 -310.93652)
			(xy 157.981298 -310.980097) (xy 157.996882 -311.026778) (xy 158.004777 -311.075355) (xy 158.005272 -311.099962)
			(xy 159.29408 -311.099962) (xy 159.29804 -311.050908) (xy 159.309817 -311.003124) (xy 159.329108 -310.957848)
			(xy 159.355411 -310.916252) (xy 159.388046 -310.879415) (xy 159.426167 -310.84829) (xy 159.468788 -310.823683)
			(xy 159.514804 -310.806231) (xy 159.563023 -310.796387) (xy 159.612198 -310.794406) (xy 159.661053 -310.800338)
			(xy 159.708324 -310.81403) (xy 159.752786 -310.835128) (xy 159.793289 -310.863084) (xy 159.828782 -310.897176)
			(xy 159.858347 -310.93652) (xy 159.881218 -310.980097) (xy 159.896802 -311.026778) (xy 159.904697 -311.075355)
			(xy 159.905192 -311.099962) (xy 161.194254 -311.099962) (xy 161.198214 -311.050908) (xy 161.209991 -311.003124)
			(xy 161.229282 -310.957848) (xy 161.255585 -310.916252) (xy 161.28822 -310.879415) (xy 161.326341 -310.84829)
			(xy 161.368962 -310.823683) (xy 161.414978 -310.806231) (xy 161.463197 -310.796387) (xy 161.512372 -310.794406)
			(xy 161.561227 -310.800338) (xy 161.608498 -310.81403) (xy 161.65296 -310.835128) (xy 161.693463 -310.863084)
			(xy 161.728956 -310.897176) (xy 161.758521 -310.93652) (xy 161.781392 -310.980097) (xy 161.796976 -311.026778)
			(xy 161.804871 -311.075355) (xy 161.805366 -311.099962) (xy 163.094174 -311.099962) (xy 163.098134 -311.050908)
			(xy 163.109911 -311.003124) (xy 163.129202 -310.957848) (xy 163.155505 -310.916252) (xy 163.18814 -310.879415)
			(xy 163.226261 -310.84829) (xy 163.268882 -310.823683) (xy 163.314898 -310.806231) (xy 163.363117 -310.796387)
			(xy 163.412292 -310.794406) (xy 163.461147 -310.800338) (xy 163.508418 -310.81403) (xy 163.55288 -310.835128)
			(xy 163.593383 -310.863084) (xy 163.628876 -310.897176) (xy 163.658441 -310.93652) (xy 163.681312 -310.980097)
			(xy 163.696896 -311.026778) (xy 163.704791 -311.075355) (xy 163.705286 -311.099962) (xy 164.994094 -311.099962)
			(xy 164.998054 -311.050908) (xy 165.009831 -311.003124) (xy 165.029122 -310.957848) (xy 165.055425 -310.916252)
			(xy 165.08806 -310.879415) (xy 165.126181 -310.84829) (xy 165.168802 -310.823683) (xy 165.214818 -310.806231)
			(xy 165.263037 -310.796387) (xy 165.312212 -310.794406) (xy 165.361067 -310.800338) (xy 165.408338 -310.81403)
			(xy 165.4528 -310.835128) (xy 165.493303 -310.863084) (xy 165.528796 -310.897176) (xy 165.558361 -310.93652)
			(xy 165.581232 -310.980097) (xy 165.596816 -311.026778) (xy 165.604711 -311.075355) (xy 165.605206 -311.099962)
			(xy 182.094136 -311.099962) (xy 182.098096 -311.050908) (xy 182.109873 -311.003124) (xy 182.129164 -310.957848)
			(xy 182.155467 -310.916252) (xy 182.188102 -310.879415) (xy 182.226223 -310.84829) (xy 182.268844 -310.823683)
			(xy 182.31486 -310.806231) (xy 182.363079 -310.796387) (xy 182.412254 -310.794406) (xy 182.461109 -310.800338)
			(xy 182.50838 -310.81403) (xy 182.552842 -310.835128) (xy 182.593345 -310.863084) (xy 182.628838 -310.897176)
			(xy 182.658403 -310.93652) (xy 182.681274 -310.980097) (xy 182.696858 -311.026778) (xy 182.704753 -311.075355)
			(xy 182.705248 -311.099962) (xy 183.994056 -311.099962) (xy 183.998016 -311.050908) (xy 184.009793 -311.003124)
			(xy 184.029084 -310.957848) (xy 184.055387 -310.916252) (xy 184.088022 -310.879415) (xy 184.126143 -310.84829)
			(xy 184.168764 -310.823683) (xy 184.21478 -310.806231) (xy 184.262999 -310.796387) (xy 184.312174 -310.794406)
			(xy 184.361029 -310.800338) (xy 184.4083 -310.81403) (xy 184.452762 -310.835128) (xy 184.493265 -310.863084)
			(xy 184.528758 -310.897176) (xy 184.558323 -310.93652) (xy 184.581194 -310.980097) (xy 184.596778 -311.026778)
			(xy 184.604673 -311.075355) (xy 184.605168 -311.099962) (xy 185.89423 -311.099962) (xy 185.89819 -311.050908)
			(xy 185.909967 -311.003124) (xy 185.929258 -310.957848) (xy 185.955561 -310.916252) (xy 185.988196 -310.879415)
			(xy 186.026317 -310.84829) (xy 186.068938 -310.823683) (xy 186.114954 -310.806231) (xy 186.163173 -310.796387)
			(xy 186.212348 -310.794406) (xy 186.261203 -310.800338) (xy 186.308474 -310.81403) (xy 186.352936 -310.835128)
			(xy 186.393439 -310.863084) (xy 186.428932 -310.897176) (xy 186.458497 -310.93652) (xy 186.481368 -310.980097)
			(xy 186.496952 -311.026778) (xy 186.504847 -311.075355) (xy 186.505342 -311.099962) (xy 187.79415 -311.099962)
			(xy 187.79811 -311.050908) (xy 187.809887 -311.003124) (xy 187.829178 -310.957848) (xy 187.855481 -310.916252)
			(xy 187.888116 -310.879415) (xy 187.926237 -310.84829) (xy 187.968858 -310.823683) (xy 188.014874 -310.806231)
			(xy 188.063093 -310.796387) (xy 188.112268 -310.794406) (xy 188.161123 -310.800338) (xy 188.208394 -310.81403)
			(xy 188.252856 -310.835128) (xy 188.293359 -310.863084) (xy 188.328852 -310.897176) (xy 188.358417 -310.93652)
			(xy 188.381288 -310.980097) (xy 188.396872 -311.026778) (xy 188.404767 -311.075355) (xy 188.405262 -311.099962)
			(xy 275.393924 -311.099962) (xy 275.397884 -311.050908) (xy 275.409661 -311.003124) (xy 275.428952 -310.957848)
			(xy 275.455255 -310.916252) (xy 275.48789 -310.879415) (xy 275.526011 -310.84829) (xy 275.568632 -310.823683)
			(xy 275.614648 -310.806231) (xy 275.662867 -310.796387) (xy 275.712042 -310.794406) (xy 275.760897 -310.800338)
			(xy 275.808168 -310.81403) (xy 275.85263 -310.835128) (xy 275.893133 -310.863084) (xy 275.928626 -310.897176)
			(xy 275.958191 -310.93652) (xy 275.981062 -310.980097) (xy 275.996646 -311.026778) (xy 276.004541 -311.075355)
			(xy 276.005036 -311.099962) (xy 277.294098 -311.099962) (xy 277.298058 -311.050908) (xy 277.309835 -311.003124)
			(xy 277.329126 -310.957848) (xy 277.355429 -310.916252) (xy 277.388064 -310.879415) (xy 277.426185 -310.84829)
			(xy 277.468806 -310.823683) (xy 277.514822 -310.806231) (xy 277.563041 -310.796387) (xy 277.612216 -310.794406)
			(xy 277.661071 -310.800338) (xy 277.708342 -310.81403) (xy 277.752804 -310.835128) (xy 277.793307 -310.863084)
			(xy 277.8288 -310.897176) (xy 277.858365 -310.93652) (xy 277.881236 -310.980097) (xy 277.89682 -311.026778)
			(xy 277.904715 -311.075355) (xy 277.90521 -311.099962) (xy 279.194018 -311.099962) (xy 279.197978 -311.050908)
			(xy 279.209755 -311.003124) (xy 279.229046 -310.957848) (xy 279.255349 -310.916252) (xy 279.287984 -310.879415)
			(xy 279.326105 -310.84829) (xy 279.368726 -310.823683) (xy 279.414742 -310.806231) (xy 279.462961 -310.796387)
			(xy 279.512136 -310.794406) (xy 279.560991 -310.800338) (xy 279.608262 -310.81403) (xy 279.652724 -310.835128)
			(xy 279.693227 -310.863084) (xy 279.72872 -310.897176) (xy 279.758285 -310.93652) (xy 279.781156 -310.980097)
			(xy 279.79674 -311.026778) (xy 279.804635 -311.075355) (xy 279.80513 -311.099962) (xy 281.093938 -311.099962)
			(xy 281.097898 -311.050908) (xy 281.109675 -311.003124) (xy 281.128966 -310.957848) (xy 281.155269 -310.916252)
			(xy 281.187904 -310.879415) (xy 281.226025 -310.84829) (xy 281.268646 -310.823683) (xy 281.314662 -310.806231)
			(xy 281.362881 -310.796387) (xy 281.412056 -310.794406) (xy 281.460911 -310.800338) (xy 281.508182 -310.81403)
			(xy 281.552644 -310.835128) (xy 281.593147 -310.863084) (xy 281.62864 -310.897176) (xy 281.658205 -310.93652)
			(xy 281.681076 -310.980097) (xy 281.69666 -311.026778) (xy 281.704555 -311.075355) (xy 281.70505 -311.099962)
			(xy 282.994112 -311.099962) (xy 282.998072 -311.050908) (xy 283.009849 -311.003124) (xy 283.02914 -310.957848)
			(xy 283.055443 -310.916252) (xy 283.088078 -310.879415) (xy 283.126199 -310.84829) (xy 283.16882 -310.823683)
			(xy 283.214836 -310.806231) (xy 283.263055 -310.796387) (xy 283.31223 -310.794406) (xy 283.361085 -310.800338)
			(xy 283.408356 -310.81403) (xy 283.452818 -310.835128) (xy 283.493321 -310.863084) (xy 283.528814 -310.897176)
			(xy 283.558379 -310.93652) (xy 283.58125 -310.980097) (xy 283.596834 -311.026778) (xy 283.604729 -311.075355)
			(xy 283.605224 -311.099962) (xy 284.894032 -311.099962) (xy 284.897992 -311.050908) (xy 284.909769 -311.003124)
			(xy 284.92906 -310.957848) (xy 284.955363 -310.916252) (xy 284.987998 -310.879415) (xy 285.026119 -310.84829)
			(xy 285.06874 -310.823683) (xy 285.114756 -310.806231) (xy 285.162975 -310.796387) (xy 285.21215 -310.794406)
			(xy 285.261005 -310.800338) (xy 285.308276 -310.81403) (xy 285.352738 -310.835128) (xy 285.393241 -310.863084)
			(xy 285.428734 -310.897176) (xy 285.458299 -310.93652) (xy 285.48117 -310.980097) (xy 285.496754 -311.026778)
			(xy 285.504649 -311.075355) (xy 285.505144 -311.099962) (xy 286.793952 -311.099962) (xy 286.797912 -311.050908)
			(xy 286.809689 -311.003124) (xy 286.82898 -310.957848) (xy 286.855283 -310.916252) (xy 286.887918 -310.879415)
			(xy 286.926039 -310.84829) (xy 286.96866 -310.823683) (xy 287.014676 -310.806231) (xy 287.062895 -310.796387)
			(xy 287.11207 -310.794406) (xy 287.160925 -310.800338) (xy 287.208196 -310.81403) (xy 287.252658 -310.835128)
			(xy 287.293161 -310.863084) (xy 287.328654 -310.897176) (xy 287.358219 -310.93652) (xy 287.38109 -310.980097)
			(xy 287.396674 -311.026778) (xy 287.404569 -311.075355) (xy 287.405064 -311.099962) (xy 288.694126 -311.099962)
			(xy 288.698086 -311.050908) (xy 288.709863 -311.003124) (xy 288.729154 -310.957848) (xy 288.755457 -310.916252)
			(xy 288.788092 -310.879415) (xy 288.826213 -310.84829) (xy 288.868834 -310.823683) (xy 288.91485 -310.806231)
			(xy 288.963069 -310.796387) (xy 289.012244 -310.794406) (xy 289.061099 -310.800338) (xy 289.10837 -310.81403)
			(xy 289.152832 -310.835128) (xy 289.193335 -310.863084) (xy 289.228828 -310.897176) (xy 289.258393 -310.93652)
			(xy 289.281264 -310.980097) (xy 289.296848 -311.026778) (xy 289.304743 -311.075355) (xy 289.305238 -311.099962)
			(xy 305.793914 -311.099962) (xy 305.797874 -311.050908) (xy 305.809651 -311.003124) (xy 305.828942 -310.957848)
			(xy 305.855245 -310.916252) (xy 305.88788 -310.879415) (xy 305.926001 -310.84829) (xy 305.968622 -310.823683)
			(xy 306.014638 -310.806231) (xy 306.062857 -310.796387) (xy 306.112032 -310.794406) (xy 306.160887 -310.800338)
			(xy 306.208158 -310.81403) (xy 306.25262 -310.835128) (xy 306.293123 -310.863084) (xy 306.328616 -310.897176)
			(xy 306.358181 -310.93652) (xy 306.381052 -310.980097) (xy 306.396636 -311.026778) (xy 306.404531 -311.075355)
			(xy 306.405026 -311.099962) (xy 307.694088 -311.099962) (xy 307.698048 -311.050908) (xy 307.709825 -311.003124)
			(xy 307.729116 -310.957848) (xy 307.755419 -310.916252) (xy 307.788054 -310.879415) (xy 307.826175 -310.84829)
			(xy 307.868796 -310.823683) (xy 307.914812 -310.806231) (xy 307.963031 -310.796387) (xy 308.012206 -310.794406)
			(xy 308.061061 -310.800338) (xy 308.108332 -310.81403) (xy 308.152794 -310.835128) (xy 308.193297 -310.863084)
			(xy 308.22879 -310.897176) (xy 308.258355 -310.93652) (xy 308.281226 -310.980097) (xy 308.29681 -311.026778)
			(xy 308.304705 -311.075355) (xy 308.3052 -311.099962) (xy 309.594008 -311.099962) (xy 309.597968 -311.050908)
			(xy 309.609745 -311.003124) (xy 309.629036 -310.957848) (xy 309.655339 -310.916252) (xy 309.687974 -310.879415)
			(xy 309.726095 -310.84829) (xy 309.768716 -310.823683) (xy 309.814732 -310.806231) (xy 309.862951 -310.796387)
			(xy 309.912126 -310.794406) (xy 309.960981 -310.800338) (xy 310.008252 -310.81403) (xy 310.052714 -310.835128)
			(xy 310.093217 -310.863084) (xy 310.12871 -310.897176) (xy 310.158275 -310.93652) (xy 310.181146 -310.980097)
			(xy 310.19673 -311.026778) (xy 310.204625 -311.075355) (xy 310.20512 -311.099962) (xy 311.493928 -311.099962)
			(xy 311.497888 -311.050908) (xy 311.509665 -311.003124) (xy 311.528956 -310.957848) (xy 311.555259 -310.916252)
			(xy 311.587894 -310.879415) (xy 311.626015 -310.84829) (xy 311.668636 -310.823683) (xy 311.714652 -310.806231)
			(xy 311.762871 -310.796387) (xy 311.812046 -310.794406) (xy 311.860901 -310.800338) (xy 311.908172 -310.81403)
			(xy 311.952634 -310.835128) (xy 311.993137 -310.863084) (xy 312.02863 -310.897176) (xy 312.058195 -310.93652)
			(xy 312.081066 -310.980097) (xy 312.09665 -311.026778) (xy 312.104545 -311.075355) (xy 312.10504 -311.099962)
			(xy 387.694182 -311.099962) (xy 387.698142 -311.050908) (xy 387.709919 -311.003124) (xy 387.72921 -310.957848)
			(xy 387.755513 -310.916252) (xy 387.788148 -310.879415) (xy 387.826269 -310.84829) (xy 387.86889 -310.823683)
			(xy 387.914906 -310.806231) (xy 387.963125 -310.796387) (xy 388.0123 -310.794406) (xy 388.061155 -310.800338)
			(xy 388.108426 -310.81403) (xy 388.152888 -310.835128) (xy 388.193391 -310.863084) (xy 388.228884 -310.897176)
			(xy 388.258449 -310.93652) (xy 388.28132 -310.980097) (xy 388.296904 -311.026778) (xy 388.304799 -311.075355)
			(xy 388.305294 -311.099962) (xy 389.594102 -311.099962) (xy 389.598062 -311.050908) (xy 389.609839 -311.003124)
			(xy 389.62913 -310.957848) (xy 389.655433 -310.916252) (xy 389.688068 -310.879415) (xy 389.726189 -310.84829)
			(xy 389.76881 -310.823683) (xy 389.814826 -310.806231) (xy 389.863045 -310.796387) (xy 389.91222 -310.794406)
			(xy 389.961075 -310.800338) (xy 390.008346 -310.81403) (xy 390.052808 -310.835128) (xy 390.093311 -310.863084)
			(xy 390.128804 -310.897176) (xy 390.158369 -310.93652) (xy 390.18124 -310.980097) (xy 390.196824 -311.026778)
			(xy 390.204719 -311.075355) (xy 390.205214 -311.099962) (xy 391.494022 -311.099962) (xy 391.497982 -311.050908)
			(xy 391.509759 -311.003124) (xy 391.52905 -310.957848) (xy 391.555353 -310.916252) (xy 391.587988 -310.879415)
			(xy 391.626109 -310.84829) (xy 391.66873 -310.823683) (xy 391.714746 -310.806231) (xy 391.762965 -310.796387)
			(xy 391.81214 -310.794406) (xy 391.860995 -310.800338) (xy 391.908266 -310.81403) (xy 391.952728 -310.835128)
			(xy 391.993231 -310.863084) (xy 392.028724 -310.897176) (xy 392.058289 -310.93652) (xy 392.08116 -310.980097)
			(xy 392.096744 -311.026778) (xy 392.104639 -311.075355) (xy 392.105134 -311.099962) (xy 393.394196 -311.099962)
			(xy 393.398156 -311.050908) (xy 393.409933 -311.003124) (xy 393.429224 -310.957848) (xy 393.455527 -310.916252)
			(xy 393.488162 -310.879415) (xy 393.526283 -310.84829) (xy 393.568904 -310.823683) (xy 393.61492 -310.806231)
			(xy 393.663139 -310.796387) (xy 393.712314 -310.794406) (xy 393.761169 -310.800338) (xy 393.80844 -310.81403)
			(xy 393.852902 -310.835128) (xy 393.893405 -310.863084) (xy 393.928898 -310.897176) (xy 393.958463 -310.93652)
			(xy 393.981334 -310.980097) (xy 393.996918 -311.026778) (xy 394.004813 -311.075355) (xy 394.005308 -311.099962)
			(xy 395.294116 -311.099962) (xy 395.298076 -311.050908) (xy 395.309853 -311.003124) (xy 395.329144 -310.957848)
			(xy 395.355447 -310.916252) (xy 395.388082 -310.879415) (xy 395.426203 -310.84829) (xy 395.468824 -310.823683)
			(xy 395.51484 -310.806231) (xy 395.563059 -310.796387) (xy 395.612234 -310.794406) (xy 395.661089 -310.800338)
			(xy 395.70836 -310.81403) (xy 395.752822 -310.835128) (xy 395.793325 -310.863084) (xy 395.828818 -310.897176)
			(xy 395.858383 -310.93652) (xy 395.881254 -310.980097) (xy 395.896838 -311.026778) (xy 395.904733 -311.075355)
			(xy 395.905228 -311.099962) (xy 397.194036 -311.099962) (xy 397.197996 -311.050908) (xy 397.209773 -311.003124)
			(xy 397.229064 -310.957848) (xy 397.255367 -310.916252) (xy 397.288002 -310.879415) (xy 397.326123 -310.84829)
			(xy 397.368744 -310.823683) (xy 397.41476 -310.806231) (xy 397.462979 -310.796387) (xy 397.512154 -310.794406)
			(xy 397.561009 -310.800338) (xy 397.60828 -310.81403) (xy 397.652742 -310.835128) (xy 397.693245 -310.863084)
			(xy 397.728738 -310.897176) (xy 397.758303 -310.93652) (xy 397.781174 -310.980097) (xy 397.796758 -311.026778)
			(xy 397.804653 -311.075355) (xy 397.805148 -311.099962) (xy 414.294078 -311.099962) (xy 414.298038 -311.050908)
			(xy 414.309815 -311.003124) (xy 414.329106 -310.957848) (xy 414.355409 -310.916252) (xy 414.388044 -310.879415)
			(xy 414.426165 -310.84829) (xy 414.468786 -310.823683) (xy 414.514802 -310.806231) (xy 414.563021 -310.796387)
			(xy 414.612196 -310.794406) (xy 414.661051 -310.800338) (xy 414.708322 -310.81403) (xy 414.752784 -310.835128)
			(xy 414.793287 -310.863084) (xy 414.82878 -310.897176) (xy 414.858345 -310.93652) (xy 414.881216 -310.980097)
			(xy 414.8968 -311.026778) (xy 414.904695 -311.075355) (xy 414.90519 -311.099962) (xy 416.193998 -311.099962)
			(xy 416.197958 -311.050908) (xy 416.209735 -311.003124) (xy 416.229026 -310.957848) (xy 416.255329 -310.916252)
			(xy 416.287964 -310.879415) (xy 416.326085 -310.84829) (xy 416.368706 -310.823683) (xy 416.414722 -310.806231)
			(xy 416.462941 -310.796387) (xy 416.512116 -310.794406) (xy 416.560971 -310.800338) (xy 416.608242 -310.81403)
			(xy 416.652704 -310.835128) (xy 416.693207 -310.863084) (xy 416.7287 -310.897176) (xy 416.758265 -310.93652)
			(xy 416.781136 -310.980097) (xy 416.79672 -311.026778) (xy 416.804615 -311.075355) (xy 416.80511 -311.099962)
			(xy 418.094172 -311.099962) (xy 418.098132 -311.050908) (xy 418.109909 -311.003124) (xy 418.1292 -310.957848)
			(xy 418.155503 -310.916252) (xy 418.188138 -310.879415) (xy 418.226259 -310.84829) (xy 418.26888 -310.823683)
			(xy 418.314896 -310.806231) (xy 418.363115 -310.796387) (xy 418.41229 -310.794406) (xy 418.461145 -310.800338)
			(xy 418.508416 -310.81403) (xy 418.552878 -310.835128) (xy 418.593381 -310.863084) (xy 418.628874 -310.897176)
			(xy 418.658439 -310.93652) (xy 418.68131 -310.980097) (xy 418.696894 -311.026778) (xy 418.704789 -311.075355)
			(xy 418.705284 -311.099962) (xy 419.994092 -311.099962) (xy 419.998052 -311.050908) (xy 420.009829 -311.003124)
			(xy 420.02912 -310.957848) (xy 420.055423 -310.916252) (xy 420.088058 -310.879415) (xy 420.126179 -310.84829)
			(xy 420.1688 -310.823683) (xy 420.214816 -310.806231) (xy 420.263035 -310.796387) (xy 420.31221 -310.794406)
			(xy 420.361065 -310.800338) (xy 420.408336 -310.81403) (xy 420.452798 -310.835128) (xy 420.493301 -310.863084)
			(xy 420.528794 -310.897176) (xy 420.558359 -310.93652) (xy 420.58123 -310.980097) (xy 420.596814 -311.026778)
			(xy 420.604709 -311.075355) (xy 420.605204 -311.099962) (xy 420.604709 -311.124569) (xy 420.596814 -311.173146)
			(xy 420.58123 -311.219827) (xy 420.558359 -311.263404) (xy 420.528794 -311.302748) (xy 420.493301 -311.33684)
			(xy 420.452798 -311.364796) (xy 420.408336 -311.385894) (xy 420.361065 -311.399586) (xy 420.31221 -311.405518)
			(xy 420.263035 -311.403537) (xy 420.214816 -311.393693) (xy 420.1688 -311.376241) (xy 420.126179 -311.351634)
			(xy 420.088058 -311.320509) (xy 420.055423 -311.283672) (xy 420.02912 -311.242076) (xy 420.009829 -311.1968)
			(xy 419.998052 -311.149016) (xy 419.994092 -311.099962) (xy 418.705284 -311.099962) (xy 418.704789 -311.124569)
			(xy 418.696894 -311.173146) (xy 418.68131 -311.219827) (xy 418.658439 -311.263404) (xy 418.628874 -311.302748)
			(xy 418.593381 -311.33684) (xy 418.552878 -311.364796) (xy 418.508416 -311.385894) (xy 418.461145 -311.399586)
			(xy 418.41229 -311.405518) (xy 418.363115 -311.403537) (xy 418.314896 -311.393693) (xy 418.26888 -311.376241)
			(xy 418.226259 -311.351634) (xy 418.188138 -311.320509) (xy 418.155503 -311.283672) (xy 418.1292 -311.242076)
			(xy 418.109909 -311.1968) (xy 418.098132 -311.149016) (xy 418.094172 -311.099962) (xy 416.80511 -311.099962)
			(xy 416.804615 -311.124569) (xy 416.79672 -311.173146) (xy 416.781136 -311.219827) (xy 416.758265 -311.263404)
			(xy 416.7287 -311.302748) (xy 416.693207 -311.33684) (xy 416.652704 -311.364796) (xy 416.608242 -311.385894)
			(xy 416.560971 -311.399586) (xy 416.512116 -311.405518) (xy 416.462941 -311.403537) (xy 416.414722 -311.393693)
			(xy 416.368706 -311.376241) (xy 416.326085 -311.351634) (xy 416.287964 -311.320509) (xy 416.255329 -311.283672)
			(xy 416.229026 -311.242076) (xy 416.209735 -311.1968) (xy 416.197958 -311.149016) (xy 416.193998 -311.099962)
			(xy 414.90519 -311.099962) (xy 414.904695 -311.124569) (xy 414.8968 -311.173146) (xy 414.881216 -311.219827)
			(xy 414.858345 -311.263404) (xy 414.82878 -311.302748) (xy 414.793287 -311.33684) (xy 414.752784 -311.364796)
			(xy 414.708322 -311.385894) (xy 414.661051 -311.399586) (xy 414.612196 -311.405518) (xy 414.563021 -311.403537)
			(xy 414.514802 -311.393693) (xy 414.468786 -311.376241) (xy 414.426165 -311.351634) (xy 414.388044 -311.320509)
			(xy 414.355409 -311.283672) (xy 414.329106 -311.242076) (xy 414.309815 -311.1968) (xy 414.298038 -311.149016)
			(xy 414.294078 -311.099962) (xy 397.805148 -311.099962) (xy 397.804653 -311.124569) (xy 397.796758 -311.173146)
			(xy 397.781174 -311.219827) (xy 397.758303 -311.263404) (xy 397.728738 -311.302748) (xy 397.693245 -311.33684)
			(xy 397.652742 -311.364796) (xy 397.60828 -311.385894) (xy 397.561009 -311.399586) (xy 397.512154 -311.405518)
			(xy 397.462979 -311.403537) (xy 397.41476 -311.393693) (xy 397.368744 -311.376241) (xy 397.326123 -311.351634)
			(xy 397.288002 -311.320509) (xy 397.255367 -311.283672) (xy 397.229064 -311.242076) (xy 397.209773 -311.1968)
			(xy 397.197996 -311.149016) (xy 397.194036 -311.099962) (xy 395.905228 -311.099962) (xy 395.904733 -311.124569)
			(xy 395.896838 -311.173146) (xy 395.881254 -311.219827) (xy 395.858383 -311.263404) (xy 395.828818 -311.302748)
			(xy 395.793325 -311.33684) (xy 395.752822 -311.364796) (xy 395.70836 -311.385894) (xy 395.661089 -311.399586)
			(xy 395.612234 -311.405518) (xy 395.563059 -311.403537) (xy 395.51484 -311.393693) (xy 395.468824 -311.376241)
			(xy 395.426203 -311.351634) (xy 395.388082 -311.320509) (xy 395.355447 -311.283672) (xy 395.329144 -311.242076)
			(xy 395.309853 -311.1968) (xy 395.298076 -311.149016) (xy 395.294116 -311.099962) (xy 394.005308 -311.099962)
			(xy 394.004813 -311.124569) (xy 393.996918 -311.173146) (xy 393.981334 -311.219827) (xy 393.958463 -311.263404)
			(xy 393.928898 -311.302748) (xy 393.893405 -311.33684) (xy 393.852902 -311.364796) (xy 393.80844 -311.385894)
			(xy 393.761169 -311.399586) (xy 393.712314 -311.405518) (xy 393.663139 -311.403537) (xy 393.61492 -311.393693)
			(xy 393.568904 -311.376241) (xy 393.526283 -311.351634) (xy 393.488162 -311.320509) (xy 393.455527 -311.283672)
			(xy 393.429224 -311.242076) (xy 393.409933 -311.1968) (xy 393.398156 -311.149016) (xy 393.394196 -311.099962)
			(xy 392.105134 -311.099962) (xy 392.104639 -311.124569) (xy 392.096744 -311.173146) (xy 392.08116 -311.219827)
			(xy 392.058289 -311.263404) (xy 392.028724 -311.302748) (xy 391.993231 -311.33684) (xy 391.952728 -311.364796)
			(xy 391.908266 -311.385894) (xy 391.860995 -311.399586) (xy 391.81214 -311.405518) (xy 391.762965 -311.403537)
			(xy 391.714746 -311.393693) (xy 391.66873 -311.376241) (xy 391.626109 -311.351634) (xy 391.587988 -311.320509)
			(xy 391.555353 -311.283672) (xy 391.52905 -311.242076) (xy 391.509759 -311.1968) (xy 391.497982 -311.149016)
			(xy 391.494022 -311.099962) (xy 390.205214 -311.099962) (xy 390.204719 -311.124569) (xy 390.196824 -311.173146)
			(xy 390.18124 -311.219827) (xy 390.158369 -311.263404) (xy 390.128804 -311.302748) (xy 390.093311 -311.33684)
			(xy 390.052808 -311.364796) (xy 390.008346 -311.385894) (xy 389.961075 -311.399586) (xy 389.91222 -311.405518)
			(xy 389.863045 -311.403537) (xy 389.814826 -311.393693) (xy 389.76881 -311.376241) (xy 389.726189 -311.351634)
			(xy 389.688068 -311.320509) (xy 389.655433 -311.283672) (xy 389.62913 -311.242076) (xy 389.609839 -311.1968)
			(xy 389.598062 -311.149016) (xy 389.594102 -311.099962) (xy 388.305294 -311.099962) (xy 388.304799 -311.124569)
			(xy 388.296904 -311.173146) (xy 388.28132 -311.219827) (xy 388.258449 -311.263404) (xy 388.228884 -311.302748)
			(xy 388.193391 -311.33684) (xy 388.152888 -311.364796) (xy 388.108426 -311.385894) (xy 388.061155 -311.399586)
			(xy 388.0123 -311.405518) (xy 387.963125 -311.403537) (xy 387.914906 -311.393693) (xy 387.86889 -311.376241)
			(xy 387.826269 -311.351634) (xy 387.788148 -311.320509) (xy 387.755513 -311.283672) (xy 387.72921 -311.242076)
			(xy 387.709919 -311.1968) (xy 387.698142 -311.149016) (xy 387.694182 -311.099962) (xy 312.10504 -311.099962)
			(xy 312.104545 -311.124569) (xy 312.09665 -311.173146) (xy 312.081066 -311.219827) (xy 312.058195 -311.263404)
			(xy 312.02863 -311.302748) (xy 311.993137 -311.33684) (xy 311.952634 -311.364796) (xy 311.908172 -311.385894)
			(xy 311.860901 -311.399586) (xy 311.812046 -311.405518) (xy 311.762871 -311.403537) (xy 311.714652 -311.393693)
			(xy 311.668636 -311.376241) (xy 311.626015 -311.351634) (xy 311.587894 -311.320509) (xy 311.555259 -311.283672)
			(xy 311.528956 -311.242076) (xy 311.509665 -311.1968) (xy 311.497888 -311.149016) (xy 311.493928 -311.099962)
			(xy 310.20512 -311.099962) (xy 310.204625 -311.124569) (xy 310.19673 -311.173146) (xy 310.181146 -311.219827)
			(xy 310.158275 -311.263404) (xy 310.12871 -311.302748) (xy 310.093217 -311.33684) (xy 310.052714 -311.364796)
			(xy 310.008252 -311.385894) (xy 309.960981 -311.399586) (xy 309.912126 -311.405518) (xy 309.862951 -311.403537)
			(xy 309.814732 -311.393693) (xy 309.768716 -311.376241) (xy 309.726095 -311.351634) (xy 309.687974 -311.320509)
			(xy 309.655339 -311.283672) (xy 309.629036 -311.242076) (xy 309.609745 -311.1968) (xy 309.597968 -311.149016)
			(xy 309.594008 -311.099962) (xy 308.3052 -311.099962) (xy 308.304705 -311.124569) (xy 308.29681 -311.173146)
			(xy 308.281226 -311.219827) (xy 308.258355 -311.263404) (xy 308.22879 -311.302748) (xy 308.193297 -311.33684)
			(xy 308.152794 -311.364796) (xy 308.108332 -311.385894) (xy 308.061061 -311.399586) (xy 308.012206 -311.405518)
			(xy 307.963031 -311.403537) (xy 307.914812 -311.393693) (xy 307.868796 -311.376241) (xy 307.826175 -311.351634)
			(xy 307.788054 -311.320509) (xy 307.755419 -311.283672) (xy 307.729116 -311.242076) (xy 307.709825 -311.1968)
			(xy 307.698048 -311.149016) (xy 307.694088 -311.099962) (xy 306.405026 -311.099962) (xy 306.404531 -311.124569)
			(xy 306.396636 -311.173146) (xy 306.381052 -311.219827) (xy 306.358181 -311.263404) (xy 306.328616 -311.302748)
			(xy 306.293123 -311.33684) (xy 306.25262 -311.364796) (xy 306.208158 -311.385894) (xy 306.160887 -311.399586)
			(xy 306.112032 -311.405518) (xy 306.062857 -311.403537) (xy 306.014638 -311.393693) (xy 305.968622 -311.376241)
			(xy 305.926001 -311.351634) (xy 305.88788 -311.320509) (xy 305.855245 -311.283672) (xy 305.828942 -311.242076)
			(xy 305.809651 -311.1968) (xy 305.797874 -311.149016) (xy 305.793914 -311.099962) (xy 289.305238 -311.099962)
			(xy 289.304743 -311.124569) (xy 289.296848 -311.173146) (xy 289.281264 -311.219827) (xy 289.258393 -311.263404)
			(xy 289.228828 -311.302748) (xy 289.193335 -311.33684) (xy 289.152832 -311.364796) (xy 289.10837 -311.385894)
			(xy 289.061099 -311.399586) (xy 289.012244 -311.405518) (xy 288.963069 -311.403537) (xy 288.91485 -311.393693)
			(xy 288.868834 -311.376241) (xy 288.826213 -311.351634) (xy 288.788092 -311.320509) (xy 288.755457 -311.283672)
			(xy 288.729154 -311.242076) (xy 288.709863 -311.1968) (xy 288.698086 -311.149016) (xy 288.694126 -311.099962)
			(xy 287.405064 -311.099962) (xy 287.404569 -311.124569) (xy 287.396674 -311.173146) (xy 287.38109 -311.219827)
			(xy 287.358219 -311.263404) (xy 287.328654 -311.302748) (xy 287.293161 -311.33684) (xy 287.252658 -311.364796)
			(xy 287.208196 -311.385894) (xy 287.160925 -311.399586) (xy 287.11207 -311.405518) (xy 287.062895 -311.403537)
			(xy 287.014676 -311.393693) (xy 286.96866 -311.376241) (xy 286.926039 -311.351634) (xy 286.887918 -311.320509)
			(xy 286.855283 -311.283672) (xy 286.82898 -311.242076) (xy 286.809689 -311.1968) (xy 286.797912 -311.149016)
			(xy 286.793952 -311.099962) (xy 285.505144 -311.099962) (xy 285.504649 -311.124569) (xy 285.496754 -311.173146)
			(xy 285.48117 -311.219827) (xy 285.458299 -311.263404) (xy 285.428734 -311.302748) (xy 285.393241 -311.33684)
			(xy 285.352738 -311.364796) (xy 285.308276 -311.385894) (xy 285.261005 -311.399586) (xy 285.21215 -311.405518)
			(xy 285.162975 -311.403537) (xy 285.114756 -311.393693) (xy 285.06874 -311.376241) (xy 285.026119 -311.351634)
			(xy 284.987998 -311.320509) (xy 284.955363 -311.283672) (xy 284.92906 -311.242076) (xy 284.909769 -311.1968)
			(xy 284.897992 -311.149016) (xy 284.894032 -311.099962) (xy 283.605224 -311.099962) (xy 283.604729 -311.124569)
			(xy 283.596834 -311.173146) (xy 283.58125 -311.219827) (xy 283.558379 -311.263404) (xy 283.528814 -311.302748)
			(xy 283.493321 -311.33684) (xy 283.452818 -311.364796) (xy 283.408356 -311.385894) (xy 283.361085 -311.399586)
			(xy 283.31223 -311.405518) (xy 283.263055 -311.403537) (xy 283.214836 -311.393693) (xy 283.16882 -311.376241)
			(xy 283.126199 -311.351634) (xy 283.088078 -311.320509) (xy 283.055443 -311.283672) (xy 283.02914 -311.242076)
			(xy 283.009849 -311.1968) (xy 282.998072 -311.149016) (xy 282.994112 -311.099962) (xy 281.70505 -311.099962)
			(xy 281.704555 -311.124569) (xy 281.69666 -311.173146) (xy 281.681076 -311.219827) (xy 281.658205 -311.263404)
			(xy 281.62864 -311.302748) (xy 281.593147 -311.33684) (xy 281.552644 -311.364796) (xy 281.508182 -311.385894)
			(xy 281.460911 -311.399586) (xy 281.412056 -311.405518) (xy 281.362881 -311.403537) (xy 281.314662 -311.393693)
			(xy 281.268646 -311.376241) (xy 281.226025 -311.351634) (xy 281.187904 -311.320509) (xy 281.155269 -311.283672)
			(xy 281.128966 -311.242076) (xy 281.109675 -311.1968) (xy 281.097898 -311.149016) (xy 281.093938 -311.099962)
			(xy 279.80513 -311.099962) (xy 279.804635 -311.124569) (xy 279.79674 -311.173146) (xy 279.781156 -311.219827)
			(xy 279.758285 -311.263404) (xy 279.72872 -311.302748) (xy 279.693227 -311.33684) (xy 279.652724 -311.364796)
			(xy 279.608262 -311.385894) (xy 279.560991 -311.399586) (xy 279.512136 -311.405518) (xy 279.462961 -311.403537)
			(xy 279.414742 -311.393693) (xy 279.368726 -311.376241) (xy 279.326105 -311.351634) (xy 279.287984 -311.320509)
			(xy 279.255349 -311.283672) (xy 279.229046 -311.242076) (xy 279.209755 -311.1968) (xy 279.197978 -311.149016)
			(xy 279.194018 -311.099962) (xy 277.90521 -311.099962) (xy 277.904715 -311.124569) (xy 277.89682 -311.173146)
			(xy 277.881236 -311.219827) (xy 277.858365 -311.263404) (xy 277.8288 -311.302748) (xy 277.793307 -311.33684)
			(xy 277.752804 -311.364796) (xy 277.708342 -311.385894) (xy 277.661071 -311.399586) (xy 277.612216 -311.405518)
			(xy 277.563041 -311.403537) (xy 277.514822 -311.393693) (xy 277.468806 -311.376241) (xy 277.426185 -311.351634)
			(xy 277.388064 -311.320509) (xy 277.355429 -311.283672) (xy 277.329126 -311.242076) (xy 277.309835 -311.1968)
			(xy 277.298058 -311.149016) (xy 277.294098 -311.099962) (xy 276.005036 -311.099962) (xy 276.004541 -311.124569)
			(xy 275.996646 -311.173146) (xy 275.981062 -311.219827) (xy 275.958191 -311.263404) (xy 275.928626 -311.302748)
			(xy 275.893133 -311.33684) (xy 275.85263 -311.364796) (xy 275.808168 -311.385894) (xy 275.760897 -311.399586)
			(xy 275.712042 -311.405518) (xy 275.662867 -311.403537) (xy 275.614648 -311.393693) (xy 275.568632 -311.376241)
			(xy 275.526011 -311.351634) (xy 275.48789 -311.320509) (xy 275.455255 -311.283672) (xy 275.428952 -311.242076)
			(xy 275.409661 -311.1968) (xy 275.397884 -311.149016) (xy 275.393924 -311.099962) (xy 188.405262 -311.099962)
			(xy 188.404767 -311.124569) (xy 188.396872 -311.173146) (xy 188.381288 -311.219827) (xy 188.358417 -311.263404)
			(xy 188.328852 -311.302748) (xy 188.293359 -311.33684) (xy 188.252856 -311.364796) (xy 188.208394 -311.385894)
			(xy 188.161123 -311.399586) (xy 188.112268 -311.405518) (xy 188.063093 -311.403537) (xy 188.014874 -311.393693)
			(xy 187.968858 -311.376241) (xy 187.926237 -311.351634) (xy 187.888116 -311.320509) (xy 187.855481 -311.283672)
			(xy 187.829178 -311.242076) (xy 187.809887 -311.1968) (xy 187.79811 -311.149016) (xy 187.79415 -311.099962)
			(xy 186.505342 -311.099962) (xy 186.504847 -311.124569) (xy 186.496952 -311.173146) (xy 186.481368 -311.219827)
			(xy 186.458497 -311.263404) (xy 186.428932 -311.302748) (xy 186.393439 -311.33684) (xy 186.352936 -311.364796)
			(xy 186.308474 -311.385894) (xy 186.261203 -311.399586) (xy 186.212348 -311.405518) (xy 186.163173 -311.403537)
			(xy 186.114954 -311.393693) (xy 186.068938 -311.376241) (xy 186.026317 -311.351634) (xy 185.988196 -311.320509)
			(xy 185.955561 -311.283672) (xy 185.929258 -311.242076) (xy 185.909967 -311.1968) (xy 185.89819 -311.149016)
			(xy 185.89423 -311.099962) (xy 184.605168 -311.099962) (xy 184.604673 -311.124569) (xy 184.596778 -311.173146)
			(xy 184.581194 -311.219827) (xy 184.558323 -311.263404) (xy 184.528758 -311.302748) (xy 184.493265 -311.33684)
			(xy 184.452762 -311.364796) (xy 184.4083 -311.385894) (xy 184.361029 -311.399586) (xy 184.312174 -311.405518)
			(xy 184.262999 -311.403537) (xy 184.21478 -311.393693) (xy 184.168764 -311.376241) (xy 184.126143 -311.351634)
			(xy 184.088022 -311.320509) (xy 184.055387 -311.283672) (xy 184.029084 -311.242076) (xy 184.009793 -311.1968)
			(xy 183.998016 -311.149016) (xy 183.994056 -311.099962) (xy 182.705248 -311.099962) (xy 182.704753 -311.124569)
			(xy 182.696858 -311.173146) (xy 182.681274 -311.219827) (xy 182.658403 -311.263404) (xy 182.628838 -311.302748)
			(xy 182.593345 -311.33684) (xy 182.552842 -311.364796) (xy 182.50838 -311.385894) (xy 182.461109 -311.399586)
			(xy 182.412254 -311.405518) (xy 182.363079 -311.403537) (xy 182.31486 -311.393693) (xy 182.268844 -311.376241)
			(xy 182.226223 -311.351634) (xy 182.188102 -311.320509) (xy 182.155467 -311.283672) (xy 182.129164 -311.242076)
			(xy 182.109873 -311.1968) (xy 182.098096 -311.149016) (xy 182.094136 -311.099962) (xy 165.605206 -311.099962)
			(xy 165.604711 -311.124569) (xy 165.596816 -311.173146) (xy 165.581232 -311.219827) (xy 165.558361 -311.263404)
			(xy 165.528796 -311.302748) (xy 165.493303 -311.33684) (xy 165.4528 -311.364796) (xy 165.408338 -311.385894)
			(xy 165.361067 -311.399586) (xy 165.312212 -311.405518) (xy 165.263037 -311.403537) (xy 165.214818 -311.393693)
			(xy 165.168802 -311.376241) (xy 165.126181 -311.351634) (xy 165.08806 -311.320509) (xy 165.055425 -311.283672)
			(xy 165.029122 -311.242076) (xy 165.009831 -311.1968) (xy 164.998054 -311.149016) (xy 164.994094 -311.099962)
			(xy 163.705286 -311.099962) (xy 163.704791 -311.124569) (xy 163.696896 -311.173146) (xy 163.681312 -311.219827)
			(xy 163.658441 -311.263404) (xy 163.628876 -311.302748) (xy 163.593383 -311.33684) (xy 163.55288 -311.364796)
			(xy 163.508418 -311.385894) (xy 163.461147 -311.399586) (xy 163.412292 -311.405518) (xy 163.363117 -311.403537)
			(xy 163.314898 -311.393693) (xy 163.268882 -311.376241) (xy 163.226261 -311.351634) (xy 163.18814 -311.320509)
			(xy 163.155505 -311.283672) (xy 163.129202 -311.242076) (xy 163.109911 -311.1968) (xy 163.098134 -311.149016)
			(xy 163.094174 -311.099962) (xy 161.805366 -311.099962) (xy 161.804871 -311.124569) (xy 161.796976 -311.173146)
			(xy 161.781392 -311.219827) (xy 161.758521 -311.263404) (xy 161.728956 -311.302748) (xy 161.693463 -311.33684)
			(xy 161.65296 -311.364796) (xy 161.608498 -311.385894) (xy 161.561227 -311.399586) (xy 161.512372 -311.405518)
			(xy 161.463197 -311.403537) (xy 161.414978 -311.393693) (xy 161.368962 -311.376241) (xy 161.326341 -311.351634)
			(xy 161.28822 -311.320509) (xy 161.255585 -311.283672) (xy 161.229282 -311.242076) (xy 161.209991 -311.1968)
			(xy 161.198214 -311.149016) (xy 161.194254 -311.099962) (xy 159.905192 -311.099962) (xy 159.904697 -311.124569)
			(xy 159.896802 -311.173146) (xy 159.881218 -311.219827) (xy 159.858347 -311.263404) (xy 159.828782 -311.302748)
			(xy 159.793289 -311.33684) (xy 159.752786 -311.364796) (xy 159.708324 -311.385894) (xy 159.661053 -311.399586)
			(xy 159.612198 -311.405518) (xy 159.563023 -311.403537) (xy 159.514804 -311.393693) (xy 159.468788 -311.376241)
			(xy 159.426167 -311.351634) (xy 159.388046 -311.320509) (xy 159.355411 -311.283672) (xy 159.329108 -311.242076)
			(xy 159.309817 -311.1968) (xy 159.29804 -311.149016) (xy 159.29408 -311.099962) (xy 158.005272 -311.099962)
			(xy 158.004777 -311.124569) (xy 157.996882 -311.173146) (xy 157.981298 -311.219827) (xy 157.958427 -311.263404)
			(xy 157.928862 -311.302748) (xy 157.893369 -311.33684) (xy 157.852866 -311.364796) (xy 157.808404 -311.385894)
			(xy 157.761133 -311.399586) (xy 157.712278 -311.405518) (xy 157.663103 -311.403537) (xy 157.614884 -311.393693)
			(xy 157.568868 -311.376241) (xy 157.526247 -311.351634) (xy 157.488126 -311.320509) (xy 157.455491 -311.283672)
			(xy 157.429188 -311.242076) (xy 157.409897 -311.1968) (xy 157.39812 -311.149016) (xy 157.39416 -311.099962)
			(xy 156.105352 -311.099962) (xy 156.104857 -311.124569) (xy 156.096962 -311.173146) (xy 156.081378 -311.219827)
			(xy 156.058507 -311.263404) (xy 156.028942 -311.302748) (xy 155.993449 -311.33684) (xy 155.952946 -311.364796)
			(xy 155.908484 -311.385894) (xy 155.861213 -311.399586) (xy 155.812358 -311.405518) (xy 155.763183 -311.403537)
			(xy 155.714964 -311.393693) (xy 155.668948 -311.376241) (xy 155.626327 -311.351634) (xy 155.588206 -311.320509)
			(xy 155.555571 -311.283672) (xy 155.529268 -311.242076) (xy 155.509977 -311.1968) (xy 155.4982 -311.149016)
			(xy 155.49424 -311.099962) (xy 79.905098 -311.099962) (xy 79.904603 -311.124569) (xy 79.896708 -311.173146)
			(xy 79.881124 -311.219827) (xy 79.858253 -311.263404) (xy 79.828688 -311.302748) (xy 79.793195 -311.33684)
			(xy 79.752692 -311.364796) (xy 79.70823 -311.385894) (xy 79.660959 -311.399586) (xy 79.612104 -311.405518)
			(xy 79.562929 -311.403537) (xy 79.51471 -311.393693) (xy 79.468694 -311.376241) (xy 79.426073 -311.351634)
			(xy 79.387952 -311.320509) (xy 79.355317 -311.283672) (xy 79.329014 -311.242076) (xy 79.309723 -311.1968)
			(xy 79.297946 -311.149016) (xy 79.293986 -311.099962) (xy 78.005178 -311.099962) (xy 78.004683 -311.124569)
			(xy 77.996788 -311.173146) (xy 77.981204 -311.219827) (xy 77.958333 -311.263404) (xy 77.928768 -311.302748)
			(xy 77.893275 -311.33684) (xy 77.852772 -311.364796) (xy 77.80831 -311.385894) (xy 77.761039 -311.399586)
			(xy 77.712184 -311.405518) (xy 77.663009 -311.403537) (xy 77.61479 -311.393693) (xy 77.568774 -311.376241)
			(xy 77.526153 -311.351634) (xy 77.488032 -311.320509) (xy 77.455397 -311.283672) (xy 77.429094 -311.242076)
			(xy 77.409803 -311.1968) (xy 77.398026 -311.149016) (xy 77.394066 -311.099962) (xy 76.105258 -311.099962)
			(xy 76.104763 -311.124569) (xy 76.096868 -311.173146) (xy 76.081284 -311.219827) (xy 76.058413 -311.263404)
			(xy 76.028848 -311.302748) (xy 75.993355 -311.33684) (xy 75.952852 -311.364796) (xy 75.90839 -311.385894)
			(xy 75.861119 -311.399586) (xy 75.812264 -311.405518) (xy 75.763089 -311.403537) (xy 75.71487 -311.393693)
			(xy 75.668854 -311.376241) (xy 75.626233 -311.351634) (xy 75.588112 -311.320509) (xy 75.555477 -311.283672)
			(xy 75.529174 -311.242076) (xy 75.509883 -311.1968) (xy 75.498106 -311.149016) (xy 75.494146 -311.099962)
			(xy 74.205084 -311.099962) (xy 74.204589 -311.124569) (xy 74.196694 -311.173146) (xy 74.18111 -311.219827)
			(xy 74.158239 -311.263404) (xy 74.128674 -311.302748) (xy 74.093181 -311.33684) (xy 74.052678 -311.364796)
			(xy 74.008216 -311.385894) (xy 73.960945 -311.399586) (xy 73.91209 -311.405518) (xy 73.862915 -311.403537)
			(xy 73.814696 -311.393693) (xy 73.76868 -311.376241) (xy 73.726059 -311.351634) (xy 73.687938 -311.320509)
			(xy 73.655303 -311.283672) (xy 73.629 -311.242076) (xy 73.609709 -311.1968) (xy 73.597932 -311.149016)
			(xy 73.593972 -311.099962) (xy 57.105296 -311.099962) (xy 57.104801 -311.124569) (xy 57.096906 -311.173146)
			(xy 57.081322 -311.219827) (xy 57.058451 -311.263404) (xy 57.028886 -311.302748) (xy 56.993393 -311.33684)
			(xy 56.95289 -311.364796) (xy 56.908428 -311.385894) (xy 56.861157 -311.399586) (xy 56.812302 -311.405518)
			(xy 56.763127 -311.403537) (xy 56.714908 -311.393693) (xy 56.668892 -311.376241) (xy 56.626271 -311.351634)
			(xy 56.58815 -311.320509) (xy 56.555515 -311.283672) (xy 56.529212 -311.242076) (xy 56.509921 -311.1968)
			(xy 56.498144 -311.149016) (xy 56.494184 -311.099962) (xy 55.205122 -311.099962) (xy 55.204627 -311.124569)
			(xy 55.196732 -311.173146) (xy 55.181148 -311.219827) (xy 55.158277 -311.263404) (xy 55.128712 -311.302748)
			(xy 55.093219 -311.33684) (xy 55.052716 -311.364796) (xy 55.008254 -311.385894) (xy 54.960983 -311.399586)
			(xy 54.912128 -311.405518) (xy 54.862953 -311.403537) (xy 54.814734 -311.393693) (xy 54.768718 -311.376241)
			(xy 54.726097 -311.351634) (xy 54.687976 -311.320509) (xy 54.655341 -311.283672) (xy 54.629038 -311.242076)
			(xy 54.609747 -311.1968) (xy 54.59797 -311.149016) (xy 54.59401 -311.099962) (xy 53.305202 -311.099962)
			(xy 53.304707 -311.124569) (xy 53.296812 -311.173146) (xy 53.281228 -311.219827) (xy 53.258357 -311.263404)
			(xy 53.228792 -311.302748) (xy 53.193299 -311.33684) (xy 53.152796 -311.364796) (xy 53.108334 -311.385894)
			(xy 53.061063 -311.399586) (xy 53.012208 -311.405518) (xy 52.963033 -311.403537) (xy 52.914814 -311.393693)
			(xy 52.868798 -311.376241) (xy 52.826177 -311.351634) (xy 52.788056 -311.320509) (xy 52.755421 -311.283672)
			(xy 52.729118 -311.242076) (xy 52.709827 -311.1968) (xy 52.69805 -311.149016) (xy 52.69409 -311.099962)
			(xy 51.405282 -311.099962) (xy 51.404787 -311.124569) (xy 51.396892 -311.173146) (xy 51.381308 -311.219827)
			(xy 51.358437 -311.263404) (xy 51.328872 -311.302748) (xy 51.293379 -311.33684) (xy 51.252876 -311.364796)
			(xy 51.208414 -311.385894) (xy 51.161143 -311.399586) (xy 51.112288 -311.405518) (xy 51.063113 -311.403537)
			(xy 51.014894 -311.393693) (xy 50.968878 -311.376241) (xy 50.926257 -311.351634) (xy 50.888136 -311.320509)
			(xy 50.855501 -311.283672) (xy 50.829198 -311.242076) (xy 50.809907 -311.1968) (xy 50.79813 -311.149016)
			(xy 50.79417 -311.099962) (xy 49.505108 -311.099962) (xy 49.504613 -311.124569) (xy 49.496718 -311.173146)
			(xy 49.481134 -311.219827) (xy 49.458263 -311.263404) (xy 49.428698 -311.302748) (xy 49.393205 -311.33684)
			(xy 49.352702 -311.364796) (xy 49.30824 -311.385894) (xy 49.260969 -311.399586) (xy 49.212114 -311.405518)
			(xy 49.162939 -311.403537) (xy 49.11472 -311.393693) (xy 49.068704 -311.376241) (xy 49.026083 -311.351634)
			(xy 48.987962 -311.320509) (xy 48.955327 -311.283672) (xy 48.929024 -311.242076) (xy 48.909733 -311.1968)
			(xy 48.897956 -311.149016) (xy 48.893996 -311.099962) (xy 47.605188 -311.099962) (xy 47.604693 -311.124569)
			(xy 47.596798 -311.173146) (xy 47.581214 -311.219827) (xy 47.558343 -311.263404) (xy 47.528778 -311.302748)
			(xy 47.493285 -311.33684) (xy 47.452782 -311.364796) (xy 47.40832 -311.385894) (xy 47.361049 -311.399586)
			(xy 47.312194 -311.405518) (xy 47.263019 -311.403537) (xy 47.2148 -311.393693) (xy 47.168784 -311.376241)
			(xy 47.126163 -311.351634) (xy 47.088042 -311.320509) (xy 47.055407 -311.283672) (xy 47.029104 -311.242076)
			(xy 47.009813 -311.1968) (xy 46.998036 -311.149016) (xy 46.994076 -311.099962) (xy 45.705268 -311.099962)
			(xy 45.704773 -311.124569) (xy 45.696878 -311.173146) (xy 45.681294 -311.219827) (xy 45.658423 -311.263404)
			(xy 45.628858 -311.302748) (xy 45.593365 -311.33684) (xy 45.552862 -311.364796) (xy 45.5084 -311.385894)
			(xy 45.461129 -311.399586) (xy 45.412274 -311.405518) (xy 45.363099 -311.403537) (xy 45.31488 -311.393693)
			(xy 45.268864 -311.376241) (xy 45.226243 -311.351634) (xy 45.188122 -311.320509) (xy 45.155487 -311.283672)
			(xy 45.129184 -311.242076) (xy 45.109893 -311.1968) (xy 45.098116 -311.149016) (xy 45.094156 -311.099962)
			(xy 43.805094 -311.099962) (xy 43.804599 -311.124569) (xy 43.796704 -311.173146) (xy 43.78112 -311.219827)
			(xy 43.758249 -311.263404) (xy 43.728684 -311.302748) (xy 43.693191 -311.33684) (xy 43.652688 -311.364796)
			(xy 43.608226 -311.385894) (xy 43.560955 -311.399586) (xy 43.5121 -311.405518) (xy 43.462925 -311.403537)
			(xy 43.414706 -311.393693) (xy 43.36869 -311.376241) (xy 43.326069 -311.351634) (xy 43.287948 -311.320509)
			(xy 43.255313 -311.283672) (xy 43.22901 -311.242076) (xy 43.209719 -311.1968) (xy 43.197942 -311.149016)
			(xy 43.193982 -311.099962) (xy 0.508 -311.099962) (xy 0.508 -312.049922) (xy 43.193982 -312.049922)
			(xy 43.197942 -312.000868) (xy 43.209719 -311.953084) (xy 43.22901 -311.907808) (xy 43.255313 -311.866212)
			(xy 43.287948 -311.829375) (xy 43.326069 -311.79825) (xy 43.36869 -311.773643) (xy 43.414706 -311.756191)
			(xy 43.462925 -311.746347) (xy 43.5121 -311.744366) (xy 43.560955 -311.750298) (xy 43.608226 -311.76399)
			(xy 43.652688 -311.785088) (xy 43.693191 -311.813044) (xy 43.728684 -311.847136) (xy 43.758249 -311.88648)
			(xy 43.78112 -311.930057) (xy 43.796704 -311.976738) (xy 43.804599 -312.025315) (xy 43.805094 -312.049922)
			(xy 45.094156 -312.049922) (xy 45.098116 -312.000868) (xy 45.109893 -311.953084) (xy 45.129184 -311.907808)
			(xy 45.155487 -311.866212) (xy 45.188122 -311.829375) (xy 45.226243 -311.79825) (xy 45.268864 -311.773643)
			(xy 45.31488 -311.756191) (xy 45.363099 -311.746347) (xy 45.412274 -311.744366) (xy 45.461129 -311.750298)
			(xy 45.5084 -311.76399) (xy 45.552862 -311.785088) (xy 45.593365 -311.813044) (xy 45.628858 -311.847136)
			(xy 45.658423 -311.88648) (xy 45.681294 -311.930057) (xy 45.696878 -311.976738) (xy 45.704773 -312.025315)
			(xy 45.705268 -312.049922) (xy 46.994076 -312.049922) (xy 46.998036 -312.000868) (xy 47.009813 -311.953084)
			(xy 47.029104 -311.907808) (xy 47.055407 -311.866212) (xy 47.088042 -311.829375) (xy 47.126163 -311.79825)
			(xy 47.168784 -311.773643) (xy 47.2148 -311.756191) (xy 47.263019 -311.746347) (xy 47.312194 -311.744366)
			(xy 47.361049 -311.750298) (xy 47.40832 -311.76399) (xy 47.452782 -311.785088) (xy 47.493285 -311.813044)
			(xy 47.528778 -311.847136) (xy 47.558343 -311.88648) (xy 47.581214 -311.930057) (xy 47.596798 -311.976738)
			(xy 47.604693 -312.025315) (xy 47.605188 -312.049922) (xy 48.893996 -312.049922) (xy 48.897956 -312.000868)
			(xy 48.909733 -311.953084) (xy 48.929024 -311.907808) (xy 48.955327 -311.866212) (xy 48.987962 -311.829375)
			(xy 49.026083 -311.79825) (xy 49.068704 -311.773643) (xy 49.11472 -311.756191) (xy 49.162939 -311.746347)
			(xy 49.212114 -311.744366) (xy 49.260969 -311.750298) (xy 49.30824 -311.76399) (xy 49.352702 -311.785088)
			(xy 49.393205 -311.813044) (xy 49.428698 -311.847136) (xy 49.458263 -311.88648) (xy 49.481134 -311.930057)
			(xy 49.496718 -311.976738) (xy 49.504613 -312.025315) (xy 49.505108 -312.049922) (xy 50.79417 -312.049922)
			(xy 50.79813 -312.000868) (xy 50.809907 -311.953084) (xy 50.829198 -311.907808) (xy 50.855501 -311.866212)
			(xy 50.888136 -311.829375) (xy 50.926257 -311.79825) (xy 50.968878 -311.773643) (xy 51.014894 -311.756191)
			(xy 51.063113 -311.746347) (xy 51.112288 -311.744366) (xy 51.161143 -311.750298) (xy 51.208414 -311.76399)
			(xy 51.252876 -311.785088) (xy 51.293379 -311.813044) (xy 51.328872 -311.847136) (xy 51.358437 -311.88648)
			(xy 51.381308 -311.930057) (xy 51.396892 -311.976738) (xy 51.404787 -312.025315) (xy 51.405282 -312.049922)
			(xy 52.69409 -312.049922) (xy 52.69805 -312.000868) (xy 52.709827 -311.953084) (xy 52.729118 -311.907808)
			(xy 52.755421 -311.866212) (xy 52.788056 -311.829375) (xy 52.826177 -311.79825) (xy 52.868798 -311.773643)
			(xy 52.914814 -311.756191) (xy 52.963033 -311.746347) (xy 53.012208 -311.744366) (xy 53.061063 -311.750298)
			(xy 53.108334 -311.76399) (xy 53.152796 -311.785088) (xy 53.193299 -311.813044) (xy 53.228792 -311.847136)
			(xy 53.258357 -311.88648) (xy 53.281228 -311.930057) (xy 53.296812 -311.976738) (xy 53.304707 -312.025315)
			(xy 53.305202 -312.049922) (xy 54.59401 -312.049922) (xy 54.59797 -312.000868) (xy 54.609747 -311.953084)
			(xy 54.629038 -311.907808) (xy 54.655341 -311.866212) (xy 54.687976 -311.829375) (xy 54.726097 -311.79825)
			(xy 54.768718 -311.773643) (xy 54.814734 -311.756191) (xy 54.862953 -311.746347) (xy 54.912128 -311.744366)
			(xy 54.960983 -311.750298) (xy 55.008254 -311.76399) (xy 55.052716 -311.785088) (xy 55.093219 -311.813044)
			(xy 55.128712 -311.847136) (xy 55.158277 -311.88648) (xy 55.181148 -311.930057) (xy 55.196732 -311.976738)
			(xy 55.204627 -312.025315) (xy 55.205122 -312.049922) (xy 56.494184 -312.049922) (xy 56.498144 -312.000868)
			(xy 56.509921 -311.953084) (xy 56.529212 -311.907808) (xy 56.555515 -311.866212) (xy 56.58815 -311.829375)
			(xy 56.626271 -311.79825) (xy 56.668892 -311.773643) (xy 56.714908 -311.756191) (xy 56.763127 -311.746347)
			(xy 56.812302 -311.744366) (xy 56.861157 -311.750298) (xy 56.908428 -311.76399) (xy 56.95289 -311.785088)
			(xy 56.993393 -311.813044) (xy 57.028886 -311.847136) (xy 57.058451 -311.88648) (xy 57.081322 -311.930057)
			(xy 57.096906 -311.976738) (xy 57.104801 -312.025315) (xy 57.105296 -312.049922) (xy 73.593972 -312.049922)
			(xy 73.597932 -312.000868) (xy 73.609709 -311.953084) (xy 73.629 -311.907808) (xy 73.655303 -311.866212)
			(xy 73.687938 -311.829375) (xy 73.726059 -311.79825) (xy 73.76868 -311.773643) (xy 73.814696 -311.756191)
			(xy 73.862915 -311.746347) (xy 73.91209 -311.744366) (xy 73.960945 -311.750298) (xy 74.008216 -311.76399)
			(xy 74.052678 -311.785088) (xy 74.093181 -311.813044) (xy 74.128674 -311.847136) (xy 74.158239 -311.88648)
			(xy 74.18111 -311.930057) (xy 74.196694 -311.976738) (xy 74.204589 -312.025315) (xy 74.205084 -312.049922)
			(xy 75.494146 -312.049922) (xy 75.498106 -312.000868) (xy 75.509883 -311.953084) (xy 75.529174 -311.907808)
			(xy 75.555477 -311.866212) (xy 75.588112 -311.829375) (xy 75.626233 -311.79825) (xy 75.668854 -311.773643)
			(xy 75.71487 -311.756191) (xy 75.763089 -311.746347) (xy 75.812264 -311.744366) (xy 75.861119 -311.750298)
			(xy 75.90839 -311.76399) (xy 75.952852 -311.785088) (xy 75.993355 -311.813044) (xy 76.028848 -311.847136)
			(xy 76.058413 -311.88648) (xy 76.081284 -311.930057) (xy 76.096868 -311.976738) (xy 76.104763 -312.025315)
			(xy 76.105258 -312.049922) (xy 77.394066 -312.049922) (xy 77.398026 -312.000868) (xy 77.409803 -311.953084)
			(xy 77.429094 -311.907808) (xy 77.455397 -311.866212) (xy 77.488032 -311.829375) (xy 77.526153 -311.79825)
			(xy 77.568774 -311.773643) (xy 77.61479 -311.756191) (xy 77.663009 -311.746347) (xy 77.712184 -311.744366)
			(xy 77.761039 -311.750298) (xy 77.80831 -311.76399) (xy 77.852772 -311.785088) (xy 77.893275 -311.813044)
			(xy 77.928768 -311.847136) (xy 77.958333 -311.88648) (xy 77.981204 -311.930057) (xy 77.996788 -311.976738)
			(xy 78.004683 -312.025315) (xy 78.005178 -312.049922) (xy 79.293986 -312.049922) (xy 79.297946 -312.000868)
			(xy 79.309723 -311.953084) (xy 79.329014 -311.907808) (xy 79.355317 -311.866212) (xy 79.387952 -311.829375)
			(xy 79.426073 -311.79825) (xy 79.468694 -311.773643) (xy 79.51471 -311.756191) (xy 79.562929 -311.746347)
			(xy 79.612104 -311.744366) (xy 79.660959 -311.750298) (xy 79.70823 -311.76399) (xy 79.752692 -311.785088)
			(xy 79.793195 -311.813044) (xy 79.828688 -311.847136) (xy 79.858253 -311.88648) (xy 79.881124 -311.930057)
			(xy 79.896708 -311.976738) (xy 79.904603 -312.025315) (xy 79.905098 -312.049922) (xy 81.19416 -312.049922)
			(xy 81.19812 -312.000868) (xy 81.209897 -311.953084) (xy 81.229188 -311.907808) (xy 81.255491 -311.866212)
			(xy 81.288126 -311.829375) (xy 81.326247 -311.79825) (xy 81.368868 -311.773643) (xy 81.414884 -311.756191)
			(xy 81.463103 -311.746347) (xy 81.512278 -311.744366) (xy 81.561133 -311.750298) (xy 81.608404 -311.76399)
			(xy 81.652866 -311.785088) (xy 81.693369 -311.813044) (xy 81.728862 -311.847136) (xy 81.758427 -311.88648)
			(xy 81.781298 -311.930057) (xy 81.796882 -311.976738) (xy 81.804777 -312.025315) (xy 81.805272 -312.049922)
			(xy 82.14412 -312.049922) (xy 82.14808 -312.000868) (xy 82.159857 -311.953084) (xy 82.179148 -311.907808)
			(xy 82.205451 -311.866212) (xy 82.238086 -311.829375) (xy 82.276207 -311.79825) (xy 82.318828 -311.773643)
			(xy 82.364844 -311.756191) (xy 82.413063 -311.746347) (xy 82.462238 -311.744366) (xy 82.511093 -311.750298)
			(xy 82.558364 -311.76399) (xy 82.602826 -311.785088) (xy 82.643329 -311.813044) (xy 82.678822 -311.847136)
			(xy 82.708387 -311.88648) (xy 82.731258 -311.930057) (xy 82.746842 -311.976738) (xy 82.754737 -312.025315)
			(xy 82.755232 -312.049922) (xy 152.644106 -312.049922) (xy 152.648066 -312.000868) (xy 152.659843 -311.953084)
			(xy 152.679134 -311.907808) (xy 152.705437 -311.866212) (xy 152.738072 -311.829375) (xy 152.776193 -311.79825)
			(xy 152.818814 -311.773643) (xy 152.86483 -311.756191) (xy 152.913049 -311.746347) (xy 152.962224 -311.744366)
			(xy 153.011079 -311.750298) (xy 153.05835 -311.76399) (xy 153.102812 -311.785088) (xy 153.143315 -311.813044)
			(xy 153.178808 -311.847136) (xy 153.208373 -311.88648) (xy 153.231244 -311.930057) (xy 153.246828 -311.976738)
			(xy 153.254723 -312.025315) (xy 153.255218 -312.049922) (xy 153.594066 -312.049922) (xy 153.598026 -312.000868)
			(xy 153.609803 -311.953084) (xy 153.629094 -311.907808) (xy 153.655397 -311.866212) (xy 153.688032 -311.829375)
			(xy 153.726153 -311.79825) (xy 153.768774 -311.773643) (xy 153.81479 -311.756191) (xy 153.863009 -311.746347)
			(xy 153.912184 -311.744366) (xy 153.961039 -311.750298) (xy 154.00831 -311.76399) (xy 154.052772 -311.785088)
			(xy 154.093275 -311.813044) (xy 154.128768 -311.847136) (xy 154.158333 -311.88648) (xy 154.181204 -311.930057)
			(xy 154.196788 -311.976738) (xy 154.204683 -312.025315) (xy 154.205178 -312.049922) (xy 155.49424 -312.049922)
			(xy 155.4982 -312.000868) (xy 155.509977 -311.953084) (xy 155.529268 -311.907808) (xy 155.555571 -311.866212)
			(xy 155.588206 -311.829375) (xy 155.626327 -311.79825) (xy 155.668948 -311.773643) (xy 155.714964 -311.756191)
			(xy 155.763183 -311.746347) (xy 155.812358 -311.744366) (xy 155.861213 -311.750298) (xy 155.908484 -311.76399)
			(xy 155.952946 -311.785088) (xy 155.993449 -311.813044) (xy 156.028942 -311.847136) (xy 156.058507 -311.88648)
			(xy 156.081378 -311.930057) (xy 156.096962 -311.976738) (xy 156.104857 -312.025315) (xy 156.105352 -312.049922)
			(xy 157.39416 -312.049922) (xy 157.39812 -312.000868) (xy 157.409897 -311.953084) (xy 157.429188 -311.907808)
			(xy 157.455491 -311.866212) (xy 157.488126 -311.829375) (xy 157.526247 -311.79825) (xy 157.568868 -311.773643)
			(xy 157.614884 -311.756191) (xy 157.663103 -311.746347) (xy 157.712278 -311.744366) (xy 157.761133 -311.750298)
			(xy 157.808404 -311.76399) (xy 157.852866 -311.785088) (xy 157.893369 -311.813044) (xy 157.928862 -311.847136)
			(xy 157.958427 -311.88648) (xy 157.981298 -311.930057) (xy 157.996882 -311.976738) (xy 158.004777 -312.025315)
			(xy 158.005272 -312.049922) (xy 159.29408 -312.049922) (xy 159.29804 -312.000868) (xy 159.309817 -311.953084)
			(xy 159.329108 -311.907808) (xy 159.355411 -311.866212) (xy 159.388046 -311.829375) (xy 159.426167 -311.79825)
			(xy 159.468788 -311.773643) (xy 159.514804 -311.756191) (xy 159.563023 -311.746347) (xy 159.612198 -311.744366)
			(xy 159.661053 -311.750298) (xy 159.708324 -311.76399) (xy 159.752786 -311.785088) (xy 159.793289 -311.813044)
			(xy 159.828782 -311.847136) (xy 159.858347 -311.88648) (xy 159.881218 -311.930057) (xy 159.896802 -311.976738)
			(xy 159.904697 -312.025315) (xy 159.905192 -312.049922) (xy 161.194254 -312.049922) (xy 161.198214 -312.000868)
			(xy 161.209991 -311.953084) (xy 161.229282 -311.907808) (xy 161.255585 -311.866212) (xy 161.28822 -311.829375)
			(xy 161.326341 -311.79825) (xy 161.368962 -311.773643) (xy 161.414978 -311.756191) (xy 161.463197 -311.746347)
			(xy 161.512372 -311.744366) (xy 161.561227 -311.750298) (xy 161.608498 -311.76399) (xy 161.65296 -311.785088)
			(xy 161.693463 -311.813044) (xy 161.728956 -311.847136) (xy 161.758521 -311.88648) (xy 161.781392 -311.930057)
			(xy 161.796976 -311.976738) (xy 161.804871 -312.025315) (xy 161.805366 -312.049922) (xy 163.094174 -312.049922)
			(xy 163.098134 -312.000868) (xy 163.109911 -311.953084) (xy 163.129202 -311.907808) (xy 163.155505 -311.866212)
			(xy 163.18814 -311.829375) (xy 163.226261 -311.79825) (xy 163.268882 -311.773643) (xy 163.314898 -311.756191)
			(xy 163.363117 -311.746347) (xy 163.412292 -311.744366) (xy 163.461147 -311.750298) (xy 163.508418 -311.76399)
			(xy 163.55288 -311.785088) (xy 163.593383 -311.813044) (xy 163.628876 -311.847136) (xy 163.658441 -311.88648)
			(xy 163.681312 -311.930057) (xy 163.696896 -311.976738) (xy 163.704791 -312.025315) (xy 163.705286 -312.049922)
			(xy 164.994094 -312.049922) (xy 164.998054 -312.000868) (xy 165.009831 -311.953084) (xy 165.029122 -311.907808)
			(xy 165.055425 -311.866212) (xy 165.08806 -311.829375) (xy 165.126181 -311.79825) (xy 165.168802 -311.773643)
			(xy 165.214818 -311.756191) (xy 165.263037 -311.746347) (xy 165.312212 -311.744366) (xy 165.361067 -311.750298)
			(xy 165.408338 -311.76399) (xy 165.4528 -311.785088) (xy 165.493303 -311.813044) (xy 165.528796 -311.847136)
			(xy 165.558361 -311.88648) (xy 165.581232 -311.930057) (xy 165.596816 -311.976738) (xy 165.604711 -312.025315)
			(xy 165.605206 -312.049922) (xy 182.094136 -312.049922) (xy 182.098096 -312.000868) (xy 182.109873 -311.953084)
			(xy 182.129164 -311.907808) (xy 182.155467 -311.866212) (xy 182.188102 -311.829375) (xy 182.226223 -311.79825)
			(xy 182.268844 -311.773643) (xy 182.31486 -311.756191) (xy 182.363079 -311.746347) (xy 182.412254 -311.744366)
			(xy 182.461109 -311.750298) (xy 182.50838 -311.76399) (xy 182.552842 -311.785088) (xy 182.593345 -311.813044)
			(xy 182.628838 -311.847136) (xy 182.658403 -311.88648) (xy 182.681274 -311.930057) (xy 182.696858 -311.976738)
			(xy 182.704753 -312.025315) (xy 182.705248 -312.049922) (xy 183.994056 -312.049922) (xy 183.998016 -312.000868)
			(xy 184.009793 -311.953084) (xy 184.029084 -311.907808) (xy 184.055387 -311.866212) (xy 184.088022 -311.829375)
			(xy 184.126143 -311.79825) (xy 184.168764 -311.773643) (xy 184.21478 -311.756191) (xy 184.262999 -311.746347)
			(xy 184.312174 -311.744366) (xy 184.361029 -311.750298) (xy 184.4083 -311.76399) (xy 184.452762 -311.785088)
			(xy 184.493265 -311.813044) (xy 184.528758 -311.847136) (xy 184.558323 -311.88648) (xy 184.581194 -311.930057)
			(xy 184.596778 -311.976738) (xy 184.604673 -312.025315) (xy 184.605168 -312.049922) (xy 185.89423 -312.049922)
			(xy 185.89819 -312.000868) (xy 185.909967 -311.953084) (xy 185.929258 -311.907808) (xy 185.955561 -311.866212)
			(xy 185.988196 -311.829375) (xy 186.026317 -311.79825) (xy 186.068938 -311.773643) (xy 186.114954 -311.756191)
			(xy 186.163173 -311.746347) (xy 186.212348 -311.744366) (xy 186.261203 -311.750298) (xy 186.308474 -311.76399)
			(xy 186.352936 -311.785088) (xy 186.393439 -311.813044) (xy 186.428932 -311.847136) (xy 186.458497 -311.88648)
			(xy 186.481368 -311.930057) (xy 186.496952 -311.976738) (xy 186.504847 -312.025315) (xy 186.505342 -312.049922)
			(xy 187.79415 -312.049922) (xy 187.79811 -312.000868) (xy 187.809887 -311.953084) (xy 187.829178 -311.907808)
			(xy 187.855481 -311.866212) (xy 187.888116 -311.829375) (xy 187.926237 -311.79825) (xy 187.968858 -311.773643)
			(xy 188.014874 -311.756191) (xy 188.063093 -311.746347) (xy 188.112268 -311.744366) (xy 188.161123 -311.750298)
			(xy 188.208394 -311.76399) (xy 188.252856 -311.785088) (xy 188.293359 -311.813044) (xy 188.328852 -311.847136)
			(xy 188.358417 -311.88648) (xy 188.381288 -311.930057) (xy 188.396872 -311.976738) (xy 188.404767 -312.025315)
			(xy 188.405262 -312.049922) (xy 275.393924 -312.049922) (xy 275.397884 -312.000868) (xy 275.409661 -311.953084)
			(xy 275.428952 -311.907808) (xy 275.455255 -311.866212) (xy 275.48789 -311.829375) (xy 275.526011 -311.79825)
			(xy 275.568632 -311.773643) (xy 275.614648 -311.756191) (xy 275.662867 -311.746347) (xy 275.712042 -311.744366)
			(xy 275.760897 -311.750298) (xy 275.808168 -311.76399) (xy 275.85263 -311.785088) (xy 275.893133 -311.813044)
			(xy 275.928626 -311.847136) (xy 275.958191 -311.88648) (xy 275.981062 -311.930057) (xy 275.996646 -311.976738)
			(xy 276.004541 -312.025315) (xy 276.005036 -312.049922) (xy 277.294098 -312.049922) (xy 277.298058 -312.000868)
			(xy 277.309835 -311.953084) (xy 277.329126 -311.907808) (xy 277.355429 -311.866212) (xy 277.388064 -311.829375)
			(xy 277.426185 -311.79825) (xy 277.468806 -311.773643) (xy 277.514822 -311.756191) (xy 277.563041 -311.746347)
			(xy 277.612216 -311.744366) (xy 277.661071 -311.750298) (xy 277.708342 -311.76399) (xy 277.752804 -311.785088)
			(xy 277.793307 -311.813044) (xy 277.8288 -311.847136) (xy 277.858365 -311.88648) (xy 277.881236 -311.930057)
			(xy 277.89682 -311.976738) (xy 277.904715 -312.025315) (xy 277.90521 -312.049922) (xy 279.194018 -312.049922)
			(xy 279.197978 -312.000868) (xy 279.209755 -311.953084) (xy 279.229046 -311.907808) (xy 279.255349 -311.866212)
			(xy 279.287984 -311.829375) (xy 279.326105 -311.79825) (xy 279.368726 -311.773643) (xy 279.414742 -311.756191)
			(xy 279.462961 -311.746347) (xy 279.512136 -311.744366) (xy 279.560991 -311.750298) (xy 279.608262 -311.76399)
			(xy 279.652724 -311.785088) (xy 279.693227 -311.813044) (xy 279.72872 -311.847136) (xy 279.758285 -311.88648)
			(xy 279.781156 -311.930057) (xy 279.79674 -311.976738) (xy 279.804635 -312.025315) (xy 279.80513 -312.049922)
			(xy 281.093938 -312.049922) (xy 281.097898 -312.000868) (xy 281.109675 -311.953084) (xy 281.128966 -311.907808)
			(xy 281.155269 -311.866212) (xy 281.187904 -311.829375) (xy 281.226025 -311.79825) (xy 281.268646 -311.773643)
			(xy 281.314662 -311.756191) (xy 281.362881 -311.746347) (xy 281.412056 -311.744366) (xy 281.460911 -311.750298)
			(xy 281.508182 -311.76399) (xy 281.552644 -311.785088) (xy 281.593147 -311.813044) (xy 281.62864 -311.847136)
			(xy 281.658205 -311.88648) (xy 281.681076 -311.930057) (xy 281.69666 -311.976738) (xy 281.704555 -312.025315)
			(xy 281.70505 -312.049922) (xy 282.994112 -312.049922) (xy 282.998072 -312.000868) (xy 283.009849 -311.953084)
			(xy 283.02914 -311.907808) (xy 283.055443 -311.866212) (xy 283.088078 -311.829375) (xy 283.126199 -311.79825)
			(xy 283.16882 -311.773643) (xy 283.214836 -311.756191) (xy 283.263055 -311.746347) (xy 283.31223 -311.744366)
			(xy 283.361085 -311.750298) (xy 283.408356 -311.76399) (xy 283.452818 -311.785088) (xy 283.493321 -311.813044)
			(xy 283.528814 -311.847136) (xy 283.558379 -311.88648) (xy 283.58125 -311.930057) (xy 283.596834 -311.976738)
			(xy 283.604729 -312.025315) (xy 283.605224 -312.049922) (xy 284.894032 -312.049922) (xy 284.897992 -312.000868)
			(xy 284.909769 -311.953084) (xy 284.92906 -311.907808) (xy 284.955363 -311.866212) (xy 284.987998 -311.829375)
			(xy 285.026119 -311.79825) (xy 285.06874 -311.773643) (xy 285.114756 -311.756191) (xy 285.162975 -311.746347)
			(xy 285.21215 -311.744366) (xy 285.261005 -311.750298) (xy 285.308276 -311.76399) (xy 285.352738 -311.785088)
			(xy 285.393241 -311.813044) (xy 285.428734 -311.847136) (xy 285.458299 -311.88648) (xy 285.48117 -311.930057)
			(xy 285.496754 -311.976738) (xy 285.504649 -312.025315) (xy 285.505144 -312.049922) (xy 286.793952 -312.049922)
			(xy 286.797912 -312.000868) (xy 286.809689 -311.953084) (xy 286.82898 -311.907808) (xy 286.855283 -311.866212)
			(xy 286.887918 -311.829375) (xy 286.926039 -311.79825) (xy 286.96866 -311.773643) (xy 287.014676 -311.756191)
			(xy 287.062895 -311.746347) (xy 287.11207 -311.744366) (xy 287.160925 -311.750298) (xy 287.208196 -311.76399)
			(xy 287.252658 -311.785088) (xy 287.293161 -311.813044) (xy 287.328654 -311.847136) (xy 287.358219 -311.88648)
			(xy 287.38109 -311.930057) (xy 287.396674 -311.976738) (xy 287.404569 -312.025315) (xy 287.405064 -312.049922)
			(xy 288.694126 -312.049922) (xy 288.698086 -312.000868) (xy 288.709863 -311.953084) (xy 288.729154 -311.907808)
			(xy 288.755457 -311.866212) (xy 288.788092 -311.829375) (xy 288.826213 -311.79825) (xy 288.868834 -311.773643)
			(xy 288.91485 -311.756191) (xy 288.963069 -311.746347) (xy 289.012244 -311.744366) (xy 289.061099 -311.750298)
			(xy 289.10837 -311.76399) (xy 289.152832 -311.785088) (xy 289.193335 -311.813044) (xy 289.228828 -311.847136)
			(xy 289.258393 -311.88648) (xy 289.281264 -311.930057) (xy 289.296848 -311.976738) (xy 289.304743 -312.025315)
			(xy 289.305238 -312.049922) (xy 305.793914 -312.049922) (xy 305.797874 -312.000868) (xy 305.809651 -311.953084)
			(xy 305.828942 -311.907808) (xy 305.855245 -311.866212) (xy 305.88788 -311.829375) (xy 305.926001 -311.79825)
			(xy 305.968622 -311.773643) (xy 306.014638 -311.756191) (xy 306.062857 -311.746347) (xy 306.112032 -311.744366)
			(xy 306.160887 -311.750298) (xy 306.208158 -311.76399) (xy 306.25262 -311.785088) (xy 306.293123 -311.813044)
			(xy 306.328616 -311.847136) (xy 306.358181 -311.88648) (xy 306.381052 -311.930057) (xy 306.396636 -311.976738)
			(xy 306.404531 -312.025315) (xy 306.405026 -312.049922) (xy 307.694088 -312.049922) (xy 307.698048 -312.000868)
			(xy 307.709825 -311.953084) (xy 307.729116 -311.907808) (xy 307.755419 -311.866212) (xy 307.788054 -311.829375)
			(xy 307.826175 -311.79825) (xy 307.868796 -311.773643) (xy 307.914812 -311.756191) (xy 307.963031 -311.746347)
			(xy 308.012206 -311.744366) (xy 308.061061 -311.750298) (xy 308.108332 -311.76399) (xy 308.152794 -311.785088)
			(xy 308.193297 -311.813044) (xy 308.22879 -311.847136) (xy 308.258355 -311.88648) (xy 308.281226 -311.930057)
			(xy 308.29681 -311.976738) (xy 308.304705 -312.025315) (xy 308.3052 -312.049922) (xy 309.594008 -312.049922)
			(xy 309.597968 -312.000868) (xy 309.609745 -311.953084) (xy 309.629036 -311.907808) (xy 309.655339 -311.866212)
			(xy 309.687974 -311.829375) (xy 309.726095 -311.79825) (xy 309.768716 -311.773643) (xy 309.814732 -311.756191)
			(xy 309.862951 -311.746347) (xy 309.912126 -311.744366) (xy 309.960981 -311.750298) (xy 310.008252 -311.76399)
			(xy 310.052714 -311.785088) (xy 310.093217 -311.813044) (xy 310.12871 -311.847136) (xy 310.158275 -311.88648)
			(xy 310.181146 -311.930057) (xy 310.19673 -311.976738) (xy 310.204625 -312.025315) (xy 310.20512 -312.049922)
			(xy 311.493928 -312.049922) (xy 311.497888 -312.000868) (xy 311.509665 -311.953084) (xy 311.528956 -311.907808)
			(xy 311.555259 -311.866212) (xy 311.587894 -311.829375) (xy 311.626015 -311.79825) (xy 311.668636 -311.773643)
			(xy 311.714652 -311.756191) (xy 311.762871 -311.746347) (xy 311.812046 -311.744366) (xy 311.860901 -311.750298)
			(xy 311.908172 -311.76399) (xy 311.952634 -311.785088) (xy 311.993137 -311.813044) (xy 312.02863 -311.847136)
			(xy 312.058195 -311.88648) (xy 312.081066 -311.930057) (xy 312.09665 -311.976738) (xy 312.104545 -312.025315)
			(xy 312.10504 -312.049922) (xy 313.394102 -312.049922) (xy 313.398062 -312.000868) (xy 313.409839 -311.953084)
			(xy 313.42913 -311.907808) (xy 313.455433 -311.866212) (xy 313.488068 -311.829375) (xy 313.526189 -311.79825)
			(xy 313.56881 -311.773643) (xy 313.614826 -311.756191) (xy 313.663045 -311.746347) (xy 313.71222 -311.744366)
			(xy 313.761075 -311.750298) (xy 313.808346 -311.76399) (xy 313.852808 -311.785088) (xy 313.893311 -311.813044)
			(xy 313.928804 -311.847136) (xy 313.958369 -311.88648) (xy 313.98124 -311.930057) (xy 313.996824 -311.976738)
			(xy 314.004719 -312.025315) (xy 314.005214 -312.049922) (xy 314.344062 -312.049922) (xy 314.348022 -312.000868)
			(xy 314.359799 -311.953084) (xy 314.37909 -311.907808) (xy 314.405393 -311.866212) (xy 314.438028 -311.829375)
			(xy 314.476149 -311.79825) (xy 314.51877 -311.773643) (xy 314.564786 -311.756191) (xy 314.613005 -311.746347)
			(xy 314.66218 -311.744366) (xy 314.711035 -311.750298) (xy 314.758306 -311.76399) (xy 314.802768 -311.785088)
			(xy 314.843271 -311.813044) (xy 314.878764 -311.847136) (xy 314.908329 -311.88648) (xy 314.9312 -311.930057)
			(xy 314.946784 -311.976738) (xy 314.954679 -312.025315) (xy 314.955174 -312.049922) (xy 384.844048 -312.049922)
			(xy 384.848008 -312.000868) (xy 384.859785 -311.953084) (xy 384.879076 -311.907808) (xy 384.905379 -311.866212)
			(xy 384.938014 -311.829375) (xy 384.976135 -311.79825) (xy 385.018756 -311.773643) (xy 385.064772 -311.756191)
			(xy 385.112991 -311.746347) (xy 385.162166 -311.744366) (xy 385.211021 -311.750298) (xy 385.258292 -311.76399)
			(xy 385.302754 -311.785088) (xy 385.343257 -311.813044) (xy 385.37875 -311.847136) (xy 385.408315 -311.88648)
			(xy 385.431186 -311.930057) (xy 385.44677 -311.976738) (xy 385.454665 -312.025315) (xy 385.45516 -312.049922)
			(xy 385.794008 -312.049922) (xy 385.797968 -312.000868) (xy 385.809745 -311.953084) (xy 385.829036 -311.907808)
			(xy 385.855339 -311.866212) (xy 385.887974 -311.829375) (xy 385.926095 -311.79825) (xy 385.968716 -311.773643)
			(xy 386.014732 -311.756191) (xy 386.062951 -311.746347) (xy 386.112126 -311.744366) (xy 386.160981 -311.750298)
			(xy 386.208252 -311.76399) (xy 386.252714 -311.785088) (xy 386.293217 -311.813044) (xy 386.32871 -311.847136)
			(xy 386.358275 -311.88648) (xy 386.381146 -311.930057) (xy 386.39673 -311.976738) (xy 386.404625 -312.025315)
			(xy 386.40512 -312.049922) (xy 387.694182 -312.049922) (xy 387.698142 -312.000868) (xy 387.709919 -311.953084)
			(xy 387.72921 -311.907808) (xy 387.755513 -311.866212) (xy 387.788148 -311.829375) (xy 387.826269 -311.79825)
			(xy 387.86889 -311.773643) (xy 387.914906 -311.756191) (xy 387.963125 -311.746347) (xy 388.0123 -311.744366)
			(xy 388.061155 -311.750298) (xy 388.108426 -311.76399) (xy 388.152888 -311.785088) (xy 388.193391 -311.813044)
			(xy 388.228884 -311.847136) (xy 388.258449 -311.88648) (xy 388.28132 -311.930057) (xy 388.296904 -311.976738)
			(xy 388.304799 -312.025315) (xy 388.305294 -312.049922) (xy 389.594102 -312.049922) (xy 389.598062 -312.000868)
			(xy 389.609839 -311.953084) (xy 389.62913 -311.907808) (xy 389.655433 -311.866212) (xy 389.688068 -311.829375)
			(xy 389.726189 -311.79825) (xy 389.76881 -311.773643) (xy 389.814826 -311.756191) (xy 389.863045 -311.746347)
			(xy 389.91222 -311.744366) (xy 389.961075 -311.750298) (xy 390.008346 -311.76399) (xy 390.052808 -311.785088)
			(xy 390.093311 -311.813044) (xy 390.128804 -311.847136) (xy 390.158369 -311.88648) (xy 390.18124 -311.930057)
			(xy 390.196824 -311.976738) (xy 390.204719 -312.025315) (xy 390.205214 -312.049922) (xy 391.494022 -312.049922)
			(xy 391.497982 -312.000868) (xy 391.509759 -311.953084) (xy 391.52905 -311.907808) (xy 391.555353 -311.866212)
			(xy 391.587988 -311.829375) (xy 391.626109 -311.79825) (xy 391.66873 -311.773643) (xy 391.714746 -311.756191)
			(xy 391.762965 -311.746347) (xy 391.81214 -311.744366) (xy 391.860995 -311.750298) (xy 391.908266 -311.76399)
			(xy 391.952728 -311.785088) (xy 391.993231 -311.813044) (xy 392.028724 -311.847136) (xy 392.058289 -311.88648)
			(xy 392.08116 -311.930057) (xy 392.096744 -311.976738) (xy 392.104639 -312.025315) (xy 392.105134 -312.049922)
			(xy 393.394196 -312.049922) (xy 393.398156 -312.000868) (xy 393.409933 -311.953084) (xy 393.429224 -311.907808)
			(xy 393.455527 -311.866212) (xy 393.488162 -311.829375) (xy 393.526283 -311.79825) (xy 393.568904 -311.773643)
			(xy 393.61492 -311.756191) (xy 393.663139 -311.746347) (xy 393.712314 -311.744366) (xy 393.761169 -311.750298)
			(xy 393.80844 -311.76399) (xy 393.852902 -311.785088) (xy 393.893405 -311.813044) (xy 393.928898 -311.847136)
			(xy 393.958463 -311.88648) (xy 393.981334 -311.930057) (xy 393.996918 -311.976738) (xy 394.004813 -312.025315)
			(xy 394.005308 -312.049922) (xy 395.294116 -312.049922) (xy 395.298076 -312.000868) (xy 395.309853 -311.953084)
			(xy 395.329144 -311.907808) (xy 395.355447 -311.866212) (xy 395.388082 -311.829375) (xy 395.426203 -311.79825)
			(xy 395.468824 -311.773643) (xy 395.51484 -311.756191) (xy 395.563059 -311.746347) (xy 395.612234 -311.744366)
			(xy 395.661089 -311.750298) (xy 395.70836 -311.76399) (xy 395.752822 -311.785088) (xy 395.793325 -311.813044)
			(xy 395.828818 -311.847136) (xy 395.858383 -311.88648) (xy 395.881254 -311.930057) (xy 395.896838 -311.976738)
			(xy 395.904733 -312.025315) (xy 395.905228 -312.049922) (xy 397.194036 -312.049922) (xy 397.197996 -312.000868)
			(xy 397.209773 -311.953084) (xy 397.229064 -311.907808) (xy 397.255367 -311.866212) (xy 397.288002 -311.829375)
			(xy 397.326123 -311.79825) (xy 397.368744 -311.773643) (xy 397.41476 -311.756191) (xy 397.462979 -311.746347)
			(xy 397.512154 -311.744366) (xy 397.561009 -311.750298) (xy 397.60828 -311.76399) (xy 397.652742 -311.785088)
			(xy 397.693245 -311.813044) (xy 397.728738 -311.847136) (xy 397.758303 -311.88648) (xy 397.781174 -311.930057)
			(xy 397.796758 -311.976738) (xy 397.804653 -312.025315) (xy 397.805148 -312.049922) (xy 414.294078 -312.049922)
			(xy 414.298038 -312.000868) (xy 414.309815 -311.953084) (xy 414.329106 -311.907808) (xy 414.355409 -311.866212)
			(xy 414.388044 -311.829375) (xy 414.426165 -311.79825) (xy 414.468786 -311.773643) (xy 414.514802 -311.756191)
			(xy 414.563021 -311.746347) (xy 414.612196 -311.744366) (xy 414.661051 -311.750298) (xy 414.708322 -311.76399)
			(xy 414.752784 -311.785088) (xy 414.793287 -311.813044) (xy 414.82878 -311.847136) (xy 414.858345 -311.88648)
			(xy 414.881216 -311.930057) (xy 414.8968 -311.976738) (xy 414.904695 -312.025315) (xy 414.90519 -312.049922)
			(xy 416.193998 -312.049922) (xy 416.197958 -312.000868) (xy 416.209735 -311.953084) (xy 416.229026 -311.907808)
			(xy 416.255329 -311.866212) (xy 416.287964 -311.829375) (xy 416.326085 -311.79825) (xy 416.368706 -311.773643)
			(xy 416.414722 -311.756191) (xy 416.462941 -311.746347) (xy 416.512116 -311.744366) (xy 416.560971 -311.750298)
			(xy 416.608242 -311.76399) (xy 416.652704 -311.785088) (xy 416.693207 -311.813044) (xy 416.7287 -311.847136)
			(xy 416.758265 -311.88648) (xy 416.781136 -311.930057) (xy 416.79672 -311.976738) (xy 416.804615 -312.025315)
			(xy 416.80511 -312.049922) (xy 418.094172 -312.049922) (xy 418.098132 -312.000868) (xy 418.109909 -311.953084)
			(xy 418.1292 -311.907808) (xy 418.155503 -311.866212) (xy 418.188138 -311.829375) (xy 418.226259 -311.79825)
			(xy 418.26888 -311.773643) (xy 418.314896 -311.756191) (xy 418.363115 -311.746347) (xy 418.41229 -311.744366)
			(xy 418.461145 -311.750298) (xy 418.508416 -311.76399) (xy 418.552878 -311.785088) (xy 418.593381 -311.813044)
			(xy 418.628874 -311.847136) (xy 418.658439 -311.88648) (xy 418.68131 -311.930057) (xy 418.696894 -311.976738)
			(xy 418.704789 -312.025315) (xy 418.705284 -312.049922) (xy 419.994092 -312.049922) (xy 419.998052 -312.000868)
			(xy 420.009829 -311.953084) (xy 420.02912 -311.907808) (xy 420.055423 -311.866212) (xy 420.088058 -311.829375)
			(xy 420.126179 -311.79825) (xy 420.1688 -311.773643) (xy 420.214816 -311.756191) (xy 420.263035 -311.746347)
			(xy 420.31221 -311.744366) (xy 420.361065 -311.750298) (xy 420.408336 -311.76399) (xy 420.452798 -311.785088)
			(xy 420.493301 -311.813044) (xy 420.528794 -311.847136) (xy 420.558359 -311.88648) (xy 420.58123 -311.930057)
			(xy 420.596814 -311.976738) (xy 420.604709 -312.025315) (xy 420.605204 -312.049922) (xy 420.604709 -312.074529)
			(xy 420.596814 -312.123106) (xy 420.58123 -312.169787) (xy 420.558359 -312.213364) (xy 420.528794 -312.252708)
			(xy 420.493301 -312.2868) (xy 420.452798 -312.314756) (xy 420.408336 -312.335854) (xy 420.361065 -312.349546)
			(xy 420.31221 -312.355478) (xy 420.263035 -312.353497) (xy 420.214816 -312.343653) (xy 420.1688 -312.326201)
			(xy 420.126179 -312.301594) (xy 420.088058 -312.270469) (xy 420.055423 -312.233632) (xy 420.02912 -312.192036)
			(xy 420.009829 -312.14676) (xy 419.998052 -312.098976) (xy 419.994092 -312.049922) (xy 418.705284 -312.049922)
			(xy 418.704789 -312.074529) (xy 418.696894 -312.123106) (xy 418.68131 -312.169787) (xy 418.658439 -312.213364)
			(xy 418.628874 -312.252708) (xy 418.593381 -312.2868) (xy 418.552878 -312.314756) (xy 418.508416 -312.335854)
			(xy 418.461145 -312.349546) (xy 418.41229 -312.355478) (xy 418.363115 -312.353497) (xy 418.314896 -312.343653)
			(xy 418.26888 -312.326201) (xy 418.226259 -312.301594) (xy 418.188138 -312.270469) (xy 418.155503 -312.233632)
			(xy 418.1292 -312.192036) (xy 418.109909 -312.14676) (xy 418.098132 -312.098976) (xy 418.094172 -312.049922)
			(xy 416.80511 -312.049922) (xy 416.804615 -312.074529) (xy 416.79672 -312.123106) (xy 416.781136 -312.169787)
			(xy 416.758265 -312.213364) (xy 416.7287 -312.252708) (xy 416.693207 -312.2868) (xy 416.652704 -312.314756)
			(xy 416.608242 -312.335854) (xy 416.560971 -312.349546) (xy 416.512116 -312.355478) (xy 416.462941 -312.353497)
			(xy 416.414722 -312.343653) (xy 416.368706 -312.326201) (xy 416.326085 -312.301594) (xy 416.287964 -312.270469)
			(xy 416.255329 -312.233632) (xy 416.229026 -312.192036) (xy 416.209735 -312.14676) (xy 416.197958 -312.098976)
			(xy 416.193998 -312.049922) (xy 414.90519 -312.049922) (xy 414.904695 -312.074529) (xy 414.8968 -312.123106)
			(xy 414.881216 -312.169787) (xy 414.858345 -312.213364) (xy 414.82878 -312.252708) (xy 414.793287 -312.2868)
			(xy 414.752784 -312.314756) (xy 414.708322 -312.335854) (xy 414.661051 -312.349546) (xy 414.612196 -312.355478)
			(xy 414.563021 -312.353497) (xy 414.514802 -312.343653) (xy 414.468786 -312.326201) (xy 414.426165 -312.301594)
			(xy 414.388044 -312.270469) (xy 414.355409 -312.233632) (xy 414.329106 -312.192036) (xy 414.309815 -312.14676)
			(xy 414.298038 -312.098976) (xy 414.294078 -312.049922) (xy 397.805148 -312.049922) (xy 397.804653 -312.074529)
			(xy 397.796758 -312.123106) (xy 397.781174 -312.169787) (xy 397.758303 -312.213364) (xy 397.728738 -312.252708)
			(xy 397.693245 -312.2868) (xy 397.652742 -312.314756) (xy 397.60828 -312.335854) (xy 397.561009 -312.349546)
			(xy 397.512154 -312.355478) (xy 397.462979 -312.353497) (xy 397.41476 -312.343653) (xy 397.368744 -312.326201)
			(xy 397.326123 -312.301594) (xy 397.288002 -312.270469) (xy 397.255367 -312.233632) (xy 397.229064 -312.192036)
			(xy 397.209773 -312.14676) (xy 397.197996 -312.098976) (xy 397.194036 -312.049922) (xy 395.905228 -312.049922)
			(xy 395.904733 -312.074529) (xy 395.896838 -312.123106) (xy 395.881254 -312.169787) (xy 395.858383 -312.213364)
			(xy 395.828818 -312.252708) (xy 395.793325 -312.2868) (xy 395.752822 -312.314756) (xy 395.70836 -312.335854)
			(xy 395.661089 -312.349546) (xy 395.612234 -312.355478) (xy 395.563059 -312.353497) (xy 395.51484 -312.343653)
			(xy 395.468824 -312.326201) (xy 395.426203 -312.301594) (xy 395.388082 -312.270469) (xy 395.355447 -312.233632)
			(xy 395.329144 -312.192036) (xy 395.309853 -312.14676) (xy 395.298076 -312.098976) (xy 395.294116 -312.049922)
			(xy 394.005308 -312.049922) (xy 394.004813 -312.074529) (xy 393.996918 -312.123106) (xy 393.981334 -312.169787)
			(xy 393.958463 -312.213364) (xy 393.928898 -312.252708) (xy 393.893405 -312.2868) (xy 393.852902 -312.314756)
			(xy 393.80844 -312.335854) (xy 393.761169 -312.349546) (xy 393.712314 -312.355478) (xy 393.663139 -312.353497)
			(xy 393.61492 -312.343653) (xy 393.568904 -312.326201) (xy 393.526283 -312.301594) (xy 393.488162 -312.270469)
			(xy 393.455527 -312.233632) (xy 393.429224 -312.192036) (xy 393.409933 -312.14676) (xy 393.398156 -312.098976)
			(xy 393.394196 -312.049922) (xy 392.105134 -312.049922) (xy 392.104639 -312.074529) (xy 392.096744 -312.123106)
			(xy 392.08116 -312.169787) (xy 392.058289 -312.213364) (xy 392.028724 -312.252708) (xy 391.993231 -312.2868)
			(xy 391.952728 -312.314756) (xy 391.908266 -312.335854) (xy 391.860995 -312.349546) (xy 391.81214 -312.355478)
			(xy 391.762965 -312.353497) (xy 391.714746 -312.343653) (xy 391.66873 -312.326201) (xy 391.626109 -312.301594)
			(xy 391.587988 -312.270469) (xy 391.555353 -312.233632) (xy 391.52905 -312.192036) (xy 391.509759 -312.14676)
			(xy 391.497982 -312.098976) (xy 391.494022 -312.049922) (xy 390.205214 -312.049922) (xy 390.204719 -312.074529)
			(xy 390.196824 -312.123106) (xy 390.18124 -312.169787) (xy 390.158369 -312.213364) (xy 390.128804 -312.252708)
			(xy 390.093311 -312.2868) (xy 390.052808 -312.314756) (xy 390.008346 -312.335854) (xy 389.961075 -312.349546)
			(xy 389.91222 -312.355478) (xy 389.863045 -312.353497) (xy 389.814826 -312.343653) (xy 389.76881 -312.326201)
			(xy 389.726189 -312.301594) (xy 389.688068 -312.270469) (xy 389.655433 -312.233632) (xy 389.62913 -312.192036)
			(xy 389.609839 -312.14676) (xy 389.598062 -312.098976) (xy 389.594102 -312.049922) (xy 388.305294 -312.049922)
			(xy 388.304799 -312.074529) (xy 388.296904 -312.123106) (xy 388.28132 -312.169787) (xy 388.258449 -312.213364)
			(xy 388.228884 -312.252708) (xy 388.193391 -312.2868) (xy 388.152888 -312.314756) (xy 388.108426 -312.335854)
			(xy 388.061155 -312.349546) (xy 388.0123 -312.355478) (xy 387.963125 -312.353497) (xy 387.914906 -312.343653)
			(xy 387.86889 -312.326201) (xy 387.826269 -312.301594) (xy 387.788148 -312.270469) (xy 387.755513 -312.233632)
			(xy 387.72921 -312.192036) (xy 387.709919 -312.14676) (xy 387.698142 -312.098976) (xy 387.694182 -312.049922)
			(xy 386.40512 -312.049922) (xy 386.404625 -312.074529) (xy 386.39673 -312.123106) (xy 386.381146 -312.169787)
			(xy 386.358275 -312.213364) (xy 386.32871 -312.252708) (xy 386.293217 -312.2868) (xy 386.252714 -312.314756)
			(xy 386.208252 -312.335854) (xy 386.160981 -312.349546) (xy 386.112126 -312.355478) (xy 386.062951 -312.353497)
			(xy 386.014732 -312.343653) (xy 385.968716 -312.326201) (xy 385.926095 -312.301594) (xy 385.887974 -312.270469)
			(xy 385.855339 -312.233632) (xy 385.829036 -312.192036) (xy 385.809745 -312.14676) (xy 385.797968 -312.098976)
			(xy 385.794008 -312.049922) (xy 385.45516 -312.049922) (xy 385.454665 -312.074529) (xy 385.44677 -312.123106)
			(xy 385.431186 -312.169787) (xy 385.408315 -312.213364) (xy 385.37875 -312.252708) (xy 385.343257 -312.2868)
			(xy 385.302754 -312.314756) (xy 385.258292 -312.335854) (xy 385.211021 -312.349546) (xy 385.162166 -312.355478)
			(xy 385.112991 -312.353497) (xy 385.064772 -312.343653) (xy 385.018756 -312.326201) (xy 384.976135 -312.301594)
			(xy 384.938014 -312.270469) (xy 384.905379 -312.233632) (xy 384.879076 -312.192036) (xy 384.859785 -312.14676)
			(xy 384.848008 -312.098976) (xy 384.844048 -312.049922) (xy 314.955174 -312.049922) (xy 314.954679 -312.074529)
			(xy 314.946784 -312.123106) (xy 314.9312 -312.169787) (xy 314.908329 -312.213364) (xy 314.878764 -312.252708)
			(xy 314.843271 -312.2868) (xy 314.802768 -312.314756) (xy 314.758306 -312.335854) (xy 314.711035 -312.349546)
			(xy 314.66218 -312.355478) (xy 314.613005 -312.353497) (xy 314.564786 -312.343653) (xy 314.51877 -312.326201)
			(xy 314.476149 -312.301594) (xy 314.438028 -312.270469) (xy 314.405393 -312.233632) (xy 314.37909 -312.192036)
			(xy 314.359799 -312.14676) (xy 314.348022 -312.098976) (xy 314.344062 -312.049922) (xy 314.005214 -312.049922)
			(xy 314.004719 -312.074529) (xy 313.996824 -312.123106) (xy 313.98124 -312.169787) (xy 313.958369 -312.213364)
			(xy 313.928804 -312.252708) (xy 313.893311 -312.2868) (xy 313.852808 -312.314756) (xy 313.808346 -312.335854)
			(xy 313.761075 -312.349546) (xy 313.71222 -312.355478) (xy 313.663045 -312.353497) (xy 313.614826 -312.343653)
			(xy 313.56881 -312.326201) (xy 313.526189 -312.301594) (xy 313.488068 -312.270469) (xy 313.455433 -312.233632)
			(xy 313.42913 -312.192036) (xy 313.409839 -312.14676) (xy 313.398062 -312.098976) (xy 313.394102 -312.049922)
			(xy 312.10504 -312.049922) (xy 312.104545 -312.074529) (xy 312.09665 -312.123106) (xy 312.081066 -312.169787)
			(xy 312.058195 -312.213364) (xy 312.02863 -312.252708) (xy 311.993137 -312.2868) (xy 311.952634 -312.314756)
			(xy 311.908172 -312.335854) (xy 311.860901 -312.349546) (xy 311.812046 -312.355478) (xy 311.762871 -312.353497)
			(xy 311.714652 -312.343653) (xy 311.668636 -312.326201) (xy 311.626015 -312.301594) (xy 311.587894 -312.270469)
			(xy 311.555259 -312.233632) (xy 311.528956 -312.192036) (xy 311.509665 -312.14676) (xy 311.497888 -312.098976)
			(xy 311.493928 -312.049922) (xy 310.20512 -312.049922) (xy 310.204625 -312.074529) (xy 310.19673 -312.123106)
			(xy 310.181146 -312.169787) (xy 310.158275 -312.213364) (xy 310.12871 -312.252708) (xy 310.093217 -312.2868)
			(xy 310.052714 -312.314756) (xy 310.008252 -312.335854) (xy 309.960981 -312.349546) (xy 309.912126 -312.355478)
			(xy 309.862951 -312.353497) (xy 309.814732 -312.343653) (xy 309.768716 -312.326201) (xy 309.726095 -312.301594)
			(xy 309.687974 -312.270469) (xy 309.655339 -312.233632) (xy 309.629036 -312.192036) (xy 309.609745 -312.14676)
			(xy 309.597968 -312.098976) (xy 309.594008 -312.049922) (xy 308.3052 -312.049922) (xy 308.304705 -312.074529)
			(xy 308.29681 -312.123106) (xy 308.281226 -312.169787) (xy 308.258355 -312.213364) (xy 308.22879 -312.252708)
			(xy 308.193297 -312.2868) (xy 308.152794 -312.314756) (xy 308.108332 -312.335854) (xy 308.061061 -312.349546)
			(xy 308.012206 -312.355478) (xy 307.963031 -312.353497) (xy 307.914812 -312.343653) (xy 307.868796 -312.326201)
			(xy 307.826175 -312.301594) (xy 307.788054 -312.270469) (xy 307.755419 -312.233632) (xy 307.729116 -312.192036)
			(xy 307.709825 -312.14676) (xy 307.698048 -312.098976) (xy 307.694088 -312.049922) (xy 306.405026 -312.049922)
			(xy 306.404531 -312.074529) (xy 306.396636 -312.123106) (xy 306.381052 -312.169787) (xy 306.358181 -312.213364)
			(xy 306.328616 -312.252708) (xy 306.293123 -312.2868) (xy 306.25262 -312.314756) (xy 306.208158 -312.335854)
			(xy 306.160887 -312.349546) (xy 306.112032 -312.355478) (xy 306.062857 -312.353497) (xy 306.014638 -312.343653)
			(xy 305.968622 -312.326201) (xy 305.926001 -312.301594) (xy 305.88788 -312.270469) (xy 305.855245 -312.233632)
			(xy 305.828942 -312.192036) (xy 305.809651 -312.14676) (xy 305.797874 -312.098976) (xy 305.793914 -312.049922)
			(xy 289.305238 -312.049922) (xy 289.304743 -312.074529) (xy 289.296848 -312.123106) (xy 289.281264 -312.169787)
			(xy 289.258393 -312.213364) (xy 289.228828 -312.252708) (xy 289.193335 -312.2868) (xy 289.152832 -312.314756)
			(xy 289.10837 -312.335854) (xy 289.061099 -312.349546) (xy 289.012244 -312.355478) (xy 288.963069 -312.353497)
			(xy 288.91485 -312.343653) (xy 288.868834 -312.326201) (xy 288.826213 -312.301594) (xy 288.788092 -312.270469)
			(xy 288.755457 -312.233632) (xy 288.729154 -312.192036) (xy 288.709863 -312.14676) (xy 288.698086 -312.098976)
			(xy 288.694126 -312.049922) (xy 287.405064 -312.049922) (xy 287.404569 -312.074529) (xy 287.396674 -312.123106)
			(xy 287.38109 -312.169787) (xy 287.358219 -312.213364) (xy 287.328654 -312.252708) (xy 287.293161 -312.2868)
			(xy 287.252658 -312.314756) (xy 287.208196 -312.335854) (xy 287.160925 -312.349546) (xy 287.11207 -312.355478)
			(xy 287.062895 -312.353497) (xy 287.014676 -312.343653) (xy 286.96866 -312.326201) (xy 286.926039 -312.301594)
			(xy 286.887918 -312.270469) (xy 286.855283 -312.233632) (xy 286.82898 -312.192036) (xy 286.809689 -312.14676)
			(xy 286.797912 -312.098976) (xy 286.793952 -312.049922) (xy 285.505144 -312.049922) (xy 285.504649 -312.074529)
			(xy 285.496754 -312.123106) (xy 285.48117 -312.169787) (xy 285.458299 -312.213364) (xy 285.428734 -312.252708)
			(xy 285.393241 -312.2868) (xy 285.352738 -312.314756) (xy 285.308276 -312.335854) (xy 285.261005 -312.349546)
			(xy 285.21215 -312.355478) (xy 285.162975 -312.353497) (xy 285.114756 -312.343653) (xy 285.06874 -312.326201)
			(xy 285.026119 -312.301594) (xy 284.987998 -312.270469) (xy 284.955363 -312.233632) (xy 284.92906 -312.192036)
			(xy 284.909769 -312.14676) (xy 284.897992 -312.098976) (xy 284.894032 -312.049922) (xy 283.605224 -312.049922)
			(xy 283.604729 -312.074529) (xy 283.596834 -312.123106) (xy 283.58125 -312.169787) (xy 283.558379 -312.213364)
			(xy 283.528814 -312.252708) (xy 283.493321 -312.2868) (xy 283.452818 -312.314756) (xy 283.408356 -312.335854)
			(xy 283.361085 -312.349546) (xy 283.31223 -312.355478) (xy 283.263055 -312.353497) (xy 283.214836 -312.343653)
			(xy 283.16882 -312.326201) (xy 283.126199 -312.301594) (xy 283.088078 -312.270469) (xy 283.055443 -312.233632)
			(xy 283.02914 -312.192036) (xy 283.009849 -312.14676) (xy 282.998072 -312.098976) (xy 282.994112 -312.049922)
			(xy 281.70505 -312.049922) (xy 281.704555 -312.074529) (xy 281.69666 -312.123106) (xy 281.681076 -312.169787)
			(xy 281.658205 -312.213364) (xy 281.62864 -312.252708) (xy 281.593147 -312.2868) (xy 281.552644 -312.314756)
			(xy 281.508182 -312.335854) (xy 281.460911 -312.349546) (xy 281.412056 -312.355478) (xy 281.362881 -312.353497)
			(xy 281.314662 -312.343653) (xy 281.268646 -312.326201) (xy 281.226025 -312.301594) (xy 281.187904 -312.270469)
			(xy 281.155269 -312.233632) (xy 281.128966 -312.192036) (xy 281.109675 -312.14676) (xy 281.097898 -312.098976)
			(xy 281.093938 -312.049922) (xy 279.80513 -312.049922) (xy 279.804635 -312.074529) (xy 279.79674 -312.123106)
			(xy 279.781156 -312.169787) (xy 279.758285 -312.213364) (xy 279.72872 -312.252708) (xy 279.693227 -312.2868)
			(xy 279.652724 -312.314756) (xy 279.608262 -312.335854) (xy 279.560991 -312.349546) (xy 279.512136 -312.355478)
			(xy 279.462961 -312.353497) (xy 279.414742 -312.343653) (xy 279.368726 -312.326201) (xy 279.326105 -312.301594)
			(xy 279.287984 -312.270469) (xy 279.255349 -312.233632) (xy 279.229046 -312.192036) (xy 279.209755 -312.14676)
			(xy 279.197978 -312.098976) (xy 279.194018 -312.049922) (xy 277.90521 -312.049922) (xy 277.904715 -312.074529)
			(xy 277.89682 -312.123106) (xy 277.881236 -312.169787) (xy 277.858365 -312.213364) (xy 277.8288 -312.252708)
			(xy 277.793307 -312.2868) (xy 277.752804 -312.314756) (xy 277.708342 -312.335854) (xy 277.661071 -312.349546)
			(xy 277.612216 -312.355478) (xy 277.563041 -312.353497) (xy 277.514822 -312.343653) (xy 277.468806 -312.326201)
			(xy 277.426185 -312.301594) (xy 277.388064 -312.270469) (xy 277.355429 -312.233632) (xy 277.329126 -312.192036)
			(xy 277.309835 -312.14676) (xy 277.298058 -312.098976) (xy 277.294098 -312.049922) (xy 276.005036 -312.049922)
			(xy 276.004541 -312.074529) (xy 275.996646 -312.123106) (xy 275.981062 -312.169787) (xy 275.958191 -312.213364)
			(xy 275.928626 -312.252708) (xy 275.893133 -312.2868) (xy 275.85263 -312.314756) (xy 275.808168 -312.335854)
			(xy 275.760897 -312.349546) (xy 275.712042 -312.355478) (xy 275.662867 -312.353497) (xy 275.614648 -312.343653)
			(xy 275.568632 -312.326201) (xy 275.526011 -312.301594) (xy 275.48789 -312.270469) (xy 275.455255 -312.233632)
			(xy 275.428952 -312.192036) (xy 275.409661 -312.14676) (xy 275.397884 -312.098976) (xy 275.393924 -312.049922)
			(xy 188.405262 -312.049922) (xy 188.404767 -312.074529) (xy 188.396872 -312.123106) (xy 188.381288 -312.169787)
			(xy 188.358417 -312.213364) (xy 188.328852 -312.252708) (xy 188.293359 -312.2868) (xy 188.252856 -312.314756)
			(xy 188.208394 -312.335854) (xy 188.161123 -312.349546) (xy 188.112268 -312.355478) (xy 188.063093 -312.353497)
			(xy 188.014874 -312.343653) (xy 187.968858 -312.326201) (xy 187.926237 -312.301594) (xy 187.888116 -312.270469)
			(xy 187.855481 -312.233632) (xy 187.829178 -312.192036) (xy 187.809887 -312.14676) (xy 187.79811 -312.098976)
			(xy 187.79415 -312.049922) (xy 186.505342 -312.049922) (xy 186.504847 -312.074529) (xy 186.496952 -312.123106)
			(xy 186.481368 -312.169787) (xy 186.458497 -312.213364) (xy 186.428932 -312.252708) (xy 186.393439 -312.2868)
			(xy 186.352936 -312.314756) (xy 186.308474 -312.335854) (xy 186.261203 -312.349546) (xy 186.212348 -312.355478)
			(xy 186.163173 -312.353497) (xy 186.114954 -312.343653) (xy 186.068938 -312.326201) (xy 186.026317 -312.301594)
			(xy 185.988196 -312.270469) (xy 185.955561 -312.233632) (xy 185.929258 -312.192036) (xy 185.909967 -312.14676)
			(xy 185.89819 -312.098976) (xy 185.89423 -312.049922) (xy 184.605168 -312.049922) (xy 184.604673 -312.074529)
			(xy 184.596778 -312.123106) (xy 184.581194 -312.169787) (xy 184.558323 -312.213364) (xy 184.528758 -312.252708)
			(xy 184.493265 -312.2868) (xy 184.452762 -312.314756) (xy 184.4083 -312.335854) (xy 184.361029 -312.349546)
			(xy 184.312174 -312.355478) (xy 184.262999 -312.353497) (xy 184.21478 -312.343653) (xy 184.168764 -312.326201)
			(xy 184.126143 -312.301594) (xy 184.088022 -312.270469) (xy 184.055387 -312.233632) (xy 184.029084 -312.192036)
			(xy 184.009793 -312.14676) (xy 183.998016 -312.098976) (xy 183.994056 -312.049922) (xy 182.705248 -312.049922)
			(xy 182.704753 -312.074529) (xy 182.696858 -312.123106) (xy 182.681274 -312.169787) (xy 182.658403 -312.213364)
			(xy 182.628838 -312.252708) (xy 182.593345 -312.2868) (xy 182.552842 -312.314756) (xy 182.50838 -312.335854)
			(xy 182.461109 -312.349546) (xy 182.412254 -312.355478) (xy 182.363079 -312.353497) (xy 182.31486 -312.343653)
			(xy 182.268844 -312.326201) (xy 182.226223 -312.301594) (xy 182.188102 -312.270469) (xy 182.155467 -312.233632)
			(xy 182.129164 -312.192036) (xy 182.109873 -312.14676) (xy 182.098096 -312.098976) (xy 182.094136 -312.049922)
			(xy 165.605206 -312.049922) (xy 165.604711 -312.074529) (xy 165.596816 -312.123106) (xy 165.581232 -312.169787)
			(xy 165.558361 -312.213364) (xy 165.528796 -312.252708) (xy 165.493303 -312.2868) (xy 165.4528 -312.314756)
			(xy 165.408338 -312.335854) (xy 165.361067 -312.349546) (xy 165.312212 -312.355478) (xy 165.263037 -312.353497)
			(xy 165.214818 -312.343653) (xy 165.168802 -312.326201) (xy 165.126181 -312.301594) (xy 165.08806 -312.270469)
			(xy 165.055425 -312.233632) (xy 165.029122 -312.192036) (xy 165.009831 -312.14676) (xy 164.998054 -312.098976)
			(xy 164.994094 -312.049922) (xy 163.705286 -312.049922) (xy 163.704791 -312.074529) (xy 163.696896 -312.123106)
			(xy 163.681312 -312.169787) (xy 163.658441 -312.213364) (xy 163.628876 -312.252708) (xy 163.593383 -312.2868)
			(xy 163.55288 -312.314756) (xy 163.508418 -312.335854) (xy 163.461147 -312.349546) (xy 163.412292 -312.355478)
			(xy 163.363117 -312.353497) (xy 163.314898 -312.343653) (xy 163.268882 -312.326201) (xy 163.226261 -312.301594)
			(xy 163.18814 -312.270469) (xy 163.155505 -312.233632) (xy 163.129202 -312.192036) (xy 163.109911 -312.14676)
			(xy 163.098134 -312.098976) (xy 163.094174 -312.049922) (xy 161.805366 -312.049922) (xy 161.804871 -312.074529)
			(xy 161.796976 -312.123106) (xy 161.781392 -312.169787) (xy 161.758521 -312.213364) (xy 161.728956 -312.252708)
			(xy 161.693463 -312.2868) (xy 161.65296 -312.314756) (xy 161.608498 -312.335854) (xy 161.561227 -312.349546)
			(xy 161.512372 -312.355478) (xy 161.463197 -312.353497) (xy 161.414978 -312.343653) (xy 161.368962 -312.326201)
			(xy 161.326341 -312.301594) (xy 161.28822 -312.270469) (xy 161.255585 -312.233632) (xy 161.229282 -312.192036)
			(xy 161.209991 -312.14676) (xy 161.198214 -312.098976) (xy 161.194254 -312.049922) (xy 159.905192 -312.049922)
			(xy 159.904697 -312.074529) (xy 159.896802 -312.123106) (xy 159.881218 -312.169787) (xy 159.858347 -312.213364)
			(xy 159.828782 -312.252708) (xy 159.793289 -312.2868) (xy 159.752786 -312.314756) (xy 159.708324 -312.335854)
			(xy 159.661053 -312.349546) (xy 159.612198 -312.355478) (xy 159.563023 -312.353497) (xy 159.514804 -312.343653)
			(xy 159.468788 -312.326201) (xy 159.426167 -312.301594) (xy 159.388046 -312.270469) (xy 159.355411 -312.233632)
			(xy 159.329108 -312.192036) (xy 159.309817 -312.14676) (xy 159.29804 -312.098976) (xy 159.29408 -312.049922)
			(xy 158.005272 -312.049922) (xy 158.004777 -312.074529) (xy 157.996882 -312.123106) (xy 157.981298 -312.169787)
			(xy 157.958427 -312.213364) (xy 157.928862 -312.252708) (xy 157.893369 -312.2868) (xy 157.852866 -312.314756)
			(xy 157.808404 -312.335854) (xy 157.761133 -312.349546) (xy 157.712278 -312.355478) (xy 157.663103 -312.353497)
			(xy 157.614884 -312.343653) (xy 157.568868 -312.326201) (xy 157.526247 -312.301594) (xy 157.488126 -312.270469)
			(xy 157.455491 -312.233632) (xy 157.429188 -312.192036) (xy 157.409897 -312.14676) (xy 157.39812 -312.098976)
			(xy 157.39416 -312.049922) (xy 156.105352 -312.049922) (xy 156.104857 -312.074529) (xy 156.096962 -312.123106)
			(xy 156.081378 -312.169787) (xy 156.058507 -312.213364) (xy 156.028942 -312.252708) (xy 155.993449 -312.2868)
			(xy 155.952946 -312.314756) (xy 155.908484 -312.335854) (xy 155.861213 -312.349546) (xy 155.812358 -312.355478)
			(xy 155.763183 -312.353497) (xy 155.714964 -312.343653) (xy 155.668948 -312.326201) (xy 155.626327 -312.301594)
			(xy 155.588206 -312.270469) (xy 155.555571 -312.233632) (xy 155.529268 -312.192036) (xy 155.509977 -312.14676)
			(xy 155.4982 -312.098976) (xy 155.49424 -312.049922) (xy 154.205178 -312.049922) (xy 154.204683 -312.074529)
			(xy 154.196788 -312.123106) (xy 154.181204 -312.169787) (xy 154.158333 -312.213364) (xy 154.128768 -312.252708)
			(xy 154.093275 -312.2868) (xy 154.052772 -312.314756) (xy 154.00831 -312.335854) (xy 153.961039 -312.349546)
			(xy 153.912184 -312.355478) (xy 153.863009 -312.353497) (xy 153.81479 -312.343653) (xy 153.768774 -312.326201)
			(xy 153.726153 -312.301594) (xy 153.688032 -312.270469) (xy 153.655397 -312.233632) (xy 153.629094 -312.192036)
			(xy 153.609803 -312.14676) (xy 153.598026 -312.098976) (xy 153.594066 -312.049922) (xy 153.255218 -312.049922)
			(xy 153.254723 -312.074529) (xy 153.246828 -312.123106) (xy 153.231244 -312.169787) (xy 153.208373 -312.213364)
			(xy 153.178808 -312.252708) (xy 153.143315 -312.2868) (xy 153.102812 -312.314756) (xy 153.05835 -312.335854)
			(xy 153.011079 -312.349546) (xy 152.962224 -312.355478) (xy 152.913049 -312.353497) (xy 152.86483 -312.343653)
			(xy 152.818814 -312.326201) (xy 152.776193 -312.301594) (xy 152.738072 -312.270469) (xy 152.705437 -312.233632)
			(xy 152.679134 -312.192036) (xy 152.659843 -312.14676) (xy 152.648066 -312.098976) (xy 152.644106 -312.049922)
			(xy 82.755232 -312.049922) (xy 82.754737 -312.074529) (xy 82.746842 -312.123106) (xy 82.731258 -312.169787)
			(xy 82.708387 -312.213364) (xy 82.678822 -312.252708) (xy 82.643329 -312.2868) (xy 82.602826 -312.314756)
			(xy 82.558364 -312.335854) (xy 82.511093 -312.349546) (xy 82.462238 -312.355478) (xy 82.413063 -312.353497)
			(xy 82.364844 -312.343653) (xy 82.318828 -312.326201) (xy 82.276207 -312.301594) (xy 82.238086 -312.270469)
			(xy 82.205451 -312.233632) (xy 82.179148 -312.192036) (xy 82.159857 -312.14676) (xy 82.14808 -312.098976)
			(xy 82.14412 -312.049922) (xy 81.805272 -312.049922) (xy 81.804777 -312.074529) (xy 81.796882 -312.123106)
			(xy 81.781298 -312.169787) (xy 81.758427 -312.213364) (xy 81.728862 -312.252708) (xy 81.693369 -312.2868)
			(xy 81.652866 -312.314756) (xy 81.608404 -312.335854) (xy 81.561133 -312.349546) (xy 81.512278 -312.355478)
			(xy 81.463103 -312.353497) (xy 81.414884 -312.343653) (xy 81.368868 -312.326201) (xy 81.326247 -312.301594)
			(xy 81.288126 -312.270469) (xy 81.255491 -312.233632) (xy 81.229188 -312.192036) (xy 81.209897 -312.14676)
			(xy 81.19812 -312.098976) (xy 81.19416 -312.049922) (xy 79.905098 -312.049922) (xy 79.904603 -312.074529)
			(xy 79.896708 -312.123106) (xy 79.881124 -312.169787) (xy 79.858253 -312.213364) (xy 79.828688 -312.252708)
			(xy 79.793195 -312.2868) (xy 79.752692 -312.314756) (xy 79.70823 -312.335854) (xy 79.660959 -312.349546)
			(xy 79.612104 -312.355478) (xy 79.562929 -312.353497) (xy 79.51471 -312.343653) (xy 79.468694 -312.326201)
			(xy 79.426073 -312.301594) (xy 79.387952 -312.270469) (xy 79.355317 -312.233632) (xy 79.329014 -312.192036)
			(xy 79.309723 -312.14676) (xy 79.297946 -312.098976) (xy 79.293986 -312.049922) (xy 78.005178 -312.049922)
			(xy 78.004683 -312.074529) (xy 77.996788 -312.123106) (xy 77.981204 -312.169787) (xy 77.958333 -312.213364)
			(xy 77.928768 -312.252708) (xy 77.893275 -312.2868) (xy 77.852772 -312.314756) (xy 77.80831 -312.335854)
			(xy 77.761039 -312.349546) (xy 77.712184 -312.355478) (xy 77.663009 -312.353497) (xy 77.61479 -312.343653)
			(xy 77.568774 -312.326201) (xy 77.526153 -312.301594) (xy 77.488032 -312.270469) (xy 77.455397 -312.233632)
			(xy 77.429094 -312.192036) (xy 77.409803 -312.14676) (xy 77.398026 -312.098976) (xy 77.394066 -312.049922)
			(xy 76.105258 -312.049922) (xy 76.104763 -312.074529) (xy 76.096868 -312.123106) (xy 76.081284 -312.169787)
			(xy 76.058413 -312.213364) (xy 76.028848 -312.252708) (xy 75.993355 -312.2868) (xy 75.952852 -312.314756)
			(xy 75.90839 -312.335854) (xy 75.861119 -312.349546) (xy 75.812264 -312.355478) (xy 75.763089 -312.353497)
			(xy 75.71487 -312.343653) (xy 75.668854 -312.326201) (xy 75.626233 -312.301594) (xy 75.588112 -312.270469)
			(xy 75.555477 -312.233632) (xy 75.529174 -312.192036) (xy 75.509883 -312.14676) (xy 75.498106 -312.098976)
			(xy 75.494146 -312.049922) (xy 74.205084 -312.049922) (xy 74.204589 -312.074529) (xy 74.196694 -312.123106)
			(xy 74.18111 -312.169787) (xy 74.158239 -312.213364) (xy 74.128674 -312.252708) (xy 74.093181 -312.2868)
			(xy 74.052678 -312.314756) (xy 74.008216 -312.335854) (xy 73.960945 -312.349546) (xy 73.91209 -312.355478)
			(xy 73.862915 -312.353497) (xy 73.814696 -312.343653) (xy 73.76868 -312.326201) (xy 73.726059 -312.301594)
			(xy 73.687938 -312.270469) (xy 73.655303 -312.233632) (xy 73.629 -312.192036) (xy 73.609709 -312.14676)
			(xy 73.597932 -312.098976) (xy 73.593972 -312.049922) (xy 57.105296 -312.049922) (xy 57.104801 -312.074529)
			(xy 57.096906 -312.123106) (xy 57.081322 -312.169787) (xy 57.058451 -312.213364) (xy 57.028886 -312.252708)
			(xy 56.993393 -312.2868) (xy 56.95289 -312.314756) (xy 56.908428 -312.335854) (xy 56.861157 -312.349546)
			(xy 56.812302 -312.355478) (xy 56.763127 -312.353497) (xy 56.714908 -312.343653) (xy 56.668892 -312.326201)
			(xy 56.626271 -312.301594) (xy 56.58815 -312.270469) (xy 56.555515 -312.233632) (xy 56.529212 -312.192036)
			(xy 56.509921 -312.14676) (xy 56.498144 -312.098976) (xy 56.494184 -312.049922) (xy 55.205122 -312.049922)
			(xy 55.204627 -312.074529) (xy 55.196732 -312.123106) (xy 55.181148 -312.169787) (xy 55.158277 -312.213364)
			(xy 55.128712 -312.252708) (xy 55.093219 -312.2868) (xy 55.052716 -312.314756) (xy 55.008254 -312.335854)
			(xy 54.960983 -312.349546) (xy 54.912128 -312.355478) (xy 54.862953 -312.353497) (xy 54.814734 -312.343653)
			(xy 54.768718 -312.326201) (xy 54.726097 -312.301594) (xy 54.687976 -312.270469) (xy 54.655341 -312.233632)
			(xy 54.629038 -312.192036) (xy 54.609747 -312.14676) (xy 54.59797 -312.098976) (xy 54.59401 -312.049922)
			(xy 53.305202 -312.049922) (xy 53.304707 -312.074529) (xy 53.296812 -312.123106) (xy 53.281228 -312.169787)
			(xy 53.258357 -312.213364) (xy 53.228792 -312.252708) (xy 53.193299 -312.2868) (xy 53.152796 -312.314756)
			(xy 53.108334 -312.335854) (xy 53.061063 -312.349546) (xy 53.012208 -312.355478) (xy 52.963033 -312.353497)
			(xy 52.914814 -312.343653) (xy 52.868798 -312.326201) (xy 52.826177 -312.301594) (xy 52.788056 -312.270469)
			(xy 52.755421 -312.233632) (xy 52.729118 -312.192036) (xy 52.709827 -312.14676) (xy 52.69805 -312.098976)
			(xy 52.69409 -312.049922) (xy 51.405282 -312.049922) (xy 51.404787 -312.074529) (xy 51.396892 -312.123106)
			(xy 51.381308 -312.169787) (xy 51.358437 -312.213364) (xy 51.328872 -312.252708) (xy 51.293379 -312.2868)
			(xy 51.252876 -312.314756) (xy 51.208414 -312.335854) (xy 51.161143 -312.349546) (xy 51.112288 -312.355478)
			(xy 51.063113 -312.353497) (xy 51.014894 -312.343653) (xy 50.968878 -312.326201) (xy 50.926257 -312.301594)
			(xy 50.888136 -312.270469) (xy 50.855501 -312.233632) (xy 50.829198 -312.192036) (xy 50.809907 -312.14676)
			(xy 50.79813 -312.098976) (xy 50.79417 -312.049922) (xy 49.505108 -312.049922) (xy 49.504613 -312.074529)
			(xy 49.496718 -312.123106) (xy 49.481134 -312.169787) (xy 49.458263 -312.213364) (xy 49.428698 -312.252708)
			(xy 49.393205 -312.2868) (xy 49.352702 -312.314756) (xy 49.30824 -312.335854) (xy 49.260969 -312.349546)
			(xy 49.212114 -312.355478) (xy 49.162939 -312.353497) (xy 49.11472 -312.343653) (xy 49.068704 -312.326201)
			(xy 49.026083 -312.301594) (xy 48.987962 -312.270469) (xy 48.955327 -312.233632) (xy 48.929024 -312.192036)
			(xy 48.909733 -312.14676) (xy 48.897956 -312.098976) (xy 48.893996 -312.049922) (xy 47.605188 -312.049922)
			(xy 47.604693 -312.074529) (xy 47.596798 -312.123106) (xy 47.581214 -312.169787) (xy 47.558343 -312.213364)
			(xy 47.528778 -312.252708) (xy 47.493285 -312.2868) (xy 47.452782 -312.314756) (xy 47.40832 -312.335854)
			(xy 47.361049 -312.349546) (xy 47.312194 -312.355478) (xy 47.263019 -312.353497) (xy 47.2148 -312.343653)
			(xy 47.168784 -312.326201) (xy 47.126163 -312.301594) (xy 47.088042 -312.270469) (xy 47.055407 -312.233632)
			(xy 47.029104 -312.192036) (xy 47.009813 -312.14676) (xy 46.998036 -312.098976) (xy 46.994076 -312.049922)
			(xy 45.705268 -312.049922) (xy 45.704773 -312.074529) (xy 45.696878 -312.123106) (xy 45.681294 -312.169787)
			(xy 45.658423 -312.213364) (xy 45.628858 -312.252708) (xy 45.593365 -312.2868) (xy 45.552862 -312.314756)
			(xy 45.5084 -312.335854) (xy 45.461129 -312.349546) (xy 45.412274 -312.355478) (xy 45.363099 -312.353497)
			(xy 45.31488 -312.343653) (xy 45.268864 -312.326201) (xy 45.226243 -312.301594) (xy 45.188122 -312.270469)
			(xy 45.155487 -312.233632) (xy 45.129184 -312.192036) (xy 45.109893 -312.14676) (xy 45.098116 -312.098976)
			(xy 45.094156 -312.049922) (xy 43.805094 -312.049922) (xy 43.804599 -312.074529) (xy 43.796704 -312.123106)
			(xy 43.78112 -312.169787) (xy 43.758249 -312.213364) (xy 43.728684 -312.252708) (xy 43.693191 -312.2868)
			(xy 43.652688 -312.314756) (xy 43.608226 -312.335854) (xy 43.560955 -312.349546) (xy 43.5121 -312.355478)
			(xy 43.462925 -312.353497) (xy 43.414706 -312.343653) (xy 43.36869 -312.326201) (xy 43.326069 -312.301594)
			(xy 43.287948 -312.270469) (xy 43.255313 -312.233632) (xy 43.22901 -312.192036) (xy 43.209719 -312.14676)
			(xy 43.197942 -312.098976) (xy 43.193982 -312.049922) (xy 0.508 -312.049922) (xy 0.508 -312.999882)
			(xy 44.143942 -312.999882) (xy 44.147902 -312.950828) (xy 44.159679 -312.903044) (xy 44.17897 -312.857768)
			(xy 44.205273 -312.816172) (xy 44.237908 -312.779335) (xy 44.276029 -312.74821) (xy 44.31865 -312.723603)
			(xy 44.364666 -312.706151) (xy 44.412885 -312.696307) (xy 44.46206 -312.694326) (xy 44.510915 -312.700258)
			(xy 44.558186 -312.71395) (xy 44.602648 -312.735048) (xy 44.643151 -312.763004) (xy 44.678644 -312.797096)
			(xy 44.708209 -312.83644) (xy 44.73108 -312.880017) (xy 44.746664 -312.926698) (xy 44.754559 -312.975275)
			(xy 44.755054 -312.999882) (xy 46.044116 -312.999882) (xy 46.048076 -312.950828) (xy 46.059853 -312.903044)
			(xy 46.079144 -312.857768) (xy 46.105447 -312.816172) (xy 46.138082 -312.779335) (xy 46.176203 -312.74821)
			(xy 46.218824 -312.723603) (xy 46.26484 -312.706151) (xy 46.313059 -312.696307) (xy 46.362234 -312.694326)
			(xy 46.411089 -312.700258) (xy 46.45836 -312.71395) (xy 46.502822 -312.735048) (xy 46.543325 -312.763004)
			(xy 46.578818 -312.797096) (xy 46.608383 -312.83644) (xy 46.631254 -312.880017) (xy 46.646838 -312.926698)
			(xy 46.654733 -312.975275) (xy 46.655228 -312.999882) (xy 47.944036 -312.999882) (xy 47.947996 -312.950828)
			(xy 47.959773 -312.903044) (xy 47.979064 -312.857768) (xy 48.005367 -312.816172) (xy 48.038002 -312.779335)
			(xy 48.076123 -312.74821) (xy 48.118744 -312.723603) (xy 48.16476 -312.706151) (xy 48.212979 -312.696307)
			(xy 48.262154 -312.694326) (xy 48.311009 -312.700258) (xy 48.35828 -312.71395) (xy 48.402742 -312.735048)
			(xy 48.443245 -312.763004) (xy 48.478738 -312.797096) (xy 48.508303 -312.83644) (xy 48.531174 -312.880017)
			(xy 48.546758 -312.926698) (xy 48.554653 -312.975275) (xy 48.555148 -312.999882) (xy 49.843956 -312.999882)
			(xy 49.847916 -312.950828) (xy 49.859693 -312.903044) (xy 49.878984 -312.857768) (xy 49.905287 -312.816172)
			(xy 49.937922 -312.779335) (xy 49.976043 -312.74821) (xy 50.018664 -312.723603) (xy 50.06468 -312.706151)
			(xy 50.112899 -312.696307) (xy 50.162074 -312.694326) (xy 50.210929 -312.700258) (xy 50.2582 -312.71395)
			(xy 50.302662 -312.735048) (xy 50.343165 -312.763004) (xy 50.378658 -312.797096) (xy 50.408223 -312.83644)
			(xy 50.431094 -312.880017) (xy 50.446678 -312.926698) (xy 50.454573 -312.975275) (xy 50.455068 -312.999882)
			(xy 51.74413 -312.999882) (xy 51.74809 -312.950828) (xy 51.759867 -312.903044) (xy 51.779158 -312.857768)
			(xy 51.805461 -312.816172) (xy 51.838096 -312.779335) (xy 51.876217 -312.74821) (xy 51.918838 -312.723603)
			(xy 51.964854 -312.706151) (xy 52.013073 -312.696307) (xy 52.062248 -312.694326) (xy 52.111103 -312.700258)
			(xy 52.158374 -312.71395) (xy 52.202836 -312.735048) (xy 52.243339 -312.763004) (xy 52.278832 -312.797096)
			(xy 52.308397 -312.83644) (xy 52.331268 -312.880017) (xy 52.346852 -312.926698) (xy 52.354747 -312.975275)
			(xy 52.355242 -312.999882) (xy 53.64405 -312.999882) (xy 53.64801 -312.950828) (xy 53.659787 -312.903044)
			(xy 53.679078 -312.857768) (xy 53.705381 -312.816172) (xy 53.738016 -312.779335) (xy 53.776137 -312.74821)
			(xy 53.818758 -312.723603) (xy 53.864774 -312.706151) (xy 53.912993 -312.696307) (xy 53.962168 -312.694326)
			(xy 54.011023 -312.700258) (xy 54.058294 -312.71395) (xy 54.102756 -312.735048) (xy 54.143259 -312.763004)
			(xy 54.178752 -312.797096) (xy 54.208317 -312.83644) (xy 54.231188 -312.880017) (xy 54.246772 -312.926698)
			(xy 54.254667 -312.975275) (xy 54.255162 -312.999882) (xy 55.54397 -312.999882) (xy 55.54793 -312.950828)
			(xy 55.559707 -312.903044) (xy 55.578998 -312.857768) (xy 55.605301 -312.816172) (xy 55.637936 -312.779335)
			(xy 55.676057 -312.74821) (xy 55.718678 -312.723603) (xy 55.764694 -312.706151) (xy 55.812913 -312.696307)
			(xy 55.862088 -312.694326) (xy 55.910943 -312.700258) (xy 55.958214 -312.71395) (xy 56.002676 -312.735048)
			(xy 56.043179 -312.763004) (xy 56.078672 -312.797096) (xy 56.108237 -312.83644) (xy 56.131108 -312.880017)
			(xy 56.146692 -312.926698) (xy 56.154587 -312.975275) (xy 56.155082 -312.999882) (xy 57.444144 -312.999882)
			(xy 57.448104 -312.950828) (xy 57.459881 -312.903044) (xy 57.479172 -312.857768) (xy 57.505475 -312.816172)
			(xy 57.53811 -312.779335) (xy 57.576231 -312.74821) (xy 57.618852 -312.723603) (xy 57.664868 -312.706151)
			(xy 57.713087 -312.696307) (xy 57.762262 -312.694326) (xy 57.811117 -312.700258) (xy 57.858388 -312.71395)
			(xy 57.90285 -312.735048) (xy 57.943353 -312.763004) (xy 57.978846 -312.797096) (xy 58.008411 -312.83644)
			(xy 58.031282 -312.880017) (xy 58.046866 -312.926698) (xy 58.054761 -312.975275) (xy 58.055256 -312.999882)
			(xy 74.544186 -312.999882) (xy 74.548146 -312.950828) (xy 74.559923 -312.903044) (xy 74.579214 -312.857768)
			(xy 74.605517 -312.816172) (xy 74.638152 -312.779335) (xy 74.676273 -312.74821) (xy 74.718894 -312.723603)
			(xy 74.76491 -312.706151) (xy 74.813129 -312.696307) (xy 74.862304 -312.694326) (xy 74.911159 -312.700258)
			(xy 74.95843 -312.71395) (xy 75.002892 -312.735048) (xy 75.043395 -312.763004) (xy 75.078888 -312.797096)
			(xy 75.108453 -312.83644) (xy 75.131324 -312.880017) (xy 75.146908 -312.926698) (xy 75.154803 -312.975275)
			(xy 75.155298 -312.999882) (xy 76.444106 -312.999882) (xy 76.448066 -312.950828) (xy 76.459843 -312.903044)
			(xy 76.479134 -312.857768) (xy 76.505437 -312.816172) (xy 76.538072 -312.779335) (xy 76.576193 -312.74821)
			(xy 76.618814 -312.723603) (xy 76.66483 -312.706151) (xy 76.713049 -312.696307) (xy 76.762224 -312.694326)
			(xy 76.811079 -312.700258) (xy 76.85835 -312.71395) (xy 76.902812 -312.735048) (xy 76.943315 -312.763004)
			(xy 76.978808 -312.797096) (xy 77.008373 -312.83644) (xy 77.031244 -312.880017) (xy 77.046828 -312.926698)
			(xy 77.054723 -312.975275) (xy 77.055218 -312.999882) (xy 78.344026 -312.999882) (xy 78.347986 -312.950828)
			(xy 78.359763 -312.903044) (xy 78.379054 -312.857768) (xy 78.405357 -312.816172) (xy 78.437992 -312.779335)
			(xy 78.476113 -312.74821) (xy 78.518734 -312.723603) (xy 78.56475 -312.706151) (xy 78.612969 -312.696307)
			(xy 78.662144 -312.694326) (xy 78.710999 -312.700258) (xy 78.75827 -312.71395) (xy 78.802732 -312.735048)
			(xy 78.843235 -312.763004) (xy 78.878728 -312.797096) (xy 78.908293 -312.83644) (xy 78.931164 -312.880017)
			(xy 78.946748 -312.926698) (xy 78.954643 -312.975275) (xy 78.955138 -312.999882) (xy 80.243946 -312.999882)
			(xy 80.247906 -312.950828) (xy 80.259683 -312.903044) (xy 80.278974 -312.857768) (xy 80.305277 -312.816172)
			(xy 80.337912 -312.779335) (xy 80.376033 -312.74821) (xy 80.418654 -312.723603) (xy 80.46467 -312.706151)
			(xy 80.512889 -312.696307) (xy 80.562064 -312.694326) (xy 80.610919 -312.700258) (xy 80.65819 -312.71395)
			(xy 80.702652 -312.735048) (xy 80.743155 -312.763004) (xy 80.778648 -312.797096) (xy 80.808213 -312.83644)
			(xy 80.831084 -312.880017) (xy 80.846668 -312.926698) (xy 80.854563 -312.975275) (xy 80.855058 -312.999882)
			(xy 154.54428 -312.999882) (xy 154.54824 -312.950828) (xy 154.560017 -312.903044) (xy 154.579308 -312.857768)
			(xy 154.605611 -312.816172) (xy 154.638246 -312.779335) (xy 154.676367 -312.74821) (xy 154.718988 -312.723603)
			(xy 154.765004 -312.706151) (xy 154.813223 -312.696307) (xy 154.862398 -312.694326) (xy 154.911253 -312.700258)
			(xy 154.958524 -312.71395) (xy 155.002986 -312.735048) (xy 155.043489 -312.763004) (xy 155.078982 -312.797096)
			(xy 155.108547 -312.83644) (xy 155.131418 -312.880017) (xy 155.147002 -312.926698) (xy 155.154897 -312.975275)
			(xy 155.155392 -312.999882) (xy 156.4442 -312.999882) (xy 156.44816 -312.950828) (xy 156.459937 -312.903044)
			(xy 156.479228 -312.857768) (xy 156.505531 -312.816172) (xy 156.538166 -312.779335) (xy 156.576287 -312.74821)
			(xy 156.618908 -312.723603) (xy 156.664924 -312.706151) (xy 156.713143 -312.696307) (xy 156.762318 -312.694326)
			(xy 156.811173 -312.700258) (xy 156.858444 -312.71395) (xy 156.902906 -312.735048) (xy 156.943409 -312.763004)
			(xy 156.978902 -312.797096) (xy 157.008467 -312.83644) (xy 157.031338 -312.880017) (xy 157.046922 -312.926698)
			(xy 157.054817 -312.975275) (xy 157.055312 -312.999882) (xy 158.34412 -312.999882) (xy 158.34808 -312.950828)
			(xy 158.359857 -312.903044) (xy 158.379148 -312.857768) (xy 158.405451 -312.816172) (xy 158.438086 -312.779335)
			(xy 158.476207 -312.74821) (xy 158.518828 -312.723603) (xy 158.564844 -312.706151) (xy 158.613063 -312.696307)
			(xy 158.662238 -312.694326) (xy 158.711093 -312.700258) (xy 158.758364 -312.71395) (xy 158.802826 -312.735048)
			(xy 158.843329 -312.763004) (xy 158.878822 -312.797096) (xy 158.908387 -312.83644) (xy 158.931258 -312.880017)
			(xy 158.946842 -312.926698) (xy 158.954737 -312.975275) (xy 158.955232 -312.999882) (xy 160.24404 -312.999882)
			(xy 160.248 -312.950828) (xy 160.259777 -312.903044) (xy 160.279068 -312.857768) (xy 160.305371 -312.816172)
			(xy 160.338006 -312.779335) (xy 160.376127 -312.74821) (xy 160.418748 -312.723603) (xy 160.464764 -312.706151)
			(xy 160.512983 -312.696307) (xy 160.562158 -312.694326) (xy 160.611013 -312.700258) (xy 160.658284 -312.71395)
			(xy 160.702746 -312.735048) (xy 160.743249 -312.763004) (xy 160.778742 -312.797096) (xy 160.808307 -312.83644)
			(xy 160.831178 -312.880017) (xy 160.846762 -312.926698) (xy 160.854657 -312.975275) (xy 160.855152 -312.999882)
			(xy 162.144214 -312.999882) (xy 162.148174 -312.950828) (xy 162.159951 -312.903044) (xy 162.179242 -312.857768)
			(xy 162.205545 -312.816172) (xy 162.23818 -312.779335) (xy 162.276301 -312.74821) (xy 162.318922 -312.723603)
			(xy 162.364938 -312.706151) (xy 162.413157 -312.696307) (xy 162.462332 -312.694326) (xy 162.511187 -312.700258)
			(xy 162.558458 -312.71395) (xy 162.60292 -312.735048) (xy 162.643423 -312.763004) (xy 162.678916 -312.797096)
			(xy 162.708481 -312.83644) (xy 162.731352 -312.880017) (xy 162.746936 -312.926698) (xy 162.754831 -312.975275)
			(xy 162.755326 -312.999882) (xy 164.044134 -312.999882) (xy 164.048094 -312.950828) (xy 164.059871 -312.903044)
			(xy 164.079162 -312.857768) (xy 164.105465 -312.816172) (xy 164.1381 -312.779335) (xy 164.176221 -312.74821)
			(xy 164.218842 -312.723603) (xy 164.264858 -312.706151) (xy 164.313077 -312.696307) (xy 164.362252 -312.694326)
			(xy 164.411107 -312.700258) (xy 164.458378 -312.71395) (xy 164.50284 -312.735048) (xy 164.543343 -312.763004)
			(xy 164.578836 -312.797096) (xy 164.608401 -312.83644) (xy 164.631272 -312.880017) (xy 164.646856 -312.926698)
			(xy 164.654751 -312.975275) (xy 164.655246 -312.999882) (xy 165.944054 -312.999882) (xy 165.948014 -312.950828)
			(xy 165.959791 -312.903044) (xy 165.979082 -312.857768) (xy 166.005385 -312.816172) (xy 166.03802 -312.779335)
			(xy 166.076141 -312.74821) (xy 166.118762 -312.723603) (xy 166.164778 -312.706151) (xy 166.212997 -312.696307)
			(xy 166.262172 -312.694326) (xy 166.311027 -312.700258) (xy 166.358298 -312.71395) (xy 166.40276 -312.735048)
			(xy 166.443263 -312.763004) (xy 166.478756 -312.797096) (xy 166.508321 -312.83644) (xy 166.531192 -312.880017)
			(xy 166.546776 -312.926698) (xy 166.554671 -312.975275) (xy 166.555166 -312.999882) (xy 183.044096 -312.999882)
			(xy 183.048056 -312.950828) (xy 183.059833 -312.903044) (xy 183.079124 -312.857768) (xy 183.105427 -312.816172)
			(xy 183.138062 -312.779335) (xy 183.176183 -312.74821) (xy 183.218804 -312.723603) (xy 183.26482 -312.706151)
			(xy 183.313039 -312.696307) (xy 183.362214 -312.694326) (xy 183.411069 -312.700258) (xy 183.45834 -312.71395)
			(xy 183.502802 -312.735048) (xy 183.543305 -312.763004) (xy 183.578798 -312.797096) (xy 183.608363 -312.83644)
			(xy 183.631234 -312.880017) (xy 183.646818 -312.926698) (xy 183.654713 -312.975275) (xy 183.655208 -312.999882)
			(xy 184.94427 -312.999882) (xy 184.94823 -312.950828) (xy 184.960007 -312.903044) (xy 184.979298 -312.857768)
			(xy 185.005601 -312.816172) (xy 185.038236 -312.779335) (xy 185.076357 -312.74821) (xy 185.118978 -312.723603)
			(xy 185.164994 -312.706151) (xy 185.213213 -312.696307) (xy 185.262388 -312.694326) (xy 185.311243 -312.700258)
			(xy 185.358514 -312.71395) (xy 185.402976 -312.735048) (xy 185.443479 -312.763004) (xy 185.478972 -312.797096)
			(xy 185.508537 -312.83644) (xy 185.531408 -312.880017) (xy 185.546992 -312.926698) (xy 185.554887 -312.975275)
			(xy 185.555382 -312.999882) (xy 186.84419 -312.999882) (xy 186.84815 -312.950828) (xy 186.859927 -312.903044)
			(xy 186.879218 -312.857768) (xy 186.905521 -312.816172) (xy 186.938156 -312.779335) (xy 186.976277 -312.74821)
			(xy 187.018898 -312.723603) (xy 187.064914 -312.706151) (xy 187.113133 -312.696307) (xy 187.162308 -312.694326)
			(xy 187.211163 -312.700258) (xy 187.258434 -312.71395) (xy 187.302896 -312.735048) (xy 187.343399 -312.763004)
			(xy 187.378892 -312.797096) (xy 187.408457 -312.83644) (xy 187.431328 -312.880017) (xy 187.446912 -312.926698)
			(xy 187.454807 -312.975275) (xy 187.455302 -312.999882) (xy 188.74411 -312.999882) (xy 188.74807 -312.950828)
			(xy 188.759847 -312.903044) (xy 188.779138 -312.857768) (xy 188.805441 -312.816172) (xy 188.838076 -312.779335)
			(xy 188.876197 -312.74821) (xy 188.918818 -312.723603) (xy 188.964834 -312.706151) (xy 189.013053 -312.696307)
			(xy 189.062228 -312.694326) (xy 189.111083 -312.700258) (xy 189.158354 -312.71395) (xy 189.202816 -312.735048)
			(xy 189.243319 -312.763004) (xy 189.278812 -312.797096) (xy 189.308377 -312.83644) (xy 189.331248 -312.880017)
			(xy 189.346832 -312.926698) (xy 189.354727 -312.975275) (xy 189.355222 -312.999882) (xy 276.343884 -312.999882)
			(xy 276.347844 -312.950828) (xy 276.359621 -312.903044) (xy 276.378912 -312.857768) (xy 276.405215 -312.816172)
			(xy 276.43785 -312.779335) (xy 276.475971 -312.74821) (xy 276.518592 -312.723603) (xy 276.564608 -312.706151)
			(xy 276.612827 -312.696307) (xy 276.662002 -312.694326) (xy 276.710857 -312.700258) (xy 276.758128 -312.71395)
			(xy 276.80259 -312.735048) (xy 276.843093 -312.763004) (xy 276.878586 -312.797096) (xy 276.908151 -312.83644)
			(xy 276.931022 -312.880017) (xy 276.946606 -312.926698) (xy 276.954501 -312.975275) (xy 276.954996 -312.999882)
			(xy 278.244058 -312.999882) (xy 278.248018 -312.950828) (xy 278.259795 -312.903044) (xy 278.279086 -312.857768)
			(xy 278.305389 -312.816172) (xy 278.338024 -312.779335) (xy 278.376145 -312.74821) (xy 278.418766 -312.723603)
			(xy 278.464782 -312.706151) (xy 278.513001 -312.696307) (xy 278.562176 -312.694326) (xy 278.611031 -312.700258)
			(xy 278.658302 -312.71395) (xy 278.702764 -312.735048) (xy 278.743267 -312.763004) (xy 278.77876 -312.797096)
			(xy 278.808325 -312.83644) (xy 278.831196 -312.880017) (xy 278.84678 -312.926698) (xy 278.854675 -312.975275)
			(xy 278.85517 -312.999882) (xy 280.143978 -312.999882) (xy 280.147938 -312.950828) (xy 280.159715 -312.903044)
			(xy 280.179006 -312.857768) (xy 280.205309 -312.816172) (xy 280.237944 -312.779335) (xy 280.276065 -312.74821)
			(xy 280.318686 -312.723603) (xy 280.364702 -312.706151) (xy 280.412921 -312.696307) (xy 280.462096 -312.694326)
			(xy 280.510951 -312.700258) (xy 280.558222 -312.71395) (xy 280.602684 -312.735048) (xy 280.643187 -312.763004)
			(xy 280.67868 -312.797096) (xy 280.708245 -312.83644) (xy 280.731116 -312.880017) (xy 280.7467 -312.926698)
			(xy 280.754595 -312.975275) (xy 280.75509 -312.999882) (xy 282.043898 -312.999882) (xy 282.047858 -312.950828)
			(xy 282.059635 -312.903044) (xy 282.078926 -312.857768) (xy 282.105229 -312.816172) (xy 282.137864 -312.779335)
			(xy 282.175985 -312.74821) (xy 282.218606 -312.723603) (xy 282.264622 -312.706151) (xy 282.312841 -312.696307)
			(xy 282.362016 -312.694326) (xy 282.410871 -312.700258) (xy 282.458142 -312.71395) (xy 282.502604 -312.735048)
			(xy 282.543107 -312.763004) (xy 282.5786 -312.797096) (xy 282.608165 -312.83644) (xy 282.631036 -312.880017)
			(xy 282.64662 -312.926698) (xy 282.654515 -312.975275) (xy 282.65501 -312.999882) (xy 283.944072 -312.999882)
			(xy 283.948032 -312.950828) (xy 283.959809 -312.903044) (xy 283.9791 -312.857768) (xy 284.005403 -312.816172)
			(xy 284.038038 -312.779335) (xy 284.076159 -312.74821) (xy 284.11878 -312.723603) (xy 284.164796 -312.706151)
			(xy 284.213015 -312.696307) (xy 284.26219 -312.694326) (xy 284.311045 -312.700258) (xy 284.358316 -312.71395)
			(xy 284.402778 -312.735048) (xy 284.443281 -312.763004) (xy 284.478774 -312.797096) (xy 284.508339 -312.83644)
			(xy 284.53121 -312.880017) (xy 284.546794 -312.926698) (xy 284.554689 -312.975275) (xy 284.555184 -312.999882)
			(xy 285.843992 -312.999882) (xy 285.847952 -312.950828) (xy 285.859729 -312.903044) (xy 285.87902 -312.857768)
			(xy 285.905323 -312.816172) (xy 285.937958 -312.779335) (xy 285.976079 -312.74821) (xy 286.0187 -312.723603)
			(xy 286.064716 -312.706151) (xy 286.112935 -312.696307) (xy 286.16211 -312.694326) (xy 286.210965 -312.700258)
			(xy 286.258236 -312.71395) (xy 286.302698 -312.735048) (xy 286.343201 -312.763004) (xy 286.378694 -312.797096)
			(xy 286.408259 -312.83644) (xy 286.43113 -312.880017) (xy 286.446714 -312.926698) (xy 286.454609 -312.975275)
			(xy 286.455104 -312.999882) (xy 287.743912 -312.999882) (xy 287.747872 -312.950828) (xy 287.759649 -312.903044)
			(xy 287.77894 -312.857768) (xy 287.805243 -312.816172) (xy 287.837878 -312.779335) (xy 287.875999 -312.74821)
			(xy 287.91862 -312.723603) (xy 287.964636 -312.706151) (xy 288.012855 -312.696307) (xy 288.06203 -312.694326)
			(xy 288.110885 -312.700258) (xy 288.158156 -312.71395) (xy 288.202618 -312.735048) (xy 288.243121 -312.763004)
			(xy 288.278614 -312.797096) (xy 288.308179 -312.83644) (xy 288.33105 -312.880017) (xy 288.346634 -312.926698)
			(xy 288.354529 -312.975275) (xy 288.355024 -312.999882) (xy 289.644086 -312.999882) (xy 289.648046 -312.950828)
			(xy 289.659823 -312.903044) (xy 289.679114 -312.857768) (xy 289.705417 -312.816172) (xy 289.738052 -312.779335)
			(xy 289.776173 -312.74821) (xy 289.818794 -312.723603) (xy 289.86481 -312.706151) (xy 289.913029 -312.696307)
			(xy 289.962204 -312.694326) (xy 290.011059 -312.700258) (xy 290.05833 -312.71395) (xy 290.102792 -312.735048)
			(xy 290.143295 -312.763004) (xy 290.178788 -312.797096) (xy 290.208353 -312.83644) (xy 290.231224 -312.880017)
			(xy 290.246808 -312.926698) (xy 290.254703 -312.975275) (xy 290.255198 -312.999882) (xy 306.744128 -312.999882)
			(xy 306.748088 -312.950828) (xy 306.759865 -312.903044) (xy 306.779156 -312.857768) (xy 306.805459 -312.816172)
			(xy 306.838094 -312.779335) (xy 306.876215 -312.74821) (xy 306.918836 -312.723603) (xy 306.964852 -312.706151)
			(xy 307.013071 -312.696307) (xy 307.062246 -312.694326) (xy 307.111101 -312.700258) (xy 307.158372 -312.71395)
			(xy 307.202834 -312.735048) (xy 307.243337 -312.763004) (xy 307.27883 -312.797096) (xy 307.308395 -312.83644)
			(xy 307.331266 -312.880017) (xy 307.34685 -312.926698) (xy 307.354745 -312.975275) (xy 307.35524 -312.999882)
			(xy 308.644048 -312.999882) (xy 308.648008 -312.950828) (xy 308.659785 -312.903044) (xy 308.679076 -312.857768)
			(xy 308.705379 -312.816172) (xy 308.738014 -312.779335) (xy 308.776135 -312.74821) (xy 308.818756 -312.723603)
			(xy 308.864772 -312.706151) (xy 308.912991 -312.696307) (xy 308.962166 -312.694326) (xy 309.011021 -312.700258)
			(xy 309.058292 -312.71395) (xy 309.102754 -312.735048) (xy 309.143257 -312.763004) (xy 309.17875 -312.797096)
			(xy 309.208315 -312.83644) (xy 309.231186 -312.880017) (xy 309.24677 -312.926698) (xy 309.254665 -312.975275)
			(xy 309.25516 -312.999882) (xy 310.543968 -312.999882) (xy 310.547928 -312.950828) (xy 310.559705 -312.903044)
			(xy 310.578996 -312.857768) (xy 310.605299 -312.816172) (xy 310.637934 -312.779335) (xy 310.676055 -312.74821)
			(xy 310.718676 -312.723603) (xy 310.764692 -312.706151) (xy 310.812911 -312.696307) (xy 310.862086 -312.694326)
			(xy 310.910941 -312.700258) (xy 310.958212 -312.71395) (xy 311.002674 -312.735048) (xy 311.043177 -312.763004)
			(xy 311.07867 -312.797096) (xy 311.108235 -312.83644) (xy 311.131106 -312.880017) (xy 311.14669 -312.926698)
			(xy 311.154585 -312.975275) (xy 311.15508 -312.999882) (xy 312.443888 -312.999882) (xy 312.447848 -312.950828)
			(xy 312.459625 -312.903044) (xy 312.478916 -312.857768) (xy 312.505219 -312.816172) (xy 312.537854 -312.779335)
			(xy 312.575975 -312.74821) (xy 312.618596 -312.723603) (xy 312.664612 -312.706151) (xy 312.712831 -312.696307)
			(xy 312.762006 -312.694326) (xy 312.810861 -312.700258) (xy 312.858132 -312.71395) (xy 312.902594 -312.735048)
			(xy 312.943097 -312.763004) (xy 312.97859 -312.797096) (xy 313.008155 -312.83644) (xy 313.031026 -312.880017)
			(xy 313.04661 -312.926698) (xy 313.054505 -312.975275) (xy 313.055 -312.999882) (xy 386.744222 -312.999882)
			(xy 386.748182 -312.950828) (xy 386.759959 -312.903044) (xy 386.77925 -312.857768) (xy 386.805553 -312.816172)
			(xy 386.838188 -312.779335) (xy 386.876309 -312.74821) (xy 386.91893 -312.723603) (xy 386.964946 -312.706151)
			(xy 387.013165 -312.696307) (xy 387.06234 -312.694326) (xy 387.111195 -312.700258) (xy 387.158466 -312.71395)
			(xy 387.202928 -312.735048) (xy 387.243431 -312.763004) (xy 387.278924 -312.797096) (xy 387.308489 -312.83644)
			(xy 387.33136 -312.880017) (xy 387.346944 -312.926698) (xy 387.354839 -312.975275) (xy 387.355334 -312.999882)
			(xy 388.644142 -312.999882) (xy 388.648102 -312.950828) (xy 388.659879 -312.903044) (xy 388.67917 -312.857768)
			(xy 388.705473 -312.816172) (xy 388.738108 -312.779335) (xy 388.776229 -312.74821) (xy 388.81885 -312.723603)
			(xy 388.864866 -312.706151) (xy 388.913085 -312.696307) (xy 388.96226 -312.694326) (xy 389.011115 -312.700258)
			(xy 389.058386 -312.71395) (xy 389.102848 -312.735048) (xy 389.143351 -312.763004) (xy 389.178844 -312.797096)
			(xy 389.208409 -312.83644) (xy 389.23128 -312.880017) (xy 389.246864 -312.926698) (xy 389.254759 -312.975275)
			(xy 389.255254 -312.999882) (xy 390.544062 -312.999882) (xy 390.548022 -312.950828) (xy 390.559799 -312.903044)
			(xy 390.57909 -312.857768) (xy 390.605393 -312.816172) (xy 390.638028 -312.779335) (xy 390.676149 -312.74821)
			(xy 390.71877 -312.723603) (xy 390.764786 -312.706151) (xy 390.813005 -312.696307) (xy 390.86218 -312.694326)
			(xy 390.911035 -312.700258) (xy 390.958306 -312.71395) (xy 391.002768 -312.735048) (xy 391.043271 -312.763004)
			(xy 391.078764 -312.797096) (xy 391.108329 -312.83644) (xy 391.1312 -312.880017) (xy 391.146784 -312.926698)
			(xy 391.154679 -312.975275) (xy 391.155174 -312.999882) (xy 392.443982 -312.999882) (xy 392.447942 -312.950828)
			(xy 392.459719 -312.903044) (xy 392.47901 -312.857768) (xy 392.505313 -312.816172) (xy 392.537948 -312.779335)
			(xy 392.576069 -312.74821) (xy 392.61869 -312.723603) (xy 392.664706 -312.706151) (xy 392.712925 -312.696307)
			(xy 392.7621 -312.694326) (xy 392.810955 -312.700258) (xy 392.858226 -312.71395) (xy 392.902688 -312.735048)
			(xy 392.943191 -312.763004) (xy 392.978684 -312.797096) (xy 393.008249 -312.83644) (xy 393.03112 -312.880017)
			(xy 393.046704 -312.926698) (xy 393.054599 -312.975275) (xy 393.055094 -312.999882) (xy 394.344156 -312.999882)
			(xy 394.348116 -312.950828) (xy 394.359893 -312.903044) (xy 394.379184 -312.857768) (xy 394.405487 -312.816172)
			(xy 394.438122 -312.779335) (xy 394.476243 -312.74821) (xy 394.518864 -312.723603) (xy 394.56488 -312.706151)
			(xy 394.613099 -312.696307) (xy 394.662274 -312.694326) (xy 394.711129 -312.700258) (xy 394.7584 -312.71395)
			(xy 394.802862 -312.735048) (xy 394.843365 -312.763004) (xy 394.878858 -312.797096) (xy 394.908423 -312.83644)
			(xy 394.931294 -312.880017) (xy 394.946878 -312.926698) (xy 394.954773 -312.975275) (xy 394.955268 -312.999882)
			(xy 396.244076 -312.999882) (xy 396.248036 -312.950828) (xy 396.259813 -312.903044) (xy 396.279104 -312.857768)
			(xy 396.305407 -312.816172) (xy 396.338042 -312.779335) (xy 396.376163 -312.74821) (xy 396.418784 -312.723603)
			(xy 396.4648 -312.706151) (xy 396.513019 -312.696307) (xy 396.562194 -312.694326) (xy 396.611049 -312.700258)
			(xy 396.65832 -312.71395) (xy 396.702782 -312.735048) (xy 396.743285 -312.763004) (xy 396.778778 -312.797096)
			(xy 396.808343 -312.83644) (xy 396.831214 -312.880017) (xy 396.846798 -312.926698) (xy 396.854693 -312.975275)
			(xy 396.855188 -312.999882) (xy 398.143996 -312.999882) (xy 398.147956 -312.950828) (xy 398.159733 -312.903044)
			(xy 398.179024 -312.857768) (xy 398.205327 -312.816172) (xy 398.237962 -312.779335) (xy 398.276083 -312.74821)
			(xy 398.318704 -312.723603) (xy 398.36472 -312.706151) (xy 398.412939 -312.696307) (xy 398.462114 -312.694326)
			(xy 398.510969 -312.700258) (xy 398.55824 -312.71395) (xy 398.602702 -312.735048) (xy 398.643205 -312.763004)
			(xy 398.678698 -312.797096) (xy 398.708263 -312.83644) (xy 398.731134 -312.880017) (xy 398.746718 -312.926698)
			(xy 398.754613 -312.975275) (xy 398.755108 -312.999882) (xy 415.244038 -312.999882) (xy 415.247998 -312.950828)
			(xy 415.259775 -312.903044) (xy 415.279066 -312.857768) (xy 415.305369 -312.816172) (xy 415.338004 -312.779335)
			(xy 415.376125 -312.74821) (xy 415.418746 -312.723603) (xy 415.464762 -312.706151) (xy 415.512981 -312.696307)
			(xy 415.562156 -312.694326) (xy 415.611011 -312.700258) (xy 415.658282 -312.71395) (xy 415.702744 -312.735048)
			(xy 415.743247 -312.763004) (xy 415.77874 -312.797096) (xy 415.808305 -312.83644) (xy 415.831176 -312.880017)
			(xy 415.84676 -312.926698) (xy 415.854655 -312.975275) (xy 415.85515 -312.999882) (xy 417.144212 -312.999882)
			(xy 417.148172 -312.950828) (xy 417.159949 -312.903044) (xy 417.17924 -312.857768) (xy 417.205543 -312.816172)
			(xy 417.238178 -312.779335) (xy 417.276299 -312.74821) (xy 417.31892 -312.723603) (xy 417.364936 -312.706151)
			(xy 417.413155 -312.696307) (xy 417.46233 -312.694326) (xy 417.511185 -312.700258) (xy 417.558456 -312.71395)
			(xy 417.602918 -312.735048) (xy 417.643421 -312.763004) (xy 417.678914 -312.797096) (xy 417.708479 -312.83644)
			(xy 417.73135 -312.880017) (xy 417.746934 -312.926698) (xy 417.754829 -312.975275) (xy 417.755324 -312.999882)
			(xy 419.044132 -312.999882) (xy 419.048092 -312.950828) (xy 419.059869 -312.903044) (xy 419.07916 -312.857768)
			(xy 419.105463 -312.816172) (xy 419.138098 -312.779335) (xy 419.176219 -312.74821) (xy 419.21884 -312.723603)
			(xy 419.264856 -312.706151) (xy 419.313075 -312.696307) (xy 419.36225 -312.694326) (xy 419.411105 -312.700258)
			(xy 419.458376 -312.71395) (xy 419.502838 -312.735048) (xy 419.543341 -312.763004) (xy 419.578834 -312.797096)
			(xy 419.608399 -312.83644) (xy 419.63127 -312.880017) (xy 419.646854 -312.926698) (xy 419.654749 -312.975275)
			(xy 419.655244 -312.999882) (xy 420.944052 -312.999882) (xy 420.948012 -312.950828) (xy 420.959789 -312.903044)
			(xy 420.97908 -312.857768) (xy 421.005383 -312.816172) (xy 421.038018 -312.779335) (xy 421.076139 -312.74821)
			(xy 421.11876 -312.723603) (xy 421.164776 -312.706151) (xy 421.212995 -312.696307) (xy 421.26217 -312.694326)
			(xy 421.311025 -312.700258) (xy 421.358296 -312.71395) (xy 421.402758 -312.735048) (xy 421.443261 -312.763004)
			(xy 421.478754 -312.797096) (xy 421.508319 -312.83644) (xy 421.53119 -312.880017) (xy 421.546774 -312.926698)
			(xy 421.554669 -312.975275) (xy 421.555164 -312.999882) (xy 421.554669 -313.024489) (xy 421.546774 -313.073066)
			(xy 421.53119 -313.119747) (xy 421.508319 -313.163324) (xy 421.478754 -313.202668) (xy 421.443261 -313.23676)
			(xy 421.402758 -313.264716) (xy 421.358296 -313.285814) (xy 421.311025 -313.299506) (xy 421.26217 -313.305438)
			(xy 421.212995 -313.303457) (xy 421.164776 -313.293613) (xy 421.11876 -313.276161) (xy 421.076139 -313.251554)
			(xy 421.038018 -313.220429) (xy 421.005383 -313.183592) (xy 420.97908 -313.141996) (xy 420.959789 -313.09672)
			(xy 420.948012 -313.048936) (xy 420.944052 -312.999882) (xy 419.655244 -312.999882) (xy 419.654749 -313.024489)
			(xy 419.646854 -313.073066) (xy 419.63127 -313.119747) (xy 419.608399 -313.163324) (xy 419.578834 -313.202668)
			(xy 419.543341 -313.23676) (xy 419.502838 -313.264716) (xy 419.458376 -313.285814) (xy 419.411105 -313.299506)
			(xy 419.36225 -313.305438) (xy 419.313075 -313.303457) (xy 419.264856 -313.293613) (xy 419.21884 -313.276161)
			(xy 419.176219 -313.251554) (xy 419.138098 -313.220429) (xy 419.105463 -313.183592) (xy 419.07916 -313.141996)
			(xy 419.059869 -313.09672) (xy 419.048092 -313.048936) (xy 419.044132 -312.999882) (xy 417.755324 -312.999882)
			(xy 417.754829 -313.024489) (xy 417.746934 -313.073066) (xy 417.73135 -313.119747) (xy 417.708479 -313.163324)
			(xy 417.678914 -313.202668) (xy 417.643421 -313.23676) (xy 417.602918 -313.264716) (xy 417.558456 -313.285814)
			(xy 417.511185 -313.299506) (xy 417.46233 -313.305438) (xy 417.413155 -313.303457) (xy 417.364936 -313.293613)
			(xy 417.31892 -313.276161) (xy 417.276299 -313.251554) (xy 417.238178 -313.220429) (xy 417.205543 -313.183592)
			(xy 417.17924 -313.141996) (xy 417.159949 -313.09672) (xy 417.148172 -313.048936) (xy 417.144212 -312.999882)
			(xy 415.85515 -312.999882) (xy 415.854655 -313.024489) (xy 415.84676 -313.073066) (xy 415.831176 -313.119747)
			(xy 415.808305 -313.163324) (xy 415.77874 -313.202668) (xy 415.743247 -313.23676) (xy 415.702744 -313.264716)
			(xy 415.658282 -313.285814) (xy 415.611011 -313.299506) (xy 415.562156 -313.305438) (xy 415.512981 -313.303457)
			(xy 415.464762 -313.293613) (xy 415.418746 -313.276161) (xy 415.376125 -313.251554) (xy 415.338004 -313.220429)
			(xy 415.305369 -313.183592) (xy 415.279066 -313.141996) (xy 415.259775 -313.09672) (xy 415.247998 -313.048936)
			(xy 415.244038 -312.999882) (xy 398.755108 -312.999882) (xy 398.754613 -313.024489) (xy 398.746718 -313.073066)
			(xy 398.731134 -313.119747) (xy 398.708263 -313.163324) (xy 398.678698 -313.202668) (xy 398.643205 -313.23676)
			(xy 398.602702 -313.264716) (xy 398.55824 -313.285814) (xy 398.510969 -313.299506) (xy 398.462114 -313.305438)
			(xy 398.412939 -313.303457) (xy 398.36472 -313.293613) (xy 398.318704 -313.276161) (xy 398.276083 -313.251554)
			(xy 398.237962 -313.220429) (xy 398.205327 -313.183592) (xy 398.179024 -313.141996) (xy 398.159733 -313.09672)
			(xy 398.147956 -313.048936) (xy 398.143996 -312.999882) (xy 396.855188 -312.999882) (xy 396.854693 -313.024489)
			(xy 396.846798 -313.073066) (xy 396.831214 -313.119747) (xy 396.808343 -313.163324) (xy 396.778778 -313.202668)
			(xy 396.743285 -313.23676) (xy 396.702782 -313.264716) (xy 396.65832 -313.285814) (xy 396.611049 -313.299506)
			(xy 396.562194 -313.305438) (xy 396.513019 -313.303457) (xy 396.4648 -313.293613) (xy 396.418784 -313.276161)
			(xy 396.376163 -313.251554) (xy 396.338042 -313.220429) (xy 396.305407 -313.183592) (xy 396.279104 -313.141996)
			(xy 396.259813 -313.09672) (xy 396.248036 -313.048936) (xy 396.244076 -312.999882) (xy 394.955268 -312.999882)
			(xy 394.954773 -313.024489) (xy 394.946878 -313.073066) (xy 394.931294 -313.119747) (xy 394.908423 -313.163324)
			(xy 394.878858 -313.202668) (xy 394.843365 -313.23676) (xy 394.802862 -313.264716) (xy 394.7584 -313.285814)
			(xy 394.711129 -313.299506) (xy 394.662274 -313.305438) (xy 394.613099 -313.303457) (xy 394.56488 -313.293613)
			(xy 394.518864 -313.276161) (xy 394.476243 -313.251554) (xy 394.438122 -313.220429) (xy 394.405487 -313.183592)
			(xy 394.379184 -313.141996) (xy 394.359893 -313.09672) (xy 394.348116 -313.048936) (xy 394.344156 -312.999882)
			(xy 393.055094 -312.999882) (xy 393.054599 -313.024489) (xy 393.046704 -313.073066) (xy 393.03112 -313.119747)
			(xy 393.008249 -313.163324) (xy 392.978684 -313.202668) (xy 392.943191 -313.23676) (xy 392.902688 -313.264716)
			(xy 392.858226 -313.285814) (xy 392.810955 -313.299506) (xy 392.7621 -313.305438) (xy 392.712925 -313.303457)
			(xy 392.664706 -313.293613) (xy 392.61869 -313.276161) (xy 392.576069 -313.251554) (xy 392.537948 -313.220429)
			(xy 392.505313 -313.183592) (xy 392.47901 -313.141996) (xy 392.459719 -313.09672) (xy 392.447942 -313.048936)
			(xy 392.443982 -312.999882) (xy 391.155174 -312.999882) (xy 391.154679 -313.024489) (xy 391.146784 -313.073066)
			(xy 391.1312 -313.119747) (xy 391.108329 -313.163324) (xy 391.078764 -313.202668) (xy 391.043271 -313.23676)
			(xy 391.002768 -313.264716) (xy 390.958306 -313.285814) (xy 390.911035 -313.299506) (xy 390.86218 -313.305438)
			(xy 390.813005 -313.303457) (xy 390.764786 -313.293613) (xy 390.71877 -313.276161) (xy 390.676149 -313.251554)
			(xy 390.638028 -313.220429) (xy 390.605393 -313.183592) (xy 390.57909 -313.141996) (xy 390.559799 -313.09672)
			(xy 390.548022 -313.048936) (xy 390.544062 -312.999882) (xy 389.255254 -312.999882) (xy 389.254759 -313.024489)
			(xy 389.246864 -313.073066) (xy 389.23128 -313.119747) (xy 389.208409 -313.163324) (xy 389.178844 -313.202668)
			(xy 389.143351 -313.23676) (xy 389.102848 -313.264716) (xy 389.058386 -313.285814) (xy 389.011115 -313.299506)
			(xy 388.96226 -313.305438) (xy 388.913085 -313.303457) (xy 388.864866 -313.293613) (xy 388.81885 -313.276161)
			(xy 388.776229 -313.251554) (xy 388.738108 -313.220429) (xy 388.705473 -313.183592) (xy 388.67917 -313.141996)
			(xy 388.659879 -313.09672) (xy 388.648102 -313.048936) (xy 388.644142 -312.999882) (xy 387.355334 -312.999882)
			(xy 387.354839 -313.024489) (xy 387.346944 -313.073066) (xy 387.33136 -313.119747) (xy 387.308489 -313.163324)
			(xy 387.278924 -313.202668) (xy 387.243431 -313.23676) (xy 387.202928 -313.264716) (xy 387.158466 -313.285814)
			(xy 387.111195 -313.299506) (xy 387.06234 -313.305438) (xy 387.013165 -313.303457) (xy 386.964946 -313.293613)
			(xy 386.91893 -313.276161) (xy 386.876309 -313.251554) (xy 386.838188 -313.220429) (xy 386.805553 -313.183592)
			(xy 386.77925 -313.141996) (xy 386.759959 -313.09672) (xy 386.748182 -313.048936) (xy 386.744222 -312.999882)
			(xy 313.055 -312.999882) (xy 313.054505 -313.024489) (xy 313.04661 -313.073066) (xy 313.031026 -313.119747)
			(xy 313.008155 -313.163324) (xy 312.97859 -313.202668) (xy 312.943097 -313.23676) (xy 312.902594 -313.264716)
			(xy 312.858132 -313.285814) (xy 312.810861 -313.299506) (xy 312.762006 -313.305438) (xy 312.712831 -313.303457)
			(xy 312.664612 -313.293613) (xy 312.618596 -313.276161) (xy 312.575975 -313.251554) (xy 312.537854 -313.220429)
			(xy 312.505219 -313.183592) (xy 312.478916 -313.141996) (xy 312.459625 -313.09672) (xy 312.447848 -313.048936)
			(xy 312.443888 -312.999882) (xy 311.15508 -312.999882) (xy 311.154585 -313.024489) (xy 311.14669 -313.073066)
			(xy 311.131106 -313.119747) (xy 311.108235 -313.163324) (xy 311.07867 -313.202668) (xy 311.043177 -313.23676)
			(xy 311.002674 -313.264716) (xy 310.958212 -313.285814) (xy 310.910941 -313.299506) (xy 310.862086 -313.305438)
			(xy 310.812911 -313.303457) (xy 310.764692 -313.293613) (xy 310.718676 -313.276161) (xy 310.676055 -313.251554)
			(xy 310.637934 -313.220429) (xy 310.605299 -313.183592) (xy 310.578996 -313.141996) (xy 310.559705 -313.09672)
			(xy 310.547928 -313.048936) (xy 310.543968 -312.999882) (xy 309.25516 -312.999882) (xy 309.254665 -313.024489)
			(xy 309.24677 -313.073066) (xy 309.231186 -313.119747) (xy 309.208315 -313.163324) (xy 309.17875 -313.202668)
			(xy 309.143257 -313.23676) (xy 309.102754 -313.264716) (xy 309.058292 -313.285814) (xy 309.011021 -313.299506)
			(xy 308.962166 -313.305438) (xy 308.912991 -313.303457) (xy 308.864772 -313.293613) (xy 308.818756 -313.276161)
			(xy 308.776135 -313.251554) (xy 308.738014 -313.220429) (xy 308.705379 -313.183592) (xy 308.679076 -313.141996)
			(xy 308.659785 -313.09672) (xy 308.648008 -313.048936) (xy 308.644048 -312.999882) (xy 307.35524 -312.999882)
			(xy 307.354745 -313.024489) (xy 307.34685 -313.073066) (xy 307.331266 -313.119747) (xy 307.308395 -313.163324)
			(xy 307.27883 -313.202668) (xy 307.243337 -313.23676) (xy 307.202834 -313.264716) (xy 307.158372 -313.285814)
			(xy 307.111101 -313.299506) (xy 307.062246 -313.305438) (xy 307.013071 -313.303457) (xy 306.964852 -313.293613)
			(xy 306.918836 -313.276161) (xy 306.876215 -313.251554) (xy 306.838094 -313.220429) (xy 306.805459 -313.183592)
			(xy 306.779156 -313.141996) (xy 306.759865 -313.09672) (xy 306.748088 -313.048936) (xy 306.744128 -312.999882)
			(xy 290.255198 -312.999882) (xy 290.254703 -313.024489) (xy 290.246808 -313.073066) (xy 290.231224 -313.119747)
			(xy 290.208353 -313.163324) (xy 290.178788 -313.202668) (xy 290.143295 -313.23676) (xy 290.102792 -313.264716)
			(xy 290.05833 -313.285814) (xy 290.011059 -313.299506) (xy 289.962204 -313.305438) (xy 289.913029 -313.303457)
			(xy 289.86481 -313.293613) (xy 289.818794 -313.276161) (xy 289.776173 -313.251554) (xy 289.738052 -313.220429)
			(xy 289.705417 -313.183592) (xy 289.679114 -313.141996) (xy 289.659823 -313.09672) (xy 289.648046 -313.048936)
			(xy 289.644086 -312.999882) (xy 288.355024 -312.999882) (xy 288.354529 -313.024489) (xy 288.346634 -313.073066)
			(xy 288.33105 -313.119747) (xy 288.308179 -313.163324) (xy 288.278614 -313.202668) (xy 288.243121 -313.23676)
			(xy 288.202618 -313.264716) (xy 288.158156 -313.285814) (xy 288.110885 -313.299506) (xy 288.06203 -313.305438)
			(xy 288.012855 -313.303457) (xy 287.964636 -313.293613) (xy 287.91862 -313.276161) (xy 287.875999 -313.251554)
			(xy 287.837878 -313.220429) (xy 287.805243 -313.183592) (xy 287.77894 -313.141996) (xy 287.759649 -313.09672)
			(xy 287.747872 -313.048936) (xy 287.743912 -312.999882) (xy 286.455104 -312.999882) (xy 286.454609 -313.024489)
			(xy 286.446714 -313.073066) (xy 286.43113 -313.119747) (xy 286.408259 -313.163324) (xy 286.378694 -313.202668)
			(xy 286.343201 -313.23676) (xy 286.302698 -313.264716) (xy 286.258236 -313.285814) (xy 286.210965 -313.299506)
			(xy 286.16211 -313.305438) (xy 286.112935 -313.303457) (xy 286.064716 -313.293613) (xy 286.0187 -313.276161)
			(xy 285.976079 -313.251554) (xy 285.937958 -313.220429) (xy 285.905323 -313.183592) (xy 285.87902 -313.141996)
			(xy 285.859729 -313.09672) (xy 285.847952 -313.048936) (xy 285.843992 -312.999882) (xy 284.555184 -312.999882)
			(xy 284.554689 -313.024489) (xy 284.546794 -313.073066) (xy 284.53121 -313.119747) (xy 284.508339 -313.163324)
			(xy 284.478774 -313.202668) (xy 284.443281 -313.23676) (xy 284.402778 -313.264716) (xy 284.358316 -313.285814)
			(xy 284.311045 -313.299506) (xy 284.26219 -313.305438) (xy 284.213015 -313.303457) (xy 284.164796 -313.293613)
			(xy 284.11878 -313.276161) (xy 284.076159 -313.251554) (xy 284.038038 -313.220429) (xy 284.005403 -313.183592)
			(xy 283.9791 -313.141996) (xy 283.959809 -313.09672) (xy 283.948032 -313.048936) (xy 283.944072 -312.999882)
			(xy 282.65501 -312.999882) (xy 282.654515 -313.024489) (xy 282.64662 -313.073066) (xy 282.631036 -313.119747)
			(xy 282.608165 -313.163324) (xy 282.5786 -313.202668) (xy 282.543107 -313.23676) (xy 282.502604 -313.264716)
			(xy 282.458142 -313.285814) (xy 282.410871 -313.299506) (xy 282.362016 -313.305438) (xy 282.312841 -313.303457)
			(xy 282.264622 -313.293613) (xy 282.218606 -313.276161) (xy 282.175985 -313.251554) (xy 282.137864 -313.220429)
			(xy 282.105229 -313.183592) (xy 282.078926 -313.141996) (xy 282.059635 -313.09672) (xy 282.047858 -313.048936)
			(xy 282.043898 -312.999882) (xy 280.75509 -312.999882) (xy 280.754595 -313.024489) (xy 280.7467 -313.073066)
			(xy 280.731116 -313.119747) (xy 280.708245 -313.163324) (xy 280.67868 -313.202668) (xy 280.643187 -313.23676)
			(xy 280.602684 -313.264716) (xy 280.558222 -313.285814) (xy 280.510951 -313.299506) (xy 280.462096 -313.305438)
			(xy 280.412921 -313.303457) (xy 280.364702 -313.293613) (xy 280.318686 -313.276161) (xy 280.276065 -313.251554)
			(xy 280.237944 -313.220429) (xy 280.205309 -313.183592) (xy 280.179006 -313.141996) (xy 280.159715 -313.09672)
			(xy 280.147938 -313.048936) (xy 280.143978 -312.999882) (xy 278.85517 -312.999882) (xy 278.854675 -313.024489)
			(xy 278.84678 -313.073066) (xy 278.831196 -313.119747) (xy 278.808325 -313.163324) (xy 278.77876 -313.202668)
			(xy 278.743267 -313.23676) (xy 278.702764 -313.264716) (xy 278.658302 -313.285814) (xy 278.611031 -313.299506)
			(xy 278.562176 -313.305438) (xy 278.513001 -313.303457) (xy 278.464782 -313.293613) (xy 278.418766 -313.276161)
			(xy 278.376145 -313.251554) (xy 278.338024 -313.220429) (xy 278.305389 -313.183592) (xy 278.279086 -313.141996)
			(xy 278.259795 -313.09672) (xy 278.248018 -313.048936) (xy 278.244058 -312.999882) (xy 276.954996 -312.999882)
			(xy 276.954501 -313.024489) (xy 276.946606 -313.073066) (xy 276.931022 -313.119747) (xy 276.908151 -313.163324)
			(xy 276.878586 -313.202668) (xy 276.843093 -313.23676) (xy 276.80259 -313.264716) (xy 276.758128 -313.285814)
			(xy 276.710857 -313.299506) (xy 276.662002 -313.305438) (xy 276.612827 -313.303457) (xy 276.564608 -313.293613)
			(xy 276.518592 -313.276161) (xy 276.475971 -313.251554) (xy 276.43785 -313.220429) (xy 276.405215 -313.183592)
			(xy 276.378912 -313.141996) (xy 276.359621 -313.09672) (xy 276.347844 -313.048936) (xy 276.343884 -312.999882)
			(xy 189.355222 -312.999882) (xy 189.354727 -313.024489) (xy 189.346832 -313.073066) (xy 189.331248 -313.119747)
			(xy 189.308377 -313.163324) (xy 189.278812 -313.202668) (xy 189.243319 -313.23676) (xy 189.202816 -313.264716)
			(xy 189.158354 -313.285814) (xy 189.111083 -313.299506) (xy 189.062228 -313.305438) (xy 189.013053 -313.303457)
			(xy 188.964834 -313.293613) (xy 188.918818 -313.276161) (xy 188.876197 -313.251554) (xy 188.838076 -313.220429)
			(xy 188.805441 -313.183592) (xy 188.779138 -313.141996) (xy 188.759847 -313.09672) (xy 188.74807 -313.048936)
			(xy 188.74411 -312.999882) (xy 187.455302 -312.999882) (xy 187.454807 -313.024489) (xy 187.446912 -313.073066)
			(xy 187.431328 -313.119747) (xy 187.408457 -313.163324) (xy 187.378892 -313.202668) (xy 187.343399 -313.23676)
			(xy 187.302896 -313.264716) (xy 187.258434 -313.285814) (xy 187.211163 -313.299506) (xy 187.162308 -313.305438)
			(xy 187.113133 -313.303457) (xy 187.064914 -313.293613) (xy 187.018898 -313.276161) (xy 186.976277 -313.251554)
			(xy 186.938156 -313.220429) (xy 186.905521 -313.183592) (xy 186.879218 -313.141996) (xy 186.859927 -313.09672)
			(xy 186.84815 -313.048936) (xy 186.84419 -312.999882) (xy 185.555382 -312.999882) (xy 185.554887 -313.024489)
			(xy 185.546992 -313.073066) (xy 185.531408 -313.119747) (xy 185.508537 -313.163324) (xy 185.478972 -313.202668)
			(xy 185.443479 -313.23676) (xy 185.402976 -313.264716) (xy 185.358514 -313.285814) (xy 185.311243 -313.299506)
			(xy 185.262388 -313.305438) (xy 185.213213 -313.303457) (xy 185.164994 -313.293613) (xy 185.118978 -313.276161)
			(xy 185.076357 -313.251554) (xy 185.038236 -313.220429) (xy 185.005601 -313.183592) (xy 184.979298 -313.141996)
			(xy 184.960007 -313.09672) (xy 184.94823 -313.048936) (xy 184.94427 -312.999882) (xy 183.655208 -312.999882)
			(xy 183.654713 -313.024489) (xy 183.646818 -313.073066) (xy 183.631234 -313.119747) (xy 183.608363 -313.163324)
			(xy 183.578798 -313.202668) (xy 183.543305 -313.23676) (xy 183.502802 -313.264716) (xy 183.45834 -313.285814)
			(xy 183.411069 -313.299506) (xy 183.362214 -313.305438) (xy 183.313039 -313.303457) (xy 183.26482 -313.293613)
			(xy 183.218804 -313.276161) (xy 183.176183 -313.251554) (xy 183.138062 -313.220429) (xy 183.105427 -313.183592)
			(xy 183.079124 -313.141996) (xy 183.059833 -313.09672) (xy 183.048056 -313.048936) (xy 183.044096 -312.999882)
			(xy 166.555166 -312.999882) (xy 166.554671 -313.024489) (xy 166.546776 -313.073066) (xy 166.531192 -313.119747)
			(xy 166.508321 -313.163324) (xy 166.478756 -313.202668) (xy 166.443263 -313.23676) (xy 166.40276 -313.264716)
			(xy 166.358298 -313.285814) (xy 166.311027 -313.299506) (xy 166.262172 -313.305438) (xy 166.212997 -313.303457)
			(xy 166.164778 -313.293613) (xy 166.118762 -313.276161) (xy 166.076141 -313.251554) (xy 166.03802 -313.220429)
			(xy 166.005385 -313.183592) (xy 165.979082 -313.141996) (xy 165.959791 -313.09672) (xy 165.948014 -313.048936)
			(xy 165.944054 -312.999882) (xy 164.655246 -312.999882) (xy 164.654751 -313.024489) (xy 164.646856 -313.073066)
			(xy 164.631272 -313.119747) (xy 164.608401 -313.163324) (xy 164.578836 -313.202668) (xy 164.543343 -313.23676)
			(xy 164.50284 -313.264716) (xy 164.458378 -313.285814) (xy 164.411107 -313.299506) (xy 164.362252 -313.305438)
			(xy 164.313077 -313.303457) (xy 164.264858 -313.293613) (xy 164.218842 -313.276161) (xy 164.176221 -313.251554)
			(xy 164.1381 -313.220429) (xy 164.105465 -313.183592) (xy 164.079162 -313.141996) (xy 164.059871 -313.09672)
			(xy 164.048094 -313.048936) (xy 164.044134 -312.999882) (xy 162.755326 -312.999882) (xy 162.754831 -313.024489)
			(xy 162.746936 -313.073066) (xy 162.731352 -313.119747) (xy 162.708481 -313.163324) (xy 162.678916 -313.202668)
			(xy 162.643423 -313.23676) (xy 162.60292 -313.264716) (xy 162.558458 -313.285814) (xy 162.511187 -313.299506)
			(xy 162.462332 -313.305438) (xy 162.413157 -313.303457) (xy 162.364938 -313.293613) (xy 162.318922 -313.276161)
			(xy 162.276301 -313.251554) (xy 162.23818 -313.220429) (xy 162.205545 -313.183592) (xy 162.179242 -313.141996)
			(xy 162.159951 -313.09672) (xy 162.148174 -313.048936) (xy 162.144214 -312.999882) (xy 160.855152 -312.999882)
			(xy 160.854657 -313.024489) (xy 160.846762 -313.073066) (xy 160.831178 -313.119747) (xy 160.808307 -313.163324)
			(xy 160.778742 -313.202668) (xy 160.743249 -313.23676) (xy 160.702746 -313.264716) (xy 160.658284 -313.285814)
			(xy 160.611013 -313.299506) (xy 160.562158 -313.305438) (xy 160.512983 -313.303457) (xy 160.464764 -313.293613)
			(xy 160.418748 -313.276161) (xy 160.376127 -313.251554) (xy 160.338006 -313.220429) (xy 160.305371 -313.183592)
			(xy 160.279068 -313.141996) (xy 160.259777 -313.09672) (xy 160.248 -313.048936) (xy 160.24404 -312.999882)
			(xy 158.955232 -312.999882) (xy 158.954737 -313.024489) (xy 158.946842 -313.073066) (xy 158.931258 -313.119747)
			(xy 158.908387 -313.163324) (xy 158.878822 -313.202668) (xy 158.843329 -313.23676) (xy 158.802826 -313.264716)
			(xy 158.758364 -313.285814) (xy 158.711093 -313.299506) (xy 158.662238 -313.305438) (xy 158.613063 -313.303457)
			(xy 158.564844 -313.293613) (xy 158.518828 -313.276161) (xy 158.476207 -313.251554) (xy 158.438086 -313.220429)
			(xy 158.405451 -313.183592) (xy 158.379148 -313.141996) (xy 158.359857 -313.09672) (xy 158.34808 -313.048936)
			(xy 158.34412 -312.999882) (xy 157.055312 -312.999882) (xy 157.054817 -313.024489) (xy 157.046922 -313.073066)
			(xy 157.031338 -313.119747) (xy 157.008467 -313.163324) (xy 156.978902 -313.202668) (xy 156.943409 -313.23676)
			(xy 156.902906 -313.264716) (xy 156.858444 -313.285814) (xy 156.811173 -313.299506) (xy 156.762318 -313.305438)
			(xy 156.713143 -313.303457) (xy 156.664924 -313.293613) (xy 156.618908 -313.276161) (xy 156.576287 -313.251554)
			(xy 156.538166 -313.220429) (xy 156.505531 -313.183592) (xy 156.479228 -313.141996) (xy 156.459937 -313.09672)
			(xy 156.44816 -313.048936) (xy 156.4442 -312.999882) (xy 155.155392 -312.999882) (xy 155.154897 -313.024489)
			(xy 155.147002 -313.073066) (xy 155.131418 -313.119747) (xy 155.108547 -313.163324) (xy 155.078982 -313.202668)
			(xy 155.043489 -313.23676) (xy 155.002986 -313.264716) (xy 154.958524 -313.285814) (xy 154.911253 -313.299506)
			(xy 154.862398 -313.305438) (xy 154.813223 -313.303457) (xy 154.765004 -313.293613) (xy 154.718988 -313.276161)
			(xy 154.676367 -313.251554) (xy 154.638246 -313.220429) (xy 154.605611 -313.183592) (xy 154.579308 -313.141996)
			(xy 154.560017 -313.09672) (xy 154.54824 -313.048936) (xy 154.54428 -312.999882) (xy 80.855058 -312.999882)
			(xy 80.854563 -313.024489) (xy 80.846668 -313.073066) (xy 80.831084 -313.119747) (xy 80.808213 -313.163324)
			(xy 80.778648 -313.202668) (xy 80.743155 -313.23676) (xy 80.702652 -313.264716) (xy 80.65819 -313.285814)
			(xy 80.610919 -313.299506) (xy 80.562064 -313.305438) (xy 80.512889 -313.303457) (xy 80.46467 -313.293613)
			(xy 80.418654 -313.276161) (xy 80.376033 -313.251554) (xy 80.337912 -313.220429) (xy 80.305277 -313.183592)
			(xy 80.278974 -313.141996) (xy 80.259683 -313.09672) (xy 80.247906 -313.048936) (xy 80.243946 -312.999882)
			(xy 78.955138 -312.999882) (xy 78.954643 -313.024489) (xy 78.946748 -313.073066) (xy 78.931164 -313.119747)
			(xy 78.908293 -313.163324) (xy 78.878728 -313.202668) (xy 78.843235 -313.23676) (xy 78.802732 -313.264716)
			(xy 78.75827 -313.285814) (xy 78.710999 -313.299506) (xy 78.662144 -313.305438) (xy 78.612969 -313.303457)
			(xy 78.56475 -313.293613) (xy 78.518734 -313.276161) (xy 78.476113 -313.251554) (xy 78.437992 -313.220429)
			(xy 78.405357 -313.183592) (xy 78.379054 -313.141996) (xy 78.359763 -313.09672) (xy 78.347986 -313.048936)
			(xy 78.344026 -312.999882) (xy 77.055218 -312.999882) (xy 77.054723 -313.024489) (xy 77.046828 -313.073066)
			(xy 77.031244 -313.119747) (xy 77.008373 -313.163324) (xy 76.978808 -313.202668) (xy 76.943315 -313.23676)
			(xy 76.902812 -313.264716) (xy 76.85835 -313.285814) (xy 76.811079 -313.299506) (xy 76.762224 -313.305438)
			(xy 76.713049 -313.303457) (xy 76.66483 -313.293613) (xy 76.618814 -313.276161) (xy 76.576193 -313.251554)
			(xy 76.538072 -313.220429) (xy 76.505437 -313.183592) (xy 76.479134 -313.141996) (xy 76.459843 -313.09672)
			(xy 76.448066 -313.048936) (xy 76.444106 -312.999882) (xy 75.155298 -312.999882) (xy 75.154803 -313.024489)
			(xy 75.146908 -313.073066) (xy 75.131324 -313.119747) (xy 75.108453 -313.163324) (xy 75.078888 -313.202668)
			(xy 75.043395 -313.23676) (xy 75.002892 -313.264716) (xy 74.95843 -313.285814) (xy 74.911159 -313.299506)
			(xy 74.862304 -313.305438) (xy 74.813129 -313.303457) (xy 74.76491 -313.293613) (xy 74.718894 -313.276161)
			(xy 74.676273 -313.251554) (xy 74.638152 -313.220429) (xy 74.605517 -313.183592) (xy 74.579214 -313.141996)
			(xy 74.559923 -313.09672) (xy 74.548146 -313.048936) (xy 74.544186 -312.999882) (xy 58.055256 -312.999882)
			(xy 58.054761 -313.024489) (xy 58.046866 -313.073066) (xy 58.031282 -313.119747) (xy 58.008411 -313.163324)
			(xy 57.978846 -313.202668) (xy 57.943353 -313.23676) (xy 57.90285 -313.264716) (xy 57.858388 -313.285814)
			(xy 57.811117 -313.299506) (xy 57.762262 -313.305438) (xy 57.713087 -313.303457) (xy 57.664868 -313.293613)
			(xy 57.618852 -313.276161) (xy 57.576231 -313.251554) (xy 57.53811 -313.220429) (xy 57.505475 -313.183592)
			(xy 57.479172 -313.141996) (xy 57.459881 -313.09672) (xy 57.448104 -313.048936) (xy 57.444144 -312.999882)
			(xy 56.155082 -312.999882) (xy 56.154587 -313.024489) (xy 56.146692 -313.073066) (xy 56.131108 -313.119747)
			(xy 56.108237 -313.163324) (xy 56.078672 -313.202668) (xy 56.043179 -313.23676) (xy 56.002676 -313.264716)
			(xy 55.958214 -313.285814) (xy 55.910943 -313.299506) (xy 55.862088 -313.305438) (xy 55.812913 -313.303457)
			(xy 55.764694 -313.293613) (xy 55.718678 -313.276161) (xy 55.676057 -313.251554) (xy 55.637936 -313.220429)
			(xy 55.605301 -313.183592) (xy 55.578998 -313.141996) (xy 55.559707 -313.09672) (xy 55.54793 -313.048936)
			(xy 55.54397 -312.999882) (xy 54.255162 -312.999882) (xy 54.254667 -313.024489) (xy 54.246772 -313.073066)
			(xy 54.231188 -313.119747) (xy 54.208317 -313.163324) (xy 54.178752 -313.202668) (xy 54.143259 -313.23676)
			(xy 54.102756 -313.264716) (xy 54.058294 -313.285814) (xy 54.011023 -313.299506) (xy 53.962168 -313.305438)
			(xy 53.912993 -313.303457) (xy 53.864774 -313.293613) (xy 53.818758 -313.276161) (xy 53.776137 -313.251554)
			(xy 53.738016 -313.220429) (xy 53.705381 -313.183592) (xy 53.679078 -313.141996) (xy 53.659787 -313.09672)
			(xy 53.64801 -313.048936) (xy 53.64405 -312.999882) (xy 52.355242 -312.999882) (xy 52.354747 -313.024489)
			(xy 52.346852 -313.073066) (xy 52.331268 -313.119747) (xy 52.308397 -313.163324) (xy 52.278832 -313.202668)
			(xy 52.243339 -313.23676) (xy 52.202836 -313.264716) (xy 52.158374 -313.285814) (xy 52.111103 -313.299506)
			(xy 52.062248 -313.305438) (xy 52.013073 -313.303457) (xy 51.964854 -313.293613) (xy 51.918838 -313.276161)
			(xy 51.876217 -313.251554) (xy 51.838096 -313.220429) (xy 51.805461 -313.183592) (xy 51.779158 -313.141996)
			(xy 51.759867 -313.09672) (xy 51.74809 -313.048936) (xy 51.74413 -312.999882) (xy 50.455068 -312.999882)
			(xy 50.454573 -313.024489) (xy 50.446678 -313.073066) (xy 50.431094 -313.119747) (xy 50.408223 -313.163324)
			(xy 50.378658 -313.202668) (xy 50.343165 -313.23676) (xy 50.302662 -313.264716) (xy 50.2582 -313.285814)
			(xy 50.210929 -313.299506) (xy 50.162074 -313.305438) (xy 50.112899 -313.303457) (xy 50.06468 -313.293613)
			(xy 50.018664 -313.276161) (xy 49.976043 -313.251554) (xy 49.937922 -313.220429) (xy 49.905287 -313.183592)
			(xy 49.878984 -313.141996) (xy 49.859693 -313.09672) (xy 49.847916 -313.048936) (xy 49.843956 -312.999882)
			(xy 48.555148 -312.999882) (xy 48.554653 -313.024489) (xy 48.546758 -313.073066) (xy 48.531174 -313.119747)
			(xy 48.508303 -313.163324) (xy 48.478738 -313.202668) (xy 48.443245 -313.23676) (xy 48.402742 -313.264716)
			(xy 48.35828 -313.285814) (xy 48.311009 -313.299506) (xy 48.262154 -313.305438) (xy 48.212979 -313.303457)
			(xy 48.16476 -313.293613) (xy 48.118744 -313.276161) (xy 48.076123 -313.251554) (xy 48.038002 -313.220429)
			(xy 48.005367 -313.183592) (xy 47.979064 -313.141996) (xy 47.959773 -313.09672) (xy 47.947996 -313.048936)
			(xy 47.944036 -312.999882) (xy 46.655228 -312.999882) (xy 46.654733 -313.024489) (xy 46.646838 -313.073066)
			(xy 46.631254 -313.119747) (xy 46.608383 -313.163324) (xy 46.578818 -313.202668) (xy 46.543325 -313.23676)
			(xy 46.502822 -313.264716) (xy 46.45836 -313.285814) (xy 46.411089 -313.299506) (xy 46.362234 -313.305438)
			(xy 46.313059 -313.303457) (xy 46.26484 -313.293613) (xy 46.218824 -313.276161) (xy 46.176203 -313.251554)
			(xy 46.138082 -313.220429) (xy 46.105447 -313.183592) (xy 46.079144 -313.141996) (xy 46.059853 -313.09672)
			(xy 46.048076 -313.048936) (xy 46.044116 -312.999882) (xy 44.755054 -312.999882) (xy 44.754559 -313.024489)
			(xy 44.746664 -313.073066) (xy 44.73108 -313.119747) (xy 44.708209 -313.163324) (xy 44.678644 -313.202668)
			(xy 44.643151 -313.23676) (xy 44.602648 -313.264716) (xy 44.558186 -313.285814) (xy 44.510915 -313.299506)
			(xy 44.46206 -313.305438) (xy 44.412885 -313.303457) (xy 44.364666 -313.293613) (xy 44.31865 -313.276161)
			(xy 44.276029 -313.251554) (xy 44.237908 -313.220429) (xy 44.205273 -313.183592) (xy 44.17897 -313.141996)
			(xy 44.159679 -313.09672) (xy 44.147902 -313.048936) (xy 44.143942 -312.999882) (xy 0.508 -312.999882)
			(xy 0.508 -313.949842) (xy 44.143942 -313.949842) (xy 44.147902 -313.900788) (xy 44.159679 -313.853004)
			(xy 44.17897 -313.807728) (xy 44.205273 -313.766132) (xy 44.237908 -313.729295) (xy 44.276029 -313.69817)
			(xy 44.31865 -313.673563) (xy 44.364666 -313.656111) (xy 44.412885 -313.646267) (xy 44.46206 -313.644286)
			(xy 44.510915 -313.650218) (xy 44.558186 -313.66391) (xy 44.602648 -313.685008) (xy 44.643151 -313.712964)
			(xy 44.678644 -313.747056) (xy 44.708209 -313.7864) (xy 44.73108 -313.829977) (xy 44.746664 -313.876658)
			(xy 44.754559 -313.925235) (xy 44.755054 -313.949842) (xy 46.044116 -313.949842) (xy 46.048076 -313.900788)
			(xy 46.059853 -313.853004) (xy 46.079144 -313.807728) (xy 46.105447 -313.766132) (xy 46.138082 -313.729295)
			(xy 46.176203 -313.69817) (xy 46.218824 -313.673563) (xy 46.26484 -313.656111) (xy 46.313059 -313.646267)
			(xy 46.362234 -313.644286) (xy 46.411089 -313.650218) (xy 46.45836 -313.66391) (xy 46.502822 -313.685008)
			(xy 46.543325 -313.712964) (xy 46.578818 -313.747056) (xy 46.608383 -313.7864) (xy 46.631254 -313.829977)
			(xy 46.646838 -313.876658) (xy 46.654733 -313.925235) (xy 46.655228 -313.949842) (xy 47.944036 -313.949842)
			(xy 47.947996 -313.900788) (xy 47.959773 -313.853004) (xy 47.979064 -313.807728) (xy 48.005367 -313.766132)
			(xy 48.038002 -313.729295) (xy 48.076123 -313.69817) (xy 48.118744 -313.673563) (xy 48.16476 -313.656111)
			(xy 48.212979 -313.646267) (xy 48.262154 -313.644286) (xy 48.311009 -313.650218) (xy 48.35828 -313.66391)
			(xy 48.402742 -313.685008) (xy 48.443245 -313.712964) (xy 48.478738 -313.747056) (xy 48.508303 -313.7864)
			(xy 48.531174 -313.829977) (xy 48.546758 -313.876658) (xy 48.554653 -313.925235) (xy 48.555148 -313.949842)
			(xy 49.843956 -313.949842) (xy 49.847916 -313.900788) (xy 49.859693 -313.853004) (xy 49.878984 -313.807728)
			(xy 49.905287 -313.766132) (xy 49.937922 -313.729295) (xy 49.976043 -313.69817) (xy 50.018664 -313.673563)
			(xy 50.06468 -313.656111) (xy 50.112899 -313.646267) (xy 50.162074 -313.644286) (xy 50.210929 -313.650218)
			(xy 50.2582 -313.66391) (xy 50.302662 -313.685008) (xy 50.343165 -313.712964) (xy 50.378658 -313.747056)
			(xy 50.408223 -313.7864) (xy 50.431094 -313.829977) (xy 50.446678 -313.876658) (xy 50.454573 -313.925235)
			(xy 50.455068 -313.949842) (xy 51.74413 -313.949842) (xy 51.74809 -313.900788) (xy 51.759867 -313.853004)
			(xy 51.779158 -313.807728) (xy 51.805461 -313.766132) (xy 51.838096 -313.729295) (xy 51.876217 -313.69817)
			(xy 51.918838 -313.673563) (xy 51.964854 -313.656111) (xy 52.013073 -313.646267) (xy 52.062248 -313.644286)
			(xy 52.111103 -313.650218) (xy 52.158374 -313.66391) (xy 52.202836 -313.685008) (xy 52.243339 -313.712964)
			(xy 52.278832 -313.747056) (xy 52.308397 -313.7864) (xy 52.331268 -313.829977) (xy 52.346852 -313.876658)
			(xy 52.354747 -313.925235) (xy 52.355242 -313.949842) (xy 53.64405 -313.949842) (xy 53.64801 -313.900788)
			(xy 53.659787 -313.853004) (xy 53.679078 -313.807728) (xy 53.705381 -313.766132) (xy 53.738016 -313.729295)
			(xy 53.776137 -313.69817) (xy 53.818758 -313.673563) (xy 53.864774 -313.656111) (xy 53.912993 -313.646267)
			(xy 53.962168 -313.644286) (xy 54.011023 -313.650218) (xy 54.058294 -313.66391) (xy 54.102756 -313.685008)
			(xy 54.143259 -313.712964) (xy 54.178752 -313.747056) (xy 54.208317 -313.7864) (xy 54.231188 -313.829977)
			(xy 54.246772 -313.876658) (xy 54.254667 -313.925235) (xy 54.255162 -313.949842) (xy 55.54397 -313.949842)
			(xy 55.54793 -313.900788) (xy 55.559707 -313.853004) (xy 55.578998 -313.807728) (xy 55.605301 -313.766132)
			(xy 55.637936 -313.729295) (xy 55.676057 -313.69817) (xy 55.718678 -313.673563) (xy 55.764694 -313.656111)
			(xy 55.812913 -313.646267) (xy 55.862088 -313.644286) (xy 55.910943 -313.650218) (xy 55.958214 -313.66391)
			(xy 56.002676 -313.685008) (xy 56.043179 -313.712964) (xy 56.078672 -313.747056) (xy 56.108237 -313.7864)
			(xy 56.131108 -313.829977) (xy 56.146692 -313.876658) (xy 56.154587 -313.925235) (xy 56.155082 -313.949842)
			(xy 57.444144 -313.949842) (xy 57.448104 -313.900788) (xy 57.459881 -313.853004) (xy 57.479172 -313.807728)
			(xy 57.505475 -313.766132) (xy 57.53811 -313.729295) (xy 57.576231 -313.69817) (xy 57.618852 -313.673563)
			(xy 57.664868 -313.656111) (xy 57.713087 -313.646267) (xy 57.762262 -313.644286) (xy 57.811117 -313.650218)
			(xy 57.858388 -313.66391) (xy 57.90285 -313.685008) (xy 57.943353 -313.712964) (xy 57.978846 -313.747056)
			(xy 58.008411 -313.7864) (xy 58.031282 -313.829977) (xy 58.046866 -313.876658) (xy 58.054761 -313.925235)
			(xy 58.055256 -313.949842) (xy 74.544186 -313.949842) (xy 74.548146 -313.900788) (xy 74.559923 -313.853004)
			(xy 74.579214 -313.807728) (xy 74.605517 -313.766132) (xy 74.638152 -313.729295) (xy 74.676273 -313.69817)
			(xy 74.718894 -313.673563) (xy 74.76491 -313.656111) (xy 74.813129 -313.646267) (xy 74.862304 -313.644286)
			(xy 74.911159 -313.650218) (xy 74.95843 -313.66391) (xy 75.002892 -313.685008) (xy 75.043395 -313.712964)
			(xy 75.078888 -313.747056) (xy 75.108453 -313.7864) (xy 75.131324 -313.829977) (xy 75.146908 -313.876658)
			(xy 75.154803 -313.925235) (xy 75.155298 -313.949842) (xy 76.444106 -313.949842) (xy 76.448066 -313.900788)
			(xy 76.459843 -313.853004) (xy 76.479134 -313.807728) (xy 76.505437 -313.766132) (xy 76.538072 -313.729295)
			(xy 76.576193 -313.69817) (xy 76.618814 -313.673563) (xy 76.66483 -313.656111) (xy 76.713049 -313.646267)
			(xy 76.762224 -313.644286) (xy 76.811079 -313.650218) (xy 76.85835 -313.66391) (xy 76.902812 -313.685008)
			(xy 76.943315 -313.712964) (xy 76.978808 -313.747056) (xy 77.008373 -313.7864) (xy 77.031244 -313.829977)
			(xy 77.046828 -313.876658) (xy 77.054723 -313.925235) (xy 77.055218 -313.949842) (xy 78.344026 -313.949842)
			(xy 78.347986 -313.900788) (xy 78.359763 -313.853004) (xy 78.379054 -313.807728) (xy 78.405357 -313.766132)
			(xy 78.437992 -313.729295) (xy 78.476113 -313.69817) (xy 78.518734 -313.673563) (xy 78.56475 -313.656111)
			(xy 78.612969 -313.646267) (xy 78.662144 -313.644286) (xy 78.710999 -313.650218) (xy 78.75827 -313.66391)
			(xy 78.802732 -313.685008) (xy 78.843235 -313.712964) (xy 78.878728 -313.747056) (xy 78.908293 -313.7864)
			(xy 78.931164 -313.829977) (xy 78.946748 -313.876658) (xy 78.954643 -313.925235) (xy 78.955138 -313.949842)
			(xy 80.243946 -313.949842) (xy 80.247906 -313.900788) (xy 80.259683 -313.853004) (xy 80.278974 -313.807728)
			(xy 80.305277 -313.766132) (xy 80.337912 -313.729295) (xy 80.376033 -313.69817) (xy 80.418654 -313.673563)
			(xy 80.46467 -313.656111) (xy 80.512889 -313.646267) (xy 80.562064 -313.644286) (xy 80.610919 -313.650218)
			(xy 80.65819 -313.66391) (xy 80.702652 -313.685008) (xy 80.743155 -313.712964) (xy 80.778648 -313.747056)
			(xy 80.808213 -313.7864) (xy 80.831084 -313.829977) (xy 80.846668 -313.876658) (xy 80.854563 -313.925235)
			(xy 80.855058 -313.949842) (xy 154.54428 -313.949842) (xy 154.54824 -313.900788) (xy 154.560017 -313.853004)
			(xy 154.579308 -313.807728) (xy 154.605611 -313.766132) (xy 154.638246 -313.729295) (xy 154.676367 -313.69817)
			(xy 154.718988 -313.673563) (xy 154.765004 -313.656111) (xy 154.813223 -313.646267) (xy 154.862398 -313.644286)
			(xy 154.911253 -313.650218) (xy 154.958524 -313.66391) (xy 155.002986 -313.685008) (xy 155.043489 -313.712964)
			(xy 155.078982 -313.747056) (xy 155.108547 -313.7864) (xy 155.131418 -313.829977) (xy 155.147002 -313.876658)
			(xy 155.154897 -313.925235) (xy 155.155392 -313.949842) (xy 156.4442 -313.949842) (xy 156.44816 -313.900788)
			(xy 156.459937 -313.853004) (xy 156.479228 -313.807728) (xy 156.505531 -313.766132) (xy 156.538166 -313.729295)
			(xy 156.576287 -313.69817) (xy 156.618908 -313.673563) (xy 156.664924 -313.656111) (xy 156.713143 -313.646267)
			(xy 156.762318 -313.644286) (xy 156.811173 -313.650218) (xy 156.858444 -313.66391) (xy 156.902906 -313.685008)
			(xy 156.943409 -313.712964) (xy 156.978902 -313.747056) (xy 157.008467 -313.7864) (xy 157.031338 -313.829977)
			(xy 157.046922 -313.876658) (xy 157.054817 -313.925235) (xy 157.055312 -313.949842) (xy 158.34412 -313.949842)
			(xy 158.34808 -313.900788) (xy 158.359857 -313.853004) (xy 158.379148 -313.807728) (xy 158.405451 -313.766132)
			(xy 158.438086 -313.729295) (xy 158.476207 -313.69817) (xy 158.518828 -313.673563) (xy 158.564844 -313.656111)
			(xy 158.613063 -313.646267) (xy 158.662238 -313.644286) (xy 158.711093 -313.650218) (xy 158.758364 -313.66391)
			(xy 158.802826 -313.685008) (xy 158.843329 -313.712964) (xy 158.878822 -313.747056) (xy 158.908387 -313.7864)
			(xy 158.931258 -313.829977) (xy 158.946842 -313.876658) (xy 158.954737 -313.925235) (xy 158.955232 -313.949842)
			(xy 160.24404 -313.949842) (xy 160.248 -313.900788) (xy 160.259777 -313.853004) (xy 160.279068 -313.807728)
			(xy 160.305371 -313.766132) (xy 160.338006 -313.729295) (xy 160.376127 -313.69817) (xy 160.418748 -313.673563)
			(xy 160.464764 -313.656111) (xy 160.512983 -313.646267) (xy 160.562158 -313.644286) (xy 160.611013 -313.650218)
			(xy 160.658284 -313.66391) (xy 160.702746 -313.685008) (xy 160.743249 -313.712964) (xy 160.778742 -313.747056)
			(xy 160.808307 -313.7864) (xy 160.831178 -313.829977) (xy 160.846762 -313.876658) (xy 160.854657 -313.925235)
			(xy 160.855152 -313.949842) (xy 162.144214 -313.949842) (xy 162.148174 -313.900788) (xy 162.159951 -313.853004)
			(xy 162.179242 -313.807728) (xy 162.205545 -313.766132) (xy 162.23818 -313.729295) (xy 162.276301 -313.69817)
			(xy 162.318922 -313.673563) (xy 162.364938 -313.656111) (xy 162.413157 -313.646267) (xy 162.462332 -313.644286)
			(xy 162.511187 -313.650218) (xy 162.558458 -313.66391) (xy 162.60292 -313.685008) (xy 162.643423 -313.712964)
			(xy 162.678916 -313.747056) (xy 162.708481 -313.7864) (xy 162.731352 -313.829977) (xy 162.746936 -313.876658)
			(xy 162.754831 -313.925235) (xy 162.755326 -313.949842) (xy 164.044134 -313.949842) (xy 164.048094 -313.900788)
			(xy 164.059871 -313.853004) (xy 164.079162 -313.807728) (xy 164.105465 -313.766132) (xy 164.1381 -313.729295)
			(xy 164.176221 -313.69817) (xy 164.218842 -313.673563) (xy 164.264858 -313.656111) (xy 164.313077 -313.646267)
			(xy 164.362252 -313.644286) (xy 164.411107 -313.650218) (xy 164.458378 -313.66391) (xy 164.50284 -313.685008)
			(xy 164.543343 -313.712964) (xy 164.578836 -313.747056) (xy 164.608401 -313.7864) (xy 164.631272 -313.829977)
			(xy 164.646856 -313.876658) (xy 164.654751 -313.925235) (xy 164.655246 -313.949842) (xy 165.944054 -313.949842)
			(xy 165.948014 -313.900788) (xy 165.959791 -313.853004) (xy 165.979082 -313.807728) (xy 166.005385 -313.766132)
			(xy 166.03802 -313.729295) (xy 166.076141 -313.69817) (xy 166.118762 -313.673563) (xy 166.164778 -313.656111)
			(xy 166.212997 -313.646267) (xy 166.262172 -313.644286) (xy 166.311027 -313.650218) (xy 166.358298 -313.66391)
			(xy 166.40276 -313.685008) (xy 166.443263 -313.712964) (xy 166.478756 -313.747056) (xy 166.508321 -313.7864)
			(xy 166.531192 -313.829977) (xy 166.546776 -313.876658) (xy 166.554671 -313.925235) (xy 166.555166 -313.949842)
			(xy 183.044096 -313.949842) (xy 183.048056 -313.900788) (xy 183.059833 -313.853004) (xy 183.079124 -313.807728)
			(xy 183.105427 -313.766132) (xy 183.138062 -313.729295) (xy 183.176183 -313.69817) (xy 183.218804 -313.673563)
			(xy 183.26482 -313.656111) (xy 183.313039 -313.646267) (xy 183.362214 -313.644286) (xy 183.411069 -313.650218)
			(xy 183.45834 -313.66391) (xy 183.502802 -313.685008) (xy 183.543305 -313.712964) (xy 183.578798 -313.747056)
			(xy 183.608363 -313.7864) (xy 183.631234 -313.829977) (xy 183.646818 -313.876658) (xy 183.654713 -313.925235)
			(xy 183.655208 -313.949842) (xy 184.94427 -313.949842) (xy 184.94823 -313.900788) (xy 184.960007 -313.853004)
			(xy 184.979298 -313.807728) (xy 185.005601 -313.766132) (xy 185.038236 -313.729295) (xy 185.076357 -313.69817)
			(xy 185.118978 -313.673563) (xy 185.164994 -313.656111) (xy 185.213213 -313.646267) (xy 185.262388 -313.644286)
			(xy 185.311243 -313.650218) (xy 185.358514 -313.66391) (xy 185.402976 -313.685008) (xy 185.443479 -313.712964)
			(xy 185.478972 -313.747056) (xy 185.508537 -313.7864) (xy 185.531408 -313.829977) (xy 185.546992 -313.876658)
			(xy 185.554887 -313.925235) (xy 185.555382 -313.949842) (xy 186.84419 -313.949842) (xy 186.84815 -313.900788)
			(xy 186.859927 -313.853004) (xy 186.879218 -313.807728) (xy 186.905521 -313.766132) (xy 186.938156 -313.729295)
			(xy 186.976277 -313.69817) (xy 187.018898 -313.673563) (xy 187.064914 -313.656111) (xy 187.113133 -313.646267)
			(xy 187.162308 -313.644286) (xy 187.211163 -313.650218) (xy 187.258434 -313.66391) (xy 187.302896 -313.685008)
			(xy 187.343399 -313.712964) (xy 187.378892 -313.747056) (xy 187.408457 -313.7864) (xy 187.431328 -313.829977)
			(xy 187.446912 -313.876658) (xy 187.454807 -313.925235) (xy 187.455302 -313.949842) (xy 188.74411 -313.949842)
			(xy 188.74807 -313.900788) (xy 188.759847 -313.853004) (xy 188.779138 -313.807728) (xy 188.805441 -313.766132)
			(xy 188.838076 -313.729295) (xy 188.876197 -313.69817) (xy 188.918818 -313.673563) (xy 188.964834 -313.656111)
			(xy 189.013053 -313.646267) (xy 189.062228 -313.644286) (xy 189.111083 -313.650218) (xy 189.158354 -313.66391)
			(xy 189.202816 -313.685008) (xy 189.243319 -313.712964) (xy 189.278812 -313.747056) (xy 189.308377 -313.7864)
			(xy 189.331248 -313.829977) (xy 189.346832 -313.876658) (xy 189.354727 -313.925235) (xy 189.355222 -313.949842)
			(xy 276.343884 -313.949842) (xy 276.347844 -313.900788) (xy 276.359621 -313.853004) (xy 276.378912 -313.807728)
			(xy 276.405215 -313.766132) (xy 276.43785 -313.729295) (xy 276.475971 -313.69817) (xy 276.518592 -313.673563)
			(xy 276.564608 -313.656111) (xy 276.612827 -313.646267) (xy 276.662002 -313.644286) (xy 276.710857 -313.650218)
			(xy 276.758128 -313.66391) (xy 276.80259 -313.685008) (xy 276.843093 -313.712964) (xy 276.878586 -313.747056)
			(xy 276.908151 -313.7864) (xy 276.931022 -313.829977) (xy 276.946606 -313.876658) (xy 276.954501 -313.925235)
			(xy 276.954996 -313.949842) (xy 278.244058 -313.949842) (xy 278.248018 -313.900788) (xy 278.259795 -313.853004)
			(xy 278.279086 -313.807728) (xy 278.305389 -313.766132) (xy 278.338024 -313.729295) (xy 278.376145 -313.69817)
			(xy 278.418766 -313.673563) (xy 278.464782 -313.656111) (xy 278.513001 -313.646267) (xy 278.562176 -313.644286)
			(xy 278.611031 -313.650218) (xy 278.658302 -313.66391) (xy 278.702764 -313.685008) (xy 278.743267 -313.712964)
			(xy 278.77876 -313.747056) (xy 278.808325 -313.7864) (xy 278.831196 -313.829977) (xy 278.84678 -313.876658)
			(xy 278.854675 -313.925235) (xy 278.85517 -313.949842) (xy 280.143978 -313.949842) (xy 280.147938 -313.900788)
			(xy 280.159715 -313.853004) (xy 280.179006 -313.807728) (xy 280.205309 -313.766132) (xy 280.237944 -313.729295)
			(xy 280.276065 -313.69817) (xy 280.318686 -313.673563) (xy 280.364702 -313.656111) (xy 280.412921 -313.646267)
			(xy 280.462096 -313.644286) (xy 280.510951 -313.650218) (xy 280.558222 -313.66391) (xy 280.602684 -313.685008)
			(xy 280.643187 -313.712964) (xy 280.67868 -313.747056) (xy 280.708245 -313.7864) (xy 280.731116 -313.829977)
			(xy 280.7467 -313.876658) (xy 280.754595 -313.925235) (xy 280.75509 -313.949842) (xy 282.043898 -313.949842)
			(xy 282.047858 -313.900788) (xy 282.059635 -313.853004) (xy 282.078926 -313.807728) (xy 282.105229 -313.766132)
			(xy 282.137864 -313.729295) (xy 282.175985 -313.69817) (xy 282.218606 -313.673563) (xy 282.264622 -313.656111)
			(xy 282.312841 -313.646267) (xy 282.362016 -313.644286) (xy 282.410871 -313.650218) (xy 282.458142 -313.66391)
			(xy 282.502604 -313.685008) (xy 282.543107 -313.712964) (xy 282.5786 -313.747056) (xy 282.608165 -313.7864)
			(xy 282.631036 -313.829977) (xy 282.64662 -313.876658) (xy 282.654515 -313.925235) (xy 282.65501 -313.949842)
			(xy 283.944072 -313.949842) (xy 283.948032 -313.900788) (xy 283.959809 -313.853004) (xy 283.9791 -313.807728)
			(xy 284.005403 -313.766132) (xy 284.038038 -313.729295) (xy 284.076159 -313.69817) (xy 284.11878 -313.673563)
			(xy 284.164796 -313.656111) (xy 284.213015 -313.646267) (xy 284.26219 -313.644286) (xy 284.311045 -313.650218)
			(xy 284.358316 -313.66391) (xy 284.402778 -313.685008) (xy 284.443281 -313.712964) (xy 284.478774 -313.747056)
			(xy 284.508339 -313.7864) (xy 284.53121 -313.829977) (xy 284.546794 -313.876658) (xy 284.554689 -313.925235)
			(xy 284.555184 -313.949842) (xy 285.843992 -313.949842) (xy 285.847952 -313.900788) (xy 285.859729 -313.853004)
			(xy 285.87902 -313.807728) (xy 285.905323 -313.766132) (xy 285.937958 -313.729295) (xy 285.976079 -313.69817)
			(xy 286.0187 -313.673563) (xy 286.064716 -313.656111) (xy 286.112935 -313.646267) (xy 286.16211 -313.644286)
			(xy 286.210965 -313.650218) (xy 286.258236 -313.66391) (xy 286.302698 -313.685008) (xy 286.343201 -313.712964)
			(xy 286.378694 -313.747056) (xy 286.408259 -313.7864) (xy 286.43113 -313.829977) (xy 286.446714 -313.876658)
			(xy 286.454609 -313.925235) (xy 286.455104 -313.949842) (xy 287.743912 -313.949842) (xy 287.747872 -313.900788)
			(xy 287.759649 -313.853004) (xy 287.77894 -313.807728) (xy 287.805243 -313.766132) (xy 287.837878 -313.729295)
			(xy 287.875999 -313.69817) (xy 287.91862 -313.673563) (xy 287.964636 -313.656111) (xy 288.012855 -313.646267)
			(xy 288.06203 -313.644286) (xy 288.110885 -313.650218) (xy 288.158156 -313.66391) (xy 288.202618 -313.685008)
			(xy 288.243121 -313.712964) (xy 288.278614 -313.747056) (xy 288.308179 -313.7864) (xy 288.33105 -313.829977)
			(xy 288.346634 -313.876658) (xy 288.354529 -313.925235) (xy 288.355024 -313.949842) (xy 289.644086 -313.949842)
			(xy 289.648046 -313.900788) (xy 289.659823 -313.853004) (xy 289.679114 -313.807728) (xy 289.705417 -313.766132)
			(xy 289.738052 -313.729295) (xy 289.776173 -313.69817) (xy 289.818794 -313.673563) (xy 289.86481 -313.656111)
			(xy 289.913029 -313.646267) (xy 289.962204 -313.644286) (xy 290.011059 -313.650218) (xy 290.05833 -313.66391)
			(xy 290.102792 -313.685008) (xy 290.143295 -313.712964) (xy 290.178788 -313.747056) (xy 290.208353 -313.7864)
			(xy 290.231224 -313.829977) (xy 290.246808 -313.876658) (xy 290.254703 -313.925235) (xy 290.255198 -313.949842)
			(xy 306.744128 -313.949842) (xy 306.748088 -313.900788) (xy 306.759865 -313.853004) (xy 306.779156 -313.807728)
			(xy 306.805459 -313.766132) (xy 306.838094 -313.729295) (xy 306.876215 -313.69817) (xy 306.918836 -313.673563)
			(xy 306.964852 -313.656111) (xy 307.013071 -313.646267) (xy 307.062246 -313.644286) (xy 307.111101 -313.650218)
			(xy 307.158372 -313.66391) (xy 307.202834 -313.685008) (xy 307.243337 -313.712964) (xy 307.27883 -313.747056)
			(xy 307.308395 -313.7864) (xy 307.331266 -313.829977) (xy 307.34685 -313.876658) (xy 307.354745 -313.925235)
			(xy 307.35524 -313.949842) (xy 308.644048 -313.949842) (xy 308.648008 -313.900788) (xy 308.659785 -313.853004)
			(xy 308.679076 -313.807728) (xy 308.705379 -313.766132) (xy 308.738014 -313.729295) (xy 308.776135 -313.69817)
			(xy 308.818756 -313.673563) (xy 308.864772 -313.656111) (xy 308.912991 -313.646267) (xy 308.962166 -313.644286)
			(xy 309.011021 -313.650218) (xy 309.058292 -313.66391) (xy 309.102754 -313.685008) (xy 309.143257 -313.712964)
			(xy 309.17875 -313.747056) (xy 309.208315 -313.7864) (xy 309.231186 -313.829977) (xy 309.24677 -313.876658)
			(xy 309.254665 -313.925235) (xy 309.25516 -313.949842) (xy 310.543968 -313.949842) (xy 310.547928 -313.900788)
			(xy 310.559705 -313.853004) (xy 310.578996 -313.807728) (xy 310.605299 -313.766132) (xy 310.637934 -313.729295)
			(xy 310.676055 -313.69817) (xy 310.718676 -313.673563) (xy 310.764692 -313.656111) (xy 310.812911 -313.646267)
			(xy 310.862086 -313.644286) (xy 310.910941 -313.650218) (xy 310.958212 -313.66391) (xy 311.002674 -313.685008)
			(xy 311.043177 -313.712964) (xy 311.07867 -313.747056) (xy 311.108235 -313.7864) (xy 311.131106 -313.829977)
			(xy 311.14669 -313.876658) (xy 311.154585 -313.925235) (xy 311.15508 -313.949842) (xy 312.443888 -313.949842)
			(xy 312.447848 -313.900788) (xy 312.459625 -313.853004) (xy 312.478916 -313.807728) (xy 312.505219 -313.766132)
			(xy 312.537854 -313.729295) (xy 312.575975 -313.69817) (xy 312.618596 -313.673563) (xy 312.664612 -313.656111)
			(xy 312.712831 -313.646267) (xy 312.762006 -313.644286) (xy 312.810861 -313.650218) (xy 312.858132 -313.66391)
			(xy 312.902594 -313.685008) (xy 312.943097 -313.712964) (xy 312.97859 -313.747056) (xy 313.008155 -313.7864)
			(xy 313.031026 -313.829977) (xy 313.04661 -313.876658) (xy 313.054505 -313.925235) (xy 313.055 -313.949842)
			(xy 386.744222 -313.949842) (xy 386.748182 -313.900788) (xy 386.759959 -313.853004) (xy 386.77925 -313.807728)
			(xy 386.805553 -313.766132) (xy 386.838188 -313.729295) (xy 386.876309 -313.69817) (xy 386.91893 -313.673563)
			(xy 386.964946 -313.656111) (xy 387.013165 -313.646267) (xy 387.06234 -313.644286) (xy 387.111195 -313.650218)
			(xy 387.158466 -313.66391) (xy 387.202928 -313.685008) (xy 387.243431 -313.712964) (xy 387.278924 -313.747056)
			(xy 387.308489 -313.7864) (xy 387.33136 -313.829977) (xy 387.346944 -313.876658) (xy 387.354839 -313.925235)
			(xy 387.355334 -313.949842) (xy 388.644142 -313.949842) (xy 388.648102 -313.900788) (xy 388.659879 -313.853004)
			(xy 388.67917 -313.807728) (xy 388.705473 -313.766132) (xy 388.738108 -313.729295) (xy 388.776229 -313.69817)
			(xy 388.81885 -313.673563) (xy 388.864866 -313.656111) (xy 388.913085 -313.646267) (xy 388.96226 -313.644286)
			(xy 389.011115 -313.650218) (xy 389.058386 -313.66391) (xy 389.102848 -313.685008) (xy 389.143351 -313.712964)
			(xy 389.178844 -313.747056) (xy 389.208409 -313.7864) (xy 389.23128 -313.829977) (xy 389.246864 -313.876658)
			(xy 389.254759 -313.925235) (xy 389.255254 -313.949842) (xy 390.544062 -313.949842) (xy 390.548022 -313.900788)
			(xy 390.559799 -313.853004) (xy 390.57909 -313.807728) (xy 390.605393 -313.766132) (xy 390.638028 -313.729295)
			(xy 390.676149 -313.69817) (xy 390.71877 -313.673563) (xy 390.764786 -313.656111) (xy 390.813005 -313.646267)
			(xy 390.86218 -313.644286) (xy 390.911035 -313.650218) (xy 390.958306 -313.66391) (xy 391.002768 -313.685008)
			(xy 391.043271 -313.712964) (xy 391.078764 -313.747056) (xy 391.108329 -313.7864) (xy 391.1312 -313.829977)
			(xy 391.146784 -313.876658) (xy 391.154679 -313.925235) (xy 391.155174 -313.949842) (xy 392.443982 -313.949842)
			(xy 392.447942 -313.900788) (xy 392.459719 -313.853004) (xy 392.47901 -313.807728) (xy 392.505313 -313.766132)
			(xy 392.537948 -313.729295) (xy 392.576069 -313.69817) (xy 392.61869 -313.673563) (xy 392.664706 -313.656111)
			(xy 392.712925 -313.646267) (xy 392.7621 -313.644286) (xy 392.810955 -313.650218) (xy 392.858226 -313.66391)
			(xy 392.902688 -313.685008) (xy 392.943191 -313.712964) (xy 392.978684 -313.747056) (xy 393.008249 -313.7864)
			(xy 393.03112 -313.829977) (xy 393.046704 -313.876658) (xy 393.054599 -313.925235) (xy 393.055094 -313.949842)
			(xy 394.344156 -313.949842) (xy 394.348116 -313.900788) (xy 394.359893 -313.853004) (xy 394.379184 -313.807728)
			(xy 394.405487 -313.766132) (xy 394.438122 -313.729295) (xy 394.476243 -313.69817) (xy 394.518864 -313.673563)
			(xy 394.56488 -313.656111) (xy 394.613099 -313.646267) (xy 394.662274 -313.644286) (xy 394.711129 -313.650218)
			(xy 394.7584 -313.66391) (xy 394.802862 -313.685008) (xy 394.843365 -313.712964) (xy 394.878858 -313.747056)
			(xy 394.908423 -313.7864) (xy 394.931294 -313.829977) (xy 394.946878 -313.876658) (xy 394.954773 -313.925235)
			(xy 394.955268 -313.949842) (xy 396.244076 -313.949842) (xy 396.248036 -313.900788) (xy 396.259813 -313.853004)
			(xy 396.279104 -313.807728) (xy 396.305407 -313.766132) (xy 396.338042 -313.729295) (xy 396.376163 -313.69817)
			(xy 396.418784 -313.673563) (xy 396.4648 -313.656111) (xy 396.513019 -313.646267) (xy 396.562194 -313.644286)
			(xy 396.611049 -313.650218) (xy 396.65832 -313.66391) (xy 396.702782 -313.685008) (xy 396.743285 -313.712964)
			(xy 396.778778 -313.747056) (xy 396.808343 -313.7864) (xy 396.831214 -313.829977) (xy 396.846798 -313.876658)
			(xy 396.854693 -313.925235) (xy 396.855188 -313.949842) (xy 398.143996 -313.949842) (xy 398.147956 -313.900788)
			(xy 398.159733 -313.853004) (xy 398.179024 -313.807728) (xy 398.205327 -313.766132) (xy 398.237962 -313.729295)
			(xy 398.276083 -313.69817) (xy 398.318704 -313.673563) (xy 398.36472 -313.656111) (xy 398.412939 -313.646267)
			(xy 398.462114 -313.644286) (xy 398.510969 -313.650218) (xy 398.55824 -313.66391) (xy 398.602702 -313.685008)
			(xy 398.643205 -313.712964) (xy 398.678698 -313.747056) (xy 398.708263 -313.7864) (xy 398.731134 -313.829977)
			(xy 398.746718 -313.876658) (xy 398.754613 -313.925235) (xy 398.755108 -313.949842) (xy 415.244038 -313.949842)
			(xy 415.247998 -313.900788) (xy 415.259775 -313.853004) (xy 415.279066 -313.807728) (xy 415.305369 -313.766132)
			(xy 415.338004 -313.729295) (xy 415.376125 -313.69817) (xy 415.418746 -313.673563) (xy 415.464762 -313.656111)
			(xy 415.512981 -313.646267) (xy 415.562156 -313.644286) (xy 415.611011 -313.650218) (xy 415.658282 -313.66391)
			(xy 415.702744 -313.685008) (xy 415.743247 -313.712964) (xy 415.77874 -313.747056) (xy 415.808305 -313.7864)
			(xy 415.831176 -313.829977) (xy 415.84676 -313.876658) (xy 415.854655 -313.925235) (xy 415.85515 -313.949842)
			(xy 417.144212 -313.949842) (xy 417.148172 -313.900788) (xy 417.159949 -313.853004) (xy 417.17924 -313.807728)
			(xy 417.205543 -313.766132) (xy 417.238178 -313.729295) (xy 417.276299 -313.69817) (xy 417.31892 -313.673563)
			(xy 417.364936 -313.656111) (xy 417.413155 -313.646267) (xy 417.46233 -313.644286) (xy 417.511185 -313.650218)
			(xy 417.558456 -313.66391) (xy 417.602918 -313.685008) (xy 417.643421 -313.712964) (xy 417.678914 -313.747056)
			(xy 417.708479 -313.7864) (xy 417.73135 -313.829977) (xy 417.746934 -313.876658) (xy 417.754829 -313.925235)
			(xy 417.755324 -313.949842) (xy 419.044132 -313.949842) (xy 419.048092 -313.900788) (xy 419.059869 -313.853004)
			(xy 419.07916 -313.807728) (xy 419.105463 -313.766132) (xy 419.138098 -313.729295) (xy 419.176219 -313.69817)
			(xy 419.21884 -313.673563) (xy 419.264856 -313.656111) (xy 419.313075 -313.646267) (xy 419.36225 -313.644286)
			(xy 419.411105 -313.650218) (xy 419.458376 -313.66391) (xy 419.502838 -313.685008) (xy 419.543341 -313.712964)
			(xy 419.578834 -313.747056) (xy 419.608399 -313.7864) (xy 419.63127 -313.829977) (xy 419.646854 -313.876658)
			(xy 419.654749 -313.925235) (xy 419.655244 -313.949842) (xy 420.944052 -313.949842) (xy 420.948012 -313.900788)
			(xy 420.959789 -313.853004) (xy 420.97908 -313.807728) (xy 421.005383 -313.766132) (xy 421.038018 -313.729295)
			(xy 421.076139 -313.69817) (xy 421.11876 -313.673563) (xy 421.164776 -313.656111) (xy 421.212995 -313.646267)
			(xy 421.26217 -313.644286) (xy 421.311025 -313.650218) (xy 421.358296 -313.66391) (xy 421.402758 -313.685008)
			(xy 421.443261 -313.712964) (xy 421.478754 -313.747056) (xy 421.508319 -313.7864) (xy 421.53119 -313.829977)
			(xy 421.546774 -313.876658) (xy 421.554669 -313.925235) (xy 421.555164 -313.949842) (xy 421.554669 -313.974449)
			(xy 421.546774 -314.023026) (xy 421.53119 -314.069707) (xy 421.508319 -314.113284) (xy 421.478754 -314.152628)
			(xy 421.443261 -314.18672) (xy 421.402758 -314.214676) (xy 421.358296 -314.235774) (xy 421.311025 -314.249466)
			(xy 421.26217 -314.255398) (xy 421.212995 -314.253417) (xy 421.164776 -314.243573) (xy 421.11876 -314.226121)
			(xy 421.076139 -314.201514) (xy 421.038018 -314.170389) (xy 421.005383 -314.133552) (xy 420.97908 -314.091956)
			(xy 420.959789 -314.04668) (xy 420.948012 -313.998896) (xy 420.944052 -313.949842) (xy 419.655244 -313.949842)
			(xy 419.654749 -313.974449) (xy 419.646854 -314.023026) (xy 419.63127 -314.069707) (xy 419.608399 -314.113284)
			(xy 419.578834 -314.152628) (xy 419.543341 -314.18672) (xy 419.502838 -314.214676) (xy 419.458376 -314.235774)
			(xy 419.411105 -314.249466) (xy 419.36225 -314.255398) (xy 419.313075 -314.253417) (xy 419.264856 -314.243573)
			(xy 419.21884 -314.226121) (xy 419.176219 -314.201514) (xy 419.138098 -314.170389) (xy 419.105463 -314.133552)
			(xy 419.07916 -314.091956) (xy 419.059869 -314.04668) (xy 419.048092 -313.998896) (xy 419.044132 -313.949842)
			(xy 417.755324 -313.949842) (xy 417.754829 -313.974449) (xy 417.746934 -314.023026) (xy 417.73135 -314.069707)
			(xy 417.708479 -314.113284) (xy 417.678914 -314.152628) (xy 417.643421 -314.18672) (xy 417.602918 -314.214676)
			(xy 417.558456 -314.235774) (xy 417.511185 -314.249466) (xy 417.46233 -314.255398) (xy 417.413155 -314.253417)
			(xy 417.364936 -314.243573) (xy 417.31892 -314.226121) (xy 417.276299 -314.201514) (xy 417.238178 -314.170389)
			(xy 417.205543 -314.133552) (xy 417.17924 -314.091956) (xy 417.159949 -314.04668) (xy 417.148172 -313.998896)
			(xy 417.144212 -313.949842) (xy 415.85515 -313.949842) (xy 415.854655 -313.974449) (xy 415.84676 -314.023026)
			(xy 415.831176 -314.069707) (xy 415.808305 -314.113284) (xy 415.77874 -314.152628) (xy 415.743247 -314.18672)
			(xy 415.702744 -314.214676) (xy 415.658282 -314.235774) (xy 415.611011 -314.249466) (xy 415.562156 -314.255398)
			(xy 415.512981 -314.253417) (xy 415.464762 -314.243573) (xy 415.418746 -314.226121) (xy 415.376125 -314.201514)
			(xy 415.338004 -314.170389) (xy 415.305369 -314.133552) (xy 415.279066 -314.091956) (xy 415.259775 -314.04668)
			(xy 415.247998 -313.998896) (xy 415.244038 -313.949842) (xy 398.755108 -313.949842) (xy 398.754613 -313.974449)
			(xy 398.746718 -314.023026) (xy 398.731134 -314.069707) (xy 398.708263 -314.113284) (xy 398.678698 -314.152628)
			(xy 398.643205 -314.18672) (xy 398.602702 -314.214676) (xy 398.55824 -314.235774) (xy 398.510969 -314.249466)
			(xy 398.462114 -314.255398) (xy 398.412939 -314.253417) (xy 398.36472 -314.243573) (xy 398.318704 -314.226121)
			(xy 398.276083 -314.201514) (xy 398.237962 -314.170389) (xy 398.205327 -314.133552) (xy 398.179024 -314.091956)
			(xy 398.159733 -314.04668) (xy 398.147956 -313.998896) (xy 398.143996 -313.949842) (xy 396.855188 -313.949842)
			(xy 396.854693 -313.974449) (xy 396.846798 -314.023026) (xy 396.831214 -314.069707) (xy 396.808343 -314.113284)
			(xy 396.778778 -314.152628) (xy 396.743285 -314.18672) (xy 396.702782 -314.214676) (xy 396.65832 -314.235774)
			(xy 396.611049 -314.249466) (xy 396.562194 -314.255398) (xy 396.513019 -314.253417) (xy 396.4648 -314.243573)
			(xy 396.418784 -314.226121) (xy 396.376163 -314.201514) (xy 396.338042 -314.170389) (xy 396.305407 -314.133552)
			(xy 396.279104 -314.091956) (xy 396.259813 -314.04668) (xy 396.248036 -313.998896) (xy 396.244076 -313.949842)
			(xy 394.955268 -313.949842) (xy 394.954773 -313.974449) (xy 394.946878 -314.023026) (xy 394.931294 -314.069707)
			(xy 394.908423 -314.113284) (xy 394.878858 -314.152628) (xy 394.843365 -314.18672) (xy 394.802862 -314.214676)
			(xy 394.7584 -314.235774) (xy 394.711129 -314.249466) (xy 394.662274 -314.255398) (xy 394.613099 -314.253417)
			(xy 394.56488 -314.243573) (xy 394.518864 -314.226121) (xy 394.476243 -314.201514) (xy 394.438122 -314.170389)
			(xy 394.405487 -314.133552) (xy 394.379184 -314.091956) (xy 394.359893 -314.04668) (xy 394.348116 -313.998896)
			(xy 394.344156 -313.949842) (xy 393.055094 -313.949842) (xy 393.054599 -313.974449) (xy 393.046704 -314.023026)
			(xy 393.03112 -314.069707) (xy 393.008249 -314.113284) (xy 392.978684 -314.152628) (xy 392.943191 -314.18672)
			(xy 392.902688 -314.214676) (xy 392.858226 -314.235774) (xy 392.810955 -314.249466) (xy 392.7621 -314.255398)
			(xy 392.712925 -314.253417) (xy 392.664706 -314.243573) (xy 392.61869 -314.226121) (xy 392.576069 -314.201514)
			(xy 392.537948 -314.170389) (xy 392.505313 -314.133552) (xy 392.47901 -314.091956) (xy 392.459719 -314.04668)
			(xy 392.447942 -313.998896) (xy 392.443982 -313.949842) (xy 391.155174 -313.949842) (xy 391.154679 -313.974449)
			(xy 391.146784 -314.023026) (xy 391.1312 -314.069707) (xy 391.108329 -314.113284) (xy 391.078764 -314.152628)
			(xy 391.043271 -314.18672) (xy 391.002768 -314.214676) (xy 390.958306 -314.235774) (xy 390.911035 -314.249466)
			(xy 390.86218 -314.255398) (xy 390.813005 -314.253417) (xy 390.764786 -314.243573) (xy 390.71877 -314.226121)
			(xy 390.676149 -314.201514) (xy 390.638028 -314.170389) (xy 390.605393 -314.133552) (xy 390.57909 -314.091956)
			(xy 390.559799 -314.04668) (xy 390.548022 -313.998896) (xy 390.544062 -313.949842) (xy 389.255254 -313.949842)
			(xy 389.254759 -313.974449) (xy 389.246864 -314.023026) (xy 389.23128 -314.069707) (xy 389.208409 -314.113284)
			(xy 389.178844 -314.152628) (xy 389.143351 -314.18672) (xy 389.102848 -314.214676) (xy 389.058386 -314.235774)
			(xy 389.011115 -314.249466) (xy 388.96226 -314.255398) (xy 388.913085 -314.253417) (xy 388.864866 -314.243573)
			(xy 388.81885 -314.226121) (xy 388.776229 -314.201514) (xy 388.738108 -314.170389) (xy 388.705473 -314.133552)
			(xy 388.67917 -314.091956) (xy 388.659879 -314.04668) (xy 388.648102 -313.998896) (xy 388.644142 -313.949842)
			(xy 387.355334 -313.949842) (xy 387.354839 -313.974449) (xy 387.346944 -314.023026) (xy 387.33136 -314.069707)
			(xy 387.308489 -314.113284) (xy 387.278924 -314.152628) (xy 387.243431 -314.18672) (xy 387.202928 -314.214676)
			(xy 387.158466 -314.235774) (xy 387.111195 -314.249466) (xy 387.06234 -314.255398) (xy 387.013165 -314.253417)
			(xy 386.964946 -314.243573) (xy 386.91893 -314.226121) (xy 386.876309 -314.201514) (xy 386.838188 -314.170389)
			(xy 386.805553 -314.133552) (xy 386.77925 -314.091956) (xy 386.759959 -314.04668) (xy 386.748182 -313.998896)
			(xy 386.744222 -313.949842) (xy 313.055 -313.949842) (xy 313.054505 -313.974449) (xy 313.04661 -314.023026)
			(xy 313.031026 -314.069707) (xy 313.008155 -314.113284) (xy 312.97859 -314.152628) (xy 312.943097 -314.18672)
			(xy 312.902594 -314.214676) (xy 312.858132 -314.235774) (xy 312.810861 -314.249466) (xy 312.762006 -314.255398)
			(xy 312.712831 -314.253417) (xy 312.664612 -314.243573) (xy 312.618596 -314.226121) (xy 312.575975 -314.201514)
			(xy 312.537854 -314.170389) (xy 312.505219 -314.133552) (xy 312.478916 -314.091956) (xy 312.459625 -314.04668)
			(xy 312.447848 -313.998896) (xy 312.443888 -313.949842) (xy 311.15508 -313.949842) (xy 311.154585 -313.974449)
			(xy 311.14669 -314.023026) (xy 311.131106 -314.069707) (xy 311.108235 -314.113284) (xy 311.07867 -314.152628)
			(xy 311.043177 -314.18672) (xy 311.002674 -314.214676) (xy 310.958212 -314.235774) (xy 310.910941 -314.249466)
			(xy 310.862086 -314.255398) (xy 310.812911 -314.253417) (xy 310.764692 -314.243573) (xy 310.718676 -314.226121)
			(xy 310.676055 -314.201514) (xy 310.637934 -314.170389) (xy 310.605299 -314.133552) (xy 310.578996 -314.091956)
			(xy 310.559705 -314.04668) (xy 310.547928 -313.998896) (xy 310.543968 -313.949842) (xy 309.25516 -313.949842)
			(xy 309.254665 -313.974449) (xy 309.24677 -314.023026) (xy 309.231186 -314.069707) (xy 309.208315 -314.113284)
			(xy 309.17875 -314.152628) (xy 309.143257 -314.18672) (xy 309.102754 -314.214676) (xy 309.058292 -314.235774)
			(xy 309.011021 -314.249466) (xy 308.962166 -314.255398) (xy 308.912991 -314.253417) (xy 308.864772 -314.243573)
			(xy 308.818756 -314.226121) (xy 308.776135 -314.201514) (xy 308.738014 -314.170389) (xy 308.705379 -314.133552)
			(xy 308.679076 -314.091956) (xy 308.659785 -314.04668) (xy 308.648008 -313.998896) (xy 308.644048 -313.949842)
			(xy 307.35524 -313.949842) (xy 307.354745 -313.974449) (xy 307.34685 -314.023026) (xy 307.331266 -314.069707)
			(xy 307.308395 -314.113284) (xy 307.27883 -314.152628) (xy 307.243337 -314.18672) (xy 307.202834 -314.214676)
			(xy 307.158372 -314.235774) (xy 307.111101 -314.249466) (xy 307.062246 -314.255398) (xy 307.013071 -314.253417)
			(xy 306.964852 -314.243573) (xy 306.918836 -314.226121) (xy 306.876215 -314.201514) (xy 306.838094 -314.170389)
			(xy 306.805459 -314.133552) (xy 306.779156 -314.091956) (xy 306.759865 -314.04668) (xy 306.748088 -313.998896)
			(xy 306.744128 -313.949842) (xy 290.255198 -313.949842) (xy 290.254703 -313.974449) (xy 290.246808 -314.023026)
			(xy 290.231224 -314.069707) (xy 290.208353 -314.113284) (xy 290.178788 -314.152628) (xy 290.143295 -314.18672)
			(xy 290.102792 -314.214676) (xy 290.05833 -314.235774) (xy 290.011059 -314.249466) (xy 289.962204 -314.255398)
			(xy 289.913029 -314.253417) (xy 289.86481 -314.243573) (xy 289.818794 -314.226121) (xy 289.776173 -314.201514)
			(xy 289.738052 -314.170389) (xy 289.705417 -314.133552) (xy 289.679114 -314.091956) (xy 289.659823 -314.04668)
			(xy 289.648046 -313.998896) (xy 289.644086 -313.949842) (xy 288.355024 -313.949842) (xy 288.354529 -313.974449)
			(xy 288.346634 -314.023026) (xy 288.33105 -314.069707) (xy 288.308179 -314.113284) (xy 288.278614 -314.152628)
			(xy 288.243121 -314.18672) (xy 288.202618 -314.214676) (xy 288.158156 -314.235774) (xy 288.110885 -314.249466)
			(xy 288.06203 -314.255398) (xy 288.012855 -314.253417) (xy 287.964636 -314.243573) (xy 287.91862 -314.226121)
			(xy 287.875999 -314.201514) (xy 287.837878 -314.170389) (xy 287.805243 -314.133552) (xy 287.77894 -314.091956)
			(xy 287.759649 -314.04668) (xy 287.747872 -313.998896) (xy 287.743912 -313.949842) (xy 286.455104 -313.949842)
			(xy 286.454609 -313.974449) (xy 286.446714 -314.023026) (xy 286.43113 -314.069707) (xy 286.408259 -314.113284)
			(xy 286.378694 -314.152628) (xy 286.343201 -314.18672) (xy 286.302698 -314.214676) (xy 286.258236 -314.235774)
			(xy 286.210965 -314.249466) (xy 286.16211 -314.255398) (xy 286.112935 -314.253417) (xy 286.064716 -314.243573)
			(xy 286.0187 -314.226121) (xy 285.976079 -314.201514) (xy 285.937958 -314.170389) (xy 285.905323 -314.133552)
			(xy 285.87902 -314.091956) (xy 285.859729 -314.04668) (xy 285.847952 -313.998896) (xy 285.843992 -313.949842)
			(xy 284.555184 -313.949842) (xy 284.554689 -313.974449) (xy 284.546794 -314.023026) (xy 284.53121 -314.069707)
			(xy 284.508339 -314.113284) (xy 284.478774 -314.152628) (xy 284.443281 -314.18672) (xy 284.402778 -314.214676)
			(xy 284.358316 -314.235774) (xy 284.311045 -314.249466) (xy 284.26219 -314.255398) (xy 284.213015 -314.253417)
			(xy 284.164796 -314.243573) (xy 284.11878 -314.226121) (xy 284.076159 -314.201514) (xy 284.038038 -314.170389)
			(xy 284.005403 -314.133552) (xy 283.9791 -314.091956) (xy 283.959809 -314.04668) (xy 283.948032 -313.998896)
			(xy 283.944072 -313.949842) (xy 282.65501 -313.949842) (xy 282.654515 -313.974449) (xy 282.64662 -314.023026)
			(xy 282.631036 -314.069707) (xy 282.608165 -314.113284) (xy 282.5786 -314.152628) (xy 282.543107 -314.18672)
			(xy 282.502604 -314.214676) (xy 282.458142 -314.235774) (xy 282.410871 -314.249466) (xy 282.362016 -314.255398)
			(xy 282.312841 -314.253417) (xy 282.264622 -314.243573) (xy 282.218606 -314.226121) (xy 282.175985 -314.201514)
			(xy 282.137864 -314.170389) (xy 282.105229 -314.133552) (xy 282.078926 -314.091956) (xy 282.059635 -314.04668)
			(xy 282.047858 -313.998896) (xy 282.043898 -313.949842) (xy 280.75509 -313.949842) (xy 280.754595 -313.974449)
			(xy 280.7467 -314.023026) (xy 280.731116 -314.069707) (xy 280.708245 -314.113284) (xy 280.67868 -314.152628)
			(xy 280.643187 -314.18672) (xy 280.602684 -314.214676) (xy 280.558222 -314.235774) (xy 280.510951 -314.249466)
			(xy 280.462096 -314.255398) (xy 280.412921 -314.253417) (xy 280.364702 -314.243573) (xy 280.318686 -314.226121)
			(xy 280.276065 -314.201514) (xy 280.237944 -314.170389) (xy 280.205309 -314.133552) (xy 280.179006 -314.091956)
			(xy 280.159715 -314.04668) (xy 280.147938 -313.998896) (xy 280.143978 -313.949842) (xy 278.85517 -313.949842)
			(xy 278.854675 -313.974449) (xy 278.84678 -314.023026) (xy 278.831196 -314.069707) (xy 278.808325 -314.113284)
			(xy 278.77876 -314.152628) (xy 278.743267 -314.18672) (xy 278.702764 -314.214676) (xy 278.658302 -314.235774)
			(xy 278.611031 -314.249466) (xy 278.562176 -314.255398) (xy 278.513001 -314.253417) (xy 278.464782 -314.243573)
			(xy 278.418766 -314.226121) (xy 278.376145 -314.201514) (xy 278.338024 -314.170389) (xy 278.305389 -314.133552)
			(xy 278.279086 -314.091956) (xy 278.259795 -314.04668) (xy 278.248018 -313.998896) (xy 278.244058 -313.949842)
			(xy 276.954996 -313.949842) (xy 276.954501 -313.974449) (xy 276.946606 -314.023026) (xy 276.931022 -314.069707)
			(xy 276.908151 -314.113284) (xy 276.878586 -314.152628) (xy 276.843093 -314.18672) (xy 276.80259 -314.214676)
			(xy 276.758128 -314.235774) (xy 276.710857 -314.249466) (xy 276.662002 -314.255398) (xy 276.612827 -314.253417)
			(xy 276.564608 -314.243573) (xy 276.518592 -314.226121) (xy 276.475971 -314.201514) (xy 276.43785 -314.170389)
			(xy 276.405215 -314.133552) (xy 276.378912 -314.091956) (xy 276.359621 -314.04668) (xy 276.347844 -313.998896)
			(xy 276.343884 -313.949842) (xy 189.355222 -313.949842) (xy 189.354727 -313.974449) (xy 189.346832 -314.023026)
			(xy 189.331248 -314.069707) (xy 189.308377 -314.113284) (xy 189.278812 -314.152628) (xy 189.243319 -314.18672)
			(xy 189.202816 -314.214676) (xy 189.158354 -314.235774) (xy 189.111083 -314.249466) (xy 189.062228 -314.255398)
			(xy 189.013053 -314.253417) (xy 188.964834 -314.243573) (xy 188.918818 -314.226121) (xy 188.876197 -314.201514)
			(xy 188.838076 -314.170389) (xy 188.805441 -314.133552) (xy 188.779138 -314.091956) (xy 188.759847 -314.04668)
			(xy 188.74807 -313.998896) (xy 188.74411 -313.949842) (xy 187.455302 -313.949842) (xy 187.454807 -313.974449)
			(xy 187.446912 -314.023026) (xy 187.431328 -314.069707) (xy 187.408457 -314.113284) (xy 187.378892 -314.152628)
			(xy 187.343399 -314.18672) (xy 187.302896 -314.214676) (xy 187.258434 -314.235774) (xy 187.211163 -314.249466)
			(xy 187.162308 -314.255398) (xy 187.113133 -314.253417) (xy 187.064914 -314.243573) (xy 187.018898 -314.226121)
			(xy 186.976277 -314.201514) (xy 186.938156 -314.170389) (xy 186.905521 -314.133552) (xy 186.879218 -314.091956)
			(xy 186.859927 -314.04668) (xy 186.84815 -313.998896) (xy 186.84419 -313.949842) (xy 185.555382 -313.949842)
			(xy 185.554887 -313.974449) (xy 185.546992 -314.023026) (xy 185.531408 -314.069707) (xy 185.508537 -314.113284)
			(xy 185.478972 -314.152628) (xy 185.443479 -314.18672) (xy 185.402976 -314.214676) (xy 185.358514 -314.235774)
			(xy 185.311243 -314.249466) (xy 185.262388 -314.255398) (xy 185.213213 -314.253417) (xy 185.164994 -314.243573)
			(xy 185.118978 -314.226121) (xy 185.076357 -314.201514) (xy 185.038236 -314.170389) (xy 185.005601 -314.133552)
			(xy 184.979298 -314.091956) (xy 184.960007 -314.04668) (xy 184.94823 -313.998896) (xy 184.94427 -313.949842)
			(xy 183.655208 -313.949842) (xy 183.654713 -313.974449) (xy 183.646818 -314.023026) (xy 183.631234 -314.069707)
			(xy 183.608363 -314.113284) (xy 183.578798 -314.152628) (xy 183.543305 -314.18672) (xy 183.502802 -314.214676)
			(xy 183.45834 -314.235774) (xy 183.411069 -314.249466) (xy 183.362214 -314.255398) (xy 183.313039 -314.253417)
			(xy 183.26482 -314.243573) (xy 183.218804 -314.226121) (xy 183.176183 -314.201514) (xy 183.138062 -314.170389)
			(xy 183.105427 -314.133552) (xy 183.079124 -314.091956) (xy 183.059833 -314.04668) (xy 183.048056 -313.998896)
			(xy 183.044096 -313.949842) (xy 166.555166 -313.949842) (xy 166.554671 -313.974449) (xy 166.546776 -314.023026)
			(xy 166.531192 -314.069707) (xy 166.508321 -314.113284) (xy 166.478756 -314.152628) (xy 166.443263 -314.18672)
			(xy 166.40276 -314.214676) (xy 166.358298 -314.235774) (xy 166.311027 -314.249466) (xy 166.262172 -314.255398)
			(xy 166.212997 -314.253417) (xy 166.164778 -314.243573) (xy 166.118762 -314.226121) (xy 166.076141 -314.201514)
			(xy 166.03802 -314.170389) (xy 166.005385 -314.133552) (xy 165.979082 -314.091956) (xy 165.959791 -314.04668)
			(xy 165.948014 -313.998896) (xy 165.944054 -313.949842) (xy 164.655246 -313.949842) (xy 164.654751 -313.974449)
			(xy 164.646856 -314.023026) (xy 164.631272 -314.069707) (xy 164.608401 -314.113284) (xy 164.578836 -314.152628)
			(xy 164.543343 -314.18672) (xy 164.50284 -314.214676) (xy 164.458378 -314.235774) (xy 164.411107 -314.249466)
			(xy 164.362252 -314.255398) (xy 164.313077 -314.253417) (xy 164.264858 -314.243573) (xy 164.218842 -314.226121)
			(xy 164.176221 -314.201514) (xy 164.1381 -314.170389) (xy 164.105465 -314.133552) (xy 164.079162 -314.091956)
			(xy 164.059871 -314.04668) (xy 164.048094 -313.998896) (xy 164.044134 -313.949842) (xy 162.755326 -313.949842)
			(xy 162.754831 -313.974449) (xy 162.746936 -314.023026) (xy 162.731352 -314.069707) (xy 162.708481 -314.113284)
			(xy 162.678916 -314.152628) (xy 162.643423 -314.18672) (xy 162.60292 -314.214676) (xy 162.558458 -314.235774)
			(xy 162.511187 -314.249466) (xy 162.462332 -314.255398) (xy 162.413157 -314.253417) (xy 162.364938 -314.243573)
			(xy 162.318922 -314.226121) (xy 162.276301 -314.201514) (xy 162.23818 -314.170389) (xy 162.205545 -314.133552)
			(xy 162.179242 -314.091956) (xy 162.159951 -314.04668) (xy 162.148174 -313.998896) (xy 162.144214 -313.949842)
			(xy 160.855152 -313.949842) (xy 160.854657 -313.974449) (xy 160.846762 -314.023026) (xy 160.831178 -314.069707)
			(xy 160.808307 -314.113284) (xy 160.778742 -314.152628) (xy 160.743249 -314.18672) (xy 160.702746 -314.214676)
			(xy 160.658284 -314.235774) (xy 160.611013 -314.249466) (xy 160.562158 -314.255398) (xy 160.512983 -314.253417)
			(xy 160.464764 -314.243573) (xy 160.418748 -314.226121) (xy 160.376127 -314.201514) (xy 160.338006 -314.170389)
			(xy 160.305371 -314.133552) (xy 160.279068 -314.091956) (xy 160.259777 -314.04668) (xy 160.248 -313.998896)
			(xy 160.24404 -313.949842) (xy 158.955232 -313.949842) (xy 158.954737 -313.974449) (xy 158.946842 -314.023026)
			(xy 158.931258 -314.069707) (xy 158.908387 -314.113284) (xy 158.878822 -314.152628) (xy 158.843329 -314.18672)
			(xy 158.802826 -314.214676) (xy 158.758364 -314.235774) (xy 158.711093 -314.249466) (xy 158.662238 -314.255398)
			(xy 158.613063 -314.253417) (xy 158.564844 -314.243573) (xy 158.518828 -314.226121) (xy 158.476207 -314.201514)
			(xy 158.438086 -314.170389) (xy 158.405451 -314.133552) (xy 158.379148 -314.091956) (xy 158.359857 -314.04668)
			(xy 158.34808 -313.998896) (xy 158.34412 -313.949842) (xy 157.055312 -313.949842) (xy 157.054817 -313.974449)
			(xy 157.046922 -314.023026) (xy 157.031338 -314.069707) (xy 157.008467 -314.113284) (xy 156.978902 -314.152628)
			(xy 156.943409 -314.18672) (xy 156.902906 -314.214676) (xy 156.858444 -314.235774) (xy 156.811173 -314.249466)
			(xy 156.762318 -314.255398) (xy 156.713143 -314.253417) (xy 156.664924 -314.243573) (xy 156.618908 -314.226121)
			(xy 156.576287 -314.201514) (xy 156.538166 -314.170389) (xy 156.505531 -314.133552) (xy 156.479228 -314.091956)
			(xy 156.459937 -314.04668) (xy 156.44816 -313.998896) (xy 156.4442 -313.949842) (xy 155.155392 -313.949842)
			(xy 155.154897 -313.974449) (xy 155.147002 -314.023026) (xy 155.131418 -314.069707) (xy 155.108547 -314.113284)
			(xy 155.078982 -314.152628) (xy 155.043489 -314.18672) (xy 155.002986 -314.214676) (xy 154.958524 -314.235774)
			(xy 154.911253 -314.249466) (xy 154.862398 -314.255398) (xy 154.813223 -314.253417) (xy 154.765004 -314.243573)
			(xy 154.718988 -314.226121) (xy 154.676367 -314.201514) (xy 154.638246 -314.170389) (xy 154.605611 -314.133552)
			(xy 154.579308 -314.091956) (xy 154.560017 -314.04668) (xy 154.54824 -313.998896) (xy 154.54428 -313.949842)
			(xy 80.855058 -313.949842) (xy 80.854563 -313.974449) (xy 80.846668 -314.023026) (xy 80.831084 -314.069707)
			(xy 80.808213 -314.113284) (xy 80.778648 -314.152628) (xy 80.743155 -314.18672) (xy 80.702652 -314.214676)
			(xy 80.65819 -314.235774) (xy 80.610919 -314.249466) (xy 80.562064 -314.255398) (xy 80.512889 -314.253417)
			(xy 80.46467 -314.243573) (xy 80.418654 -314.226121) (xy 80.376033 -314.201514) (xy 80.337912 -314.170389)
			(xy 80.305277 -314.133552) (xy 80.278974 -314.091956) (xy 80.259683 -314.04668) (xy 80.247906 -313.998896)
			(xy 80.243946 -313.949842) (xy 78.955138 -313.949842) (xy 78.954643 -313.974449) (xy 78.946748 -314.023026)
			(xy 78.931164 -314.069707) (xy 78.908293 -314.113284) (xy 78.878728 -314.152628) (xy 78.843235 -314.18672)
			(xy 78.802732 -314.214676) (xy 78.75827 -314.235774) (xy 78.710999 -314.249466) (xy 78.662144 -314.255398)
			(xy 78.612969 -314.253417) (xy 78.56475 -314.243573) (xy 78.518734 -314.226121) (xy 78.476113 -314.201514)
			(xy 78.437992 -314.170389) (xy 78.405357 -314.133552) (xy 78.379054 -314.091956) (xy 78.359763 -314.04668)
			(xy 78.347986 -313.998896) (xy 78.344026 -313.949842) (xy 77.055218 -313.949842) (xy 77.054723 -313.974449)
			(xy 77.046828 -314.023026) (xy 77.031244 -314.069707) (xy 77.008373 -314.113284) (xy 76.978808 -314.152628)
			(xy 76.943315 -314.18672) (xy 76.902812 -314.214676) (xy 76.85835 -314.235774) (xy 76.811079 -314.249466)
			(xy 76.762224 -314.255398) (xy 76.713049 -314.253417) (xy 76.66483 -314.243573) (xy 76.618814 -314.226121)
			(xy 76.576193 -314.201514) (xy 76.538072 -314.170389) (xy 76.505437 -314.133552) (xy 76.479134 -314.091956)
			(xy 76.459843 -314.04668) (xy 76.448066 -313.998896) (xy 76.444106 -313.949842) (xy 75.155298 -313.949842)
			(xy 75.154803 -313.974449) (xy 75.146908 -314.023026) (xy 75.131324 -314.069707) (xy 75.108453 -314.113284)
			(xy 75.078888 -314.152628) (xy 75.043395 -314.18672) (xy 75.002892 -314.214676) (xy 74.95843 -314.235774)
			(xy 74.911159 -314.249466) (xy 74.862304 -314.255398) (xy 74.813129 -314.253417) (xy 74.76491 -314.243573)
			(xy 74.718894 -314.226121) (xy 74.676273 -314.201514) (xy 74.638152 -314.170389) (xy 74.605517 -314.133552)
			(xy 74.579214 -314.091956) (xy 74.559923 -314.04668) (xy 74.548146 -313.998896) (xy 74.544186 -313.949842)
			(xy 58.055256 -313.949842) (xy 58.054761 -313.974449) (xy 58.046866 -314.023026) (xy 58.031282 -314.069707)
			(xy 58.008411 -314.113284) (xy 57.978846 -314.152628) (xy 57.943353 -314.18672) (xy 57.90285 -314.214676)
			(xy 57.858388 -314.235774) (xy 57.811117 -314.249466) (xy 57.762262 -314.255398) (xy 57.713087 -314.253417)
			(xy 57.664868 -314.243573) (xy 57.618852 -314.226121) (xy 57.576231 -314.201514) (xy 57.53811 -314.170389)
			(xy 57.505475 -314.133552) (xy 57.479172 -314.091956) (xy 57.459881 -314.04668) (xy 57.448104 -313.998896)
			(xy 57.444144 -313.949842) (xy 56.155082 -313.949842) (xy 56.154587 -313.974449) (xy 56.146692 -314.023026)
			(xy 56.131108 -314.069707) (xy 56.108237 -314.113284) (xy 56.078672 -314.152628) (xy 56.043179 -314.18672)
			(xy 56.002676 -314.214676) (xy 55.958214 -314.235774) (xy 55.910943 -314.249466) (xy 55.862088 -314.255398)
			(xy 55.812913 -314.253417) (xy 55.764694 -314.243573) (xy 55.718678 -314.226121) (xy 55.676057 -314.201514)
			(xy 55.637936 -314.170389) (xy 55.605301 -314.133552) (xy 55.578998 -314.091956) (xy 55.559707 -314.04668)
			(xy 55.54793 -313.998896) (xy 55.54397 -313.949842) (xy 54.255162 -313.949842) (xy 54.254667 -313.974449)
			(xy 54.246772 -314.023026) (xy 54.231188 -314.069707) (xy 54.208317 -314.113284) (xy 54.178752 -314.152628)
			(xy 54.143259 -314.18672) (xy 54.102756 -314.214676) (xy 54.058294 -314.235774) (xy 54.011023 -314.249466)
			(xy 53.962168 -314.255398) (xy 53.912993 -314.253417) (xy 53.864774 -314.243573) (xy 53.818758 -314.226121)
			(xy 53.776137 -314.201514) (xy 53.738016 -314.170389) (xy 53.705381 -314.133552) (xy 53.679078 -314.091956)
			(xy 53.659787 -314.04668) (xy 53.64801 -313.998896) (xy 53.64405 -313.949842) (xy 52.355242 -313.949842)
			(xy 52.354747 -313.974449) (xy 52.346852 -314.023026) (xy 52.331268 -314.069707) (xy 52.308397 -314.113284)
			(xy 52.278832 -314.152628) (xy 52.243339 -314.18672) (xy 52.202836 -314.214676) (xy 52.158374 -314.235774)
			(xy 52.111103 -314.249466) (xy 52.062248 -314.255398) (xy 52.013073 -314.253417) (xy 51.964854 -314.243573)
			(xy 51.918838 -314.226121) (xy 51.876217 -314.201514) (xy 51.838096 -314.170389) (xy 51.805461 -314.133552)
			(xy 51.779158 -314.091956) (xy 51.759867 -314.04668) (xy 51.74809 -313.998896) (xy 51.74413 -313.949842)
			(xy 50.455068 -313.949842) (xy 50.454573 -313.974449) (xy 50.446678 -314.023026) (xy 50.431094 -314.069707)
			(xy 50.408223 -314.113284) (xy 50.378658 -314.152628) (xy 50.343165 -314.18672) (xy 50.302662 -314.214676)
			(xy 50.2582 -314.235774) (xy 50.210929 -314.249466) (xy 50.162074 -314.255398) (xy 50.112899 -314.253417)
			(xy 50.06468 -314.243573) (xy 50.018664 -314.226121) (xy 49.976043 -314.201514) (xy 49.937922 -314.170389)
			(xy 49.905287 -314.133552) (xy 49.878984 -314.091956) (xy 49.859693 -314.04668) (xy 49.847916 -313.998896)
			(xy 49.843956 -313.949842) (xy 48.555148 -313.949842) (xy 48.554653 -313.974449) (xy 48.546758 -314.023026)
			(xy 48.531174 -314.069707) (xy 48.508303 -314.113284) (xy 48.478738 -314.152628) (xy 48.443245 -314.18672)
			(xy 48.402742 -314.214676) (xy 48.35828 -314.235774) (xy 48.311009 -314.249466) (xy 48.262154 -314.255398)
			(xy 48.212979 -314.253417) (xy 48.16476 -314.243573) (xy 48.118744 -314.226121) (xy 48.076123 -314.201514)
			(xy 48.038002 -314.170389) (xy 48.005367 -314.133552) (xy 47.979064 -314.091956) (xy 47.959773 -314.04668)
			(xy 47.947996 -313.998896) (xy 47.944036 -313.949842) (xy 46.655228 -313.949842) (xy 46.654733 -313.974449)
			(xy 46.646838 -314.023026) (xy 46.631254 -314.069707) (xy 46.608383 -314.113284) (xy 46.578818 -314.152628)
			(xy 46.543325 -314.18672) (xy 46.502822 -314.214676) (xy 46.45836 -314.235774) (xy 46.411089 -314.249466)
			(xy 46.362234 -314.255398) (xy 46.313059 -314.253417) (xy 46.26484 -314.243573) (xy 46.218824 -314.226121)
			(xy 46.176203 -314.201514) (xy 46.138082 -314.170389) (xy 46.105447 -314.133552) (xy 46.079144 -314.091956)
			(xy 46.059853 -314.04668) (xy 46.048076 -313.998896) (xy 46.044116 -313.949842) (xy 44.755054 -313.949842)
			(xy 44.754559 -313.974449) (xy 44.746664 -314.023026) (xy 44.73108 -314.069707) (xy 44.708209 -314.113284)
			(xy 44.678644 -314.152628) (xy 44.643151 -314.18672) (xy 44.602648 -314.214676) (xy 44.558186 -314.235774)
			(xy 44.510915 -314.249466) (xy 44.46206 -314.255398) (xy 44.412885 -314.253417) (xy 44.364666 -314.243573)
			(xy 44.31865 -314.226121) (xy 44.276029 -314.201514) (xy 44.237908 -314.170389) (xy 44.205273 -314.133552)
			(xy 44.17897 -314.091956) (xy 44.159679 -314.04668) (xy 44.147902 -313.998896) (xy 44.143942 -313.949842)
			(xy 0.508 -313.949842) (xy 0.508 -314.899802) (xy 81.19416 -314.899802) (xy 81.19812 -314.850748)
			(xy 81.209897 -314.802964) (xy 81.229188 -314.757688) (xy 81.255491 -314.716092) (xy 81.288126 -314.679255)
			(xy 81.326247 -314.64813) (xy 81.368868 -314.623523) (xy 81.414884 -314.606071) (xy 81.463103 -314.596227)
			(xy 81.512278 -314.594246) (xy 81.561133 -314.600178) (xy 81.608404 -314.61387) (xy 81.652866 -314.634968)
			(xy 81.693369 -314.662924) (xy 81.728862 -314.697016) (xy 81.758427 -314.73636) (xy 81.781298 -314.779937)
			(xy 81.796882 -314.826618) (xy 81.804777 -314.875195) (xy 81.805272 -314.899802) (xy 82.14412 -314.899802)
			(xy 82.14808 -314.850748) (xy 82.159857 -314.802964) (xy 82.179148 -314.757688) (xy 82.205451 -314.716092)
			(xy 82.238086 -314.679255) (xy 82.276207 -314.64813) (xy 82.318828 -314.623523) (xy 82.364844 -314.606071)
			(xy 82.413063 -314.596227) (xy 82.462238 -314.594246) (xy 82.511093 -314.600178) (xy 82.558364 -314.61387)
			(xy 82.602826 -314.634968) (xy 82.643329 -314.662924) (xy 82.678822 -314.697016) (xy 82.708387 -314.73636)
			(xy 82.731258 -314.779937) (xy 82.746842 -314.826618) (xy 82.754737 -314.875195) (xy 82.755232 -314.899802)
			(xy 152.644106 -314.899802) (xy 152.648066 -314.850748) (xy 152.659843 -314.802964) (xy 152.679134 -314.757688)
			(xy 152.705437 -314.716092) (xy 152.738072 -314.679255) (xy 152.776193 -314.64813) (xy 152.818814 -314.623523)
			(xy 152.86483 -314.606071) (xy 152.913049 -314.596227) (xy 152.962224 -314.594246) (xy 153.011079 -314.600178)
			(xy 153.05835 -314.61387) (xy 153.102812 -314.634968) (xy 153.143315 -314.662924) (xy 153.178808 -314.697016)
			(xy 153.208373 -314.73636) (xy 153.231244 -314.779937) (xy 153.246828 -314.826618) (xy 153.254723 -314.875195)
			(xy 153.255218 -314.899802) (xy 153.594066 -314.899802) (xy 153.598026 -314.850748) (xy 153.609803 -314.802964)
			(xy 153.629094 -314.757688) (xy 153.655397 -314.716092) (xy 153.688032 -314.679255) (xy 153.726153 -314.64813)
			(xy 153.768774 -314.623523) (xy 153.81479 -314.606071) (xy 153.863009 -314.596227) (xy 153.912184 -314.594246)
			(xy 153.961039 -314.600178) (xy 154.00831 -314.61387) (xy 154.052772 -314.634968) (xy 154.093275 -314.662924)
			(xy 154.128768 -314.697016) (xy 154.158333 -314.73636) (xy 154.181204 -314.779937) (xy 154.196788 -314.826618)
			(xy 154.204683 -314.875195) (xy 154.205178 -314.899802) (xy 313.394102 -314.899802) (xy 313.398062 -314.850748)
			(xy 313.409839 -314.802964) (xy 313.42913 -314.757688) (xy 313.455433 -314.716092) (xy 313.488068 -314.679255)
			(xy 313.526189 -314.64813) (xy 313.56881 -314.623523) (xy 313.614826 -314.606071) (xy 313.663045 -314.596227)
			(xy 313.71222 -314.594246) (xy 313.761075 -314.600178) (xy 313.808346 -314.61387) (xy 313.852808 -314.634968)
			(xy 313.893311 -314.662924) (xy 313.928804 -314.697016) (xy 313.958369 -314.73636) (xy 313.98124 -314.779937)
			(xy 313.996824 -314.826618) (xy 314.004719 -314.875195) (xy 314.005214 -314.899802) (xy 314.344062 -314.899802)
			(xy 314.348022 -314.850748) (xy 314.359799 -314.802964) (xy 314.37909 -314.757688) (xy 314.405393 -314.716092)
			(xy 314.438028 -314.679255) (xy 314.476149 -314.64813) (xy 314.51877 -314.623523) (xy 314.564786 -314.606071)
			(xy 314.613005 -314.596227) (xy 314.66218 -314.594246) (xy 314.711035 -314.600178) (xy 314.758306 -314.61387)
			(xy 314.802768 -314.634968) (xy 314.843271 -314.662924) (xy 314.878764 -314.697016) (xy 314.908329 -314.73636)
			(xy 314.9312 -314.779937) (xy 314.946784 -314.826618) (xy 314.954679 -314.875195) (xy 314.955174 -314.899802)
			(xy 384.844048 -314.899802) (xy 384.848008 -314.850748) (xy 384.859785 -314.802964) (xy 384.879076 -314.757688)
			(xy 384.905379 -314.716092) (xy 384.938014 -314.679255) (xy 384.976135 -314.64813) (xy 385.018756 -314.623523)
			(xy 385.064772 -314.606071) (xy 385.112991 -314.596227) (xy 385.162166 -314.594246) (xy 385.211021 -314.600178)
			(xy 385.258292 -314.61387) (xy 385.302754 -314.634968) (xy 385.343257 -314.662924) (xy 385.37875 -314.697016)
			(xy 385.408315 -314.73636) (xy 385.431186 -314.779937) (xy 385.44677 -314.826618) (xy 385.454665 -314.875195)
			(xy 385.45516 -314.899802) (xy 385.794008 -314.899802) (xy 385.797968 -314.850748) (xy 385.809745 -314.802964)
			(xy 385.829036 -314.757688) (xy 385.855339 -314.716092) (xy 385.887974 -314.679255) (xy 385.926095 -314.64813)
			(xy 385.968716 -314.623523) (xy 386.014732 -314.606071) (xy 386.062951 -314.596227) (xy 386.112126 -314.594246)
			(xy 386.160981 -314.600178) (xy 386.208252 -314.61387) (xy 386.252714 -314.634968) (xy 386.293217 -314.662924)
			(xy 386.32871 -314.697016) (xy 386.358275 -314.73636) (xy 386.381146 -314.779937) (xy 386.39673 -314.826618)
			(xy 386.404625 -314.875195) (xy 386.40512 -314.899802) (xy 386.404625 -314.924409) (xy 386.39673 -314.972986)
			(xy 386.381146 -315.019667) (xy 386.358275 -315.063244) (xy 386.32871 -315.102588) (xy 386.293217 -315.13668)
			(xy 386.252714 -315.164636) (xy 386.208252 -315.185734) (xy 386.160981 -315.199426) (xy 386.112126 -315.205358)
			(xy 386.062951 -315.203377) (xy 386.014732 -315.193533) (xy 385.968716 -315.176081) (xy 385.926095 -315.151474)
			(xy 385.887974 -315.120349) (xy 385.855339 -315.083512) (xy 385.829036 -315.041916) (xy 385.809745 -314.99664)
			(xy 385.797968 -314.948856) (xy 385.794008 -314.899802) (xy 385.45516 -314.899802) (xy 385.454665 -314.924409)
			(xy 385.44677 -314.972986) (xy 385.431186 -315.019667) (xy 385.408315 -315.063244) (xy 385.37875 -315.102588)
			(xy 385.343257 -315.13668) (xy 385.302754 -315.164636) (xy 385.258292 -315.185734) (xy 385.211021 -315.199426)
			(xy 385.162166 -315.205358) (xy 385.112991 -315.203377) (xy 385.064772 -315.193533) (xy 385.018756 -315.176081)
			(xy 384.976135 -315.151474) (xy 384.938014 -315.120349) (xy 384.905379 -315.083512) (xy 384.879076 -315.041916)
			(xy 384.859785 -314.99664) (xy 384.848008 -314.948856) (xy 384.844048 -314.899802) (xy 314.955174 -314.899802)
			(xy 314.954679 -314.924409) (xy 314.946784 -314.972986) (xy 314.9312 -315.019667) (xy 314.908329 -315.063244)
			(xy 314.878764 -315.102588) (xy 314.843271 -315.13668) (xy 314.802768 -315.164636) (xy 314.758306 -315.185734)
			(xy 314.711035 -315.199426) (xy 314.66218 -315.205358) (xy 314.613005 -315.203377) (xy 314.564786 -315.193533)
			(xy 314.51877 -315.176081) (xy 314.476149 -315.151474) (xy 314.438028 -315.120349) (xy 314.405393 -315.083512)
			(xy 314.37909 -315.041916) (xy 314.359799 -314.99664) (xy 314.348022 -314.948856) (xy 314.344062 -314.899802)
			(xy 314.005214 -314.899802) (xy 314.004719 -314.924409) (xy 313.996824 -314.972986) (xy 313.98124 -315.019667)
			(xy 313.958369 -315.063244) (xy 313.928804 -315.102588) (xy 313.893311 -315.13668) (xy 313.852808 -315.164636)
			(xy 313.808346 -315.185734) (xy 313.761075 -315.199426) (xy 313.71222 -315.205358) (xy 313.663045 -315.203377)
			(xy 313.614826 -315.193533) (xy 313.56881 -315.176081) (xy 313.526189 -315.151474) (xy 313.488068 -315.120349)
			(xy 313.455433 -315.083512) (xy 313.42913 -315.041916) (xy 313.409839 -314.99664) (xy 313.398062 -314.948856)
			(xy 313.394102 -314.899802) (xy 154.205178 -314.899802) (xy 154.204683 -314.924409) (xy 154.196788 -314.972986)
			(xy 154.181204 -315.019667) (xy 154.158333 -315.063244) (xy 154.128768 -315.102588) (xy 154.093275 -315.13668)
			(xy 154.052772 -315.164636) (xy 154.00831 -315.185734) (xy 153.961039 -315.199426) (xy 153.912184 -315.205358)
			(xy 153.863009 -315.203377) (xy 153.81479 -315.193533) (xy 153.768774 -315.176081) (xy 153.726153 -315.151474)
			(xy 153.688032 -315.120349) (xy 153.655397 -315.083512) (xy 153.629094 -315.041916) (xy 153.609803 -314.99664)
			(xy 153.598026 -314.948856) (xy 153.594066 -314.899802) (xy 153.255218 -314.899802) (xy 153.254723 -314.924409)
			(xy 153.246828 -314.972986) (xy 153.231244 -315.019667) (xy 153.208373 -315.063244) (xy 153.178808 -315.102588)
			(xy 153.143315 -315.13668) (xy 153.102812 -315.164636) (xy 153.05835 -315.185734) (xy 153.011079 -315.199426)
			(xy 152.962224 -315.205358) (xy 152.913049 -315.203377) (xy 152.86483 -315.193533) (xy 152.818814 -315.176081)
			(xy 152.776193 -315.151474) (xy 152.738072 -315.120349) (xy 152.705437 -315.083512) (xy 152.679134 -315.041916)
			(xy 152.659843 -314.99664) (xy 152.648066 -314.948856) (xy 152.644106 -314.899802) (xy 82.755232 -314.899802)
			(xy 82.754737 -314.924409) (xy 82.746842 -314.972986) (xy 82.731258 -315.019667) (xy 82.708387 -315.063244)
			(xy 82.678822 -315.102588) (xy 82.643329 -315.13668) (xy 82.602826 -315.164636) (xy 82.558364 -315.185734)
			(xy 82.511093 -315.199426) (xy 82.462238 -315.205358) (xy 82.413063 -315.203377) (xy 82.364844 -315.193533)
			(xy 82.318828 -315.176081) (xy 82.276207 -315.151474) (xy 82.238086 -315.120349) (xy 82.205451 -315.083512)
			(xy 82.179148 -315.041916) (xy 82.159857 -314.99664) (xy 82.14808 -314.948856) (xy 82.14412 -314.899802)
			(xy 81.805272 -314.899802) (xy 81.804777 -314.924409) (xy 81.796882 -314.972986) (xy 81.781298 -315.019667)
			(xy 81.758427 -315.063244) (xy 81.728862 -315.102588) (xy 81.693369 -315.13668) (xy 81.652866 -315.164636)
			(xy 81.608404 -315.185734) (xy 81.561133 -315.199426) (xy 81.512278 -315.205358) (xy 81.463103 -315.203377)
			(xy 81.414884 -315.193533) (xy 81.368868 -315.176081) (xy 81.326247 -315.151474) (xy 81.288126 -315.120349)
			(xy 81.255491 -315.083512) (xy 81.229188 -315.041916) (xy 81.209897 -314.99664) (xy 81.19812 -314.948856)
			(xy 81.19416 -314.899802) (xy 0.508 -314.899802) (xy 0.508 -315.849762) (xy 73.593972 -315.849762)
			(xy 73.597932 -315.800708) (xy 73.609709 -315.752924) (xy 73.629 -315.707648) (xy 73.655303 -315.666052)
			(xy 73.687938 -315.629215) (xy 73.726059 -315.59809) (xy 73.76868 -315.573483) (xy 73.814696 -315.556031)
			(xy 73.862915 -315.546187) (xy 73.91209 -315.544206) (xy 73.960945 -315.550138) (xy 74.008216 -315.56383)
			(xy 74.052678 -315.584928) (xy 74.093181 -315.612884) (xy 74.128674 -315.646976) (xy 74.158239 -315.68632)
			(xy 74.18111 -315.729897) (xy 74.196694 -315.776578) (xy 74.204589 -315.825155) (xy 74.205084 -315.849762)
			(xy 75.494146 -315.849762) (xy 75.498106 -315.800708) (xy 75.509883 -315.752924) (xy 75.529174 -315.707648)
			(xy 75.555477 -315.666052) (xy 75.588112 -315.629215) (xy 75.626233 -315.59809) (xy 75.668854 -315.573483)
			(xy 75.71487 -315.556031) (xy 75.763089 -315.546187) (xy 75.812264 -315.544206) (xy 75.861119 -315.550138)
			(xy 75.90839 -315.56383) (xy 75.952852 -315.584928) (xy 75.993355 -315.612884) (xy 76.028848 -315.646976)
			(xy 76.058413 -315.68632) (xy 76.081284 -315.729897) (xy 76.096868 -315.776578) (xy 76.104763 -315.825155)
			(xy 76.105258 -315.849762) (xy 77.394066 -315.849762) (xy 77.398026 -315.800708) (xy 77.409803 -315.752924)
			(xy 77.429094 -315.707648) (xy 77.455397 -315.666052) (xy 77.488032 -315.629215) (xy 77.526153 -315.59809)
			(xy 77.568774 -315.573483) (xy 77.61479 -315.556031) (xy 77.663009 -315.546187) (xy 77.712184 -315.544206)
			(xy 77.761039 -315.550138) (xy 77.80831 -315.56383) (xy 77.852772 -315.584928) (xy 77.893275 -315.612884)
			(xy 77.928768 -315.646976) (xy 77.958333 -315.68632) (xy 77.981204 -315.729897) (xy 77.996788 -315.776578)
			(xy 78.004683 -315.825155) (xy 78.005178 -315.849762) (xy 79.293986 -315.849762) (xy 79.297946 -315.800708)
			(xy 79.309723 -315.752924) (xy 79.329014 -315.707648) (xy 79.355317 -315.666052) (xy 79.387952 -315.629215)
			(xy 79.426073 -315.59809) (xy 79.468694 -315.573483) (xy 79.51471 -315.556031) (xy 79.562929 -315.546187)
			(xy 79.612104 -315.544206) (xy 79.660959 -315.550138) (xy 79.70823 -315.56383) (xy 79.752692 -315.584928)
			(xy 79.793195 -315.612884) (xy 79.828688 -315.646976) (xy 79.858253 -315.68632) (xy 79.881124 -315.729897)
			(xy 79.896708 -315.776578) (xy 79.904603 -315.825155) (xy 79.905098 -315.849762) (xy 159.29408 -315.849762)
			(xy 159.29804 -315.800708) (xy 159.309817 -315.752924) (xy 159.329108 -315.707648) (xy 159.355411 -315.666052)
			(xy 159.388046 -315.629215) (xy 159.426167 -315.59809) (xy 159.468788 -315.573483) (xy 159.514804 -315.556031)
			(xy 159.563023 -315.546187) (xy 159.612198 -315.544206) (xy 159.661053 -315.550138) (xy 159.708324 -315.56383)
			(xy 159.752786 -315.584928) (xy 159.793289 -315.612884) (xy 159.828782 -315.646976) (xy 159.858347 -315.68632)
			(xy 159.881218 -315.729897) (xy 159.896802 -315.776578) (xy 159.904697 -315.825155) (xy 159.905192 -315.849762)
			(xy 161.194254 -315.849762) (xy 161.198214 -315.800708) (xy 161.209991 -315.752924) (xy 161.229282 -315.707648)
			(xy 161.255585 -315.666052) (xy 161.28822 -315.629215) (xy 161.326341 -315.59809) (xy 161.368962 -315.573483)
			(xy 161.414978 -315.556031) (xy 161.463197 -315.546187) (xy 161.512372 -315.544206) (xy 161.561227 -315.550138)
			(xy 161.608498 -315.56383) (xy 161.65296 -315.584928) (xy 161.693463 -315.612884) (xy 161.728956 -315.646976)
			(xy 161.758521 -315.68632) (xy 161.781392 -315.729897) (xy 161.796976 -315.776578) (xy 161.804871 -315.825155)
			(xy 161.805366 -315.849762) (xy 163.094174 -315.849762) (xy 163.098134 -315.800708) (xy 163.109911 -315.752924)
			(xy 163.129202 -315.707648) (xy 163.155505 -315.666052) (xy 163.18814 -315.629215) (xy 163.226261 -315.59809)
			(xy 163.268882 -315.573483) (xy 163.314898 -315.556031) (xy 163.363117 -315.546187) (xy 163.412292 -315.544206)
			(xy 163.461147 -315.550138) (xy 163.508418 -315.56383) (xy 163.55288 -315.584928) (xy 163.593383 -315.612884)
			(xy 163.628876 -315.646976) (xy 163.658441 -315.68632) (xy 163.681312 -315.729897) (xy 163.696896 -315.776578)
			(xy 163.704791 -315.825155) (xy 163.705286 -315.849762) (xy 164.994094 -315.849762) (xy 164.998054 -315.800708)
			(xy 165.009831 -315.752924) (xy 165.029122 -315.707648) (xy 165.055425 -315.666052) (xy 165.08806 -315.629215)
			(xy 165.126181 -315.59809) (xy 165.168802 -315.573483) (xy 165.214818 -315.556031) (xy 165.263037 -315.546187)
			(xy 165.312212 -315.544206) (xy 165.361067 -315.550138) (xy 165.408338 -315.56383) (xy 165.4528 -315.584928)
			(xy 165.493303 -315.612884) (xy 165.528796 -315.646976) (xy 165.558361 -315.68632) (xy 165.581232 -315.729897)
			(xy 165.596816 -315.776578) (xy 165.604711 -315.825155) (xy 165.605206 -315.849762) (xy 182.094136 -315.849762)
			(xy 182.098096 -315.800708) (xy 182.109873 -315.752924) (xy 182.129164 -315.707648) (xy 182.155467 -315.666052)
			(xy 182.188102 -315.629215) (xy 182.226223 -315.59809) (xy 182.268844 -315.573483) (xy 182.31486 -315.556031)
			(xy 182.363079 -315.546187) (xy 182.412254 -315.544206) (xy 182.461109 -315.550138) (xy 182.50838 -315.56383)
			(xy 182.552842 -315.584928) (xy 182.593345 -315.612884) (xy 182.628838 -315.646976) (xy 182.658403 -315.68632)
			(xy 182.681274 -315.729897) (xy 182.696858 -315.776578) (xy 182.704753 -315.825155) (xy 182.705248 -315.849762)
			(xy 183.994056 -315.849762) (xy 183.998016 -315.800708) (xy 184.009793 -315.752924) (xy 184.029084 -315.707648)
			(xy 184.055387 -315.666052) (xy 184.088022 -315.629215) (xy 184.126143 -315.59809) (xy 184.168764 -315.573483)
			(xy 184.21478 -315.556031) (xy 184.262999 -315.546187) (xy 184.312174 -315.544206) (xy 184.361029 -315.550138)
			(xy 184.4083 -315.56383) (xy 184.452762 -315.584928) (xy 184.493265 -315.612884) (xy 184.528758 -315.646976)
			(xy 184.558323 -315.68632) (xy 184.581194 -315.729897) (xy 184.596778 -315.776578) (xy 184.604673 -315.825155)
			(xy 184.605168 -315.849762) (xy 185.89423 -315.849762) (xy 185.89819 -315.800708) (xy 185.909967 -315.752924)
			(xy 185.929258 -315.707648) (xy 185.955561 -315.666052) (xy 185.988196 -315.629215) (xy 186.026317 -315.59809)
			(xy 186.068938 -315.573483) (xy 186.114954 -315.556031) (xy 186.163173 -315.546187) (xy 186.212348 -315.544206)
			(xy 186.261203 -315.550138) (xy 186.308474 -315.56383) (xy 186.352936 -315.584928) (xy 186.393439 -315.612884)
			(xy 186.428932 -315.646976) (xy 186.458497 -315.68632) (xy 186.481368 -315.729897) (xy 186.496952 -315.776578)
			(xy 186.504847 -315.825155) (xy 186.505342 -315.849762) (xy 187.79415 -315.849762) (xy 187.79811 -315.800708)
			(xy 187.809887 -315.752924) (xy 187.829178 -315.707648) (xy 187.855481 -315.666052) (xy 187.888116 -315.629215)
			(xy 187.926237 -315.59809) (xy 187.968858 -315.573483) (xy 188.014874 -315.556031) (xy 188.063093 -315.546187)
			(xy 188.112268 -315.544206) (xy 188.161123 -315.550138) (xy 188.208394 -315.56383) (xy 188.252856 -315.584928)
			(xy 188.293359 -315.612884) (xy 188.328852 -315.646976) (xy 188.358417 -315.68632) (xy 188.381288 -315.729897)
			(xy 188.396872 -315.776578) (xy 188.404767 -315.825155) (xy 188.405262 -315.849762) (xy 305.793914 -315.849762)
			(xy 305.797874 -315.800708) (xy 305.809651 -315.752924) (xy 305.828942 -315.707648) (xy 305.855245 -315.666052)
			(xy 305.88788 -315.629215) (xy 305.926001 -315.59809) (xy 305.968622 -315.573483) (xy 306.014638 -315.556031)
			(xy 306.062857 -315.546187) (xy 306.112032 -315.544206) (xy 306.160887 -315.550138) (xy 306.208158 -315.56383)
			(xy 306.25262 -315.584928) (xy 306.293123 -315.612884) (xy 306.328616 -315.646976) (xy 306.358181 -315.68632)
			(xy 306.381052 -315.729897) (xy 306.396636 -315.776578) (xy 306.404531 -315.825155) (xy 306.405026 -315.849762)
			(xy 307.694088 -315.849762) (xy 307.698048 -315.800708) (xy 307.709825 -315.752924) (xy 307.729116 -315.707648)
			(xy 307.755419 -315.666052) (xy 307.788054 -315.629215) (xy 307.826175 -315.59809) (xy 307.868796 -315.573483)
			(xy 307.914812 -315.556031) (xy 307.963031 -315.546187) (xy 308.012206 -315.544206) (xy 308.061061 -315.550138)
			(xy 308.108332 -315.56383) (xy 308.152794 -315.584928) (xy 308.193297 -315.612884) (xy 308.22879 -315.646976)
			(xy 308.258355 -315.68632) (xy 308.281226 -315.729897) (xy 308.29681 -315.776578) (xy 308.304705 -315.825155)
			(xy 308.3052 -315.849762) (xy 309.594008 -315.849762) (xy 309.597968 -315.800708) (xy 309.609745 -315.752924)
			(xy 309.629036 -315.707648) (xy 309.655339 -315.666052) (xy 309.687974 -315.629215) (xy 309.726095 -315.59809)
			(xy 309.768716 -315.573483) (xy 309.814732 -315.556031) (xy 309.862951 -315.546187) (xy 309.912126 -315.544206)
			(xy 309.960981 -315.550138) (xy 310.008252 -315.56383) (xy 310.052714 -315.584928) (xy 310.093217 -315.612884)
			(xy 310.12871 -315.646976) (xy 310.158275 -315.68632) (xy 310.181146 -315.729897) (xy 310.19673 -315.776578)
			(xy 310.204625 -315.825155) (xy 310.20512 -315.849762) (xy 311.493928 -315.849762) (xy 311.497888 -315.800708)
			(xy 311.509665 -315.752924) (xy 311.528956 -315.707648) (xy 311.555259 -315.666052) (xy 311.587894 -315.629215)
			(xy 311.626015 -315.59809) (xy 311.668636 -315.573483) (xy 311.714652 -315.556031) (xy 311.762871 -315.546187)
			(xy 311.812046 -315.544206) (xy 311.860901 -315.550138) (xy 311.908172 -315.56383) (xy 311.952634 -315.584928)
			(xy 311.993137 -315.612884) (xy 312.02863 -315.646976) (xy 312.058195 -315.68632) (xy 312.081066 -315.729897)
			(xy 312.09665 -315.776578) (xy 312.104545 -315.825155) (xy 312.10504 -315.849762) (xy 391.494022 -315.849762)
			(xy 391.497982 -315.800708) (xy 391.509759 -315.752924) (xy 391.52905 -315.707648) (xy 391.555353 -315.666052)
			(xy 391.587988 -315.629215) (xy 391.626109 -315.59809) (xy 391.66873 -315.573483) (xy 391.714746 -315.556031)
			(xy 391.762965 -315.546187) (xy 391.81214 -315.544206) (xy 391.860995 -315.550138) (xy 391.908266 -315.56383)
			(xy 391.952728 -315.584928) (xy 391.993231 -315.612884) (xy 392.028724 -315.646976) (xy 392.058289 -315.68632)
			(xy 392.08116 -315.729897) (xy 392.096744 -315.776578) (xy 392.104639 -315.825155) (xy 392.105134 -315.849762)
			(xy 393.394196 -315.849762) (xy 393.398156 -315.800708) (xy 393.409933 -315.752924) (xy 393.429224 -315.707648)
			(xy 393.455527 -315.666052) (xy 393.488162 -315.629215) (xy 393.526283 -315.59809) (xy 393.568904 -315.573483)
			(xy 393.61492 -315.556031) (xy 393.663139 -315.546187) (xy 393.712314 -315.544206) (xy 393.761169 -315.550138)
			(xy 393.80844 -315.56383) (xy 393.852902 -315.584928) (xy 393.893405 -315.612884) (xy 393.928898 -315.646976)
			(xy 393.958463 -315.68632) (xy 393.981334 -315.729897) (xy 393.996918 -315.776578) (xy 394.004813 -315.825155)
			(xy 394.005308 -315.849762) (xy 395.294116 -315.849762) (xy 395.298076 -315.800708) (xy 395.309853 -315.752924)
			(xy 395.329144 -315.707648) (xy 395.355447 -315.666052) (xy 395.388082 -315.629215) (xy 395.426203 -315.59809)
			(xy 395.468824 -315.573483) (xy 395.51484 -315.556031) (xy 395.563059 -315.546187) (xy 395.612234 -315.544206)
			(xy 395.661089 -315.550138) (xy 395.70836 -315.56383) (xy 395.752822 -315.584928) (xy 395.793325 -315.612884)
			(xy 395.828818 -315.646976) (xy 395.858383 -315.68632) (xy 395.881254 -315.729897) (xy 395.896838 -315.776578)
			(xy 395.904733 -315.825155) (xy 395.905228 -315.849762) (xy 397.194036 -315.849762) (xy 397.197996 -315.800708)
			(xy 397.209773 -315.752924) (xy 397.229064 -315.707648) (xy 397.255367 -315.666052) (xy 397.288002 -315.629215)
			(xy 397.326123 -315.59809) (xy 397.368744 -315.573483) (xy 397.41476 -315.556031) (xy 397.462979 -315.546187)
			(xy 397.512154 -315.544206) (xy 397.561009 -315.550138) (xy 397.60828 -315.56383) (xy 397.652742 -315.584928)
			(xy 397.693245 -315.612884) (xy 397.728738 -315.646976) (xy 397.758303 -315.68632) (xy 397.781174 -315.729897)
			(xy 397.796758 -315.776578) (xy 397.804653 -315.825155) (xy 397.805148 -315.849762) (xy 414.294078 -315.849762)
			(xy 414.298038 -315.800708) (xy 414.309815 -315.752924) (xy 414.329106 -315.707648) (xy 414.355409 -315.666052)
			(xy 414.388044 -315.629215) (xy 414.426165 -315.59809) (xy 414.468786 -315.573483) (xy 414.514802 -315.556031)
			(xy 414.563021 -315.546187) (xy 414.612196 -315.544206) (xy 414.661051 -315.550138) (xy 414.708322 -315.56383)
			(xy 414.752784 -315.584928) (xy 414.793287 -315.612884) (xy 414.82878 -315.646976) (xy 414.858345 -315.68632)
			(xy 414.881216 -315.729897) (xy 414.8968 -315.776578) (xy 414.904695 -315.825155) (xy 414.90519 -315.849762)
			(xy 416.193998 -315.849762) (xy 416.197958 -315.800708) (xy 416.209735 -315.752924) (xy 416.229026 -315.707648)
			(xy 416.255329 -315.666052) (xy 416.287964 -315.629215) (xy 416.326085 -315.59809) (xy 416.368706 -315.573483)
			(xy 416.414722 -315.556031) (xy 416.462941 -315.546187) (xy 416.512116 -315.544206) (xy 416.560971 -315.550138)
			(xy 416.608242 -315.56383) (xy 416.652704 -315.584928) (xy 416.693207 -315.612884) (xy 416.7287 -315.646976)
			(xy 416.758265 -315.68632) (xy 416.781136 -315.729897) (xy 416.79672 -315.776578) (xy 416.804615 -315.825155)
			(xy 416.80511 -315.849762) (xy 418.094172 -315.849762) (xy 418.098132 -315.800708) (xy 418.109909 -315.752924)
			(xy 418.1292 -315.707648) (xy 418.155503 -315.666052) (xy 418.188138 -315.629215) (xy 418.226259 -315.59809)
			(xy 418.26888 -315.573483) (xy 418.314896 -315.556031) (xy 418.363115 -315.546187) (xy 418.41229 -315.544206)
			(xy 418.461145 -315.550138) (xy 418.508416 -315.56383) (xy 418.552878 -315.584928) (xy 418.593381 -315.612884)
			(xy 418.628874 -315.646976) (xy 418.658439 -315.68632) (xy 418.68131 -315.729897) (xy 418.696894 -315.776578)
			(xy 418.704789 -315.825155) (xy 418.705284 -315.849762) (xy 419.994092 -315.849762) (xy 419.998052 -315.800708)
			(xy 420.009829 -315.752924) (xy 420.02912 -315.707648) (xy 420.055423 -315.666052) (xy 420.088058 -315.629215)
			(xy 420.126179 -315.59809) (xy 420.1688 -315.573483) (xy 420.214816 -315.556031) (xy 420.263035 -315.546187)
			(xy 420.31221 -315.544206) (xy 420.361065 -315.550138) (xy 420.408336 -315.56383) (xy 420.452798 -315.584928)
			(xy 420.493301 -315.612884) (xy 420.528794 -315.646976) (xy 420.558359 -315.68632) (xy 420.58123 -315.729897)
			(xy 420.596814 -315.776578) (xy 420.604709 -315.825155) (xy 420.605204 -315.849762) (xy 420.604709 -315.874369)
			(xy 420.596814 -315.922946) (xy 420.58123 -315.969627) (xy 420.558359 -316.013204) (xy 420.528794 -316.052548)
			(xy 420.493301 -316.08664) (xy 420.452798 -316.114596) (xy 420.408336 -316.135694) (xy 420.361065 -316.149386)
			(xy 420.31221 -316.155318) (xy 420.263035 -316.153337) (xy 420.214816 -316.143493) (xy 420.1688 -316.126041)
			(xy 420.126179 -316.101434) (xy 420.088058 -316.070309) (xy 420.055423 -316.033472) (xy 420.02912 -315.991876)
			(xy 420.009829 -315.9466) (xy 419.998052 -315.898816) (xy 419.994092 -315.849762) (xy 418.705284 -315.849762)
			(xy 418.704789 -315.874369) (xy 418.696894 -315.922946) (xy 418.68131 -315.969627) (xy 418.658439 -316.013204)
			(xy 418.628874 -316.052548) (xy 418.593381 -316.08664) (xy 418.552878 -316.114596) (xy 418.508416 -316.135694)
			(xy 418.461145 -316.149386) (xy 418.41229 -316.155318) (xy 418.363115 -316.153337) (xy 418.314896 -316.143493)
			(xy 418.26888 -316.126041) (xy 418.226259 -316.101434) (xy 418.188138 -316.070309) (xy 418.155503 -316.033472)
			(xy 418.1292 -315.991876) (xy 418.109909 -315.9466) (xy 418.098132 -315.898816) (xy 418.094172 -315.849762)
			(xy 416.80511 -315.849762) (xy 416.804615 -315.874369) (xy 416.79672 -315.922946) (xy 416.781136 -315.969627)
			(xy 416.758265 -316.013204) (xy 416.7287 -316.052548) (xy 416.693207 -316.08664) (xy 416.652704 -316.114596)
			(xy 416.608242 -316.135694) (xy 416.560971 -316.149386) (xy 416.512116 -316.155318) (xy 416.462941 -316.153337)
			(xy 416.414722 -316.143493) (xy 416.368706 -316.126041) (xy 416.326085 -316.101434) (xy 416.287964 -316.070309)
			(xy 416.255329 -316.033472) (xy 416.229026 -315.991876) (xy 416.209735 -315.9466) (xy 416.197958 -315.898816)
			(xy 416.193998 -315.849762) (xy 414.90519 -315.849762) (xy 414.904695 -315.874369) (xy 414.8968 -315.922946)
			(xy 414.881216 -315.969627) (xy 414.858345 -316.013204) (xy 414.82878 -316.052548) (xy 414.793287 -316.08664)
			(xy 414.752784 -316.114596) (xy 414.708322 -316.135694) (xy 414.661051 -316.149386) (xy 414.612196 -316.155318)
			(xy 414.563021 -316.153337) (xy 414.514802 -316.143493) (xy 414.468786 -316.126041) (xy 414.426165 -316.101434)
			(xy 414.388044 -316.070309) (xy 414.355409 -316.033472) (xy 414.329106 -315.991876) (xy 414.309815 -315.9466)
			(xy 414.298038 -315.898816) (xy 414.294078 -315.849762) (xy 397.805148 -315.849762) (xy 397.804653 -315.874369)
			(xy 397.796758 -315.922946) (xy 397.781174 -315.969627) (xy 397.758303 -316.013204) (xy 397.728738 -316.052548)
			(xy 397.693245 -316.08664) (xy 397.652742 -316.114596) (xy 397.60828 -316.135694) (xy 397.561009 -316.149386)
			(xy 397.512154 -316.155318) (xy 397.462979 -316.153337) (xy 397.41476 -316.143493) (xy 397.368744 -316.126041)
			(xy 397.326123 -316.101434) (xy 397.288002 -316.070309) (xy 397.255367 -316.033472) (xy 397.229064 -315.991876)
			(xy 397.209773 -315.9466) (xy 397.197996 -315.898816) (xy 397.194036 -315.849762) (xy 395.905228 -315.849762)
			(xy 395.904733 -315.874369) (xy 395.896838 -315.922946) (xy 395.881254 -315.969627) (xy 395.858383 -316.013204)
			(xy 395.828818 -316.052548) (xy 395.793325 -316.08664) (xy 395.752822 -316.114596) (xy 395.70836 -316.135694)
			(xy 395.661089 -316.149386) (xy 395.612234 -316.155318) (xy 395.563059 -316.153337) (xy 395.51484 -316.143493)
			(xy 395.468824 -316.126041) (xy 395.426203 -316.101434) (xy 395.388082 -316.070309) (xy 395.355447 -316.033472)
			(xy 395.329144 -315.991876) (xy 395.309853 -315.9466) (xy 395.298076 -315.898816) (xy 395.294116 -315.849762)
			(xy 394.005308 -315.849762) (xy 394.004813 -315.874369) (xy 393.996918 -315.922946) (xy 393.981334 -315.969627)
			(xy 393.958463 -316.013204) (xy 393.928898 -316.052548) (xy 393.893405 -316.08664) (xy 393.852902 -316.114596)
			(xy 393.80844 -316.135694) (xy 393.761169 -316.149386) (xy 393.712314 -316.155318) (xy 393.663139 -316.153337)
			(xy 393.61492 -316.143493) (xy 393.568904 -316.126041) (xy 393.526283 -316.101434) (xy 393.488162 -316.070309)
			(xy 393.455527 -316.033472) (xy 393.429224 -315.991876) (xy 393.409933 -315.9466) (xy 393.398156 -315.898816)
			(xy 393.394196 -315.849762) (xy 392.105134 -315.849762) (xy 392.104639 -315.874369) (xy 392.096744 -315.922946)
			(xy 392.08116 -315.969627) (xy 392.058289 -316.013204) (xy 392.028724 -316.052548) (xy 391.993231 -316.08664)
			(xy 391.952728 -316.114596) (xy 391.908266 -316.135694) (xy 391.860995 -316.149386) (xy 391.81214 -316.155318)
			(xy 391.762965 -316.153337) (xy 391.714746 -316.143493) (xy 391.66873 -316.126041) (xy 391.626109 -316.101434)
			(xy 391.587988 -316.070309) (xy 391.555353 -316.033472) (xy 391.52905 -315.991876) (xy 391.509759 -315.9466)
			(xy 391.497982 -315.898816) (xy 391.494022 -315.849762) (xy 312.10504 -315.849762) (xy 312.104545 -315.874369)
			(xy 312.09665 -315.922946) (xy 312.081066 -315.969627) (xy 312.058195 -316.013204) (xy 312.02863 -316.052548)
			(xy 311.993137 -316.08664) (xy 311.952634 -316.114596) (xy 311.908172 -316.135694) (xy 311.860901 -316.149386)
			(xy 311.812046 -316.155318) (xy 311.762871 -316.153337) (xy 311.714652 -316.143493) (xy 311.668636 -316.126041)
			(xy 311.626015 -316.101434) (xy 311.587894 -316.070309) (xy 311.555259 -316.033472) (xy 311.528956 -315.991876)
			(xy 311.509665 -315.9466) (xy 311.497888 -315.898816) (xy 311.493928 -315.849762) (xy 310.20512 -315.849762)
			(xy 310.204625 -315.874369) (xy 310.19673 -315.922946) (xy 310.181146 -315.969627) (xy 310.158275 -316.013204)
			(xy 310.12871 -316.052548) (xy 310.093217 -316.08664) (xy 310.052714 -316.114596) (xy 310.008252 -316.135694)
			(xy 309.960981 -316.149386) (xy 309.912126 -316.155318) (xy 309.862951 -316.153337) (xy 309.814732 -316.143493)
			(xy 309.768716 -316.126041) (xy 309.726095 -316.101434) (xy 309.687974 -316.070309) (xy 309.655339 -316.033472)
			(xy 309.629036 -315.991876) (xy 309.609745 -315.9466) (xy 309.597968 -315.898816) (xy 309.594008 -315.849762)
			(xy 308.3052 -315.849762) (xy 308.304705 -315.874369) (xy 308.29681 -315.922946) (xy 308.281226 -315.969627)
			(xy 308.258355 -316.013204) (xy 308.22879 -316.052548) (xy 308.193297 -316.08664) (xy 308.152794 -316.114596)
			(xy 308.108332 -316.135694) (xy 308.061061 -316.149386) (xy 308.012206 -316.155318) (xy 307.963031 -316.153337)
			(xy 307.914812 -316.143493) (xy 307.868796 -316.126041) (xy 307.826175 -316.101434) (xy 307.788054 -316.070309)
			(xy 307.755419 -316.033472) (xy 307.729116 -315.991876) (xy 307.709825 -315.9466) (xy 307.698048 -315.898816)
			(xy 307.694088 -315.849762) (xy 306.405026 -315.849762) (xy 306.404531 -315.874369) (xy 306.396636 -315.922946)
			(xy 306.381052 -315.969627) (xy 306.358181 -316.013204) (xy 306.328616 -316.052548) (xy 306.293123 -316.08664)
			(xy 306.25262 -316.114596) (xy 306.208158 -316.135694) (xy 306.160887 -316.149386) (xy 306.112032 -316.155318)
			(xy 306.062857 -316.153337) (xy 306.014638 -316.143493) (xy 305.968622 -316.126041) (xy 305.926001 -316.101434)
			(xy 305.88788 -316.070309) (xy 305.855245 -316.033472) (xy 305.828942 -315.991876) (xy 305.809651 -315.9466)
			(xy 305.797874 -315.898816) (xy 305.793914 -315.849762) (xy 188.405262 -315.849762) (xy 188.404767 -315.874369)
			(xy 188.396872 -315.922946) (xy 188.381288 -315.969627) (xy 188.358417 -316.013204) (xy 188.328852 -316.052548)
			(xy 188.293359 -316.08664) (xy 188.252856 -316.114596) (xy 188.208394 -316.135694) (xy 188.161123 -316.149386)
			(xy 188.112268 -316.155318) (xy 188.063093 -316.153337) (xy 188.014874 -316.143493) (xy 187.968858 -316.126041)
			(xy 187.926237 -316.101434) (xy 187.888116 -316.070309) (xy 187.855481 -316.033472) (xy 187.829178 -315.991876)
			(xy 187.809887 -315.9466) (xy 187.79811 -315.898816) (xy 187.79415 -315.849762) (xy 186.505342 -315.849762)
			(xy 186.504847 -315.874369) (xy 186.496952 -315.922946) (xy 186.481368 -315.969627) (xy 186.458497 -316.013204)
			(xy 186.428932 -316.052548) (xy 186.393439 -316.08664) (xy 186.352936 -316.114596) (xy 186.308474 -316.135694)
			(xy 186.261203 -316.149386) (xy 186.212348 -316.155318) (xy 186.163173 -316.153337) (xy 186.114954 -316.143493)
			(xy 186.068938 -316.126041) (xy 186.026317 -316.101434) (xy 185.988196 -316.070309) (xy 185.955561 -316.033472)
			(xy 185.929258 -315.991876) (xy 185.909967 -315.9466) (xy 185.89819 -315.898816) (xy 185.89423 -315.849762)
			(xy 184.605168 -315.849762) (xy 184.604673 -315.874369) (xy 184.596778 -315.922946) (xy 184.581194 -315.969627)
			(xy 184.558323 -316.013204) (xy 184.528758 -316.052548) (xy 184.493265 -316.08664) (xy 184.452762 -316.114596)
			(xy 184.4083 -316.135694) (xy 184.361029 -316.149386) (xy 184.312174 -316.155318) (xy 184.262999 -316.153337)
			(xy 184.21478 -316.143493) (xy 184.168764 -316.126041) (xy 184.126143 -316.101434) (xy 184.088022 -316.070309)
			(xy 184.055387 -316.033472) (xy 184.029084 -315.991876) (xy 184.009793 -315.9466) (xy 183.998016 -315.898816)
			(xy 183.994056 -315.849762) (xy 182.705248 -315.849762) (xy 182.704753 -315.874369) (xy 182.696858 -315.922946)
			(xy 182.681274 -315.969627) (xy 182.658403 -316.013204) (xy 182.628838 -316.052548) (xy 182.593345 -316.08664)
			(xy 182.552842 -316.114596) (xy 182.50838 -316.135694) (xy 182.461109 -316.149386) (xy 182.412254 -316.155318)
			(xy 182.363079 -316.153337) (xy 182.31486 -316.143493) (xy 182.268844 -316.126041) (xy 182.226223 -316.101434)
			(xy 182.188102 -316.070309) (xy 182.155467 -316.033472) (xy 182.129164 -315.991876) (xy 182.109873 -315.9466)
			(xy 182.098096 -315.898816) (xy 182.094136 -315.849762) (xy 165.605206 -315.849762) (xy 165.604711 -315.874369)
			(xy 165.596816 -315.922946) (xy 165.581232 -315.969627) (xy 165.558361 -316.013204) (xy 165.528796 -316.052548)
			(xy 165.493303 -316.08664) (xy 165.4528 -316.114596) (xy 165.408338 -316.135694) (xy 165.361067 -316.149386)
			(xy 165.312212 -316.155318) (xy 165.263037 -316.153337) (xy 165.214818 -316.143493) (xy 165.168802 -316.126041)
			(xy 165.126181 -316.101434) (xy 165.08806 -316.070309) (xy 165.055425 -316.033472) (xy 165.029122 -315.991876)
			(xy 165.009831 -315.9466) (xy 164.998054 -315.898816) (xy 164.994094 -315.849762) (xy 163.705286 -315.849762)
			(xy 163.704791 -315.874369) (xy 163.696896 -315.922946) (xy 163.681312 -315.969627) (xy 163.658441 -316.013204)
			(xy 163.628876 -316.052548) (xy 163.593383 -316.08664) (xy 163.55288 -316.114596) (xy 163.508418 -316.135694)
			(xy 163.461147 -316.149386) (xy 163.412292 -316.155318) (xy 163.363117 -316.153337) (xy 163.314898 -316.143493)
			(xy 163.268882 -316.126041) (xy 163.226261 -316.101434) (xy 163.18814 -316.070309) (xy 163.155505 -316.033472)
			(xy 163.129202 -315.991876) (xy 163.109911 -315.9466) (xy 163.098134 -315.898816) (xy 163.094174 -315.849762)
			(xy 161.805366 -315.849762) (xy 161.804871 -315.874369) (xy 161.796976 -315.922946) (xy 161.781392 -315.969627)
			(xy 161.758521 -316.013204) (xy 161.728956 -316.052548) (xy 161.693463 -316.08664) (xy 161.65296 -316.114596)
			(xy 161.608498 -316.135694) (xy 161.561227 -316.149386) (xy 161.512372 -316.155318) (xy 161.463197 -316.153337)
			(xy 161.414978 -316.143493) (xy 161.368962 -316.126041) (xy 161.326341 -316.101434) (xy 161.28822 -316.070309)
			(xy 161.255585 -316.033472) (xy 161.229282 -315.991876) (xy 161.209991 -315.9466) (xy 161.198214 -315.898816)
			(xy 161.194254 -315.849762) (xy 159.905192 -315.849762) (xy 159.904697 -315.874369) (xy 159.896802 -315.922946)
			(xy 159.881218 -315.969627) (xy 159.858347 -316.013204) (xy 159.828782 -316.052548) (xy 159.793289 -316.08664)
			(xy 159.752786 -316.114596) (xy 159.708324 -316.135694) (xy 159.661053 -316.149386) (xy 159.612198 -316.155318)
			(xy 159.563023 -316.153337) (xy 159.514804 -316.143493) (xy 159.468788 -316.126041) (xy 159.426167 -316.101434)
			(xy 159.388046 -316.070309) (xy 159.355411 -316.033472) (xy 159.329108 -315.991876) (xy 159.309817 -315.9466)
			(xy 159.29804 -315.898816) (xy 159.29408 -315.849762) (xy 79.905098 -315.849762) (xy 79.904603 -315.874369)
			(xy 79.896708 -315.922946) (xy 79.881124 -315.969627) (xy 79.858253 -316.013204) (xy 79.828688 -316.052548)
			(xy 79.793195 -316.08664) (xy 79.752692 -316.114596) (xy 79.70823 -316.135694) (xy 79.660959 -316.149386)
			(xy 79.612104 -316.155318) (xy 79.562929 -316.153337) (xy 79.51471 -316.143493) (xy 79.468694 -316.126041)
			(xy 79.426073 -316.101434) (xy 79.387952 -316.070309) (xy 79.355317 -316.033472) (xy 79.329014 -315.991876)
			(xy 79.309723 -315.9466) (xy 79.297946 -315.898816) (xy 79.293986 -315.849762) (xy 78.005178 -315.849762)
			(xy 78.004683 -315.874369) (xy 77.996788 -315.922946) (xy 77.981204 -315.969627) (xy 77.958333 -316.013204)
			(xy 77.928768 -316.052548) (xy 77.893275 -316.08664) (xy 77.852772 -316.114596) (xy 77.80831 -316.135694)
			(xy 77.761039 -316.149386) (xy 77.712184 -316.155318) (xy 77.663009 -316.153337) (xy 77.61479 -316.143493)
			(xy 77.568774 -316.126041) (xy 77.526153 -316.101434) (xy 77.488032 -316.070309) (xy 77.455397 -316.033472)
			(xy 77.429094 -315.991876) (xy 77.409803 -315.9466) (xy 77.398026 -315.898816) (xy 77.394066 -315.849762)
			(xy 76.105258 -315.849762) (xy 76.104763 -315.874369) (xy 76.096868 -315.922946) (xy 76.081284 -315.969627)
			(xy 76.058413 -316.013204) (xy 76.028848 -316.052548) (xy 75.993355 -316.08664) (xy 75.952852 -316.114596)
			(xy 75.90839 -316.135694) (xy 75.861119 -316.149386) (xy 75.812264 -316.155318) (xy 75.763089 -316.153337)
			(xy 75.71487 -316.143493) (xy 75.668854 -316.126041) (xy 75.626233 -316.101434) (xy 75.588112 -316.070309)
			(xy 75.555477 -316.033472) (xy 75.529174 -315.991876) (xy 75.509883 -315.9466) (xy 75.498106 -315.898816)
			(xy 75.494146 -315.849762) (xy 74.205084 -315.849762) (xy 74.204589 -315.874369) (xy 74.196694 -315.922946)
			(xy 74.18111 -315.969627) (xy 74.158239 -316.013204) (xy 74.128674 -316.052548) (xy 74.093181 -316.08664)
			(xy 74.052678 -316.114596) (xy 74.008216 -316.135694) (xy 73.960945 -316.149386) (xy 73.91209 -316.155318)
			(xy 73.862915 -316.153337) (xy 73.814696 -316.143493) (xy 73.76868 -316.126041) (xy 73.726059 -316.101434)
			(xy 73.687938 -316.070309) (xy 73.655303 -316.033472) (xy 73.629 -315.991876) (xy 73.609709 -315.9466)
			(xy 73.597932 -315.898816) (xy 73.593972 -315.849762) (xy 0.508 -315.849762) (xy 0.508 -316.799722)
			(xy 73.593972 -316.799722) (xy 73.597932 -316.750668) (xy 73.609709 -316.702884) (xy 73.629 -316.657608)
			(xy 73.655303 -316.616012) (xy 73.687938 -316.579175) (xy 73.726059 -316.54805) (xy 73.76868 -316.523443)
			(xy 73.814696 -316.505991) (xy 73.862915 -316.496147) (xy 73.91209 -316.494166) (xy 73.960945 -316.500098)
			(xy 74.008216 -316.51379) (xy 74.052678 -316.534888) (xy 74.093181 -316.562844) (xy 74.128674 -316.596936)
			(xy 74.158239 -316.63628) (xy 74.18111 -316.679857) (xy 74.196694 -316.726538) (xy 74.204589 -316.775115)
			(xy 74.205084 -316.799722) (xy 75.494146 -316.799722) (xy 75.498106 -316.750668) (xy 75.509883 -316.702884)
			(xy 75.529174 -316.657608) (xy 75.555477 -316.616012) (xy 75.588112 -316.579175) (xy 75.626233 -316.54805)
			(xy 75.668854 -316.523443) (xy 75.71487 -316.505991) (xy 75.763089 -316.496147) (xy 75.812264 -316.494166)
			(xy 75.861119 -316.500098) (xy 75.90839 -316.51379) (xy 75.952852 -316.534888) (xy 75.993355 -316.562844)
			(xy 76.028848 -316.596936) (xy 76.058413 -316.63628) (xy 76.081284 -316.679857) (xy 76.096868 -316.726538)
			(xy 76.104763 -316.775115) (xy 76.105258 -316.799722) (xy 77.394066 -316.799722) (xy 77.398026 -316.750668)
			(xy 77.409803 -316.702884) (xy 77.429094 -316.657608) (xy 77.455397 -316.616012) (xy 77.488032 -316.579175)
			(xy 77.526153 -316.54805) (xy 77.568774 -316.523443) (xy 77.61479 -316.505991) (xy 77.663009 -316.496147)
			(xy 77.712184 -316.494166) (xy 77.761039 -316.500098) (xy 77.80831 -316.51379) (xy 77.852772 -316.534888)
			(xy 77.893275 -316.562844) (xy 77.928768 -316.596936) (xy 77.958333 -316.63628) (xy 77.981204 -316.679857)
			(xy 77.996788 -316.726538) (xy 78.004683 -316.775115) (xy 78.005178 -316.799722) (xy 79.293986 -316.799722)
			(xy 79.297946 -316.750668) (xy 79.309723 -316.702884) (xy 79.329014 -316.657608) (xy 79.355317 -316.616012)
			(xy 79.387952 -316.579175) (xy 79.426073 -316.54805) (xy 79.468694 -316.523443) (xy 79.51471 -316.505991)
			(xy 79.562929 -316.496147) (xy 79.612104 -316.494166) (xy 79.660959 -316.500098) (xy 79.70823 -316.51379)
			(xy 79.752692 -316.534888) (xy 79.793195 -316.562844) (xy 79.828688 -316.596936) (xy 79.858253 -316.63628)
			(xy 79.881124 -316.679857) (xy 79.896708 -316.726538) (xy 79.904603 -316.775115) (xy 79.905098 -316.799722)
			(xy 81.19416 -316.799722) (xy 81.19812 -316.750668) (xy 81.209897 -316.702884) (xy 81.229188 -316.657608)
			(xy 81.255491 -316.616012) (xy 81.288126 -316.579175) (xy 81.326247 -316.54805) (xy 81.368868 -316.523443)
			(xy 81.414884 -316.505991) (xy 81.463103 -316.496147) (xy 81.512278 -316.494166) (xy 81.561133 -316.500098)
			(xy 81.608404 -316.51379) (xy 81.652866 -316.534888) (xy 81.693369 -316.562844) (xy 81.728862 -316.596936)
			(xy 81.758427 -316.63628) (xy 81.781298 -316.679857) (xy 81.796882 -316.726538) (xy 81.804777 -316.775115)
			(xy 81.805272 -316.799722) (xy 82.14412 -316.799722) (xy 82.14808 -316.750668) (xy 82.159857 -316.702884)
			(xy 82.179148 -316.657608) (xy 82.205451 -316.616012) (xy 82.238086 -316.579175) (xy 82.276207 -316.54805)
			(xy 82.318828 -316.523443) (xy 82.364844 -316.505991) (xy 82.413063 -316.496147) (xy 82.462238 -316.494166)
			(xy 82.511093 -316.500098) (xy 82.558364 -316.51379) (xy 82.602826 -316.534888) (xy 82.643329 -316.562844)
			(xy 82.678822 -316.596936) (xy 82.708387 -316.63628) (xy 82.731258 -316.679857) (xy 82.746842 -316.726538)
			(xy 82.754737 -316.775115) (xy 82.755232 -316.799722) (xy 159.29408 -316.799722) (xy 159.29804 -316.750668)
			(xy 159.309817 -316.702884) (xy 159.329108 -316.657608) (xy 159.355411 -316.616012) (xy 159.388046 -316.579175)
			(xy 159.426167 -316.54805) (xy 159.468788 -316.523443) (xy 159.514804 -316.505991) (xy 159.563023 -316.496147)
			(xy 159.612198 -316.494166) (xy 159.661053 -316.500098) (xy 159.708324 -316.51379) (xy 159.752786 -316.534888)
			(xy 159.793289 -316.562844) (xy 159.828782 -316.596936) (xy 159.858347 -316.63628) (xy 159.881218 -316.679857)
			(xy 159.896802 -316.726538) (xy 159.904697 -316.775115) (xy 159.905192 -316.799722) (xy 161.194254 -316.799722)
			(xy 161.198214 -316.750668) (xy 161.209991 -316.702884) (xy 161.229282 -316.657608) (xy 161.255585 -316.616012)
			(xy 161.28822 -316.579175) (xy 161.326341 -316.54805) (xy 161.368962 -316.523443) (xy 161.414978 -316.505991)
			(xy 161.463197 -316.496147) (xy 161.512372 -316.494166) (xy 161.561227 -316.500098) (xy 161.608498 -316.51379)
			(xy 161.65296 -316.534888) (xy 161.693463 -316.562844) (xy 161.728956 -316.596936) (xy 161.758521 -316.63628)
			(xy 161.781392 -316.679857) (xy 161.796976 -316.726538) (xy 161.804871 -316.775115) (xy 161.805366 -316.799722)
			(xy 163.094174 -316.799722) (xy 163.098134 -316.750668) (xy 163.109911 -316.702884) (xy 163.129202 -316.657608)
			(xy 163.155505 -316.616012) (xy 163.18814 -316.579175) (xy 163.226261 -316.54805) (xy 163.268882 -316.523443)
			(xy 163.314898 -316.505991) (xy 163.363117 -316.496147) (xy 163.412292 -316.494166) (xy 163.461147 -316.500098)
			(xy 163.508418 -316.51379) (xy 163.55288 -316.534888) (xy 163.593383 -316.562844) (xy 163.628876 -316.596936)
			(xy 163.658441 -316.63628) (xy 163.681312 -316.679857) (xy 163.696896 -316.726538) (xy 163.704791 -316.775115)
			(xy 163.705286 -316.799722) (xy 164.994094 -316.799722) (xy 164.998054 -316.750668) (xy 165.009831 -316.702884)
			(xy 165.029122 -316.657608) (xy 165.055425 -316.616012) (xy 165.08806 -316.579175) (xy 165.126181 -316.54805)
			(xy 165.168802 -316.523443) (xy 165.214818 -316.505991) (xy 165.263037 -316.496147) (xy 165.312212 -316.494166)
			(xy 165.361067 -316.500098) (xy 165.408338 -316.51379) (xy 165.4528 -316.534888) (xy 165.493303 -316.562844)
			(xy 165.528796 -316.596936) (xy 165.558361 -316.63628) (xy 165.581232 -316.679857) (xy 165.596816 -316.726538)
			(xy 165.604711 -316.775115) (xy 165.605206 -316.799722) (xy 182.094136 -316.799722) (xy 182.098096 -316.750668)
			(xy 182.109873 -316.702884) (xy 182.129164 -316.657608) (xy 182.155467 -316.616012) (xy 182.188102 -316.579175)
			(xy 182.226223 -316.54805) (xy 182.268844 -316.523443) (xy 182.31486 -316.505991) (xy 182.363079 -316.496147)
			(xy 182.412254 -316.494166) (xy 182.461109 -316.500098) (xy 182.50838 -316.51379) (xy 182.552842 -316.534888)
			(xy 182.593345 -316.562844) (xy 182.628838 -316.596936) (xy 182.658403 -316.63628) (xy 182.681274 -316.679857)
			(xy 182.696858 -316.726538) (xy 182.704753 -316.775115) (xy 182.705248 -316.799722) (xy 183.994056 -316.799722)
			(xy 183.998016 -316.750668) (xy 184.009793 -316.702884) (xy 184.029084 -316.657608) (xy 184.055387 -316.616012)
			(xy 184.088022 -316.579175) (xy 184.126143 -316.54805) (xy 184.168764 -316.523443) (xy 184.21478 -316.505991)
			(xy 184.262999 -316.496147) (xy 184.312174 -316.494166) (xy 184.361029 -316.500098) (xy 184.4083 -316.51379)
			(xy 184.452762 -316.534888) (xy 184.493265 -316.562844) (xy 184.528758 -316.596936) (xy 184.558323 -316.63628)
			(xy 184.581194 -316.679857) (xy 184.596778 -316.726538) (xy 184.604673 -316.775115) (xy 184.605168 -316.799722)
			(xy 185.89423 -316.799722) (xy 185.89819 -316.750668) (xy 185.909967 -316.702884) (xy 185.929258 -316.657608)
			(xy 185.955561 -316.616012) (xy 185.988196 -316.579175) (xy 186.026317 -316.54805) (xy 186.068938 -316.523443)
			(xy 186.114954 -316.505991) (xy 186.163173 -316.496147) (xy 186.212348 -316.494166) (xy 186.261203 -316.500098)
			(xy 186.308474 -316.51379) (xy 186.352936 -316.534888) (xy 186.393439 -316.562844) (xy 186.428932 -316.596936)
			(xy 186.458497 -316.63628) (xy 186.481368 -316.679857) (xy 186.496952 -316.726538) (xy 186.504847 -316.775115)
			(xy 186.505342 -316.799722) (xy 187.79415 -316.799722) (xy 187.79811 -316.750668) (xy 187.809887 -316.702884)
			(xy 187.829178 -316.657608) (xy 187.855481 -316.616012) (xy 187.888116 -316.579175) (xy 187.926237 -316.54805)
			(xy 187.968858 -316.523443) (xy 188.014874 -316.505991) (xy 188.063093 -316.496147) (xy 188.112268 -316.494166)
			(xy 188.161123 -316.500098) (xy 188.208394 -316.51379) (xy 188.252856 -316.534888) (xy 188.293359 -316.562844)
			(xy 188.328852 -316.596936) (xy 188.358417 -316.63628) (xy 188.381288 -316.679857) (xy 188.396872 -316.726538)
			(xy 188.404767 -316.775115) (xy 188.405262 -316.799722) (xy 305.793914 -316.799722) (xy 305.797874 -316.750668)
			(xy 305.809651 -316.702884) (xy 305.828942 -316.657608) (xy 305.855245 -316.616012) (xy 305.88788 -316.579175)
			(xy 305.926001 -316.54805) (xy 305.968622 -316.523443) (xy 306.014638 -316.505991) (xy 306.062857 -316.496147)
			(xy 306.112032 -316.494166) (xy 306.160887 -316.500098) (xy 306.208158 -316.51379) (xy 306.25262 -316.534888)
			(xy 306.293123 -316.562844) (xy 306.328616 -316.596936) (xy 306.358181 -316.63628) (xy 306.381052 -316.679857)
			(xy 306.396636 -316.726538) (xy 306.404531 -316.775115) (xy 306.405026 -316.799722) (xy 307.694088 -316.799722)
			(xy 307.698048 -316.750668) (xy 307.709825 -316.702884) (xy 307.729116 -316.657608) (xy 307.755419 -316.616012)
			(xy 307.788054 -316.579175) (xy 307.826175 -316.54805) (xy 307.868796 -316.523443) (xy 307.914812 -316.505991)
			(xy 307.963031 -316.496147) (xy 308.012206 -316.494166) (xy 308.061061 -316.500098) (xy 308.108332 -316.51379)
			(xy 308.152794 -316.534888) (xy 308.193297 -316.562844) (xy 308.22879 -316.596936) (xy 308.258355 -316.63628)
			(xy 308.281226 -316.679857) (xy 308.29681 -316.726538) (xy 308.304705 -316.775115) (xy 308.3052 -316.799722)
			(xy 309.594008 -316.799722) (xy 309.597968 -316.750668) (xy 309.609745 -316.702884) (xy 309.629036 -316.657608)
			(xy 309.655339 -316.616012) (xy 309.687974 -316.579175) (xy 309.726095 -316.54805) (xy 309.768716 -316.523443)
			(xy 309.814732 -316.505991) (xy 309.862951 -316.496147) (xy 309.912126 -316.494166) (xy 309.960981 -316.500098)
			(xy 310.008252 -316.51379) (xy 310.052714 -316.534888) (xy 310.093217 -316.562844) (xy 310.12871 -316.596936)
			(xy 310.158275 -316.63628) (xy 310.181146 -316.679857) (xy 310.19673 -316.726538) (xy 310.204625 -316.775115)
			(xy 310.20512 -316.799722) (xy 311.493928 -316.799722) (xy 311.497888 -316.750668) (xy 311.509665 -316.702884)
			(xy 311.528956 -316.657608) (xy 311.555259 -316.616012) (xy 311.587894 -316.579175) (xy 311.626015 -316.54805)
			(xy 311.668636 -316.523443) (xy 311.714652 -316.505991) (xy 311.762871 -316.496147) (xy 311.812046 -316.494166)
			(xy 311.860901 -316.500098) (xy 311.908172 -316.51379) (xy 311.952634 -316.534888) (xy 311.993137 -316.562844)
			(xy 312.02863 -316.596936) (xy 312.058195 -316.63628) (xy 312.081066 -316.679857) (xy 312.09665 -316.726538)
			(xy 312.104545 -316.775115) (xy 312.10504 -316.799722) (xy 313.394102 -316.799722) (xy 313.398062 -316.750668)
			(xy 313.409839 -316.702884) (xy 313.42913 -316.657608) (xy 313.455433 -316.616012) (xy 313.488068 -316.579175)
			(xy 313.526189 -316.54805) (xy 313.56881 -316.523443) (xy 313.614826 -316.505991) (xy 313.663045 -316.496147)
			(xy 313.71222 -316.494166) (xy 313.761075 -316.500098) (xy 313.808346 -316.51379) (xy 313.852808 -316.534888)
			(xy 313.893311 -316.562844) (xy 313.928804 -316.596936) (xy 313.958369 -316.63628) (xy 313.98124 -316.679857)
			(xy 313.996824 -316.726538) (xy 314.004719 -316.775115) (xy 314.005214 -316.799722) (xy 314.344062 -316.799722)
			(xy 314.348022 -316.750668) (xy 314.359799 -316.702884) (xy 314.37909 -316.657608) (xy 314.405393 -316.616012)
			(xy 314.438028 -316.579175) (xy 314.476149 -316.54805) (xy 314.51877 -316.523443) (xy 314.564786 -316.505991)
			(xy 314.613005 -316.496147) (xy 314.66218 -316.494166) (xy 314.711035 -316.500098) (xy 314.758306 -316.51379)
			(xy 314.802768 -316.534888) (xy 314.843271 -316.562844) (xy 314.878764 -316.596936) (xy 314.908329 -316.63628)
			(xy 314.9312 -316.679857) (xy 314.946784 -316.726538) (xy 314.954679 -316.775115) (xy 314.955174 -316.799722)
			(xy 391.494022 -316.799722) (xy 391.497982 -316.750668) (xy 391.509759 -316.702884) (xy 391.52905 -316.657608)
			(xy 391.555353 -316.616012) (xy 391.587988 -316.579175) (xy 391.626109 -316.54805) (xy 391.66873 -316.523443)
			(xy 391.714746 -316.505991) (xy 391.762965 -316.496147) (xy 391.81214 -316.494166) (xy 391.860995 -316.500098)
			(xy 391.908266 -316.51379) (xy 391.952728 -316.534888) (xy 391.993231 -316.562844) (xy 392.028724 -316.596936)
			(xy 392.058289 -316.63628) (xy 392.08116 -316.679857) (xy 392.096744 -316.726538) (xy 392.104639 -316.775115)
			(xy 392.105134 -316.799722) (xy 393.394196 -316.799722) (xy 393.398156 -316.750668) (xy 393.409933 -316.702884)
			(xy 393.429224 -316.657608) (xy 393.455527 -316.616012) (xy 393.488162 -316.579175) (xy 393.526283 -316.54805)
			(xy 393.568904 -316.523443) (xy 393.61492 -316.505991) (xy 393.663139 -316.496147) (xy 393.712314 -316.494166)
			(xy 393.761169 -316.500098) (xy 393.80844 -316.51379) (xy 393.852902 -316.534888) (xy 393.893405 -316.562844)
			(xy 393.928898 -316.596936) (xy 393.958463 -316.63628) (xy 393.981334 -316.679857) (xy 393.996918 -316.726538)
			(xy 394.004813 -316.775115) (xy 394.005308 -316.799722) (xy 395.294116 -316.799722) (xy 395.298076 -316.750668)
			(xy 395.309853 -316.702884) (xy 395.329144 -316.657608) (xy 395.355447 -316.616012) (xy 395.388082 -316.579175)
			(xy 395.426203 -316.54805) (xy 395.468824 -316.523443) (xy 395.51484 -316.505991) (xy 395.563059 -316.496147)
			(xy 395.612234 -316.494166) (xy 395.661089 -316.500098) (xy 395.70836 -316.51379) (xy 395.752822 -316.534888)
			(xy 395.793325 -316.562844) (xy 395.828818 -316.596936) (xy 395.858383 -316.63628) (xy 395.881254 -316.679857)
			(xy 395.896838 -316.726538) (xy 395.904733 -316.775115) (xy 395.905228 -316.799722) (xy 397.194036 -316.799722)
			(xy 397.197996 -316.750668) (xy 397.209773 -316.702884) (xy 397.229064 -316.657608) (xy 397.255367 -316.616012)
			(xy 397.288002 -316.579175) (xy 397.326123 -316.54805) (xy 397.368744 -316.523443) (xy 397.41476 -316.505991)
			(xy 397.462979 -316.496147) (xy 397.512154 -316.494166) (xy 397.561009 -316.500098) (xy 397.60828 -316.51379)
			(xy 397.652742 -316.534888) (xy 397.693245 -316.562844) (xy 397.728738 -316.596936) (xy 397.758303 -316.63628)
			(xy 397.781174 -316.679857) (xy 397.796758 -316.726538) (xy 397.804653 -316.775115) (xy 397.805148 -316.799722)
			(xy 414.294078 -316.799722) (xy 414.298038 -316.750668) (xy 414.309815 -316.702884) (xy 414.329106 -316.657608)
			(xy 414.355409 -316.616012) (xy 414.388044 -316.579175) (xy 414.426165 -316.54805) (xy 414.468786 -316.523443)
			(xy 414.514802 -316.505991) (xy 414.563021 -316.496147) (xy 414.612196 -316.494166) (xy 414.661051 -316.500098)
			(xy 414.708322 -316.51379) (xy 414.752784 -316.534888) (xy 414.793287 -316.562844) (xy 414.82878 -316.596936)
			(xy 414.858345 -316.63628) (xy 414.881216 -316.679857) (xy 414.8968 -316.726538) (xy 414.904695 -316.775115)
			(xy 414.90519 -316.799722) (xy 416.193998 -316.799722) (xy 416.197958 -316.750668) (xy 416.209735 -316.702884)
			(xy 416.229026 -316.657608) (xy 416.255329 -316.616012) (xy 416.287964 -316.579175) (xy 416.326085 -316.54805)
			(xy 416.368706 -316.523443) (xy 416.414722 -316.505991) (xy 416.462941 -316.496147) (xy 416.512116 -316.494166)
			(xy 416.560971 -316.500098) (xy 416.608242 -316.51379) (xy 416.652704 -316.534888) (xy 416.693207 -316.562844)
			(xy 416.7287 -316.596936) (xy 416.758265 -316.63628) (xy 416.781136 -316.679857) (xy 416.79672 -316.726538)
			(xy 416.804615 -316.775115) (xy 416.80511 -316.799722) (xy 418.094172 -316.799722) (xy 418.098132 -316.750668)
			(xy 418.109909 -316.702884) (xy 418.1292 -316.657608) (xy 418.155503 -316.616012) (xy 418.188138 -316.579175)
			(xy 418.226259 -316.54805) (xy 418.26888 -316.523443) (xy 418.314896 -316.505991) (xy 418.363115 -316.496147)
			(xy 418.41229 -316.494166) (xy 418.461145 -316.500098) (xy 418.508416 -316.51379) (xy 418.552878 -316.534888)
			(xy 418.593381 -316.562844) (xy 418.628874 -316.596936) (xy 418.658439 -316.63628) (xy 418.68131 -316.679857)
			(xy 418.696894 -316.726538) (xy 418.704789 -316.775115) (xy 418.705284 -316.799722) (xy 419.994092 -316.799722)
			(xy 419.998052 -316.750668) (xy 420.009829 -316.702884) (xy 420.02912 -316.657608) (xy 420.055423 -316.616012)
			(xy 420.088058 -316.579175) (xy 420.126179 -316.54805) (xy 420.1688 -316.523443) (xy 420.214816 -316.505991)
			(xy 420.263035 -316.496147) (xy 420.31221 -316.494166) (xy 420.361065 -316.500098) (xy 420.408336 -316.51379)
			(xy 420.452798 -316.534888) (xy 420.493301 -316.562844) (xy 420.528794 -316.596936) (xy 420.558359 -316.63628)
			(xy 420.58123 -316.679857) (xy 420.596814 -316.726538) (xy 420.604709 -316.775115) (xy 420.605204 -316.799722)
			(xy 420.604709 -316.824329) (xy 420.596814 -316.872906) (xy 420.58123 -316.919587) (xy 420.558359 -316.963164)
			(xy 420.528794 -317.002508) (xy 420.493301 -317.0366) (xy 420.452798 -317.064556) (xy 420.408336 -317.085654)
			(xy 420.361065 -317.099346) (xy 420.31221 -317.105278) (xy 420.263035 -317.103297) (xy 420.214816 -317.093453)
			(xy 420.1688 -317.076001) (xy 420.126179 -317.051394) (xy 420.088058 -317.020269) (xy 420.055423 -316.983432)
			(xy 420.02912 -316.941836) (xy 420.009829 -316.89656) (xy 419.998052 -316.848776) (xy 419.994092 -316.799722)
			(xy 418.705284 -316.799722) (xy 418.704789 -316.824329) (xy 418.696894 -316.872906) (xy 418.68131 -316.919587)
			(xy 418.658439 -316.963164) (xy 418.628874 -317.002508) (xy 418.593381 -317.0366) (xy 418.552878 -317.064556)
			(xy 418.508416 -317.085654) (xy 418.461145 -317.099346) (xy 418.41229 -317.105278) (xy 418.363115 -317.103297)
			(xy 418.314896 -317.093453) (xy 418.26888 -317.076001) (xy 418.226259 -317.051394) (xy 418.188138 -317.020269)
			(xy 418.155503 -316.983432) (xy 418.1292 -316.941836) (xy 418.109909 -316.89656) (xy 418.098132 -316.848776)
			(xy 418.094172 -316.799722) (xy 416.80511 -316.799722) (xy 416.804615 -316.824329) (xy 416.79672 -316.872906)
			(xy 416.781136 -316.919587) (xy 416.758265 -316.963164) (xy 416.7287 -317.002508) (xy 416.693207 -317.0366)
			(xy 416.652704 -317.064556) (xy 416.608242 -317.085654) (xy 416.560971 -317.099346) (xy 416.512116 -317.105278)
			(xy 416.462941 -317.103297) (xy 416.414722 -317.093453) (xy 416.368706 -317.076001) (xy 416.326085 -317.051394)
			(xy 416.287964 -317.020269) (xy 416.255329 -316.983432) (xy 416.229026 -316.941836) (xy 416.209735 -316.89656)
			(xy 416.197958 -316.848776) (xy 416.193998 -316.799722) (xy 414.90519 -316.799722) (xy 414.904695 -316.824329)
			(xy 414.8968 -316.872906) (xy 414.881216 -316.919587) (xy 414.858345 -316.963164) (xy 414.82878 -317.002508)
			(xy 414.793287 -317.0366) (xy 414.752784 -317.064556) (xy 414.708322 -317.085654) (xy 414.661051 -317.099346)
			(xy 414.612196 -317.105278) (xy 414.563021 -317.103297) (xy 414.514802 -317.093453) (xy 414.468786 -317.076001)
			(xy 414.426165 -317.051394) (xy 414.388044 -317.020269) (xy 414.355409 -316.983432) (xy 414.329106 -316.941836)
			(xy 414.309815 -316.89656) (xy 414.298038 -316.848776) (xy 414.294078 -316.799722) (xy 397.805148 -316.799722)
			(xy 397.804653 -316.824329) (xy 397.796758 -316.872906) (xy 397.781174 -316.919587) (xy 397.758303 -316.963164)
			(xy 397.728738 -317.002508) (xy 397.693245 -317.0366) (xy 397.652742 -317.064556) (xy 397.60828 -317.085654)
			(xy 397.561009 -317.099346) (xy 397.512154 -317.105278) (xy 397.462979 -317.103297) (xy 397.41476 -317.093453)
			(xy 397.368744 -317.076001) (xy 397.326123 -317.051394) (xy 397.288002 -317.020269) (xy 397.255367 -316.983432)
			(xy 397.229064 -316.941836) (xy 397.209773 -316.89656) (xy 397.197996 -316.848776) (xy 397.194036 -316.799722)
			(xy 395.905228 -316.799722) (xy 395.904733 -316.824329) (xy 395.896838 -316.872906) (xy 395.881254 -316.919587)
			(xy 395.858383 -316.963164) (xy 395.828818 -317.002508) (xy 395.793325 -317.0366) (xy 395.752822 -317.064556)
			(xy 395.70836 -317.085654) (xy 395.661089 -317.099346) (xy 395.612234 -317.105278) (xy 395.563059 -317.103297)
			(xy 395.51484 -317.093453) (xy 395.468824 -317.076001) (xy 395.426203 -317.051394) (xy 395.388082 -317.020269)
			(xy 395.355447 -316.983432) (xy 395.329144 -316.941836) (xy 395.309853 -316.89656) (xy 395.298076 -316.848776)
			(xy 395.294116 -316.799722) (xy 394.005308 -316.799722) (xy 394.004813 -316.824329) (xy 393.996918 -316.872906)
			(xy 393.981334 -316.919587) (xy 393.958463 -316.963164) (xy 393.928898 -317.002508) (xy 393.893405 -317.0366)
			(xy 393.852902 -317.064556) (xy 393.80844 -317.085654) (xy 393.761169 -317.099346) (xy 393.712314 -317.105278)
			(xy 393.663139 -317.103297) (xy 393.61492 -317.093453) (xy 393.568904 -317.076001) (xy 393.526283 -317.051394)
			(xy 393.488162 -317.020269) (xy 393.455527 -316.983432) (xy 393.429224 -316.941836) (xy 393.409933 -316.89656)
			(xy 393.398156 -316.848776) (xy 393.394196 -316.799722) (xy 392.105134 -316.799722) (xy 392.104639 -316.824329)
			(xy 392.096744 -316.872906) (xy 392.08116 -316.919587) (xy 392.058289 -316.963164) (xy 392.028724 -317.002508)
			(xy 391.993231 -317.0366) (xy 391.952728 -317.064556) (xy 391.908266 -317.085654) (xy 391.860995 -317.099346)
			(xy 391.81214 -317.105278) (xy 391.762965 -317.103297) (xy 391.714746 -317.093453) (xy 391.66873 -317.076001)
			(xy 391.626109 -317.051394) (xy 391.587988 -317.020269) (xy 391.555353 -316.983432) (xy 391.52905 -316.941836)
			(xy 391.509759 -316.89656) (xy 391.497982 -316.848776) (xy 391.494022 -316.799722) (xy 314.955174 -316.799722)
			(xy 314.954679 -316.824329) (xy 314.946784 -316.872906) (xy 314.9312 -316.919587) (xy 314.908329 -316.963164)
			(xy 314.878764 -317.002508) (xy 314.843271 -317.0366) (xy 314.802768 -317.064556) (xy 314.758306 -317.085654)
			(xy 314.711035 -317.099346) (xy 314.66218 -317.105278) (xy 314.613005 -317.103297) (xy 314.564786 -317.093453)
			(xy 314.51877 -317.076001) (xy 314.476149 -317.051394) (xy 314.438028 -317.020269) (xy 314.405393 -316.983432)
			(xy 314.37909 -316.941836) (xy 314.359799 -316.89656) (xy 314.348022 -316.848776) (xy 314.344062 -316.799722)
			(xy 314.005214 -316.799722) (xy 314.004719 -316.824329) (xy 313.996824 -316.872906) (xy 313.98124 -316.919587)
			(xy 313.958369 -316.963164) (xy 313.928804 -317.002508) (xy 313.893311 -317.0366) (xy 313.852808 -317.064556)
			(xy 313.808346 -317.085654) (xy 313.761075 -317.099346) (xy 313.71222 -317.105278) (xy 313.663045 -317.103297)
			(xy 313.614826 -317.093453) (xy 313.56881 -317.076001) (xy 313.526189 -317.051394) (xy 313.488068 -317.020269)
			(xy 313.455433 -316.983432) (xy 313.42913 -316.941836) (xy 313.409839 -316.89656) (xy 313.398062 -316.848776)
			(xy 313.394102 -316.799722) (xy 312.10504 -316.799722) (xy 312.104545 -316.824329) (xy 312.09665 -316.872906)
			(xy 312.081066 -316.919587) (xy 312.058195 -316.963164) (xy 312.02863 -317.002508) (xy 311.993137 -317.0366)
			(xy 311.952634 -317.064556) (xy 311.908172 -317.085654) (xy 311.860901 -317.099346) (xy 311.812046 -317.105278)
			(xy 311.762871 -317.103297) (xy 311.714652 -317.093453) (xy 311.668636 -317.076001) (xy 311.626015 -317.051394)
			(xy 311.587894 -317.020269) (xy 311.555259 -316.983432) (xy 311.528956 -316.941836) (xy 311.509665 -316.89656)
			(xy 311.497888 -316.848776) (xy 311.493928 -316.799722) (xy 310.20512 -316.799722) (xy 310.204625 -316.824329)
			(xy 310.19673 -316.872906) (xy 310.181146 -316.919587) (xy 310.158275 -316.963164) (xy 310.12871 -317.002508)
			(xy 310.093217 -317.0366) (xy 310.052714 -317.064556) (xy 310.008252 -317.085654) (xy 309.960981 -317.099346)
			(xy 309.912126 -317.105278) (xy 309.862951 -317.103297) (xy 309.814732 -317.093453) (xy 309.768716 -317.076001)
			(xy 309.726095 -317.051394) (xy 309.687974 -317.020269) (xy 309.655339 -316.983432) (xy 309.629036 -316.941836)
			(xy 309.609745 -316.89656) (xy 309.597968 -316.848776) (xy 309.594008 -316.799722) (xy 308.3052 -316.799722)
			(xy 308.304705 -316.824329) (xy 308.29681 -316.872906) (xy 308.281226 -316.919587) (xy 308.258355 -316.963164)
			(xy 308.22879 -317.002508) (xy 308.193297 -317.0366) (xy 308.152794 -317.064556) (xy 308.108332 -317.085654)
			(xy 308.061061 -317.099346) (xy 308.012206 -317.105278) (xy 307.963031 -317.103297) (xy 307.914812 -317.093453)
			(xy 307.868796 -317.076001) (xy 307.826175 -317.051394) (xy 307.788054 -317.020269) (xy 307.755419 -316.983432)
			(xy 307.729116 -316.941836) (xy 307.709825 -316.89656) (xy 307.698048 -316.848776) (xy 307.694088 -316.799722)
			(xy 306.405026 -316.799722) (xy 306.404531 -316.824329) (xy 306.396636 -316.872906) (xy 306.381052 -316.919587)
			(xy 306.358181 -316.963164) (xy 306.328616 -317.002508) (xy 306.293123 -317.0366) (xy 306.25262 -317.064556)
			(xy 306.208158 -317.085654) (xy 306.160887 -317.099346) (xy 306.112032 -317.105278) (xy 306.062857 -317.103297)
			(xy 306.014638 -317.093453) (xy 305.968622 -317.076001) (xy 305.926001 -317.051394) (xy 305.88788 -317.020269)
			(xy 305.855245 -316.983432) (xy 305.828942 -316.941836) (xy 305.809651 -316.89656) (xy 305.797874 -316.848776)
			(xy 305.793914 -316.799722) (xy 188.405262 -316.799722) (xy 188.404767 -316.824329) (xy 188.396872 -316.872906)
			(xy 188.381288 -316.919587) (xy 188.358417 -316.963164) (xy 188.328852 -317.002508) (xy 188.293359 -317.0366)
			(xy 188.252856 -317.064556) (xy 188.208394 -317.085654) (xy 188.161123 -317.099346) (xy 188.112268 -317.105278)
			(xy 188.063093 -317.103297) (xy 188.014874 -317.093453) (xy 187.968858 -317.076001) (xy 187.926237 -317.051394)
			(xy 187.888116 -317.020269) (xy 187.855481 -316.983432) (xy 187.829178 -316.941836) (xy 187.809887 -316.89656)
			(xy 187.79811 -316.848776) (xy 187.79415 -316.799722) (xy 186.505342 -316.799722) (xy 186.504847 -316.824329)
			(xy 186.496952 -316.872906) (xy 186.481368 -316.919587) (xy 186.458497 -316.963164) (xy 186.428932 -317.002508)
			(xy 186.393439 -317.0366) (xy 186.352936 -317.064556) (xy 186.308474 -317.085654) (xy 186.261203 -317.099346)
			(xy 186.212348 -317.105278) (xy 186.163173 -317.103297) (xy 186.114954 -317.093453) (xy 186.068938 -317.076001)
			(xy 186.026317 -317.051394) (xy 185.988196 -317.020269) (xy 185.955561 -316.983432) (xy 185.929258 -316.941836)
			(xy 185.909967 -316.89656) (xy 185.89819 -316.848776) (xy 185.89423 -316.799722) (xy 184.605168 -316.799722)
			(xy 184.604673 -316.824329) (xy 184.596778 -316.872906) (xy 184.581194 -316.919587) (xy 184.558323 -316.963164)
			(xy 184.528758 -317.002508) (xy 184.493265 -317.0366) (xy 184.452762 -317.064556) (xy 184.4083 -317.085654)
			(xy 184.361029 -317.099346) (xy 184.312174 -317.105278) (xy 184.262999 -317.103297) (xy 184.21478 -317.093453)
			(xy 184.168764 -317.076001) (xy 184.126143 -317.051394) (xy 184.088022 -317.020269) (xy 184.055387 -316.983432)
			(xy 184.029084 -316.941836) (xy 184.009793 -316.89656) (xy 183.998016 -316.848776) (xy 183.994056 -316.799722)
			(xy 182.705248 -316.799722) (xy 182.704753 -316.824329) (xy 182.696858 -316.872906) (xy 182.681274 -316.919587)
			(xy 182.658403 -316.963164) (xy 182.628838 -317.002508) (xy 182.593345 -317.0366) (xy 182.552842 -317.064556)
			(xy 182.50838 -317.085654) (xy 182.461109 -317.099346) (xy 182.412254 -317.105278) (xy 182.363079 -317.103297)
			(xy 182.31486 -317.093453) (xy 182.268844 -317.076001) (xy 182.226223 -317.051394) (xy 182.188102 -317.020269)
			(xy 182.155467 -316.983432) (xy 182.129164 -316.941836) (xy 182.109873 -316.89656) (xy 182.098096 -316.848776)
			(xy 182.094136 -316.799722) (xy 165.605206 -316.799722) (xy 165.604711 -316.824329) (xy 165.596816 -316.872906)
			(xy 165.581232 -316.919587) (xy 165.558361 -316.963164) (xy 165.528796 -317.002508) (xy 165.493303 -317.0366)
			(xy 165.4528 -317.064556) (xy 165.408338 -317.085654) (xy 165.361067 -317.099346) (xy 165.312212 -317.105278)
			(xy 165.263037 -317.103297) (xy 165.214818 -317.093453) (xy 165.168802 -317.076001) (xy 165.126181 -317.051394)
			(xy 165.08806 -317.020269) (xy 165.055425 -316.983432) (xy 165.029122 -316.941836) (xy 165.009831 -316.89656)
			(xy 164.998054 -316.848776) (xy 164.994094 -316.799722) (xy 163.705286 -316.799722) (xy 163.704791 -316.824329)
			(xy 163.696896 -316.872906) (xy 163.681312 -316.919587) (xy 163.658441 -316.963164) (xy 163.628876 -317.002508)
			(xy 163.593383 -317.0366) (xy 163.55288 -317.064556) (xy 163.508418 -317.085654) (xy 163.461147 -317.099346)
			(xy 163.412292 -317.105278) (xy 163.363117 -317.103297) (xy 163.314898 -317.093453) (xy 163.268882 -317.076001)
			(xy 163.226261 -317.051394) (xy 163.18814 -317.020269) (xy 163.155505 -316.983432) (xy 163.129202 -316.941836)
			(xy 163.109911 -316.89656) (xy 163.098134 -316.848776) (xy 163.094174 -316.799722) (xy 161.805366 -316.799722)
			(xy 161.804871 -316.824329) (xy 161.796976 -316.872906) (xy 161.781392 -316.919587) (xy 161.758521 -316.963164)
			(xy 161.728956 -317.002508) (xy 161.693463 -317.0366) (xy 161.65296 -317.064556) (xy 161.608498 -317.085654)
			(xy 161.561227 -317.099346) (xy 161.512372 -317.105278) (xy 161.463197 -317.103297) (xy 161.414978 -317.093453)
			(xy 161.368962 -317.076001) (xy 161.326341 -317.051394) (xy 161.28822 -317.020269) (xy 161.255585 -316.983432)
			(xy 161.229282 -316.941836) (xy 161.209991 -316.89656) (xy 161.198214 -316.848776) (xy 161.194254 -316.799722)
			(xy 159.905192 -316.799722) (xy 159.904697 -316.824329) (xy 159.896802 -316.872906) (xy 159.881218 -316.919587)
			(xy 159.858347 -316.963164) (xy 159.828782 -317.002508) (xy 159.793289 -317.0366) (xy 159.752786 -317.064556)
			(xy 159.708324 -317.085654) (xy 159.661053 -317.099346) (xy 159.612198 -317.105278) (xy 159.563023 -317.103297)
			(xy 159.514804 -317.093453) (xy 159.468788 -317.076001) (xy 159.426167 -317.051394) (xy 159.388046 -317.020269)
			(xy 159.355411 -316.983432) (xy 159.329108 -316.941836) (xy 159.309817 -316.89656) (xy 159.29804 -316.848776)
			(xy 159.29408 -316.799722) (xy 82.755232 -316.799722) (xy 82.754737 -316.824329) (xy 82.746842 -316.872906)
			(xy 82.731258 -316.919587) (xy 82.708387 -316.963164) (xy 82.678822 -317.002508) (xy 82.643329 -317.0366)
			(xy 82.602826 -317.064556) (xy 82.558364 -317.085654) (xy 82.511093 -317.099346) (xy 82.462238 -317.105278)
			(xy 82.413063 -317.103297) (xy 82.364844 -317.093453) (xy 82.318828 -317.076001) (xy 82.276207 -317.051394)
			(xy 82.238086 -317.020269) (xy 82.205451 -316.983432) (xy 82.179148 -316.941836) (xy 82.159857 -316.89656)
			(xy 82.14808 -316.848776) (xy 82.14412 -316.799722) (xy 81.805272 -316.799722) (xy 81.804777 -316.824329)
			(xy 81.796882 -316.872906) (xy 81.781298 -316.919587) (xy 81.758427 -316.963164) (xy 81.728862 -317.002508)
			(xy 81.693369 -317.0366) (xy 81.652866 -317.064556) (xy 81.608404 -317.085654) (xy 81.561133 -317.099346)
			(xy 81.512278 -317.105278) (xy 81.463103 -317.103297) (xy 81.414884 -317.093453) (xy 81.368868 -317.076001)
			(xy 81.326247 -317.051394) (xy 81.288126 -317.020269) (xy 81.255491 -316.983432) (xy 81.229188 -316.941836)
			(xy 81.209897 -316.89656) (xy 81.19812 -316.848776) (xy 81.19416 -316.799722) (xy 79.905098 -316.799722)
			(xy 79.904603 -316.824329) (xy 79.896708 -316.872906) (xy 79.881124 -316.919587) (xy 79.858253 -316.963164)
			(xy 79.828688 -317.002508) (xy 79.793195 -317.0366) (xy 79.752692 -317.064556) (xy 79.70823 -317.085654)
			(xy 79.660959 -317.099346) (xy 79.612104 -317.105278) (xy 79.562929 -317.103297) (xy 79.51471 -317.093453)
			(xy 79.468694 -317.076001) (xy 79.426073 -317.051394) (xy 79.387952 -317.020269) (xy 79.355317 -316.983432)
			(xy 79.329014 -316.941836) (xy 79.309723 -316.89656) (xy 79.297946 -316.848776) (xy 79.293986 -316.799722)
			(xy 78.005178 -316.799722) (xy 78.004683 -316.824329) (xy 77.996788 -316.872906) (xy 77.981204 -316.919587)
			(xy 77.958333 -316.963164) (xy 77.928768 -317.002508) (xy 77.893275 -317.0366) (xy 77.852772 -317.064556)
			(xy 77.80831 -317.085654) (xy 77.761039 -317.099346) (xy 77.712184 -317.105278) (xy 77.663009 -317.103297)
			(xy 77.61479 -317.093453) (xy 77.568774 -317.076001) (xy 77.526153 -317.051394) (xy 77.488032 -317.020269)
			(xy 77.455397 -316.983432) (xy 77.429094 -316.941836) (xy 77.409803 -316.89656) (xy 77.398026 -316.848776)
			(xy 77.394066 -316.799722) (xy 76.105258 -316.799722) (xy 76.104763 -316.824329) (xy 76.096868 -316.872906)
			(xy 76.081284 -316.919587) (xy 76.058413 -316.963164) (xy 76.028848 -317.002508) (xy 75.993355 -317.0366)
			(xy 75.952852 -317.064556) (xy 75.90839 -317.085654) (xy 75.861119 -317.099346) (xy 75.812264 -317.105278)
			(xy 75.763089 -317.103297) (xy 75.71487 -317.093453) (xy 75.668854 -317.076001) (xy 75.626233 -317.051394)
			(xy 75.588112 -317.020269) (xy 75.555477 -316.983432) (xy 75.529174 -316.941836) (xy 75.509883 -316.89656)
			(xy 75.498106 -316.848776) (xy 75.494146 -316.799722) (xy 74.205084 -316.799722) (xy 74.204589 -316.824329)
			(xy 74.196694 -316.872906) (xy 74.18111 -316.919587) (xy 74.158239 -316.963164) (xy 74.128674 -317.002508)
			(xy 74.093181 -317.0366) (xy 74.052678 -317.064556) (xy 74.008216 -317.085654) (xy 73.960945 -317.099346)
			(xy 73.91209 -317.105278) (xy 73.862915 -317.103297) (xy 73.814696 -317.093453) (xy 73.76868 -317.076001)
			(xy 73.726059 -317.051394) (xy 73.687938 -317.020269) (xy 73.655303 -316.983432) (xy 73.629 -316.941836)
			(xy 73.609709 -316.89656) (xy 73.597932 -316.848776) (xy 73.593972 -316.799722) (xy 0.508 -316.799722)
			(xy 0.508 -317.749936) (xy 74.544186 -317.749936) (xy 74.548146 -317.700882) (xy 74.559923 -317.653098)
			(xy 74.579214 -317.607822) (xy 74.605517 -317.566226) (xy 74.638152 -317.529389) (xy 74.676273 -317.498264)
			(xy 74.718894 -317.473657) (xy 74.76491 -317.456205) (xy 74.813129 -317.446361) (xy 74.862304 -317.44438)
			(xy 74.911159 -317.450312) (xy 74.95843 -317.464004) (xy 75.002892 -317.485102) (xy 75.043395 -317.513058)
			(xy 75.078888 -317.54715) (xy 75.108453 -317.586494) (xy 75.131324 -317.630071) (xy 75.146908 -317.676752)
			(xy 75.154803 -317.725329) (xy 75.155298 -317.749936) (xy 76.444106 -317.749936) (xy 76.448066 -317.700882)
			(xy 76.459843 -317.653098) (xy 76.479134 -317.607822) (xy 76.505437 -317.566226) (xy 76.538072 -317.529389)
			(xy 76.576193 -317.498264) (xy 76.618814 -317.473657) (xy 76.66483 -317.456205) (xy 76.713049 -317.446361)
			(xy 76.762224 -317.44438) (xy 76.811079 -317.450312) (xy 76.85835 -317.464004) (xy 76.902812 -317.485102)
			(xy 76.943315 -317.513058) (xy 76.978808 -317.54715) (xy 77.008373 -317.586494) (xy 77.031244 -317.630071)
			(xy 77.046828 -317.676752) (xy 77.054723 -317.725329) (xy 77.055218 -317.749936) (xy 78.344026 -317.749936)
			(xy 78.347986 -317.700882) (xy 78.359763 -317.653098) (xy 78.379054 -317.607822) (xy 78.405357 -317.566226)
			(xy 78.437992 -317.529389) (xy 78.476113 -317.498264) (xy 78.518734 -317.473657) (xy 78.56475 -317.456205)
			(xy 78.612969 -317.446361) (xy 78.662144 -317.44438) (xy 78.710999 -317.450312) (xy 78.75827 -317.464004)
			(xy 78.802732 -317.485102) (xy 78.843235 -317.513058) (xy 78.878728 -317.54715) (xy 78.908293 -317.586494)
			(xy 78.931164 -317.630071) (xy 78.946748 -317.676752) (xy 78.954643 -317.725329) (xy 78.955138 -317.749936)
			(xy 80.243946 -317.749936) (xy 80.247906 -317.700882) (xy 80.259683 -317.653098) (xy 80.278974 -317.607822)
			(xy 80.305277 -317.566226) (xy 80.337912 -317.529389) (xy 80.376033 -317.498264) (xy 80.418654 -317.473657)
			(xy 80.46467 -317.456205) (xy 80.512889 -317.446361) (xy 80.562064 -317.44438) (xy 80.610919 -317.450312)
			(xy 80.65819 -317.464004) (xy 80.702652 -317.485102) (xy 80.743155 -317.513058) (xy 80.778648 -317.54715)
			(xy 80.808213 -317.586494) (xy 80.831084 -317.630071) (xy 80.846668 -317.676752) (xy 80.854563 -317.725329)
			(xy 80.855058 -317.749936) (xy 160.24404 -317.749936) (xy 160.248 -317.700882) (xy 160.259777 -317.653098)
			(xy 160.279068 -317.607822) (xy 160.305371 -317.566226) (xy 160.338006 -317.529389) (xy 160.376127 -317.498264)
			(xy 160.418748 -317.473657) (xy 160.464764 -317.456205) (xy 160.512983 -317.446361) (xy 160.562158 -317.44438)
			(xy 160.611013 -317.450312) (xy 160.658284 -317.464004) (xy 160.702746 -317.485102) (xy 160.743249 -317.513058)
			(xy 160.778742 -317.54715) (xy 160.808307 -317.586494) (xy 160.831178 -317.630071) (xy 160.846762 -317.676752)
			(xy 160.854657 -317.725329) (xy 160.855152 -317.749936) (xy 162.144214 -317.749936) (xy 162.148174 -317.700882)
			(xy 162.159951 -317.653098) (xy 162.179242 -317.607822) (xy 162.205545 -317.566226) (xy 162.23818 -317.529389)
			(xy 162.276301 -317.498264) (xy 162.318922 -317.473657) (xy 162.364938 -317.456205) (xy 162.413157 -317.446361)
			(xy 162.462332 -317.44438) (xy 162.511187 -317.450312) (xy 162.558458 -317.464004) (xy 162.60292 -317.485102)
			(xy 162.643423 -317.513058) (xy 162.678916 -317.54715) (xy 162.708481 -317.586494) (xy 162.731352 -317.630071)
			(xy 162.746936 -317.676752) (xy 162.754831 -317.725329) (xy 162.755326 -317.749936) (xy 164.044134 -317.749936)
			(xy 164.048094 -317.700882) (xy 164.059871 -317.653098) (xy 164.079162 -317.607822) (xy 164.105465 -317.566226)
			(xy 164.1381 -317.529389) (xy 164.176221 -317.498264) (xy 164.218842 -317.473657) (xy 164.264858 -317.456205)
			(xy 164.313077 -317.446361) (xy 164.362252 -317.44438) (xy 164.411107 -317.450312) (xy 164.458378 -317.464004)
			(xy 164.50284 -317.485102) (xy 164.543343 -317.513058) (xy 164.578836 -317.54715) (xy 164.608401 -317.586494)
			(xy 164.631272 -317.630071) (xy 164.646856 -317.676752) (xy 164.654751 -317.725329) (xy 164.655246 -317.749936)
			(xy 165.944054 -317.749936) (xy 165.948014 -317.700882) (xy 165.959791 -317.653098) (xy 165.979082 -317.607822)
			(xy 166.005385 -317.566226) (xy 166.03802 -317.529389) (xy 166.076141 -317.498264) (xy 166.118762 -317.473657)
			(xy 166.164778 -317.456205) (xy 166.212997 -317.446361) (xy 166.262172 -317.44438) (xy 166.311027 -317.450312)
			(xy 166.358298 -317.464004) (xy 166.40276 -317.485102) (xy 166.443263 -317.513058) (xy 166.478756 -317.54715)
			(xy 166.508321 -317.586494) (xy 166.531192 -317.630071) (xy 166.546776 -317.676752) (xy 166.554671 -317.725329)
			(xy 166.555166 -317.749936) (xy 183.044096 -317.749936) (xy 183.048056 -317.700882) (xy 183.059833 -317.653098)
			(xy 183.079124 -317.607822) (xy 183.105427 -317.566226) (xy 183.138062 -317.529389) (xy 183.176183 -317.498264)
			(xy 183.218804 -317.473657) (xy 183.26482 -317.456205) (xy 183.313039 -317.446361) (xy 183.362214 -317.44438)
			(xy 183.411069 -317.450312) (xy 183.45834 -317.464004) (xy 183.502802 -317.485102) (xy 183.543305 -317.513058)
			(xy 183.578798 -317.54715) (xy 183.608363 -317.586494) (xy 183.631234 -317.630071) (xy 183.646818 -317.676752)
			(xy 183.654713 -317.725329) (xy 183.655208 -317.749936) (xy 184.94427 -317.749936) (xy 184.94823 -317.700882)
			(xy 184.960007 -317.653098) (xy 184.979298 -317.607822) (xy 185.005601 -317.566226) (xy 185.038236 -317.529389)
			(xy 185.076357 -317.498264) (xy 185.118978 -317.473657) (xy 185.164994 -317.456205) (xy 185.213213 -317.446361)
			(xy 185.262388 -317.44438) (xy 185.311243 -317.450312) (xy 185.358514 -317.464004) (xy 185.402976 -317.485102)
			(xy 185.443479 -317.513058) (xy 185.478972 -317.54715) (xy 185.508537 -317.586494) (xy 185.531408 -317.630071)
			(xy 185.546992 -317.676752) (xy 185.554887 -317.725329) (xy 185.555382 -317.749936) (xy 186.84419 -317.749936)
			(xy 186.84815 -317.700882) (xy 186.859927 -317.653098) (xy 186.879218 -317.607822) (xy 186.905521 -317.566226)
			(xy 186.938156 -317.529389) (xy 186.976277 -317.498264) (xy 187.018898 -317.473657) (xy 187.064914 -317.456205)
			(xy 187.113133 -317.446361) (xy 187.162308 -317.44438) (xy 187.211163 -317.450312) (xy 187.258434 -317.464004)
			(xy 187.302896 -317.485102) (xy 187.343399 -317.513058) (xy 187.378892 -317.54715) (xy 187.408457 -317.586494)
			(xy 187.431328 -317.630071) (xy 187.446912 -317.676752) (xy 187.454807 -317.725329) (xy 187.455302 -317.749936)
			(xy 188.74411 -317.749936) (xy 188.74807 -317.700882) (xy 188.759847 -317.653098) (xy 188.779138 -317.607822)
			(xy 188.805441 -317.566226) (xy 188.838076 -317.529389) (xy 188.876197 -317.498264) (xy 188.918818 -317.473657)
			(xy 188.964834 -317.456205) (xy 189.013053 -317.446361) (xy 189.062228 -317.44438) (xy 189.111083 -317.450312)
			(xy 189.158354 -317.464004) (xy 189.202816 -317.485102) (xy 189.243319 -317.513058) (xy 189.278812 -317.54715)
			(xy 189.308377 -317.586494) (xy 189.331248 -317.630071) (xy 189.346832 -317.676752) (xy 189.354727 -317.725329)
			(xy 189.355222 -317.749936) (xy 306.744128 -317.749936) (xy 306.748088 -317.700882) (xy 306.759865 -317.653098)
			(xy 306.779156 -317.607822) (xy 306.805459 -317.566226) (xy 306.838094 -317.529389) (xy 306.876215 -317.498264)
			(xy 306.918836 -317.473657) (xy 306.964852 -317.456205) (xy 307.013071 -317.446361) (xy 307.062246 -317.44438)
			(xy 307.111101 -317.450312) (xy 307.158372 -317.464004) (xy 307.202834 -317.485102) (xy 307.243337 -317.513058)
			(xy 307.27883 -317.54715) (xy 307.308395 -317.586494) (xy 307.331266 -317.630071) (xy 307.34685 -317.676752)
			(xy 307.354745 -317.725329) (xy 307.35524 -317.749936) (xy 308.644048 -317.749936) (xy 308.648008 -317.700882)
			(xy 308.659785 -317.653098) (xy 308.679076 -317.607822) (xy 308.705379 -317.566226) (xy 308.738014 -317.529389)
			(xy 308.776135 -317.498264) (xy 308.818756 -317.473657) (xy 308.864772 -317.456205) (xy 308.912991 -317.446361)
			(xy 308.962166 -317.44438) (xy 309.011021 -317.450312) (xy 309.058292 -317.464004) (xy 309.102754 -317.485102)
			(xy 309.143257 -317.513058) (xy 309.17875 -317.54715) (xy 309.208315 -317.586494) (xy 309.231186 -317.630071)
			(xy 309.24677 -317.676752) (xy 309.254665 -317.725329) (xy 309.25516 -317.749936) (xy 310.543968 -317.749936)
			(xy 310.547928 -317.700882) (xy 310.559705 -317.653098) (xy 310.578996 -317.607822) (xy 310.605299 -317.566226)
			(xy 310.637934 -317.529389) (xy 310.676055 -317.498264) (xy 310.718676 -317.473657) (xy 310.764692 -317.456205)
			(xy 310.812911 -317.446361) (xy 310.862086 -317.44438) (xy 310.910941 -317.450312) (xy 310.958212 -317.464004)
			(xy 311.002674 -317.485102) (xy 311.043177 -317.513058) (xy 311.07867 -317.54715) (xy 311.108235 -317.586494)
			(xy 311.131106 -317.630071) (xy 311.14669 -317.676752) (xy 311.154585 -317.725329) (xy 311.15508 -317.749936)
			(xy 312.443888 -317.749936) (xy 312.447848 -317.700882) (xy 312.459625 -317.653098) (xy 312.478916 -317.607822)
			(xy 312.505219 -317.566226) (xy 312.537854 -317.529389) (xy 312.575975 -317.498264) (xy 312.618596 -317.473657)
			(xy 312.664612 -317.456205) (xy 312.712831 -317.446361) (xy 312.762006 -317.44438) (xy 312.810861 -317.450312)
			(xy 312.858132 -317.464004) (xy 312.902594 -317.485102) (xy 312.943097 -317.513058) (xy 312.97859 -317.54715)
			(xy 313.008155 -317.586494) (xy 313.031026 -317.630071) (xy 313.04661 -317.676752) (xy 313.054505 -317.725329)
			(xy 313.055 -317.749936) (xy 392.443982 -317.749936) (xy 392.447942 -317.700882) (xy 392.459719 -317.653098)
			(xy 392.47901 -317.607822) (xy 392.505313 -317.566226) (xy 392.537948 -317.529389) (xy 392.576069 -317.498264)
			(xy 392.61869 -317.473657) (xy 392.664706 -317.456205) (xy 392.712925 -317.446361) (xy 392.7621 -317.44438)
			(xy 392.810955 -317.450312) (xy 392.858226 -317.464004) (xy 392.902688 -317.485102) (xy 392.943191 -317.513058)
			(xy 392.978684 -317.54715) (xy 393.008249 -317.586494) (xy 393.03112 -317.630071) (xy 393.046704 -317.676752)
			(xy 393.054599 -317.725329) (xy 393.055094 -317.749936) (xy 394.344156 -317.749936) (xy 394.348116 -317.700882)
			(xy 394.359893 -317.653098) (xy 394.379184 -317.607822) (xy 394.405487 -317.566226) (xy 394.438122 -317.529389)
			(xy 394.476243 -317.498264) (xy 394.518864 -317.473657) (xy 394.56488 -317.456205) (xy 394.613099 -317.446361)
			(xy 394.662274 -317.44438) (xy 394.711129 -317.450312) (xy 394.7584 -317.464004) (xy 394.802862 -317.485102)
			(xy 394.843365 -317.513058) (xy 394.878858 -317.54715) (xy 394.908423 -317.586494) (xy 394.931294 -317.630071)
			(xy 394.946878 -317.676752) (xy 394.954773 -317.725329) (xy 394.955268 -317.749936) (xy 396.244076 -317.749936)
			(xy 396.248036 -317.700882) (xy 396.259813 -317.653098) (xy 396.279104 -317.607822) (xy 396.305407 -317.566226)
			(xy 396.338042 -317.529389) (xy 396.376163 -317.498264) (xy 396.418784 -317.473657) (xy 396.4648 -317.456205)
			(xy 396.513019 -317.446361) (xy 396.562194 -317.44438) (xy 396.611049 -317.450312) (xy 396.65832 -317.464004)
			(xy 396.702782 -317.485102) (xy 396.743285 -317.513058) (xy 396.778778 -317.54715) (xy 396.808343 -317.586494)
			(xy 396.831214 -317.630071) (xy 396.846798 -317.676752) (xy 396.854693 -317.725329) (xy 396.855188 -317.749936)
			(xy 398.143996 -317.749936) (xy 398.147956 -317.700882) (xy 398.159733 -317.653098) (xy 398.179024 -317.607822)
			(xy 398.205327 -317.566226) (xy 398.237962 -317.529389) (xy 398.276083 -317.498264) (xy 398.318704 -317.473657)
			(xy 398.36472 -317.456205) (xy 398.412939 -317.446361) (xy 398.462114 -317.44438) (xy 398.510969 -317.450312)
			(xy 398.55824 -317.464004) (xy 398.602702 -317.485102) (xy 398.643205 -317.513058) (xy 398.678698 -317.54715)
			(xy 398.708263 -317.586494) (xy 398.731134 -317.630071) (xy 398.746718 -317.676752) (xy 398.754613 -317.725329)
			(xy 398.755108 -317.749936) (xy 415.244038 -317.749936) (xy 415.247998 -317.700882) (xy 415.259775 -317.653098)
			(xy 415.279066 -317.607822) (xy 415.305369 -317.566226) (xy 415.338004 -317.529389) (xy 415.376125 -317.498264)
			(xy 415.418746 -317.473657) (xy 415.464762 -317.456205) (xy 415.512981 -317.446361) (xy 415.562156 -317.44438)
			(xy 415.611011 -317.450312) (xy 415.658282 -317.464004) (xy 415.702744 -317.485102) (xy 415.743247 -317.513058)
			(xy 415.77874 -317.54715) (xy 415.808305 -317.586494) (xy 415.831176 -317.630071) (xy 415.84676 -317.676752)
			(xy 415.854655 -317.725329) (xy 415.85515 -317.749936) (xy 417.144212 -317.749936) (xy 417.148172 -317.700882)
			(xy 417.159949 -317.653098) (xy 417.17924 -317.607822) (xy 417.205543 -317.566226) (xy 417.238178 -317.529389)
			(xy 417.276299 -317.498264) (xy 417.31892 -317.473657) (xy 417.364936 -317.456205) (xy 417.413155 -317.446361)
			(xy 417.46233 -317.44438) (xy 417.511185 -317.450312) (xy 417.558456 -317.464004) (xy 417.602918 -317.485102)
			(xy 417.643421 -317.513058) (xy 417.678914 -317.54715) (xy 417.708479 -317.586494) (xy 417.73135 -317.630071)
			(xy 417.746934 -317.676752) (xy 417.754829 -317.725329) (xy 417.755324 -317.749936) (xy 419.044132 -317.749936)
			(xy 419.048092 -317.700882) (xy 419.059869 -317.653098) (xy 419.07916 -317.607822) (xy 419.105463 -317.566226)
			(xy 419.138098 -317.529389) (xy 419.176219 -317.498264) (xy 419.21884 -317.473657) (xy 419.264856 -317.456205)
			(xy 419.313075 -317.446361) (xy 419.36225 -317.44438) (xy 419.411105 -317.450312) (xy 419.458376 -317.464004)
			(xy 419.502838 -317.485102) (xy 419.543341 -317.513058) (xy 419.578834 -317.54715) (xy 419.608399 -317.586494)
			(xy 419.63127 -317.630071) (xy 419.646854 -317.676752) (xy 419.654749 -317.725329) (xy 419.655244 -317.749936)
			(xy 420.944052 -317.749936) (xy 420.948012 -317.700882) (xy 420.959789 -317.653098) (xy 420.97908 -317.607822)
			(xy 421.005383 -317.566226) (xy 421.038018 -317.529389) (xy 421.076139 -317.498264) (xy 421.11876 -317.473657)
			(xy 421.164776 -317.456205) (xy 421.212995 -317.446361) (xy 421.26217 -317.44438) (xy 421.311025 -317.450312)
			(xy 421.358296 -317.464004) (xy 421.402758 -317.485102) (xy 421.443261 -317.513058) (xy 421.478754 -317.54715)
			(xy 421.508319 -317.586494) (xy 421.53119 -317.630071) (xy 421.546774 -317.676752) (xy 421.554669 -317.725329)
			(xy 421.555164 -317.749936) (xy 421.554669 -317.774543) (xy 421.546774 -317.82312) (xy 421.53119 -317.869801)
			(xy 421.508319 -317.913378) (xy 421.478754 -317.952722) (xy 421.443261 -317.986814) (xy 421.402758 -318.01477)
			(xy 421.358296 -318.035868) (xy 421.311025 -318.04956) (xy 421.26217 -318.055492) (xy 421.212995 -318.053511)
			(xy 421.164776 -318.043667) (xy 421.11876 -318.026215) (xy 421.076139 -318.001608) (xy 421.038018 -317.970483)
			(xy 421.005383 -317.933646) (xy 420.97908 -317.89205) (xy 420.959789 -317.846774) (xy 420.948012 -317.79899)
			(xy 420.944052 -317.749936) (xy 419.655244 -317.749936) (xy 419.654749 -317.774543) (xy 419.646854 -317.82312)
			(xy 419.63127 -317.869801) (xy 419.608399 -317.913378) (xy 419.578834 -317.952722) (xy 419.543341 -317.986814)
			(xy 419.502838 -318.01477) (xy 419.458376 -318.035868) (xy 419.411105 -318.04956) (xy 419.36225 -318.055492)
			(xy 419.313075 -318.053511) (xy 419.264856 -318.043667) (xy 419.21884 -318.026215) (xy 419.176219 -318.001608)
			(xy 419.138098 -317.970483) (xy 419.105463 -317.933646) (xy 419.07916 -317.89205) (xy 419.059869 -317.846774)
			(xy 419.048092 -317.79899) (xy 419.044132 -317.749936) (xy 417.755324 -317.749936) (xy 417.754829 -317.774543)
			(xy 417.746934 -317.82312) (xy 417.73135 -317.869801) (xy 417.708479 -317.913378) (xy 417.678914 -317.952722)
			(xy 417.643421 -317.986814) (xy 417.602918 -318.01477) (xy 417.558456 -318.035868) (xy 417.511185 -318.04956)
			(xy 417.46233 -318.055492) (xy 417.413155 -318.053511) (xy 417.364936 -318.043667) (xy 417.31892 -318.026215)
			(xy 417.276299 -318.001608) (xy 417.238178 -317.970483) (xy 417.205543 -317.933646) (xy 417.17924 -317.89205)
			(xy 417.159949 -317.846774) (xy 417.148172 -317.79899) (xy 417.144212 -317.749936) (xy 415.85515 -317.749936)
			(xy 415.854655 -317.774543) (xy 415.84676 -317.82312) (xy 415.831176 -317.869801) (xy 415.808305 -317.913378)
			(xy 415.77874 -317.952722) (xy 415.743247 -317.986814) (xy 415.702744 -318.01477) (xy 415.658282 -318.035868)
			(xy 415.611011 -318.04956) (xy 415.562156 -318.055492) (xy 415.512981 -318.053511) (xy 415.464762 -318.043667)
			(xy 415.418746 -318.026215) (xy 415.376125 -318.001608) (xy 415.338004 -317.970483) (xy 415.305369 -317.933646)
			(xy 415.279066 -317.89205) (xy 415.259775 -317.846774) (xy 415.247998 -317.79899) (xy 415.244038 -317.749936)
			(xy 398.755108 -317.749936) (xy 398.754613 -317.774543) (xy 398.746718 -317.82312) (xy 398.731134 -317.869801)
			(xy 398.708263 -317.913378) (xy 398.678698 -317.952722) (xy 398.643205 -317.986814) (xy 398.602702 -318.01477)
			(xy 398.55824 -318.035868) (xy 398.510969 -318.04956) (xy 398.462114 -318.055492) (xy 398.412939 -318.053511)
			(xy 398.36472 -318.043667) (xy 398.318704 -318.026215) (xy 398.276083 -318.001608) (xy 398.237962 -317.970483)
			(xy 398.205327 -317.933646) (xy 398.179024 -317.89205) (xy 398.159733 -317.846774) (xy 398.147956 -317.79899)
			(xy 398.143996 -317.749936) (xy 396.855188 -317.749936) (xy 396.854693 -317.774543) (xy 396.846798 -317.82312)
			(xy 396.831214 -317.869801) (xy 396.808343 -317.913378) (xy 396.778778 -317.952722) (xy 396.743285 -317.986814)
			(xy 396.702782 -318.01477) (xy 396.65832 -318.035868) (xy 396.611049 -318.04956) (xy 396.562194 -318.055492)
			(xy 396.513019 -318.053511) (xy 396.4648 -318.043667) (xy 396.418784 -318.026215) (xy 396.376163 -318.001608)
			(xy 396.338042 -317.970483) (xy 396.305407 -317.933646) (xy 396.279104 -317.89205) (xy 396.259813 -317.846774)
			(xy 396.248036 -317.79899) (xy 396.244076 -317.749936) (xy 394.955268 -317.749936) (xy 394.954773 -317.774543)
			(xy 394.946878 -317.82312) (xy 394.931294 -317.869801) (xy 394.908423 -317.913378) (xy 394.878858 -317.952722)
			(xy 394.843365 -317.986814) (xy 394.802862 -318.01477) (xy 394.7584 -318.035868) (xy 394.711129 -318.04956)
			(xy 394.662274 -318.055492) (xy 394.613099 -318.053511) (xy 394.56488 -318.043667) (xy 394.518864 -318.026215)
			(xy 394.476243 -318.001608) (xy 394.438122 -317.970483) (xy 394.405487 -317.933646) (xy 394.379184 -317.89205)
			(xy 394.359893 -317.846774) (xy 394.348116 -317.79899) (xy 394.344156 -317.749936) (xy 393.055094 -317.749936)
			(xy 393.054599 -317.774543) (xy 393.046704 -317.82312) (xy 393.03112 -317.869801) (xy 393.008249 -317.913378)
			(xy 392.978684 -317.952722) (xy 392.943191 -317.986814) (xy 392.902688 -318.01477) (xy 392.858226 -318.035868)
			(xy 392.810955 -318.04956) (xy 392.7621 -318.055492) (xy 392.712925 -318.053511) (xy 392.664706 -318.043667)
			(xy 392.61869 -318.026215) (xy 392.576069 -318.001608) (xy 392.537948 -317.970483) (xy 392.505313 -317.933646)
			(xy 392.47901 -317.89205) (xy 392.459719 -317.846774) (xy 392.447942 -317.79899) (xy 392.443982 -317.749936)
			(xy 313.055 -317.749936) (xy 313.054505 -317.774543) (xy 313.04661 -317.82312) (xy 313.031026 -317.869801)
			(xy 313.008155 -317.913378) (xy 312.97859 -317.952722) (xy 312.943097 -317.986814) (xy 312.902594 -318.01477)
			(xy 312.858132 -318.035868) (xy 312.810861 -318.04956) (xy 312.762006 -318.055492) (xy 312.712831 -318.053511)
			(xy 312.664612 -318.043667) (xy 312.618596 -318.026215) (xy 312.575975 -318.001608) (xy 312.537854 -317.970483)
			(xy 312.505219 -317.933646) (xy 312.478916 -317.89205) (xy 312.459625 -317.846774) (xy 312.447848 -317.79899)
			(xy 312.443888 -317.749936) (xy 311.15508 -317.749936) (xy 311.154585 -317.774543) (xy 311.14669 -317.82312)
			(xy 311.131106 -317.869801) (xy 311.108235 -317.913378) (xy 311.07867 -317.952722) (xy 311.043177 -317.986814)
			(xy 311.002674 -318.01477) (xy 310.958212 -318.035868) (xy 310.910941 -318.04956) (xy 310.862086 -318.055492)
			(xy 310.812911 -318.053511) (xy 310.764692 -318.043667) (xy 310.718676 -318.026215) (xy 310.676055 -318.001608)
			(xy 310.637934 -317.970483) (xy 310.605299 -317.933646) (xy 310.578996 -317.89205) (xy 310.559705 -317.846774)
			(xy 310.547928 -317.79899) (xy 310.543968 -317.749936) (xy 309.25516 -317.749936) (xy 309.254665 -317.774543)
			(xy 309.24677 -317.82312) (xy 309.231186 -317.869801) (xy 309.208315 -317.913378) (xy 309.17875 -317.952722)
			(xy 309.143257 -317.986814) (xy 309.102754 -318.01477) (xy 309.058292 -318.035868) (xy 309.011021 -318.04956)
			(xy 308.962166 -318.055492) (xy 308.912991 -318.053511) (xy 308.864772 -318.043667) (xy 308.818756 -318.026215)
			(xy 308.776135 -318.001608) (xy 308.738014 -317.970483) (xy 308.705379 -317.933646) (xy 308.679076 -317.89205)
			(xy 308.659785 -317.846774) (xy 308.648008 -317.79899) (xy 308.644048 -317.749936) (xy 307.35524 -317.749936)
			(xy 307.354745 -317.774543) (xy 307.34685 -317.82312) (xy 307.331266 -317.869801) (xy 307.308395 -317.913378)
			(xy 307.27883 -317.952722) (xy 307.243337 -317.986814) (xy 307.202834 -318.01477) (xy 307.158372 -318.035868)
			(xy 307.111101 -318.04956) (xy 307.062246 -318.055492) (xy 307.013071 -318.053511) (xy 306.964852 -318.043667)
			(xy 306.918836 -318.026215) (xy 306.876215 -318.001608) (xy 306.838094 -317.970483) (xy 306.805459 -317.933646)
			(xy 306.779156 -317.89205) (xy 306.759865 -317.846774) (xy 306.748088 -317.79899) (xy 306.744128 -317.749936)
			(xy 189.355222 -317.749936) (xy 189.354727 -317.774543) (xy 189.346832 -317.82312) (xy 189.331248 -317.869801)
			(xy 189.308377 -317.913378) (xy 189.278812 -317.952722) (xy 189.243319 -317.986814) (xy 189.202816 -318.01477)
			(xy 189.158354 -318.035868) (xy 189.111083 -318.04956) (xy 189.062228 -318.055492) (xy 189.013053 -318.053511)
			(xy 188.964834 -318.043667) (xy 188.918818 -318.026215) (xy 188.876197 -318.001608) (xy 188.838076 -317.970483)
			(xy 188.805441 -317.933646) (xy 188.779138 -317.89205) (xy 188.759847 -317.846774) (xy 188.74807 -317.79899)
			(xy 188.74411 -317.749936) (xy 187.455302 -317.749936) (xy 187.454807 -317.774543) (xy 187.446912 -317.82312)
			(xy 187.431328 -317.869801) (xy 187.408457 -317.913378) (xy 187.378892 -317.952722) (xy 187.343399 -317.986814)
			(xy 187.302896 -318.01477) (xy 187.258434 -318.035868) (xy 187.211163 -318.04956) (xy 187.162308 -318.055492)
			(xy 187.113133 -318.053511) (xy 187.064914 -318.043667) (xy 187.018898 -318.026215) (xy 186.976277 -318.001608)
			(xy 186.938156 -317.970483) (xy 186.905521 -317.933646) (xy 186.879218 -317.89205) (xy 186.859927 -317.846774)
			(xy 186.84815 -317.79899) (xy 186.84419 -317.749936) (xy 185.555382 -317.749936) (xy 185.554887 -317.774543)
			(xy 185.546992 -317.82312) (xy 185.531408 -317.869801) (xy 185.508537 -317.913378) (xy 185.478972 -317.952722)
			(xy 185.443479 -317.986814) (xy 185.402976 -318.01477) (xy 185.358514 -318.035868) (xy 185.311243 -318.04956)
			(xy 185.262388 -318.055492) (xy 185.213213 -318.053511) (xy 185.164994 -318.043667) (xy 185.118978 -318.026215)
			(xy 185.076357 -318.001608) (xy 185.038236 -317.970483) (xy 185.005601 -317.933646) (xy 184.979298 -317.89205)
			(xy 184.960007 -317.846774) (xy 184.94823 -317.79899) (xy 184.94427 -317.749936) (xy 183.655208 -317.749936)
			(xy 183.654713 -317.774543) (xy 183.646818 -317.82312) (xy 183.631234 -317.869801) (xy 183.608363 -317.913378)
			(xy 183.578798 -317.952722) (xy 183.543305 -317.986814) (xy 183.502802 -318.01477) (xy 183.45834 -318.035868)
			(xy 183.411069 -318.04956) (xy 183.362214 -318.055492) (xy 183.313039 -318.053511) (xy 183.26482 -318.043667)
			(xy 183.218804 -318.026215) (xy 183.176183 -318.001608) (xy 183.138062 -317.970483) (xy 183.105427 -317.933646)
			(xy 183.079124 -317.89205) (xy 183.059833 -317.846774) (xy 183.048056 -317.79899) (xy 183.044096 -317.749936)
			(xy 166.555166 -317.749936) (xy 166.554671 -317.774543) (xy 166.546776 -317.82312) (xy 166.531192 -317.869801)
			(xy 166.508321 -317.913378) (xy 166.478756 -317.952722) (xy 166.443263 -317.986814) (xy 166.40276 -318.01477)
			(xy 166.358298 -318.035868) (xy 166.311027 -318.04956) (xy 166.262172 -318.055492) (xy 166.212997 -318.053511)
			(xy 166.164778 -318.043667) (xy 166.118762 -318.026215) (xy 166.076141 -318.001608) (xy 166.03802 -317.970483)
			(xy 166.005385 -317.933646) (xy 165.979082 -317.89205) (xy 165.959791 -317.846774) (xy 165.948014 -317.79899)
			(xy 165.944054 -317.749936) (xy 164.655246 -317.749936) (xy 164.654751 -317.774543) (xy 164.646856 -317.82312)
			(xy 164.631272 -317.869801) (xy 164.608401 -317.913378) (xy 164.578836 -317.952722) (xy 164.543343 -317.986814)
			(xy 164.50284 -318.01477) (xy 164.458378 -318.035868) (xy 164.411107 -318.04956) (xy 164.362252 -318.055492)
			(xy 164.313077 -318.053511) (xy 164.264858 -318.043667) (xy 164.218842 -318.026215) (xy 164.176221 -318.001608)
			(xy 164.1381 -317.970483) (xy 164.105465 -317.933646) (xy 164.079162 -317.89205) (xy 164.059871 -317.846774)
			(xy 164.048094 -317.79899) (xy 164.044134 -317.749936) (xy 162.755326 -317.749936) (xy 162.754831 -317.774543)
			(xy 162.746936 -317.82312) (xy 162.731352 -317.869801) (xy 162.708481 -317.913378) (xy 162.678916 -317.952722)
			(xy 162.643423 -317.986814) (xy 162.60292 -318.01477) (xy 162.558458 -318.035868) (xy 162.511187 -318.04956)
			(xy 162.462332 -318.055492) (xy 162.413157 -318.053511) (xy 162.364938 -318.043667) (xy 162.318922 -318.026215)
			(xy 162.276301 -318.001608) (xy 162.23818 -317.970483) (xy 162.205545 -317.933646) (xy 162.179242 -317.89205)
			(xy 162.159951 -317.846774) (xy 162.148174 -317.79899) (xy 162.144214 -317.749936) (xy 160.855152 -317.749936)
			(xy 160.854657 -317.774543) (xy 160.846762 -317.82312) (xy 160.831178 -317.869801) (xy 160.808307 -317.913378)
			(xy 160.778742 -317.952722) (xy 160.743249 -317.986814) (xy 160.702746 -318.01477) (xy 160.658284 -318.035868)
			(xy 160.611013 -318.04956) (xy 160.562158 -318.055492) (xy 160.512983 -318.053511) (xy 160.464764 -318.043667)
			(xy 160.418748 -318.026215) (xy 160.376127 -318.001608) (xy 160.338006 -317.970483) (xy 160.305371 -317.933646)
			(xy 160.279068 -317.89205) (xy 160.259777 -317.846774) (xy 160.248 -317.79899) (xy 160.24404 -317.749936)
			(xy 80.855058 -317.749936) (xy 80.854563 -317.774543) (xy 80.846668 -317.82312) (xy 80.831084 -317.869801)
			(xy 80.808213 -317.913378) (xy 80.778648 -317.952722) (xy 80.743155 -317.986814) (xy 80.702652 -318.01477)
			(xy 80.65819 -318.035868) (xy 80.610919 -318.04956) (xy 80.562064 -318.055492) (xy 80.512889 -318.053511)
			(xy 80.46467 -318.043667) (xy 80.418654 -318.026215) (xy 80.376033 -318.001608) (xy 80.337912 -317.970483)
			(xy 80.305277 -317.933646) (xy 80.278974 -317.89205) (xy 80.259683 -317.846774) (xy 80.247906 -317.79899)
			(xy 80.243946 -317.749936) (xy 78.955138 -317.749936) (xy 78.954643 -317.774543) (xy 78.946748 -317.82312)
			(xy 78.931164 -317.869801) (xy 78.908293 -317.913378) (xy 78.878728 -317.952722) (xy 78.843235 -317.986814)
			(xy 78.802732 -318.01477) (xy 78.75827 -318.035868) (xy 78.710999 -318.04956) (xy 78.662144 -318.055492)
			(xy 78.612969 -318.053511) (xy 78.56475 -318.043667) (xy 78.518734 -318.026215) (xy 78.476113 -318.001608)
			(xy 78.437992 -317.970483) (xy 78.405357 -317.933646) (xy 78.379054 -317.89205) (xy 78.359763 -317.846774)
			(xy 78.347986 -317.79899) (xy 78.344026 -317.749936) (xy 77.055218 -317.749936) (xy 77.054723 -317.774543)
			(xy 77.046828 -317.82312) (xy 77.031244 -317.869801) (xy 77.008373 -317.913378) (xy 76.978808 -317.952722)
			(xy 76.943315 -317.986814) (xy 76.902812 -318.01477) (xy 76.85835 -318.035868) (xy 76.811079 -318.04956)
			(xy 76.762224 -318.055492) (xy 76.713049 -318.053511) (xy 76.66483 -318.043667) (xy 76.618814 -318.026215)
			(xy 76.576193 -318.001608) (xy 76.538072 -317.970483) (xy 76.505437 -317.933646) (xy 76.479134 -317.89205)
			(xy 76.459843 -317.846774) (xy 76.448066 -317.79899) (xy 76.444106 -317.749936) (xy 75.155298 -317.749936)
			(xy 75.154803 -317.774543) (xy 75.146908 -317.82312) (xy 75.131324 -317.869801) (xy 75.108453 -317.913378)
			(xy 75.078888 -317.952722) (xy 75.043395 -317.986814) (xy 75.002892 -318.01477) (xy 74.95843 -318.035868)
			(xy 74.911159 -318.04956) (xy 74.862304 -318.055492) (xy 74.813129 -318.053511) (xy 74.76491 -318.043667)
			(xy 74.718894 -318.026215) (xy 74.676273 -318.001608) (xy 74.638152 -317.970483) (xy 74.605517 -317.933646)
			(xy 74.579214 -317.89205) (xy 74.559923 -317.846774) (xy 74.548146 -317.79899) (xy 74.544186 -317.749936)
			(xy 0.508 -317.749936) (xy 0.508 -320.900044) (xy 26.882353 -320.900044) (xy 26.886342 -320.751504)
			(xy 26.898299 -320.603391) (xy 26.918189 -320.456134) (xy 26.945954 -320.310158) (xy 26.981515 -320.165881)
			(xy 27.024769 -320.023722) (xy 27.075591 -319.884089) (xy 27.133835 -319.747386) (xy 27.199333 -319.614006)
			(xy 27.271896 -319.484334) (xy 27.351314 -319.358744) (xy 27.437359 -319.237597) (xy 27.529783 -319.121244)
			(xy 27.628319 -319.01002) (xy 27.732683 -318.904245) (xy 27.842575 -318.804225) (xy 27.957676 -318.710247)
			(xy 28.077656 -318.622583) (xy 28.202169 -318.541486) (xy 28.330855 -318.467189) (xy 28.463344 -318.399907)
			(xy 28.599253 -318.339833) (xy 28.738191 -318.287141) (xy 28.879757 -318.241982) (xy 29.023543 -318.204487)
			(xy 29.169134 -318.174765) (xy 29.31611 -318.1529) (xy 29.464049 -318.138956) (xy 29.612522 -318.132972)
			(xy 29.761103 -318.134967) (xy 29.909362 -318.144935) (xy 30.056873 -318.162846) (xy 30.203209 -318.188649)
			(xy 30.34795 -318.222269) (xy 30.490677 -318.263611) (xy 30.63098 -318.312554) (xy 30.768453 -318.368957)
			(xy 30.9027 -318.432658) (xy 31.033335 -318.503474) (xy 31.15998 -318.581199) (xy 31.28227 -318.66561)
			(xy 31.326643 -318.699896) (xy 74.544186 -318.699896) (xy 74.548146 -318.650842) (xy 74.559923 -318.603058)
			(xy 74.579214 -318.557782) (xy 74.605517 -318.516186) (xy 74.638152 -318.479349) (xy 74.676273 -318.448224)
			(xy 74.718894 -318.423617) (xy 74.76491 -318.406165) (xy 74.813129 -318.396321) (xy 74.862304 -318.39434)
			(xy 74.911159 -318.400272) (xy 74.95843 -318.413964) (xy 75.002892 -318.435062) (xy 75.043395 -318.463018)
			(xy 75.078888 -318.49711) (xy 75.108453 -318.536454) (xy 75.131324 -318.580031) (xy 75.146908 -318.626712)
			(xy 75.154803 -318.675289) (xy 75.155298 -318.699896) (xy 76.444106 -318.699896) (xy 76.448066 -318.650842)
			(xy 76.459843 -318.603058) (xy 76.479134 -318.557782) (xy 76.505437 -318.516186) (xy 76.538072 -318.479349)
			(xy 76.576193 -318.448224) (xy 76.618814 -318.423617) (xy 76.66483 -318.406165) (xy 76.713049 -318.396321)
			(xy 76.762224 -318.39434) (xy 76.811079 -318.400272) (xy 76.85835 -318.413964) (xy 76.902812 -318.435062)
			(xy 76.943315 -318.463018) (xy 76.978808 -318.49711) (xy 77.008373 -318.536454) (xy 77.031244 -318.580031)
			(xy 77.046828 -318.626712) (xy 77.054723 -318.675289) (xy 77.055218 -318.699896) (xy 78.344026 -318.699896)
			(xy 78.347986 -318.650842) (xy 78.359763 -318.603058) (xy 78.379054 -318.557782) (xy 78.405357 -318.516186)
			(xy 78.437992 -318.479349) (xy 78.476113 -318.448224) (xy 78.518734 -318.423617) (xy 78.56475 -318.406165)
			(xy 78.612969 -318.396321) (xy 78.662144 -318.39434) (xy 78.710999 -318.400272) (xy 78.75827 -318.413964)
			(xy 78.802732 -318.435062) (xy 78.843235 -318.463018) (xy 78.878728 -318.49711) (xy 78.908293 -318.536454)
			(xy 78.931164 -318.580031) (xy 78.946748 -318.626712) (xy 78.954643 -318.675289) (xy 78.955138 -318.699896)
			(xy 80.243946 -318.699896) (xy 80.247906 -318.650842) (xy 80.259683 -318.603058) (xy 80.278974 -318.557782)
			(xy 80.305277 -318.516186) (xy 80.337912 -318.479349) (xy 80.376033 -318.448224) (xy 80.418654 -318.423617)
			(xy 80.46467 -318.406165) (xy 80.512889 -318.396321) (xy 80.562064 -318.39434) (xy 80.610919 -318.400272)
			(xy 80.65819 -318.413964) (xy 80.702652 -318.435062) (xy 80.743155 -318.463018) (xy 80.778648 -318.49711)
			(xy 80.808213 -318.536454) (xy 80.831084 -318.580031) (xy 80.846668 -318.626712) (xy 80.854563 -318.675289)
			(xy 80.855058 -318.699896) (xy 80.854563 -318.724503) (xy 80.846668 -318.77308) (xy 80.831084 -318.819761)
			(xy 80.808213 -318.863338) (xy 80.778648 -318.902682) (xy 80.743155 -318.936774) (xy 80.702652 -318.96473)
			(xy 80.65819 -318.985828) (xy 80.610919 -318.99952) (xy 80.562064 -319.005452) (xy 80.512889 -319.003471)
			(xy 80.46467 -318.993627) (xy 80.418654 -318.976175) (xy 80.376033 -318.951568) (xy 80.337912 -318.920443)
			(xy 80.305277 -318.883606) (xy 80.278974 -318.84201) (xy 80.259683 -318.796734) (xy 80.247906 -318.74895)
			(xy 80.243946 -318.699896) (xy 78.955138 -318.699896) (xy 78.954643 -318.724503) (xy 78.946748 -318.77308)
			(xy 78.931164 -318.819761) (xy 78.908293 -318.863338) (xy 78.878728 -318.902682) (xy 78.843235 -318.936774)
			(xy 78.802732 -318.96473) (xy 78.75827 -318.985828) (xy 78.710999 -318.99952) (xy 78.662144 -319.005452)
			(xy 78.612969 -319.003471) (xy 78.56475 -318.993627) (xy 78.518734 -318.976175) (xy 78.476113 -318.951568)
			(xy 78.437992 -318.920443) (xy 78.405357 -318.883606) (xy 78.379054 -318.84201) (xy 78.359763 -318.796734)
			(xy 78.347986 -318.74895) (xy 78.344026 -318.699896) (xy 77.055218 -318.699896) (xy 77.054723 -318.724503)
			(xy 77.046828 -318.77308) (xy 77.031244 -318.819761) (xy 77.008373 -318.863338) (xy 76.978808 -318.902682)
			(xy 76.943315 -318.936774) (xy 76.902812 -318.96473) (xy 76.85835 -318.985828) (xy 76.811079 -318.99952)
			(xy 76.762224 -319.005452) (xy 76.713049 -319.003471) (xy 76.66483 -318.993627) (xy 76.618814 -318.976175)
			(xy 76.576193 -318.951568) (xy 76.538072 -318.920443) (xy 76.505437 -318.883606) (xy 76.479134 -318.84201)
			(xy 76.459843 -318.796734) (xy 76.448066 -318.74895) (xy 76.444106 -318.699896) (xy 75.155298 -318.699896)
			(xy 75.154803 -318.724503) (xy 75.146908 -318.77308) (xy 75.131324 -318.819761) (xy 75.108453 -318.863338)
			(xy 75.078888 -318.902682) (xy 75.043395 -318.936774) (xy 75.002892 -318.96473) (xy 74.95843 -318.985828)
			(xy 74.911159 -318.99952) (xy 74.862304 -319.005452) (xy 74.813129 -319.003471) (xy 74.76491 -318.993627)
			(xy 74.718894 -318.976175) (xy 74.676273 -318.951568) (xy 74.638152 -318.920443) (xy 74.605517 -318.883606)
			(xy 74.579214 -318.84201) (xy 74.559923 -318.796734) (xy 74.548146 -318.74895) (xy 74.544186 -318.699896)
			(xy 31.326643 -318.699896) (xy 31.399853 -318.756463) (xy 31.51239 -318.853497) (xy 31.619557 -318.956432)
			(xy 31.721044 -319.064971) (xy 31.816558 -319.1788) (xy 31.905825 -319.297593) (xy 31.988586 -319.421005)
			(xy 32.064604 -319.548683) (xy 32.133659 -319.680256) (xy 32.195552 -319.815347) (xy 32.250105 -319.953564)
			(xy 32.29716 -320.094511) (xy 32.336582 -320.237781) (xy 32.368256 -320.38296) (xy 32.392092 -320.529629)
			(xy 32.408021 -320.677367) (xy 32.415997 -320.825747) (xy 32.416496 -320.900044) (xy 86.882487 -320.900044)
			(xy 86.886476 -320.751504) (xy 86.898433 -320.603391) (xy 86.918323 -320.456134) (xy 86.946088 -320.310158)
			(xy 86.981649 -320.165881) (xy 87.024903 -320.023722) (xy 87.075725 -319.884089) (xy 87.133969 -319.747386)
			(xy 87.199467 -319.614006) (xy 87.27203 -319.484334) (xy 87.351448 -319.358744) (xy 87.437493 -319.237597)
			(xy 87.529917 -319.121244) (xy 87.628453 -319.01002) (xy 87.732817 -318.904245) (xy 87.842709 -318.804225)
			(xy 87.95781 -318.710247) (xy 88.07779 -318.622583) (xy 88.202303 -318.541486) (xy 88.330989 -318.467189)
			(xy 88.463478 -318.399907) (xy 88.599387 -318.339833) (xy 88.738325 -318.287141) (xy 88.879891 -318.241982)
			(xy 89.023677 -318.204487) (xy 89.169268 -318.174765) (xy 89.316244 -318.1529) (xy 89.464183 -318.138956)
			(xy 89.612656 -318.132972) (xy 89.761237 -318.134967) (xy 89.909496 -318.144935) (xy 90.057007 -318.162846)
			(xy 90.203343 -318.188649) (xy 90.348084 -318.222269) (xy 90.490811 -318.263611) (xy 90.631114 -318.312554)
			(xy 90.768587 -318.368957) (xy 90.902834 -318.432658) (xy 91.033469 -318.503474) (xy 91.160114 -318.581199)
			(xy 91.282404 -318.66561) (xy 91.399987 -318.756463) (xy 91.512524 -318.853497) (xy 91.619691 -318.956432)
			(xy 91.721178 -319.064971) (xy 91.816692 -319.1788) (xy 91.905959 -319.297593) (xy 91.98872 -319.421005)
			(xy 92.064738 -319.548683) (xy 92.133793 -319.680256) (xy 92.195686 -319.815347) (xy 92.250239 -319.953564)
			(xy 92.297294 -320.094511) (xy 92.336716 -320.237781) (xy 92.36839 -320.38296) (xy 92.392226 -320.529629)
			(xy 92.408155 -320.677367) (xy 92.416131 -320.825747) (xy 92.41663 -320.900044) (xy 142.982451 -320.900044)
			(xy 142.98644 -320.751504) (xy 142.998397 -320.603391) (xy 143.018287 -320.456134) (xy 143.046052 -320.310158)
			(xy 143.081613 -320.165881) (xy 143.124867 -320.023722) (xy 143.175689 -319.884089) (xy 143.233933 -319.747386)
			(xy 143.299431 -319.614006) (xy 143.371994 -319.484334) (xy 143.451412 -319.358744) (xy 143.537457 -319.237597)
			(xy 143.629881 -319.121244) (xy 143.728417 -319.01002) (xy 143.832781 -318.904245) (xy 143.942673 -318.804225)
			(xy 144.057774 -318.710247) (xy 144.177754 -318.622583) (xy 144.302267 -318.541486) (xy 144.430953 -318.467189)
			(xy 144.563442 -318.399907) (xy 144.699351 -318.339833) (xy 144.838289 -318.287141) (xy 144.979855 -318.241982)
			(xy 145.123641 -318.204487) (xy 145.269232 -318.174765) (xy 145.416208 -318.1529) (xy 145.564147 -318.138956)
			(xy 145.71262 -318.132972) (xy 145.861201 -318.134967) (xy 146.00946 -318.144935) (xy 146.156971 -318.162846)
			(xy 146.303307 -318.188649) (xy 146.448048 -318.222269) (xy 146.590775 -318.263611) (xy 146.731078 -318.312554)
			(xy 146.868551 -318.368957) (xy 147.002798 -318.432658) (xy 147.133433 -318.503474) (xy 147.260078 -318.581199)
			(xy 147.382368 -318.66561) (xy 147.426741 -318.699896) (xy 160.24404 -318.699896) (xy 160.248 -318.650842)
			(xy 160.259777 -318.603058) (xy 160.279068 -318.557782) (xy 160.305371 -318.516186) (xy 160.338006 -318.479349)
			(xy 160.376127 -318.448224) (xy 160.418748 -318.423617) (xy 160.464764 -318.406165) (xy 160.512983 -318.396321)
			(xy 160.562158 -318.39434) (xy 160.611013 -318.400272) (xy 160.658284 -318.413964) (xy 160.702746 -318.435062)
			(xy 160.743249 -318.463018) (xy 160.778742 -318.49711) (xy 160.808307 -318.536454) (xy 160.831178 -318.580031)
			(xy 160.846762 -318.626712) (xy 160.854657 -318.675289) (xy 160.855152 -318.699896) (xy 162.144214 -318.699896)
			(xy 162.148174 -318.650842) (xy 162.159951 -318.603058) (xy 162.179242 -318.557782) (xy 162.205545 -318.516186)
			(xy 162.23818 -318.479349) (xy 162.276301 -318.448224) (xy 162.318922 -318.423617) (xy 162.364938 -318.406165)
			(xy 162.413157 -318.396321) (xy 162.462332 -318.39434) (xy 162.511187 -318.400272) (xy 162.558458 -318.413964)
			(xy 162.60292 -318.435062) (xy 162.643423 -318.463018) (xy 162.678916 -318.49711) (xy 162.708481 -318.536454)
			(xy 162.731352 -318.580031) (xy 162.746936 -318.626712) (xy 162.754831 -318.675289) (xy 162.755326 -318.699896)
			(xy 164.044134 -318.699896) (xy 164.048094 -318.650842) (xy 164.059871 -318.603058) (xy 164.079162 -318.557782)
			(xy 164.105465 -318.516186) (xy 164.1381 -318.479349) (xy 164.176221 -318.448224) (xy 164.218842 -318.423617)
			(xy 164.264858 -318.406165) (xy 164.313077 -318.396321) (xy 164.362252 -318.39434) (xy 164.411107 -318.400272)
			(xy 164.458378 -318.413964) (xy 164.50284 -318.435062) (xy 164.543343 -318.463018) (xy 164.578836 -318.49711)
			(xy 164.608401 -318.536454) (xy 164.631272 -318.580031) (xy 164.646856 -318.626712) (xy 164.654751 -318.675289)
			(xy 164.655246 -318.699896) (xy 165.944054 -318.699896) (xy 165.948014 -318.650842) (xy 165.959791 -318.603058)
			(xy 165.979082 -318.557782) (xy 166.005385 -318.516186) (xy 166.03802 -318.479349) (xy 166.076141 -318.448224)
			(xy 166.118762 -318.423617) (xy 166.164778 -318.406165) (xy 166.212997 -318.396321) (xy 166.262172 -318.39434)
			(xy 166.311027 -318.400272) (xy 166.358298 -318.413964) (xy 166.40276 -318.435062) (xy 166.443263 -318.463018)
			(xy 166.478756 -318.49711) (xy 166.508321 -318.536454) (xy 166.531192 -318.580031) (xy 166.546776 -318.626712)
			(xy 166.554671 -318.675289) (xy 166.555166 -318.699896) (xy 183.044096 -318.699896) (xy 183.048056 -318.650842)
			(xy 183.059833 -318.603058) (xy 183.079124 -318.557782) (xy 183.105427 -318.516186) (xy 183.138062 -318.479349)
			(xy 183.176183 -318.448224) (xy 183.218804 -318.423617) (xy 183.26482 -318.406165) (xy 183.313039 -318.396321)
			(xy 183.362214 -318.39434) (xy 183.411069 -318.400272) (xy 183.45834 -318.413964) (xy 183.502802 -318.435062)
			(xy 183.543305 -318.463018) (xy 183.578798 -318.49711) (xy 183.608363 -318.536454) (xy 183.631234 -318.580031)
			(xy 183.646818 -318.626712) (xy 183.654713 -318.675289) (xy 183.655208 -318.699896) (xy 184.94427 -318.699896)
			(xy 184.94823 -318.650842) (xy 184.960007 -318.603058) (xy 184.979298 -318.557782) (xy 185.005601 -318.516186)
			(xy 185.038236 -318.479349) (xy 185.076357 -318.448224) (xy 185.118978 -318.423617) (xy 185.164994 -318.406165)
			(xy 185.213213 -318.396321) (xy 185.262388 -318.39434) (xy 185.311243 -318.400272) (xy 185.358514 -318.413964)
			(xy 185.402976 -318.435062) (xy 185.443479 -318.463018) (xy 185.478972 -318.49711) (xy 185.508537 -318.536454)
			(xy 185.531408 -318.580031) (xy 185.546992 -318.626712) (xy 185.554887 -318.675289) (xy 185.555382 -318.699896)
			(xy 186.84419 -318.699896) (xy 186.84815 -318.650842) (xy 186.859927 -318.603058) (xy 186.879218 -318.557782)
			(xy 186.905521 -318.516186) (xy 186.938156 -318.479349) (xy 186.976277 -318.448224) (xy 187.018898 -318.423617)
			(xy 187.064914 -318.406165) (xy 187.113133 -318.396321) (xy 187.162308 -318.39434) (xy 187.211163 -318.400272)
			(xy 187.258434 -318.413964) (xy 187.302896 -318.435062) (xy 187.343399 -318.463018) (xy 187.378892 -318.49711)
			(xy 187.408457 -318.536454) (xy 187.431328 -318.580031) (xy 187.446912 -318.626712) (xy 187.454807 -318.675289)
			(xy 187.455302 -318.699896) (xy 188.74411 -318.699896) (xy 188.74807 -318.650842) (xy 188.759847 -318.603058)
			(xy 188.779138 -318.557782) (xy 188.805441 -318.516186) (xy 188.838076 -318.479349) (xy 188.876197 -318.448224)
			(xy 188.918818 -318.423617) (xy 188.964834 -318.406165) (xy 189.013053 -318.396321) (xy 189.062228 -318.39434)
			(xy 189.111083 -318.400272) (xy 189.158354 -318.413964) (xy 189.202816 -318.435062) (xy 189.243319 -318.463018)
			(xy 189.278812 -318.49711) (xy 189.308377 -318.536454) (xy 189.331248 -318.580031) (xy 189.346832 -318.626712)
			(xy 189.354727 -318.675289) (xy 189.355222 -318.699896) (xy 189.354727 -318.724503) (xy 189.346832 -318.77308)
			(xy 189.331248 -318.819761) (xy 189.308377 -318.863338) (xy 189.278812 -318.902682) (xy 189.243319 -318.936774)
			(xy 189.202816 -318.96473) (xy 189.158354 -318.985828) (xy 189.111083 -318.99952) (xy 189.062228 -319.005452)
			(xy 189.013053 -319.003471) (xy 188.964834 -318.993627) (xy 188.918818 -318.976175) (xy 188.876197 -318.951568)
			(xy 188.838076 -318.920443) (xy 188.805441 -318.883606) (xy 188.779138 -318.84201) (xy 188.759847 -318.796734)
			(xy 188.74807 -318.74895) (xy 188.74411 -318.699896) (xy 187.455302 -318.699896) (xy 187.454807 -318.724503)
			(xy 187.446912 -318.77308) (xy 187.431328 -318.819761) (xy 187.408457 -318.863338) (xy 187.378892 -318.902682)
			(xy 187.343399 -318.936774) (xy 187.302896 -318.96473) (xy 187.258434 -318.985828) (xy 187.211163 -318.99952)
			(xy 187.162308 -319.005452) (xy 187.113133 -319.003471) (xy 187.064914 -318.993627) (xy 187.018898 -318.976175)
			(xy 186.976277 -318.951568) (xy 186.938156 -318.920443) (xy 186.905521 -318.883606) (xy 186.879218 -318.84201)
			(xy 186.859927 -318.796734) (xy 186.84815 -318.74895) (xy 186.84419 -318.699896) (xy 185.555382 -318.699896)
			(xy 185.554887 -318.724503) (xy 185.546992 -318.77308) (xy 185.531408 -318.819761) (xy 185.508537 -318.863338)
			(xy 185.478972 -318.902682) (xy 185.443479 -318.936774) (xy 185.402976 -318.96473) (xy 185.358514 -318.985828)
			(xy 185.311243 -318.99952) (xy 185.262388 -319.005452) (xy 185.213213 -319.003471) (xy 185.164994 -318.993627)
			(xy 185.118978 -318.976175) (xy 185.076357 -318.951568) (xy 185.038236 -318.920443) (xy 185.005601 -318.883606)
			(xy 184.979298 -318.84201) (xy 184.960007 -318.796734) (xy 184.94823 -318.74895) (xy 184.94427 -318.699896)
			(xy 183.655208 -318.699896) (xy 183.654713 -318.724503) (xy 183.646818 -318.77308) (xy 183.631234 -318.819761)
			(xy 183.608363 -318.863338) (xy 183.578798 -318.902682) (xy 183.543305 -318.936774) (xy 183.502802 -318.96473)
			(xy 183.45834 -318.985828) (xy 183.411069 -318.99952) (xy 183.362214 -319.005452) (xy 183.313039 -319.003471)
			(xy 183.26482 -318.993627) (xy 183.218804 -318.976175) (xy 183.176183 -318.951568) (xy 183.138062 -318.920443)
			(xy 183.105427 -318.883606) (xy 183.079124 -318.84201) (xy 183.059833 -318.796734) (xy 183.048056 -318.74895)
			(xy 183.044096 -318.699896) (xy 166.555166 -318.699896) (xy 166.554671 -318.724503) (xy 166.546776 -318.77308)
			(xy 166.531192 -318.819761) (xy 166.508321 -318.863338) (xy 166.478756 -318.902682) (xy 166.443263 -318.936774)
			(xy 166.40276 -318.96473) (xy 166.358298 -318.985828) (xy 166.311027 -318.99952) (xy 166.262172 -319.005452)
			(xy 166.212997 -319.003471) (xy 166.164778 -318.993627) (xy 166.118762 -318.976175) (xy 166.076141 -318.951568)
			(xy 166.03802 -318.920443) (xy 166.005385 -318.883606) (xy 165.979082 -318.84201) (xy 165.959791 -318.796734)
			(xy 165.948014 -318.74895) (xy 165.944054 -318.699896) (xy 164.655246 -318.699896) (xy 164.654751 -318.724503)
			(xy 164.646856 -318.77308) (xy 164.631272 -318.819761) (xy 164.608401 -318.863338) (xy 164.578836 -318.902682)
			(xy 164.543343 -318.936774) (xy 164.50284 -318.96473) (xy 164.458378 -318.985828) (xy 164.411107 -318.99952)
			(xy 164.362252 -319.005452) (xy 164.313077 -319.003471) (xy 164.264858 -318.993627) (xy 164.218842 -318.976175)
			(xy 164.176221 -318.951568) (xy 164.1381 -318.920443) (xy 164.105465 -318.883606) (xy 164.079162 -318.84201)
			(xy 164.059871 -318.796734) (xy 164.048094 -318.74895) (xy 164.044134 -318.699896) (xy 162.755326 -318.699896)
			(xy 162.754831 -318.724503) (xy 162.746936 -318.77308) (xy 162.731352 -318.819761) (xy 162.708481 -318.863338)
			(xy 162.678916 -318.902682) (xy 162.643423 -318.936774) (xy 162.60292 -318.96473) (xy 162.558458 -318.985828)
			(xy 162.511187 -318.99952) (xy 162.462332 -319.005452) (xy 162.413157 -319.003471) (xy 162.364938 -318.993627)
			(xy 162.318922 -318.976175) (xy 162.276301 -318.951568) (xy 162.23818 -318.920443) (xy 162.205545 -318.883606)
			(xy 162.179242 -318.84201) (xy 162.159951 -318.796734) (xy 162.148174 -318.74895) (xy 162.144214 -318.699896)
			(xy 160.855152 -318.699896) (xy 160.854657 -318.724503) (xy 160.846762 -318.77308) (xy 160.831178 -318.819761)
			(xy 160.808307 -318.863338) (xy 160.778742 -318.902682) (xy 160.743249 -318.936774) (xy 160.702746 -318.96473)
			(xy 160.658284 -318.985828) (xy 160.611013 -318.99952) (xy 160.562158 -319.005452) (xy 160.512983 -319.003471)
			(xy 160.464764 -318.993627) (xy 160.418748 -318.976175) (xy 160.376127 -318.951568) (xy 160.338006 -318.920443)
			(xy 160.305371 -318.883606) (xy 160.279068 -318.84201) (xy 160.259777 -318.796734) (xy 160.248 -318.74895)
			(xy 160.24404 -318.699896) (xy 147.426741 -318.699896) (xy 147.499951 -318.756463) (xy 147.612488 -318.853497)
			(xy 147.719655 -318.956432) (xy 147.821142 -319.064971) (xy 147.916656 -319.1788) (xy 148.005923 -319.297593)
			(xy 148.088684 -319.421005) (xy 148.164702 -319.548683) (xy 148.233757 -319.680256) (xy 148.29565 -319.815347)
			(xy 148.350203 -319.953564) (xy 148.397258 -320.094511) (xy 148.43668 -320.237781) (xy 148.468354 -320.38296)
			(xy 148.49219 -320.529629) (xy 148.508119 -320.677367) (xy 148.516095 -320.825747) (xy 148.516594 -320.900044)
			(xy 202.982331 -320.900044) (xy 202.98632 -320.751504) (xy 202.998277 -320.603391) (xy 203.018167 -320.456134)
			(xy 203.045932 -320.310158) (xy 203.081493 -320.165881) (xy 203.124747 -320.023722) (xy 203.175569 -319.884089)
			(xy 203.233813 -319.747386) (xy 203.299311 -319.614006) (xy 203.371874 -319.484334) (xy 203.451292 -319.358744)
			(xy 203.537337 -319.237597) (xy 203.629761 -319.121244) (xy 203.728297 -319.01002) (xy 203.832661 -318.904245)
			(xy 203.942553 -318.804225) (xy 204.057654 -318.710247) (xy 204.177634 -318.622583) (xy 204.302147 -318.541486)
			(xy 204.430833 -318.467189) (xy 204.563322 -318.399907) (xy 204.699231 -318.339833) (xy 204.838169 -318.287141)
			(xy 204.979735 -318.241982) (xy 205.123521 -318.204487) (xy 205.269112 -318.174765) (xy 205.416088 -318.1529)
			(xy 205.564027 -318.138956) (xy 205.7125 -318.132972) (xy 205.861081 -318.134967) (xy 206.00934 -318.144935)
			(xy 206.156851 -318.162846) (xy 206.303187 -318.188649) (xy 206.447928 -318.222269) (xy 206.590655 -318.263611)
			(xy 206.730958 -318.312554) (xy 206.868431 -318.368957) (xy 207.002678 -318.432658) (xy 207.133313 -318.503474)
			(xy 207.259958 -318.581199) (xy 207.382248 -318.66561) (xy 207.499831 -318.756463) (xy 207.612368 -318.853497)
			(xy 207.719535 -318.956432) (xy 207.821022 -319.064971) (xy 207.916536 -319.1788) (xy 208.005803 -319.297593)
			(xy 208.088564 -319.421005) (xy 208.164582 -319.548683) (xy 208.233637 -319.680256) (xy 208.29553 -319.815347)
			(xy 208.350083 -319.953564) (xy 208.397138 -320.094511) (xy 208.43656 -320.237781) (xy 208.468234 -320.38296)
			(xy 208.49207 -320.529629) (xy 208.507999 -320.677367) (xy 208.515975 -320.825747) (xy 208.516474 -320.900044)
			(xy 259.082549 -320.900044) (xy 259.086538 -320.751504) (xy 259.098495 -320.603391) (xy 259.118385 -320.456134)
			(xy 259.14615 -320.310158) (xy 259.181711 -320.165881) (xy 259.224965 -320.023722) (xy 259.275787 -319.884089)
			(xy 259.334031 -319.747386) (xy 259.399529 -319.614006) (xy 259.472092 -319.484334) (xy 259.55151 -319.358744)
			(xy 259.637555 -319.237597) (xy 259.729979 -319.121244) (xy 259.828515 -319.01002) (xy 259.932879 -318.904245)
			(xy 260.042771 -318.804225) (xy 260.157872 -318.710247) (xy 260.277852 -318.622583) (xy 260.402365 -318.541486)
			(xy 260.531051 -318.467189) (xy 260.66354 -318.399907) (xy 260.799449 -318.339833) (xy 260.938387 -318.287141)
			(xy 261.079953 -318.241982) (xy 261.223739 -318.204487) (xy 261.36933 -318.174765) (xy 261.516306 -318.1529)
			(xy 261.664245 -318.138956) (xy 261.812718 -318.132972) (xy 261.961299 -318.134967) (xy 262.109558 -318.144935)
			(xy 262.257069 -318.162846) (xy 262.403405 -318.188649) (xy 262.548146 -318.222269) (xy 262.690873 -318.263611)
			(xy 262.831176 -318.312554) (xy 262.968649 -318.368957) (xy 263.102896 -318.432658) (xy 263.233531 -318.503474)
			(xy 263.360176 -318.581199) (xy 263.482466 -318.66561) (xy 263.526839 -318.699896) (xy 306.744128 -318.699896)
			(xy 306.748088 -318.650842) (xy 306.759865 -318.603058) (xy 306.779156 -318.557782) (xy 306.805459 -318.516186)
			(xy 306.838094 -318.479349) (xy 306.876215 -318.448224) (xy 306.918836 -318.423617) (xy 306.964852 -318.406165)
			(xy 307.013071 -318.396321) (xy 307.062246 -318.39434) (xy 307.111101 -318.400272) (xy 307.158372 -318.413964)
			(xy 307.202834 -318.435062) (xy 307.243337 -318.463018) (xy 307.27883 -318.49711) (xy 307.308395 -318.536454)
			(xy 307.331266 -318.580031) (xy 307.34685 -318.626712) (xy 307.354745 -318.675289) (xy 307.35524 -318.699896)
			(xy 308.644048 -318.699896) (xy 308.648008 -318.650842) (xy 308.659785 -318.603058) (xy 308.679076 -318.557782)
			(xy 308.705379 -318.516186) (xy 308.738014 -318.479349) (xy 308.776135 -318.448224) (xy 308.818756 -318.423617)
			(xy 308.864772 -318.406165) (xy 308.912991 -318.396321) (xy 308.962166 -318.39434) (xy 309.011021 -318.400272)
			(xy 309.058292 -318.413964) (xy 309.102754 -318.435062) (xy 309.143257 -318.463018) (xy 309.17875 -318.49711)
			(xy 309.208315 -318.536454) (xy 309.231186 -318.580031) (xy 309.24677 -318.626712) (xy 309.254665 -318.675289)
			(xy 309.25516 -318.699896) (xy 310.543968 -318.699896) (xy 310.547928 -318.650842) (xy 310.559705 -318.603058)
			(xy 310.578996 -318.557782) (xy 310.605299 -318.516186) (xy 310.637934 -318.479349) (xy 310.676055 -318.448224)
			(xy 310.718676 -318.423617) (xy 310.764692 -318.406165) (xy 310.812911 -318.396321) (xy 310.862086 -318.39434)
			(xy 310.910941 -318.400272) (xy 310.958212 -318.413964) (xy 311.002674 -318.435062) (xy 311.043177 -318.463018)
			(xy 311.07867 -318.49711) (xy 311.108235 -318.536454) (xy 311.131106 -318.580031) (xy 311.14669 -318.626712)
			(xy 311.154585 -318.675289) (xy 311.15508 -318.699896) (xy 312.443888 -318.699896) (xy 312.447848 -318.650842)
			(xy 312.459625 -318.603058) (xy 312.478916 -318.557782) (xy 312.505219 -318.516186) (xy 312.537854 -318.479349)
			(xy 312.575975 -318.448224) (xy 312.618596 -318.423617) (xy 312.664612 -318.406165) (xy 312.712831 -318.396321)
			(xy 312.762006 -318.39434) (xy 312.810861 -318.400272) (xy 312.858132 -318.413964) (xy 312.902594 -318.435062)
			(xy 312.943097 -318.463018) (xy 312.97859 -318.49711) (xy 313.008155 -318.536454) (xy 313.031026 -318.580031)
			(xy 313.04661 -318.626712) (xy 313.054505 -318.675289) (xy 313.055 -318.699896) (xy 313.054505 -318.724503)
			(xy 313.04661 -318.77308) (xy 313.031026 -318.819761) (xy 313.008155 -318.863338) (xy 312.97859 -318.902682)
			(xy 312.943097 -318.936774) (xy 312.902594 -318.96473) (xy 312.858132 -318.985828) (xy 312.810861 -318.99952)
			(xy 312.762006 -319.005452) (xy 312.712831 -319.003471) (xy 312.664612 -318.993627) (xy 312.618596 -318.976175)
			(xy 312.575975 -318.951568) (xy 312.537854 -318.920443) (xy 312.505219 -318.883606) (xy 312.478916 -318.84201)
			(xy 312.459625 -318.796734) (xy 312.447848 -318.74895) (xy 312.443888 -318.699896) (xy 311.15508 -318.699896)
			(xy 311.154585 -318.724503) (xy 311.14669 -318.77308) (xy 311.131106 -318.819761) (xy 311.108235 -318.863338)
			(xy 311.07867 -318.902682) (xy 311.043177 -318.936774) (xy 311.002674 -318.96473) (xy 310.958212 -318.985828)
			(xy 310.910941 -318.99952) (xy 310.862086 -319.005452) (xy 310.812911 -319.003471) (xy 310.764692 -318.993627)
			(xy 310.718676 -318.976175) (xy 310.676055 -318.951568) (xy 310.637934 -318.920443) (xy 310.605299 -318.883606)
			(xy 310.578996 -318.84201) (xy 310.559705 -318.796734) (xy 310.547928 -318.74895) (xy 310.543968 -318.699896)
			(xy 309.25516 -318.699896) (xy 309.254665 -318.724503) (xy 309.24677 -318.77308) (xy 309.231186 -318.819761)
			(xy 309.208315 -318.863338) (xy 309.17875 -318.902682) (xy 309.143257 -318.936774) (xy 309.102754 -318.96473)
			(xy 309.058292 -318.985828) (xy 309.011021 -318.99952) (xy 308.962166 -319.005452) (xy 308.912991 -319.003471)
			(xy 308.864772 -318.993627) (xy 308.818756 -318.976175) (xy 308.776135 -318.951568) (xy 308.738014 -318.920443)
			(xy 308.705379 -318.883606) (xy 308.679076 -318.84201) (xy 308.659785 -318.796734) (xy 308.648008 -318.74895)
			(xy 308.644048 -318.699896) (xy 307.35524 -318.699896) (xy 307.354745 -318.724503) (xy 307.34685 -318.77308)
			(xy 307.331266 -318.819761) (xy 307.308395 -318.863338) (xy 307.27883 -318.902682) (xy 307.243337 -318.936774)
			(xy 307.202834 -318.96473) (xy 307.158372 -318.985828) (xy 307.111101 -318.99952) (xy 307.062246 -319.005452)
			(xy 307.013071 -319.003471) (xy 306.964852 -318.993627) (xy 306.918836 -318.976175) (xy 306.876215 -318.951568)
			(xy 306.838094 -318.920443) (xy 306.805459 -318.883606) (xy 306.779156 -318.84201) (xy 306.759865 -318.796734)
			(xy 306.748088 -318.74895) (xy 306.744128 -318.699896) (xy 263.526839 -318.699896) (xy 263.600049 -318.756463)
			(xy 263.712586 -318.853497) (xy 263.819753 -318.956432) (xy 263.92124 -319.064971) (xy 264.016754 -319.1788)
			(xy 264.106021 -319.297593) (xy 264.188782 -319.421005) (xy 264.2648 -319.548683) (xy 264.333855 -319.680256)
			(xy 264.395748 -319.815347) (xy 264.450301 -319.953564) (xy 264.497356 -320.094511) (xy 264.536778 -320.237781)
			(xy 264.568452 -320.38296) (xy 264.592288 -320.529629) (xy 264.608217 -320.677367) (xy 264.616193 -320.825747)
			(xy 264.616692 -320.900044) (xy 319.082429 -320.900044) (xy 319.086418 -320.751504) (xy 319.098375 -320.603391)
			(xy 319.118265 -320.456134) (xy 319.14603 -320.310158) (xy 319.181591 -320.165881) (xy 319.224845 -320.023722)
			(xy 319.275667 -319.884089) (xy 319.333911 -319.747386) (xy 319.399409 -319.614006) (xy 319.471972 -319.484334)
			(xy 319.55139 -319.358744) (xy 319.637435 -319.237597) (xy 319.729859 -319.121244) (xy 319.828395 -319.01002)
			(xy 319.932759 -318.904245) (xy 320.042651 -318.804225) (xy 320.157752 -318.710247) (xy 320.277732 -318.622583)
			(xy 320.402245 -318.541486) (xy 320.530931 -318.467189) (xy 320.66342 -318.399907) (xy 320.799329 -318.339833)
			(xy 320.938267 -318.287141) (xy 321.079833 -318.241982) (xy 321.223619 -318.204487) (xy 321.36921 -318.174765)
			(xy 321.516186 -318.1529) (xy 321.664125 -318.138956) (xy 321.812598 -318.132972) (xy 321.961179 -318.134967)
			(xy 322.109438 -318.144935) (xy 322.256949 -318.162846) (xy 322.403285 -318.188649) (xy 322.548026 -318.222269)
			(xy 322.690753 -318.263611) (xy 322.831056 -318.312554) (xy 322.968529 -318.368957) (xy 323.102776 -318.432658)
			(xy 323.233411 -318.503474) (xy 323.360056 -318.581199) (xy 323.482346 -318.66561) (xy 323.599929 -318.756463)
			(xy 323.712466 -318.853497) (xy 323.819633 -318.956432) (xy 323.92112 -319.064971) (xy 324.016634 -319.1788)
			(xy 324.105901 -319.297593) (xy 324.188662 -319.421005) (xy 324.26468 -319.548683) (xy 324.333735 -319.680256)
			(xy 324.395628 -319.815347) (xy 324.450181 -319.953564) (xy 324.497236 -320.094511) (xy 324.536658 -320.237781)
			(xy 324.568332 -320.38296) (xy 324.592168 -320.529629) (xy 324.608097 -320.677367) (xy 324.616073 -320.825747)
			(xy 324.616572 -320.900044) (xy 375.182393 -320.900044) (xy 375.186382 -320.751504) (xy 375.198339 -320.603391)
			(xy 375.218229 -320.456134) (xy 375.245994 -320.310158) (xy 375.281555 -320.165881) (xy 375.324809 -320.023722)
			(xy 375.375631 -319.884089) (xy 375.433875 -319.747386) (xy 375.499373 -319.614006) (xy 375.571936 -319.484334)
			(xy 375.651354 -319.358744) (xy 375.737399 -319.237597) (xy 375.829823 -319.121244) (xy 375.928359 -319.01002)
			(xy 376.032723 -318.904245) (xy 376.142615 -318.804225) (xy 376.257716 -318.710247) (xy 376.377696 -318.622583)
			(xy 376.502209 -318.541486) (xy 376.630895 -318.467189) (xy 376.763384 -318.399907) (xy 376.899293 -318.339833)
			(xy 377.038231 -318.287141) (xy 377.179797 -318.241982) (xy 377.323583 -318.204487) (xy 377.469174 -318.174765)
			(xy 377.61615 -318.1529) (xy 377.764089 -318.138956) (xy 377.912562 -318.132972) (xy 378.061143 -318.134967)
			(xy 378.209402 -318.144935) (xy 378.356913 -318.162846) (xy 378.503249 -318.188649) (xy 378.64799 -318.222269)
			(xy 378.790717 -318.263611) (xy 378.93102 -318.312554) (xy 379.068493 -318.368957) (xy 379.20274 -318.432658)
			(xy 379.333375 -318.503474) (xy 379.46002 -318.581199) (xy 379.58231 -318.66561) (xy 379.626683 -318.699896)
			(xy 392.443982 -318.699896) (xy 392.447942 -318.650842) (xy 392.459719 -318.603058) (xy 392.47901 -318.557782)
			(xy 392.505313 -318.516186) (xy 392.537948 -318.479349) (xy 392.576069 -318.448224) (xy 392.61869 -318.423617)
			(xy 392.664706 -318.406165) (xy 392.712925 -318.396321) (xy 392.7621 -318.39434) (xy 392.810955 -318.400272)
			(xy 392.858226 -318.413964) (xy 392.902688 -318.435062) (xy 392.943191 -318.463018) (xy 392.978684 -318.49711)
			(xy 393.008249 -318.536454) (xy 393.03112 -318.580031) (xy 393.046704 -318.626712) (xy 393.054599 -318.675289)
			(xy 393.055094 -318.699896) (xy 394.344156 -318.699896) (xy 394.348116 -318.650842) (xy 394.359893 -318.603058)
			(xy 394.379184 -318.557782) (xy 394.405487 -318.516186) (xy 394.438122 -318.479349) (xy 394.476243 -318.448224)
			(xy 394.518864 -318.423617) (xy 394.56488 -318.406165) (xy 394.613099 -318.396321) (xy 394.662274 -318.39434)
			(xy 394.711129 -318.400272) (xy 394.7584 -318.413964) (xy 394.802862 -318.435062) (xy 394.843365 -318.463018)
			(xy 394.878858 -318.49711) (xy 394.908423 -318.536454) (xy 394.931294 -318.580031) (xy 394.946878 -318.626712)
			(xy 394.954773 -318.675289) (xy 394.955268 -318.699896) (xy 396.244076 -318.699896) (xy 396.248036 -318.650842)
			(xy 396.259813 -318.603058) (xy 396.279104 -318.557782) (xy 396.305407 -318.516186) (xy 396.338042 -318.479349)
			(xy 396.376163 -318.448224) (xy 396.418784 -318.423617) (xy 396.4648 -318.406165) (xy 396.513019 -318.396321)
			(xy 396.562194 -318.39434) (xy 396.611049 -318.400272) (xy 396.65832 -318.413964) (xy 396.702782 -318.435062)
			(xy 396.743285 -318.463018) (xy 396.778778 -318.49711) (xy 396.808343 -318.536454) (xy 396.831214 -318.580031)
			(xy 396.846798 -318.626712) (xy 396.854693 -318.675289) (xy 396.855188 -318.699896) (xy 398.143996 -318.699896)
			(xy 398.147956 -318.650842) (xy 398.159733 -318.603058) (xy 398.179024 -318.557782) (xy 398.205327 -318.516186)
			(xy 398.237962 -318.479349) (xy 398.276083 -318.448224) (xy 398.318704 -318.423617) (xy 398.36472 -318.406165)
			(xy 398.412939 -318.396321) (xy 398.462114 -318.39434) (xy 398.510969 -318.400272) (xy 398.55824 -318.413964)
			(xy 398.602702 -318.435062) (xy 398.643205 -318.463018) (xy 398.678698 -318.49711) (xy 398.708263 -318.536454)
			(xy 398.731134 -318.580031) (xy 398.746718 -318.626712) (xy 398.754613 -318.675289) (xy 398.755108 -318.699896)
			(xy 415.244038 -318.699896) (xy 415.247998 -318.650842) (xy 415.259775 -318.603058) (xy 415.279066 -318.557782)
			(xy 415.305369 -318.516186) (xy 415.338004 -318.479349) (xy 415.376125 -318.448224) (xy 415.418746 -318.423617)
			(xy 415.464762 -318.406165) (xy 415.512981 -318.396321) (xy 415.562156 -318.39434) (xy 415.611011 -318.400272)
			(xy 415.658282 -318.413964) (xy 415.702744 -318.435062) (xy 415.743247 -318.463018) (xy 415.77874 -318.49711)
			(xy 415.808305 -318.536454) (xy 415.831176 -318.580031) (xy 415.84676 -318.626712) (xy 415.854655 -318.675289)
			(xy 415.85515 -318.699896) (xy 417.144212 -318.699896) (xy 417.148172 -318.650842) (xy 417.159949 -318.603058)
			(xy 417.17924 -318.557782) (xy 417.205543 -318.516186) (xy 417.238178 -318.479349) (xy 417.276299 -318.448224)
			(xy 417.31892 -318.423617) (xy 417.364936 -318.406165) (xy 417.413155 -318.396321) (xy 417.46233 -318.39434)
			(xy 417.511185 -318.400272) (xy 417.558456 -318.413964) (xy 417.602918 -318.435062) (xy 417.643421 -318.463018)
			(xy 417.678914 -318.49711) (xy 417.708479 -318.536454) (xy 417.73135 -318.580031) (xy 417.746934 -318.626712)
			(xy 417.754829 -318.675289) (xy 417.755324 -318.699896) (xy 419.044132 -318.699896) (xy 419.048092 -318.650842)
			(xy 419.059869 -318.603058) (xy 419.07916 -318.557782) (xy 419.105463 -318.516186) (xy 419.138098 -318.479349)
			(xy 419.176219 -318.448224) (xy 419.21884 -318.423617) (xy 419.264856 -318.406165) (xy 419.313075 -318.396321)
			(xy 419.36225 -318.39434) (xy 419.411105 -318.400272) (xy 419.458376 -318.413964) (xy 419.502838 -318.435062)
			(xy 419.543341 -318.463018) (xy 419.578834 -318.49711) (xy 419.608399 -318.536454) (xy 419.63127 -318.580031)
			(xy 419.646854 -318.626712) (xy 419.654749 -318.675289) (xy 419.655244 -318.699896) (xy 420.944052 -318.699896)
			(xy 420.948012 -318.650842) (xy 420.959789 -318.603058) (xy 420.97908 -318.557782) (xy 421.005383 -318.516186)
			(xy 421.038018 -318.479349) (xy 421.076139 -318.448224) (xy 421.11876 -318.423617) (xy 421.164776 -318.406165)
			(xy 421.212995 -318.396321) (xy 421.26217 -318.39434) (xy 421.311025 -318.400272) (xy 421.358296 -318.413964)
			(xy 421.402758 -318.435062) (xy 421.443261 -318.463018) (xy 421.478754 -318.49711) (xy 421.508319 -318.536454)
			(xy 421.53119 -318.580031) (xy 421.546774 -318.626712) (xy 421.554669 -318.675289) (xy 421.555164 -318.699896)
			(xy 421.554669 -318.724503) (xy 421.546774 -318.77308) (xy 421.53119 -318.819761) (xy 421.508319 -318.863338)
			(xy 421.478754 -318.902682) (xy 421.443261 -318.936774) (xy 421.402758 -318.96473) (xy 421.358296 -318.985828)
			(xy 421.311025 -318.99952) (xy 421.26217 -319.005452) (xy 421.212995 -319.003471) (xy 421.164776 -318.993627)
			(xy 421.11876 -318.976175) (xy 421.076139 -318.951568) (xy 421.038018 -318.920443) (xy 421.005383 -318.883606)
			(xy 420.97908 -318.84201) (xy 420.959789 -318.796734) (xy 420.948012 -318.74895) (xy 420.944052 -318.699896)
			(xy 419.655244 -318.699896) (xy 419.654749 -318.724503) (xy 419.646854 -318.77308) (xy 419.63127 -318.819761)
			(xy 419.608399 -318.863338) (xy 419.578834 -318.902682) (xy 419.543341 -318.936774) (xy 419.502838 -318.96473)
			(xy 419.458376 -318.985828) (xy 419.411105 -318.99952) (xy 419.36225 -319.005452) (xy 419.313075 -319.003471)
			(xy 419.264856 -318.993627) (xy 419.21884 -318.976175) (xy 419.176219 -318.951568) (xy 419.138098 -318.920443)
			(xy 419.105463 -318.883606) (xy 419.07916 -318.84201) (xy 419.059869 -318.796734) (xy 419.048092 -318.74895)
			(xy 419.044132 -318.699896) (xy 417.755324 -318.699896) (xy 417.754829 -318.724503) (xy 417.746934 -318.77308)
			(xy 417.73135 -318.819761) (xy 417.708479 -318.863338) (xy 417.678914 -318.902682) (xy 417.643421 -318.936774)
			(xy 417.602918 -318.96473) (xy 417.558456 -318.985828) (xy 417.511185 -318.99952) (xy 417.46233 -319.005452)
			(xy 417.413155 -319.003471) (xy 417.364936 -318.993627) (xy 417.31892 -318.976175) (xy 417.276299 -318.951568)
			(xy 417.238178 -318.920443) (xy 417.205543 -318.883606) (xy 417.17924 -318.84201) (xy 417.159949 -318.796734)
			(xy 417.148172 -318.74895) (xy 417.144212 -318.699896) (xy 415.85515 -318.699896) (xy 415.854655 -318.724503)
			(xy 415.84676 -318.77308) (xy 415.831176 -318.819761) (xy 415.808305 -318.863338) (xy 415.77874 -318.902682)
			(xy 415.743247 -318.936774) (xy 415.702744 -318.96473) (xy 415.658282 -318.985828) (xy 415.611011 -318.99952)
			(xy 415.562156 -319.005452) (xy 415.512981 -319.003471) (xy 415.464762 -318.993627) (xy 415.418746 -318.976175)
			(xy 415.376125 -318.951568) (xy 415.338004 -318.920443) (xy 415.305369 -318.883606) (xy 415.279066 -318.84201)
			(xy 415.259775 -318.796734) (xy 415.247998 -318.74895) (xy 415.244038 -318.699896) (xy 398.755108 -318.699896)
			(xy 398.754613 -318.724503) (xy 398.746718 -318.77308) (xy 398.731134 -318.819761) (xy 398.708263 -318.863338)
			(xy 398.678698 -318.902682) (xy 398.643205 -318.936774) (xy 398.602702 -318.96473) (xy 398.55824 -318.985828)
			(xy 398.510969 -318.99952) (xy 398.462114 -319.005452) (xy 398.412939 -319.003471) (xy 398.36472 -318.993627)
			(xy 398.318704 -318.976175) (xy 398.276083 -318.951568) (xy 398.237962 -318.920443) (xy 398.205327 -318.883606)
			(xy 398.179024 -318.84201) (xy 398.159733 -318.796734) (xy 398.147956 -318.74895) (xy 398.143996 -318.699896)
			(xy 396.855188 -318.699896) (xy 396.854693 -318.724503) (xy 396.846798 -318.77308) (xy 396.831214 -318.819761)
			(xy 396.808343 -318.863338) (xy 396.778778 -318.902682) (xy 396.743285 -318.936774) (xy 396.702782 -318.96473)
			(xy 396.65832 -318.985828) (xy 396.611049 -318.99952) (xy 396.562194 -319.005452) (xy 396.513019 -319.003471)
			(xy 396.4648 -318.993627) (xy 396.418784 -318.976175) (xy 396.376163 -318.951568) (xy 396.338042 -318.920443)
			(xy 396.305407 -318.883606) (xy 396.279104 -318.84201) (xy 396.259813 -318.796734) (xy 396.248036 -318.74895)
			(xy 396.244076 -318.699896) (xy 394.955268 -318.699896) (xy 394.954773 -318.724503) (xy 394.946878 -318.77308)
			(xy 394.931294 -318.819761) (xy 394.908423 -318.863338) (xy 394.878858 -318.902682) (xy 394.843365 -318.936774)
			(xy 394.802862 -318.96473) (xy 394.7584 -318.985828) (xy 394.711129 -318.99952) (xy 394.662274 -319.005452)
			(xy 394.613099 -319.003471) (xy 394.56488 -318.993627) (xy 394.518864 -318.976175) (xy 394.476243 -318.951568)
			(xy 394.438122 -318.920443) (xy 394.405487 -318.883606) (xy 394.379184 -318.84201) (xy 394.359893 -318.796734)
			(xy 394.348116 -318.74895) (xy 394.344156 -318.699896) (xy 393.055094 -318.699896) (xy 393.054599 -318.724503)
			(xy 393.046704 -318.77308) (xy 393.03112 -318.819761) (xy 393.008249 -318.863338) (xy 392.978684 -318.902682)
			(xy 392.943191 -318.936774) (xy 392.902688 -318.96473) (xy 392.858226 -318.985828) (xy 392.810955 -318.99952)
			(xy 392.7621 -319.005452) (xy 392.712925 -319.003471) (xy 392.664706 -318.993627) (xy 392.61869 -318.976175)
			(xy 392.576069 -318.951568) (xy 392.537948 -318.920443) (xy 392.505313 -318.883606) (xy 392.47901 -318.84201)
			(xy 392.459719 -318.796734) (xy 392.447942 -318.74895) (xy 392.443982 -318.699896) (xy 379.626683 -318.699896)
			(xy 379.699893 -318.756463) (xy 379.81243 -318.853497) (xy 379.919597 -318.956432) (xy 380.021084 -319.064971)
			(xy 380.116598 -319.1788) (xy 380.205865 -319.297593) (xy 380.288626 -319.421005) (xy 380.364644 -319.548683)
			(xy 380.433699 -319.680256) (xy 380.495592 -319.815347) (xy 380.550145 -319.953564) (xy 380.5972 -320.094511)
			(xy 380.636622 -320.237781) (xy 380.668296 -320.38296) (xy 380.692132 -320.529629) (xy 380.708061 -320.677367)
			(xy 380.716037 -320.825747) (xy 380.716536 -320.900044) (xy 435.182527 -320.900044) (xy 435.186516 -320.751504)
			(xy 435.198473 -320.603391) (xy 435.218363 -320.456134) (xy 435.246128 -320.310158) (xy 435.281689 -320.165881)
			(xy 435.324943 -320.023722) (xy 435.375765 -319.884089) (xy 435.434009 -319.747386) (xy 435.499507 -319.614006)
			(xy 435.57207 -319.484334) (xy 435.651488 -319.358744) (xy 435.737533 -319.237597) (xy 435.829957 -319.121244)
			(xy 435.928493 -319.01002) (xy 436.032857 -318.904245) (xy 436.142749 -318.804225) (xy 436.25785 -318.710247)
			(xy 436.37783 -318.622583) (xy 436.502343 -318.541486) (xy 436.631029 -318.467189) (xy 436.763518 -318.399907)
			(xy 436.899427 -318.339833) (xy 437.038365 -318.287141) (xy 437.179931 -318.241982) (xy 437.323717 -318.204487)
			(xy 437.469308 -318.174765) (xy 437.616284 -318.1529) (xy 437.764223 -318.138956) (xy 437.912696 -318.132972)
			(xy 438.061277 -318.134967) (xy 438.209536 -318.144935) (xy 438.357047 -318.162846) (xy 438.503383 -318.188649)
			(xy 438.648124 -318.222269) (xy 438.790851 -318.263611) (xy 438.931154 -318.312554) (xy 439.068627 -318.368957)
			(xy 439.202874 -318.432658) (xy 439.333509 -318.503474) (xy 439.460154 -318.581199) (xy 439.582444 -318.66561)
			(xy 439.700027 -318.756463) (xy 439.812564 -318.853497) (xy 439.919731 -318.956432) (xy 440.021218 -319.064971)
			(xy 440.116732 -319.1788) (xy 440.205999 -319.297593) (xy 440.28876 -319.421005) (xy 440.364778 -319.548683)
			(xy 440.433833 -319.680256) (xy 440.495726 -319.815347) (xy 440.550279 -319.953564) (xy 440.597334 -320.094511)
			(xy 440.636756 -320.237781) (xy 440.66843 -320.38296) (xy 440.692266 -320.529629) (xy 440.708195 -320.677367)
			(xy 440.716171 -320.825747) (xy 440.71667 -320.900044) (xy 440.716171 -320.974341) (xy 440.708195 -321.122721)
			(xy 440.692266 -321.270459) (xy 440.66843 -321.417128) (xy 440.636756 -321.562307) (xy 440.597334 -321.705577)
			(xy 440.550279 -321.846524) (xy 440.495726 -321.984741) (xy 440.433833 -322.119832) (xy 440.364778 -322.251405)
			(xy 440.28876 -322.379083) (xy 440.205999 -322.502495) (xy 440.116732 -322.621288) (xy 440.021218 -322.735117)
			(xy 439.919731 -322.843656) (xy 439.812564 -322.946591) (xy 439.700027 -323.043625) (xy 439.582444 -323.134478)
			(xy 439.460154 -323.218889) (xy 439.333509 -323.296614) (xy 439.202874 -323.36743) (xy 439.068627 -323.431131)
			(xy 438.931154 -323.487534) (xy 438.790851 -323.536477) (xy 438.648124 -323.577819) (xy 438.503383 -323.611439)
			(xy 438.357047 -323.637242) (xy 438.209536 -323.655153) (xy 438.061277 -323.665121) (xy 437.912696 -323.667116)
			(xy 437.764223 -323.661132) (xy 437.616284 -323.647188) (xy 437.469308 -323.625323) (xy 437.323717 -323.595601)
			(xy 437.179931 -323.558106) (xy 437.038365 -323.512947) (xy 436.899427 -323.460255) (xy 436.763518 -323.400181)
			(xy 436.631029 -323.332899) (xy 436.502343 -323.258602) (xy 436.37783 -323.177505) (xy 436.25785 -323.089841)
			(xy 436.142749 -322.995863) (xy 436.032857 -322.895843) (xy 435.928493 -322.790068) (xy 435.829957 -322.678844)
			(xy 435.737533 -322.562491) (xy 435.651488 -322.441344) (xy 435.57207 -322.315754) (xy 435.499507 -322.186082)
			(xy 435.434009 -322.052702) (xy 435.375765 -321.915999) (xy 435.324943 -321.776366) (xy 435.281689 -321.634207)
			(xy 435.246128 -321.48993) (xy 435.218363 -321.343954) (xy 435.198473 -321.196697) (xy 435.186516 -321.048584)
			(xy 435.182527 -320.900044) (xy 380.716536 -320.900044) (xy 380.716037 -320.974341) (xy 380.708061 -321.122721)
			(xy 380.692132 -321.270459) (xy 380.668296 -321.417128) (xy 380.636622 -321.562307) (xy 380.5972 -321.705577)
			(xy 380.550145 -321.846524) (xy 380.495592 -321.984741) (xy 380.433699 -322.119832) (xy 380.364644 -322.251405)
			(xy 380.288626 -322.379083) (xy 380.205865 -322.502495) (xy 380.116598 -322.621288) (xy 380.021084 -322.735117)
			(xy 379.919597 -322.843656) (xy 379.81243 -322.946591) (xy 379.699893 -323.043625) (xy 379.58231 -323.134478)
			(xy 379.46002 -323.218889) (xy 379.333375 -323.296614) (xy 379.20274 -323.36743) (xy 379.068493 -323.431131)
			(xy 378.93102 -323.487534) (xy 378.790717 -323.536477) (xy 378.64799 -323.577819) (xy 378.503249 -323.611439)
			(xy 378.356913 -323.637242) (xy 378.209402 -323.655153) (xy 378.061143 -323.665121) (xy 377.912562 -323.667116)
			(xy 377.764089 -323.661132) (xy 377.61615 -323.647188) (xy 377.469174 -323.625323) (xy 377.323583 -323.595601)
			(xy 377.179797 -323.558106) (xy 377.038231 -323.512947) (xy 376.899293 -323.460255) (xy 376.763384 -323.400181)
			(xy 376.630895 -323.332899) (xy 376.502209 -323.258602) (xy 376.377696 -323.177505) (xy 376.257716 -323.089841)
			(xy 376.142615 -322.995863) (xy 376.032723 -322.895843) (xy 375.928359 -322.790068) (xy 375.829823 -322.678844)
			(xy 375.737399 -322.562491) (xy 375.651354 -322.441344) (xy 375.571936 -322.315754) (xy 375.499373 -322.186082)
			(xy 375.433875 -322.052702) (xy 375.375631 -321.915999) (xy 375.324809 -321.776366) (xy 375.281555 -321.634207)
			(xy 375.245994 -321.48993) (xy 375.218229 -321.343954) (xy 375.198339 -321.196697) (xy 375.186382 -321.048584)
			(xy 375.182393 -320.900044) (xy 324.616572 -320.900044) (xy 324.616073 -320.974341) (xy 324.608097 -321.122721)
			(xy 324.592168 -321.270459) (xy 324.568332 -321.417128) (xy 324.536658 -321.562307) (xy 324.497236 -321.705577)
			(xy 324.450181 -321.846524) (xy 324.395628 -321.984741) (xy 324.333735 -322.119832) (xy 324.26468 -322.251405)
			(xy 324.188662 -322.379083) (xy 324.105901 -322.502495) (xy 324.016634 -322.621288) (xy 323.92112 -322.735117)
			(xy 323.819633 -322.843656) (xy 323.712466 -322.946591) (xy 323.599929 -323.043625) (xy 323.482346 -323.134478)
			(xy 323.360056 -323.218889) (xy 323.233411 -323.296614) (xy 323.102776 -323.36743) (xy 322.968529 -323.431131)
			(xy 322.831056 -323.487534) (xy 322.690753 -323.536477) (xy 322.548026 -323.577819) (xy 322.403285 -323.611439)
			(xy 322.256949 -323.637242) (xy 322.109438 -323.655153) (xy 321.961179 -323.665121) (xy 321.812598 -323.667116)
			(xy 321.664125 -323.661132) (xy 321.516186 -323.647188) (xy 321.36921 -323.625323) (xy 321.223619 -323.595601)
			(xy 321.079833 -323.558106) (xy 320.938267 -323.512947) (xy 320.799329 -323.460255) (xy 320.66342 -323.400181)
			(xy 320.530931 -323.332899) (xy 320.402245 -323.258602) (xy 320.277732 -323.177505) (xy 320.157752 -323.089841)
			(xy 320.042651 -322.995863) (xy 319.932759 -322.895843) (xy 319.828395 -322.790068) (xy 319.729859 -322.678844)
			(xy 319.637435 -322.562491) (xy 319.55139 -322.441344) (xy 319.471972 -322.315754) (xy 319.399409 -322.186082)
			(xy 319.333911 -322.052702) (xy 319.275667 -321.915999) (xy 319.224845 -321.776366) (xy 319.181591 -321.634207)
			(xy 319.14603 -321.48993) (xy 319.118265 -321.343954) (xy 319.098375 -321.196697) (xy 319.086418 -321.048584)
			(xy 319.082429 -320.900044) (xy 264.616692 -320.900044) (xy 264.616193 -320.974341) (xy 264.608217 -321.122721)
			(xy 264.592288 -321.270459) (xy 264.568452 -321.417128) (xy 264.536778 -321.562307) (xy 264.497356 -321.705577)
			(xy 264.450301 -321.846524) (xy 264.395748 -321.984741) (xy 264.333855 -322.119832) (xy 264.2648 -322.251405)
			(xy 264.188782 -322.379083) (xy 264.106021 -322.502495) (xy 264.016754 -322.621288) (xy 263.92124 -322.735117)
			(xy 263.819753 -322.843656) (xy 263.712586 -322.946591) (xy 263.600049 -323.043625) (xy 263.482466 -323.134478)
			(xy 263.360176 -323.218889) (xy 263.233531 -323.296614) (xy 263.102896 -323.36743) (xy 262.968649 -323.431131)
			(xy 262.831176 -323.487534) (xy 262.690873 -323.536477) (xy 262.548146 -323.577819) (xy 262.403405 -323.611439)
			(xy 262.257069 -323.637242) (xy 262.109558 -323.655153) (xy 261.961299 -323.665121) (xy 261.812718 -323.667116)
			(xy 261.664245 -323.661132) (xy 261.516306 -323.647188) (xy 261.36933 -323.625323) (xy 261.223739 -323.595601)
			(xy 261.079953 -323.558106) (xy 260.938387 -323.512947) (xy 260.799449 -323.460255) (xy 260.66354 -323.400181)
			(xy 260.531051 -323.332899) (xy 260.402365 -323.258602) (xy 260.277852 -323.177505) (xy 260.157872 -323.089841)
			(xy 260.042771 -322.995863) (xy 259.932879 -322.895843) (xy 259.828515 -322.790068) (xy 259.729979 -322.678844)
			(xy 259.637555 -322.562491) (xy 259.55151 -322.441344) (xy 259.472092 -322.315754) (xy 259.399529 -322.186082)
			(xy 259.334031 -322.052702) (xy 259.275787 -321.915999) (xy 259.224965 -321.776366) (xy 259.181711 -321.634207)
			(xy 259.14615 -321.48993) (xy 259.118385 -321.343954) (xy 259.098495 -321.196697) (xy 259.086538 -321.048584)
			(xy 259.082549 -320.900044) (xy 208.516474 -320.900044) (xy 208.515975 -320.974341) (xy 208.507999 -321.122721)
			(xy 208.49207 -321.270459) (xy 208.468234 -321.417128) (xy 208.43656 -321.562307) (xy 208.397138 -321.705577)
			(xy 208.350083 -321.846524) (xy 208.29553 -321.984741) (xy 208.233637 -322.119832) (xy 208.164582 -322.251405)
			(xy 208.088564 -322.379083) (xy 208.005803 -322.502495) (xy 207.916536 -322.621288) (xy 207.821022 -322.735117)
			(xy 207.719535 -322.843656) (xy 207.612368 -322.946591) (xy 207.499831 -323.043625) (xy 207.382248 -323.134478)
			(xy 207.259958 -323.218889) (xy 207.133313 -323.296614) (xy 207.002678 -323.36743) (xy 206.868431 -323.431131)
			(xy 206.730958 -323.487534) (xy 206.590655 -323.536477) (xy 206.447928 -323.577819) (xy 206.303187 -323.611439)
			(xy 206.156851 -323.637242) (xy 206.00934 -323.655153) (xy 205.861081 -323.665121) (xy 205.7125 -323.667116)
			(xy 205.564027 -323.661132) (xy 205.416088 -323.647188) (xy 205.269112 -323.625323) (xy 205.123521 -323.595601)
			(xy 204.979735 -323.558106) (xy 204.838169 -323.512947) (xy 204.699231 -323.460255) (xy 204.563322 -323.400181)
			(xy 204.430833 -323.332899) (xy 204.302147 -323.258602) (xy 204.177634 -323.177505) (xy 204.057654 -323.089841)
			(xy 203.942553 -322.995863) (xy 203.832661 -322.895843) (xy 203.728297 -322.790068) (xy 203.629761 -322.678844)
			(xy 203.537337 -322.562491) (xy 203.451292 -322.441344) (xy 203.371874 -322.315754) (xy 203.299311 -322.186082)
			(xy 203.233813 -322.052702) (xy 203.175569 -321.915999) (xy 203.124747 -321.776366) (xy 203.081493 -321.634207)
			(xy 203.045932 -321.48993) (xy 203.018167 -321.343954) (xy 202.998277 -321.196697) (xy 202.98632 -321.048584)
			(xy 202.982331 -320.900044) (xy 148.516594 -320.900044) (xy 148.516095 -320.974341) (xy 148.508119 -321.122721)
			(xy 148.49219 -321.270459) (xy 148.468354 -321.417128) (xy 148.43668 -321.562307) (xy 148.397258 -321.705577)
			(xy 148.350203 -321.846524) (xy 148.29565 -321.984741) (xy 148.233757 -322.119832) (xy 148.164702 -322.251405)
			(xy 148.088684 -322.379083) (xy 148.005923 -322.502495) (xy 147.916656 -322.621288) (xy 147.821142 -322.735117)
			(xy 147.719655 -322.843656) (xy 147.612488 -322.946591) (xy 147.499951 -323.043625) (xy 147.382368 -323.134478)
			(xy 147.260078 -323.218889) (xy 147.133433 -323.296614) (xy 147.002798 -323.36743) (xy 146.868551 -323.431131)
			(xy 146.731078 -323.487534) (xy 146.590775 -323.536477) (xy 146.448048 -323.577819) (xy 146.303307 -323.611439)
			(xy 146.156971 -323.637242) (xy 146.00946 -323.655153) (xy 145.861201 -323.665121) (xy 145.71262 -323.667116)
			(xy 145.564147 -323.661132) (xy 145.416208 -323.647188) (xy 145.269232 -323.625323) (xy 145.123641 -323.595601)
			(xy 144.979855 -323.558106) (xy 144.838289 -323.512947) (xy 144.699351 -323.460255) (xy 144.563442 -323.400181)
			(xy 144.430953 -323.332899) (xy 144.302267 -323.258602) (xy 144.177754 -323.177505) (xy 144.057774 -323.089841)
			(xy 143.942673 -322.995863) (xy 143.832781 -322.895843) (xy 143.728417 -322.790068) (xy 143.629881 -322.678844)
			(xy 143.537457 -322.562491) (xy 143.451412 -322.441344) (xy 143.371994 -322.315754) (xy 143.299431 -322.186082)
			(xy 143.233933 -322.052702) (xy 143.175689 -321.915999) (xy 143.124867 -321.776366) (xy 143.081613 -321.634207)
			(xy 143.046052 -321.48993) (xy 143.018287 -321.343954) (xy 142.998397 -321.196697) (xy 142.98644 -321.048584)
			(xy 142.982451 -320.900044) (xy 92.41663 -320.900044) (xy 92.416131 -320.974341) (xy 92.408155 -321.122721)
			(xy 92.392226 -321.270459) (xy 92.36839 -321.417128) (xy 92.336716 -321.562307) (xy 92.297294 -321.705577)
			(xy 92.250239 -321.846524) (xy 92.195686 -321.984741) (xy 92.133793 -322.119832) (xy 92.064738 -322.251405)
			(xy 91.98872 -322.379083) (xy 91.905959 -322.502495) (xy 91.816692 -322.621288) (xy 91.721178 -322.735117)
			(xy 91.619691 -322.843656) (xy 91.512524 -322.946591) (xy 91.399987 -323.043625) (xy 91.282404 -323.134478)
			(xy 91.160114 -323.218889) (xy 91.033469 -323.296614) (xy 90.902834 -323.36743) (xy 90.768587 -323.431131)
			(xy 90.631114 -323.487534) (xy 90.490811 -323.536477) (xy 90.348084 -323.577819) (xy 90.203343 -323.611439)
			(xy 90.057007 -323.637242) (xy 89.909496 -323.655153) (xy 89.761237 -323.665121) (xy 89.612656 -323.667116)
			(xy 89.464183 -323.661132) (xy 89.316244 -323.647188) (xy 89.169268 -323.625323) (xy 89.023677 -323.595601)
			(xy 88.879891 -323.558106) (xy 88.738325 -323.512947) (xy 88.599387 -323.460255) (xy 88.463478 -323.400181)
			(xy 88.330989 -323.332899) (xy 88.202303 -323.258602) (xy 88.07779 -323.177505) (xy 87.95781 -323.089841)
			(xy 87.842709 -322.995863) (xy 87.732817 -322.895843) (xy 87.628453 -322.790068) (xy 87.529917 -322.678844)
			(xy 87.437493 -322.562491) (xy 87.351448 -322.441344) (xy 87.27203 -322.315754) (xy 87.199467 -322.186082)
			(xy 87.133969 -322.052702) (xy 87.075725 -321.915999) (xy 87.024903 -321.776366) (xy 86.981649 -321.634207)
			(xy 86.946088 -321.48993) (xy 86.918323 -321.343954) (xy 86.898433 -321.196697) (xy 86.886476 -321.048584)
			(xy 86.882487 -320.900044) (xy 32.416496 -320.900044) (xy 32.415997 -320.974341) (xy 32.408021 -321.122721)
			(xy 32.392092 -321.270459) (xy 32.368256 -321.417128) (xy 32.336582 -321.562307) (xy 32.29716 -321.705577)
			(xy 32.250105 -321.846524) (xy 32.195552 -321.984741) (xy 32.133659 -322.119832) (xy 32.064604 -322.251405)
			(xy 31.988586 -322.379083) (xy 31.905825 -322.502495) (xy 31.816558 -322.621288) (xy 31.721044 -322.735117)
			(xy 31.619557 -322.843656) (xy 31.51239 -322.946591) (xy 31.399853 -323.043625) (xy 31.28227 -323.134478)
			(xy 31.15998 -323.218889) (xy 31.033335 -323.296614) (xy 30.9027 -323.36743) (xy 30.768453 -323.431131)
			(xy 30.63098 -323.487534) (xy 30.490677 -323.536477) (xy 30.34795 -323.577819) (xy 30.203209 -323.611439)
			(xy 30.056873 -323.637242) (xy 29.909362 -323.655153) (xy 29.761103 -323.665121) (xy 29.612522 -323.667116)
			(xy 29.464049 -323.661132) (xy 29.31611 -323.647188) (xy 29.169134 -323.625323) (xy 29.023543 -323.595601)
			(xy 28.879757 -323.558106) (xy 28.738191 -323.512947) (xy 28.599253 -323.460255) (xy 28.463344 -323.400181)
			(xy 28.330855 -323.332899) (xy 28.202169 -323.258602) (xy 28.077656 -323.177505) (xy 27.957676 -323.089841)
			(xy 27.842575 -322.995863) (xy 27.732683 -322.895843) (xy 27.628319 -322.790068) (xy 27.529783 -322.678844)
			(xy 27.437359 -322.562491) (xy 27.351314 -322.441344) (xy 27.271896 -322.315754) (xy 27.199333 -322.186082)
			(xy 27.133835 -322.052702) (xy 27.075591 -321.915999) (xy 27.024769 -321.776366) (xy 26.981515 -321.634207)
			(xy 26.945954 -321.48993) (xy 26.918189 -321.343954) (xy 26.898299 -321.196697) (xy 26.886342 -321.048584)
			(xy 26.882353 -320.900044) (xy 0.508 -320.900044) (xy 0.508 -330.416662) (xy 97.355152 -330.416662)
			(xy 97.355152 -329.553062) (xy 97.355642 -329.523078) (xy 97.36347 -329.463622) (xy 97.378991 -329.405697)
			(xy 97.40194 -329.350293) (xy 97.431924 -329.298359) (xy 97.46843 -329.250783) (xy 97.510835 -329.208378)
			(xy 97.558411 -329.171872) (xy 97.610345 -329.141888) (xy 97.665749 -329.118939) (xy 97.723674 -329.103418)
			(xy 97.78313 -329.09559) (xy 97.843098 -329.09559) (xy 97.902554 -329.103418) (xy 97.960479 -329.118939)
			(xy 98.015883 -329.141888) (xy 98.067817 -329.171872) (xy 98.115393 -329.208378) (xy 98.157798 -329.250783)
			(xy 98.194304 -329.298359) (xy 98.224288 -329.350293) (xy 98.247237 -329.405697) (xy 98.262758 -329.463622)
			(xy 98.270586 -329.523078) (xy 98.271076 -329.553062) (xy 98.271076 -330.416662) (xy 98.270586 -330.446646)
			(xy 98.262758 -330.506102) (xy 98.247237 -330.564027) (xy 98.224288 -330.619431) (xy 98.194304 -330.671365)
			(xy 98.157798 -330.718941) (xy 98.115393 -330.761346) (xy 98.067817 -330.797852) (xy 98.015883 -330.827836)
			(xy 97.960479 -330.850785) (xy 97.902554 -330.866306) (xy 97.843098 -330.874134) (xy 97.78313 -330.874134)
			(xy 97.723674 -330.866306) (xy 97.665749 -330.850785) (xy 97.610345 -330.827836) (xy 97.558411 -330.797852)
			(xy 97.510835 -330.761346) (xy 97.46843 -330.718941) (xy 97.431924 -330.671365) (xy 97.40194 -330.619431)
			(xy 97.378991 -330.564027) (xy 97.36347 -330.506102) (xy 97.355642 -330.446646) (xy 97.355152 -330.416662)
			(xy 0.508 -330.416662) (xy 0.508 -331.53223) (xy 114.955828 -331.53223) (xy 114.955828 -330.66863)
			(xy 114.956318 -330.638646) (xy 114.964146 -330.57919) (xy 114.979667 -330.521265) (xy 115.002616 -330.465861)
			(xy 115.0326 -330.413927) (xy 115.069106 -330.366351) (xy 115.111511 -330.323946) (xy 115.159087 -330.28744)
			(xy 115.211021 -330.257456) (xy 115.266425 -330.234507) (xy 115.32435 -330.218986) (xy 115.383806 -330.211158)
			(xy 115.443774 -330.211158) (xy 115.50323 -330.218986) (xy 115.561155 -330.234507) (xy 115.616559 -330.257456)
			(xy 115.668493 -330.28744) (xy 115.716069 -330.323946) (xy 115.758474 -330.366351) (xy 115.79498 -330.413927)
			(xy 115.824964 -330.465861) (xy 115.847913 -330.521265) (xy 115.863434 -330.57919) (xy 115.871262 -330.638646)
			(xy 115.871752 -330.66863) (xy 115.871752 -331.53223) (xy 115.871262 -331.562214) (xy 115.863434 -331.62167)
			(xy 115.847913 -331.679595) (xy 115.824964 -331.734999) (xy 115.79498 -331.786933) (xy 115.758474 -331.834509)
			(xy 115.716069 -331.876914) (xy 115.668493 -331.91342) (xy 115.616559 -331.943404) (xy 115.561155 -331.966353)
			(xy 115.50323 -331.981874) (xy 115.443774 -331.989702) (xy 115.383806 -331.989702) (xy 115.32435 -331.981874)
			(xy 115.266425 -331.966353) (xy 115.211021 -331.943404) (xy 115.159087 -331.91342) (xy 115.111511 -331.876914)
			(xy 115.069106 -331.834509) (xy 115.0326 -331.786933) (xy 115.002616 -331.734999) (xy 114.979667 -331.679595)
			(xy 114.964146 -331.62167) (xy 114.956318 -331.562214) (xy 114.955828 -331.53223) (xy 0.508 -331.53223)
			(xy 0.508 -333.950056) (xy 93.5736 -333.950056) (xy 93.5736 -333.086456) (xy 93.57409 -333.056488)
			(xy 93.581913 -332.997066) (xy 93.597426 -332.939173) (xy 93.620362 -332.8838) (xy 93.650329 -332.831894)
			(xy 93.686816 -332.784344) (xy 93.729196 -332.741964) (xy 93.776746 -332.705477) (xy 93.828652 -332.67551)
			(xy 93.884025 -332.652574) (xy 93.941918 -332.637061) (xy 94.00134 -332.629238) (xy 94.061276 -332.629238)
			(xy 94.120698 -332.637061) (xy 94.178591 -332.652574) (xy 94.233964 -332.67551) (xy 94.28587 -332.705477)
			(xy 94.33342 -332.741964) (xy 94.3758 -332.784344) (xy 94.412287 -332.831894) (xy 94.442254 -332.8838)
			(xy 94.46519 -332.939173) (xy 94.46736 -332.947271) (xy 365.368753 -332.947271) (xy 365.368753 -332.887329)
			(xy 365.376578 -332.827899) (xy 365.392093 -332.77) (xy 365.415033 -332.71462) (xy 365.445006 -332.66271)
			(xy 365.481498 -332.615155) (xy 365.523886 -332.572772) (xy 365.571443 -332.536283) (xy 365.623356 -332.506315)
			(xy 365.678737 -332.48338) (xy 365.736639 -332.46787) (xy 365.796069 -332.460051) (xy 365.82604 -332.459584)
			(xy 366.68964 -332.459584) (xy 366.719605 -332.460093) (xy 366.779023 -332.46792) (xy 366.836911 -332.483435)
			(xy 366.892278 -332.506374) (xy 366.944178 -332.536342) (xy 366.991723 -332.572828) (xy 367.034098 -332.615207)
			(xy 367.07058 -332.662755) (xy 367.100544 -332.714658) (xy 367.123478 -332.770027) (xy 367.138988 -332.827916)
			(xy 367.14681 -332.887335) (xy 367.14681 -332.947265) (xy 367.138988 -333.006684) (xy 367.123478 -333.064573)
			(xy 367.100544 -333.119942) (xy 367.07058 -333.171845) (xy 367.034098 -333.219393) (xy 366.991723 -333.261772)
			(xy 366.944178 -333.298258) (xy 366.892278 -333.328226) (xy 366.836911 -333.351165) (xy 366.779023 -333.36668)
			(xy 366.719605 -333.374507) (xy 366.68964 -333.375) (xy 365.82604 -333.375) (xy 365.796069 -333.374549)
			(xy 365.736639 -333.36673) (xy 365.678737 -333.35122) (xy 365.623356 -333.328285) (xy 365.571443 -333.298317)
			(xy 365.523886 -333.261828) (xy 365.481498 -333.219445) (xy 365.445006 -333.17189) (xy 365.415033 -333.11998)
			(xy 365.392093 -333.0646) (xy 365.376578 -333.006701) (xy 365.368753 -332.947271) (xy 94.46736 -332.947271)
			(xy 94.480703 -332.997066) (xy 94.488526 -333.056488) (xy 94.489016 -333.086456) (xy 94.489016 -333.950056)
			(xy 94.488526 -333.980024) (xy 94.480703 -334.039446) (xy 94.46519 -334.097339) (xy 94.442254 -334.152712)
			(xy 94.412287 -334.204618) (xy 94.3758 -334.252168) (xy 94.33342 -334.294548) (xy 94.28587 -334.331035)
			(xy 94.233964 -334.361002) (xy 94.178591 -334.383938) (xy 94.120698 -334.399451) (xy 94.061276 -334.407274)
			(xy 94.00134 -334.407274) (xy 93.941918 -334.399451) (xy 93.884025 -334.383938) (xy 93.828652 -334.361002)
			(xy 93.776746 -334.331035) (xy 93.729196 -334.294548) (xy 93.686816 -334.252168) (xy 93.650329 -334.204618)
			(xy 93.620362 -334.152712) (xy 93.597426 -334.097339) (xy 93.581913 -334.039446) (xy 93.57409 -333.980024)
			(xy 93.5736 -333.950056) (xy 0.508 -333.950056) (xy 0.508 -337.266026) (xy 234.403392 -337.266026)
			(xy 234.403392 -336.402426) (xy 234.403882 -336.372458) (xy 234.411705 -336.313036) (xy 234.427218 -336.255143)
			(xy 234.450154 -336.19977) (xy 234.480121 -336.147864) (xy 234.516608 -336.100314) (xy 234.558988 -336.057934)
			(xy 234.606538 -336.021447) (xy 234.658444 -335.99148) (xy 234.713817 -335.968544) (xy 234.77171 -335.953031)
			(xy 234.831132 -335.945208) (xy 234.891068 -335.945208) (xy 234.95049 -335.953031) (xy 235.008383 -335.968544)
			(xy 235.063756 -335.99148) (xy 235.115662 -336.021447) (xy 235.163212 -336.057934) (xy 235.205592 -336.100314)
			(xy 235.242079 -336.147864) (xy 235.272046 -336.19977) (xy 235.294982 -336.255143) (xy 235.310495 -336.313036)
			(xy 235.318318 -336.372458) (xy 235.318808 -336.402426) (xy 235.318808 -337.266026) (xy 235.318318 -337.295994)
			(xy 235.310495 -337.355416) (xy 235.294982 -337.413309) (xy 235.272046 -337.468682) (xy 235.242079 -337.520588)
			(xy 235.205592 -337.568138) (xy 235.163212 -337.610518) (xy 235.115662 -337.647005) (xy 235.063756 -337.676972)
			(xy 235.008383 -337.699908) (xy 234.95049 -337.715421) (xy 234.891068 -337.723244) (xy 234.831132 -337.723244)
			(xy 234.77171 -337.715421) (xy 234.713817 -337.699908) (xy 234.658444 -337.676972) (xy 234.606538 -337.647005)
			(xy 234.558988 -337.610518) (xy 234.516608 -337.568138) (xy 234.480121 -337.520588) (xy 234.450154 -337.468682)
			(xy 234.427218 -337.413309) (xy 234.411705 -337.355416) (xy 234.403882 -337.295994) (xy 234.403392 -337.266026)
			(xy 0.508 -337.266026) (xy 0.508 -342.466769) (xy 18.951172 -342.466769) (xy 18.951172 -342.412231)
			(xy 18.958934 -342.358247) (xy 18.974299 -342.305917) (xy 18.996956 -342.256307) (xy 19.026441 -342.210426)
			(xy 19.062157 -342.169208) (xy 19.103374 -342.133493) (xy 19.149255 -342.104007) (xy 19.198865 -342.08135)
			(xy 19.251195 -342.065985) (xy 19.305179 -342.058223) (xy 19.332448 -342.057736) (xy 20.196048 -342.057736)
			(xy 20.223319 -342.058203) (xy 20.277306 -342.065965) (xy 20.329638 -342.081331) (xy 20.379252 -342.103989)
			(xy 20.425135 -342.133476) (xy 20.466355 -342.169193) (xy 20.502073 -342.210413) (xy 20.53156 -342.256297)
			(xy 20.554218 -342.30591) (xy 20.569584 -342.358242) (xy 20.577347 -342.412229) (xy 20.577347 -342.466771)
			(xy 20.577347 -342.466772) (xy 22.0601 -342.466772) (xy 22.0601 -342.412228) (xy 22.067862 -342.358241)
			(xy 22.083229 -342.305907) (xy 22.105887 -342.256293) (xy 22.135375 -342.210409) (xy 22.171094 -342.169188)
			(xy 22.212315 -342.133471) (xy 22.2582 -342.103983) (xy 22.307815 -342.081326) (xy 22.360148 -342.06596)
			(xy 22.414136 -342.058199) (xy 22.441408 -342.057736) (xy 23.305008 -342.057736) (xy 23.332277 -342.058227)
			(xy 23.386259 -342.06599) (xy 23.438588 -342.081355) (xy 23.488197 -342.104012) (xy 23.534076 -342.133498)
			(xy 23.575293 -342.169213) (xy 23.611007 -342.21043) (xy 23.640492 -342.256311) (xy 23.663147 -342.30592)
			(xy 23.678512 -342.358249) (xy 23.686274 -342.412231) (xy 23.686274 -342.466768) (xy 25.169122 -342.466768)
			(xy 25.169122 -342.412232) (xy 25.176883 -342.358251) (xy 25.192247 -342.305924) (xy 25.214901 -342.256315)
			(xy 25.244384 -342.210436) (xy 25.280096 -342.169219) (xy 25.32131 -342.133503) (xy 25.367187 -342.104016)
			(xy 25.416794 -342.081358) (xy 25.46912 -342.06599) (xy 25.5231 -342.058225) (xy 25.550368 -342.057736)
			(xy 26.413968 -342.057736) (xy 26.44124 -342.058201) (xy 26.49523 -342.06596) (xy 26.547567 -342.081323)
			(xy 26.597184 -342.103979) (xy 26.643071 -342.133465) (xy 26.684295 -342.169183) (xy 26.720015 -342.210403)
			(xy 26.749506 -342.256288) (xy 26.772166 -342.305903) (xy 26.787533 -342.358238) (xy 26.795296 -342.412228)
			(xy 26.795296 -342.466772) (xy 28.278 -342.466772) (xy 28.278 -342.412228) (xy 28.285762 -342.358238)
			(xy 28.30113 -342.305903) (xy 28.32379 -342.256288) (xy 28.35328 -342.210402) (xy 28.389001 -342.169181)
			(xy 28.430225 -342.133464) (xy 28.476112 -342.103977) (xy 28.525729 -342.08132) (xy 28.578065 -342.065957)
			(xy 28.632056 -342.058198) (xy 28.659328 -342.057736) (xy 29.522928 -342.057736) (xy 29.550196 -342.058228)
			(xy 29.604176 -342.065993) (xy 29.656502 -342.081361) (xy 29.706109 -342.104019) (xy 29.751986 -342.133505)
			(xy 29.7932 -342.16922) (xy 29.828912 -342.210437) (xy 29.858395 -342.256316) (xy 29.881049 -342.305924)
			(xy 29.896413 -342.358251) (xy 29.904174 -342.412232) (xy 29.904174 -342.466768) (xy 29.904174 -342.466769)
			(xy 31.387022 -342.466769) (xy 31.387022 -342.412231) (xy 31.394784 -342.358248) (xy 31.410149 -342.305919)
			(xy 31.432804 -342.25631) (xy 31.462289 -342.210429) (xy 31.498003 -342.169212) (xy 31.53922 -342.133496)
			(xy 31.585099 -342.10401) (xy 31.634708 -342.081353) (xy 31.687036 -342.065986) (xy 31.741019 -342.058223)
			(xy 31.768288 -342.057736) (xy 32.631888 -342.057736) (xy 32.659159 -342.058203) (xy 32.713147 -342.065963)
			(xy 32.765481 -342.081329) (xy 32.815096 -342.103985) (xy 32.86098 -342.133472) (xy 32.902202 -342.16919)
			(xy 32.93792 -342.21041) (xy 32.967409 -342.256294) (xy 32.990067 -342.305908) (xy 33.005434 -342.358241)
			(xy 33.013196 -342.412229) (xy 33.013196 -342.466771) (xy 33.013196 -342.466773) (xy 34.4959 -342.466773)
			(xy 34.4959 -342.412227) (xy 34.503663 -342.358235) (xy 34.519032 -342.305899) (xy 34.541693 -342.256282)
			(xy 34.571185 -342.210396) (xy 34.606908 -342.169174) (xy 34.648134 -342.133456) (xy 34.694024 -342.10397)
			(xy 34.743644 -342.081315) (xy 34.795982 -342.065953) (xy 34.849975 -342.058196) (xy 34.877248 -342.057736)
			(xy 35.740848 -342.057736) (xy 35.768115 -342.05823) (xy 35.822093 -342.065997) (xy 35.874417 -342.081366)
			(xy 35.92402 -342.104025) (xy 35.969895 -342.133512) (xy 36.011107 -342.169227) (xy 36.046817 -342.210443)
			(xy 36.076298 -342.256322) (xy 36.098951 -342.305928) (xy 36.114313 -342.358254) (xy 36.122074 -342.412233)
			(xy 36.122074 -342.466767) (xy 36.122073 -342.466772) (xy 37.6049 -342.466772) (xy 37.6049 -342.412228)
			(xy 37.612662 -342.358241) (xy 37.628029 -342.305907) (xy 37.650687 -342.256293) (xy 37.680175 -342.210409)
			(xy 37.715894 -342.169188) (xy 37.757115 -342.133471) (xy 37.803 -342.103983) (xy 37.852615 -342.081326)
			(xy 37.904948 -342.06596) (xy 37.958936 -342.058199) (xy 37.986208 -342.057736) (xy 38.849808 -342.057736)
			(xy 38.877077 -342.058227) (xy 38.931059 -342.06599) (xy 38.983388 -342.081355) (xy 39.032997 -342.104012)
			(xy 39.078876 -342.133498) (xy 39.120093 -342.169213) (xy 39.155807 -342.21043) (xy 39.185292 -342.256311)
			(xy 39.207947 -342.30592) (xy 39.223312 -342.358249) (xy 39.231074 -342.412231) (xy 39.231074 -342.466768)
			(xy 40.713922 -342.466768) (xy 40.713922 -342.412232) (xy 40.721683 -342.358251) (xy 40.737047 -342.305924)
			(xy 40.759701 -342.256315) (xy 40.789184 -342.210436) (xy 40.824896 -342.169219) (xy 40.86611 -342.133503)
			(xy 40.911987 -342.104016) (xy 40.961594 -342.081358) (xy 41.01392 -342.06599) (xy 41.0679 -342.058225)
			(xy 41.095168 -342.057736) (xy 41.958768 -342.057736) (xy 41.98604 -342.058201) (xy 42.04003 -342.06596)
			(xy 42.092367 -342.081323) (xy 42.141984 -342.103979) (xy 42.187871 -342.133465) (xy 42.229095 -342.169183)
			(xy 42.264815 -342.210403) (xy 42.294306 -342.256288) (xy 42.316966 -342.305903) (xy 42.332333 -342.358238)
			(xy 42.340096 -342.412228) (xy 42.340096 -342.466772) (xy 43.8228 -342.466772) (xy 43.8228 -342.412228)
			(xy 43.830562 -342.358238) (xy 43.84593 -342.305903) (xy 43.86859 -342.256288) (xy 43.89808 -342.210402)
			(xy 43.933801 -342.169181) (xy 43.975025 -342.133464) (xy 44.020912 -342.103977) (xy 44.070529 -342.08132)
			(xy 44.122865 -342.065957) (xy 44.176856 -342.058198) (xy 44.204128 -342.057736) (xy 45.067728 -342.057736)
			(xy 45.094996 -342.058228) (xy 45.148976 -342.065993) (xy 45.201302 -342.081361) (xy 45.250909 -342.104019)
			(xy 45.296786 -342.133505) (xy 45.338 -342.16922) (xy 45.373712 -342.210437) (xy 45.403195 -342.256316)
			(xy 45.425849 -342.305924) (xy 45.441213 -342.358251) (xy 45.448974 -342.412232) (xy 45.448974 -342.466768)
			(xy 45.448974 -342.466769) (xy 46.931822 -342.466769) (xy 46.931822 -342.412231) (xy 46.939584 -342.358248)
			(xy 46.954949 -342.305919) (xy 46.977604 -342.25631) (xy 47.007089 -342.210429) (xy 47.042803 -342.169212)
			(xy 47.08402 -342.133496) (xy 47.129899 -342.10401) (xy 47.179508 -342.081353) (xy 47.231836 -342.065986)
			(xy 47.285819 -342.058223) (xy 47.313088 -342.057736) (xy 48.176688 -342.057736) (xy 48.203959 -342.058203)
			(xy 48.257947 -342.065963) (xy 48.310281 -342.081329) (xy 48.359896 -342.103985) (xy 48.40578 -342.133472)
			(xy 48.447002 -342.16919) (xy 48.48272 -342.21041) (xy 48.512209 -342.256294) (xy 48.534867 -342.305908)
			(xy 48.550234 -342.358241) (xy 48.557996 -342.412229) (xy 48.557996 -342.466771) (xy 48.557996 -342.466773)
			(xy 50.0407 -342.466773) (xy 50.0407 -342.412227) (xy 50.048463 -342.358235) (xy 50.063832 -342.305899)
			(xy 50.086493 -342.256282) (xy 50.115985 -342.210396) (xy 50.151708 -342.169174) (xy 50.192934 -342.133456)
			(xy 50.238824 -342.10397) (xy 50.288444 -342.081315) (xy 50.340782 -342.065953) (xy 50.394775 -342.058196)
			(xy 50.422048 -342.057736) (xy 51.285648 -342.057736) (xy 51.312915 -342.05823) (xy 51.366893 -342.065997)
			(xy 51.419217 -342.081366) (xy 51.46882 -342.104025) (xy 51.514695 -342.133512) (xy 51.555907 -342.169227)
			(xy 51.591617 -342.210443) (xy 51.621098 -342.256322) (xy 51.643751 -342.305928) (xy 51.659113 -342.358254)
			(xy 51.666874 -342.412233) (xy 51.666874 -342.466767) (xy 51.666873 -342.466773) (xy 60.9909 -342.466773)
			(xy 60.9909 -342.412227) (xy 60.998663 -342.358236) (xy 61.014031 -342.3059) (xy 61.036692 -342.256284)
			(xy 61.066184 -342.210398) (xy 61.101906 -342.169176) (xy 61.143131 -342.133459) (xy 61.18902 -342.103972)
			(xy 61.238639 -342.081317) (xy 61.290977 -342.065954) (xy 61.344969 -342.058197) (xy 61.372242 -342.057736)
			(xy 62.235842 -342.057736) (xy 62.263109 -342.058229) (xy 62.317088 -342.065996) (xy 62.369412 -342.081365)
			(xy 62.419017 -342.104023) (xy 62.464892 -342.13351) (xy 62.506105 -342.169225) (xy 62.541815 -342.210441)
			(xy 62.571297 -342.25632) (xy 62.59395 -342.305927) (xy 62.609313 -342.358253) (xy 62.617074 -342.412233)
			(xy 62.617074 -342.466767) (xy 62.617073 -342.466771) (xy 64.099899 -342.466771) (xy 64.099899 -342.412229)
			(xy 64.107662 -342.358241) (xy 64.123028 -342.305908) (xy 64.145686 -342.256295) (xy 64.175174 -342.210411)
			(xy 64.210892 -342.16919) (xy 64.252112 -342.133473) (xy 64.297997 -342.103985) (xy 64.34761 -342.081327)
			(xy 64.399943 -342.065961) (xy 64.453931 -342.058199) (xy 64.481202 -342.057736) (xy 65.344802 -342.057736)
			(xy 65.372071 -342.058227) (xy 65.426054 -342.065988) (xy 65.478383 -342.081354) (xy 65.527993 -342.10401)
			(xy 65.573873 -342.133496) (xy 65.615091 -342.169211) (xy 65.650805 -342.210428) (xy 65.680291 -342.256309)
			(xy 65.702947 -342.305919) (xy 65.718312 -342.358248) (xy 65.726074 -342.412231) (xy 65.726074 -342.466768)
			(xy 67.208922 -342.466768) (xy 67.208922 -342.412232) (xy 67.216683 -342.358252) (xy 67.232047 -342.305925)
			(xy 67.2547 -342.256317) (xy 67.284183 -342.210438) (xy 67.319894 -342.169221) (xy 67.361107 -342.133505)
			(xy 67.406984 -342.104018) (xy 67.456589 -342.08136) (xy 67.508914 -342.065991) (xy 67.562894 -342.058225)
			(xy 67.590162 -342.057736) (xy 68.453762 -342.057736) (xy 68.481035 -342.058201) (xy 68.535025 -342.065959)
			(xy 68.587362 -342.081321) (xy 68.63698 -342.103977) (xy 68.682868 -342.133463) (xy 68.724093 -342.16918)
			(xy 68.759814 -342.210401) (xy 68.789305 -342.256287) (xy 68.811965 -342.305902) (xy 68.827333 -342.358237)
			(xy 68.835096 -342.412227) (xy 68.835096 -342.466772) (xy 70.3178 -342.466772) (xy 70.3178 -342.412228)
			(xy 70.325562 -342.358239) (xy 70.34093 -342.305904) (xy 70.363589 -342.256289) (xy 70.393079 -342.210404)
			(xy 70.428799 -342.169183) (xy 70.470022 -342.133466) (xy 70.515909 -342.103979) (xy 70.565525 -342.081322)
			(xy 70.61786 -342.065958) (xy 70.67185 -342.058198) (xy 70.699122 -342.057736) (xy 71.562722 -342.057736)
			(xy 71.58999 -342.058228) (xy 71.643971 -342.065992) (xy 71.696298 -342.081359) (xy 71.745905 -342.104017)
			(xy 71.791783 -342.133503) (xy 71.832998 -342.169218) (xy 71.86871 -342.210435) (xy 71.898194 -342.256314)
			(xy 71.920848 -342.305923) (xy 71.936213 -342.35825) (xy 71.943974 -342.412232) (xy 71.943974 -342.466768)
			(xy 71.943974 -342.466769) (xy 73.426822 -342.466769) (xy 73.426822 -342.412231) (xy 73.434584 -342.358249)
			(xy 73.449948 -342.305921) (xy 73.472603 -342.256311) (xy 73.502087 -342.210431) (xy 73.537801 -342.169214)
			(xy 73.579017 -342.133498) (xy 73.624896 -342.104012) (xy 73.674504 -342.081354) (xy 73.726831 -342.065987)
			(xy 73.780813 -342.058224) (xy 73.808082 -342.057736) (xy 74.671682 -342.057736) (xy 74.698954 -342.058202)
			(xy 74.752942 -342.065962) (xy 74.805277 -342.081327) (xy 74.854892 -342.103983) (xy 74.900778 -342.13347)
			(xy 74.942 -342.169188) (xy 74.977719 -342.210408) (xy 75.007208 -342.256292) (xy 75.029867 -342.305906)
			(xy 75.045234 -342.35824) (xy 75.052996 -342.412228) (xy 75.052996 -342.466772) (xy 75.052996 -342.466773)
			(xy 76.5357 -342.466773) (xy 76.5357 -342.412227) (xy 76.543463 -342.358236) (xy 76.558831 -342.3059)
			(xy 76.581492 -342.256284) (xy 76.610984 -342.210398) (xy 76.646706 -342.169176) (xy 76.687931 -342.133459)
			(xy 76.73382 -342.103972) (xy 76.783439 -342.081317) (xy 76.835777 -342.065954) (xy 76.889769 -342.058197)
			(xy 76.917042 -342.057736) (xy 77.780642 -342.057736) (xy 77.807909 -342.058229) (xy 77.861888 -342.065996)
			(xy 77.914212 -342.081365) (xy 77.963817 -342.104023) (xy 78.009692 -342.13351) (xy 78.050905 -342.169225)
			(xy 78.086615 -342.210441) (xy 78.116097 -342.25632) (xy 78.13875 -342.305927) (xy 78.154113 -342.358253)
			(xy 78.161874 -342.412233) (xy 78.161874 -342.466767) (xy 78.161873 -342.466771) (xy 79.644699 -342.466771)
			(xy 79.644699 -342.412229) (xy 79.652462 -342.358241) (xy 79.667828 -342.305908) (xy 79.690486 -342.256295)
			(xy 79.719974 -342.210411) (xy 79.755692 -342.16919) (xy 79.796912 -342.133473) (xy 79.842797 -342.103985)
			(xy 79.89241 -342.081327) (xy 79.944743 -342.065961) (xy 79.998731 -342.058199) (xy 80.026002 -342.057736)
			(xy 80.889602 -342.057736) (xy 80.916871 -342.058227) (xy 80.970854 -342.065988) (xy 81.023183 -342.081354)
			(xy 81.072793 -342.10401) (xy 81.118673 -342.133496) (xy 81.159891 -342.169211) (xy 81.195605 -342.210428)
			(xy 81.225091 -342.256309) (xy 81.247747 -342.305919) (xy 81.263112 -342.358248) (xy 81.270874 -342.412231)
			(xy 81.270874 -342.466768) (xy 82.753722 -342.466768) (xy 82.753722 -342.412232) (xy 82.761483 -342.358252)
			(xy 82.776847 -342.305925) (xy 82.7995 -342.256317) (xy 82.828983 -342.210438) (xy 82.864694 -342.169221)
			(xy 82.905907 -342.133505) (xy 82.951784 -342.104018) (xy 83.001389 -342.08136) (xy 83.053714 -342.065991)
			(xy 83.107694 -342.058225) (xy 83.134962 -342.057736) (xy 83.998562 -342.057736) (xy 84.025835 -342.058201)
			(xy 84.079825 -342.065959) (xy 84.132162 -342.081321) (xy 84.18178 -342.103977) (xy 84.227668 -342.133463)
			(xy 84.268893 -342.16918) (xy 84.304614 -342.210401) (xy 84.334105 -342.256287) (xy 84.356765 -342.305902)
			(xy 84.372133 -342.358237) (xy 84.379896 -342.412227) (xy 84.379896 -342.466772) (xy 85.8626 -342.466772)
			(xy 85.8626 -342.412228) (xy 85.870362 -342.358239) (xy 85.88573 -342.305904) (xy 85.908389 -342.256289)
			(xy 85.937879 -342.210404) (xy 85.973599 -342.169183) (xy 86.014822 -342.133466) (xy 86.060709 -342.103979)
			(xy 86.110325 -342.081322) (xy 86.16266 -342.065958) (xy 86.21665 -342.058198) (xy 86.243922 -342.057736)
			(xy 87.107522 -342.057736) (xy 87.13479 -342.058228) (xy 87.188771 -342.065992) (xy 87.241098 -342.081359)
			(xy 87.290705 -342.104017) (xy 87.336583 -342.133503) (xy 87.377798 -342.169218) (xy 87.41351 -342.210435)
			(xy 87.442994 -342.256314) (xy 87.465648 -342.305923) (xy 87.481013 -342.35825) (xy 87.488774 -342.412232)
			(xy 87.488774 -342.466768) (xy 87.488774 -342.466769) (xy 88.971622 -342.466769) (xy 88.971622 -342.412231)
			(xy 88.979384 -342.358249) (xy 88.994748 -342.305921) (xy 89.017403 -342.256311) (xy 89.046887 -342.210431)
			(xy 89.082601 -342.169214) (xy 89.123817 -342.133498) (xy 89.169696 -342.104012) (xy 89.219304 -342.081354)
			(xy 89.271631 -342.065987) (xy 89.325613 -342.058224) (xy 89.352882 -342.057736) (xy 90.216482 -342.057736)
			(xy 90.243754 -342.058202) (xy 90.297742 -342.065962) (xy 90.350077 -342.081327) (xy 90.399692 -342.103983)
			(xy 90.445578 -342.13347) (xy 90.4868 -342.169188) (xy 90.522519 -342.210408) (xy 90.552008 -342.256292)
			(xy 90.574667 -342.305906) (xy 90.590034 -342.35824) (xy 90.597796 -342.412228) (xy 90.597796 -342.466772)
			(xy 90.597796 -342.466773) (xy 92.0805 -342.466773) (xy 92.0805 -342.412227) (xy 92.088263 -342.358236)
			(xy 92.103631 -342.3059) (xy 92.126292 -342.256284) (xy 92.155784 -342.210398) (xy 92.191506 -342.169176)
			(xy 92.232731 -342.133459) (xy 92.27862 -342.103972) (xy 92.328239 -342.081317) (xy 92.380577 -342.065954)
			(xy 92.434569 -342.058197) (xy 92.461842 -342.057736) (xy 93.325442 -342.057736) (xy 93.352709 -342.058229)
			(xy 93.406688 -342.065996) (xy 93.459012 -342.081365) (xy 93.508617 -342.104023) (xy 93.554492 -342.13351)
			(xy 93.595705 -342.169225) (xy 93.631415 -342.210441) (xy 93.660897 -342.25632) (xy 93.68355 -342.305927)
			(xy 93.698913 -342.358253) (xy 93.706674 -342.412233) (xy 93.706674 -342.466767) (xy 93.698913 -342.520747)
			(xy 93.68355 -342.573073) (xy 93.660897 -342.62268) (xy 93.631415 -342.668559) (xy 93.60914 -342.694268)
			(xy 102.35157 -342.694268) (xy 102.35157 -342.634332) (xy 102.359393 -342.574909) (xy 102.374905 -342.517016)
			(xy 102.397841 -342.461642) (xy 102.427809 -342.409736) (xy 102.464294 -342.362185) (xy 102.506675 -342.319804)
			(xy 102.554224 -342.283316) (xy 102.60613 -342.253347) (xy 102.661502 -342.23041) (xy 102.719395 -342.214896)
			(xy 102.778818 -342.207071) (xy 102.808786 -342.20658) (xy 103.672386 -342.20658) (xy 103.702355 -342.207072)
			(xy 103.76178 -342.214894) (xy 103.819676 -342.230405) (xy 103.875051 -342.253341) (xy 103.926959 -342.283309)
			(xy 103.974512 -342.319796) (xy 104.016895 -342.362178) (xy 104.053383 -342.409729) (xy 104.083352 -342.461636)
			(xy 104.085479 -342.466772) (xy 111.4808 -342.466772) (xy 111.4808 -342.412228) (xy 111.488562 -342.358241)
			(xy 111.503929 -342.305907) (xy 111.526587 -342.256293) (xy 111.556075 -342.210409) (xy 111.591794 -342.169188)
			(xy 111.633015 -342.133471) (xy 111.6789 -342.103983) (xy 111.728515 -342.081326) (xy 111.780848 -342.06596)
			(xy 111.834836 -342.058199) (xy 111.862108 -342.057736) (xy 112.725708 -342.057736) (xy 112.752977 -342.058227)
			(xy 112.806959 -342.06599) (xy 112.859288 -342.081355) (xy 112.908897 -342.104012) (xy 112.954776 -342.133498)
			(xy 112.995993 -342.169213) (xy 113.031707 -342.21043) (xy 113.061192 -342.256311) (xy 113.083847 -342.30592)
			(xy 113.099212 -342.358249) (xy 113.106974 -342.412231) (xy 113.106974 -342.466768) (xy 114.589822 -342.466768)
			(xy 114.589822 -342.412232) (xy 114.597583 -342.358251) (xy 114.612947 -342.305924) (xy 114.635601 -342.256315)
			(xy 114.665084 -342.210436) (xy 114.700796 -342.169219) (xy 114.74201 -342.133503) (xy 114.787887 -342.104016)
			(xy 114.837494 -342.081358) (xy 114.88982 -342.06599) (xy 114.9438 -342.058225) (xy 114.971068 -342.057736)
			(xy 115.834668 -342.057736) (xy 115.86194 -342.058201) (xy 115.91593 -342.06596) (xy 115.968267 -342.081323)
			(xy 116.017884 -342.103979) (xy 116.063771 -342.133465) (xy 116.104995 -342.169183) (xy 116.140715 -342.210403)
			(xy 116.170206 -342.256288) (xy 116.192866 -342.305903) (xy 116.208233 -342.358238) (xy 116.215996 -342.412228)
			(xy 116.215996 -342.466772) (xy 117.6987 -342.466772) (xy 117.6987 -342.412228) (xy 117.706462 -342.358238)
			(xy 117.72183 -342.305903) (xy 117.74449 -342.256288) (xy 117.77398 -342.210402) (xy 117.809701 -342.169181)
			(xy 117.850925 -342.133464) (xy 117.896812 -342.103977) (xy 117.946429 -342.08132) (xy 117.998765 -342.065957)
			(xy 118.052756 -342.058198) (xy 118.080028 -342.057736) (xy 118.943628 -342.057736) (xy 118.970896 -342.058228)
			(xy 119.024876 -342.065993) (xy 119.077202 -342.081361) (xy 119.126809 -342.104019) (xy 119.172686 -342.133505)
			(xy 119.2139 -342.16922) (xy 119.249612 -342.210437) (xy 119.279095 -342.256316) (xy 119.301749 -342.305924)
			(xy 119.317113 -342.358251) (xy 119.324874 -342.412232) (xy 119.324874 -342.466768) (xy 119.324874 -342.466769)
			(xy 120.807722 -342.466769) (xy 120.807722 -342.412231) (xy 120.815484 -342.358248) (xy 120.830849 -342.305919)
			(xy 120.853504 -342.25631) (xy 120.882989 -342.210429) (xy 120.918703 -342.169212) (xy 120.95992 -342.133496)
			(xy 121.005799 -342.10401) (xy 121.055408 -342.081353) (xy 121.107736 -342.065986) (xy 121.161719 -342.058223)
			(xy 121.188988 -342.057736) (xy 122.052588 -342.057736) (xy 122.079859 -342.058203) (xy 122.133847 -342.065963)
			(xy 122.186181 -342.081329) (xy 122.235796 -342.103985) (xy 122.28168 -342.133472) (xy 122.322902 -342.16919)
			(xy 122.35862 -342.21041) (xy 122.388109 -342.256294) (xy 122.410767 -342.305908) (xy 122.426134 -342.358241)
			(xy 122.433896 -342.412229) (xy 122.433896 -342.466771) (xy 122.433896 -342.466773) (xy 123.9166 -342.466773)
			(xy 123.9166 -342.412227) (xy 123.924363 -342.358235) (xy 123.939732 -342.305899) (xy 123.962393 -342.256282)
			(xy 123.991885 -342.210396) (xy 124.027608 -342.169174) (xy 124.068834 -342.133456) (xy 124.114724 -342.10397)
			(xy 124.164344 -342.081315) (xy 124.216682 -342.065953) (xy 124.270675 -342.058196) (xy 124.297948 -342.057736)
			(xy 125.161548 -342.057736) (xy 125.188815 -342.05823) (xy 125.242793 -342.065997) (xy 125.295117 -342.081366)
			(xy 125.34472 -342.104025) (xy 125.390595 -342.133512) (xy 125.431807 -342.169227) (xy 125.467517 -342.210443)
			(xy 125.496998 -342.256322) (xy 125.519651 -342.305928) (xy 125.535013 -342.358254) (xy 125.542774 -342.412233)
			(xy 125.542774 -342.466767) (xy 125.542773 -342.466772) (xy 127.0256 -342.466772) (xy 127.0256 -342.412228)
			(xy 127.033362 -342.358241) (xy 127.048729 -342.305907) (xy 127.071387 -342.256293) (xy 127.100875 -342.210409)
			(xy 127.136594 -342.169188) (xy 127.177815 -342.133471) (xy 127.2237 -342.103983) (xy 127.273315 -342.081326)
			(xy 127.325648 -342.06596) (xy 127.379636 -342.058199) (xy 127.406908 -342.057736) (xy 128.270508 -342.057736)
			(xy 128.297777 -342.058227) (xy 128.351759 -342.06599) (xy 128.404088 -342.081355) (xy 128.453697 -342.104012)
			(xy 128.499576 -342.133498) (xy 128.540793 -342.169213) (xy 128.576507 -342.21043) (xy 128.605992 -342.256311)
			(xy 128.628647 -342.30592) (xy 128.644012 -342.358249) (xy 128.651774 -342.412231) (xy 128.651774 -342.466768)
			(xy 130.134622 -342.466768) (xy 130.134622 -342.412232) (xy 130.142383 -342.358251) (xy 130.157747 -342.305924)
			(xy 130.180401 -342.256315) (xy 130.209884 -342.210436) (xy 130.245596 -342.169219) (xy 130.28681 -342.133503)
			(xy 130.332687 -342.104016) (xy 130.382294 -342.081358) (xy 130.43462 -342.06599) (xy 130.4886 -342.058225)
			(xy 130.515868 -342.057736) (xy 131.379468 -342.057736) (xy 131.40674 -342.058201) (xy 131.46073 -342.06596)
			(xy 131.513067 -342.081323) (xy 131.562684 -342.103979) (xy 131.608571 -342.133465) (xy 131.649795 -342.169183)
			(xy 131.685515 -342.210403) (xy 131.715006 -342.256288) (xy 131.737666 -342.305903) (xy 131.753033 -342.358238)
			(xy 131.760796 -342.412228) (xy 131.760796 -342.466772) (xy 133.2435 -342.466772) (xy 133.2435 -342.412228)
			(xy 133.251262 -342.358238) (xy 133.26663 -342.305903) (xy 133.28929 -342.256288) (xy 133.31878 -342.210402)
			(xy 133.354501 -342.169181) (xy 133.395725 -342.133464) (xy 133.441612 -342.103977) (xy 133.491229 -342.08132)
			(xy 133.543565 -342.065957) (xy 133.597556 -342.058198) (xy 133.624828 -342.057736) (xy 134.488428 -342.057736)
			(xy 134.515696 -342.058228) (xy 134.569676 -342.065993) (xy 134.622002 -342.081361) (xy 134.671609 -342.104019)
			(xy 134.717486 -342.133505) (xy 134.7587 -342.16922) (xy 134.794412 -342.210437) (xy 134.823895 -342.256316)
			(xy 134.846549 -342.305924) (xy 134.861913 -342.358251) (xy 134.869674 -342.412232) (xy 134.869674 -342.466768)
			(xy 134.869674 -342.466769) (xy 136.352522 -342.466769) (xy 136.352522 -342.412231) (xy 136.360284 -342.358248)
			(xy 136.375649 -342.305919) (xy 136.398304 -342.25631) (xy 136.427789 -342.210429) (xy 136.463503 -342.169212)
			(xy 136.50472 -342.133496) (xy 136.550599 -342.10401) (xy 136.600208 -342.081353) (xy 136.652536 -342.065986)
			(xy 136.706519 -342.058223) (xy 136.733788 -342.057736) (xy 137.597388 -342.057736) (xy 137.624659 -342.058203)
			(xy 137.678647 -342.065963) (xy 137.730981 -342.081329) (xy 137.780596 -342.103985) (xy 137.82648 -342.133472)
			(xy 137.867702 -342.16919) (xy 137.90342 -342.21041) (xy 137.932909 -342.256294) (xy 137.955567 -342.305908)
			(xy 137.970934 -342.358241) (xy 137.978696 -342.412229) (xy 137.978696 -342.466771) (xy 137.978696 -342.466773)
			(xy 139.4614 -342.466773) (xy 139.4614 -342.412227) (xy 139.469163 -342.358235) (xy 139.484532 -342.305899)
			(xy 139.507193 -342.256282) (xy 139.536685 -342.210396) (xy 139.572408 -342.169174) (xy 139.613634 -342.133456)
			(xy 139.659524 -342.10397) (xy 139.709144 -342.081315) (xy 139.761482 -342.065953) (xy 139.815475 -342.058196)
			(xy 139.842748 -342.057736) (xy 140.706348 -342.057736) (xy 140.733615 -342.05823) (xy 140.787593 -342.065997)
			(xy 140.839917 -342.081366) (xy 140.88952 -342.104025) (xy 140.935395 -342.133512) (xy 140.976607 -342.169227)
			(xy 141.012317 -342.210443) (xy 141.041798 -342.256322) (xy 141.064451 -342.305928) (xy 141.079813 -342.358254)
			(xy 141.087574 -342.412233) (xy 141.087574 -342.466767) (xy 141.087573 -342.466772) (xy 142.5704 -342.466772)
			(xy 142.5704 -342.412228) (xy 142.578162 -342.358241) (xy 142.593529 -342.305907) (xy 142.616187 -342.256293)
			(xy 142.645675 -342.210409) (xy 142.681394 -342.169188) (xy 142.722615 -342.133471) (xy 142.7685 -342.103983)
			(xy 142.818115 -342.081326) (xy 142.870448 -342.06596) (xy 142.924436 -342.058199) (xy 142.951708 -342.057736)
			(xy 143.815308 -342.057736) (xy 143.842577 -342.058227) (xy 143.896559 -342.06599) (xy 143.948888 -342.081355)
			(xy 143.998497 -342.104012) (xy 144.044376 -342.133498) (xy 144.085593 -342.169213) (xy 144.121307 -342.21043)
			(xy 144.150792 -342.256311) (xy 144.173447 -342.30592) (xy 144.188812 -342.358249) (xy 144.196574 -342.412231)
			(xy 144.196574 -342.466768) (xy 164.913822 -342.466768) (xy 164.913822 -342.412232) (xy 164.921583 -342.35825)
			(xy 164.936947 -342.305923) (xy 164.959602 -342.256314) (xy 164.989085 -342.210434) (xy 165.024797 -342.169217)
			(xy 165.066012 -342.133502) (xy 165.11189 -342.104015) (xy 165.161496 -342.081357) (xy 165.213823 -342.065989)
			(xy 165.267804 -342.058224) (xy 165.295072 -342.057736) (xy 166.158672 -342.057736) (xy 166.185944 -342.058202)
			(xy 166.239934 -342.06596) (xy 166.29227 -342.081324) (xy 166.341886 -342.10398) (xy 166.387773 -342.133467)
			(xy 166.428996 -342.169184) (xy 166.464716 -342.210405) (xy 166.494207 -342.256289) (xy 166.516866 -342.305904)
			(xy 166.532234 -342.358239) (xy 166.539996 -342.412228) (xy 166.539996 -342.466772) (xy 166.539996 -342.466773)
			(xy 168.0227 -342.466773) (xy 168.0227 -342.412227) (xy 168.030463 -342.358237) (xy 168.045831 -342.305902)
			(xy 168.068491 -342.256286) (xy 168.097981 -342.210401) (xy 168.133702 -342.16918) (xy 168.174927 -342.133462)
			(xy 168.220815 -342.103975) (xy 168.270432 -342.081319) (xy 168.322769 -342.065956) (xy 168.376759 -342.058197)
			(xy 168.404032 -342.057736) (xy 169.267632 -342.057736) (xy 169.2949 -342.058229) (xy 169.34888 -342.065994)
			(xy 169.401205 -342.081362) (xy 169.450811 -342.10402) (xy 169.496688 -342.133506) (xy 169.537901 -342.169222)
			(xy 169.573613 -342.210438) (xy 169.603095 -342.256317) (xy 169.625749 -342.305925) (xy 169.641113 -342.358252)
			(xy 169.648874 -342.412232) (xy 169.648874 -342.466768) (xy 169.648874 -342.466769) (xy 171.131722 -342.466769)
			(xy 171.131722 -342.412231) (xy 171.139484 -342.358248) (xy 171.154849 -342.305918) (xy 171.177505 -342.256309)
			(xy 171.20699 -342.210428) (xy 171.242705 -342.16921) (xy 171.283921 -342.133495) (xy 171.329802 -342.104009)
			(xy 171.379411 -342.081352) (xy 171.43174 -342.065986) (xy 171.485723 -342.058223) (xy 171.512992 -342.057736)
			(xy 172.376592 -342.057736) (xy 172.403863 -342.058203) (xy 172.457851 -342.065964) (xy 172.510184 -342.08133)
			(xy 172.559798 -342.103987) (xy 172.605682 -342.133474) (xy 172.646903 -342.169191) (xy 172.682621 -342.210411)
			(xy 172.71211 -342.256295) (xy 172.734768 -342.305908) (xy 172.750134 -342.358241) (xy 172.757896 -342.412229)
			(xy 172.757896 -342.466767) (xy 174.240722 -342.466767) (xy 174.240722 -342.412233) (xy 174.248483 -342.358253)
			(xy 174.263846 -342.305927) (xy 174.286499 -342.25632) (xy 174.31598 -342.210441) (xy 174.35169 -342.169224)
			(xy 174.392902 -342.133509) (xy 174.438778 -342.104022) (xy 174.488382 -342.081363) (xy 174.540706 -342.065993)
			(xy 174.594685 -342.058226) (xy 174.621952 -342.057736) (xy 175.485552 -342.057736) (xy 175.512825 -342.0582)
			(xy 175.566817 -342.065957) (xy 175.619155 -342.081319) (xy 175.668774 -342.103974) (xy 175.714663 -342.13346)
			(xy 175.755889 -342.169177) (xy 175.791612 -342.210398) (xy 175.821103 -342.256284) (xy 175.843764 -342.3059)
			(xy 175.859133 -342.358236) (xy 175.866896 -342.412227) (xy 175.866896 -342.466772) (xy 177.3496 -342.466772)
			(xy 177.3496 -342.412228) (xy 177.357362 -342.35824) (xy 177.372729 -342.305906) (xy 177.395388 -342.256292)
			(xy 177.424876 -342.210407) (xy 177.460595 -342.169187) (xy 177.501817 -342.133469) (xy 177.547703 -342.103982)
			(xy 177.597317 -342.081325) (xy 177.649652 -342.065959) (xy 177.70364 -342.058199) (xy 177.730912 -342.057736)
			(xy 178.594512 -342.057736) (xy 178.621781 -342.058227) (xy 178.675763 -342.06599) (xy 178.728091 -342.081357)
			(xy 178.777699 -342.104013) (xy 178.823578 -342.133499) (xy 178.864794 -342.169214) (xy 178.900508 -342.210432)
			(xy 178.929992 -342.256312) (xy 178.952648 -342.305921) (xy 178.968012 -342.358249) (xy 178.975774 -342.412231)
			(xy 178.975774 -342.466768) (xy 180.458622 -342.466768) (xy 180.458622 -342.412232) (xy 180.466383 -342.35825)
			(xy 180.481747 -342.305923) (xy 180.504402 -342.256314) (xy 180.533885 -342.210434) (xy 180.569597 -342.169217)
			(xy 180.610812 -342.133502) (xy 180.65669 -342.104015) (xy 180.706296 -342.081357) (xy 180.758623 -342.065989)
			(xy 180.812604 -342.058224) (xy 180.839872 -342.057736) (xy 181.703472 -342.057736) (xy 181.730744 -342.058202)
			(xy 181.784734 -342.06596) (xy 181.83707 -342.081324) (xy 181.886686 -342.10398) (xy 181.932573 -342.133467)
			(xy 181.973796 -342.169184) (xy 182.009516 -342.210405) (xy 182.039007 -342.256289) (xy 182.061666 -342.305904)
			(xy 182.077034 -342.358239) (xy 182.084796 -342.412228) (xy 182.084796 -342.466772) (xy 182.084796 -342.466773)
			(xy 183.5675 -342.466773) (xy 183.5675 -342.412227) (xy 183.575263 -342.358237) (xy 183.590631 -342.305902)
			(xy 183.613291 -342.256286) (xy 183.642781 -342.210401) (xy 183.678502 -342.16918) (xy 183.719727 -342.133462)
			(xy 183.765615 -342.103975) (xy 183.815232 -342.081319) (xy 183.867569 -342.065956) (xy 183.921559 -342.058197)
			(xy 183.948832 -342.057736) (xy 184.812432 -342.057736) (xy 184.8397 -342.058229) (xy 184.89368 -342.065994)
			(xy 184.946005 -342.081362) (xy 184.995611 -342.10402) (xy 185.041488 -342.133506) (xy 185.082701 -342.169222)
			(xy 185.118413 -342.210438) (xy 185.147895 -342.256317) (xy 185.170549 -342.305925) (xy 185.185913 -342.358252)
			(xy 185.193674 -342.412232) (xy 185.193674 -342.466768) (xy 185.193674 -342.466769) (xy 186.676522 -342.466769)
			(xy 186.676522 -342.412231) (xy 186.684284 -342.358248) (xy 186.699649 -342.305918) (xy 186.722305 -342.256309)
			(xy 186.75179 -342.210428) (xy 186.787505 -342.16921) (xy 186.828721 -342.133495) (xy 186.874602 -342.104009)
			(xy 186.924211 -342.081352) (xy 186.97654 -342.065986) (xy 187.030523 -342.058223) (xy 187.057792 -342.057736)
			(xy 187.921392 -342.057736) (xy 187.948663 -342.058203) (xy 188.002651 -342.065964) (xy 188.054984 -342.08133)
			(xy 188.104598 -342.103987) (xy 188.150482 -342.133474) (xy 188.191703 -342.169191) (xy 188.227421 -342.210411)
			(xy 188.25691 -342.256295) (xy 188.279568 -342.305908) (xy 188.294934 -342.358241) (xy 188.302696 -342.412229)
			(xy 188.302696 -342.466767) (xy 189.785522 -342.466767) (xy 189.785522 -342.412233) (xy 189.793283 -342.358253)
			(xy 189.808646 -342.305927) (xy 189.831299 -342.25632) (xy 189.86078 -342.210441) (xy 189.89649 -342.169224)
			(xy 189.937702 -342.133509) (xy 189.983578 -342.104022) (xy 190.033182 -342.081363) (xy 190.085506 -342.065993)
			(xy 190.139485 -342.058226) (xy 190.166752 -342.057736) (xy 191.030352 -342.057736) (xy 191.057625 -342.0582)
			(xy 191.111617 -342.065957) (xy 191.163955 -342.081319) (xy 191.213574 -342.103974) (xy 191.259463 -342.13346)
			(xy 191.300689 -342.169177) (xy 191.336412 -342.210398) (xy 191.365903 -342.256284) (xy 191.388564 -342.3059)
			(xy 191.403933 -342.358236) (xy 191.411696 -342.412227) (xy 191.411696 -342.466772) (xy 192.8944 -342.466772)
			(xy 192.8944 -342.412228) (xy 192.902162 -342.35824) (xy 192.917529 -342.305906) (xy 192.940188 -342.256292)
			(xy 192.969676 -342.210407) (xy 193.005395 -342.169187) (xy 193.046617 -342.133469) (xy 193.092503 -342.103982)
			(xy 193.142117 -342.081325) (xy 193.194452 -342.065959) (xy 193.24844 -342.058199) (xy 193.275712 -342.057736)
			(xy 194.139312 -342.057736) (xy 194.166581 -342.058227) (xy 194.220563 -342.06599) (xy 194.272891 -342.081357)
			(xy 194.322499 -342.104013) (xy 194.368378 -342.133499) (xy 194.409594 -342.169214) (xy 194.445308 -342.210432)
			(xy 194.474792 -342.256312) (xy 194.497448 -342.305921) (xy 194.512812 -342.358249) (xy 194.520574 -342.412231)
			(xy 194.520574 -342.466768) (xy 196.003422 -342.466768) (xy 196.003422 -342.412232) (xy 196.011183 -342.35825)
			(xy 196.026547 -342.305923) (xy 196.049202 -342.256314) (xy 196.078685 -342.210434) (xy 196.114397 -342.169217)
			(xy 196.155612 -342.133502) (xy 196.20149 -342.104015) (xy 196.251096 -342.081357) (xy 196.303423 -342.065989)
			(xy 196.357404 -342.058224) (xy 196.384672 -342.057736) (xy 197.248272 -342.057736) (xy 197.275544 -342.058202)
			(xy 197.28821 -342.060022) (xy 255.91262 -342.060022) (xy 255.91262 -341.196422) (xy 255.91311 -341.166438)
			(xy 255.920938 -341.106982) (xy 255.936459 -341.049057) (xy 255.959408 -340.993653) (xy 255.989392 -340.941719)
			(xy 256.025898 -340.894143) (xy 256.068303 -340.851738) (xy 256.115879 -340.815232) (xy 256.167813 -340.785248)
			(xy 256.223217 -340.762299) (xy 256.281142 -340.746778) (xy 256.340598 -340.73895) (xy 256.400566 -340.73895)
			(xy 256.460022 -340.746778) (xy 256.517947 -340.762299) (xy 256.573351 -340.785248) (xy 256.625285 -340.815232)
			(xy 256.672861 -340.851738) (xy 256.715266 -340.894143) (xy 256.751772 -340.941719) (xy 256.781756 -340.993653)
			(xy 256.804705 -341.049057) (xy 256.820226 -341.106982) (xy 256.828054 -341.166438) (xy 256.828544 -341.196422)
			(xy 256.828544 -342.060022) (xy 256.828054 -342.090006) (xy 256.820226 -342.149462) (xy 256.804705 -342.207387)
			(xy 256.781756 -342.262791) (xy 256.751772 -342.314725) (xy 256.715266 -342.362301) (xy 256.672861 -342.404706)
			(xy 256.625285 -342.441212) (xy 256.581015 -342.466771) (xy 267.515799 -342.466771) (xy 267.515799 -342.412229)
			(xy 267.523562 -342.358241) (xy 267.538928 -342.305908) (xy 267.561586 -342.256295) (xy 267.591074 -342.210411)
			(xy 267.626792 -342.16919) (xy 267.668012 -342.133473) (xy 267.713897 -342.103985) (xy 267.76351 -342.081327)
			(xy 267.815843 -342.065961) (xy 267.869831 -342.058199) (xy 267.897102 -342.057736) (xy 268.760702 -342.057736)
			(xy 268.787971 -342.058227) (xy 268.841954 -342.065988) (xy 268.894283 -342.081354) (xy 268.943893 -342.10401)
			(xy 268.989773 -342.133496) (xy 269.030991 -342.169211) (xy 269.066705 -342.210428) (xy 269.096191 -342.256309)
			(xy 269.118847 -342.305919) (xy 269.134212 -342.358248) (xy 269.141974 -342.412231) (xy 269.141974 -342.466768)
			(xy 270.624822 -342.466768) (xy 270.624822 -342.412232) (xy 270.632583 -342.358252) (xy 270.647947 -342.305925)
			(xy 270.6706 -342.256317) (xy 270.700083 -342.210438) (xy 270.735794 -342.169221) (xy 270.777007 -342.133505)
			(xy 270.822884 -342.104018) (xy 270.872489 -342.08136) (xy 270.924814 -342.065991) (xy 270.978794 -342.058225)
			(xy 271.006062 -342.057736) (xy 271.869662 -342.057736) (xy 271.896935 -342.058201) (xy 271.950925 -342.065959)
			(xy 272.003262 -342.081321) (xy 272.05288 -342.103977) (xy 272.098768 -342.133463) (xy 272.139993 -342.16918)
			(xy 272.175714 -342.210401) (xy 272.205205 -342.256287) (xy 272.227865 -342.305902) (xy 272.243233 -342.358237)
			(xy 272.250996 -342.412227) (xy 272.250996 -342.466772) (xy 273.7337 -342.466772) (xy 273.7337 -342.412228)
			(xy 273.741462 -342.358239) (xy 273.75683 -342.305904) (xy 273.779489 -342.256289) (xy 273.808979 -342.210404)
			(xy 273.844699 -342.169183) (xy 273.885922 -342.133466) (xy 273.931809 -342.103979) (xy 273.981425 -342.081322)
			(xy 274.03376 -342.065958) (xy 274.08775 -342.058198) (xy 274.115022 -342.057736) (xy 274.978622 -342.057736)
			(xy 275.00589 -342.058228) (xy 275.059871 -342.065992) (xy 275.112198 -342.081359) (xy 275.161805 -342.104017)
			(xy 275.207683 -342.133503) (xy 275.248898 -342.169218) (xy 275.28461 -342.210435) (xy 275.314094 -342.256314)
			(xy 275.336748 -342.305923) (xy 275.352113 -342.35825) (xy 275.359874 -342.412232) (xy 275.359874 -342.466768)
			(xy 275.359874 -342.466769) (xy 276.842722 -342.466769) (xy 276.842722 -342.412231) (xy 276.850484 -342.358249)
			(xy 276.865848 -342.305921) (xy 276.888503 -342.256311) (xy 276.917987 -342.210431) (xy 276.953701 -342.169214)
			(xy 276.994917 -342.133498) (xy 277.040796 -342.104012) (xy 277.090404 -342.081354) (xy 277.142731 -342.065987)
			(xy 277.196713 -342.058224) (xy 277.223982 -342.057736) (xy 278.087582 -342.057736) (xy 278.114854 -342.058202)
			(xy 278.168842 -342.065962) (xy 278.221177 -342.081327) (xy 278.270792 -342.103983) (xy 278.316678 -342.13347)
			(xy 278.3579 -342.169188) (xy 278.393619 -342.210408) (xy 278.423108 -342.256292) (xy 278.445767 -342.305906)
			(xy 278.461134 -342.35824) (xy 278.468896 -342.412228) (xy 278.468896 -342.466772) (xy 278.468896 -342.466773)
			(xy 279.9516 -342.466773) (xy 279.9516 -342.412227) (xy 279.959363 -342.358236) (xy 279.974731 -342.3059)
			(xy 279.997392 -342.256284) (xy 280.026884 -342.210398) (xy 280.062606 -342.169176) (xy 280.103831 -342.133459)
			(xy 280.14972 -342.103972) (xy 280.199339 -342.081317) (xy 280.251677 -342.065954) (xy 280.305669 -342.058197)
			(xy 280.332942 -342.057736) (xy 281.196542 -342.057736) (xy 281.223809 -342.058229) (xy 281.277788 -342.065996)
			(xy 281.330112 -342.081365) (xy 281.379717 -342.104023) (xy 281.425592 -342.13351) (xy 281.466805 -342.169225)
			(xy 281.502515 -342.210441) (xy 281.531997 -342.25632) (xy 281.55465 -342.305927) (xy 281.570013 -342.358253)
			(xy 281.577774 -342.412233) (xy 281.577774 -342.466767) (xy 281.577773 -342.466771) (xy 283.060599 -342.466771)
			(xy 283.060599 -342.412229) (xy 283.068362 -342.358241) (xy 283.083728 -342.305908) (xy 283.106386 -342.256295)
			(xy 283.135874 -342.210411) (xy 283.171592 -342.16919) (xy 283.212812 -342.133473) (xy 283.258697 -342.103985)
			(xy 283.30831 -342.081327) (xy 283.360643 -342.065961) (xy 283.414631 -342.058199) (xy 283.441902 -342.057736)
			(xy 284.305502 -342.057736) (xy 284.332771 -342.058227) (xy 284.386754 -342.065988) (xy 284.439083 -342.081354)
			(xy 284.488693 -342.10401) (xy 284.534573 -342.133496) (xy 284.575791 -342.169211) (xy 284.611505 -342.210428)
			(xy 284.640991 -342.256309) (xy 284.663647 -342.305919) (xy 284.679012 -342.358248) (xy 284.686774 -342.412231)
			(xy 284.686774 -342.466768) (xy 286.169622 -342.466768) (xy 286.169622 -342.412232) (xy 286.177383 -342.358252)
			(xy 286.192747 -342.305925) (xy 286.2154 -342.256317) (xy 286.244883 -342.210438) (xy 286.280594 -342.169221)
			(xy 286.321807 -342.133505) (xy 286.367684 -342.104018) (xy 286.417289 -342.08136) (xy 286.469614 -342.065991)
			(xy 286.523594 -342.058225) (xy 286.550862 -342.057736) (xy 287.414462 -342.057736) (xy 287.441735 -342.058201)
			(xy 287.495725 -342.065959) (xy 287.548062 -342.081321) (xy 287.59768 -342.103977) (xy 287.643568 -342.133463)
			(xy 287.684793 -342.16918) (xy 287.720514 -342.210401) (xy 287.750005 -342.256287) (xy 287.772665 -342.305902)
			(xy 287.788033 -342.358237) (xy 287.795796 -342.412227) (xy 287.795796 -342.466772) (xy 289.2785 -342.466772)
			(xy 289.2785 -342.412228) (xy 289.286262 -342.358239) (xy 289.30163 -342.305904) (xy 289.324289 -342.256289)
			(xy 289.353779 -342.210404) (xy 289.389499 -342.169183) (xy 289.430722 -342.133466) (xy 289.476609 -342.103979)
			(xy 289.526225 -342.081322) (xy 289.57856 -342.065958) (xy 289.63255 -342.058198) (xy 289.659822 -342.057736)
			(xy 290.523422 -342.057736) (xy 290.55069 -342.058228) (xy 290.604671 -342.065992) (xy 290.656998 -342.081359)
			(xy 290.706605 -342.104017) (xy 290.752483 -342.133503) (xy 290.793698 -342.169218) (xy 290.82941 -342.210435)
			(xy 290.858894 -342.256314) (xy 290.881548 -342.305923) (xy 290.896913 -342.35825) (xy 290.904674 -342.412232)
			(xy 290.904674 -342.466768) (xy 290.904674 -342.466769) (xy 292.387522 -342.466769) (xy 292.387522 -342.412231)
			(xy 292.395284 -342.358249) (xy 292.410648 -342.305921) (xy 292.433303 -342.256311) (xy 292.462787 -342.210431)
			(xy 292.498501 -342.169214) (xy 292.539717 -342.133498) (xy 292.585596 -342.104012) (xy 292.635204 -342.081354)
			(xy 292.687531 -342.065987) (xy 292.741513 -342.058224) (xy 292.768782 -342.057736) (xy 293.632382 -342.057736)
			(xy 293.659654 -342.058202) (xy 293.713642 -342.065962) (xy 293.765977 -342.081327) (xy 293.815592 -342.103983)
			(xy 293.861478 -342.13347) (xy 293.9027 -342.169188) (xy 293.938419 -342.210408) (xy 293.967908 -342.256292)
			(xy 293.990567 -342.305906) (xy 294.005934 -342.35824) (xy 294.013696 -342.412228) (xy 294.013696 -342.466772)
			(xy 294.013696 -342.466773) (xy 295.4964 -342.466773) (xy 295.4964 -342.412227) (xy 295.504163 -342.358236)
			(xy 295.519531 -342.3059) (xy 295.542192 -342.256284) (xy 295.571684 -342.210398) (xy 295.607406 -342.169176)
			(xy 295.648631 -342.133459) (xy 295.69452 -342.103972) (xy 295.744139 -342.081317) (xy 295.796477 -342.065954)
			(xy 295.850469 -342.058197) (xy 295.877742 -342.057736) (xy 296.741342 -342.057736) (xy 296.768609 -342.058229)
			(xy 296.822588 -342.065996) (xy 296.874912 -342.081365) (xy 296.924517 -342.104023) (xy 296.970392 -342.13351)
			(xy 297.011605 -342.169225) (xy 297.047315 -342.210441) (xy 297.076797 -342.25632) (xy 297.09945 -342.305927)
			(xy 297.114813 -342.358253) (xy 297.122574 -342.412233) (xy 297.122574 -342.466767) (xy 297.122573 -342.466771)
			(xy 298.605399 -342.466771) (xy 298.605399 -342.412229) (xy 298.613162 -342.358241) (xy 298.628528 -342.305908)
			(xy 298.651186 -342.256295) (xy 298.680674 -342.210411) (xy 298.716392 -342.16919) (xy 298.757612 -342.133473)
			(xy 298.803497 -342.103985) (xy 298.85311 -342.081327) (xy 298.905443 -342.065961) (xy 298.959431 -342.058199)
			(xy 298.986702 -342.057736) (xy 299.850302 -342.057736) (xy 299.877571 -342.058227) (xy 299.931554 -342.065988)
			(xy 299.983883 -342.081354) (xy 300.033493 -342.10401) (xy 300.079373 -342.133496) (xy 300.120591 -342.169211)
			(xy 300.156305 -342.210428) (xy 300.185791 -342.256309) (xy 300.208447 -342.305919) (xy 300.223812 -342.358248)
			(xy 300.231574 -342.412231) (xy 300.231574 -342.466769) (xy 300.231574 -342.466771) (xy 312.1215 -342.466771)
			(xy 312.1215 -342.412229) (xy 312.129262 -342.358241) (xy 312.144628 -342.305908) (xy 312.167286 -342.256294)
			(xy 312.196774 -342.21041) (xy 312.232493 -342.16919) (xy 312.273713 -342.133472) (xy 312.319598 -342.103984)
			(xy 312.369212 -342.081327) (xy 312.421545 -342.065961) (xy 312.475533 -342.058199) (xy 312.502804 -342.057736)
			(xy 313.366404 -342.057736) (xy 313.393673 -342.058227) (xy 313.447656 -342.065989) (xy 313.499985 -342.081354)
			(xy 313.549594 -342.104011) (xy 313.595474 -342.133497) (xy 313.636691 -342.169212) (xy 313.672406 -342.210429)
			(xy 313.701891 -342.256309) (xy 313.724547 -342.305919) (xy 313.739912 -342.358248) (xy 313.747674 -342.412231)
			(xy 313.747674 -342.466768) (xy 315.230522 -342.466768) (xy 315.230522 -342.412232) (xy 315.238283 -342.358251)
			(xy 315.253647 -342.305924) (xy 315.2763 -342.256316) (xy 315.305783 -342.210437) (xy 315.341495 -342.16922)
			(xy 315.382708 -342.133505) (xy 315.428585 -342.104018) (xy 315.478191 -342.081359) (xy 315.530516 -342.065991)
			(xy 315.584496 -342.058225) (xy 315.611764 -342.057736) (xy 316.475364 -342.057736) (xy 316.502637 -342.058201)
			(xy 316.556627 -342.065959) (xy 316.608964 -342.081322) (xy 316.658581 -342.103977) (xy 316.704469 -342.133464)
			(xy 316.745693 -342.169181) (xy 316.781414 -342.210402) (xy 316.810905 -342.256287) (xy 316.833565 -342.305902)
			(xy 316.848933 -342.358238) (xy 316.856696 -342.412228) (xy 316.856696 -342.466772) (xy 318.3394 -342.466772)
			(xy 318.3394 -342.412228) (xy 318.347162 -342.358239) (xy 318.36253 -342.305904) (xy 318.385189 -342.256289)
			(xy 318.414679 -342.210404) (xy 318.4504 -342.169183) (xy 318.491623 -342.133465) (xy 318.53751 -342.103978)
			(xy 318.587126 -342.081322) (xy 318.639462 -342.065957) (xy 318.693452 -342.058198) (xy 318.720724 -342.057736)
			(xy 319.584324 -342.057736) (xy 319.611592 -342.058228) (xy 319.665573 -342.065992) (xy 319.717899 -342.08136)
			(xy 319.767506 -342.104017) (xy 319.813384 -342.133504) (xy 319.854598 -342.169219) (xy 319.890311 -342.210435)
			(xy 319.919794 -342.256315) (xy 319.942449 -342.305923) (xy 319.957813 -342.358251) (xy 319.965574 -342.412232)
			(xy 319.965574 -342.466768) (xy 319.965574 -342.466769) (xy 321.448422 -342.466769) (xy 321.448422 -342.412231)
			(xy 321.456184 -342.358249) (xy 321.471548 -342.30592) (xy 321.494203 -342.256311) (xy 321.523688 -342.21043)
			(xy 321.559402 -342.169213) (xy 321.600618 -342.133498) (xy 321.646497 -342.104011) (xy 321.696105 -342.081354)
			(xy 321.748433 -342.065987) (xy 321.802415 -342.058224) (xy 321.829684 -342.057736) (xy 322.693284 -342.057736)
			(xy 322.720556 -342.058202) (xy 322.774544 -342.065963) (xy 322.826878 -342.081327) (xy 322.876493 -342.103984)
			(xy 322.922379 -342.133471) (xy 322.9636 -342.169188) (xy 322.999319 -342.210409) (xy 323.028808 -342.256293)
			(xy 323.051467 -342.305907) (xy 323.066834 -342.35824) (xy 323.074596 -342.412228) (xy 323.074596 -342.466772)
			(xy 323.074596 -342.466773) (xy 324.5573 -342.466773) (xy 324.5573 -342.412227) (xy 324.565063 -342.358236)
			(xy 324.580432 -342.305899) (xy 324.603092 -342.256283) (xy 324.632584 -342.210397) (xy 324.668307 -342.169176)
			(xy 324.709532 -342.133458) (xy 324.755422 -342.103971) (xy 324.805041 -342.081316) (xy 324.857379 -342.065954)
			(xy 324.911371 -342.058196) (xy 324.938644 -342.057736) (xy 325.802244 -342.057736) (xy 325.829511 -342.058229)
			(xy 325.88349 -342.065996) (xy 325.935814 -342.081365) (xy 325.985418 -342.104024) (xy 326.031293 -342.133511)
			(xy 326.072505 -342.169226) (xy 326.108216 -342.210442) (xy 326.137697 -342.256321) (xy 326.16035 -342.305928)
			(xy 326.175713 -342.358253) (xy 326.183474 -342.412233) (xy 326.183474 -342.466767) (xy 326.183473 -342.466771)
			(xy 327.6663 -342.466771) (xy 327.6663 -342.412229) (xy 327.674062 -342.358241) (xy 327.689428 -342.305908)
			(xy 327.712086 -342.256294) (xy 327.741574 -342.21041) (xy 327.777293 -342.16919) (xy 327.818513 -342.133472)
			(xy 327.864398 -342.103984) (xy 327.914012 -342.081327) (xy 327.966345 -342.065961) (xy 328.020333 -342.058199)
			(xy 328.047604 -342.057736) (xy 328.911204 -342.057736) (xy 328.938473 -342.058227) (xy 328.992456 -342.065989)
			(xy 329.044785 -342.081354) (xy 329.094394 -342.104011) (xy 329.140274 -342.133497) (xy 329.181491 -342.169212)
			(xy 329.217206 -342.210429) (xy 329.246691 -342.256309) (xy 329.269347 -342.305919) (xy 329.284712 -342.358248)
			(xy 329.292474 -342.412231) (xy 329.292474 -342.466768) (xy 330.775322 -342.466768) (xy 330.775322 -342.412232)
			(xy 330.783083 -342.358251) (xy 330.798447 -342.305924) (xy 330.8211 -342.256316) (xy 330.850583 -342.210437)
			(xy 330.886295 -342.16922) (xy 330.927508 -342.133505) (xy 330.973385 -342.104018) (xy 331.022991 -342.081359)
			(xy 331.075316 -342.065991) (xy 331.129296 -342.058225) (xy 331.156564 -342.057736) (xy 332.020164 -342.057736)
			(xy 332.047437 -342.058201) (xy 332.101427 -342.065959) (xy 332.153764 -342.081322) (xy 332.203381 -342.103977)
			(xy 332.249269 -342.133464) (xy 332.290493 -342.169181) (xy 332.326214 -342.210402) (xy 332.355705 -342.256287)
			(xy 332.378365 -342.305902) (xy 332.393733 -342.358238) (xy 332.401496 -342.412228) (xy 332.401496 -342.466772)
			(xy 333.8842 -342.466772) (xy 333.8842 -342.412228) (xy 333.891962 -342.358239) (xy 333.90733 -342.305904)
			(xy 333.929989 -342.256289) (xy 333.959479 -342.210404) (xy 333.9952 -342.169183) (xy 334.036423 -342.133465)
			(xy 334.08231 -342.103978) (xy 334.131926 -342.081322) (xy 334.184262 -342.065957) (xy 334.238252 -342.058198)
			(xy 334.265524 -342.057736) (xy 335.129124 -342.057736) (xy 335.156392 -342.058228) (xy 335.210373 -342.065992)
			(xy 335.262699 -342.08136) (xy 335.312306 -342.104017) (xy 335.358184 -342.133504) (xy 335.399398 -342.169219)
			(xy 335.435111 -342.210435) (xy 335.464594 -342.256315) (xy 335.487249 -342.305923) (xy 335.502613 -342.358251)
			(xy 335.510374 -342.412232) (xy 335.510374 -342.466768) (xy 335.510374 -342.466769) (xy 336.993222 -342.466769)
			(xy 336.993222 -342.412231) (xy 337.000984 -342.358249) (xy 337.016348 -342.30592) (xy 337.039003 -342.256311)
			(xy 337.068488 -342.21043) (xy 337.104202 -342.169213) (xy 337.145418 -342.133498) (xy 337.191297 -342.104011)
			(xy 337.240905 -342.081354) (xy 337.293233 -342.065987) (xy 337.347215 -342.058224) (xy 337.374484 -342.057736)
			(xy 338.238084 -342.057736) (xy 338.265356 -342.058202) (xy 338.319344 -342.065963) (xy 338.371678 -342.081327)
			(xy 338.421293 -342.103984) (xy 338.467179 -342.133471) (xy 338.5084 -342.169188) (xy 338.544119 -342.210409)
			(xy 338.573608 -342.256293) (xy 338.596267 -342.305907) (xy 338.611634 -342.35824) (xy 338.619396 -342.412228)
			(xy 338.619396 -342.466772) (xy 338.619396 -342.466773) (xy 340.1021 -342.466773) (xy 340.1021 -342.412227)
			(xy 340.109863 -342.358236) (xy 340.125232 -342.305899) (xy 340.147892 -342.256283) (xy 340.177384 -342.210397)
			(xy 340.213107 -342.169176) (xy 340.254332 -342.133458) (xy 340.300222 -342.103971) (xy 340.349841 -342.081316)
			(xy 340.402179 -342.065954) (xy 340.456171 -342.058196) (xy 340.483444 -342.057736) (xy 341.347044 -342.057736)
			(xy 341.374311 -342.058229) (xy 341.42829 -342.065996) (xy 341.480614 -342.081365) (xy 341.530218 -342.104024)
			(xy 341.576093 -342.133511) (xy 341.617305 -342.169226) (xy 341.653016 -342.210442) (xy 341.682497 -342.256321)
			(xy 341.70515 -342.305928) (xy 341.720513 -342.358253) (xy 341.728274 -342.412233) (xy 341.728274 -342.466767)
			(xy 341.728273 -342.466771) (xy 343.2111 -342.466771) (xy 343.2111 -342.412229) (xy 343.218862 -342.358241)
			(xy 343.234228 -342.305908) (xy 343.256886 -342.256294) (xy 343.286374 -342.21041) (xy 343.322093 -342.16919)
			(xy 343.363313 -342.133472) (xy 343.409198 -342.103984) (xy 343.458812 -342.081327) (xy 343.511145 -342.065961)
			(xy 343.565133 -342.058199) (xy 343.592404 -342.057736) (xy 344.456004 -342.057736) (xy 344.483273 -342.058227)
			(xy 344.537256 -342.065989) (xy 344.589585 -342.081354) (xy 344.639194 -342.104011) (xy 344.685074 -342.133497)
			(xy 344.726291 -342.169212) (xy 344.762006 -342.210429) (xy 344.791491 -342.256309) (xy 344.814147 -342.305919)
			(xy 344.829512 -342.358248) (xy 344.837274 -342.412231) (xy 344.837274 -342.466769) (xy 370.806722 -342.466769)
			(xy 370.806722 -342.412231) (xy 370.814484 -342.358249) (xy 370.829848 -342.305921) (xy 370.852503 -342.256312)
			(xy 370.881987 -342.210432) (xy 370.9177 -342.169214) (xy 370.958916 -342.133499) (xy 371.004794 -342.104012)
			(xy 371.054402 -342.081355) (xy 371.10673 -342.065988) (xy 371.160711 -342.058224) (xy 371.18798 -342.057736)
			(xy 372.05158 -342.057736) (xy 372.078852 -342.058202) (xy 372.132841 -342.065962) (xy 372.185175 -342.081326)
			(xy 372.234791 -342.103983) (xy 372.280677 -342.13347) (xy 372.321899 -342.169187) (xy 372.357618 -342.210407)
			(xy 372.387108 -342.256292) (xy 372.409767 -342.305906) (xy 372.425134 -342.35824) (xy 372.432896 -342.412228)
			(xy 372.432896 -342.466772) (xy 372.432896 -342.466773) (xy 373.9156 -342.466773) (xy 373.9156 -342.412227)
			(xy 373.923363 -342.358236) (xy 373.938731 -342.3059) (xy 373.961392 -342.256284) (xy 373.990883 -342.210398)
			(xy 374.026605 -342.169177) (xy 374.06783 -342.133459) (xy 374.113719 -342.103973) (xy 374.163338 -342.081317)
			(xy 374.215676 -342.065954) (xy 374.269667 -342.058197) (xy 374.29694 -342.057736) (xy 375.16054 -342.057736)
			(xy 375.187807 -342.058229) (xy 375.241786 -342.065995) (xy 375.294111 -342.081364) (xy 375.343716 -342.104022)
			(xy 375.389591 -342.133509) (xy 375.430804 -342.169224) (xy 375.466515 -342.210441) (xy 375.495997 -342.256319)
			(xy 375.51865 -342.305927) (xy 375.534013 -342.358253) (xy 375.541774 -342.412233) (xy 375.541774 -342.466767)
			(xy 375.541774 -342.46677) (xy 377.024622 -342.46677) (xy 377.024622 -342.41223) (xy 377.032384 -342.358247)
			(xy 377.04775 -342.305917) (xy 377.070406 -342.256306) (xy 377.099892 -342.210425) (xy 377.135607 -342.169207)
			(xy 377.176825 -342.133492) (xy 377.222706 -342.104006) (xy 377.272317 -342.08135) (xy 377.324647 -342.065984)
			(xy 377.37863 -342.058222) (xy 377.4059 -342.057736) (xy 378.2695 -342.057736) (xy 378.296769 -342.058226)
			(xy 378.350753 -342.065988) (xy 378.403082 -342.081353) (xy 378.452692 -342.104009) (xy 378.498572 -342.133495)
			(xy 378.53979 -342.16921) (xy 378.575505 -342.210428) (xy 378.604991 -342.256308) (xy 378.627647 -342.305918)
			(xy 378.643012 -342.358247) (xy 378.650774 -342.412231) (xy 378.650774 -342.466768) (xy 380.133622 -342.466768)
			(xy 380.133622 -342.412232) (xy 380.141383 -342.358252) (xy 380.156746 -342.305925) (xy 380.1794 -342.256318)
			(xy 380.208882 -342.210438) (xy 380.244593 -342.169222) (xy 380.285806 -342.133506) (xy 380.331682 -342.104019)
			(xy 380.381288 -342.08136) (xy 380.433613 -342.065991) (xy 380.487592 -342.058225) (xy 380.51486 -342.057736)
			(xy 381.37846 -342.057736) (xy 381.405733 -342.058201) (xy 381.459724 -342.065958) (xy 381.512061 -342.081321)
			(xy 381.561679 -342.103976) (xy 381.607567 -342.133463) (xy 381.648792 -342.16918) (xy 381.684513 -342.210401)
			(xy 381.714005 -342.256286) (xy 381.736665 -342.305902) (xy 381.752033 -342.358237) (xy 381.759796 -342.412227)
			(xy 381.759796 -342.466772) (xy 383.2425 -342.466772) (xy 383.2425 -342.412228) (xy 383.250262 -342.358239)
			(xy 383.26563 -342.305904) (xy 383.288289 -342.25629) (xy 383.317778 -342.210405) (xy 383.353498 -342.169184)
			(xy 383.394721 -342.133466) (xy 383.440607 -342.103979) (xy 383.490223 -342.081323) (xy 383.542559 -342.065958)
			(xy 383.596548 -342.058198) (xy 383.62382 -342.057736) (xy 384.48742 -342.057736) (xy 384.514688 -342.058228)
			(xy 384.568669 -342.065992) (xy 384.620996 -342.081359) (xy 384.670604 -342.104016) (xy 384.716482 -342.133502)
			(xy 384.757697 -342.169217) (xy 384.79341 -342.210434) (xy 384.822894 -342.256314) (xy 384.845548 -342.305922)
			(xy 384.860913 -342.35825) (xy 384.868674 -342.412232) (xy 384.868674 -342.466768) (xy 384.868674 -342.466769)
			(xy 386.351522 -342.466769) (xy 386.351522 -342.412231) (xy 386.359284 -342.358249) (xy 386.374648 -342.305921)
			(xy 386.397303 -342.256312) (xy 386.426787 -342.210432) (xy 386.4625 -342.169214) (xy 386.503716 -342.133499)
			(xy 386.549594 -342.104012) (xy 386.599202 -342.081355) (xy 386.65153 -342.065988) (xy 386.705511 -342.058224)
			(xy 386.73278 -342.057736) (xy 387.59638 -342.057736) (xy 387.623652 -342.058202) (xy 387.677641 -342.065962)
			(xy 387.729975 -342.081326) (xy 387.779591 -342.103983) (xy 387.825477 -342.13347) (xy 387.866699 -342.169187)
			(xy 387.902418 -342.210407) (xy 387.931908 -342.256292) (xy 387.954567 -342.305906) (xy 387.969934 -342.35824)
			(xy 387.977696 -342.412228) (xy 387.977696 -342.466772) (xy 387.977696 -342.466773) (xy 389.4604 -342.466773)
			(xy 389.4604 -342.412227) (xy 389.468163 -342.358236) (xy 389.483531 -342.3059) (xy 389.506192 -342.256284)
			(xy 389.535683 -342.210398) (xy 389.571405 -342.169177) (xy 389.61263 -342.133459) (xy 389.658519 -342.103973)
			(xy 389.708138 -342.081317) (xy 389.760476 -342.065954) (xy 389.814467 -342.058197) (xy 389.84174 -342.057736)
			(xy 390.70534 -342.057736) (xy 390.732607 -342.058229) (xy 390.786586 -342.065995) (xy 390.838911 -342.081364)
			(xy 390.888516 -342.104022) (xy 390.934391 -342.133509) (xy 390.975604 -342.169224) (xy 391.011315 -342.210441)
			(xy 391.040797 -342.256319) (xy 391.06345 -342.305927) (xy 391.078813 -342.358253) (xy 391.086574 -342.412233)
			(xy 391.086574 -342.466767) (xy 391.086574 -342.46677) (xy 392.569422 -342.46677) (xy 392.569422 -342.41223)
			(xy 392.577184 -342.358247) (xy 392.59255 -342.305917) (xy 392.615206 -342.256306) (xy 392.644692 -342.210425)
			(xy 392.680407 -342.169207) (xy 392.721625 -342.133492) (xy 392.767506 -342.104006) (xy 392.817117 -342.08135)
			(xy 392.869447 -342.065984) (xy 392.92343 -342.058222) (xy 392.9507 -342.057736) (xy 393.8143 -342.057736)
			(xy 393.841569 -342.058226) (xy 393.895553 -342.065988) (xy 393.947882 -342.081353) (xy 393.997492 -342.104009)
			(xy 394.043372 -342.133495) (xy 394.08459 -342.16921) (xy 394.120305 -342.210428) (xy 394.149791 -342.256308)
			(xy 394.172447 -342.305918) (xy 394.187812 -342.358247) (xy 394.195574 -342.412231) (xy 394.195574 -342.466768)
			(xy 395.678422 -342.466768) (xy 395.678422 -342.412232) (xy 395.686183 -342.358252) (xy 395.701546 -342.305925)
			(xy 395.7242 -342.256318) (xy 395.753682 -342.210438) (xy 395.789393 -342.169222) (xy 395.830606 -342.133506)
			(xy 395.876482 -342.104019) (xy 395.926088 -342.08136) (xy 395.978413 -342.065991) (xy 396.032392 -342.058225)
			(xy 396.05966 -342.057736) (xy 396.92326 -342.057736) (xy 396.950533 -342.058201) (xy 397.004524 -342.065958)
			(xy 397.056861 -342.081321) (xy 397.106479 -342.103976) (xy 397.152367 -342.133463) (xy 397.193592 -342.16918)
			(xy 397.229313 -342.210401) (xy 397.258805 -342.256286) (xy 397.281465 -342.305902) (xy 397.296833 -342.358237)
			(xy 397.304596 -342.412227) (xy 397.304596 -342.466772) (xy 398.7873 -342.466772) (xy 398.7873 -342.412228)
			(xy 398.795062 -342.358239) (xy 398.81043 -342.305904) (xy 398.833089 -342.25629) (xy 398.862578 -342.210405)
			(xy 398.898298 -342.169184) (xy 398.939521 -342.133466) (xy 398.985407 -342.103979) (xy 399.035023 -342.081323)
			(xy 399.087359 -342.065958) (xy 399.141348 -342.058198) (xy 399.16862 -342.057736) (xy 400.03222 -342.057736)
			(xy 400.059488 -342.058228) (xy 400.113469 -342.065992) (xy 400.165796 -342.081359) (xy 400.215404 -342.104016)
			(xy 400.261282 -342.133502) (xy 400.302497 -342.169217) (xy 400.33821 -342.210434) (xy 400.367694 -342.256314)
			(xy 400.390348 -342.305922) (xy 400.405713 -342.35825) (xy 400.413474 -342.412232) (xy 400.413474 -342.466768)
			(xy 400.413474 -342.466769) (xy 401.896322 -342.466769) (xy 401.896322 -342.412231) (xy 401.904084 -342.358249)
			(xy 401.919448 -342.305921) (xy 401.942103 -342.256312) (xy 401.971587 -342.210432) (xy 402.0073 -342.169214)
			(xy 402.048516 -342.133499) (xy 402.094394 -342.104012) (xy 402.144002 -342.081355) (xy 402.19633 -342.065988)
			(xy 402.250311 -342.058224) (xy 402.27758 -342.057736) (xy 403.14118 -342.057736) (xy 403.168452 -342.058202)
			(xy 403.222441 -342.065962) (xy 403.274775 -342.081326) (xy 403.324391 -342.103983) (xy 403.370277 -342.13347)
			(xy 403.411499 -342.169187) (xy 403.447218 -342.210407) (xy 403.476708 -342.256292) (xy 403.499367 -342.305906)
			(xy 403.514734 -342.35824) (xy 403.522496 -342.412228) (xy 403.522496 -342.466769) (xy 408.913822 -342.466769)
			(xy 408.913822 -342.412231) (xy 408.921584 -342.358248) (xy 408.936949 -342.305918) (xy 408.959605 -342.256309)
			(xy 408.98909 -342.210428) (xy 409.024805 -342.16921) (xy 409.066021 -342.133495) (xy 409.111902 -342.104009)
			(xy 409.161511 -342.081352) (xy 409.21384 -342.065986) (xy 409.267823 -342.058223) (xy 409.295092 -342.057736)
			(xy 410.158692 -342.057736) (xy 410.185963 -342.058203) (xy 410.239951 -342.065964) (xy 410.292284 -342.08133)
			(xy 410.341898 -342.103987) (xy 410.387782 -342.133474) (xy 410.429003 -342.169191) (xy 410.464721 -342.210411)
			(xy 410.49421 -342.256295) (xy 410.516868 -342.305908) (xy 410.532234 -342.358241) (xy 410.539996 -342.412229)
			(xy 410.539996 -342.466767) (xy 412.022822 -342.466767) (xy 412.022822 -342.412233) (xy 412.030583 -342.358253)
			(xy 412.045946 -342.305927) (xy 412.068599 -342.25632) (xy 412.09808 -342.210441) (xy 412.13379 -342.169224)
			(xy 412.175002 -342.133509) (xy 412.220878 -342.104022) (xy 412.270482 -342.081363) (xy 412.322806 -342.065993)
			(xy 412.376785 -342.058226) (xy 412.404052 -342.057736) (xy 413.267652 -342.057736) (xy 413.294925 -342.0582)
			(xy 413.348917 -342.065957) (xy 413.401255 -342.081319) (xy 413.450874 -342.103974) (xy 413.496763 -342.13346)
			(xy 413.537989 -342.169177) (xy 413.573712 -342.210398) (xy 413.603203 -342.256284) (xy 413.625864 -342.3059)
			(xy 413.641233 -342.358236) (xy 413.648996 -342.412227) (xy 413.648996 -342.466772) (xy 415.1317 -342.466772)
			(xy 415.1317 -342.412228) (xy 415.139462 -342.35824) (xy 415.154829 -342.305906) (xy 415.177488 -342.256292)
			(xy 415.206976 -342.210407) (xy 415.242695 -342.169187) (xy 415.283917 -342.133469) (xy 415.329803 -342.103982)
			(xy 415.379417 -342.081325) (xy 415.431752 -342.065959) (xy 415.48574 -342.058199) (xy 415.513012 -342.057736)
			(xy 416.376612 -342.057736) (xy 416.403881 -342.058227) (xy 416.457863 -342.06599) (xy 416.510191 -342.081357)
			(xy 416.559799 -342.104013) (xy 416.605678 -342.133499) (xy 416.646894 -342.169214) (xy 416.682608 -342.210432)
			(xy 416.712092 -342.256312) (xy 416.734748 -342.305921) (xy 416.750112 -342.358249) (xy 416.757874 -342.412231)
			(xy 416.757874 -342.466768) (xy 418.240722 -342.466768) (xy 418.240722 -342.412232) (xy 418.248483 -342.35825)
			(xy 418.263847 -342.305923) (xy 418.286502 -342.256314) (xy 418.315985 -342.210434) (xy 418.351697 -342.169217)
			(xy 418.392912 -342.133502) (xy 418.43879 -342.104015) (xy 418.488396 -342.081357) (xy 418.540723 -342.065989)
			(xy 418.594704 -342.058224) (xy 418.621972 -342.057736) (xy 419.485572 -342.057736) (xy 419.512844 -342.058202)
			(xy 419.566834 -342.06596) (xy 419.61917 -342.081324) (xy 419.668786 -342.10398) (xy 419.714673 -342.133467)
			(xy 419.755896 -342.169184) (xy 419.791616 -342.210405) (xy 419.821107 -342.256289) (xy 419.843766 -342.305904)
			(xy 419.859134 -342.358239) (xy 419.866896 -342.412228) (xy 419.866896 -342.466772) (xy 419.866896 -342.466773)
			(xy 421.3496 -342.466773) (xy 421.3496 -342.412227) (xy 421.357363 -342.358237) (xy 421.372731 -342.305902)
			(xy 421.395391 -342.256286) (xy 421.424881 -342.210401) (xy 421.460602 -342.16918) (xy 421.501827 -342.133462)
			(xy 421.547715 -342.103975) (xy 421.597332 -342.081319) (xy 421.649669 -342.065956) (xy 421.703659 -342.058197)
			(xy 421.730932 -342.057736) (xy 422.594532 -342.057736) (xy 422.6218 -342.058229) (xy 422.67578 -342.065994)
			(xy 422.728105 -342.081362) (xy 422.777711 -342.10402) (xy 422.823588 -342.133506) (xy 422.864801 -342.169222)
			(xy 422.900513 -342.210438) (xy 422.929995 -342.256317) (xy 422.952649 -342.305925) (xy 422.968013 -342.358252)
			(xy 422.975774 -342.412232) (xy 422.975774 -342.466768) (xy 422.975774 -342.466769) (xy 424.458622 -342.466769)
			(xy 424.458622 -342.412231) (xy 424.466384 -342.358248) (xy 424.481749 -342.305918) (xy 424.504405 -342.256309)
			(xy 424.53389 -342.210428) (xy 424.569605 -342.16921) (xy 424.610821 -342.133495) (xy 424.656702 -342.104009)
			(xy 424.706311 -342.081352) (xy 424.75864 -342.065986) (xy 424.812623 -342.058223) (xy 424.839892 -342.057736)
			(xy 425.703492 -342.057736) (xy 425.730763 -342.058203) (xy 425.784751 -342.065964) (xy 425.837084 -342.08133)
			(xy 425.886698 -342.103987) (xy 425.932582 -342.133474) (xy 425.973803 -342.169191) (xy 426.009521 -342.210411)
			(xy 426.03901 -342.256295) (xy 426.061668 -342.305908) (xy 426.077034 -342.358241) (xy 426.084796 -342.412229)
			(xy 426.084796 -342.466767) (xy 427.567622 -342.466767) (xy 427.567622 -342.412233) (xy 427.575383 -342.358253)
			(xy 427.590746 -342.305927) (xy 427.613399 -342.25632) (xy 427.64288 -342.210441) (xy 427.67859 -342.169224)
			(xy 427.719802 -342.133509) (xy 427.765678 -342.104022) (xy 427.815282 -342.081363) (xy 427.867606 -342.065993)
			(xy 427.921585 -342.058226) (xy 427.948852 -342.057736) (xy 428.812452 -342.057736) (xy 428.839725 -342.0582)
			(xy 428.893717 -342.065957) (xy 428.946055 -342.081319) (xy 428.995674 -342.103974) (xy 429.041563 -342.13346)
			(xy 429.082789 -342.169177) (xy 429.118512 -342.210398) (xy 429.148003 -342.256284) (xy 429.170664 -342.3059)
			(xy 429.186033 -342.358236) (xy 429.193796 -342.412227) (xy 429.193796 -342.466772) (xy 430.6765 -342.466772)
			(xy 430.6765 -342.412228) (xy 430.684262 -342.35824) (xy 430.699629 -342.305906) (xy 430.722288 -342.256292)
			(xy 430.751776 -342.210407) (xy 430.787495 -342.169187) (xy 430.828717 -342.133469) (xy 430.874603 -342.103982)
			(xy 430.924217 -342.081325) (xy 430.976552 -342.065959) (xy 431.03054 -342.058199) (xy 431.057812 -342.057736)
			(xy 431.921412 -342.057736) (xy 431.948681 -342.058227) (xy 432.002663 -342.06599) (xy 432.054991 -342.081357)
			(xy 432.104599 -342.104013) (xy 432.150478 -342.133499) (xy 432.191694 -342.169214) (xy 432.227408 -342.210432)
			(xy 432.256892 -342.256312) (xy 432.279548 -342.305921) (xy 432.294912 -342.358249) (xy 432.302674 -342.412231)
			(xy 432.302674 -342.466768) (xy 433.785522 -342.466768) (xy 433.785522 -342.412232) (xy 433.793283 -342.35825)
			(xy 433.808647 -342.305923) (xy 433.831302 -342.256314) (xy 433.860785 -342.210434) (xy 433.896497 -342.169217)
			(xy 433.937712 -342.133502) (xy 433.98359 -342.104015) (xy 434.033196 -342.081357) (xy 434.085523 -342.065989)
			(xy 434.139504 -342.058224) (xy 434.166772 -342.057736) (xy 435.030372 -342.057736) (xy 435.057644 -342.058202)
			(xy 435.111634 -342.06596) (xy 435.16397 -342.081324) (xy 435.213586 -342.10398) (xy 435.259473 -342.133467)
			(xy 435.300696 -342.169184) (xy 435.336416 -342.210405) (xy 435.365907 -342.256289) (xy 435.388566 -342.305904)
			(xy 435.403934 -342.358239) (xy 435.411696 -342.412228) (xy 435.411696 -342.466772) (xy 435.411696 -342.466773)
			(xy 436.8944 -342.466773) (xy 436.8944 -342.412227) (xy 436.902163 -342.358237) (xy 436.917531 -342.305902)
			(xy 436.940191 -342.256286) (xy 436.969681 -342.210401) (xy 437.005402 -342.16918) (xy 437.046627 -342.133462)
			(xy 437.092515 -342.103975) (xy 437.142132 -342.081319) (xy 437.194469 -342.065956) (xy 437.248459 -342.058197)
			(xy 437.275732 -342.057736) (xy 438.139332 -342.057736) (xy 438.1666 -342.058229) (xy 438.22058 -342.065994)
			(xy 438.272905 -342.081362) (xy 438.322511 -342.10402) (xy 438.368388 -342.133506) (xy 438.409601 -342.169222)
			(xy 438.445313 -342.210438) (xy 438.474795 -342.256317) (xy 438.497449 -342.305925) (xy 438.512813 -342.358252)
			(xy 438.520574 -342.412232) (xy 438.520574 -342.466768) (xy 438.520574 -342.466769) (xy 440.003422 -342.466769)
			(xy 440.003422 -342.412231) (xy 440.011184 -342.358248) (xy 440.026549 -342.305918) (xy 440.049205 -342.256309)
			(xy 440.07869 -342.210428) (xy 440.114405 -342.16921) (xy 440.155621 -342.133495) (xy 440.201502 -342.104009)
			(xy 440.251111 -342.081352) (xy 440.30344 -342.065986) (xy 440.357423 -342.058223) (xy 440.384692 -342.057736)
			(xy 441.248292 -342.057736) (xy 441.275563 -342.058203) (xy 441.329551 -342.065964) (xy 441.381884 -342.08133)
			(xy 441.431498 -342.103987) (xy 441.477382 -342.133474) (xy 441.518603 -342.169191) (xy 441.554321 -342.210411)
			(xy 441.58381 -342.256295) (xy 441.606468 -342.305908) (xy 441.621834 -342.358241) (xy 441.629596 -342.412229)
			(xy 441.629596 -342.466771) (xy 441.621834 -342.520759) (xy 441.606468 -342.573092) (xy 441.58381 -342.622705)
			(xy 441.554321 -342.668589) (xy 441.518603 -342.709809) (xy 441.477382 -342.745526) (xy 441.431498 -342.775013)
			(xy 441.381884 -342.79767) (xy 441.329551 -342.813036) (xy 441.275563 -342.820797) (xy 441.248292 -342.82126)
			(xy 440.384692 -342.82126) (xy 440.357423 -342.820777) (xy 440.30344 -342.813014) (xy 440.251111 -342.797648)
			(xy 440.201502 -342.774991) (xy 440.155621 -342.745505) (xy 440.114405 -342.70979) (xy 440.07869 -342.668572)
			(xy 440.049205 -342.622691) (xy 440.026549 -342.573082) (xy 440.011184 -342.520752) (xy 440.003422 -342.466769)
			(xy 438.520574 -342.466769) (xy 438.512813 -342.520748) (xy 438.497449 -342.573075) (xy 438.474795 -342.622683)
			(xy 438.445313 -342.668562) (xy 438.409601 -342.709778) (xy 438.368388 -342.745494) (xy 438.322511 -342.77498)
			(xy 438.272905 -342.797638) (xy 438.22058 -342.813006) (xy 438.1666 -342.820771) (xy 438.139332 -342.82126)
			(xy 437.275732 -342.82126) (xy 437.248459 -342.820803) (xy 437.194469 -342.813044) (xy 437.142132 -342.797681)
			(xy 437.092515 -342.775025) (xy 437.046627 -342.745538) (xy 437.005402 -342.70982) (xy 436.969681 -342.668599)
			(xy 436.940191 -342.622714) (xy 436.917531 -342.573098) (xy 436.902163 -342.520763) (xy 436.8944 -342.466773)
			(xy 435.411696 -342.466773) (xy 435.403934 -342.520761) (xy 435.388566 -342.573096) (xy 435.365907 -342.622711)
			(xy 435.336416 -342.668595) (xy 435.300696 -342.709816) (xy 435.259473 -342.745533) (xy 435.213586 -342.77502)
			(xy 435.16397 -342.797676) (xy 435.111634 -342.81304) (xy 435.057644 -342.820798) (xy 435.030372 -342.82126)
			(xy 434.166772 -342.82126) (xy 434.139504 -342.820776) (xy 434.085523 -342.813011) (xy 434.033196 -342.797643)
			(xy 433.98359 -342.774985) (xy 433.937712 -342.745498) (xy 433.896497 -342.709783) (xy 433.860785 -342.668566)
			(xy 433.831302 -342.622686) (xy 433.808647 -342.573077) (xy 433.793283 -342.52075) (xy 433.785522 -342.466768)
			(xy 432.302674 -342.466768) (xy 432.302674 -342.466769) (xy 432.294912 -342.520751) (xy 432.279548 -342.573079)
			(xy 432.256892 -342.622688) (xy 432.227408 -342.668568) (xy 432.191694 -342.709786) (xy 432.150478 -342.745501)
			(xy 432.104599 -342.774987) (xy 432.054991 -342.797643) (xy 432.002663 -342.81301) (xy 431.948681 -342.820773)
			(xy 431.921412 -342.82126) (xy 431.057812 -342.82126) (xy 431.03054 -342.820801) (xy 430.976552 -342.813041)
			(xy 430.924217 -342.797675) (xy 430.874603 -342.775018) (xy 430.828717 -342.745531) (xy 430.787495 -342.709813)
			(xy 430.751776 -342.668593) (xy 430.722288 -342.622708) (xy 430.699629 -342.573094) (xy 430.684262 -342.52076)
			(xy 430.6765 -342.466772) (xy 429.193796 -342.466772) (xy 429.193796 -342.466773) (xy 429.186033 -342.520764)
			(xy 429.170664 -342.5731) (xy 429.148003 -342.622716) (xy 429.118512 -342.668602) (xy 429.082789 -342.709823)
			(xy 429.041563 -342.74554) (xy 428.995674 -342.775026) (xy 428.946055 -342.797681) (xy 428.893717 -342.813043)
			(xy 428.839725 -342.8208) (xy 428.812452 -342.82126) (xy 427.948852 -342.82126) (xy 427.921585 -342.820774)
			(xy 427.867606 -342.813007) (xy 427.815282 -342.797637) (xy 427.765678 -342.774978) (xy 427.719802 -342.745491)
			(xy 427.67859 -342.709776) (xy 427.64288 -342.668559) (xy 427.613399 -342.62268) (xy 427.590746 -342.573073)
			(xy 427.575383 -342.520747) (xy 427.567622 -342.466767) (xy 426.084796 -342.466767) (xy 426.084796 -342.466771)
			(xy 426.077034 -342.520759) (xy 426.061668 -342.573092) (xy 426.03901 -342.622705) (xy 426.009521 -342.668589)
			(xy 425.973803 -342.709809) (xy 425.932582 -342.745526) (xy 425.886698 -342.775013) (xy 425.837084 -342.79767)
			(xy 425.784751 -342.813036) (xy 425.730763 -342.820797) (xy 425.703492 -342.82126) (xy 424.839892 -342.82126)
			(xy 424.812623 -342.820777) (xy 424.75864 -342.813014) (xy 424.706311 -342.797648) (xy 424.656702 -342.774991)
			(xy 424.610821 -342.745505) (xy 424.569605 -342.70979) (xy 424.53389 -342.668572) (xy 424.504405 -342.622691)
			(xy 424.481749 -342.573082) (xy 424.466384 -342.520752) (xy 424.458622 -342.466769) (xy 422.975774 -342.466769)
			(xy 422.968013 -342.520748) (xy 422.952649 -342.573075) (xy 422.929995 -342.622683) (xy 422.900513 -342.668562)
			(xy 422.864801 -342.709778) (xy 422.823588 -342.745494) (xy 422.777711 -342.77498) (xy 422.728105 -342.797638)
			(xy 422.67578 -342.813006) (xy 422.6218 -342.820771) (xy 422.594532 -342.82126) (xy 421.730932 -342.82126)
			(xy 421.703659 -342.820803) (xy 421.649669 -342.813044) (xy 421.597332 -342.797681) (xy 421.547715 -342.775025)
			(xy 421.501827 -342.745538) (xy 421.460602 -342.70982) (xy 421.424881 -342.668599) (xy 421.395391 -342.622714)
			(xy 421.372731 -342.573098) (xy 421.357363 -342.520763) (xy 421.3496 -342.466773) (xy 419.866896 -342.466773)
			(xy 419.859134 -342.520761) (xy 419.843766 -342.573096) (xy 419.821107 -342.622711) (xy 419.791616 -342.668595)
			(xy 419.755896 -342.709816) (xy 419.714673 -342.745533) (xy 419.668786 -342.77502) (xy 419.61917 -342.797676)
			(xy 419.566834 -342.81304) (xy 419.512844 -342.820798) (xy 419.485572 -342.82126) (xy 418.621972 -342.82126)
			(xy 418.594704 -342.820776) (xy 418.540723 -342.813011) (xy 418.488396 -342.797643) (xy 418.43879 -342.774985)
			(xy 418.392912 -342.745498) (xy 418.351697 -342.709783) (xy 418.315985 -342.668566) (xy 418.286502 -342.622686)
			(xy 418.263847 -342.573077) (xy 418.248483 -342.52075) (xy 418.240722 -342.466768) (xy 416.757874 -342.466768)
			(xy 416.757874 -342.466769) (xy 416.750112 -342.520751) (xy 416.734748 -342.573079) (xy 416.712092 -342.622688)
			(xy 416.682608 -342.668568) (xy 416.646894 -342.709786) (xy 416.605678 -342.745501) (xy 416.559799 -342.774987)
			(xy 416.510191 -342.797643) (xy 416.457863 -342.81301) (xy 416.403881 -342.820773) (xy 416.376612 -342.82126)
			(xy 415.513012 -342.82126) (xy 415.48574 -342.820801) (xy 415.431752 -342.813041) (xy 415.379417 -342.797675)
			(xy 415.329803 -342.775018) (xy 415.283917 -342.745531) (xy 415.242695 -342.709813) (xy 415.206976 -342.668593)
			(xy 415.177488 -342.622708) (xy 415.154829 -342.573094) (xy 415.139462 -342.52076) (xy 415.1317 -342.466772)
			(xy 413.648996 -342.466772) (xy 413.648996 -342.466773) (xy 413.641233 -342.520764) (xy 413.625864 -342.5731)
			(xy 413.603203 -342.622716) (xy 413.573712 -342.668602) (xy 413.537989 -342.709823) (xy 413.496763 -342.74554)
			(xy 413.450874 -342.775026) (xy 413.401255 -342.797681) (xy 413.348917 -342.813043) (xy 413.294925 -342.8208)
			(xy 413.267652 -342.82126) (xy 412.404052 -342.82126) (xy 412.376785 -342.820774) (xy 412.322806 -342.813007)
			(xy 412.270482 -342.797637) (xy 412.220878 -342.774978) (xy 412.175002 -342.745491) (xy 412.13379 -342.709776)
			(xy 412.09808 -342.668559) (xy 412.068599 -342.62268) (xy 412.045946 -342.573073) (xy 412.030583 -342.520747)
			(xy 412.022822 -342.466767) (xy 410.539996 -342.466767) (xy 410.539996 -342.466771) (xy 410.532234 -342.520759)
			(xy 410.516868 -342.573092) (xy 410.49421 -342.622705) (xy 410.464721 -342.668589) (xy 410.429003 -342.709809)
			(xy 410.387782 -342.745526) (xy 410.341898 -342.775013) (xy 410.292284 -342.79767) (xy 410.239951 -342.813036)
			(xy 410.185963 -342.820797) (xy 410.158692 -342.82126) (xy 409.295092 -342.82126) (xy 409.267823 -342.820777)
			(xy 409.21384 -342.813014) (xy 409.161511 -342.797648) (xy 409.111902 -342.774991) (xy 409.066021 -342.745505)
			(xy 409.024805 -342.70979) (xy 408.98909 -342.668572) (xy 408.959605 -342.622691) (xy 408.936949 -342.573082)
			(xy 408.921584 -342.520752) (xy 408.913822 -342.466769) (xy 403.522496 -342.466769) (xy 403.522496 -342.466772)
			(xy 403.514734 -342.52076) (xy 403.499367 -342.573094) (xy 403.476708 -342.622708) (xy 403.447218 -342.668593)
			(xy 403.411499 -342.709813) (xy 403.370277 -342.74553) (xy 403.324391 -342.775017) (xy 403.274775 -342.797674)
			(xy 403.222441 -342.813038) (xy 403.168452 -342.820798) (xy 403.14118 -342.82126) (xy 402.27758 -342.82126)
			(xy 402.250311 -342.820776) (xy 402.19633 -342.813012) (xy 402.144002 -342.797645) (xy 402.094394 -342.774988)
			(xy 402.048516 -342.745501) (xy 402.0073 -342.709786) (xy 401.971587 -342.668568) (xy 401.942103 -342.622688)
			(xy 401.919448 -342.573079) (xy 401.904084 -342.520751) (xy 401.896322 -342.466769) (xy 400.413474 -342.466769)
			(xy 400.405713 -342.52075) (xy 400.390348 -342.573078) (xy 400.367694 -342.622686) (xy 400.33821 -342.668566)
			(xy 400.302497 -342.709783) (xy 400.261282 -342.745498) (xy 400.215404 -342.774984) (xy 400.165796 -342.797641)
			(xy 400.113469 -342.813008) (xy 400.059488 -342.820772) (xy 400.03222 -342.82126) (xy 399.16862 -342.82126)
			(xy 399.141348 -342.820802) (xy 399.087359 -342.813042) (xy 399.035023 -342.797677) (xy 398.985407 -342.775021)
			(xy 398.939521 -342.745534) (xy 398.898298 -342.709816) (xy 398.862578 -342.668595) (xy 398.833089 -342.62271)
			(xy 398.81043 -342.573096) (xy 398.795062 -342.520761) (xy 398.7873 -342.466772) (xy 397.304596 -342.466772)
			(xy 397.304596 -342.466773) (xy 397.296833 -342.520763) (xy 397.281465 -342.573098) (xy 397.258805 -342.622714)
			(xy 397.229313 -342.668599) (xy 397.193592 -342.70982) (xy 397.152367 -342.745537) (xy 397.106479 -342.775024)
			(xy 397.056861 -342.797679) (xy 397.004524 -342.813042) (xy 396.950533 -342.820799) (xy 396.92326 -342.82126)
			(xy 396.05966 -342.82126) (xy 396.032392 -342.820775) (xy 395.978413 -342.813009) (xy 395.926088 -342.79764)
			(xy 395.876482 -342.774981) (xy 395.830606 -342.745494) (xy 395.789393 -342.709778) (xy 395.753682 -342.668562)
			(xy 395.7242 -342.622682) (xy 395.701546 -342.573075) (xy 395.686183 -342.520748) (xy 395.678422 -342.466768)
			(xy 394.195574 -342.466768) (xy 394.195574 -342.466769) (xy 394.187812 -342.520753) (xy 394.172447 -342.573082)
			(xy 394.149791 -342.622692) (xy 394.120305 -342.668572) (xy 394.08459 -342.70979) (xy 394.043372 -342.745505)
			(xy 393.997492 -342.774991) (xy 393.947882 -342.797647) (xy 393.895553 -342.813012) (xy 393.841569 -342.820774)
			(xy 393.8143 -342.82126) (xy 392.9507 -342.82126) (xy 392.92343 -342.820778) (xy 392.869447 -342.813016)
			(xy 392.817117 -342.79765) (xy 392.767506 -342.774994) (xy 392.721625 -342.745508) (xy 392.680407 -342.709793)
			(xy 392.644692 -342.668575) (xy 392.615206 -342.622694) (xy 392.59255 -342.573083) (xy 392.577184 -342.520753)
			(xy 392.569422 -342.46677) (xy 391.086574 -342.46677) (xy 391.078813 -342.520747) (xy 391.06345 -342.573073)
			(xy 391.040797 -342.622681) (xy 391.011315 -342.668559) (xy 390.975604 -342.709776) (xy 390.934391 -342.745491)
			(xy 390.888516 -342.774978) (xy 390.838911 -342.797636) (xy 390.786586 -342.813005) (xy 390.732607 -342.820771)
			(xy 390.70534 -342.82126) (xy 389.84174 -342.82126) (xy 389.814467 -342.820803) (xy 389.760476 -342.813046)
			(xy 389.708138 -342.797683) (xy 389.658519 -342.775027) (xy 389.61263 -342.745541) (xy 389.571405 -342.709823)
			(xy 389.535683 -342.668602) (xy 389.506192 -342.622716) (xy 389.483531 -342.5731) (xy 389.468163 -342.520764)
			(xy 389.4604 -342.466773) (xy 387.977696 -342.466773) (xy 387.969934 -342.52076) (xy 387.954567 -342.573094)
			(xy 387.931908 -342.622708) (xy 387.902418 -342.668593) (xy 387.866699 -342.709813) (xy 387.825477 -342.74553)
			(xy 387.779591 -342.775017) (xy 387.729975 -342.797674) (xy 387.677641 -342.813038) (xy 387.623652 -342.820798)
			(xy 387.59638 -342.82126) (xy 386.73278 -342.82126) (xy 386.705511 -342.820776) (xy 386.65153 -342.813012)
			(xy 386.599202 -342.797645) (xy 386.549594 -342.774988) (xy 386.503716 -342.745501) (xy 386.4625 -342.709786)
			(xy 386.426787 -342.668568) (xy 386.397303 -342.622688) (xy 386.374648 -342.573079) (xy 386.359284 -342.520751)
			(xy 386.351522 -342.466769) (xy 384.868674 -342.466769) (xy 384.860913 -342.52075) (xy 384.845548 -342.573078)
			(xy 384.822894 -342.622686) (xy 384.79341 -342.668566) (xy 384.757697 -342.709783) (xy 384.716482 -342.745498)
			(xy 384.670604 -342.774984) (xy 384.620996 -342.797641) (xy 384.568669 -342.813008) (xy 384.514688 -342.820772)
			(xy 384.48742 -342.82126) (xy 383.62382 -342.82126) (xy 383.596548 -342.820802) (xy 383.542559 -342.813042)
			(xy 383.490223 -342.797677) (xy 383.440607 -342.775021) (xy 383.394721 -342.745534) (xy 383.353498 -342.709816)
			(xy 383.317778 -342.668595) (xy 383.288289 -342.62271) (xy 383.26563 -342.573096) (xy 383.250262 -342.520761)
			(xy 383.2425 -342.466772) (xy 381.759796 -342.466772) (xy 381.759796 -342.466773) (xy 381.752033 -342.520763)
			(xy 381.736665 -342.573098) (xy 381.714005 -342.622714) (xy 381.684513 -342.668599) (xy 381.648792 -342.70982)
			(xy 381.607567 -342.745537) (xy 381.561679 -342.775024) (xy 381.512061 -342.797679) (xy 381.459724 -342.813042)
			(xy 381.405733 -342.820799) (xy 381.37846 -342.82126) (xy 380.51486 -342.82126) (xy 380.487592 -342.820775)
			(xy 380.433613 -342.813009) (xy 380.381288 -342.79764) (xy 380.331682 -342.774981) (xy 380.285806 -342.745494)
			(xy 380.244593 -342.709778) (xy 380.208882 -342.668562) (xy 380.1794 -342.622682) (xy 380.156746 -342.573075)
			(xy 380.141383 -342.520748) (xy 380.133622 -342.466768) (xy 378.650774 -342.466768) (xy 378.650774 -342.466769)
			(xy 378.643012 -342.520753) (xy 378.627647 -342.573082) (xy 378.604991 -342.622692) (xy 378.575505 -342.668572)
			(xy 378.53979 -342.70979) (xy 378.498572 -342.745505) (xy 378.452692 -342.774991) (xy 378.403082 -342.797647)
			(xy 378.350753 -342.813012) (xy 378.296769 -342.820774) (xy 378.2695 -342.82126) (xy 377.4059 -342.82126)
			(xy 377.37863 -342.820778) (xy 377.324647 -342.813016) (xy 377.272317 -342.79765) (xy 377.222706 -342.774994)
			(xy 377.176825 -342.745508) (xy 377.135607 -342.709793) (xy 377.099892 -342.668575) (xy 377.070406 -342.622694)
			(xy 377.04775 -342.573083) (xy 377.032384 -342.520753) (xy 377.024622 -342.46677) (xy 375.541774 -342.46677)
			(xy 375.534013 -342.520747) (xy 375.51865 -342.573073) (xy 375.495997 -342.622681) (xy 375.466515 -342.668559)
			(xy 375.430804 -342.709776) (xy 375.389591 -342.745491) (xy 375.343716 -342.774978) (xy 375.294111 -342.797636)
			(xy 375.241786 -342.813005) (xy 375.187807 -342.820771) (xy 375.16054 -342.82126) (xy 374.29694 -342.82126)
			(xy 374.269667 -342.820803) (xy 374.215676 -342.813046) (xy 374.163338 -342.797683) (xy 374.113719 -342.775027)
			(xy 374.06783 -342.745541) (xy 374.026605 -342.709823) (xy 373.990883 -342.668602) (xy 373.961392 -342.622716)
			(xy 373.938731 -342.5731) (xy 373.923363 -342.520764) (xy 373.9156 -342.466773) (xy 372.432896 -342.466773)
			(xy 372.425134 -342.52076) (xy 372.409767 -342.573094) (xy 372.387108 -342.622708) (xy 372.357618 -342.668593)
			(xy 372.321899 -342.709813) (xy 372.280677 -342.74553) (xy 372.234791 -342.775017) (xy 372.185175 -342.797674)
			(xy 372.132841 -342.813038) (xy 372.078852 -342.820798) (xy 372.05158 -342.82126) (xy 371.18798 -342.82126)
			(xy 371.160711 -342.820776) (xy 371.10673 -342.813012) (xy 371.054402 -342.797645) (xy 371.004794 -342.774988)
			(xy 370.958916 -342.745501) (xy 370.9177 -342.709786) (xy 370.881987 -342.668568) (xy 370.852503 -342.622688)
			(xy 370.829848 -342.573079) (xy 370.814484 -342.520751) (xy 370.806722 -342.466769) (xy 344.837274 -342.466769)
			(xy 344.829512 -342.520752) (xy 344.814147 -342.573081) (xy 344.791491 -342.622691) (xy 344.762006 -342.668571)
			(xy 344.726291 -342.709788) (xy 344.685074 -342.745503) (xy 344.639194 -342.774989) (xy 344.589585 -342.797646)
			(xy 344.537256 -342.813011) (xy 344.483273 -342.820773) (xy 344.456004 -342.82126) (xy 343.592404 -342.82126)
			(xy 343.565133 -342.820801) (xy 343.511145 -342.813039) (xy 343.458812 -342.797673) (xy 343.409198 -342.775016)
			(xy 343.363313 -342.745528) (xy 343.322093 -342.70981) (xy 343.286374 -342.66859) (xy 343.256886 -342.622706)
			(xy 343.234228 -342.573092) (xy 343.218862 -342.520759) (xy 343.2111 -342.466771) (xy 341.728273 -342.466771)
			(xy 341.720513 -342.520747) (xy 341.70515 -342.573072) (xy 341.682497 -342.622679) (xy 341.653016 -342.668558)
			(xy 341.617305 -342.709774) (xy 341.576093 -342.745489) (xy 341.530218 -342.774976) (xy 341.480614 -342.797635)
			(xy 341.42829 -342.813004) (xy 341.374311 -342.820771) (xy 341.347044 -342.82126) (xy 340.483444 -342.82126)
			(xy 340.456171 -342.820804) (xy 340.402179 -342.813046) (xy 340.349841 -342.797684) (xy 340.300222 -342.775029)
			(xy 340.254332 -342.745542) (xy 340.213107 -342.709824) (xy 340.177384 -342.668603) (xy 340.147892 -342.622717)
			(xy 340.125232 -342.573101) (xy 340.109863 -342.520764) (xy 340.1021 -342.466773) (xy 338.619396 -342.466773)
			(xy 338.611634 -342.52076) (xy 338.596267 -342.573093) (xy 338.573608 -342.622707) (xy 338.544119 -342.668591)
			(xy 338.5084 -342.709812) (xy 338.467179 -342.745529) (xy 338.421293 -342.775016) (xy 338.371678 -342.797673)
			(xy 338.319344 -342.813037) (xy 338.265356 -342.820798) (xy 338.238084 -342.82126) (xy 337.374484 -342.82126)
			(xy 337.347215 -342.820776) (xy 337.293233 -342.813013) (xy 337.240905 -342.797646) (xy 337.191297 -342.774989)
			(xy 337.145418 -342.745502) (xy 337.104202 -342.709787) (xy 337.068488 -342.66857) (xy 337.039003 -342.622689)
			(xy 337.016348 -342.57308) (xy 337.000984 -342.520751) (xy 336.993222 -342.466769) (xy 335.510374 -342.466769)
			(xy 335.502613 -342.520749) (xy 335.487249 -342.573077) (xy 335.464594 -342.622685) (xy 335.435111 -342.668565)
			(xy 335.399398 -342.709781) (xy 335.358184 -342.745496) (xy 335.312306 -342.774983) (xy 335.262699 -342.79764)
			(xy 335.210373 -342.813008) (xy 335.156392 -342.820772) (xy 335.129124 -342.82126) (xy 334.265524 -342.82126)
			(xy 334.238252 -342.820802) (xy 334.184262 -342.813043) (xy 334.131926 -342.797678) (xy 334.08231 -342.775022)
			(xy 334.036423 -342.745535) (xy 333.9952 -342.709817) (xy 333.959479 -342.668596) (xy 333.929989 -342.622711)
			(xy 333.90733 -342.573096) (xy 333.891962 -342.520761) (xy 333.8842 -342.466772) (xy 332.401496 -342.466772)
			(xy 332.393733 -342.520762) (xy 332.378365 -342.573098) (xy 332.355705 -342.622713) (xy 332.326214 -342.668598)
			(xy 332.290493 -342.709819) (xy 332.249269 -342.745536) (xy 332.203381 -342.775023) (xy 332.153764 -342.797678)
			(xy 332.101427 -342.813041) (xy 332.047437 -342.820799) (xy 332.020164 -342.82126) (xy 331.156564 -342.82126)
			(xy 331.129296 -342.820775) (xy 331.075316 -342.813009) (xy 331.022991 -342.797641) (xy 330.973385 -342.774982)
			(xy 330.927508 -342.745495) (xy 330.886295 -342.70978) (xy 330.850583 -342.668563) (xy 330.8211 -342.622684)
			(xy 330.798447 -342.573076) (xy 330.783083 -342.520749) (xy 330.775322 -342.466768) (xy 329.292474 -342.466768)
			(xy 329.292474 -342.466769) (xy 329.284712 -342.520752) (xy 329.269347 -342.573081) (xy 329.246691 -342.622691)
			(xy 329.217206 -342.668571) (xy 329.181491 -342.709788) (xy 329.140274 -342.745503) (xy 329.094394 -342.774989)
			(xy 329.044785 -342.797646) (xy 328.992456 -342.813011) (xy 328.938473 -342.820773) (xy 328.911204 -342.82126)
			(xy 328.047604 -342.82126) (xy 328.020333 -342.820801) (xy 327.966345 -342.813039) (xy 327.914012 -342.797673)
			(xy 327.864398 -342.775016) (xy 327.818513 -342.745528) (xy 327.777293 -342.70981) (xy 327.741574 -342.66859)
			(xy 327.712086 -342.622706) (xy 327.689428 -342.573092) (xy 327.674062 -342.520759) (xy 327.6663 -342.466771)
			(xy 326.183473 -342.466771) (xy 326.175713 -342.520747) (xy 326.16035 -342.573072) (xy 326.137697 -342.622679)
			(xy 326.108216 -342.668558) (xy 326.072505 -342.709774) (xy 326.031293 -342.745489) (xy 325.985418 -342.774976)
			(xy 325.935814 -342.797635) (xy 325.88349 -342.813004) (xy 325.829511 -342.820771) (xy 325.802244 -342.82126)
			(xy 324.938644 -342.82126) (xy 324.911371 -342.820804) (xy 324.857379 -342.813046) (xy 324.805041 -342.797684)
			(xy 324.755422 -342.775029) (xy 324.709532 -342.745542) (xy 324.668307 -342.709824) (xy 324.632584 -342.668603)
			(xy 324.603092 -342.622717) (xy 324.580432 -342.573101) (xy 324.565063 -342.520764) (xy 324.5573 -342.466773)
			(xy 323.074596 -342.466773) (xy 323.066834 -342.52076) (xy 323.051467 -342.573093) (xy 323.028808 -342.622707)
			(xy 322.999319 -342.668591) (xy 322.9636 -342.709812) (xy 322.922379 -342.745529) (xy 322.876493 -342.775016)
			(xy 322.826878 -342.797673) (xy 322.774544 -342.813037) (xy 322.720556 -342.820798) (xy 322.693284 -342.82126)
			(xy 321.829684 -342.82126) (xy 321.802415 -342.820776) (xy 321.748433 -342.813013) (xy 321.696105 -342.797646)
			(xy 321.646497 -342.774989) (xy 321.600618 -342.745502) (xy 321.559402 -342.709787) (xy 321.523688 -342.66857)
			(xy 321.494203 -342.622689) (xy 321.471548 -342.57308) (xy 321.456184 -342.520751) (xy 321.448422 -342.466769)
			(xy 319.965574 -342.466769) (xy 319.957813 -342.520749) (xy 319.942449 -342.573077) (xy 319.919794 -342.622685)
			(xy 319.890311 -342.668565) (xy 319.854598 -342.709781) (xy 319.813384 -342.745496) (xy 319.767506 -342.774983)
			(xy 319.717899 -342.79764) (xy 319.665573 -342.813008) (xy 319.611592 -342.820772) (xy 319.584324 -342.82126)
			(xy 318.720724 -342.82126) (xy 318.693452 -342.820802) (xy 318.639462 -342.813043) (xy 318.587126 -342.797678)
			(xy 318.53751 -342.775022) (xy 318.491623 -342.745535) (xy 318.4504 -342.709817) (xy 318.414679 -342.668596)
			(xy 318.385189 -342.622711) (xy 318.36253 -342.573096) (xy 318.347162 -342.520761) (xy 318.3394 -342.466772)
			(xy 316.856696 -342.466772) (xy 316.848933 -342.520762) (xy 316.833565 -342.573098) (xy 316.810905 -342.622713)
			(xy 316.781414 -342.668598) (xy 316.745693 -342.709819) (xy 316.704469 -342.745536) (xy 316.658581 -342.775023)
			(xy 316.608964 -342.797678) (xy 316.556627 -342.813041) (xy 316.502637 -342.820799) (xy 316.475364 -342.82126)
			(xy 315.611764 -342.82126) (xy 315.584496 -342.820775) (xy 315.530516 -342.813009) (xy 315.478191 -342.797641)
			(xy 315.428585 -342.774982) (xy 315.382708 -342.745495) (xy 315.341495 -342.70978) (xy 315.305783 -342.668563)
			(xy 315.2763 -342.622684) (xy 315.253647 -342.573076) (xy 315.238283 -342.520749) (xy 315.230522 -342.466768)
			(xy 313.747674 -342.466768) (xy 313.747674 -342.466769) (xy 313.739912 -342.520752) (xy 313.724547 -342.573081)
			(xy 313.701891 -342.622691) (xy 313.672406 -342.668571) (xy 313.636691 -342.709788) (xy 313.595474 -342.745503)
			(xy 313.549594 -342.774989) (xy 313.499985 -342.797646) (xy 313.447656 -342.813011) (xy 313.393673 -342.820773)
			(xy 313.366404 -342.82126) (xy 312.502804 -342.82126) (xy 312.475533 -342.820801) (xy 312.421545 -342.813039)
			(xy 312.369212 -342.797673) (xy 312.319598 -342.775016) (xy 312.273713 -342.745528) (xy 312.232493 -342.70981)
			(xy 312.196774 -342.66859) (xy 312.167286 -342.622706) (xy 312.144628 -342.573092) (xy 312.129262 -342.520759)
			(xy 312.1215 -342.466771) (xy 300.231574 -342.466771) (xy 300.223812 -342.520752) (xy 300.208447 -342.573081)
			(xy 300.185791 -342.622691) (xy 300.156305 -342.668572) (xy 300.120591 -342.709789) (xy 300.079373 -342.745504)
			(xy 300.033493 -342.77499) (xy 299.983883 -342.797646) (xy 299.931554 -342.813012) (xy 299.877571 -342.820773)
			(xy 299.850302 -342.82126) (xy 298.986702 -342.82126) (xy 298.959431 -342.820801) (xy 298.905443 -342.813039)
			(xy 298.85311 -342.797673) (xy 298.803497 -342.775015) (xy 298.757612 -342.745527) (xy 298.716392 -342.70981)
			(xy 298.680674 -342.668589) (xy 298.651186 -342.622705) (xy 298.628528 -342.573092) (xy 298.613162 -342.520759)
			(xy 298.605399 -342.466771) (xy 297.122573 -342.466771) (xy 297.114813 -342.520747) (xy 297.09945 -342.573073)
			(xy 297.076797 -342.62268) (xy 297.047315 -342.668559) (xy 297.011605 -342.709775) (xy 296.970392 -342.74549)
			(xy 296.924517 -342.774977) (xy 296.874912 -342.797635) (xy 296.822588 -342.813004) (xy 296.768609 -342.820771)
			(xy 296.741342 -342.82126) (xy 295.877742 -342.82126) (xy 295.850469 -342.820803) (xy 295.796477 -342.813046)
			(xy 295.744139 -342.797683) (xy 295.694521 -342.775028) (xy 295.648631 -342.745541) (xy 295.607406 -342.709824)
			(xy 295.571684 -342.668602) (xy 295.542192 -342.622716) (xy 295.519531 -342.5731) (xy 295.504163 -342.520764)
			(xy 295.4964 -342.466773) (xy 294.013696 -342.466773) (xy 294.005934 -342.52076) (xy 293.990567 -342.573094)
			(xy 293.967908 -342.622708) (xy 293.938419 -342.668592) (xy 293.9027 -342.709812) (xy 293.861478 -342.74553)
			(xy 293.815592 -342.775017) (xy 293.765977 -342.797673) (xy 293.713642 -342.813038) (xy 293.659654 -342.820798)
			(xy 293.632382 -342.82126) (xy 292.768782 -342.82126) (xy 292.741513 -342.820776) (xy 292.687531 -342.813013)
			(xy 292.635204 -342.797646) (xy 292.585596 -342.774988) (xy 292.539717 -342.745502) (xy 292.498501 -342.709786)
			(xy 292.462787 -342.668569) (xy 292.433303 -342.622689) (xy 292.410648 -342.573079) (xy 292.395284 -342.520751)
			(xy 292.387522 -342.466769) (xy 290.904674 -342.466769) (xy 290.896913 -342.52075) (xy 290.881548 -342.573077)
			(xy 290.858894 -342.622686) (xy 290.82941 -342.668565) (xy 290.793698 -342.709782) (xy 290.752483 -342.745497)
			(xy 290.706605 -342.774983) (xy 290.656998 -342.797641) (xy 290.604671 -342.813008) (xy 290.55069 -342.820772)
			(xy 290.523422 -342.82126) (xy 289.659822 -342.82126) (xy 289.63255 -342.820802) (xy 289.57856 -342.813042)
			(xy 289.526225 -342.797678) (xy 289.476609 -342.775021) (xy 289.430722 -342.745534) (xy 289.389499 -342.709817)
			(xy 289.353779 -342.668596) (xy 289.324289 -342.622711) (xy 289.30163 -342.573096) (xy 289.286262 -342.520761)
			(xy 289.2785 -342.466772) (xy 287.795796 -342.466772) (xy 287.795796 -342.466773) (xy 287.788033 -342.520763)
			(xy 287.772665 -342.573098) (xy 287.750005 -342.622713) (xy 287.720514 -342.668599) (xy 287.684793 -342.70982)
			(xy 287.643568 -342.745537) (xy 287.59768 -342.775023) (xy 287.548062 -342.797679) (xy 287.495725 -342.813041)
			(xy 287.441735 -342.820799) (xy 287.414462 -342.82126) (xy 286.550862 -342.82126) (xy 286.523594 -342.820775)
			(xy 286.469614 -342.813009) (xy 286.417289 -342.79764) (xy 286.367684 -342.774982) (xy 286.321807 -342.745495)
			(xy 286.280594 -342.709779) (xy 286.244883 -342.668562) (xy 286.2154 -342.622683) (xy 286.192747 -342.573075)
			(xy 286.177383 -342.520748) (xy 286.169622 -342.466768) (xy 284.686774 -342.466768) (xy 284.686774 -342.466769)
			(xy 284.679012 -342.520752) (xy 284.663647 -342.573081) (xy 284.640991 -342.622691) (xy 284.611505 -342.668572)
			(xy 284.575791 -342.709789) (xy 284.534573 -342.745504) (xy 284.488693 -342.77499) (xy 284.439083 -342.797646)
			(xy 284.386754 -342.813012) (xy 284.332771 -342.820773) (xy 284.305502 -342.82126) (xy 283.441902 -342.82126)
			(xy 283.414631 -342.820801) (xy 283.360643 -342.813039) (xy 283.30831 -342.797673) (xy 283.258697 -342.775015)
			(xy 283.212812 -342.745527) (xy 283.171592 -342.70981) (xy 283.135874 -342.668589) (xy 283.106386 -342.622705)
			(xy 283.083728 -342.573092) (xy 283.068362 -342.520759) (xy 283.060599 -342.466771) (xy 281.577773 -342.466771)
			(xy 281.570013 -342.520747) (xy 281.55465 -342.573073) (xy 281.531997 -342.62268) (xy 281.502515 -342.668559)
			(xy 281.466805 -342.709775) (xy 281.425592 -342.74549) (xy 281.379717 -342.774977) (xy 281.330112 -342.797635)
			(xy 281.277788 -342.813004) (xy 281.223809 -342.820771) (xy 281.196542 -342.82126) (xy 280.332942 -342.82126)
			(xy 280.305669 -342.820803) (xy 280.251677 -342.813046) (xy 280.199339 -342.797683) (xy 280.149721 -342.775028)
			(xy 280.103831 -342.745541) (xy 280.062606 -342.709824) (xy 280.026884 -342.668602) (xy 279.997392 -342.622716)
			(xy 279.974731 -342.5731) (xy 279.959363 -342.520764) (xy 279.9516 -342.466773) (xy 278.468896 -342.466773)
			(xy 278.461134 -342.52076) (xy 278.445767 -342.573094) (xy 278.423108 -342.622708) (xy 278.393619 -342.668592)
			(xy 278.3579 -342.709812) (xy 278.316678 -342.74553) (xy 278.270792 -342.775017) (xy 278.221177 -342.797673)
			(xy 278.168842 -342.813038) (xy 278.114854 -342.820798) (xy 278.087582 -342.82126) (xy 277.223982 -342.82126)
			(xy 277.196713 -342.820776) (xy 277.142731 -342.813013) (xy 277.090404 -342.797646) (xy 277.040796 -342.774988)
			(xy 276.994917 -342.745502) (xy 276.953701 -342.709786) (xy 276.917987 -342.668569) (xy 276.888503 -342.622689)
			(xy 276.865848 -342.573079) (xy 276.850484 -342.520751) (xy 276.842722 -342.466769) (xy 275.359874 -342.466769)
			(xy 275.352113 -342.52075) (xy 275.336748 -342.573077) (xy 275.314094 -342.622686) (xy 275.28461 -342.668565)
			(xy 275.248898 -342.709782) (xy 275.207683 -342.745497) (xy 275.161805 -342.774983) (xy 275.112198 -342.797641)
			(xy 275.059871 -342.813008) (xy 275.00589 -342.820772) (xy 274.978622 -342.82126) (xy 274.115022 -342.82126)
			(xy 274.08775 -342.820802) (xy 274.03376 -342.813042) (xy 273.981425 -342.797678) (xy 273.931809 -342.775021)
			(xy 273.885922 -342.745534) (xy 273.844699 -342.709817) (xy 273.808979 -342.668596) (xy 273.779489 -342.622711)
			(xy 273.75683 -342.573096) (xy 273.741462 -342.520761) (xy 273.7337 -342.466772) (xy 272.250996 -342.466772)
			(xy 272.250996 -342.466773) (xy 272.243233 -342.520763) (xy 272.227865 -342.573098) (xy 272.205205 -342.622713)
			(xy 272.175714 -342.668599) (xy 272.139993 -342.70982) (xy 272.098768 -342.745537) (xy 272.05288 -342.775023)
			(xy 272.003262 -342.797679) (xy 271.950925 -342.813041) (xy 271.896935 -342.820799) (xy 271.869662 -342.82126)
			(xy 271.006062 -342.82126) (xy 270.978794 -342.820775) (xy 270.924814 -342.813009) (xy 270.872489 -342.79764)
			(xy 270.822884 -342.774982) (xy 270.777007 -342.745495) (xy 270.735794 -342.709779) (xy 270.700083 -342.668562)
			(xy 270.6706 -342.622683) (xy 270.647947 -342.573075) (xy 270.632583 -342.520748) (xy 270.624822 -342.466768)
			(xy 269.141974 -342.466768) (xy 269.141974 -342.466769) (xy 269.134212 -342.520752) (xy 269.118847 -342.573081)
			(xy 269.096191 -342.622691) (xy 269.066705 -342.668572) (xy 269.030991 -342.709789) (xy 268.989773 -342.745504)
			(xy 268.943893 -342.77499) (xy 268.894283 -342.797646) (xy 268.841954 -342.813012) (xy 268.787971 -342.820773)
			(xy 268.760702 -342.82126) (xy 267.897102 -342.82126) (xy 267.869831 -342.820801) (xy 267.815843 -342.813039)
			(xy 267.76351 -342.797673) (xy 267.713897 -342.775015) (xy 267.668012 -342.745527) (xy 267.626792 -342.70981)
			(xy 267.591074 -342.668589) (xy 267.561586 -342.622705) (xy 267.538928 -342.573092) (xy 267.523562 -342.520759)
			(xy 267.515799 -342.466771) (xy 256.581015 -342.466771) (xy 256.573351 -342.471196) (xy 256.517947 -342.494145)
			(xy 256.460022 -342.509666) (xy 256.400566 -342.517494) (xy 256.340598 -342.517494) (xy 256.281142 -342.509666)
			(xy 256.223217 -342.494145) (xy 256.167813 -342.471196) (xy 256.115879 -342.441212) (xy 256.068303 -342.404706)
			(xy 256.025898 -342.362301) (xy 255.989392 -342.314725) (xy 255.959408 -342.262791) (xy 255.936459 -342.207387)
			(xy 255.920938 -342.149462) (xy 255.91311 -342.090006) (xy 255.91262 -342.060022) (xy 197.28821 -342.060022)
			(xy 197.329534 -342.06596) (xy 197.38187 -342.081324) (xy 197.431486 -342.10398) (xy 197.477373 -342.133467)
			(xy 197.518596 -342.169184) (xy 197.554316 -342.210405) (xy 197.583807 -342.256289) (xy 197.606466 -342.305904)
			(xy 197.621834 -342.358239) (xy 197.629596 -342.412228) (xy 197.629596 -342.466772) (xy 197.621834 -342.520761)
			(xy 197.606466 -342.573096) (xy 197.583807 -342.622711) (xy 197.554316 -342.668595) (xy 197.518596 -342.709816)
			(xy 197.477373 -342.745533) (xy 197.431486 -342.77502) (xy 197.38187 -342.797676) (xy 197.329534 -342.81304)
			(xy 197.275544 -342.820798) (xy 197.248272 -342.82126) (xy 196.384672 -342.82126) (xy 196.357404 -342.820776)
			(xy 196.303423 -342.813011) (xy 196.251096 -342.797643) (xy 196.20149 -342.774985) (xy 196.155612 -342.745498)
			(xy 196.114397 -342.709783) (xy 196.078685 -342.668566) (xy 196.049202 -342.622686) (xy 196.026547 -342.573077)
			(xy 196.011183 -342.52075) (xy 196.003422 -342.466768) (xy 194.520574 -342.466768) (xy 194.520574 -342.466769)
			(xy 194.512812 -342.520751) (xy 194.497448 -342.573079) (xy 194.474792 -342.622688) (xy 194.445308 -342.668568)
			(xy 194.409594 -342.709786) (xy 194.368378 -342.745501) (xy 194.322499 -342.774987) (xy 194.272891 -342.797643)
			(xy 194.220563 -342.81301) (xy 194.166581 -342.820773) (xy 194.139312 -342.82126) (xy 193.275712 -342.82126)
			(xy 193.24844 -342.820801) (xy 193.194452 -342.813041) (xy 193.142117 -342.797675) (xy 193.092503 -342.775018)
			(xy 193.046617 -342.745531) (xy 193.005395 -342.709813) (xy 192.969676 -342.668593) (xy 192.940188 -342.622708)
			(xy 192.917529 -342.573094) (xy 192.902162 -342.52076) (xy 192.8944 -342.466772) (xy 191.411696 -342.466772)
			(xy 191.411696 -342.466773) (xy 191.403933 -342.520764) (xy 191.388564 -342.5731) (xy 191.365903 -342.622716)
			(xy 191.336412 -342.668602) (xy 191.300689 -342.709823) (xy 191.259463 -342.74554) (xy 191.213574 -342.775026)
			(xy 191.163955 -342.797681) (xy 191.111617 -342.813043) (xy 191.057625 -342.8208) (xy 191.030352 -342.82126)
			(xy 190.166752 -342.82126) (xy 190.139485 -342.820774) (xy 190.085506 -342.813007) (xy 190.033182 -342.797637)
			(xy 189.983578 -342.774978) (xy 189.937702 -342.745491) (xy 189.89649 -342.709776) (xy 189.86078 -342.668559)
			(xy 189.831299 -342.62268) (xy 189.808646 -342.573073) (xy 189.793283 -342.520747) (xy 189.785522 -342.466767)
			(xy 188.302696 -342.466767) (xy 188.302696 -342.466771) (xy 188.294934 -342.520759) (xy 188.279568 -342.573092)
			(xy 188.25691 -342.622705) (xy 188.227421 -342.668589) (xy 188.191703 -342.709809) (xy 188.150482 -342.745526)
			(xy 188.104598 -342.775013) (xy 188.054984 -342.79767) (xy 188.002651 -342.813036) (xy 187.948663 -342.820797)
			(xy 187.921392 -342.82126) (xy 187.057792 -342.82126) (xy 187.030523 -342.820777) (xy 186.97654 -342.813014)
			(xy 186.924211 -342.797648) (xy 186.874602 -342.774991) (xy 186.828721 -342.745505) (xy 186.787505 -342.70979)
			(xy 186.75179 -342.668572) (xy 186.722305 -342.622691) (xy 186.699649 -342.573082) (xy 186.684284 -342.520752)
			(xy 186.676522 -342.466769) (xy 185.193674 -342.466769) (xy 185.185913 -342.520748) (xy 185.170549 -342.573075)
			(xy 185.147895 -342.622683) (xy 185.118413 -342.668562) (xy 185.082701 -342.709778) (xy 185.041488 -342.745494)
			(xy 184.995611 -342.77498) (xy 184.946005 -342.797638) (xy 184.89368 -342.813006) (xy 184.8397 -342.820771)
			(xy 184.812432 -342.82126) (xy 183.948832 -342.82126) (xy 183.921559 -342.820803) (xy 183.867569 -342.813044)
			(xy 183.815232 -342.797681) (xy 183.765615 -342.775025) (xy 183.719727 -342.745538) (xy 183.678502 -342.70982)
			(xy 183.642781 -342.668599) (xy 183.613291 -342.622714) (xy 183.590631 -342.573098) (xy 183.575263 -342.520763)
			(xy 183.5675 -342.466773) (xy 182.084796 -342.466773) (xy 182.077034 -342.520761) (xy 182.061666 -342.573096)
			(xy 182.039007 -342.622711) (xy 182.009516 -342.668595) (xy 181.973796 -342.709816) (xy 181.932573 -342.745533)
			(xy 181.886686 -342.77502) (xy 181.83707 -342.797676) (xy 181.784734 -342.81304) (xy 181.730744 -342.820798)
			(xy 181.703472 -342.82126) (xy 180.839872 -342.82126) (xy 180.812604 -342.820776) (xy 180.758623 -342.813011)
			(xy 180.706296 -342.797643) (xy 180.65669 -342.774985) (xy 180.610812 -342.745498) (xy 180.569597 -342.709783)
			(xy 180.533885 -342.668566) (xy 180.504402 -342.622686) (xy 180.481747 -342.573077) (xy 180.466383 -342.52075)
			(xy 180.458622 -342.466768) (xy 178.975774 -342.466768) (xy 178.975774 -342.466769) (xy 178.968012 -342.520751)
			(xy 178.952648 -342.573079) (xy 178.929992 -342.622688) (xy 178.900508 -342.668568) (xy 178.864794 -342.709786)
			(xy 178.823578 -342.745501) (xy 178.777699 -342.774987) (xy 178.728091 -342.797643) (xy 178.675763 -342.81301)
			(xy 178.621781 -342.820773) (xy 178.594512 -342.82126) (xy 177.730912 -342.82126) (xy 177.70364 -342.820801)
			(xy 177.649652 -342.813041) (xy 177.597317 -342.797675) (xy 177.547703 -342.775018) (xy 177.501817 -342.745531)
			(xy 177.460595 -342.709813) (xy 177.424876 -342.668593) (xy 177.395388 -342.622708) (xy 177.372729 -342.573094)
			(xy 177.357362 -342.52076) (xy 177.3496 -342.466772) (xy 175.866896 -342.466772) (xy 175.866896 -342.466773)
			(xy 175.859133 -342.520764) (xy 175.843764 -342.5731) (xy 175.821103 -342.622716) (xy 175.791612 -342.668602)
			(xy 175.755889 -342.709823) (xy 175.714663 -342.74554) (xy 175.668774 -342.775026) (xy 175.619155 -342.797681)
			(xy 175.566817 -342.813043) (xy 175.512825 -342.8208) (xy 175.485552 -342.82126) (xy 174.621952 -342.82126)
			(xy 174.594685 -342.820774) (xy 174.540706 -342.813007) (xy 174.488382 -342.797637) (xy 174.438778 -342.774978)
			(xy 174.392902 -342.745491) (xy 174.35169 -342.709776) (xy 174.31598 -342.668559) (xy 174.286499 -342.62268)
			(xy 174.263846 -342.573073) (xy 174.248483 -342.520747) (xy 174.240722 -342.466767) (xy 172.757896 -342.466767)
			(xy 172.757896 -342.466771) (xy 172.750134 -342.520759) (xy 172.734768 -342.573092) (xy 172.71211 -342.622705)
			(xy 172.682621 -342.668589) (xy 172.646903 -342.709809) (xy 172.605682 -342.745526) (xy 172.559798 -342.775013)
			(xy 172.510184 -342.79767) (xy 172.457851 -342.813036) (xy 172.403863 -342.820797) (xy 172.376592 -342.82126)
			(xy 171.512992 -342.82126) (xy 171.485723 -342.820777) (xy 171.43174 -342.813014) (xy 171.379411 -342.797648)
			(xy 171.329802 -342.774991) (xy 171.283921 -342.745505) (xy 171.242705 -342.70979) (xy 171.20699 -342.668572)
			(xy 171.177505 -342.622691) (xy 171.154849 -342.573082) (xy 171.139484 -342.520752) (xy 171.131722 -342.466769)
			(xy 169.648874 -342.466769) (xy 169.641113 -342.520748) (xy 169.625749 -342.573075) (xy 169.603095 -342.622683)
			(xy 169.573613 -342.668562) (xy 169.537901 -342.709778) (xy 169.496688 -342.745494) (xy 169.450811 -342.77498)
			(xy 169.401205 -342.797638) (xy 169.34888 -342.813006) (xy 169.2949 -342.820771) (xy 169.267632 -342.82126)
			(xy 168.404032 -342.82126) (xy 168.376759 -342.820803) (xy 168.322769 -342.813044) (xy 168.270432 -342.797681)
			(xy 168.220815 -342.775025) (xy 168.174927 -342.745538) (xy 168.133702 -342.70982) (xy 168.097981 -342.668599)
			(xy 168.068491 -342.622714) (xy 168.045831 -342.573098) (xy 168.030463 -342.520763) (xy 168.0227 -342.466773)
			(xy 166.539996 -342.466773) (xy 166.532234 -342.520761) (xy 166.516866 -342.573096) (xy 166.494207 -342.622711)
			(xy 166.464716 -342.668595) (xy 166.428996 -342.709816) (xy 166.387773 -342.745533) (xy 166.341886 -342.77502)
			(xy 166.29227 -342.797676) (xy 166.239934 -342.81304) (xy 166.185944 -342.820798) (xy 166.158672 -342.82126)
			(xy 165.295072 -342.82126) (xy 165.267804 -342.820776) (xy 165.213823 -342.813011) (xy 165.161496 -342.797643)
			(xy 165.11189 -342.774985) (xy 165.066012 -342.745498) (xy 165.024797 -342.709783) (xy 164.989085 -342.668566)
			(xy 164.959602 -342.622686) (xy 164.936947 -342.573077) (xy 164.921583 -342.52075) (xy 164.913822 -342.466768)
			(xy 144.196574 -342.466768) (xy 144.196574 -342.466769) (xy 144.188812 -342.520751) (xy 144.173447 -342.57308)
			(xy 144.150792 -342.622689) (xy 144.121307 -342.66857) (xy 144.085593 -342.709787) (xy 144.044376 -342.745502)
			(xy 143.998497 -342.774988) (xy 143.948888 -342.797645) (xy 143.896559 -342.81301) (xy 143.842577 -342.820773)
			(xy 143.815308 -342.82126) (xy 142.951708 -342.82126) (xy 142.924436 -342.820801) (xy 142.870448 -342.81304)
			(xy 142.818115 -342.797674) (xy 142.7685 -342.775017) (xy 142.722615 -342.745529) (xy 142.681394 -342.709812)
			(xy 142.645675 -342.668591) (xy 142.616187 -342.622707) (xy 142.593529 -342.573093) (xy 142.578162 -342.520759)
			(xy 142.5704 -342.466772) (xy 141.087573 -342.466772) (xy 141.079813 -342.520746) (xy 141.064451 -342.573072)
			(xy 141.041798 -342.622678) (xy 141.012317 -342.668557) (xy 140.976607 -342.709773) (xy 140.935395 -342.745488)
			(xy 140.88952 -342.774975) (xy 140.839917 -342.797634) (xy 140.787593 -342.813003) (xy 140.733615 -342.82077)
			(xy 140.706348 -342.82126) (xy 139.842748 -342.82126) (xy 139.815475 -342.820804) (xy 139.761482 -342.813047)
			(xy 139.709144 -342.797685) (xy 139.659524 -342.77503) (xy 139.613634 -342.745544) (xy 139.572408 -342.709826)
			(xy 139.536685 -342.668604) (xy 139.507193 -342.622718) (xy 139.484532 -342.573101) (xy 139.469163 -342.520765)
			(xy 139.4614 -342.466773) (xy 137.978696 -342.466773) (xy 137.970934 -342.520759) (xy 137.955567 -342.573092)
			(xy 137.932909 -342.622706) (xy 137.90342 -342.66859) (xy 137.867702 -342.70981) (xy 137.82648 -342.745528)
			(xy 137.780596 -342.775015) (xy 137.730981 -342.797671) (xy 137.678647 -342.813037) (xy 137.624659 -342.820797)
			(xy 137.597388 -342.82126) (xy 136.733788 -342.82126) (xy 136.706519 -342.820777) (xy 136.652536 -342.813014)
			(xy 136.600208 -342.797647) (xy 136.550599 -342.77499) (xy 136.50472 -342.745504) (xy 136.463503 -342.709788)
			(xy 136.427789 -342.668571) (xy 136.398304 -342.62269) (xy 136.375649 -342.573081) (xy 136.360284 -342.520752)
			(xy 136.352522 -342.466769) (xy 134.869674 -342.466769) (xy 134.861913 -342.520749) (xy 134.846549 -342.573076)
			(xy 134.823895 -342.622684) (xy 134.794412 -342.668563) (xy 134.7587 -342.70978) (xy 134.717486 -342.745495)
			(xy 134.671609 -342.774981) (xy 134.622002 -342.797639) (xy 134.569676 -342.813007) (xy 134.515696 -342.820772)
			(xy 134.488428 -342.82126) (xy 133.624828 -342.82126) (xy 133.597556 -342.820802) (xy 133.543565 -342.813043)
			(xy 133.491229 -342.79768) (xy 133.441612 -342.775023) (xy 133.395725 -342.745536) (xy 133.354501 -342.709819)
			(xy 133.31878 -342.668598) (xy 133.28929 -342.622712) (xy 133.26663 -342.573097) (xy 133.251262 -342.520762)
			(xy 133.2435 -342.466772) (xy 131.760796 -342.466772) (xy 131.753033 -342.520762) (xy 131.737666 -342.573097)
			(xy 131.715006 -342.622712) (xy 131.685515 -342.668597) (xy 131.649795 -342.709817) (xy 131.608571 -342.745535)
			(xy 131.562684 -342.775021) (xy 131.513067 -342.797677) (xy 131.46073 -342.81304) (xy 131.40674 -342.820799)
			(xy 131.379468 -342.82126) (xy 130.515868 -342.82126) (xy 130.4886 -342.820775) (xy 130.43462 -342.81301)
			(xy 130.382294 -342.797642) (xy 130.332687 -342.774984) (xy 130.28681 -342.745497) (xy 130.245596 -342.709781)
			(xy 130.209884 -342.668564) (xy 130.180401 -342.622685) (xy 130.157747 -342.573076) (xy 130.142383 -342.520749)
			(xy 130.134622 -342.466768) (xy 128.651774 -342.466768) (xy 128.651774 -342.466769) (xy 128.644012 -342.520751)
			(xy 128.628647 -342.57308) (xy 128.605992 -342.622689) (xy 128.576507 -342.66857) (xy 128.540793 -342.709787)
			(xy 128.499576 -342.745502) (xy 128.453697 -342.774988) (xy 128.404088 -342.797645) (xy 128.351759 -342.81301)
			(xy 128.297777 -342.820773) (xy 128.270508 -342.82126) (xy 127.406908 -342.82126) (xy 127.379636 -342.820801)
			(xy 127.325648 -342.81304) (xy 127.273315 -342.797674) (xy 127.2237 -342.775017) (xy 127.177815 -342.745529)
			(xy 127.136594 -342.709812) (xy 127.100875 -342.668591) (xy 127.071387 -342.622707) (xy 127.048729 -342.573093)
			(xy 127.033362 -342.520759) (xy 127.0256 -342.466772) (xy 125.542773 -342.466772) (xy 125.535013 -342.520746)
			(xy 125.519651 -342.573072) (xy 125.496998 -342.622678) (xy 125.467517 -342.668557) (xy 125.431807 -342.709773)
			(xy 125.390595 -342.745488) (xy 125.34472 -342.774975) (xy 125.295117 -342.797634) (xy 125.242793 -342.813003)
			(xy 125.188815 -342.82077) (xy 125.161548 -342.82126) (xy 124.297948 -342.82126) (xy 124.270675 -342.820804)
			(xy 124.216682 -342.813047) (xy 124.164344 -342.797685) (xy 124.114724 -342.77503) (xy 124.068834 -342.745544)
			(xy 124.027608 -342.709826) (xy 123.991885 -342.668604) (xy 123.962393 -342.622718) (xy 123.939732 -342.573101)
			(xy 123.924363 -342.520765) (xy 123.9166 -342.466773) (xy 122.433896 -342.466773) (xy 122.426134 -342.520759)
			(xy 122.410767 -342.573092) (xy 122.388109 -342.622706) (xy 122.35862 -342.66859) (xy 122.322902 -342.70981)
			(xy 122.28168 -342.745528) (xy 122.235796 -342.775015) (xy 122.186181 -342.797671) (xy 122.133847 -342.813037)
			(xy 122.079859 -342.820797) (xy 122.052588 -342.82126) (xy 121.188988 -342.82126) (xy 121.161719 -342.820777)
			(xy 121.107736 -342.813014) (xy 121.055408 -342.797647) (xy 121.005799 -342.77499) (xy 120.95992 -342.745504)
			(xy 120.918703 -342.709788) (xy 120.882989 -342.668571) (xy 120.853504 -342.62269) (xy 120.830849 -342.573081)
			(xy 120.815484 -342.520752) (xy 120.807722 -342.466769) (xy 119.324874 -342.466769) (xy 119.317113 -342.520749)
			(xy 119.301749 -342.573076) (xy 119.279095 -342.622684) (xy 119.249612 -342.668563) (xy 119.2139 -342.70978)
			(xy 119.172686 -342.745495) (xy 119.126809 -342.774981) (xy 119.077202 -342.797639) (xy 119.024876 -342.813007)
			(xy 118.970896 -342.820772) (xy 118.943628 -342.82126) (xy 118.080028 -342.82126) (xy 118.052756 -342.820802)
			(xy 117.998765 -342.813043) (xy 117.946429 -342.79768) (xy 117.896812 -342.775023) (xy 117.850925 -342.745536)
			(xy 117.809701 -342.709819) (xy 117.77398 -342.668598) (xy 117.74449 -342.622712) (xy 117.72183 -342.573097)
			(xy 117.706462 -342.520762) (xy 117.6987 -342.466772) (xy 116.215996 -342.466772) (xy 116.208233 -342.520762)
			(xy 116.192866 -342.573097) (xy 116.170206 -342.622712) (xy 116.140715 -342.668597) (xy 116.104995 -342.709817)
			(xy 116.063771 -342.745535) (xy 116.017884 -342.775021) (xy 115.968267 -342.797677) (xy 115.91593 -342.81304)
			(xy 115.86194 -342.820799) (xy 115.834668 -342.82126) (xy 114.971068 -342.82126) (xy 114.9438 -342.820775)
			(xy 114.88982 -342.81301) (xy 114.837494 -342.797642) (xy 114.787887 -342.774984) (xy 114.74201 -342.745497)
			(xy 114.700796 -342.709781) (xy 114.665084 -342.668564) (xy 114.635601 -342.622685) (xy 114.612947 -342.573076)
			(xy 114.597583 -342.520749) (xy 114.589822 -342.466768) (xy 113.106974 -342.466768) (xy 113.106974 -342.466769)
			(xy 113.099212 -342.520751) (xy 113.083847 -342.57308) (xy 113.061192 -342.622689) (xy 113.031707 -342.66857)
			(xy 112.995993 -342.709787) (xy 112.954776 -342.745502) (xy 112.908897 -342.774988) (xy 112.859288 -342.797645)
			(xy 112.806959 -342.81301) (xy 112.752977 -342.820773) (xy 112.725708 -342.82126) (xy 111.862108 -342.82126)
			(xy 111.834836 -342.820801) (xy 111.780848 -342.81304) (xy 111.728515 -342.797674) (xy 111.6789 -342.775017)
			(xy 111.633015 -342.745529) (xy 111.591794 -342.709812) (xy 111.556075 -342.668591) (xy 111.526587 -342.622707)
			(xy 111.503929 -342.573093) (xy 111.488562 -342.520759) (xy 111.4808 -342.466772) (xy 104.085479 -342.466772)
			(xy 104.10629 -342.517011) (xy 104.121803 -342.574906) (xy 104.129627 -342.634331) (xy 104.129627 -342.694269)
			(xy 104.121803 -342.753694) (xy 104.10629 -342.811589) (xy 104.083352 -342.866964) (xy 104.053383 -342.918871)
			(xy 104.016895 -342.966422) (xy 103.974512 -343.008804) (xy 103.926959 -343.045291) (xy 103.875051 -343.075259)
			(xy 103.819676 -343.098195) (xy 103.76178 -343.113706) (xy 103.702355 -343.121528) (xy 103.672386 -343.121996)
			(xy 102.808786 -343.121996) (xy 102.778818 -343.121529) (xy 102.719395 -343.113704) (xy 102.661502 -343.09819)
			(xy 102.60613 -343.075253) (xy 102.554224 -343.045284) (xy 102.506675 -343.008796) (xy 102.464294 -342.966415)
			(xy 102.427809 -342.918864) (xy 102.397841 -342.866958) (xy 102.374905 -342.811584) (xy 102.359393 -342.753691)
			(xy 102.35157 -342.694268) (xy 93.60914 -342.694268) (xy 93.595705 -342.709775) (xy 93.554492 -342.74549)
			(xy 93.508617 -342.774977) (xy 93.459012 -342.797635) (xy 93.406688 -342.813004) (xy 93.352709 -342.820771)
			(xy 93.325442 -342.82126) (xy 92.461842 -342.82126) (xy 92.434569 -342.820803) (xy 92.380577 -342.813046)
			(xy 92.328239 -342.797683) (xy 92.278621 -342.775028) (xy 92.232731 -342.745541) (xy 92.191506 -342.709824)
			(xy 92.155784 -342.668602) (xy 92.126292 -342.622716) (xy 92.103631 -342.5731) (xy 92.088263 -342.520764)
			(xy 92.0805 -342.466773) (xy 90.597796 -342.466773) (xy 90.590034 -342.52076) (xy 90.574667 -342.573094)
			(xy 90.552008 -342.622708) (xy 90.522519 -342.668592) (xy 90.4868 -342.709812) (xy 90.445578 -342.74553)
			(xy 90.399692 -342.775017) (xy 90.350077 -342.797673) (xy 90.297742 -342.813038) (xy 90.243754 -342.820798)
			(xy 90.216482 -342.82126) (xy 89.352882 -342.82126) (xy 89.325613 -342.820776) (xy 89.271631 -342.813013)
			(xy 89.219304 -342.797646) (xy 89.169696 -342.774988) (xy 89.123817 -342.745502) (xy 89.082601 -342.709786)
			(xy 89.046887 -342.668569) (xy 89.017403 -342.622689) (xy 88.994748 -342.573079) (xy 88.979384 -342.520751)
			(xy 88.971622 -342.466769) (xy 87.488774 -342.466769) (xy 87.481013 -342.52075) (xy 87.465648 -342.573077)
			(xy 87.442994 -342.622686) (xy 87.41351 -342.668565) (xy 87.377798 -342.709782) (xy 87.336583 -342.745497)
			(xy 87.290705 -342.774983) (xy 87.241098 -342.797641) (xy 87.188771 -342.813008) (xy 87.13479 -342.820772)
			(xy 87.107522 -342.82126) (xy 86.243922 -342.82126) (xy 86.21665 -342.820802) (xy 86.16266 -342.813042)
			(xy 86.110325 -342.797678) (xy 86.060709 -342.775021) (xy 86.014822 -342.745534) (xy 85.973599 -342.709817)
			(xy 85.937879 -342.668596) (xy 85.908389 -342.622711) (xy 85.88573 -342.573096) (xy 85.870362 -342.520761)
			(xy 85.8626 -342.466772) (xy 84.379896 -342.466772) (xy 84.379896 -342.466773) (xy 84.372133 -342.520763)
			(xy 84.356765 -342.573098) (xy 84.334105 -342.622713) (xy 84.304614 -342.668599) (xy 84.268893 -342.70982)
			(xy 84.227668 -342.745537) (xy 84.18178 -342.775023) (xy 84.132162 -342.797679) (xy 84.079825 -342.813041)
			(xy 84.025835 -342.820799) (xy 83.998562 -342.82126) (xy 83.134962 -342.82126) (xy 83.107694 -342.820775)
			(xy 83.053714 -342.813009) (xy 83.001389 -342.79764) (xy 82.951784 -342.774982) (xy 82.905907 -342.745495)
			(xy 82.864694 -342.709779) (xy 82.828983 -342.668562) (xy 82.7995 -342.622683) (xy 82.776847 -342.573075)
			(xy 82.761483 -342.520748) (xy 82.753722 -342.466768) (xy 81.270874 -342.466768) (xy 81.270874 -342.466769)
			(xy 81.263112 -342.520752) (xy 81.247747 -342.573081) (xy 81.225091 -342.622691) (xy 81.195605 -342.668572)
			(xy 81.159891 -342.709789) (xy 81.118673 -342.745504) (xy 81.072793 -342.77499) (xy 81.023183 -342.797646)
			(xy 80.970854 -342.813012) (xy 80.916871 -342.820773) (xy 80.889602 -342.82126) (xy 80.026002 -342.82126)
			(xy 79.998731 -342.820801) (xy 79.944743 -342.813039) (xy 79.89241 -342.797673) (xy 79.842797 -342.775015)
			(xy 79.796912 -342.745527) (xy 79.755692 -342.70981) (xy 79.719974 -342.668589) (xy 79.690486 -342.622705)
			(xy 79.667828 -342.573092) (xy 79.652462 -342.520759) (xy 79.644699 -342.466771) (xy 78.161873 -342.466771)
			(xy 78.154113 -342.520747) (xy 78.13875 -342.573073) (xy 78.116097 -342.62268) (xy 78.086615 -342.668559)
			(xy 78.050905 -342.709775) (xy 78.009692 -342.74549) (xy 77.963817 -342.774977) (xy 77.914212 -342.797635)
			(xy 77.861888 -342.813004) (xy 77.807909 -342.820771) (xy 77.780642 -342.82126) (xy 76.917042 -342.82126)
			(xy 76.889769 -342.820803) (xy 76.835777 -342.813046) (xy 76.783439 -342.797683) (xy 76.733821 -342.775028)
			(xy 76.687931 -342.745541) (xy 76.646706 -342.709824) (xy 76.610984 -342.668602) (xy 76.581492 -342.622716)
			(xy 76.558831 -342.5731) (xy 76.543463 -342.520764) (xy 76.5357 -342.466773) (xy 75.052996 -342.466773)
			(xy 75.045234 -342.52076) (xy 75.029867 -342.573094) (xy 75.007208 -342.622708) (xy 74.977719 -342.668592)
			(xy 74.942 -342.709812) (xy 74.900778 -342.74553) (xy 74.854892 -342.775017) (xy 74.805277 -342.797673)
			(xy 74.752942 -342.813038) (xy 74.698954 -342.820798) (xy 74.671682 -342.82126) (xy 73.808082 -342.82126)
			(xy 73.780813 -342.820776) (xy 73.726831 -342.813013) (xy 73.674504 -342.797646) (xy 73.624896 -342.774988)
			(xy 73.579017 -342.745502) (xy 73.537801 -342.709786) (xy 73.502087 -342.668569) (xy 73.472603 -342.622689)
			(xy 73.449948 -342.573079) (xy 73.434584 -342.520751) (xy 73.426822 -342.466769) (xy 71.943974 -342.466769)
			(xy 71.936213 -342.52075) (xy 71.920848 -342.573077) (xy 71.898194 -342.622686) (xy 71.86871 -342.668565)
			(xy 71.832998 -342.709782) (xy 71.791783 -342.745497) (xy 71.745905 -342.774983) (xy 71.696298 -342.797641)
			(xy 71.643971 -342.813008) (xy 71.58999 -342.820772) (xy 71.562722 -342.82126) (xy 70.699122 -342.82126)
			(xy 70.67185 -342.820802) (xy 70.61786 -342.813042) (xy 70.565525 -342.797678) (xy 70.515909 -342.775021)
			(xy 70.470022 -342.745534) (xy 70.428799 -342.709817) (xy 70.393079 -342.668596) (xy 70.363589 -342.622711)
			(xy 70.34093 -342.573096) (xy 70.325562 -342.520761) (xy 70.3178 -342.466772) (xy 68.835096 -342.466772)
			(xy 68.835096 -342.466773) (xy 68.827333 -342.520763) (xy 68.811965 -342.573098) (xy 68.789305 -342.622713)
			(xy 68.759814 -342.668599) (xy 68.724093 -342.70982) (xy 68.682868 -342.745537) (xy 68.63698 -342.775023)
			(xy 68.587362 -342.797679) (xy 68.535025 -342.813041) (xy 68.481035 -342.820799) (xy 68.453762 -342.82126)
			(xy 67.590162 -342.82126) (xy 67.562894 -342.820775) (xy 67.508914 -342.813009) (xy 67.456589 -342.79764)
			(xy 67.406984 -342.774982) (xy 67.361107 -342.745495) (xy 67.319894 -342.709779) (xy 67.284183 -342.668562)
			(xy 67.2547 -342.622683) (xy 67.232047 -342.573075) (xy 67.216683 -342.520748) (xy 67.208922 -342.466768)
			(xy 65.726074 -342.466768) (xy 65.726074 -342.466769) (xy 65.718312 -342.520752) (xy 65.702947 -342.573081)
			(xy 65.680291 -342.622691) (xy 65.650805 -342.668572) (xy 65.615091 -342.709789) (xy 65.573873 -342.745504)
			(xy 65.527993 -342.77499) (xy 65.478383 -342.797646) (xy 65.426054 -342.813012) (xy 65.372071 -342.820773)
			(xy 65.344802 -342.82126) (xy 64.481202 -342.82126) (xy 64.453931 -342.820801) (xy 64.399943 -342.813039)
			(xy 64.34761 -342.797673) (xy 64.297997 -342.775015) (xy 64.252112 -342.745527) (xy 64.210892 -342.70981)
			(xy 64.175174 -342.668589) (xy 64.145686 -342.622705) (xy 64.123028 -342.573092) (xy 64.107662 -342.520759)
			(xy 64.099899 -342.466771) (xy 62.617073 -342.466771) (xy 62.609313 -342.520747) (xy 62.59395 -342.573073)
			(xy 62.571297 -342.62268) (xy 62.541815 -342.668559) (xy 62.506105 -342.709775) (xy 62.464892 -342.74549)
			(xy 62.419017 -342.774977) (xy 62.369412 -342.797635) (xy 62.317088 -342.813004) (xy 62.263109 -342.820771)
			(xy 62.235842 -342.82126) (xy 61.372242 -342.82126) (xy 61.344969 -342.820803) (xy 61.290977 -342.813046)
			(xy 61.238639 -342.797683) (xy 61.189021 -342.775028) (xy 61.143131 -342.745541) (xy 61.101906 -342.709824)
			(xy 61.066184 -342.668602) (xy 61.036692 -342.622716) (xy 61.014031 -342.5731) (xy 60.998663 -342.520764)
			(xy 60.9909 -342.466773) (xy 51.666873 -342.466773) (xy 51.659113 -342.520746) (xy 51.643751 -342.573072)
			(xy 51.621098 -342.622678) (xy 51.591617 -342.668557) (xy 51.555907 -342.709773) (xy 51.514695 -342.745488)
			(xy 51.46882 -342.774975) (xy 51.419217 -342.797634) (xy 51.366893 -342.813003) (xy 51.312915 -342.82077)
			(xy 51.285648 -342.82126) (xy 50.422048 -342.82126) (xy 50.394775 -342.820804) (xy 50.340782 -342.813047)
			(xy 50.288444 -342.797685) (xy 50.238824 -342.77503) (xy 50.192934 -342.745544) (xy 50.151708 -342.709826)
			(xy 50.115985 -342.668604) (xy 50.086493 -342.622718) (xy 50.063832 -342.573101) (xy 50.048463 -342.520765)
			(xy 50.0407 -342.466773) (xy 48.557996 -342.466773) (xy 48.550234 -342.520759) (xy 48.534867 -342.573092)
			(xy 48.512209 -342.622706) (xy 48.48272 -342.66859) (xy 48.447002 -342.70981) (xy 48.40578 -342.745528)
			(xy 48.359896 -342.775015) (xy 48.310281 -342.797671) (xy 48.257947 -342.813037) (xy 48.203959 -342.820797)
			(xy 48.176688 -342.82126) (xy 47.313088 -342.82126) (xy 47.285819 -342.820777) (xy 47.231836 -342.813014)
			(xy 47.179508 -342.797647) (xy 47.129899 -342.77499) (xy 47.08402 -342.745504) (xy 47.042803 -342.709788)
			(xy 47.007089 -342.668571) (xy 46.977604 -342.62269) (xy 46.954949 -342.573081) (xy 46.939584 -342.520752)
			(xy 46.931822 -342.466769) (xy 45.448974 -342.466769) (xy 45.441213 -342.520749) (xy 45.425849 -342.573076)
			(xy 45.403195 -342.622684) (xy 45.373712 -342.668563) (xy 45.338 -342.70978) (xy 45.296786 -342.745495)
			(xy 45.250909 -342.774981) (xy 45.201302 -342.797639) (xy 45.148976 -342.813007) (xy 45.094996 -342.820772)
			(xy 45.067728 -342.82126) (xy 44.204128 -342.82126) (xy 44.176856 -342.820802) (xy 44.122865 -342.813043)
			(xy 44.070529 -342.79768) (xy 44.020912 -342.775023) (xy 43.975025 -342.745536) (xy 43.933801 -342.709819)
			(xy 43.89808 -342.668598) (xy 43.86859 -342.622712) (xy 43.84593 -342.573097) (xy 43.830562 -342.520762)
			(xy 43.8228 -342.466772) (xy 42.340096 -342.466772) (xy 42.332333 -342.520762) (xy 42.316966 -342.573097)
			(xy 42.294306 -342.622712) (xy 42.264815 -342.668597) (xy 42.229095 -342.709817) (xy 42.187871 -342.745535)
			(xy 42.141984 -342.775021) (xy 42.092367 -342.797677) (xy 42.04003 -342.81304) (xy 41.98604 -342.820799)
			(xy 41.958768 -342.82126) (xy 41.095168 -342.82126) (xy 41.0679 -342.820775) (xy 41.01392 -342.81301)
			(xy 40.961594 -342.797642) (xy 40.911987 -342.774984) (xy 40.86611 -342.745497) (xy 40.824896 -342.709781)
			(xy 40.789184 -342.668564) (xy 40.759701 -342.622685) (xy 40.737047 -342.573076) (xy 40.721683 -342.520749)
			(xy 40.713922 -342.466768) (xy 39.231074 -342.466768) (xy 39.231074 -342.466769) (xy 39.223312 -342.520751)
			(xy 39.207947 -342.57308) (xy 39.185292 -342.622689) (xy 39.155807 -342.66857) (xy 39.120093 -342.709787)
			(xy 39.078876 -342.745502) (xy 39.032997 -342.774988) (xy 38.983388 -342.797645) (xy 38.931059 -342.81301)
			(xy 38.877077 -342.820773) (xy 38.849808 -342.82126) (xy 37.986208 -342.82126) (xy 37.958936 -342.820801)
			(xy 37.904948 -342.81304) (xy 37.852615 -342.797674) (xy 37.803 -342.775017) (xy 37.757115 -342.745529)
			(xy 37.715894 -342.709812) (xy 37.680175 -342.668591) (xy 37.650687 -342.622707) (xy 37.628029 -342.573093)
			(xy 37.612662 -342.520759) (xy 37.6049 -342.466772) (xy 36.122073 -342.466772) (xy 36.114313 -342.520746)
			(xy 36.098951 -342.573072) (xy 36.076298 -342.622678) (xy 36.046817 -342.668557) (xy 36.011107 -342.709773)
			(xy 35.969895 -342.745488) (xy 35.92402 -342.774975) (xy 35.874417 -342.797634) (xy 35.822093 -342.813003)
			(xy 35.768115 -342.82077) (xy 35.740848 -342.82126) (xy 34.877248 -342.82126) (xy 34.849975 -342.820804)
			(xy 34.795982 -342.813047) (xy 34.743644 -342.797685) (xy 34.694024 -342.77503) (xy 34.648134 -342.745544)
			(xy 34.606908 -342.709826) (xy 34.571185 -342.668604) (xy 34.541693 -342.622718) (xy 34.519032 -342.573101)
			(xy 34.503663 -342.520765) (xy 34.4959 -342.466773) (xy 33.013196 -342.466773) (xy 33.005434 -342.520759)
			(xy 32.990067 -342.573092) (xy 32.967409 -342.622706) (xy 32.93792 -342.66859) (xy 32.902202 -342.70981)
			(xy 32.86098 -342.745528) (xy 32.815096 -342.775015) (xy 32.765481 -342.797671) (xy 32.713147 -342.813037)
			(xy 32.659159 -342.820797) (xy 32.631888 -342.82126) (xy 31.768288 -342.82126) (xy 31.741019 -342.820777)
			(xy 31.687036 -342.813014) (xy 31.634708 -342.797647) (xy 31.585099 -342.77499) (xy 31.53922 -342.745504)
			(xy 31.498003 -342.709788) (xy 31.462289 -342.668571) (xy 31.432804 -342.62269) (xy 31.410149 -342.573081)
			(xy 31.394784 -342.520752) (xy 31.387022 -342.466769) (xy 29.904174 -342.466769) (xy 29.896413 -342.520749)
			(xy 29.881049 -342.573076) (xy 29.858395 -342.622684) (xy 29.828912 -342.668563) (xy 29.7932 -342.70978)
			(xy 29.751986 -342.745495) (xy 29.706109 -342.774981) (xy 29.656502 -342.797639) (xy 29.604176 -342.813007)
			(xy 29.550196 -342.820772) (xy 29.522928 -342.82126) (xy 28.659328 -342.82126) (xy 28.632056 -342.820802)
			(xy 28.578065 -342.813043) (xy 28.525729 -342.79768) (xy 28.476112 -342.775023) (xy 28.430225 -342.745536)
			(xy 28.389001 -342.709819) (xy 28.35328 -342.668598) (xy 28.32379 -342.622712) (xy 28.30113 -342.573097)
			(xy 28.285762 -342.520762) (xy 28.278 -342.466772) (xy 26.795296 -342.466772) (xy 26.787533 -342.520762)
			(xy 26.772166 -342.573097) (xy 26.749506 -342.622712) (xy 26.720015 -342.668597) (xy 26.684295 -342.709817)
			(xy 26.643071 -342.745535) (xy 26.597184 -342.775021) (xy 26.547567 -342.797677) (xy 26.49523 -342.81304)
			(xy 26.44124 -342.820799) (xy 26.413968 -342.82126) (xy 25.550368 -342.82126) (xy 25.5231 -342.820775)
			(xy 25.46912 -342.81301) (xy 25.416794 -342.797642) (xy 25.367187 -342.774984) (xy 25.32131 -342.745497)
			(xy 25.280096 -342.709781) (xy 25.244384 -342.668564) (xy 25.214901 -342.622685) (xy 25.192247 -342.573076)
			(xy 25.176883 -342.520749) (xy 25.169122 -342.466768) (xy 23.686274 -342.466768) (xy 23.686274 -342.466769)
			(xy 23.678512 -342.520751) (xy 23.663147 -342.57308) (xy 23.640492 -342.622689) (xy 23.611007 -342.66857)
			(xy 23.575293 -342.709787) (xy 23.534076 -342.745502) (xy 23.488197 -342.774988) (xy 23.438588 -342.797645)
			(xy 23.386259 -342.81301) (xy 23.332277 -342.820773) (xy 23.305008 -342.82126) (xy 22.441408 -342.82126)
			(xy 22.414136 -342.820801) (xy 22.360148 -342.81304) (xy 22.307815 -342.797674) (xy 22.2582 -342.775017)
			(xy 22.212315 -342.745529) (xy 22.171094 -342.709812) (xy 22.135375 -342.668591) (xy 22.105887 -342.622707)
			(xy 22.083229 -342.573093) (xy 22.067862 -342.520759) (xy 22.0601 -342.466772) (xy 20.577347 -342.466772)
			(xy 20.569584 -342.520758) (xy 20.554218 -342.57309) (xy 20.53156 -342.622703) (xy 20.502073 -342.668587)
			(xy 20.466355 -342.709807) (xy 20.425135 -342.745524) (xy 20.379252 -342.775011) (xy 20.329638 -342.797669)
			(xy 20.277306 -342.813035) (xy 20.223319 -342.820797) (xy 20.196048 -342.82126) (xy 19.332448 -342.82126)
			(xy 19.305179 -342.820777) (xy 19.251195 -342.813015) (xy 19.198865 -342.79765) (xy 19.149255 -342.774993)
			(xy 19.103374 -342.745507) (xy 19.062157 -342.709792) (xy 19.026441 -342.668574) (xy 18.996956 -342.622693)
			(xy 18.974299 -342.573083) (xy 18.958934 -342.520753) (xy 18.951172 -342.466769) (xy 0.508 -342.466769)
			(xy 0.508 -345.49242) (xy 18.95117 -345.49242) (xy 18.95117 -345.43788) (xy 18.958932 -345.383896)
			(xy 18.974298 -345.331567) (xy 18.996954 -345.281956) (xy 19.02644 -345.236075) (xy 19.062155 -345.194857)
			(xy 19.103373 -345.159141) (xy 19.149254 -345.129655) (xy 19.198865 -345.106998) (xy 19.251194 -345.091633)
			(xy 19.305178 -345.083871) (xy 19.332448 -345.083384) (xy 20.196048 -345.083384) (xy 20.223319 -345.083855)
			(xy 20.277305 -345.091617) (xy 20.329638 -345.106983) (xy 20.379251 -345.12964) (xy 20.425134 -345.159128)
			(xy 20.466354 -345.194845) (xy 20.502071 -345.236064) (xy 20.531559 -345.281948) (xy 20.554216 -345.33156)
			(xy 20.569582 -345.383893) (xy 20.577345 -345.437879) (xy 20.577345 -345.49242) (xy 22.06013 -345.49242)
			(xy 22.06013 -345.43788) (xy 22.067892 -345.383896) (xy 22.083258 -345.331567) (xy 22.105914 -345.281956)
			(xy 22.1354 -345.236075) (xy 22.171115 -345.194857) (xy 22.212333 -345.159141) (xy 22.258214 -345.129655)
			(xy 22.307825 -345.106998) (xy 22.360154 -345.091633) (xy 22.414138 -345.083871) (xy 22.441408 -345.083384)
			(xy 23.305008 -345.083384) (xy 23.332279 -345.083855) (xy 23.386265 -345.091617) (xy 23.438598 -345.106983)
			(xy 23.488211 -345.12964) (xy 23.534094 -345.159128) (xy 23.575314 -345.194845) (xy 23.611031 -345.236064)
			(xy 23.640519 -345.281948) (xy 23.663176 -345.33156) (xy 23.678542 -345.383893) (xy 23.686305 -345.437879)
			(xy 23.686305 -345.492365) (xy 25.16917 -345.492365) (xy 25.16917 -345.437835) (xy 25.17693 -345.383861)
			(xy 25.192292 -345.33154) (xy 25.214943 -345.281938) (xy 25.244422 -345.236064) (xy 25.28013 -345.194853)
			(xy 25.321339 -345.159142) (xy 25.36721 -345.129658) (xy 25.41681 -345.107003) (xy 25.46913 -345.091637)
			(xy 25.523103 -345.083872) (xy 25.550368 -345.083384) (xy 26.413968 -345.083384) (xy 26.441244 -345.083753)
			(xy 26.495241 -345.091513) (xy 26.547583 -345.106878) (xy 26.597207 -345.129537) (xy 26.6431 -345.159027)
			(xy 26.684329 -345.194749) (xy 26.720054 -345.235975) (xy 26.749548 -345.281865) (xy 26.772211 -345.331487)
			(xy 26.78758 -345.383828) (xy 26.795344 -345.437824) (xy 26.795344 -345.492369) (xy 28.278047 -345.492369)
			(xy 28.278047 -345.437831) (xy 28.285809 -345.383848) (xy 28.301175 -345.33152) (xy 28.323832 -345.281911)
			(xy 28.353319 -345.236031) (xy 28.389035 -345.194815) (xy 28.430253 -345.159102) (xy 28.476135 -345.129619)
			(xy 28.525746 -345.106965) (xy 28.578076 -345.091603) (xy 28.632059 -345.083845) (xy 28.659328 -345.083384)
			(xy 29.522928 -345.083384) (xy 29.550199 -345.08378) (xy 29.604186 -345.091546) (xy 29.656519 -345.106916)
			(xy 29.706132 -345.129576) (xy 29.752014 -345.159067) (xy 29.793234 -345.194786) (xy 29.82895 -345.236008)
			(xy 29.858437 -345.281893) (xy 29.881094 -345.331507) (xy 29.89646 -345.383841) (xy 29.904222 -345.437829)
			(xy 29.904222 -345.492366) (xy 31.38707 -345.492366) (xy 31.38707 -345.437834) (xy 31.394831 -345.383858)
			(xy 31.410194 -345.331536) (xy 31.432846 -345.281933) (xy 31.462327 -345.236058) (xy 31.498037 -345.194846)
			(xy 31.539248 -345.159135) (xy 31.585122 -345.129652) (xy 31.634725 -345.106998) (xy 31.687047 -345.091633)
			(xy 31.741022 -345.083871) (xy 31.768288 -345.083384) (xy 32.631888 -345.083384) (xy 32.659163 -345.083755)
			(xy 32.713157 -345.091516) (xy 32.765498 -345.106884) (xy 32.815119 -345.129543) (xy 32.861009 -345.159034)
			(xy 32.902236 -345.194756) (xy 32.937959 -345.235981) (xy 32.967451 -345.281871) (xy 32.990112 -345.331491)
			(xy 33.005481 -345.383831) (xy 33.013244 -345.437825) (xy 33.013244 -345.49237) (xy 34.495948 -345.49237)
			(xy 34.495948 -345.43783) (xy 34.50371 -345.383846) (xy 34.519077 -345.331515) (xy 34.541735 -345.281905)
			(xy 34.571224 -345.236024) (xy 34.606942 -345.194808) (xy 34.648163 -345.159095) (xy 34.694047 -345.129612)
			(xy 34.74366 -345.10696) (xy 34.795992 -345.0916) (xy 34.849978 -345.083844) (xy 34.877248 -345.083384)
			(xy 35.740848 -345.083384) (xy 35.768118 -345.083782) (xy 35.822103 -345.09155) (xy 35.874433 -345.106921)
			(xy 35.924044 -345.129583) (xy 35.969924 -345.159074) (xy 36.011141 -345.194793) (xy 36.046855 -345.236015)
			(xy 36.07634 -345.281899) (xy 36.098995 -345.331512) (xy 36.11436 -345.383844) (xy 36.122122 -345.43783)
			(xy 36.122122 -345.492368) (xy 37.604947 -345.492368) (xy 37.604947 -345.437832) (xy 37.612709 -345.383851)
			(xy 37.628074 -345.331524) (xy 37.650729 -345.281916) (xy 37.680214 -345.236038) (xy 37.715928 -345.194822)
			(xy 37.757144 -345.159109) (xy 37.803023 -345.129625) (xy 37.852631 -345.106971) (xy 37.904959 -345.091607)
			(xy 37.95894 -345.083847) (xy 37.986208 -345.083384) (xy 38.849808 -345.083384) (xy 38.87708 -345.083779)
			(xy 38.93107 -345.091543) (xy 38.983404 -345.106911) (xy 39.03302 -345.12957) (xy 39.078905 -345.15906)
			(xy 39.120127 -345.194779) (xy 39.155845 -345.236001) (xy 39.185334 -345.281888) (xy 39.207992 -345.331503)
			(xy 39.223359 -345.383838) (xy 39.231121 -345.437828) (xy 39.231121 -345.492365) (xy 40.71397 -345.492365)
			(xy 40.71397 -345.437835) (xy 40.72173 -345.383861) (xy 40.737092 -345.33154) (xy 40.759743 -345.281938)
			(xy 40.789222 -345.236064) (xy 40.82493 -345.194853) (xy 40.866139 -345.159142) (xy 40.91201 -345.129658)
			(xy 40.96161 -345.107003) (xy 41.01393 -345.091637) (xy 41.067903 -345.083872) (xy 41.095168 -345.083384)
			(xy 41.958768 -345.083384) (xy 41.986044 -345.083753) (xy 42.040041 -345.091513) (xy 42.092383 -345.106878)
			(xy 42.142007 -345.129537) (xy 42.1879 -345.159027) (xy 42.229129 -345.194749) (xy 42.264854 -345.235975)
			(xy 42.294348 -345.281865) (xy 42.317011 -345.331487) (xy 42.33238 -345.383828) (xy 42.340144 -345.437824)
			(xy 42.340144 -345.492369) (xy 43.822847 -345.492369) (xy 43.822847 -345.437831) (xy 43.830609 -345.383848)
			(xy 43.845975 -345.33152) (xy 43.868632 -345.281911) (xy 43.898119 -345.236031) (xy 43.933835 -345.194815)
			(xy 43.975053 -345.159102) (xy 44.020935 -345.129619) (xy 44.070546 -345.106965) (xy 44.122876 -345.091603)
			(xy 44.176859 -345.083845) (xy 44.204128 -345.083384) (xy 45.067728 -345.083384) (xy 45.094999 -345.08378)
			(xy 45.148986 -345.091546) (xy 45.201319 -345.106916) (xy 45.250932 -345.129576) (xy 45.296814 -345.159067)
			(xy 45.338034 -345.194786) (xy 45.37375 -345.236008) (xy 45.403237 -345.281893) (xy 45.425894 -345.331507)
			(xy 45.44126 -345.383841) (xy 45.449022 -345.437829) (xy 45.449022 -345.492366) (xy 46.93187 -345.492366)
			(xy 46.93187 -345.437834) (xy 46.939631 -345.383858) (xy 46.954994 -345.331536) (xy 46.977646 -345.281933)
			(xy 47.007127 -345.236058) (xy 47.042837 -345.194846) (xy 47.084048 -345.159135) (xy 47.129922 -345.129652)
			(xy 47.179525 -345.106998) (xy 47.231847 -345.091633) (xy 47.285822 -345.083871) (xy 47.313088 -345.083384)
			(xy 48.176688 -345.083384) (xy 48.203963 -345.083755) (xy 48.257957 -345.091516) (xy 48.310298 -345.106884)
			(xy 48.359919 -345.129543) (xy 48.405809 -345.159034) (xy 48.447036 -345.194756) (xy 48.482759 -345.235981)
			(xy 48.512251 -345.281871) (xy 48.534912 -345.331491) (xy 48.550281 -345.383831) (xy 48.558044 -345.437825)
			(xy 48.558044 -345.49237) (xy 50.040748 -345.49237) (xy 50.040748 -345.43783) (xy 50.04851 -345.383846)
			(xy 50.063877 -345.331515) (xy 50.086535 -345.281905) (xy 50.116024 -345.236024) (xy 50.151742 -345.194808)
			(xy 50.192963 -345.159095) (xy 50.238847 -345.129612) (xy 50.28846 -345.10696) (xy 50.340792 -345.0916)
			(xy 50.394778 -345.083844) (xy 50.422048 -345.083384) (xy 51.285648 -345.083384) (xy 51.312918 -345.083782)
			(xy 51.366903 -345.09155) (xy 51.419233 -345.106921) (xy 51.468844 -345.129583) (xy 51.514724 -345.159074)
			(xy 51.555941 -345.194793) (xy 51.591655 -345.236015) (xy 51.62114 -345.281899) (xy 51.643795 -345.331512)
			(xy 51.65916 -345.383844) (xy 51.666922 -345.43783) (xy 51.666922 -345.49237) (xy 60.990948 -345.49237)
			(xy 60.990948 -345.43783) (xy 60.99871 -345.383846) (xy 61.014076 -345.331517) (xy 61.036734 -345.281907)
			(xy 61.066222 -345.236026) (xy 61.10194 -345.19481) (xy 61.14316 -345.159097) (xy 61.189044 -345.129614)
			(xy 61.238656 -345.106962) (xy 61.290987 -345.091601) (xy 61.344972 -345.083845) (xy 61.372242 -345.083384)
			(xy 62.235842 -345.083384) (xy 62.263113 -345.083781) (xy 62.317098 -345.091549) (xy 62.369429 -345.10692)
			(xy 62.41904 -345.129581) (xy 62.464921 -345.159072) (xy 62.506139 -345.194791) (xy 62.541854 -345.236013)
			(xy 62.571339 -345.281897) (xy 62.593995 -345.33151) (xy 62.60936 -345.383843) (xy 62.617122 -345.437829)
			(xy 62.617122 -345.492368) (xy 64.099947 -345.492368) (xy 64.099947 -345.437832) (xy 64.107709 -345.383852)
			(xy 64.123073 -345.331525) (xy 64.145728 -345.281918) (xy 64.175212 -345.23604) (xy 64.210926 -345.194824)
			(xy 64.252141 -345.159111) (xy 64.29802 -345.129627) (xy 64.347627 -345.106972) (xy 64.399954 -345.091608)
			(xy 64.453934 -345.083847) (xy 64.481202 -345.083384) (xy 65.344802 -345.083384) (xy 65.372075 -345.083779)
			(xy 65.426064 -345.091542) (xy 65.4784 -345.106909) (xy 65.528016 -345.129568) (xy 65.573902 -345.159057)
			(xy 65.615124 -345.194777) (xy 65.650844 -345.236) (xy 65.680333 -345.281886) (xy 65.702992 -345.331502)
			(xy 65.718359 -345.383838) (xy 65.726121 -345.437827) (xy 65.726121 -345.492364) (xy 67.20897 -345.492364)
			(xy 67.20897 -345.437836) (xy 67.21673 -345.383862) (xy 67.232092 -345.331542) (xy 67.254742 -345.28194)
			(xy 67.284221 -345.236066) (xy 67.319928 -345.194855) (xy 67.361136 -345.159144) (xy 67.407007 -345.12966)
			(xy 67.456606 -345.107005) (xy 67.508925 -345.091638) (xy 67.562898 -345.083873) (xy 67.590162 -345.083384)
			(xy 68.453762 -345.083384) (xy 68.481038 -345.083753) (xy 68.535036 -345.091512) (xy 68.587379 -345.106877)
			(xy 68.637003 -345.129535) (xy 68.682897 -345.159025) (xy 68.724127 -345.194747) (xy 68.759852 -345.235973)
			(xy 68.789347 -345.281864) (xy 68.81201 -345.331485) (xy 68.82738 -345.383827) (xy 68.835144 -345.437824)
			(xy 68.835144 -345.492369) (xy 70.317847 -345.492369) (xy 70.317847 -345.437831) (xy 70.325609 -345.383849)
			(xy 70.340975 -345.331521) (xy 70.363631 -345.281912) (xy 70.393117 -345.236033) (xy 70.428833 -345.194817)
			(xy 70.470051 -345.159104) (xy 70.515932 -345.129621) (xy 70.565541 -345.106967) (xy 70.617871 -345.091605)
			(xy 70.671853 -345.083846) (xy 70.699122 -345.083384) (xy 71.562722 -345.083384) (xy 71.589994 -345.08378)
			(xy 71.643981 -345.091545) (xy 71.696315 -345.106914) (xy 71.745928 -345.129574) (xy 71.791812 -345.159064)
			(xy 71.833032 -345.194784) (xy 71.868749 -345.236006) (xy 71.898236 -345.281891) (xy 71.920893 -345.331506)
			(xy 71.936259 -345.38384) (xy 71.944022 -345.437828) (xy 71.944022 -345.492365) (xy 73.42687 -345.492365)
			(xy 73.42687 -345.437835) (xy 73.434631 -345.383859) (xy 73.449993 -345.331537) (xy 73.472645 -345.281934)
			(xy 73.502126 -345.23606) (xy 73.537835 -345.194848) (xy 73.579045 -345.159137) (xy 73.624919 -345.129654)
			(xy 73.674521 -345.106999) (xy 73.726842 -345.091634) (xy 73.780817 -345.083872) (xy 73.808082 -345.083384)
			(xy 74.671682 -345.083384) (xy 74.698957 -345.083754) (xy 74.752952 -345.091515) (xy 74.805294 -345.106882)
			(xy 74.854915 -345.129541) (xy 74.900806 -345.159032) (xy 74.942034 -345.194754) (xy 74.977757 -345.235979)
			(xy 75.00725 -345.281869) (xy 75.029912 -345.33149) (xy 75.045281 -345.38383) (xy 75.053044 -345.437825)
			(xy 75.053044 -345.49237) (xy 76.535748 -345.49237) (xy 76.535748 -345.43783) (xy 76.54351 -345.383846)
			(xy 76.558876 -345.331517) (xy 76.581534 -345.281907) (xy 76.611022 -345.236026) (xy 76.64674 -345.19481)
			(xy 76.68796 -345.159097) (xy 76.733844 -345.129614) (xy 76.783456 -345.106962) (xy 76.835787 -345.091601)
			(xy 76.889772 -345.083845) (xy 76.917042 -345.083384) (xy 77.780642 -345.083384) (xy 77.807913 -345.083781)
			(xy 77.861898 -345.091549) (xy 77.914229 -345.10692) (xy 77.96384 -345.129581) (xy 78.009721 -345.159072)
			(xy 78.050939 -345.194791) (xy 78.086654 -345.236013) (xy 78.116139 -345.281897) (xy 78.138795 -345.33151)
			(xy 78.15416 -345.383843) (xy 78.161922 -345.437829) (xy 78.161922 -345.492368) (xy 79.644747 -345.492368)
			(xy 79.644747 -345.437832) (xy 79.652509 -345.383852) (xy 79.667873 -345.331525) (xy 79.690528 -345.281918)
			(xy 79.720012 -345.23604) (xy 79.755726 -345.194824) (xy 79.796941 -345.159111) (xy 79.84282 -345.129627)
			(xy 79.892427 -345.106972) (xy 79.944754 -345.091608) (xy 79.998734 -345.083847) (xy 80.026002 -345.083384)
			(xy 80.889602 -345.083384) (xy 80.916875 -345.083779) (xy 80.970864 -345.091542) (xy 81.0232 -345.106909)
			(xy 81.072816 -345.129568) (xy 81.118702 -345.159057) (xy 81.159924 -345.194777) (xy 81.195644 -345.236)
			(xy 81.225133 -345.281886) (xy 81.247792 -345.331502) (xy 81.263159 -345.383838) (xy 81.270921 -345.437827)
			(xy 81.270921 -345.492364) (xy 82.75377 -345.492364) (xy 82.75377 -345.437836) (xy 82.76153 -345.383862)
			(xy 82.776892 -345.331542) (xy 82.799542 -345.28194) (xy 82.829021 -345.236066) (xy 82.864728 -345.194855)
			(xy 82.905936 -345.159144) (xy 82.951807 -345.12966) (xy 83.001406 -345.107005) (xy 83.053725 -345.091638)
			(xy 83.107698 -345.083873) (xy 83.134962 -345.083384) (xy 83.998562 -345.083384) (xy 84.025838 -345.083753)
			(xy 84.079836 -345.091512) (xy 84.132179 -345.106877) (xy 84.181803 -345.129535) (xy 84.227697 -345.159025)
			(xy 84.268927 -345.194747) (xy 84.304652 -345.235973) (xy 84.334147 -345.281864) (xy 84.35681 -345.331485)
			(xy 84.37218 -345.383827) (xy 84.379944 -345.437824) (xy 84.379944 -345.492369) (xy 85.862647 -345.492369)
			(xy 85.862647 -345.437831) (xy 85.870409 -345.383849) (xy 85.885775 -345.331521) (xy 85.908431 -345.281912)
			(xy 85.937917 -345.236033) (xy 85.973633 -345.194817) (xy 86.014851 -345.159104) (xy 86.060732 -345.129621)
			(xy 86.110341 -345.106967) (xy 86.162671 -345.091605) (xy 86.216653 -345.083846) (xy 86.243922 -345.083384)
			(xy 87.107522 -345.083384) (xy 87.134794 -345.08378) (xy 87.188781 -345.091545) (xy 87.241115 -345.106914)
			(xy 87.290728 -345.129574) (xy 87.336612 -345.159064) (xy 87.377832 -345.194784) (xy 87.413549 -345.236006)
			(xy 87.443036 -345.281891) (xy 87.465693 -345.331506) (xy 87.481059 -345.38384) (xy 87.488822 -345.437828)
			(xy 87.488822 -345.492365) (xy 88.97167 -345.492365) (xy 88.97167 -345.437835) (xy 88.979431 -345.383859)
			(xy 88.994793 -345.331537) (xy 89.017445 -345.281934) (xy 89.046926 -345.23606) (xy 89.082635 -345.194848)
			(xy 89.123845 -345.159137) (xy 89.169719 -345.129654) (xy 89.219321 -345.106999) (xy 89.271642 -345.091634)
			(xy 89.325617 -345.083872) (xy 89.352882 -345.083384) (xy 90.216482 -345.083384) (xy 90.243757 -345.083754)
			(xy 90.297752 -345.091515) (xy 90.350094 -345.106882) (xy 90.399715 -345.129541) (xy 90.445606 -345.159032)
			(xy 90.486834 -345.194754) (xy 90.522557 -345.235979) (xy 90.55205 -345.281869) (xy 90.574712 -345.33149)
			(xy 90.590081 -345.38383) (xy 90.597844 -345.437825) (xy 90.597844 -345.49237) (xy 92.080548 -345.49237)
			(xy 92.080548 -345.43783) (xy 92.08831 -345.383846) (xy 92.103676 -345.331517) (xy 92.126334 -345.281907)
			(xy 92.155822 -345.236026) (xy 92.19154 -345.19481) (xy 92.23276 -345.159097) (xy 92.278644 -345.129614)
			(xy 92.328256 -345.106962) (xy 92.380587 -345.091601) (xy 92.434572 -345.083845) (xy 92.461842 -345.083384)
			(xy 93.325442 -345.083384) (xy 93.352713 -345.083781) (xy 93.406698 -345.091549) (xy 93.459029 -345.10692)
			(xy 93.50864 -345.129581) (xy 93.554521 -345.159072) (xy 93.595739 -345.194791) (xy 93.631454 -345.236013)
			(xy 93.660939 -345.281897) (xy 93.683595 -345.33151) (xy 93.69896 -345.383843) (xy 93.706722 -345.437829)
			(xy 93.706722 -345.492368) (xy 111.480847 -345.492368) (xy 111.480847 -345.437832) (xy 111.488609 -345.383851)
			(xy 111.503974 -345.331524) (xy 111.526629 -345.281916) (xy 111.556114 -345.236038) (xy 111.591828 -345.194822)
			(xy 111.633044 -345.159109) (xy 111.678923 -345.129625) (xy 111.728531 -345.106971) (xy 111.780859 -345.091607)
			(xy 111.83484 -345.083847) (xy 111.862108 -345.083384) (xy 112.725708 -345.083384) (xy 112.75298 -345.083779)
			(xy 112.80697 -345.091543) (xy 112.859304 -345.106911) (xy 112.90892 -345.12957) (xy 112.954805 -345.15906)
			(xy 112.996027 -345.194779) (xy 113.031745 -345.236001) (xy 113.061234 -345.281888) (xy 113.083892 -345.331503)
			(xy 113.099259 -345.383838) (xy 113.107021 -345.437828) (xy 113.107021 -345.492365) (xy 114.58987 -345.492365)
			(xy 114.58987 -345.437835) (xy 114.59763 -345.383861) (xy 114.612992 -345.33154) (xy 114.635643 -345.281938)
			(xy 114.665122 -345.236064) (xy 114.70083 -345.194853) (xy 114.742039 -345.159142) (xy 114.78791 -345.129658)
			(xy 114.83751 -345.107003) (xy 114.88983 -345.091637) (xy 114.943803 -345.083872) (xy 114.971068 -345.083384)
			(xy 115.834668 -345.083384) (xy 115.861944 -345.083753) (xy 115.915941 -345.091513) (xy 115.968283 -345.106878)
			(xy 116.017907 -345.129537) (xy 116.0638 -345.159027) (xy 116.105029 -345.194749) (xy 116.140754 -345.235975)
			(xy 116.170248 -345.281865) (xy 116.192911 -345.331487) (xy 116.20828 -345.383828) (xy 116.216044 -345.437824)
			(xy 116.216044 -345.492369) (xy 117.698747 -345.492369) (xy 117.698747 -345.437831) (xy 117.706509 -345.383848)
			(xy 117.721875 -345.33152) (xy 117.744532 -345.281911) (xy 117.774019 -345.236031) (xy 117.809735 -345.194815)
			(xy 117.850953 -345.159102) (xy 117.896835 -345.129619) (xy 117.946446 -345.106965) (xy 117.998776 -345.091603)
			(xy 118.052759 -345.083845) (xy 118.080028 -345.083384) (xy 118.943628 -345.083384) (xy 118.970899 -345.08378)
			(xy 119.024886 -345.091546) (xy 119.077219 -345.106916) (xy 119.126832 -345.129576) (xy 119.172714 -345.159067)
			(xy 119.213934 -345.194786) (xy 119.24965 -345.236008) (xy 119.279137 -345.281893) (xy 119.301794 -345.331507)
			(xy 119.31716 -345.383841) (xy 119.324922 -345.437829) (xy 119.324922 -345.492366) (xy 120.80777 -345.492366)
			(xy 120.80777 -345.437834) (xy 120.815531 -345.383858) (xy 120.830894 -345.331536) (xy 120.853546 -345.281933)
			(xy 120.883027 -345.236058) (xy 120.918737 -345.194846) (xy 120.959948 -345.159135) (xy 121.005822 -345.129652)
			(xy 121.055425 -345.106998) (xy 121.107747 -345.091633) (xy 121.161722 -345.083871) (xy 121.188988 -345.083384)
			(xy 122.052588 -345.083384) (xy 122.079863 -345.083755) (xy 122.133857 -345.091516) (xy 122.186198 -345.106884)
			(xy 122.235819 -345.129543) (xy 122.281709 -345.159034) (xy 122.322936 -345.194756) (xy 122.358659 -345.235981)
			(xy 122.388151 -345.281871) (xy 122.410812 -345.331491) (xy 122.426181 -345.383831) (xy 122.433944 -345.437825)
			(xy 122.433944 -345.49237) (xy 123.916648 -345.49237) (xy 123.916648 -345.43783) (xy 123.92441 -345.383846)
			(xy 123.939777 -345.331515) (xy 123.962435 -345.281905) (xy 123.991924 -345.236024) (xy 124.027642 -345.194808)
			(xy 124.068863 -345.159095) (xy 124.114747 -345.129612) (xy 124.16436 -345.10696) (xy 124.216692 -345.0916)
			(xy 124.270678 -345.083844) (xy 124.297948 -345.083384) (xy 125.161548 -345.083384) (xy 125.188818 -345.083782)
			(xy 125.242803 -345.09155) (xy 125.295133 -345.106921) (xy 125.344744 -345.129583) (xy 125.390624 -345.159074)
			(xy 125.431841 -345.194793) (xy 125.467555 -345.236015) (xy 125.49704 -345.281899) (xy 125.519695 -345.331512)
			(xy 125.53506 -345.383844) (xy 125.542822 -345.43783) (xy 125.542822 -345.492368) (xy 127.025647 -345.492368)
			(xy 127.025647 -345.437832) (xy 127.033409 -345.383851) (xy 127.048774 -345.331524) (xy 127.071429 -345.281916)
			(xy 127.100914 -345.236038) (xy 127.136628 -345.194822) (xy 127.177844 -345.159109) (xy 127.223723 -345.129625)
			(xy 127.273331 -345.106971) (xy 127.325659 -345.091607) (xy 127.37964 -345.083847) (xy 127.406908 -345.083384)
			(xy 128.270508 -345.083384) (xy 128.29778 -345.083779) (xy 128.35177 -345.091543) (xy 128.404104 -345.106911)
			(xy 128.45372 -345.12957) (xy 128.499605 -345.15906) (xy 128.540827 -345.194779) (xy 128.576545 -345.236001)
			(xy 128.606034 -345.281888) (xy 128.628692 -345.331503) (xy 128.644059 -345.383838) (xy 128.651821 -345.437828)
			(xy 128.651821 -345.492365) (xy 130.13467 -345.492365) (xy 130.13467 -345.437835) (xy 130.14243 -345.383861)
			(xy 130.157792 -345.33154) (xy 130.180443 -345.281938) (xy 130.209922 -345.236064) (xy 130.24563 -345.194853)
			(xy 130.286839 -345.159142) (xy 130.33271 -345.129658) (xy 130.38231 -345.107003) (xy 130.43463 -345.091637)
			(xy 130.488603 -345.083872) (xy 130.515868 -345.083384) (xy 131.379468 -345.083384) (xy 131.406744 -345.083753)
			(xy 131.460741 -345.091513) (xy 131.513083 -345.106878) (xy 131.562707 -345.129537) (xy 131.6086 -345.159027)
			(xy 131.649829 -345.194749) (xy 131.685554 -345.235975) (xy 131.715048 -345.281865) (xy 131.737711 -345.331487)
			(xy 131.75308 -345.383828) (xy 131.760844 -345.437824) (xy 131.760844 -345.492369) (xy 133.243547 -345.492369)
			(xy 133.243547 -345.437831) (xy 133.251309 -345.383848) (xy 133.266675 -345.33152) (xy 133.289332 -345.281911)
			(xy 133.318819 -345.236031) (xy 133.354535 -345.194815) (xy 133.395753 -345.159102) (xy 133.441635 -345.129619)
			(xy 133.491246 -345.106965) (xy 133.543576 -345.091603) (xy 133.597559 -345.083845) (xy 133.624828 -345.083384)
			(xy 134.488428 -345.083384) (xy 134.515699 -345.08378) (xy 134.569686 -345.091546) (xy 134.622019 -345.106916)
			(xy 134.671632 -345.129576) (xy 134.717514 -345.159067) (xy 134.758734 -345.194786) (xy 134.79445 -345.236008)
			(xy 134.823937 -345.281893) (xy 134.846594 -345.331507) (xy 134.86196 -345.383841) (xy 134.869722 -345.437829)
			(xy 134.869722 -345.492366) (xy 136.35257 -345.492366) (xy 136.35257 -345.437834) (xy 136.360331 -345.383858)
			(xy 136.375694 -345.331536) (xy 136.398346 -345.281933) (xy 136.427827 -345.236058) (xy 136.463537 -345.194846)
			(xy 136.504748 -345.159135) (xy 136.550622 -345.129652) (xy 136.600225 -345.106998) (xy 136.652547 -345.091633)
			(xy 136.706522 -345.083871) (xy 136.733788 -345.083384) (xy 137.597388 -345.083384) (xy 137.624663 -345.083755)
			(xy 137.678657 -345.091516) (xy 137.730998 -345.106884) (xy 137.780619 -345.129543) (xy 137.826509 -345.159034)
			(xy 137.867736 -345.194756) (xy 137.903459 -345.235981) (xy 137.932951 -345.281871) (xy 137.955612 -345.331491)
			(xy 137.970981 -345.383831) (xy 137.978744 -345.437825) (xy 137.978744 -345.49237) (xy 139.461448 -345.49237)
			(xy 139.461448 -345.43783) (xy 139.46921 -345.383846) (xy 139.484577 -345.331515) (xy 139.507235 -345.281905)
			(xy 139.536724 -345.236024) (xy 139.572442 -345.194808) (xy 139.613663 -345.159095) (xy 139.659547 -345.129612)
			(xy 139.70916 -345.10696) (xy 139.761492 -345.0916) (xy 139.815478 -345.083844) (xy 139.842748 -345.083384)
			(xy 140.706348 -345.083384) (xy 140.733618 -345.083782) (xy 140.787603 -345.09155) (xy 140.839933 -345.106921)
			(xy 140.889544 -345.129583) (xy 140.935424 -345.159074) (xy 140.976641 -345.194793) (xy 141.012355 -345.236015)
			(xy 141.04184 -345.281899) (xy 141.064495 -345.331512) (xy 141.07986 -345.383844) (xy 141.087622 -345.43783)
			(xy 141.087622 -345.492368) (xy 142.570447 -345.492368) (xy 142.570447 -345.437832) (xy 142.578209 -345.383851)
			(xy 142.593574 -345.331524) (xy 142.616229 -345.281916) (xy 142.645714 -345.236038) (xy 142.681428 -345.194822)
			(xy 142.722644 -345.159109) (xy 142.768523 -345.129625) (xy 142.818131 -345.106971) (xy 142.870459 -345.091607)
			(xy 142.92444 -345.083847) (xy 142.951708 -345.083384) (xy 143.815308 -345.083384) (xy 143.84258 -345.083779)
			(xy 143.89657 -345.091543) (xy 143.948904 -345.106911) (xy 143.99852 -345.12957) (xy 144.044405 -345.15906)
			(xy 144.085627 -345.194779) (xy 144.121345 -345.236001) (xy 144.150834 -345.281888) (xy 144.173492 -345.331503)
			(xy 144.188859 -345.383838) (xy 144.196621 -345.437828) (xy 144.196621 -345.492365) (xy 164.91387 -345.492365)
			(xy 164.91387 -345.437835) (xy 164.92163 -345.383861) (xy 164.936992 -345.33154) (xy 164.959644 -345.281937)
			(xy 164.989123 -345.236063) (xy 165.024831 -345.194851) (xy 165.066041 -345.15914) (xy 165.111913 -345.129657)
			(xy 165.161513 -345.107002) (xy 165.213833 -345.091636) (xy 165.267807 -345.083872) (xy 165.295072 -345.083384)
			(xy 166.158672 -345.083384) (xy 166.185948 -345.083754) (xy 166.239944 -345.091514) (xy 166.292286 -345.106879)
			(xy 166.341909 -345.129538) (xy 166.387802 -345.159028) (xy 166.42903 -345.19475) (xy 166.464755 -345.235976)
			(xy 166.494249 -345.281866) (xy 166.516911 -345.331487) (xy 166.532281 -345.383829) (xy 166.540044 -345.437824)
			(xy 166.540044 -345.492369) (xy 168.022747 -345.492369) (xy 168.022747 -345.437831) (xy 168.03051 -345.383848)
			(xy 168.045876 -345.331519) (xy 168.068533 -345.281909) (xy 168.09802 -345.23603) (xy 168.133736 -345.194814)
			(xy 168.174955 -345.159101) (xy 168.220838 -345.129617) (xy 168.270449 -345.106964) (xy 168.322779 -345.091603)
			(xy 168.376763 -345.083845) (xy 168.404032 -345.083384) (xy 169.267632 -345.083384) (xy 169.294903 -345.083781)
			(xy 169.34889 -345.091547) (xy 169.401222 -345.106917) (xy 169.450834 -345.129578) (xy 169.496716 -345.159068)
			(xy 169.537935 -345.194788) (xy 169.573651 -345.236009) (xy 169.603138 -345.281894) (xy 169.625794 -345.331508)
			(xy 169.64116 -345.383842) (xy 169.648922 -345.437829) (xy 169.648922 -345.492366) (xy 171.13177 -345.492366)
			(xy 171.13177 -345.437834) (xy 171.139531 -345.383858) (xy 171.154894 -345.331535) (xy 171.177547 -345.281932)
			(xy 171.207028 -345.236057) (xy 171.242738 -345.194844) (xy 171.28395 -345.159133) (xy 171.329825 -345.129651)
			(xy 171.379428 -345.106997) (xy 171.43175 -345.091633) (xy 171.485726 -345.083871) (xy 171.512992 -345.083384)
			(xy 172.376592 -345.083384) (xy 172.403867 -345.083755) (xy 172.457861 -345.091517) (xy 172.510201 -345.106885)
			(xy 172.559821 -345.129544) (xy 172.605711 -345.159035) (xy 172.646937 -345.194757) (xy 172.68266 -345.235982)
			(xy 172.712152 -345.281872) (xy 172.734813 -345.331492) (xy 172.750181 -345.383831) (xy 172.757944 -345.437825)
			(xy 172.757944 -345.492364) (xy 174.24077 -345.492364) (xy 174.24077 -345.437836) (xy 174.24853 -345.383863)
			(xy 174.263891 -345.331544) (xy 174.286541 -345.281943) (xy 174.316019 -345.23607) (xy 174.351724 -345.194858)
			(xy 174.392931 -345.159147) (xy 174.438801 -345.129664) (xy 174.488399 -345.107008) (xy 174.540716 -345.09164)
			(xy 174.594688 -345.083874) (xy 174.621952 -345.083384) (xy 175.485552 -345.083384) (xy 175.512829 -345.083752)
			(xy 175.566827 -345.09151) (xy 175.619172 -345.106874) (xy 175.668797 -345.129531) (xy 175.714692 -345.159021)
			(xy 175.755923 -345.194743) (xy 175.79165 -345.235969) (xy 175.821146 -345.281861) (xy 175.843809 -345.331483)
			(xy 175.85918 -345.383826) (xy 175.866944 -345.437824) (xy 175.866944 -345.492368) (xy 177.349647 -345.492368)
			(xy 177.349647 -345.437832) (xy 177.357409 -345.38385) (xy 177.372774 -345.331523) (xy 177.39543 -345.281915)
			(xy 177.424915 -345.236036) (xy 177.460629 -345.194821) (xy 177.501846 -345.159108) (xy 177.547726 -345.129624)
			(xy 177.597334 -345.10697) (xy 177.649662 -345.091606) (xy 177.703644 -345.083847) (xy 177.730912 -345.083384)
			(xy 178.594512 -345.083384) (xy 178.621784 -345.083779) (xy 178.675773 -345.091543) (xy 178.728107 -345.106912)
			(xy 178.777722 -345.129571) (xy 178.823607 -345.159061) (xy 178.864828 -345.194781) (xy 178.900546 -345.236003)
			(xy 178.930035 -345.281889) (xy 178.952693 -345.331504) (xy 178.968059 -345.383839) (xy 178.975821 -345.437828)
			(xy 178.975821 -345.492365) (xy 180.45867 -345.492365) (xy 180.45867 -345.437835) (xy 180.46643 -345.383861)
			(xy 180.481792 -345.33154) (xy 180.504444 -345.281937) (xy 180.533923 -345.236063) (xy 180.569631 -345.194851)
			(xy 180.610841 -345.15914) (xy 180.656713 -345.129657) (xy 180.706313 -345.107002) (xy 180.758633 -345.091636)
			(xy 180.812607 -345.083872) (xy 180.839872 -345.083384) (xy 181.703472 -345.083384) (xy 181.730748 -345.083754)
			(xy 181.784744 -345.091514) (xy 181.837086 -345.106879) (xy 181.886709 -345.129538) (xy 181.932602 -345.159028)
			(xy 181.97383 -345.19475) (xy 182.009555 -345.235976) (xy 182.039049 -345.281866) (xy 182.061711 -345.331487)
			(xy 182.077081 -345.383829) (xy 182.084844 -345.437824) (xy 182.084844 -345.492369) (xy 183.567547 -345.492369)
			(xy 183.567547 -345.437831) (xy 183.57531 -345.383848) (xy 183.590676 -345.331519) (xy 183.613333 -345.281909)
			(xy 183.64282 -345.23603) (xy 183.678536 -345.194814) (xy 183.719755 -345.159101) (xy 183.765638 -345.129617)
			(xy 183.815249 -345.106964) (xy 183.867579 -345.091603) (xy 183.921563 -345.083845) (xy 183.948832 -345.083384)
			(xy 184.812432 -345.083384) (xy 184.839703 -345.083781) (xy 184.89369 -345.091547) (xy 184.946022 -345.106917)
			(xy 184.995634 -345.129578) (xy 185.041516 -345.159068) (xy 185.082735 -345.194788) (xy 185.118451 -345.236009)
			(xy 185.147938 -345.281894) (xy 185.170594 -345.331508) (xy 185.18596 -345.383842) (xy 185.193722 -345.437829)
			(xy 185.193722 -345.492366) (xy 186.67657 -345.492366) (xy 186.67657 -345.437834) (xy 186.684331 -345.383858)
			(xy 186.699694 -345.331535) (xy 186.722347 -345.281932) (xy 186.751828 -345.236057) (xy 186.787538 -345.194844)
			(xy 186.82875 -345.159133) (xy 186.874625 -345.129651) (xy 186.924228 -345.106997) (xy 186.97655 -345.091633)
			(xy 187.030526 -345.083871) (xy 187.057792 -345.083384) (xy 187.921392 -345.083384) (xy 187.948667 -345.083755)
			(xy 188.002661 -345.091517) (xy 188.055001 -345.106885) (xy 188.104621 -345.129544) (xy 188.150511 -345.159035)
			(xy 188.191737 -345.194757) (xy 188.22746 -345.235982) (xy 188.256952 -345.281872) (xy 188.279613 -345.331492)
			(xy 188.294981 -345.383831) (xy 188.302744 -345.437825) (xy 188.302744 -345.492364) (xy 189.78557 -345.492364)
			(xy 189.78557 -345.437836) (xy 189.79333 -345.383863) (xy 189.808691 -345.331544) (xy 189.831341 -345.281943)
			(xy 189.860819 -345.23607) (xy 189.896524 -345.194858) (xy 189.937731 -345.159147) (xy 189.983601 -345.129664)
			(xy 190.033199 -345.107008) (xy 190.085516 -345.09164) (xy 190.139488 -345.083874) (xy 190.166752 -345.083384)
			(xy 191.030352 -345.083384) (xy 191.057629 -345.083752) (xy 191.111627 -345.09151) (xy 191.163972 -345.106874)
			(xy 191.213597 -345.129531) (xy 191.259492 -345.159021) (xy 191.300723 -345.194743) (xy 191.33645 -345.235969)
			(xy 191.365946 -345.281861) (xy 191.388609 -345.331483) (xy 191.40398 -345.383826) (xy 191.411744 -345.437824)
			(xy 191.411744 -345.492368) (xy 192.894447 -345.492368) (xy 192.894447 -345.437832) (xy 192.902209 -345.38385)
			(xy 192.917574 -345.331523) (xy 192.94023 -345.281915) (xy 192.969715 -345.236036) (xy 193.005429 -345.194821)
			(xy 193.046646 -345.159108) (xy 193.092526 -345.129624) (xy 193.142134 -345.10697) (xy 193.194462 -345.091606)
			(xy 193.248444 -345.083847) (xy 193.275712 -345.083384) (xy 194.139312 -345.083384) (xy 194.166584 -345.083779)
			(xy 194.220573 -345.091543) (xy 194.272907 -345.106912) (xy 194.322522 -345.129571) (xy 194.368407 -345.159061)
			(xy 194.409628 -345.194781) (xy 194.445346 -345.236003) (xy 194.474835 -345.281889) (xy 194.497493 -345.331504)
			(xy 194.512859 -345.383839) (xy 194.520621 -345.437828) (xy 194.520621 -345.492365) (xy 196.00347 -345.492365)
			(xy 196.00347 -345.437835) (xy 196.01123 -345.383861) (xy 196.026592 -345.33154) (xy 196.049244 -345.281937)
			(xy 196.078723 -345.236063) (xy 196.114431 -345.194851) (xy 196.155641 -345.15914) (xy 196.201513 -345.129657)
			(xy 196.251113 -345.107002) (xy 196.303433 -345.091636) (xy 196.357407 -345.083872) (xy 196.384672 -345.083384)
			(xy 197.248272 -345.083384) (xy 197.275548 -345.083754) (xy 197.329544 -345.091514) (xy 197.381886 -345.106879)
			(xy 197.431509 -345.129538) (xy 197.477402 -345.159028) (xy 197.51863 -345.19475) (xy 197.554355 -345.235976)
			(xy 197.583849 -345.281866) (xy 197.606511 -345.331487) (xy 197.621881 -345.383829) (xy 197.629644 -345.437824)
			(xy 197.629644 -345.492368) (xy 267.515847 -345.492368) (xy 267.515847 -345.437832) (xy 267.523609 -345.383852)
			(xy 267.538973 -345.331525) (xy 267.561628 -345.281918) (xy 267.591112 -345.23604) (xy 267.626826 -345.194824)
			(xy 267.668041 -345.159111) (xy 267.71392 -345.129627) (xy 267.763527 -345.106972) (xy 267.815854 -345.091608)
			(xy 267.869834 -345.083847) (xy 267.897102 -345.083384) (xy 268.760702 -345.083384) (xy 268.787975 -345.083779)
			(xy 268.841964 -345.091542) (xy 268.8943 -345.106909) (xy 268.943916 -345.129568) (xy 268.989802 -345.159057)
			(xy 269.031024 -345.194777) (xy 269.066744 -345.236) (xy 269.096233 -345.281886) (xy 269.118892 -345.331502)
			(xy 269.134259 -345.383838) (xy 269.142021 -345.437827) (xy 269.142021 -345.492364) (xy 270.62487 -345.492364)
			(xy 270.62487 -345.437836) (xy 270.63263 -345.383862) (xy 270.647992 -345.331542) (xy 270.670642 -345.28194)
			(xy 270.700121 -345.236066) (xy 270.735828 -345.194855) (xy 270.777036 -345.159144) (xy 270.822907 -345.12966)
			(xy 270.872506 -345.107005) (xy 270.924825 -345.091638) (xy 270.978798 -345.083873) (xy 271.006062 -345.083384)
			(xy 271.869662 -345.083384) (xy 271.896938 -345.083753) (xy 271.950936 -345.091512) (xy 272.003279 -345.106877)
			(xy 272.052903 -345.129535) (xy 272.098797 -345.159025) (xy 272.140027 -345.194747) (xy 272.175752 -345.235973)
			(xy 272.205247 -345.281864) (xy 272.22791 -345.331485) (xy 272.24328 -345.383827) (xy 272.251044 -345.437824)
			(xy 272.251044 -345.492369) (xy 273.733747 -345.492369) (xy 273.733747 -345.437831) (xy 273.741509 -345.383849)
			(xy 273.756875 -345.331521) (xy 273.779531 -345.281912) (xy 273.809017 -345.236033) (xy 273.844733 -345.194817)
			(xy 273.885951 -345.159104) (xy 273.931832 -345.129621) (xy 273.981441 -345.106967) (xy 274.033771 -345.091605)
			(xy 274.087753 -345.083846) (xy 274.115022 -345.083384) (xy 274.978622 -345.083384) (xy 275.005894 -345.08378)
			(xy 275.059881 -345.091545) (xy 275.112215 -345.106914) (xy 275.161828 -345.129574) (xy 275.207712 -345.159064)
			(xy 275.248932 -345.194784) (xy 275.284649 -345.236006) (xy 275.314136 -345.281891) (xy 275.336793 -345.331506)
			(xy 275.352159 -345.38384) (xy 275.359922 -345.437828) (xy 275.359922 -345.492365) (xy 276.84277 -345.492365)
			(xy 276.84277 -345.437835) (xy 276.850531 -345.383859) (xy 276.865893 -345.331537) (xy 276.888545 -345.281934)
			(xy 276.918026 -345.23606) (xy 276.953735 -345.194848) (xy 276.994945 -345.159137) (xy 277.040819 -345.129654)
			(xy 277.090421 -345.106999) (xy 277.142742 -345.091634) (xy 277.196717 -345.083872) (xy 277.223982 -345.083384)
			(xy 278.087582 -345.083384) (xy 278.114857 -345.083754) (xy 278.168852 -345.091515) (xy 278.221194 -345.106882)
			(xy 278.270815 -345.129541) (xy 278.316706 -345.159032) (xy 278.357934 -345.194754) (xy 278.393657 -345.235979)
			(xy 278.42315 -345.281869) (xy 278.445812 -345.33149) (xy 278.461181 -345.38383) (xy 278.468944 -345.437825)
			(xy 278.468944 -345.49237) (xy 279.951648 -345.49237) (xy 279.951648 -345.43783) (xy 279.95941 -345.383846)
			(xy 279.974776 -345.331517) (xy 279.997434 -345.281907) (xy 280.026922 -345.236026) (xy 280.06264 -345.19481)
			(xy 280.10386 -345.159097) (xy 280.149744 -345.129614) (xy 280.199356 -345.106962) (xy 280.251687 -345.091601)
			(xy 280.305672 -345.083845) (xy 280.332942 -345.083384) (xy 281.196542 -345.083384) (xy 281.223813 -345.083781)
			(xy 281.277798 -345.091549) (xy 281.330129 -345.10692) (xy 281.37974 -345.129581) (xy 281.425621 -345.159072)
			(xy 281.466839 -345.194791) (xy 281.502554 -345.236013) (xy 281.532039 -345.281897) (xy 281.554695 -345.33151)
			(xy 281.57006 -345.383843) (xy 281.577822 -345.437829) (xy 281.577822 -345.492368) (xy 283.060647 -345.492368)
			(xy 283.060647 -345.437832) (xy 283.068409 -345.383852) (xy 283.083773 -345.331525) (xy 283.106428 -345.281918)
			(xy 283.135912 -345.23604) (xy 283.171626 -345.194824) (xy 283.212841 -345.159111) (xy 283.25872 -345.129627)
			(xy 283.308327 -345.106972) (xy 283.360654 -345.091608) (xy 283.414634 -345.083847) (xy 283.441902 -345.083384)
			(xy 284.305502 -345.083384) (xy 284.332775 -345.083779) (xy 284.386764 -345.091542) (xy 284.4391 -345.106909)
			(xy 284.488716 -345.129568) (xy 284.534602 -345.159057) (xy 284.575824 -345.194777) (xy 284.611544 -345.236)
			(xy 284.641033 -345.281886) (xy 284.663692 -345.331502) (xy 284.679059 -345.383838) (xy 284.686821 -345.437827)
			(xy 284.686821 -345.492364) (xy 286.16967 -345.492364) (xy 286.16967 -345.437836) (xy 286.17743 -345.383862)
			(xy 286.192792 -345.331542) (xy 286.215442 -345.28194) (xy 286.244921 -345.236066) (xy 286.280628 -345.194855)
			(xy 286.321836 -345.159144) (xy 286.367707 -345.12966) (xy 286.417306 -345.107005) (xy 286.469625 -345.091638)
			(xy 286.523598 -345.083873) (xy 286.550862 -345.083384) (xy 287.414462 -345.083384) (xy 287.441738 -345.083753)
			(xy 287.495736 -345.091512) (xy 287.548079 -345.106877) (xy 287.597703 -345.129535) (xy 287.643597 -345.159025)
			(xy 287.684827 -345.194747) (xy 287.720552 -345.235973) (xy 287.750047 -345.281864) (xy 287.77271 -345.331485)
			(xy 287.78808 -345.383827) (xy 287.795844 -345.437824) (xy 287.795844 -345.492369) (xy 289.278547 -345.492369)
			(xy 289.278547 -345.437831) (xy 289.286309 -345.383849) (xy 289.301675 -345.331521) (xy 289.324331 -345.281912)
			(xy 289.353817 -345.236033) (xy 289.389533 -345.194817) (xy 289.430751 -345.159104) (xy 289.476632 -345.129621)
			(xy 289.526241 -345.106967) (xy 289.578571 -345.091605) (xy 289.632553 -345.083846) (xy 289.659822 -345.083384)
			(xy 290.523422 -345.083384) (xy 290.550694 -345.08378) (xy 290.604681 -345.091545) (xy 290.657015 -345.106914)
			(xy 290.706628 -345.129574) (xy 290.752512 -345.159064) (xy 290.793732 -345.194784) (xy 290.829449 -345.236006)
			(xy 290.858936 -345.281891) (xy 290.881593 -345.331506) (xy 290.896959 -345.38384) (xy 290.904722 -345.437828)
			(xy 290.904722 -345.492365) (xy 292.38757 -345.492365) (xy 292.38757 -345.437835) (xy 292.395331 -345.383859)
			(xy 292.410693 -345.331537) (xy 292.433345 -345.281934) (xy 292.462826 -345.23606) (xy 292.498535 -345.194848)
			(xy 292.539745 -345.159137) (xy 292.585619 -345.129654) (xy 292.635221 -345.106999) (xy 292.687542 -345.091634)
			(xy 292.741517 -345.083872) (xy 292.768782 -345.083384) (xy 293.632382 -345.083384) (xy 293.659657 -345.083754)
			(xy 293.713652 -345.091515) (xy 293.765994 -345.106882) (xy 293.815615 -345.129541) (xy 293.861506 -345.159032)
			(xy 293.902734 -345.194754) (xy 293.938457 -345.235979) (xy 293.96795 -345.281869) (xy 293.990612 -345.33149)
			(xy 294.005981 -345.38383) (xy 294.013744 -345.437825) (xy 294.013744 -345.49237) (xy 295.496448 -345.49237)
			(xy 295.496448 -345.43783) (xy 295.50421 -345.383846) (xy 295.519576 -345.331517) (xy 295.542234 -345.281907)
			(xy 295.571722 -345.236026) (xy 295.60744 -345.19481) (xy 295.64866 -345.159097) (xy 295.694544 -345.129614)
			(xy 295.744156 -345.106962) (xy 295.796487 -345.091601) (xy 295.850472 -345.083845) (xy 295.877742 -345.083384)
			(xy 296.741342 -345.083384) (xy 296.768613 -345.083781) (xy 296.822598 -345.091549) (xy 296.874929 -345.10692)
			(xy 296.92454 -345.129581) (xy 296.970421 -345.159072) (xy 297.011639 -345.194791) (xy 297.047354 -345.236013)
			(xy 297.076839 -345.281897) (xy 297.099495 -345.33151) (xy 297.11486 -345.383843) (xy 297.122622 -345.437829)
			(xy 297.122622 -345.492368) (xy 298.605447 -345.492368) (xy 298.605447 -345.437832) (xy 298.613209 -345.383852)
			(xy 298.628573 -345.331525) (xy 298.651228 -345.281918) (xy 298.680712 -345.23604) (xy 298.716426 -345.194824)
			(xy 298.757641 -345.159111) (xy 298.80352 -345.129627) (xy 298.853127 -345.106972) (xy 298.905454 -345.091608)
			(xy 298.959434 -345.083847) (xy 298.986702 -345.083384) (xy 299.850302 -345.083384) (xy 299.877575 -345.083779)
			(xy 299.931564 -345.091542) (xy 299.9839 -345.106909) (xy 300.033516 -345.129568) (xy 300.079402 -345.159057)
			(xy 300.120624 -345.194777) (xy 300.156344 -345.236) (xy 300.185833 -345.281886) (xy 300.208492 -345.331502)
			(xy 300.223859 -345.383838) (xy 300.231621 -345.437827) (xy 300.231621 -345.492368) (xy 312.121547 -345.492368)
			(xy 312.121547 -345.437832) (xy 312.129309 -345.383851) (xy 312.144673 -345.331525) (xy 312.167328 -345.281917)
			(xy 312.196813 -345.236039) (xy 312.232526 -345.194824) (xy 312.273742 -345.159111) (xy 312.319621 -345.129627)
			(xy 312.369228 -345.106972) (xy 312.421555 -345.091608) (xy 312.475536 -345.083847) (xy 312.502804 -345.083384)
			(xy 313.366404 -345.083384) (xy 313.393676 -345.083779) (xy 313.447666 -345.091542) (xy 313.500001 -345.106909)
			(xy 313.549617 -345.129569) (xy 313.595503 -345.159058) (xy 313.636725 -345.194778) (xy 313.672444 -345.236)
			(xy 313.701933 -345.281886) (xy 313.724592 -345.331502) (xy 313.739959 -345.383838) (xy 313.747721 -345.437828)
			(xy 313.747721 -345.492364) (xy 315.23057 -345.492364) (xy 315.23057 -345.437836) (xy 315.23833 -345.383862)
			(xy 315.253692 -345.331541) (xy 315.276343 -345.281939) (xy 315.305821 -345.236066) (xy 315.341529 -345.194854)
			(xy 315.382737 -345.159143) (xy 315.428608 -345.12966) (xy 315.478207 -345.107004) (xy 315.530526 -345.091638)
			(xy 315.5845 -345.083873) (xy 315.611764 -345.083384) (xy 316.475364 -345.083384) (xy 316.50264 -345.083753)
			(xy 316.556637 -345.091512) (xy 316.608981 -345.106877) (xy 316.658604 -345.129535) (xy 316.704498 -345.159026)
			(xy 316.745727 -345.194747) (xy 316.781453 -345.235973) (xy 316.810947 -345.281864) (xy 316.83361 -345.331486)
			(xy 316.84898 -345.383828) (xy 316.856744 -345.437824) (xy 316.856744 -345.492369) (xy 318.339447 -345.492369)
			(xy 318.339447 -345.437831) (xy 318.347209 -345.383849) (xy 318.362575 -345.33152) (xy 318.385231 -345.281912)
			(xy 318.414718 -345.236032) (xy 318.450434 -345.194817) (xy 318.491652 -345.159103) (xy 318.537533 -345.12962)
			(xy 318.587143 -345.106966) (xy 318.639472 -345.091604) (xy 318.693455 -345.083846) (xy 318.720724 -345.083384)
			(xy 319.584324 -345.083384) (xy 319.611596 -345.08378) (xy 319.665583 -345.091546) (xy 319.717916 -345.106915)
			(xy 319.767529 -345.129575) (xy 319.813413 -345.159065) (xy 319.854632 -345.194785) (xy 319.890349 -345.236007)
			(xy 319.919836 -345.281892) (xy 319.942494 -345.331507) (xy 319.95786 -345.38384) (xy 319.965622 -345.437828)
			(xy 319.965622 -345.492365) (xy 321.44847 -345.492365) (xy 321.44847 -345.437835) (xy 321.456231 -345.383859)
			(xy 321.471593 -345.331537) (xy 321.494246 -345.281934) (xy 321.523726 -345.236059) (xy 321.559436 -345.194847)
			(xy 321.600646 -345.159136) (xy 321.64652 -345.129653) (xy 321.696122 -345.106999) (xy 321.748443 -345.091634)
			(xy 321.802419 -345.083871) (xy 321.829684 -345.083384) (xy 322.693284 -345.083384) (xy 322.720559 -345.083755)
			(xy 322.774554 -345.091516) (xy 322.826895 -345.106882) (xy 322.876516 -345.129542) (xy 322.922407 -345.159033)
			(xy 322.963634 -345.194754) (xy 322.999358 -345.23598) (xy 323.02885 -345.28187) (xy 323.051512 -345.33149)
			(xy 323.066881 -345.38383) (xy 323.074644 -345.437825) (xy 323.074644 -345.49237) (xy 324.557348 -345.49237)
			(xy 324.557348 -345.43783) (xy 324.56511 -345.383846) (xy 324.580476 -345.331516) (xy 324.603135 -345.281906)
			(xy 324.632623 -345.236026) (xy 324.668341 -345.194809) (xy 324.709561 -345.159096) (xy 324.755445 -345.129613)
			(xy 324.805057 -345.106961) (xy 324.857389 -345.0916) (xy 324.911374 -345.083844) (xy 324.938644 -345.083384)
			(xy 325.802244 -345.083384) (xy 325.829515 -345.083782) (xy 325.8835 -345.091549) (xy 325.93583 -345.10692)
			(xy 325.985441 -345.129582) (xy 326.031322 -345.159072) (xy 326.072539 -345.194792) (xy 326.108254 -345.236013)
			(xy 326.137739 -345.281898) (xy 326.160395 -345.331511) (xy 326.17576 -345.383843) (xy 326.183522 -345.437829)
			(xy 326.183522 -345.492368) (xy 327.666347 -345.492368) (xy 327.666347 -345.437832) (xy 327.674109 -345.383851)
			(xy 327.689473 -345.331525) (xy 327.712128 -345.281917) (xy 327.741613 -345.236039) (xy 327.777326 -345.194824)
			(xy 327.818542 -345.159111) (xy 327.864421 -345.129627) (xy 327.914028 -345.106972) (xy 327.966355 -345.091608)
			(xy 328.020336 -345.083847) (xy 328.047604 -345.083384) (xy 328.911204 -345.083384) (xy 328.938476 -345.083779)
			(xy 328.992466 -345.091542) (xy 329.044801 -345.106909) (xy 329.094417 -345.129569) (xy 329.140303 -345.159058)
			(xy 329.181525 -345.194778) (xy 329.217244 -345.236) (xy 329.246733 -345.281886) (xy 329.269392 -345.331502)
			(xy 329.284759 -345.383838) (xy 329.292521 -345.437828) (xy 329.292521 -345.492364) (xy 330.77537 -345.492364)
			(xy 330.77537 -345.437836) (xy 330.78313 -345.383862) (xy 330.798492 -345.331541) (xy 330.821143 -345.281939)
			(xy 330.850621 -345.236066) (xy 330.886329 -345.194854) (xy 330.927537 -345.159143) (xy 330.973408 -345.12966)
			(xy 331.023007 -345.107004) (xy 331.075326 -345.091638) (xy 331.1293 -345.083873) (xy 331.156564 -345.083384)
			(xy 332.020164 -345.083384) (xy 332.04744 -345.083753) (xy 332.101437 -345.091512) (xy 332.153781 -345.106877)
			(xy 332.203404 -345.129535) (xy 332.249298 -345.159026) (xy 332.290527 -345.194747) (xy 332.326253 -345.235973)
			(xy 332.355747 -345.281864) (xy 332.37841 -345.331486) (xy 332.39378 -345.383828) (xy 332.401544 -345.437824)
			(xy 332.401544 -345.492369) (xy 333.884247 -345.492369) (xy 333.884247 -345.437831) (xy 333.892009 -345.383849)
			(xy 333.907375 -345.33152) (xy 333.930031 -345.281912) (xy 333.959518 -345.236032) (xy 333.995234 -345.194817)
			(xy 334.036452 -345.159103) (xy 334.082333 -345.12962) (xy 334.131943 -345.106966) (xy 334.184272 -345.091604)
			(xy 334.238255 -345.083846) (xy 334.265524 -345.083384) (xy 335.129124 -345.083384) (xy 335.156396 -345.08378)
			(xy 335.210383 -345.091546) (xy 335.262716 -345.106915) (xy 335.312329 -345.129575) (xy 335.358213 -345.159065)
			(xy 335.399432 -345.194785) (xy 335.435149 -345.236007) (xy 335.464636 -345.281892) (xy 335.487294 -345.331507)
			(xy 335.50266 -345.38384) (xy 335.510422 -345.437828) (xy 335.510422 -345.492365) (xy 336.99327 -345.492365)
			(xy 336.99327 -345.437835) (xy 337.001031 -345.383859) (xy 337.016393 -345.331537) (xy 337.039046 -345.281934)
			(xy 337.068526 -345.236059) (xy 337.104236 -345.194847) (xy 337.145446 -345.159136) (xy 337.19132 -345.129653)
			(xy 337.240922 -345.106999) (xy 337.293243 -345.091634) (xy 337.347219 -345.083871) (xy 337.374484 -345.083384)
			(xy 338.238084 -345.083384) (xy 338.265359 -345.083755) (xy 338.319354 -345.091516) (xy 338.371695 -345.106882)
			(xy 338.421316 -345.129542) (xy 338.467207 -345.159033) (xy 338.508434 -345.194754) (xy 338.544158 -345.23598)
			(xy 338.57365 -345.28187) (xy 338.596312 -345.33149) (xy 338.611681 -345.38383) (xy 338.619444 -345.437825)
			(xy 338.619444 -345.49237) (xy 340.102148 -345.49237) (xy 340.102148 -345.43783) (xy 340.10991 -345.383846)
			(xy 340.125276 -345.331516) (xy 340.147935 -345.281906) (xy 340.177423 -345.236026) (xy 340.213141 -345.194809)
			(xy 340.254361 -345.159096) (xy 340.300245 -345.129613) (xy 340.349857 -345.106961) (xy 340.402189 -345.0916)
			(xy 340.456174 -345.083844) (xy 340.483444 -345.083384) (xy 341.347044 -345.083384) (xy 341.374315 -345.083782)
			(xy 341.4283 -345.091549) (xy 341.48063 -345.10692) (xy 341.530241 -345.129582) (xy 341.576122 -345.159072)
			(xy 341.617339 -345.194792) (xy 341.653054 -345.236013) (xy 341.682539 -345.281898) (xy 341.705195 -345.331511)
			(xy 341.72056 -345.383843) (xy 341.728322 -345.437829) (xy 341.728322 -345.492368) (xy 343.211147 -345.492368)
			(xy 343.211147 -345.437832) (xy 343.218909 -345.383851) (xy 343.234273 -345.331525) (xy 343.256928 -345.281917)
			(xy 343.286413 -345.236039) (xy 343.322126 -345.194824) (xy 343.363342 -345.159111) (xy 343.409221 -345.129627)
			(xy 343.458828 -345.106972) (xy 343.511155 -345.091608) (xy 343.565136 -345.083847) (xy 343.592404 -345.083384)
			(xy 344.456004 -345.083384) (xy 344.483276 -345.083779) (xy 344.537266 -345.091542) (xy 344.589601 -345.106909)
			(xy 344.639217 -345.129569) (xy 344.685103 -345.159058) (xy 344.726325 -345.194778) (xy 344.762044 -345.236)
			(xy 344.791533 -345.281886) (xy 344.814192 -345.331502) (xy 344.829559 -345.383838) (xy 344.837321 -345.437828)
			(xy 344.837321 -345.492365) (xy 370.80677 -345.492365) (xy 370.80677 -345.437835) (xy 370.81453 -345.383859)
			(xy 370.829893 -345.331538) (xy 370.852545 -345.281935) (xy 370.882025 -345.236061) (xy 370.917734 -345.194848)
			(xy 370.958945 -345.159137) (xy 371.004817 -345.129655) (xy 371.054419 -345.107) (xy 371.10674 -345.091635)
			(xy 371.160715 -345.083872) (xy 371.18798 -345.083384) (xy 372.05158 -345.083384) (xy 372.078855 -345.083754)
			(xy 372.132851 -345.091515) (xy 372.185192 -345.106881) (xy 372.234814 -345.129541) (xy 372.280705 -345.159031)
			(xy 372.321933 -345.194753) (xy 372.357657 -345.235978) (xy 372.38715 -345.281869) (xy 372.409812 -345.331489)
			(xy 372.425181 -345.38383) (xy 372.432944 -345.437825) (xy 372.432944 -345.49237) (xy 373.915647 -345.49237)
			(xy 373.915647 -345.43783) (xy 373.92341 -345.383847) (xy 373.938776 -345.331517) (xy 373.961434 -345.281907)
			(xy 373.990922 -345.236027) (xy 374.026639 -345.194811) (xy 374.067859 -345.159098) (xy 374.113742 -345.129615)
			(xy 374.163355 -345.106962) (xy 374.215686 -345.091601) (xy 374.26967 -345.083845) (xy 374.29694 -345.083384)
			(xy 375.16054 -345.083384) (xy 375.187811 -345.083781) (xy 375.241797 -345.091549) (xy 375.294128 -345.106919)
			(xy 375.343739 -345.12958) (xy 375.38962 -345.159071) (xy 375.430838 -345.19479) (xy 375.466553 -345.236012)
			(xy 375.496039 -345.281896) (xy 375.518695 -345.33151) (xy 375.53406 -345.383843) (xy 375.541822 -345.437829)
			(xy 375.541822 -345.492366) (xy 377.02467 -345.492366) (xy 377.02467 -345.437834) (xy 377.032431 -345.383857)
			(xy 377.047795 -345.331534) (xy 377.070448 -345.281929) (xy 377.09993 -345.236054) (xy 377.135641 -345.194841)
			(xy 377.176854 -345.15913) (xy 377.222729 -345.129648) (xy 377.272334 -345.106995) (xy 377.324657 -345.091631)
			(xy 377.378634 -345.08387) (xy 377.4059 -345.083384) (xy 378.2695 -345.083384) (xy 378.296773 -345.083779)
			(xy 378.350763 -345.091541) (xy 378.403099 -345.106908) (xy 378.452715 -345.129567) (xy 378.498601 -345.159057)
			(xy 378.539824 -345.194776) (xy 378.575543 -345.235999) (xy 378.605033 -345.281885) (xy 378.627692 -345.331501)
			(xy 378.643059 -345.383837) (xy 378.650821 -345.437827) (xy 378.650821 -345.492364) (xy 380.13367 -345.492364)
			(xy 380.13367 -345.437836) (xy 380.14143 -345.383862) (xy 380.156791 -345.331542) (xy 380.179442 -345.281941)
			(xy 380.208921 -345.236067) (xy 380.244627 -345.194855) (xy 380.285835 -345.159145) (xy 380.331705 -345.129661)
			(xy 380.381305 -345.107005) (xy 380.433623 -345.091638) (xy 380.487596 -345.083873) (xy 380.51486 -345.083384)
			(xy 381.37846 -345.083384) (xy 381.405736 -345.083753) (xy 381.459734 -345.091511) (xy 381.512078 -345.106876)
			(xy 381.561702 -345.129534) (xy 381.607596 -345.159024) (xy 381.648826 -345.194746) (xy 381.684552 -345.235972)
			(xy 381.714047 -345.281863) (xy 381.73671 -345.331485) (xy 381.75208 -345.383827) (xy 381.759844 -345.437824)
			(xy 381.759844 -345.492369) (xy 383.242547 -345.492369) (xy 383.242547 -345.437831) (xy 383.250309 -345.383849)
			(xy 383.265675 -345.331521) (xy 383.288331 -345.281913) (xy 383.317817 -345.236034) (xy 383.353532 -345.194818)
			(xy 383.39475 -345.159105) (xy 383.44063 -345.129621) (xy 383.49024 -345.106968) (xy 383.542569 -345.091605)
			(xy 383.596551 -345.083846) (xy 383.62382 -345.083384) (xy 384.48742 -345.083384) (xy 384.514692 -345.08378)
			(xy 384.56868 -345.091545) (xy 384.621013 -345.106914) (xy 384.670627 -345.129574) (xy 384.716511 -345.159064)
			(xy 384.757731 -345.194783) (xy 384.793448 -345.236005) (xy 384.822936 -345.281891) (xy 384.845593 -345.331506)
			(xy 384.860959 -345.38384) (xy 384.868722 -345.437828) (xy 384.868722 -345.492365) (xy 386.35157 -345.492365)
			(xy 386.35157 -345.437835) (xy 386.35933 -345.383859) (xy 386.374693 -345.331538) (xy 386.397345 -345.281935)
			(xy 386.426825 -345.236061) (xy 386.462534 -345.194848) (xy 386.503745 -345.159137) (xy 386.549617 -345.129655)
			(xy 386.599219 -345.107) (xy 386.65154 -345.091635) (xy 386.705515 -345.083872) (xy 386.73278 -345.083384)
			(xy 387.59638 -345.083384) (xy 387.623655 -345.083754) (xy 387.677651 -345.091515) (xy 387.729992 -345.106881)
			(xy 387.779614 -345.129541) (xy 387.825505 -345.159031) (xy 387.866733 -345.194753) (xy 387.902457 -345.235978)
			(xy 387.93195 -345.281869) (xy 387.954612 -345.331489) (xy 387.969981 -345.38383) (xy 387.977744 -345.437825)
			(xy 387.977744 -345.49237) (xy 389.460447 -345.49237) (xy 389.460447 -345.43783) (xy 389.46821 -345.383847)
			(xy 389.483576 -345.331517) (xy 389.506234 -345.281907) (xy 389.535722 -345.236027) (xy 389.571439 -345.194811)
			(xy 389.612659 -345.159098) (xy 389.658542 -345.129615) (xy 389.708155 -345.106962) (xy 389.760486 -345.091601)
			(xy 389.81447 -345.083845) (xy 389.84174 -345.083384) (xy 390.70534 -345.083384) (xy 390.732611 -345.083781)
			(xy 390.786597 -345.091549) (xy 390.838928 -345.106919) (xy 390.888539 -345.12958) (xy 390.93442 -345.159071)
			(xy 390.975638 -345.19479) (xy 391.011353 -345.236012) (xy 391.040839 -345.281896) (xy 391.063495 -345.33151)
			(xy 391.07886 -345.383843) (xy 391.086622 -345.437829) (xy 391.086622 -345.492366) (xy 392.56947 -345.492366)
			(xy 392.56947 -345.437834) (xy 392.577231 -345.383857) (xy 392.592595 -345.331534) (xy 392.615248 -345.281929)
			(xy 392.64473 -345.236054) (xy 392.680441 -345.194841) (xy 392.721654 -345.15913) (xy 392.767529 -345.129648)
			(xy 392.817134 -345.106995) (xy 392.869457 -345.091631) (xy 392.923434 -345.08387) (xy 392.9507 -345.083384)
			(xy 393.8143 -345.083384) (xy 393.841573 -345.083779) (xy 393.895563 -345.091541) (xy 393.947899 -345.106908)
			(xy 393.997515 -345.129567) (xy 394.043401 -345.159057) (xy 394.084624 -345.194776) (xy 394.120343 -345.235999)
			(xy 394.149833 -345.281885) (xy 394.172492 -345.331501) (xy 394.187859 -345.383837) (xy 394.195621 -345.437827)
			(xy 394.195621 -345.492364) (xy 395.67847 -345.492364) (xy 395.67847 -345.437836) (xy 395.68623 -345.383862)
			(xy 395.701591 -345.331542) (xy 395.724242 -345.281941) (xy 395.753721 -345.236067) (xy 395.789427 -345.194855)
			(xy 395.830635 -345.159145) (xy 395.876505 -345.129661) (xy 395.926105 -345.107005) (xy 395.978423 -345.091638)
			(xy 396.032396 -345.083873) (xy 396.05966 -345.083384) (xy 396.92326 -345.083384) (xy 396.950536 -345.083753)
			(xy 397.004534 -345.091511) (xy 397.056878 -345.106876) (xy 397.106502 -345.129534) (xy 397.152396 -345.159024)
			(xy 397.193626 -345.194746) (xy 397.229352 -345.235972) (xy 397.258847 -345.281863) (xy 397.28151 -345.331485)
			(xy 397.29688 -345.383827) (xy 397.304644 -345.437824) (xy 397.304644 -345.492369) (xy 398.787347 -345.492369)
			(xy 398.787347 -345.437831) (xy 398.795109 -345.383849) (xy 398.810475 -345.331521) (xy 398.833131 -345.281913)
			(xy 398.862617 -345.236034) (xy 398.898332 -345.194818) (xy 398.93955 -345.159105) (xy 398.98543 -345.129621)
			(xy 399.03504 -345.106968) (xy 399.087369 -345.091605) (xy 399.141351 -345.083846) (xy 399.16862 -345.083384)
			(xy 400.03222 -345.083384) (xy 400.059492 -345.08378) (xy 400.11348 -345.091545) (xy 400.165813 -345.106914)
			(xy 400.215427 -345.129574) (xy 400.261311 -345.159064) (xy 400.302531 -345.194783) (xy 400.338248 -345.236005)
			(xy 400.367736 -345.281891) (xy 400.390393 -345.331506) (xy 400.405759 -345.38384) (xy 400.413522 -345.437828)
			(xy 400.413522 -345.492365) (xy 401.89637 -345.492365) (xy 401.89637 -345.437835) (xy 401.90413 -345.383859)
			(xy 401.919493 -345.331538) (xy 401.942145 -345.281935) (xy 401.971625 -345.236061) (xy 402.007334 -345.194848)
			(xy 402.048545 -345.159137) (xy 402.094417 -345.129655) (xy 402.144019 -345.107) (xy 402.19634 -345.091635)
			(xy 402.250315 -345.083872) (xy 402.27758 -345.083384) (xy 403.14118 -345.083384) (xy 403.168455 -345.083754)
			(xy 403.222451 -345.091515) (xy 403.274792 -345.106881) (xy 403.324414 -345.129541) (xy 403.370305 -345.159031)
			(xy 403.411533 -345.194753) (xy 403.447257 -345.235978) (xy 403.47675 -345.281869) (xy 403.499412 -345.331489)
			(xy 403.514781 -345.38383) (xy 403.522544 -345.437825) (xy 403.522544 -345.492366) (xy 408.91387 -345.492366)
			(xy 408.91387 -345.437834) (xy 408.921631 -345.383858) (xy 408.936994 -345.331535) (xy 408.959647 -345.281932)
			(xy 408.989128 -345.236057) (xy 409.024838 -345.194844) (xy 409.06605 -345.159133) (xy 409.111925 -345.129651)
			(xy 409.161528 -345.106997) (xy 409.21385 -345.091633) (xy 409.267826 -345.083871) (xy 409.295092 -345.083384)
			(xy 410.158692 -345.083384) (xy 410.185967 -345.083755) (xy 410.239961 -345.091517) (xy 410.292301 -345.106885)
			(xy 410.341921 -345.129544) (xy 410.387811 -345.159035) (xy 410.429037 -345.194757) (xy 410.46476 -345.235982)
			(xy 410.494252 -345.281872) (xy 410.516913 -345.331492) (xy 410.532281 -345.383831) (xy 410.540044 -345.437825)
			(xy 410.540044 -345.492364) (xy 412.02287 -345.492364) (xy 412.02287 -345.437836) (xy 412.03063 -345.383863)
			(xy 412.045991 -345.331544) (xy 412.068641 -345.281943) (xy 412.098119 -345.23607) (xy 412.133824 -345.194858)
			(xy 412.175031 -345.159147) (xy 412.220901 -345.129664) (xy 412.270499 -345.107008) (xy 412.322816 -345.09164)
			(xy 412.376788 -345.083874) (xy 412.404052 -345.083384) (xy 413.267652 -345.083384) (xy 413.294929 -345.083752)
			(xy 413.348927 -345.09151) (xy 413.401272 -345.106874) (xy 413.450897 -345.129531) (xy 413.496792 -345.159021)
			(xy 413.538023 -345.194743) (xy 413.57375 -345.235969) (xy 413.603246 -345.281861) (xy 413.625909 -345.331483)
			(xy 413.64128 -345.383826) (xy 413.649044 -345.437824) (xy 413.649044 -345.492368) (xy 415.131747 -345.492368)
			(xy 415.131747 -345.437832) (xy 415.139509 -345.38385) (xy 415.154874 -345.331523) (xy 415.17753 -345.281915)
			(xy 415.207015 -345.236036) (xy 415.242729 -345.194821) (xy 415.283946 -345.159108) (xy 415.329826 -345.129624)
			(xy 415.379434 -345.10697) (xy 415.431762 -345.091606) (xy 415.485744 -345.083847) (xy 415.513012 -345.083384)
			(xy 416.376612 -345.083384) (xy 416.403884 -345.083779) (xy 416.457873 -345.091543) (xy 416.510207 -345.106912)
			(xy 416.559822 -345.129571) (xy 416.605707 -345.159061) (xy 416.646928 -345.194781) (xy 416.682646 -345.236003)
			(xy 416.712135 -345.281889) (xy 416.734793 -345.331504) (xy 416.750159 -345.383839) (xy 416.757921 -345.437828)
			(xy 416.757921 -345.492365) (xy 418.24077 -345.492365) (xy 418.24077 -345.437835) (xy 418.24853 -345.383861)
			(xy 418.263892 -345.33154) (xy 418.286544 -345.281937) (xy 418.316023 -345.236063) (xy 418.351731 -345.194851)
			(xy 418.392941 -345.15914) (xy 418.438813 -345.129657) (xy 418.488413 -345.107002) (xy 418.540733 -345.091636)
			(xy 418.594707 -345.083872) (xy 418.621972 -345.083384) (xy 419.485572 -345.083384) (xy 419.512848 -345.083754)
			(xy 419.566844 -345.091514) (xy 419.619186 -345.106879) (xy 419.668809 -345.129538) (xy 419.714702 -345.159028)
			(xy 419.75593 -345.19475) (xy 419.791655 -345.235976) (xy 419.821149 -345.281866) (xy 419.843811 -345.331487)
			(xy 419.859181 -345.383829) (xy 419.866944 -345.437824) (xy 419.866944 -345.492369) (xy 421.349647 -345.492369)
			(xy 421.349647 -345.437831) (xy 421.35741 -345.383848) (xy 421.372776 -345.331519) (xy 421.395433 -345.281909)
			(xy 421.42492 -345.23603) (xy 421.460636 -345.194814) (xy 421.501855 -345.159101) (xy 421.547738 -345.129617)
			(xy 421.597349 -345.106964) (xy 421.649679 -345.091603) (xy 421.703663 -345.083845) (xy 421.730932 -345.083384)
			(xy 422.594532 -345.083384) (xy 422.621803 -345.083781) (xy 422.67579 -345.091547) (xy 422.728122 -345.106917)
			(xy 422.777734 -345.129578) (xy 422.823616 -345.159068) (xy 422.864835 -345.194788) (xy 422.900551 -345.236009)
			(xy 422.930038 -345.281894) (xy 422.952694 -345.331508) (xy 422.96806 -345.383842) (xy 422.975822 -345.437829)
			(xy 422.975822 -345.492366) (xy 424.45867 -345.492366) (xy 424.45867 -345.437834) (xy 424.466431 -345.383858)
			(xy 424.481794 -345.331535) (xy 424.504447 -345.281932) (xy 424.533928 -345.236057) (xy 424.569638 -345.194844)
			(xy 424.61085 -345.159133) (xy 424.656725 -345.129651) (xy 424.706328 -345.106997) (xy 424.75865 -345.091633)
			(xy 424.812626 -345.083871) (xy 424.839892 -345.083384) (xy 425.703492 -345.083384) (xy 425.730767 -345.083755)
			(xy 425.784761 -345.091517) (xy 425.837101 -345.106885) (xy 425.886721 -345.129544) (xy 425.932611 -345.159035)
			(xy 425.973837 -345.194757) (xy 426.00956 -345.235982) (xy 426.039052 -345.281872) (xy 426.061713 -345.331492)
			(xy 426.077081 -345.383831) (xy 426.084844 -345.437825) (xy 426.084844 -345.492364) (xy 427.56767 -345.492364)
			(xy 427.56767 -345.437836) (xy 427.57543 -345.383863) (xy 427.590791 -345.331544) (xy 427.613441 -345.281943)
			(xy 427.642919 -345.23607) (xy 427.678624 -345.194858) (xy 427.719831 -345.159147) (xy 427.765701 -345.129664)
			(xy 427.815299 -345.107008) (xy 427.867616 -345.09164) (xy 427.921588 -345.083874) (xy 427.948852 -345.083384)
			(xy 428.812452 -345.083384) (xy 428.839729 -345.083752) (xy 428.893727 -345.09151) (xy 428.946072 -345.106874)
			(xy 428.995697 -345.129531) (xy 429.041592 -345.159021) (xy 429.082823 -345.194743) (xy 429.11855 -345.235969)
			(xy 429.148046 -345.281861) (xy 429.170709 -345.331483) (xy 429.18608 -345.383826) (xy 429.193844 -345.437824)
			(xy 429.193844 -345.492368) (xy 430.676547 -345.492368) (xy 430.676547 -345.437832) (xy 430.684309 -345.38385)
			(xy 430.699674 -345.331523) (xy 430.72233 -345.281915) (xy 430.751815 -345.236036) (xy 430.787529 -345.194821)
			(xy 430.828746 -345.159108) (xy 430.874626 -345.129624) (xy 430.924234 -345.10697) (xy 430.976562 -345.091606)
			(xy 431.030544 -345.083847) (xy 431.057812 -345.083384) (xy 431.921412 -345.083384) (xy 431.948684 -345.083779)
			(xy 432.002673 -345.091543) (xy 432.055007 -345.106912) (xy 432.104622 -345.129571) (xy 432.150507 -345.159061)
			(xy 432.191728 -345.194781) (xy 432.227446 -345.236003) (xy 432.256935 -345.281889) (xy 432.279593 -345.331504)
			(xy 432.294959 -345.383839) (xy 432.302721 -345.437828) (xy 432.302721 -345.492365) (xy 433.78557 -345.492365)
			(xy 433.78557 -345.437835) (xy 433.79333 -345.383861) (xy 433.808692 -345.33154) (xy 433.831344 -345.281937)
			(xy 433.860823 -345.236063) (xy 433.896531 -345.194851) (xy 433.937741 -345.15914) (xy 433.983613 -345.129657)
			(xy 434.033213 -345.107002) (xy 434.085533 -345.091636) (xy 434.139507 -345.083872) (xy 434.166772 -345.083384)
			(xy 435.030372 -345.083384) (xy 435.057648 -345.083754) (xy 435.111644 -345.091514) (xy 435.163986 -345.106879)
			(xy 435.213609 -345.129538) (xy 435.259502 -345.159028) (xy 435.30073 -345.19475) (xy 435.336455 -345.235976)
			(xy 435.365949 -345.281866) (xy 435.388611 -345.331487) (xy 435.403981 -345.383829) (xy 435.411744 -345.437824)
			(xy 435.411744 -345.492369) (xy 436.894447 -345.492369) (xy 436.894447 -345.437831) (xy 436.90221 -345.383848)
			(xy 436.917576 -345.331519) (xy 436.940233 -345.281909) (xy 436.96972 -345.23603) (xy 437.005436 -345.194814)
			(xy 437.046655 -345.159101) (xy 437.092538 -345.129617) (xy 437.142149 -345.106964) (xy 437.194479 -345.091603)
			(xy 437.248463 -345.083845) (xy 437.275732 -345.083384) (xy 438.139332 -345.083384) (xy 438.166603 -345.083781)
			(xy 438.22059 -345.091547) (xy 438.272922 -345.106917) (xy 438.322534 -345.129578) (xy 438.368416 -345.159068)
			(xy 438.409635 -345.194788) (xy 438.445351 -345.236009) (xy 438.474838 -345.281894) (xy 438.497494 -345.331508)
			(xy 438.51286 -345.383842) (xy 438.520622 -345.437829) (xy 438.520622 -345.492366) (xy 440.00347 -345.492366)
			(xy 440.00347 -345.437834) (xy 440.011231 -345.383858) (xy 440.026594 -345.331535) (xy 440.049247 -345.281932)
			(xy 440.078728 -345.236057) (xy 440.114438 -345.194844) (xy 440.15565 -345.159133) (xy 440.201525 -345.129651)
			(xy 440.251128 -345.106997) (xy 440.30345 -345.091633) (xy 440.357426 -345.083871) (xy 440.384692 -345.083384)
			(xy 441.248292 -345.083384) (xy 441.275567 -345.083755) (xy 441.329561 -345.091517) (xy 441.381901 -345.106885)
			(xy 441.431521 -345.129544) (xy 441.477411 -345.159035) (xy 441.518637 -345.194757) (xy 441.55436 -345.235982)
			(xy 441.583852 -345.281872) (xy 441.606513 -345.331492) (xy 441.621881 -345.383831) (xy 441.629644 -345.437825)
			(xy 441.629644 -345.492375) (xy 441.621881 -345.546369) (xy 441.606513 -345.598708) (xy 441.583852 -345.648328)
			(xy 441.55436 -345.694218) (xy 441.518637 -345.735443) (xy 441.477411 -345.771165) (xy 441.431521 -345.800656)
			(xy 441.381901 -345.823315) (xy 441.329561 -345.838683) (xy 441.275567 -345.846445) (xy 441.248292 -345.846908)
			(xy 440.384692 -345.846908) (xy 440.357426 -345.846329) (xy 440.30345 -345.838567) (xy 440.251128 -345.823203)
			(xy 440.201525 -345.800549) (xy 440.15565 -345.771067) (xy 440.114438 -345.735356) (xy 440.078728 -345.694143)
			(xy 440.049247 -345.648268) (xy 440.026594 -345.598665) (xy 440.011231 -345.546342) (xy 440.00347 -345.492366)
			(xy 438.520622 -345.492366) (xy 438.520622 -345.492371) (xy 438.51286 -345.546358) (xy 438.497494 -345.598692)
			(xy 438.474838 -345.648306) (xy 438.445351 -345.694191) (xy 438.409635 -345.735412) (xy 438.368416 -345.771132)
			(xy 438.322534 -345.800622) (xy 438.272922 -345.823283) (xy 438.22059 -345.838653) (xy 438.166603 -345.846419)
			(xy 438.139332 -345.846908) (xy 437.275732 -345.846908) (xy 437.248463 -345.846355) (xy 437.194479 -345.838597)
			(xy 437.142149 -345.823236) (xy 437.092538 -345.800583) (xy 437.046655 -345.771099) (xy 437.005436 -345.735386)
			(xy 436.96972 -345.69417) (xy 436.940233 -345.648291) (xy 436.917576 -345.598681) (xy 436.90221 -345.546352)
			(xy 436.894447 -345.492369) (xy 435.411744 -345.492369) (xy 435.411744 -345.492376) (xy 435.403981 -345.546371)
			(xy 435.388611 -345.598713) (xy 435.365949 -345.648334) (xy 435.336455 -345.694224) (xy 435.30073 -345.73545)
			(xy 435.259502 -345.771172) (xy 435.213609 -345.800662) (xy 435.163986 -345.823321) (xy 435.111644 -345.838686)
			(xy 435.057648 -345.846446) (xy 435.030372 -345.846908) (xy 434.166772 -345.846908) (xy 434.139507 -345.846328)
			(xy 434.085533 -345.838564) (xy 434.033213 -345.823198) (xy 433.983613 -345.800543) (xy 433.937741 -345.77106)
			(xy 433.896531 -345.735349) (xy 433.860823 -345.694137) (xy 433.831344 -345.648263) (xy 433.808692 -345.59866)
			(xy 433.79333 -345.546339) (xy 433.78557 -345.492365) (xy 432.302721 -345.492365) (xy 432.302721 -345.492372)
			(xy 432.294959 -345.546361) (xy 432.279593 -345.598696) (xy 432.256935 -345.648311) (xy 432.227446 -345.694197)
			(xy 432.191728 -345.735419) (xy 432.150507 -345.771139) (xy 432.104622 -345.800629) (xy 432.055007 -345.823288)
			(xy 432.002673 -345.838657) (xy 431.948684 -345.846421) (xy 431.921412 -345.846908) (xy 431.057812 -345.846908)
			(xy 431.030544 -345.846353) (xy 430.976562 -345.838594) (xy 430.924234 -345.82323) (xy 430.874626 -345.800576)
			(xy 430.828746 -345.771092) (xy 430.787529 -345.735379) (xy 430.751815 -345.694164) (xy 430.72233 -345.648285)
			(xy 430.699674 -345.598677) (xy 430.684309 -345.54635) (xy 430.676547 -345.492368) (xy 429.193844 -345.492368)
			(xy 429.193844 -345.492376) (xy 429.18608 -345.546374) (xy 429.170709 -345.598717) (xy 429.148046 -345.648339)
			(xy 429.11855 -345.694231) (xy 429.082823 -345.735457) (xy 429.041592 -345.771179) (xy 428.995697 -345.800669)
			(xy 428.946072 -345.823326) (xy 428.893727 -345.83869) (xy 428.839729 -345.846448) (xy 428.812452 -345.846908)
			(xy 427.948852 -345.846908) (xy 427.921588 -345.846326) (xy 427.867616 -345.83856) (xy 427.815299 -345.823192)
			(xy 427.765701 -345.800536) (xy 427.719831 -345.771053) (xy 427.678624 -345.735342) (xy 427.642919 -345.69413)
			(xy 427.613441 -345.648257) (xy 427.590791 -345.598656) (xy 427.57543 -345.546337) (xy 427.56767 -345.492364)
			(xy 426.084844 -345.492364) (xy 426.084844 -345.492375) (xy 426.077081 -345.546369) (xy 426.061713 -345.598708)
			(xy 426.039052 -345.648328) (xy 426.00956 -345.694218) (xy 425.973837 -345.735443) (xy 425.932611 -345.771165)
			(xy 425.886721 -345.800656) (xy 425.837101 -345.823315) (xy 425.784761 -345.838683) (xy 425.730767 -345.846445)
			(xy 425.703492 -345.846908) (xy 424.839892 -345.846908) (xy 424.812626 -345.846329) (xy 424.75865 -345.838567)
			(xy 424.706328 -345.823203) (xy 424.656725 -345.800549) (xy 424.61085 -345.771067) (xy 424.569638 -345.735356)
			(xy 424.533928 -345.694143) (xy 424.504447 -345.648268) (xy 424.481794 -345.598665) (xy 424.466431 -345.546342)
			(xy 424.45867 -345.492366) (xy 422.975822 -345.492366) (xy 422.975822 -345.492371) (xy 422.96806 -345.546358)
			(xy 422.952694 -345.598692) (xy 422.930038 -345.648306) (xy 422.900551 -345.694191) (xy 422.864835 -345.735412)
			(xy 422.823616 -345.771132) (xy 422.777734 -345.800622) (xy 422.728122 -345.823283) (xy 422.67579 -345.838653)
			(xy 422.621803 -345.846419) (xy 422.594532 -345.846908) (xy 421.730932 -345.846908) (xy 421.703663 -345.846355)
			(xy 421.649679 -345.838597) (xy 421.597349 -345.823236) (xy 421.547738 -345.800583) (xy 421.501855 -345.771099)
			(xy 421.460636 -345.735386) (xy 421.42492 -345.69417) (xy 421.395433 -345.648291) (xy 421.372776 -345.598681)
			(xy 421.35741 -345.546352) (xy 421.349647 -345.492369) (xy 419.866944 -345.492369) (xy 419.866944 -345.492376)
			(xy 419.859181 -345.546371) (xy 419.843811 -345.598713) (xy 419.821149 -345.648334) (xy 419.791655 -345.694224)
			(xy 419.75593 -345.73545) (xy 419.714702 -345.771172) (xy 419.668809 -345.800662) (xy 419.619186 -345.823321)
			(xy 419.566844 -345.838686) (xy 419.512848 -345.846446) (xy 419.485572 -345.846908) (xy 418.621972 -345.846908)
			(xy 418.594707 -345.846328) (xy 418.540733 -345.838564) (xy 418.488413 -345.823198) (xy 418.438813 -345.800543)
			(xy 418.392941 -345.77106) (xy 418.351731 -345.735349) (xy 418.316023 -345.694137) (xy 418.286544 -345.648263)
			(xy 418.263892 -345.59866) (xy 418.24853 -345.546339) (xy 418.24077 -345.492365) (xy 416.757921 -345.492365)
			(xy 416.757921 -345.492372) (xy 416.750159 -345.546361) (xy 416.734793 -345.598696) (xy 416.712135 -345.648311)
			(xy 416.682646 -345.694197) (xy 416.646928 -345.735419) (xy 416.605707 -345.771139) (xy 416.559822 -345.800629)
			(xy 416.510207 -345.823288) (xy 416.457873 -345.838657) (xy 416.403884 -345.846421) (xy 416.376612 -345.846908)
			(xy 415.513012 -345.846908) (xy 415.485744 -345.846353) (xy 415.431762 -345.838594) (xy 415.379434 -345.82323)
			(xy 415.329826 -345.800576) (xy 415.283946 -345.771092) (xy 415.242729 -345.735379) (xy 415.207015 -345.694164)
			(xy 415.17753 -345.648285) (xy 415.154874 -345.598677) (xy 415.139509 -345.54635) (xy 415.131747 -345.492368)
			(xy 413.649044 -345.492368) (xy 413.649044 -345.492376) (xy 413.64128 -345.546374) (xy 413.625909 -345.598717)
			(xy 413.603246 -345.648339) (xy 413.57375 -345.694231) (xy 413.538023 -345.735457) (xy 413.496792 -345.771179)
			(xy 413.450897 -345.800669) (xy 413.401272 -345.823326) (xy 413.348927 -345.83869) (xy 413.294929 -345.846448)
			(xy 413.267652 -345.846908) (xy 412.404052 -345.846908) (xy 412.376788 -345.846326) (xy 412.322816 -345.83856)
			(xy 412.270499 -345.823192) (xy 412.220901 -345.800536) (xy 412.175031 -345.771053) (xy 412.133824 -345.735342)
			(xy 412.098119 -345.69413) (xy 412.068641 -345.648257) (xy 412.045991 -345.598656) (xy 412.03063 -345.546337)
			(xy 412.02287 -345.492364) (xy 410.540044 -345.492364) (xy 410.540044 -345.492375) (xy 410.532281 -345.546369)
			(xy 410.516913 -345.598708) (xy 410.494252 -345.648328) (xy 410.46476 -345.694218) (xy 410.429037 -345.735443)
			(xy 410.387811 -345.771165) (xy 410.341921 -345.800656) (xy 410.292301 -345.823315) (xy 410.239961 -345.838683)
			(xy 410.185967 -345.846445) (xy 410.158692 -345.846908) (xy 409.295092 -345.846908) (xy 409.267826 -345.846329)
			(xy 409.21385 -345.838567) (xy 409.161528 -345.823203) (xy 409.111925 -345.800549) (xy 409.06605 -345.771067)
			(xy 409.024838 -345.735356) (xy 408.989128 -345.694143) (xy 408.959647 -345.648268) (xy 408.936994 -345.598665)
			(xy 408.921631 -345.546342) (xy 408.91387 -345.492366) (xy 403.522544 -345.492366) (xy 403.522544 -345.492375)
			(xy 403.514781 -345.54637) (xy 403.499412 -345.598711) (xy 403.47675 -345.648331) (xy 403.447257 -345.694221)
			(xy 403.411533 -345.735447) (xy 403.370305 -345.771169) (xy 403.324414 -345.800659) (xy 403.274792 -345.823319)
			(xy 403.222451 -345.838685) (xy 403.168455 -345.846446) (xy 403.14118 -345.846908) (xy 402.27758 -345.846908)
			(xy 402.250315 -345.846328) (xy 402.19634 -345.838565) (xy 402.144019 -345.8232) (xy 402.094417 -345.800545)
			(xy 402.048545 -345.771063) (xy 402.007334 -345.735352) (xy 401.971625 -345.694139) (xy 401.942145 -345.648265)
			(xy 401.919493 -345.598662) (xy 401.90413 -345.546341) (xy 401.89637 -345.492365) (xy 400.413522 -345.492365)
			(xy 400.413522 -345.492372) (xy 400.405759 -345.54636) (xy 400.390393 -345.598694) (xy 400.367736 -345.648309)
			(xy 400.338248 -345.694195) (xy 400.302531 -345.735417) (xy 400.261311 -345.771136) (xy 400.215427 -345.800626)
			(xy 400.165813 -345.823286) (xy 400.11348 -345.838655) (xy 400.059492 -345.84642) (xy 400.03222 -345.846908)
			(xy 399.16862 -345.846908) (xy 399.141351 -345.846354) (xy 399.087369 -345.838595) (xy 399.03504 -345.823232)
			(xy 398.98543 -345.800579) (xy 398.93955 -345.771095) (xy 398.898332 -345.735382) (xy 398.862617 -345.694166)
			(xy 398.833131 -345.648287) (xy 398.810475 -345.598679) (xy 398.795109 -345.546351) (xy 398.787347 -345.492369)
			(xy 397.304644 -345.492369) (xy 397.304644 -345.492376) (xy 397.29688 -345.546373) (xy 397.28151 -345.598715)
			(xy 397.258847 -345.648337) (xy 397.229352 -345.694228) (xy 397.193626 -345.735454) (xy 397.152396 -345.771176)
			(xy 397.106502 -345.800666) (xy 397.056878 -345.823324) (xy 397.004534 -345.838689) (xy 396.950536 -345.846447)
			(xy 396.92326 -345.846908) (xy 396.05966 -345.846908) (xy 396.032396 -345.846327) (xy 395.978423 -345.838562)
			(xy 395.926105 -345.823195) (xy 395.876505 -345.800539) (xy 395.830635 -345.771055) (xy 395.789427 -345.735345)
			(xy 395.753721 -345.694133) (xy 395.724242 -345.648259) (xy 395.701591 -345.598658) (xy 395.68623 -345.546338)
			(xy 395.67847 -345.492364) (xy 394.195621 -345.492364) (xy 394.195621 -345.492373) (xy 394.187859 -345.546363)
			(xy 394.172492 -345.598699) (xy 394.149833 -345.648315) (xy 394.120343 -345.694201) (xy 394.084624 -345.735424)
			(xy 394.043401 -345.771143) (xy 393.997515 -345.800633) (xy 393.947899 -345.823292) (xy 393.895563 -345.838659)
			(xy 393.841573 -345.846421) (xy 393.8143 -345.846908) (xy 392.9507 -345.846908) (xy 392.923434 -345.84633)
			(xy 392.869457 -345.838569) (xy 392.817134 -345.823205) (xy 392.767529 -345.800552) (xy 392.721654 -345.77107)
			(xy 392.680441 -345.735359) (xy 392.64473 -345.694146) (xy 392.615248 -345.648271) (xy 392.592595 -345.598666)
			(xy 392.577231 -345.546343) (xy 392.56947 -345.492366) (xy 391.086622 -345.492366) (xy 391.086622 -345.492371)
			(xy 391.07886 -345.546357) (xy 391.063495 -345.59869) (xy 391.040839 -345.648304) (xy 391.011353 -345.694188)
			(xy 390.975638 -345.73541) (xy 390.93442 -345.771129) (xy 390.888539 -345.80062) (xy 390.838928 -345.823281)
			(xy 390.786597 -345.838651) (xy 390.732611 -345.846419) (xy 390.70534 -345.846908) (xy 389.84174 -345.846908)
			(xy 389.81447 -345.846355) (xy 389.760486 -345.838599) (xy 389.708155 -345.823238) (xy 389.658542 -345.800585)
			(xy 389.612659 -345.771102) (xy 389.571439 -345.735389) (xy 389.535722 -345.694173) (xy 389.506234 -345.648293)
			(xy 389.483576 -345.598683) (xy 389.46821 -345.546353) (xy 389.460447 -345.49237) (xy 387.977744 -345.49237)
			(xy 387.977744 -345.492375) (xy 387.969981 -345.54637) (xy 387.954612 -345.598711) (xy 387.93195 -345.648331)
			(xy 387.902457 -345.694221) (xy 387.866733 -345.735447) (xy 387.825505 -345.771169) (xy 387.779614 -345.800659)
			(xy 387.729992 -345.823319) (xy 387.677651 -345.838685) (xy 387.623655 -345.846446) (xy 387.59638 -345.846908)
			(xy 386.73278 -345.846908) (xy 386.705515 -345.846328) (xy 386.65154 -345.838565) (xy 386.599219 -345.8232)
			(xy 386.549617 -345.800545) (xy 386.503745 -345.771063) (xy 386.462534 -345.735352) (xy 386.426825 -345.694139)
			(xy 386.397345 -345.648265) (xy 386.374693 -345.598662) (xy 386.35933 -345.546341) (xy 386.35157 -345.492365)
			(xy 384.868722 -345.492365) (xy 384.868722 -345.492372) (xy 384.860959 -345.54636) (xy 384.845593 -345.598694)
			(xy 384.822936 -345.648309) (xy 384.793448 -345.694195) (xy 384.757731 -345.735417) (xy 384.716511 -345.771136)
			(xy 384.670627 -345.800626) (xy 384.621013 -345.823286) (xy 384.56868 -345.838655) (xy 384.514692 -345.84642)
			(xy 384.48742 -345.846908) (xy 383.62382 -345.846908) (xy 383.596551 -345.846354) (xy 383.542569 -345.838595)
			(xy 383.49024 -345.823232) (xy 383.44063 -345.800579) (xy 383.39475 -345.771095) (xy 383.353532 -345.735382)
			(xy 383.317817 -345.694166) (xy 383.288331 -345.648287) (xy 383.265675 -345.598679) (xy 383.250309 -345.546351)
			(xy 383.242547 -345.492369) (xy 381.759844 -345.492369) (xy 381.759844 -345.492376) (xy 381.75208 -345.546373)
			(xy 381.73671 -345.598715) (xy 381.714047 -345.648337) (xy 381.684552 -345.694228) (xy 381.648826 -345.735454)
			(xy 381.607596 -345.771176) (xy 381.561702 -345.800666) (xy 381.512078 -345.823324) (xy 381.459734 -345.838689)
			(xy 381.405736 -345.846447) (xy 381.37846 -345.846908) (xy 380.51486 -345.846908) (xy 380.487596 -345.846327)
			(xy 380.433623 -345.838562) (xy 380.381305 -345.823195) (xy 380.331705 -345.800539) (xy 380.285835 -345.771055)
			(xy 380.244627 -345.735345) (xy 380.208921 -345.694133) (xy 380.179442 -345.648259) (xy 380.156791 -345.598658)
			(xy 380.14143 -345.546338) (xy 380.13367 -345.492364) (xy 378.650821 -345.492364) (xy 378.650821 -345.492373)
			(xy 378.643059 -345.546363) (xy 378.627692 -345.598699) (xy 378.605033 -345.648315) (xy 378.575543 -345.694201)
			(xy 378.539824 -345.735424) (xy 378.498601 -345.771143) (xy 378.452715 -345.800633) (xy 378.403099 -345.823292)
			(xy 378.350763 -345.838659) (xy 378.296773 -345.846421) (xy 378.2695 -345.846908) (xy 377.4059 -345.846908)
			(xy 377.378634 -345.84633) (xy 377.324657 -345.838569) (xy 377.272334 -345.823205) (xy 377.222729 -345.800552)
			(xy 377.176854 -345.77107) (xy 377.135641 -345.735359) (xy 377.09993 -345.694146) (xy 377.070448 -345.648271)
			(xy 377.047795 -345.598666) (xy 377.032431 -345.546343) (xy 377.02467 -345.492366) (xy 375.541822 -345.492366)
			(xy 375.541822 -345.492371) (xy 375.53406 -345.546357) (xy 375.518695 -345.59869) (xy 375.496039 -345.648304)
			(xy 375.466553 -345.694188) (xy 375.430838 -345.73541) (xy 375.38962 -345.771129) (xy 375.343739 -345.80062)
			(xy 375.294128 -345.823281) (xy 375.241797 -345.838651) (xy 375.187811 -345.846419) (xy 375.16054 -345.846908)
			(xy 374.29694 -345.846908) (xy 374.26967 -345.846355) (xy 374.215686 -345.838599) (xy 374.163355 -345.823238)
			(xy 374.113742 -345.800585) (xy 374.067859 -345.771102) (xy 374.026639 -345.735389) (xy 373.990922 -345.694173)
			(xy 373.961434 -345.648293) (xy 373.938776 -345.598683) (xy 373.92341 -345.546353) (xy 373.915647 -345.49237)
			(xy 372.432944 -345.49237) (xy 372.432944 -345.492375) (xy 372.425181 -345.54637) (xy 372.409812 -345.598711)
			(xy 372.38715 -345.648331) (xy 372.357657 -345.694221) (xy 372.321933 -345.735447) (xy 372.280705 -345.771169)
			(xy 372.234814 -345.800659) (xy 372.185192 -345.823319) (xy 372.132851 -345.838685) (xy 372.078855 -345.846446)
			(xy 372.05158 -345.846908) (xy 371.18798 -345.846908) (xy 371.160715 -345.846328) (xy 371.10674 -345.838565)
			(xy 371.054419 -345.8232) (xy 371.004817 -345.800545) (xy 370.958945 -345.771063) (xy 370.917734 -345.735352)
			(xy 370.882025 -345.694139) (xy 370.852545 -345.648265) (xy 370.829893 -345.598662) (xy 370.81453 -345.546341)
			(xy 370.80677 -345.492365) (xy 344.837321 -345.492365) (xy 344.837321 -345.492372) (xy 344.829559 -345.546362)
			(xy 344.814192 -345.598698) (xy 344.791533 -345.648314) (xy 344.762044 -345.6942) (xy 344.726325 -345.735422)
			(xy 344.685103 -345.771142) (xy 344.639217 -345.800631) (xy 344.589601 -345.823291) (xy 344.537266 -345.838658)
			(xy 344.483276 -345.846421) (xy 344.456004 -345.846908) (xy 343.592404 -345.846908) (xy 343.565136 -345.846353)
			(xy 343.511155 -345.838592) (xy 343.458828 -345.823228) (xy 343.409221 -345.800573) (xy 343.363342 -345.771089)
			(xy 343.322126 -345.735376) (xy 343.286413 -345.694161) (xy 343.256928 -345.648283) (xy 343.234273 -345.598675)
			(xy 343.218909 -345.546349) (xy 343.211147 -345.492368) (xy 341.728322 -345.492368) (xy 341.728322 -345.492371)
			(xy 341.72056 -345.546357) (xy 341.705195 -345.598689) (xy 341.682539 -345.648302) (xy 341.653054 -345.694187)
			(xy 341.617339 -345.735408) (xy 341.576122 -345.771128) (xy 341.530241 -345.800618) (xy 341.48063 -345.82328)
			(xy 341.4283 -345.838651) (xy 341.374315 -345.846418) (xy 341.347044 -345.846908) (xy 340.483444 -345.846908)
			(xy 340.456174 -345.846356) (xy 340.402189 -345.8386) (xy 340.349857 -345.823239) (xy 340.300245 -345.800587)
			(xy 340.254361 -345.771104) (xy 340.213141 -345.735391) (xy 340.177423 -345.694174) (xy 340.147935 -345.648294)
			(xy 340.125276 -345.598684) (xy 340.10991 -345.546354) (xy 340.102148 -345.49237) (xy 338.619444 -345.49237)
			(xy 338.619444 -345.492375) (xy 338.611681 -345.54637) (xy 338.596312 -345.59871) (xy 338.57365 -345.64833)
			(xy 338.544158 -345.69422) (xy 338.508434 -345.735446) (xy 338.467207 -345.771167) (xy 338.421316 -345.800658)
			(xy 338.371695 -345.823318) (xy 338.319354 -345.838684) (xy 338.265359 -345.846445) (xy 338.238084 -345.846908)
			(xy 337.374484 -345.846908) (xy 337.347219 -345.846329) (xy 337.293243 -345.838566) (xy 337.240922 -345.823201)
			(xy 337.19132 -345.800547) (xy 337.145446 -345.771064) (xy 337.104236 -345.735353) (xy 337.068526 -345.694141)
			(xy 337.039046 -345.648266) (xy 337.016393 -345.598663) (xy 337.001031 -345.546341) (xy 336.99327 -345.492365)
			(xy 335.510422 -345.492365) (xy 335.510422 -345.492372) (xy 335.50266 -345.54636) (xy 335.487294 -345.598693)
			(xy 335.464636 -345.648308) (xy 335.435149 -345.694193) (xy 335.399432 -345.735415) (xy 335.358213 -345.771135)
			(xy 335.312329 -345.800625) (xy 335.262716 -345.823285) (xy 335.210383 -345.838654) (xy 335.156396 -345.84642)
			(xy 335.129124 -345.846908) (xy 334.265524 -345.846908) (xy 334.238255 -345.846354) (xy 334.184272 -345.838596)
			(xy 334.131943 -345.823234) (xy 334.082333 -345.80058) (xy 334.036452 -345.771097) (xy 333.995234 -345.735383)
			(xy 333.959518 -345.694168) (xy 333.930031 -345.648288) (xy 333.907375 -345.59868) (xy 333.892009 -345.546351)
			(xy 333.884247 -345.492369) (xy 332.401544 -345.492369) (xy 332.401544 -345.492376) (xy 332.39378 -345.546372)
			(xy 332.37841 -345.598714) (xy 332.355747 -345.648336) (xy 332.326253 -345.694227) (xy 332.290527 -345.735453)
			(xy 332.249298 -345.771174) (xy 332.203404 -345.800665) (xy 332.153781 -345.823323) (xy 332.101437 -345.838688)
			(xy 332.04744 -345.846447) (xy 332.020164 -345.846908) (xy 331.156564 -345.846908) (xy 331.1293 -345.846327)
			(xy 331.075326 -345.838562) (xy 331.023007 -345.823196) (xy 330.973408 -345.80054) (xy 330.927537 -345.771057)
			(xy 330.886329 -345.735346) (xy 330.850622 -345.694134) (xy 330.821143 -345.648261) (xy 330.798492 -345.598659)
			(xy 330.78313 -345.546338) (xy 330.77537 -345.492364) (xy 329.292521 -345.492364) (xy 329.292521 -345.492372)
			(xy 329.284759 -345.546362) (xy 329.269392 -345.598698) (xy 329.246733 -345.648314) (xy 329.217244 -345.6942)
			(xy 329.181525 -345.735422) (xy 329.140303 -345.771142) (xy 329.094417 -345.800631) (xy 329.044801 -345.823291)
			(xy 328.992466 -345.838658) (xy 328.938476 -345.846421) (xy 328.911204 -345.846908) (xy 328.047604 -345.846908)
			(xy 328.020336 -345.846353) (xy 327.966355 -345.838592) (xy 327.914028 -345.823228) (xy 327.864421 -345.800573)
			(xy 327.818542 -345.771089) (xy 327.777326 -345.735376) (xy 327.741613 -345.694161) (xy 327.712128 -345.648283)
			(xy 327.689473 -345.598675) (xy 327.674109 -345.546349) (xy 327.666347 -345.492368) (xy 326.183522 -345.492368)
			(xy 326.183522 -345.492371) (xy 326.17576 -345.546357) (xy 326.160395 -345.598689) (xy 326.137739 -345.648302)
			(xy 326.108254 -345.694187) (xy 326.072539 -345.735408) (xy 326.031322 -345.771128) (xy 325.985441 -345.800618)
			(xy 325.93583 -345.82328) (xy 325.8835 -345.838651) (xy 325.829515 -345.846418) (xy 325.802244 -345.846908)
			(xy 324.938644 -345.846908) (xy 324.911374 -345.846356) (xy 324.857389 -345.8386) (xy 324.805057 -345.823239)
			(xy 324.755445 -345.800587) (xy 324.709561 -345.771104) (xy 324.668341 -345.735391) (xy 324.632623 -345.694174)
			(xy 324.603135 -345.648294) (xy 324.580476 -345.598684) (xy 324.56511 -345.546354) (xy 324.557348 -345.49237)
			(xy 323.074644 -345.49237) (xy 323.074644 -345.492375) (xy 323.066881 -345.54637) (xy 323.051512 -345.59871)
			(xy 323.02885 -345.64833) (xy 322.999358 -345.69422) (xy 322.963634 -345.735446) (xy 322.922407 -345.771167)
			(xy 322.876516 -345.800658) (xy 322.826895 -345.823318) (xy 322.774554 -345.838684) (xy 322.720559 -345.846445)
			(xy 322.693284 -345.846908) (xy 321.829684 -345.846908) (xy 321.802419 -345.846329) (xy 321.748443 -345.838566)
			(xy 321.696122 -345.823201) (xy 321.64652 -345.800547) (xy 321.600646 -345.771064) (xy 321.559436 -345.735353)
			(xy 321.523726 -345.694141) (xy 321.494246 -345.648266) (xy 321.471593 -345.598663) (xy 321.456231 -345.546341)
			(xy 321.44847 -345.492365) (xy 319.965622 -345.492365) (xy 319.965622 -345.492372) (xy 319.95786 -345.54636)
			(xy 319.942494 -345.598693) (xy 319.919836 -345.648308) (xy 319.890349 -345.694193) (xy 319.854632 -345.735415)
			(xy 319.813413 -345.771135) (xy 319.767529 -345.800625) (xy 319.717916 -345.823285) (xy 319.665583 -345.838654)
			(xy 319.611596 -345.84642) (xy 319.584324 -345.846908) (xy 318.720724 -345.846908) (xy 318.693455 -345.846354)
			(xy 318.639472 -345.838596) (xy 318.587143 -345.823234) (xy 318.537533 -345.80058) (xy 318.491652 -345.771097)
			(xy 318.450434 -345.735383) (xy 318.414718 -345.694168) (xy 318.385231 -345.648288) (xy 318.362575 -345.59868)
			(xy 318.347209 -345.546351) (xy 318.339447 -345.492369) (xy 316.856744 -345.492369) (xy 316.856744 -345.492376)
			(xy 316.84898 -345.546372) (xy 316.83361 -345.598714) (xy 316.810947 -345.648336) (xy 316.781453 -345.694227)
			(xy 316.745727 -345.735453) (xy 316.704498 -345.771174) (xy 316.658604 -345.800665) (xy 316.608981 -345.823323)
			(xy 316.556637 -345.838688) (xy 316.50264 -345.846447) (xy 316.475364 -345.846908) (xy 315.611764 -345.846908)
			(xy 315.5845 -345.846327) (xy 315.530526 -345.838562) (xy 315.478207 -345.823196) (xy 315.428608 -345.80054)
			(xy 315.382737 -345.771057) (xy 315.341529 -345.735346) (xy 315.305822 -345.694134) (xy 315.276343 -345.648261)
			(xy 315.253692 -345.598659) (xy 315.23833 -345.546338) (xy 315.23057 -345.492364) (xy 313.747721 -345.492364)
			(xy 313.747721 -345.492372) (xy 313.739959 -345.546362) (xy 313.724592 -345.598698) (xy 313.701933 -345.648314)
			(xy 313.672444 -345.6942) (xy 313.636725 -345.735422) (xy 313.595503 -345.771142) (xy 313.549617 -345.800631)
			(xy 313.500001 -345.823291) (xy 313.447666 -345.838658) (xy 313.393676 -345.846421) (xy 313.366404 -345.846908)
			(xy 312.502804 -345.846908) (xy 312.475536 -345.846353) (xy 312.421555 -345.838592) (xy 312.369228 -345.823228)
			(xy 312.319621 -345.800573) (xy 312.273742 -345.771089) (xy 312.232526 -345.735376) (xy 312.196813 -345.694161)
			(xy 312.167328 -345.648283) (xy 312.144673 -345.598675) (xy 312.129309 -345.546349) (xy 312.121547 -345.492368)
			(xy 300.231621 -345.492368) (xy 300.231621 -345.492373) (xy 300.223859 -345.546362) (xy 300.208492 -345.598698)
			(xy 300.185833 -345.648314) (xy 300.156344 -345.6942) (xy 300.120624 -345.735423) (xy 300.079402 -345.771143)
			(xy 300.033516 -345.800632) (xy 299.9839 -345.823291) (xy 299.931564 -345.838658) (xy 299.877575 -345.846421)
			(xy 299.850302 -345.846908) (xy 298.986702 -345.846908) (xy 298.959434 -345.846353) (xy 298.905454 -345.838592)
			(xy 298.853127 -345.823228) (xy 298.80352 -345.800573) (xy 298.757641 -345.771089) (xy 298.716426 -345.735376)
			(xy 298.680712 -345.69416) (xy 298.651228 -345.648282) (xy 298.628573 -345.598675) (xy 298.613209 -345.546348)
			(xy 298.605447 -345.492368) (xy 297.122622 -345.492368) (xy 297.122622 -345.492371) (xy 297.11486 -345.546357)
			(xy 297.099495 -345.59869) (xy 297.076839 -345.648303) (xy 297.047354 -345.694187) (xy 297.011639 -345.735409)
			(xy 296.970421 -345.771128) (xy 296.92454 -345.800619) (xy 296.874929 -345.82328) (xy 296.822598 -345.838651)
			(xy 296.768613 -345.846419) (xy 296.741342 -345.846908) (xy 295.877742 -345.846908) (xy 295.850472 -345.846355)
			(xy 295.796487 -345.838599) (xy 295.744156 -345.823238) (xy 295.694543 -345.800586) (xy 295.64866 -345.771103)
			(xy 295.60744 -345.73539) (xy 295.571722 -345.694174) (xy 295.542234 -345.648293) (xy 295.519576 -345.598683)
			(xy 295.50421 -345.546354) (xy 295.496448 -345.49237) (xy 294.013744 -345.49237) (xy 294.013744 -345.492375)
			(xy 294.005981 -345.54637) (xy 293.990612 -345.59871) (xy 293.96795 -345.648331) (xy 293.938457 -345.694221)
			(xy 293.902734 -345.735446) (xy 293.861506 -345.771168) (xy 293.815615 -345.800659) (xy 293.765994 -345.823318)
			(xy 293.713652 -345.838685) (xy 293.659657 -345.846446) (xy 293.632382 -345.846908) (xy 292.768782 -345.846908)
			(xy 292.741517 -345.846328) (xy 292.687542 -345.838566) (xy 292.635221 -345.823201) (xy 292.585619 -345.800546)
			(xy 292.539745 -345.771063) (xy 292.498535 -345.735352) (xy 292.462826 -345.69414) (xy 292.433345 -345.648266)
			(xy 292.410693 -345.598663) (xy 292.395331 -345.546341) (xy 292.38757 -345.492365) (xy 290.904722 -345.492365)
			(xy 290.904722 -345.492372) (xy 290.896959 -345.54636) (xy 290.881593 -345.598694) (xy 290.858936 -345.648309)
			(xy 290.829449 -345.694194) (xy 290.793732 -345.735416) (xy 290.752512 -345.771136) (xy 290.706628 -345.800626)
			(xy 290.657015 -345.823286) (xy 290.604681 -345.838655) (xy 290.550694 -345.84642) (xy 290.523422 -345.846908)
			(xy 289.659822 -345.846908) (xy 289.632553 -345.846354) (xy 289.57857 -345.838595) (xy 289.526241 -345.823233)
			(xy 289.476632 -345.800579) (xy 289.430751 -345.771096) (xy 289.389533 -345.735383) (xy 289.353817 -345.694167)
			(xy 289.324331 -345.648288) (xy 289.301675 -345.598679) (xy 289.286309 -345.546351) (xy 289.278547 -345.492369)
			(xy 287.795844 -345.492369) (xy 287.795844 -345.492376) (xy 287.78808 -345.546373) (xy 287.77271 -345.598715)
			(xy 287.750047 -345.648336) (xy 287.720552 -345.694227) (xy 287.684827 -345.735453) (xy 287.643597 -345.771175)
			(xy 287.597703 -345.800665) (xy 287.548079 -345.823323) (xy 287.495736 -345.838688) (xy 287.441738 -345.846447)
			(xy 287.414462 -345.846908) (xy 286.550862 -345.846908) (xy 286.523598 -345.846327) (xy 286.469625 -345.838562)
			(xy 286.417306 -345.823195) (xy 286.367707 -345.80054) (xy 286.321836 -345.771056) (xy 286.280628 -345.735345)
			(xy 286.244921 -345.694134) (xy 286.215442 -345.64826) (xy 286.192792 -345.598658) (xy 286.17743 -345.546338)
			(xy 286.16967 -345.492364) (xy 284.686821 -345.492364) (xy 284.686821 -345.492373) (xy 284.679059 -345.546362)
			(xy 284.663692 -345.598698) (xy 284.641033 -345.648314) (xy 284.611544 -345.6942) (xy 284.575824 -345.735423)
			(xy 284.534602 -345.771143) (xy 284.488716 -345.800632) (xy 284.4391 -345.823291) (xy 284.386764 -345.838658)
			(xy 284.332775 -345.846421) (xy 284.305502 -345.846908) (xy 283.441902 -345.846908) (xy 283.414634 -345.846353)
			(xy 283.360654 -345.838592) (xy 283.308327 -345.823228) (xy 283.25872 -345.800573) (xy 283.212841 -345.771089)
			(xy 283.171626 -345.735376) (xy 283.135912 -345.69416) (xy 283.106428 -345.648282) (xy 283.083773 -345.598675)
			(xy 283.068409 -345.546348) (xy 283.060647 -345.492368) (xy 281.577822 -345.492368) (xy 281.577822 -345.492371)
			(xy 281.57006 -345.546357) (xy 281.554695 -345.59869) (xy 281.532039 -345.648303) (xy 281.502554 -345.694187)
			(xy 281.466839 -345.735409) (xy 281.425621 -345.771128) (xy 281.37974 -345.800619) (xy 281.330129 -345.82328)
			(xy 281.277798 -345.838651) (xy 281.223813 -345.846419) (xy 281.196542 -345.846908) (xy 280.332942 -345.846908)
			(xy 280.305672 -345.846355) (xy 280.251687 -345.838599) (xy 280.199356 -345.823238) (xy 280.149743 -345.800586)
			(xy 280.10386 -345.771103) (xy 280.06264 -345.73539) (xy 280.026922 -345.694174) (xy 279.997434 -345.648293)
			(xy 279.974776 -345.598683) (xy 279.95941 -345.546354) (xy 279.951648 -345.49237) (xy 278.468944 -345.49237)
			(xy 278.468944 -345.492375) (xy 278.461181 -345.54637) (xy 278.445812 -345.59871) (xy 278.42315 -345.648331)
			(xy 278.393657 -345.694221) (xy 278.357934 -345.735446) (xy 278.316706 -345.771168) (xy 278.270815 -345.800659)
			(xy 278.221194 -345.823318) (xy 278.168852 -345.838685) (xy 278.114857 -345.846446) (xy 278.087582 -345.846908)
			(xy 277.223982 -345.846908) (xy 277.196717 -345.846328) (xy 277.142742 -345.838566) (xy 277.090421 -345.823201)
			(xy 277.040819 -345.800546) (xy 276.994945 -345.771063) (xy 276.953735 -345.735352) (xy 276.918026 -345.69414)
			(xy 276.888545 -345.648266) (xy 276.865893 -345.598663) (xy 276.850531 -345.546341) (xy 276.84277 -345.492365)
			(xy 275.359922 -345.492365) (xy 275.359922 -345.492372) (xy 275.352159 -345.54636) (xy 275.336793 -345.598694)
			(xy 275.314136 -345.648309) (xy 275.284649 -345.694194) (xy 275.248932 -345.735416) (xy 275.207712 -345.771136)
			(xy 275.161828 -345.800626) (xy 275.112215 -345.823286) (xy 275.059881 -345.838655) (xy 275.005894 -345.84642)
			(xy 274.978622 -345.846908) (xy 274.115022 -345.846908) (xy 274.087753 -345.846354) (xy 274.03377 -345.838595)
			(xy 273.981441 -345.823233) (xy 273.931832 -345.800579) (xy 273.885951 -345.771096) (xy 273.844733 -345.735383)
			(xy 273.809017 -345.694167) (xy 273.779531 -345.648288) (xy 273.756875 -345.598679) (xy 273.741509 -345.546351)
			(xy 273.733747 -345.492369) (xy 272.251044 -345.492369) (xy 272.251044 -345.492376) (xy 272.24328 -345.546373)
			(xy 272.22791 -345.598715) (xy 272.205247 -345.648336) (xy 272.175752 -345.694227) (xy 272.140027 -345.735453)
			(xy 272.098797 -345.771175) (xy 272.052903 -345.800665) (xy 272.003279 -345.823323) (xy 271.950936 -345.838688)
			(xy 271.896938 -345.846447) (xy 271.869662 -345.846908) (xy 271.006062 -345.846908) (xy 270.978798 -345.846327)
			(xy 270.924825 -345.838562) (xy 270.872506 -345.823195) (xy 270.822907 -345.80054) (xy 270.777036 -345.771056)
			(xy 270.735828 -345.735345) (xy 270.700121 -345.694134) (xy 270.670642 -345.64826) (xy 270.647992 -345.598658)
			(xy 270.63263 -345.546338) (xy 270.62487 -345.492364) (xy 269.142021 -345.492364) (xy 269.142021 -345.492373)
			(xy 269.134259 -345.546362) (xy 269.118892 -345.598698) (xy 269.096233 -345.648314) (xy 269.066744 -345.6942)
			(xy 269.031024 -345.735423) (xy 268.989802 -345.771143) (xy 268.943916 -345.800632) (xy 268.8943 -345.823291)
			(xy 268.841964 -345.838658) (xy 268.787975 -345.846421) (xy 268.760702 -345.846908) (xy 267.897102 -345.846908)
			(xy 267.869834 -345.846353) (xy 267.815854 -345.838592) (xy 267.763527 -345.823228) (xy 267.71392 -345.800573)
			(xy 267.668041 -345.771089) (xy 267.626826 -345.735376) (xy 267.591112 -345.69416) (xy 267.561628 -345.648282)
			(xy 267.538973 -345.598675) (xy 267.523609 -345.546348) (xy 267.515847 -345.492368) (xy 197.629644 -345.492368)
			(xy 197.629644 -345.492376) (xy 197.621881 -345.546371) (xy 197.606511 -345.598713) (xy 197.583849 -345.648334)
			(xy 197.554355 -345.694224) (xy 197.51863 -345.73545) (xy 197.477402 -345.771172) (xy 197.431509 -345.800662)
			(xy 197.381886 -345.823321) (xy 197.329544 -345.838686) (xy 197.275548 -345.846446) (xy 197.248272 -345.846908)
			(xy 196.384672 -345.846908) (xy 196.357407 -345.846328) (xy 196.303433 -345.838564) (xy 196.251113 -345.823198)
			(xy 196.201513 -345.800543) (xy 196.155641 -345.77106) (xy 196.114431 -345.735349) (xy 196.078723 -345.694137)
			(xy 196.049244 -345.648263) (xy 196.026592 -345.59866) (xy 196.01123 -345.546339) (xy 196.00347 -345.492365)
			(xy 194.520621 -345.492365) (xy 194.520621 -345.492372) (xy 194.512859 -345.546361) (xy 194.497493 -345.598696)
			(xy 194.474835 -345.648311) (xy 194.445346 -345.694197) (xy 194.409628 -345.735419) (xy 194.368407 -345.771139)
			(xy 194.322522 -345.800629) (xy 194.272907 -345.823288) (xy 194.220573 -345.838657) (xy 194.166584 -345.846421)
			(xy 194.139312 -345.846908) (xy 193.275712 -345.846908) (xy 193.248444 -345.846353) (xy 193.194462 -345.838594)
			(xy 193.142134 -345.82323) (xy 193.092526 -345.800576) (xy 193.046646 -345.771092) (xy 193.005429 -345.735379)
			(xy 192.969715 -345.694164) (xy 192.94023 -345.648285) (xy 192.917574 -345.598677) (xy 192.902209 -345.54635)
			(xy 192.894447 -345.492368) (xy 191.411744 -345.492368) (xy 191.411744 -345.492376) (xy 191.40398 -345.546374)
			(xy 191.388609 -345.598717) (xy 191.365946 -345.648339) (xy 191.33645 -345.694231) (xy 191.300723 -345.735457)
			(xy 191.259492 -345.771179) (xy 191.213597 -345.800669) (xy 191.163972 -345.823326) (xy 191.111627 -345.83869)
			(xy 191.057629 -345.846448) (xy 191.030352 -345.846908) (xy 190.166752 -345.846908) (xy 190.139488 -345.846326)
			(xy 190.085516 -345.83856) (xy 190.033199 -345.823192) (xy 189.983601 -345.800536) (xy 189.937731 -345.771053)
			(xy 189.896524 -345.735342) (xy 189.860819 -345.69413) (xy 189.831341 -345.648257) (xy 189.808691 -345.598656)
			(xy 189.79333 -345.546337) (xy 189.78557 -345.492364) (xy 188.302744 -345.492364) (xy 188.302744 -345.492375)
			(xy 188.294981 -345.546369) (xy 188.279613 -345.598708) (xy 188.256952 -345.648328) (xy 188.22746 -345.694218)
			(xy 188.191737 -345.735443) (xy 188.150511 -345.771165) (xy 188.104621 -345.800656) (xy 188.055001 -345.823315)
			(xy 188.002661 -345.838683) (xy 187.948667 -345.846445) (xy 187.921392 -345.846908) (xy 187.057792 -345.846908)
			(xy 187.030526 -345.846329) (xy 186.97655 -345.838567) (xy 186.924228 -345.823203) (xy 186.874625 -345.800549)
			(xy 186.82875 -345.771067) (xy 186.787538 -345.735356) (xy 186.751828 -345.694143) (xy 186.722347 -345.648268)
			(xy 186.699694 -345.598665) (xy 186.684331 -345.546342) (xy 186.67657 -345.492366) (xy 185.193722 -345.492366)
			(xy 185.193722 -345.492371) (xy 185.18596 -345.546358) (xy 185.170594 -345.598692) (xy 185.147938 -345.648306)
			(xy 185.118451 -345.694191) (xy 185.082735 -345.735412) (xy 185.041516 -345.771132) (xy 184.995634 -345.800622)
			(xy 184.946022 -345.823283) (xy 184.89369 -345.838653) (xy 184.839703 -345.846419) (xy 184.812432 -345.846908)
			(xy 183.948832 -345.846908) (xy 183.921563 -345.846355) (xy 183.867579 -345.838597) (xy 183.815249 -345.823236)
			(xy 183.765638 -345.800583) (xy 183.719755 -345.771099) (xy 183.678536 -345.735386) (xy 183.64282 -345.69417)
			(xy 183.613333 -345.648291) (xy 183.590676 -345.598681) (xy 183.57531 -345.546352) (xy 183.567547 -345.492369)
			(xy 182.084844 -345.492369) (xy 182.084844 -345.492376) (xy 182.077081 -345.546371) (xy 182.061711 -345.598713)
			(xy 182.039049 -345.648334) (xy 182.009555 -345.694224) (xy 181.97383 -345.73545) (xy 181.932602 -345.771172)
			(xy 181.886709 -345.800662) (xy 181.837086 -345.823321) (xy 181.784744 -345.838686) (xy 181.730748 -345.846446)
			(xy 181.703472 -345.846908) (xy 180.839872 -345.846908) (xy 180.812607 -345.846328) (xy 180.758633 -345.838564)
			(xy 180.706313 -345.823198) (xy 180.656713 -345.800543) (xy 180.610841 -345.77106) (xy 180.569631 -345.735349)
			(xy 180.533923 -345.694137) (xy 180.504444 -345.648263) (xy 180.481792 -345.59866) (xy 180.46643 -345.546339)
			(xy 180.45867 -345.492365) (xy 178.975821 -345.492365) (xy 178.975821 -345.492372) (xy 178.968059 -345.546361)
			(xy 178.952693 -345.598696) (xy 178.930035 -345.648311) (xy 178.900546 -345.694197) (xy 178.864828 -345.735419)
			(xy 178.823607 -345.771139) (xy 178.777722 -345.800629) (xy 178.728107 -345.823288) (xy 178.675773 -345.838657)
			(xy 178.621784 -345.846421) (xy 178.594512 -345.846908) (xy 177.730912 -345.846908) (xy 177.703644 -345.846353)
			(xy 177.649662 -345.838594) (xy 177.597334 -345.82323) (xy 177.547726 -345.800576) (xy 177.501846 -345.771092)
			(xy 177.460629 -345.735379) (xy 177.424915 -345.694164) (xy 177.39543 -345.648285) (xy 177.372774 -345.598677)
			(xy 177.357409 -345.54635) (xy 177.349647 -345.492368) (xy 175.866944 -345.492368) (xy 175.866944 -345.492376)
			(xy 175.85918 -345.546374) (xy 175.843809 -345.598717) (xy 175.821146 -345.648339) (xy 175.79165 -345.694231)
			(xy 175.755923 -345.735457) (xy 175.714692 -345.771179) (xy 175.668797 -345.800669) (xy 175.619172 -345.823326)
			(xy 175.566827 -345.83869) (xy 175.512829 -345.846448) (xy 175.485552 -345.846908) (xy 174.621952 -345.846908)
			(xy 174.594688 -345.846326) (xy 174.540716 -345.83856) (xy 174.488399 -345.823192) (xy 174.438801 -345.800536)
			(xy 174.392931 -345.771053) (xy 174.351724 -345.735342) (xy 174.316019 -345.69413) (xy 174.286541 -345.648257)
			(xy 174.263891 -345.598656) (xy 174.24853 -345.546337) (xy 174.24077 -345.492364) (xy 172.757944 -345.492364)
			(xy 172.757944 -345.492375) (xy 172.750181 -345.546369) (xy 172.734813 -345.598708) (xy 172.712152 -345.648328)
			(xy 172.68266 -345.694218) (xy 172.646937 -345.735443) (xy 172.605711 -345.771165) (xy 172.559821 -345.800656)
			(xy 172.510201 -345.823315) (xy 172.457861 -345.838683) (xy 172.403867 -345.846445) (xy 172.376592 -345.846908)
			(xy 171.512992 -345.846908) (xy 171.485726 -345.846329) (xy 171.43175 -345.838567) (xy 171.379428 -345.823203)
			(xy 171.329825 -345.800549) (xy 171.28395 -345.771067) (xy 171.242738 -345.735356) (xy 171.207028 -345.694143)
			(xy 171.177547 -345.648268) (xy 171.154894 -345.598665) (xy 171.139531 -345.546342) (xy 171.13177 -345.492366)
			(xy 169.648922 -345.492366) (xy 169.648922 -345.492371) (xy 169.64116 -345.546358) (xy 169.625794 -345.598692)
			(xy 169.603138 -345.648306) (xy 169.573651 -345.694191) (xy 169.537935 -345.735412) (xy 169.496716 -345.771132)
			(xy 169.450834 -345.800622) (xy 169.401222 -345.823283) (xy 169.34889 -345.838653) (xy 169.294903 -345.846419)
			(xy 169.267632 -345.846908) (xy 168.404032 -345.846908) (xy 168.376763 -345.846355) (xy 168.322779 -345.838597)
			(xy 168.270449 -345.823236) (xy 168.220838 -345.800583) (xy 168.174955 -345.771099) (xy 168.133736 -345.735386)
			(xy 168.09802 -345.69417) (xy 168.068533 -345.648291) (xy 168.045876 -345.598681) (xy 168.03051 -345.546352)
			(xy 168.022747 -345.492369) (xy 166.540044 -345.492369) (xy 166.540044 -345.492376) (xy 166.532281 -345.546371)
			(xy 166.516911 -345.598713) (xy 166.494249 -345.648334) (xy 166.464755 -345.694224) (xy 166.42903 -345.73545)
			(xy 166.387802 -345.771172) (xy 166.341909 -345.800662) (xy 166.292286 -345.823321) (xy 166.239944 -345.838686)
			(xy 166.185948 -345.846446) (xy 166.158672 -345.846908) (xy 165.295072 -345.846908) (xy 165.267807 -345.846328)
			(xy 165.213833 -345.838564) (xy 165.161513 -345.823198) (xy 165.111913 -345.800543) (xy 165.066041 -345.77106)
			(xy 165.024831 -345.735349) (xy 164.989123 -345.694137) (xy 164.959644 -345.648263) (xy 164.936992 -345.59866)
			(xy 164.92163 -345.546339) (xy 164.91387 -345.492365) (xy 144.196621 -345.492365) (xy 144.196621 -345.492372)
			(xy 144.188859 -345.546362) (xy 144.173492 -345.598697) (xy 144.150834 -345.648312) (xy 144.121345 -345.694199)
			(xy 144.085627 -345.735421) (xy 144.044405 -345.77114) (xy 143.99852 -345.80063) (xy 143.948904 -345.82329)
			(xy 143.89657 -345.838657) (xy 143.84258 -345.846421) (xy 143.815308 -345.846908) (xy 142.951708 -345.846908)
			(xy 142.92444 -345.846353) (xy 142.870459 -345.838593) (xy 142.818131 -345.823229) (xy 142.768523 -345.800575)
			(xy 142.722644 -345.771091) (xy 142.681428 -345.735378) (xy 142.645714 -345.694162) (xy 142.616229 -345.648284)
			(xy 142.593574 -345.598676) (xy 142.578209 -345.546349) (xy 142.570447 -345.492368) (xy 141.087622 -345.492368)
			(xy 141.087622 -345.49237) (xy 141.07986 -345.546356) (xy 141.064495 -345.598688) (xy 141.04184 -345.648301)
			(xy 141.012355 -345.694185) (xy 140.976641 -345.735407) (xy 140.935424 -345.771126) (xy 140.889543 -345.800617)
			(xy 140.839933 -345.823279) (xy 140.787603 -345.83865) (xy 140.733618 -345.846418) (xy 140.706348 -345.846908)
			(xy 139.842748 -345.846908) (xy 139.815478 -345.846356) (xy 139.761492 -345.8386) (xy 139.70916 -345.82324)
			(xy 139.659547 -345.800588) (xy 139.613663 -345.771105) (xy 139.572442 -345.735392) (xy 139.536724 -345.694176)
			(xy 139.507235 -345.648295) (xy 139.484577 -345.598685) (xy 139.46921 -345.546354) (xy 139.461448 -345.49237)
			(xy 137.978744 -345.49237) (xy 137.978744 -345.492375) (xy 137.970981 -345.546369) (xy 137.955612 -345.598709)
			(xy 137.932951 -345.648329) (xy 137.903459 -345.694219) (xy 137.867736 -345.735444) (xy 137.826509 -345.771166)
			(xy 137.780619 -345.800657) (xy 137.730998 -345.823316) (xy 137.678658 -345.838684) (xy 137.624663 -345.846445)
			(xy 137.597388 -345.846908) (xy 136.733788 -345.846908) (xy 136.706522 -345.846329) (xy 136.652547 -345.838567)
			(xy 136.600225 -345.823202) (xy 136.550622 -345.800548) (xy 136.504748 -345.771065) (xy 136.463537 -345.735354)
			(xy 136.427827 -345.694142) (xy 136.398346 -345.648267) (xy 136.375694 -345.598664) (xy 136.360331 -345.546342)
			(xy 136.35257 -345.492366) (xy 134.869722 -345.492366) (xy 134.869722 -345.492371) (xy 134.86196 -345.546359)
			(xy 134.846594 -345.598693) (xy 134.823937 -345.648307) (xy 134.79445 -345.694192) (xy 134.758734 -345.735414)
			(xy 134.717514 -345.771133) (xy 134.671632 -345.800624) (xy 134.622019 -345.823284) (xy 134.569686 -345.838654)
			(xy 134.515699 -345.84642) (xy 134.488428 -345.846908) (xy 133.624828 -345.846908) (xy 133.597559 -345.846355)
			(xy 133.543576 -345.838597) (xy 133.491246 -345.823235) (xy 133.441635 -345.800581) (xy 133.395753 -345.771098)
			(xy 133.354535 -345.735385) (xy 133.318819 -345.694169) (xy 133.289332 -345.648289) (xy 133.266675 -345.59868)
			(xy 133.251309 -345.546352) (xy 133.243547 -345.492369) (xy 131.760844 -345.492369) (xy 131.760844 -345.492376)
			(xy 131.75308 -345.546372) (xy 131.737711 -345.598713) (xy 131.715048 -345.648335) (xy 131.685554 -345.694225)
			(xy 131.649829 -345.735451) (xy 131.6086 -345.771173) (xy 131.562707 -345.800663) (xy 131.513083 -345.823322)
			(xy 131.460741 -345.838687) (xy 131.406744 -345.846447) (xy 131.379468 -345.846908) (xy 130.515868 -345.846908)
			(xy 130.488603 -345.846328) (xy 130.43463 -345.838563) (xy 130.38231 -345.823197) (xy 130.33271 -345.800542)
			(xy 130.286839 -345.771058) (xy 130.24563 -345.735347) (xy 130.209922 -345.694136) (xy 130.180443 -345.648262)
			(xy 130.157792 -345.59866) (xy 130.14243 -345.546339) (xy 130.13467 -345.492365) (xy 128.651821 -345.492365)
			(xy 128.651821 -345.492372) (xy 128.644059 -345.546362) (xy 128.628692 -345.598697) (xy 128.606034 -345.648312)
			(xy 128.576545 -345.694199) (xy 128.540827 -345.735421) (xy 128.499605 -345.77114) (xy 128.45372 -345.80063)
			(xy 128.404104 -345.82329) (xy 128.35177 -345.838657) (xy 128.29778 -345.846421) (xy 128.270508 -345.846908)
			(xy 127.406908 -345.846908) (xy 127.37964 -345.846353) (xy 127.325659 -345.838593) (xy 127.273331 -345.823229)
			(xy 127.223723 -345.800575) (xy 127.177844 -345.771091) (xy 127.136628 -345.735378) (xy 127.100914 -345.694162)
			(xy 127.071429 -345.648284) (xy 127.048774 -345.598676) (xy 127.033409 -345.546349) (xy 127.025647 -345.492368)
			(xy 125.542822 -345.492368) (xy 125.542822 -345.49237) (xy 125.53506 -345.546356) (xy 125.519695 -345.598688)
			(xy 125.49704 -345.648301) (xy 125.467555 -345.694185) (xy 125.431841 -345.735407) (xy 125.390624 -345.771126)
			(xy 125.344743 -345.800617) (xy 125.295133 -345.823279) (xy 125.242803 -345.83865) (xy 125.188818 -345.846418)
			(xy 125.161548 -345.846908) (xy 124.297948 -345.846908) (xy 124.270678 -345.846356) (xy 124.216692 -345.8386)
			(xy 124.16436 -345.82324) (xy 124.114747 -345.800588) (xy 124.068863 -345.771105) (xy 124.027642 -345.735392)
			(xy 123.991924 -345.694176) (xy 123.962435 -345.648295) (xy 123.939777 -345.598685) (xy 123.92441 -345.546354)
			(xy 123.916648 -345.49237) (xy 122.433944 -345.49237) (xy 122.433944 -345.492375) (xy 122.426181 -345.546369)
			(xy 122.410812 -345.598709) (xy 122.388151 -345.648329) (xy 122.358659 -345.694219) (xy 122.322936 -345.735444)
			(xy 122.281709 -345.771166) (xy 122.235819 -345.800657) (xy 122.186198 -345.823316) (xy 122.133858 -345.838684)
			(xy 122.079863 -345.846445) (xy 122.052588 -345.846908) (xy 121.188988 -345.846908) (xy 121.161722 -345.846329)
			(xy 121.107747 -345.838567) (xy 121.055425 -345.823202) (xy 121.005822 -345.800548) (xy 120.959948 -345.771065)
			(xy 120.918737 -345.735354) (xy 120.883027 -345.694142) (xy 120.853546 -345.648267) (xy 120.830894 -345.598664)
			(xy 120.815531 -345.546342) (xy 120.80777 -345.492366) (xy 119.324922 -345.492366) (xy 119.324922 -345.492371)
			(xy 119.31716 -345.546359) (xy 119.301794 -345.598693) (xy 119.279137 -345.648307) (xy 119.24965 -345.694192)
			(xy 119.213934 -345.735414) (xy 119.172714 -345.771133) (xy 119.126832 -345.800624) (xy 119.077219 -345.823284)
			(xy 119.024886 -345.838654) (xy 118.970899 -345.84642) (xy 118.943628 -345.846908) (xy 118.080028 -345.846908)
			(xy 118.052759 -345.846355) (xy 117.998776 -345.838597) (xy 117.946446 -345.823235) (xy 117.896835 -345.800581)
			(xy 117.850953 -345.771098) (xy 117.809735 -345.735385) (xy 117.774019 -345.694169) (xy 117.744532 -345.648289)
			(xy 117.721875 -345.59868) (xy 117.706509 -345.546352) (xy 117.698747 -345.492369) (xy 116.216044 -345.492369)
			(xy 116.216044 -345.492376) (xy 116.20828 -345.546372) (xy 116.192911 -345.598713) (xy 116.170248 -345.648335)
			(xy 116.140754 -345.694225) (xy 116.105029 -345.735451) (xy 116.0638 -345.771173) (xy 116.017907 -345.800663)
			(xy 115.968283 -345.823322) (xy 115.915941 -345.838687) (xy 115.861944 -345.846447) (xy 115.834668 -345.846908)
			(xy 114.971068 -345.846908) (xy 114.943803 -345.846328) (xy 114.88983 -345.838563) (xy 114.83751 -345.823197)
			(xy 114.78791 -345.800542) (xy 114.742039 -345.771058) (xy 114.70083 -345.735347) (xy 114.665122 -345.694136)
			(xy 114.635643 -345.648262) (xy 114.612992 -345.59866) (xy 114.59763 -345.546339) (xy 114.58987 -345.492365)
			(xy 113.107021 -345.492365) (xy 113.107021 -345.492372) (xy 113.099259 -345.546362) (xy 113.083892 -345.598697)
			(xy 113.061234 -345.648312) (xy 113.031745 -345.694199) (xy 112.996027 -345.735421) (xy 112.954805 -345.77114)
			(xy 112.90892 -345.80063) (xy 112.859304 -345.82329) (xy 112.80697 -345.838657) (xy 112.75298 -345.846421)
			(xy 112.725708 -345.846908) (xy 111.862108 -345.846908) (xy 111.83484 -345.846353) (xy 111.780859 -345.838593)
			(xy 111.728531 -345.823229) (xy 111.678923 -345.800575) (xy 111.633044 -345.771091) (xy 111.591828 -345.735378)
			(xy 111.556114 -345.694162) (xy 111.526629 -345.648284) (xy 111.503974 -345.598676) (xy 111.488609 -345.546349)
			(xy 111.480847 -345.492368) (xy 93.706722 -345.492368) (xy 93.706722 -345.492371) (xy 93.69896 -345.546357)
			(xy 93.683595 -345.59869) (xy 93.660939 -345.648303) (xy 93.631454 -345.694187) (xy 93.595739 -345.735409)
			(xy 93.554521 -345.771128) (xy 93.50864 -345.800619) (xy 93.459029 -345.82328) (xy 93.406698 -345.838651)
			(xy 93.352713 -345.846419) (xy 93.325442 -345.846908) (xy 92.461842 -345.846908) (xy 92.434572 -345.846355)
			(xy 92.380587 -345.838599) (xy 92.328256 -345.823238) (xy 92.278643 -345.800586) (xy 92.23276 -345.771103)
			(xy 92.19154 -345.73539) (xy 92.155822 -345.694174) (xy 92.126334 -345.648293) (xy 92.103676 -345.598683)
			(xy 92.08831 -345.546354) (xy 92.080548 -345.49237) (xy 90.597844 -345.49237) (xy 90.597844 -345.492375)
			(xy 90.590081 -345.54637) (xy 90.574712 -345.59871) (xy 90.55205 -345.648331) (xy 90.522557 -345.694221)
			(xy 90.486834 -345.735446) (xy 90.445606 -345.771168) (xy 90.399715 -345.800659) (xy 90.350094 -345.823318)
			(xy 90.297752 -345.838685) (xy 90.243757 -345.846446) (xy 90.216482 -345.846908) (xy 89.352882 -345.846908)
			(xy 89.325617 -345.846328) (xy 89.271642 -345.838566) (xy 89.219321 -345.823201) (xy 89.169719 -345.800546)
			(xy 89.123845 -345.771063) (xy 89.082635 -345.735352) (xy 89.046926 -345.69414) (xy 89.017445 -345.648266)
			(xy 88.994793 -345.598663) (xy 88.979431 -345.546341) (xy 88.97167 -345.492365) (xy 87.488822 -345.492365)
			(xy 87.488822 -345.492372) (xy 87.481059 -345.54636) (xy 87.465693 -345.598694) (xy 87.443036 -345.648309)
			(xy 87.413549 -345.694194) (xy 87.377832 -345.735416) (xy 87.336612 -345.771136) (xy 87.290728 -345.800626)
			(xy 87.241115 -345.823286) (xy 87.188781 -345.838655) (xy 87.134794 -345.84642) (xy 87.107522 -345.846908)
			(xy 86.243922 -345.846908) (xy 86.216653 -345.846354) (xy 86.16267 -345.838595) (xy 86.110341 -345.823233)
			(xy 86.060732 -345.800579) (xy 86.014851 -345.771096) (xy 85.973633 -345.735383) (xy 85.937917 -345.694167)
			(xy 85.908431 -345.648288) (xy 85.885775 -345.598679) (xy 85.870409 -345.546351) (xy 85.862647 -345.492369)
			(xy 84.379944 -345.492369) (xy 84.379944 -345.492376) (xy 84.37218 -345.546373) (xy 84.35681 -345.598715)
			(xy 84.334147 -345.648336) (xy 84.304652 -345.694227) (xy 84.268927 -345.735453) (xy 84.227697 -345.771175)
			(xy 84.181803 -345.800665) (xy 84.132179 -345.823323) (xy 84.079836 -345.838688) (xy 84.025838 -345.846447)
			(xy 83.998562 -345.846908) (xy 83.134962 -345.846908) (xy 83.107698 -345.846327) (xy 83.053725 -345.838562)
			(xy 83.001406 -345.823195) (xy 82.951807 -345.80054) (xy 82.905936 -345.771056) (xy 82.864728 -345.735345)
			(xy 82.829021 -345.694134) (xy 82.799542 -345.64826) (xy 82.776892 -345.598658) (xy 82.76153 -345.546338)
			(xy 82.75377 -345.492364) (xy 81.270921 -345.492364) (xy 81.270921 -345.492373) (xy 81.263159 -345.546362)
			(xy 81.247792 -345.598698) (xy 81.225133 -345.648314) (xy 81.195644 -345.6942) (xy 81.159924 -345.735423)
			(xy 81.118702 -345.771143) (xy 81.072816 -345.800632) (xy 81.0232 -345.823291) (xy 80.970864 -345.838658)
			(xy 80.916875 -345.846421) (xy 80.889602 -345.846908) (xy 80.026002 -345.846908) (xy 79.998734 -345.846353)
			(xy 79.944754 -345.838592) (xy 79.892427 -345.823228) (xy 79.84282 -345.800573) (xy 79.796941 -345.771089)
			(xy 79.755726 -345.735376) (xy 79.720012 -345.69416) (xy 79.690528 -345.648282) (xy 79.667873 -345.598675)
			(xy 79.652509 -345.546348) (xy 79.644747 -345.492368) (xy 78.161922 -345.492368) (xy 78.161922 -345.492371)
			(xy 78.15416 -345.546357) (xy 78.138795 -345.59869) (xy 78.116139 -345.648303) (xy 78.086654 -345.694187)
			(xy 78.050939 -345.735409) (xy 78.009721 -345.771128) (xy 77.96384 -345.800619) (xy 77.914229 -345.82328)
			(xy 77.861898 -345.838651) (xy 77.807913 -345.846419) (xy 77.780642 -345.846908) (xy 76.917042 -345.846908)
			(xy 76.889772 -345.846355) (xy 76.835787 -345.838599) (xy 76.783456 -345.823238) (xy 76.733843 -345.800586)
			(xy 76.68796 -345.771103) (xy 76.64674 -345.73539) (xy 76.611022 -345.694174) (xy 76.581534 -345.648293)
			(xy 76.558876 -345.598683) (xy 76.54351 -345.546354) (xy 76.535748 -345.49237) (xy 75.053044 -345.49237)
			(xy 75.053044 -345.492375) (xy 75.045281 -345.54637) (xy 75.029912 -345.59871) (xy 75.00725 -345.648331)
			(xy 74.977757 -345.694221) (xy 74.942034 -345.735446) (xy 74.900806 -345.771168) (xy 74.854915 -345.800659)
			(xy 74.805294 -345.823318) (xy 74.752952 -345.838685) (xy 74.698957 -345.846446) (xy 74.671682 -345.846908)
			(xy 73.808082 -345.846908) (xy 73.780817 -345.846328) (xy 73.726842 -345.838566) (xy 73.674521 -345.823201)
			(xy 73.624919 -345.800546) (xy 73.579045 -345.771063) (xy 73.537835 -345.735352) (xy 73.502126 -345.69414)
			(xy 73.472645 -345.648266) (xy 73.449993 -345.598663) (xy 73.434631 -345.546341) (xy 73.42687 -345.492365)
			(xy 71.944022 -345.492365) (xy 71.944022 -345.492372) (xy 71.936259 -345.54636) (xy 71.920893 -345.598694)
			(xy 71.898236 -345.648309) (xy 71.868749 -345.694194) (xy 71.833032 -345.735416) (xy 71.791812 -345.771136)
			(xy 71.745928 -345.800626) (xy 71.696315 -345.823286) (xy 71.643981 -345.838655) (xy 71.589994 -345.84642)
			(xy 71.562722 -345.846908) (xy 70.699122 -345.846908) (xy 70.671853 -345.846354) (xy 70.61787 -345.838595)
			(xy 70.565541 -345.823233) (xy 70.515932 -345.800579) (xy 70.470051 -345.771096) (xy 70.428833 -345.735383)
			(xy 70.393117 -345.694167) (xy 70.363631 -345.648288) (xy 70.340975 -345.598679) (xy 70.325609 -345.546351)
			(xy 70.317847 -345.492369) (xy 68.835144 -345.492369) (xy 68.835144 -345.492376) (xy 68.82738 -345.546373)
			(xy 68.81201 -345.598715) (xy 68.789347 -345.648336) (xy 68.759852 -345.694227) (xy 68.724127 -345.735453)
			(xy 68.682897 -345.771175) (xy 68.637003 -345.800665) (xy 68.587379 -345.823323) (xy 68.535036 -345.838688)
			(xy 68.481038 -345.846447) (xy 68.453762 -345.846908) (xy 67.590162 -345.846908) (xy 67.562898 -345.846327)
			(xy 67.508925 -345.838562) (xy 67.456606 -345.823195) (xy 67.407007 -345.80054) (xy 67.361136 -345.771056)
			(xy 67.319928 -345.735345) (xy 67.284221 -345.694134) (xy 67.254742 -345.64826) (xy 67.232092 -345.598658)
			(xy 67.21673 -345.546338) (xy 67.20897 -345.492364) (xy 65.726121 -345.492364) (xy 65.726121 -345.492373)
			(xy 65.718359 -345.546362) (xy 65.702992 -345.598698) (xy 65.680333 -345.648314) (xy 65.650844 -345.6942)
			(xy 65.615124 -345.735423) (xy 65.573902 -345.771143) (xy 65.528016 -345.800632) (xy 65.4784 -345.823291)
			(xy 65.426064 -345.838658) (xy 65.372075 -345.846421) (xy 65.344802 -345.846908) (xy 64.481202 -345.846908)
			(xy 64.453934 -345.846353) (xy 64.399954 -345.838592) (xy 64.347627 -345.823228) (xy 64.29802 -345.800573)
			(xy 64.252141 -345.771089) (xy 64.210926 -345.735376) (xy 64.175212 -345.69416) (xy 64.145728 -345.648282)
			(xy 64.123073 -345.598675) (xy 64.107709 -345.546348) (xy 64.099947 -345.492368) (xy 62.617122 -345.492368)
			(xy 62.617122 -345.492371) (xy 62.60936 -345.546357) (xy 62.593995 -345.59869) (xy 62.571339 -345.648303)
			(xy 62.541854 -345.694187) (xy 62.506139 -345.735409) (xy 62.464921 -345.771128) (xy 62.41904 -345.800619)
			(xy 62.369429 -345.82328) (xy 62.317098 -345.838651) (xy 62.263113 -345.846419) (xy 62.235842 -345.846908)
			(xy 61.372242 -345.846908) (xy 61.344972 -345.846355) (xy 61.290987 -345.838599) (xy 61.238656 -345.823238)
			(xy 61.189043 -345.800586) (xy 61.14316 -345.771103) (xy 61.10194 -345.73539) (xy 61.066222 -345.694174)
			(xy 61.036734 -345.648293) (xy 61.014076 -345.598683) (xy 60.99871 -345.546354) (xy 60.990948 -345.49237)
			(xy 51.666922 -345.49237) (xy 51.65916 -345.546356) (xy 51.643795 -345.598688) (xy 51.62114 -345.648301)
			(xy 51.591655 -345.694185) (xy 51.555941 -345.735407) (xy 51.514724 -345.771126) (xy 51.468843 -345.800617)
			(xy 51.419233 -345.823279) (xy 51.366903 -345.83865) (xy 51.312918 -345.846418) (xy 51.285648 -345.846908)
			(xy 50.422048 -345.846908) (xy 50.394778 -345.846356) (xy 50.340792 -345.8386) (xy 50.28846 -345.82324)
			(xy 50.238847 -345.800588) (xy 50.192963 -345.771105) (xy 50.151742 -345.735392) (xy 50.116024 -345.694176)
			(xy 50.086535 -345.648295) (xy 50.063877 -345.598685) (xy 50.04851 -345.546354) (xy 50.040748 -345.49237)
			(xy 48.558044 -345.49237) (xy 48.558044 -345.492375) (xy 48.550281 -345.546369) (xy 48.534912 -345.598709)
			(xy 48.512251 -345.648329) (xy 48.482759 -345.694219) (xy 48.447036 -345.735444) (xy 48.405809 -345.771166)
			(xy 48.359919 -345.800657) (xy 48.310298 -345.823316) (xy 48.257958 -345.838684) (xy 48.203963 -345.846445)
			(xy 48.176688 -345.846908) (xy 47.313088 -345.846908) (xy 47.285822 -345.846329) (xy 47.231847 -345.838567)
			(xy 47.179525 -345.823202) (xy 47.129922 -345.800548) (xy 47.084048 -345.771065) (xy 47.042837 -345.735354)
			(xy 47.007127 -345.694142) (xy 46.977646 -345.648267) (xy 46.954994 -345.598664) (xy 46.939631 -345.546342)
			(xy 46.93187 -345.492366) (xy 45.449022 -345.492366) (xy 45.449022 -345.492371) (xy 45.44126 -345.546359)
			(xy 45.425894 -345.598693) (xy 45.403237 -345.648307) (xy 45.37375 -345.694192) (xy 45.338034 -345.735414)
			(xy 45.296814 -345.771133) (xy 45.250932 -345.800624) (xy 45.201319 -345.823284) (xy 45.148986 -345.838654)
			(xy 45.094999 -345.84642) (xy 45.067728 -345.846908) (xy 44.204128 -345.846908) (xy 44.176859 -345.846355)
			(xy 44.122876 -345.838597) (xy 44.070546 -345.823235) (xy 44.020935 -345.800581) (xy 43.975053 -345.771098)
			(xy 43.933835 -345.735385) (xy 43.898119 -345.694169) (xy 43.868632 -345.648289) (xy 43.845975 -345.59868)
			(xy 43.830609 -345.546352) (xy 43.822847 -345.492369) (xy 42.340144 -345.492369) (xy 42.340144 -345.492376)
			(xy 42.33238 -345.546372) (xy 42.317011 -345.598713) (xy 42.294348 -345.648335) (xy 42.264854 -345.694225)
			(xy 42.229129 -345.735451) (xy 42.1879 -345.771173) (xy 42.142007 -345.800663) (xy 42.092383 -345.823322)
			(xy 42.040041 -345.838687) (xy 41.986044 -345.846447) (xy 41.958768 -345.846908) (xy 41.095168 -345.846908)
			(xy 41.067903 -345.846328) (xy 41.01393 -345.838563) (xy 40.96161 -345.823197) (xy 40.91201 -345.800542)
			(xy 40.866139 -345.771058) (xy 40.82493 -345.735347) (xy 40.789222 -345.694136) (xy 40.759743 -345.648262)
			(xy 40.737092 -345.59866) (xy 40.72173 -345.546339) (xy 40.71397 -345.492365) (xy 39.231121 -345.492365)
			(xy 39.231121 -345.492372) (xy 39.223359 -345.546362) (xy 39.207992 -345.598697) (xy 39.185334 -345.648312)
			(xy 39.155845 -345.694199) (xy 39.120127 -345.735421) (xy 39.078905 -345.77114) (xy 39.03302 -345.80063)
			(xy 38.983404 -345.82329) (xy 38.93107 -345.838657) (xy 38.87708 -345.846421) (xy 38.849808 -345.846908)
			(xy 37.986208 -345.846908) (xy 37.95894 -345.846353) (xy 37.904959 -345.838593) (xy 37.852631 -345.823229)
			(xy 37.803023 -345.800575) (xy 37.757144 -345.771091) (xy 37.715928 -345.735378) (xy 37.680214 -345.694162)
			(xy 37.650729 -345.648284) (xy 37.628074 -345.598676) (xy 37.612709 -345.546349) (xy 37.604947 -345.492368)
			(xy 36.122122 -345.492368) (xy 36.122122 -345.49237) (xy 36.11436 -345.546356) (xy 36.098995 -345.598688)
			(xy 36.07634 -345.648301) (xy 36.046855 -345.694185) (xy 36.011141 -345.735407) (xy 35.969924 -345.771126)
			(xy 35.924043 -345.800617) (xy 35.874433 -345.823279) (xy 35.822103 -345.83865) (xy 35.768118 -345.846418)
			(xy 35.740848 -345.846908) (xy 34.877248 -345.846908) (xy 34.849978 -345.846356) (xy 34.795992 -345.8386)
			(xy 34.74366 -345.82324) (xy 34.694047 -345.800588) (xy 34.648163 -345.771105) (xy 34.606942 -345.735392)
			(xy 34.571224 -345.694176) (xy 34.541735 -345.648295) (xy 34.519077 -345.598685) (xy 34.50371 -345.546354)
			(xy 34.495948 -345.49237) (xy 33.013244 -345.49237) (xy 33.013244 -345.492375) (xy 33.005481 -345.546369)
			(xy 32.990112 -345.598709) (xy 32.967451 -345.648329) (xy 32.937959 -345.694219) (xy 32.902236 -345.735444)
			(xy 32.861009 -345.771166) (xy 32.815119 -345.800657) (xy 32.765498 -345.823316) (xy 32.713158 -345.838684)
			(xy 32.659163 -345.846445) (xy 32.631888 -345.846908) (xy 31.768288 -345.846908) (xy 31.741022 -345.846329)
			(xy 31.687047 -345.838567) (xy 31.634725 -345.823202) (xy 31.585122 -345.800548) (xy 31.539248 -345.771065)
			(xy 31.498037 -345.735354) (xy 31.462327 -345.694142) (xy 31.432846 -345.648267) (xy 31.410194 -345.598664)
			(xy 31.394831 -345.546342) (xy 31.38707 -345.492366) (xy 29.904222 -345.492366) (xy 29.904222 -345.492371)
			(xy 29.89646 -345.546359) (xy 29.881094 -345.598693) (xy 29.858437 -345.648307) (xy 29.82895 -345.694192)
			(xy 29.793234 -345.735414) (xy 29.752014 -345.771133) (xy 29.706132 -345.800624) (xy 29.656519 -345.823284)
			(xy 29.604186 -345.838654) (xy 29.550199 -345.84642) (xy 29.522928 -345.846908) (xy 28.659328 -345.846908)
			(xy 28.632059 -345.846355) (xy 28.578076 -345.838597) (xy 28.525746 -345.823235) (xy 28.476135 -345.800581)
			(xy 28.430253 -345.771098) (xy 28.389035 -345.735385) (xy 28.353319 -345.694169) (xy 28.323832 -345.648289)
			(xy 28.301175 -345.59868) (xy 28.285809 -345.546352) (xy 28.278047 -345.492369) (xy 26.795344 -345.492369)
			(xy 26.795344 -345.492376) (xy 26.78758 -345.546372) (xy 26.772211 -345.598713) (xy 26.749548 -345.648335)
			(xy 26.720054 -345.694225) (xy 26.684329 -345.735451) (xy 26.6431 -345.771173) (xy 26.597207 -345.800663)
			(xy 26.547583 -345.823322) (xy 26.495241 -345.838687) (xy 26.441244 -345.846447) (xy 26.413968 -345.846908)
			(xy 25.550368 -345.846908) (xy 25.523103 -345.846328) (xy 25.46913 -345.838563) (xy 25.41681 -345.823197)
			(xy 25.36721 -345.800542) (xy 25.321339 -345.771058) (xy 25.28013 -345.735347) (xy 25.244422 -345.694136)
			(xy 25.214943 -345.648262) (xy 25.192292 -345.59866) (xy 25.17693 -345.546339) (xy 25.16917 -345.492365)
			(xy 23.686305 -345.492365) (xy 23.686305 -345.492421) (xy 23.678542 -345.546407) (xy 23.663176 -345.59874)
			(xy 23.640519 -345.648352) (xy 23.611031 -345.694236) (xy 23.575314 -345.735455) (xy 23.534094 -345.771172)
			(xy 23.488211 -345.80066) (xy 23.438598 -345.823317) (xy 23.386265 -345.838683) (xy 23.332279 -345.846445)
			(xy 23.305008 -345.846908) (xy 22.441408 -345.846908) (xy 22.414138 -345.846429) (xy 22.360154 -345.838667)
			(xy 22.307825 -345.823302) (xy 22.258214 -345.800645) (xy 22.212333 -345.771159) (xy 22.171115 -345.735443)
			(xy 22.1354 -345.694225) (xy 22.105914 -345.648344) (xy 22.083258 -345.598733) (xy 22.067892 -345.546404)
			(xy 22.06013 -345.49242) (xy 20.577345 -345.49242) (xy 20.577345 -345.492421) (xy 20.569582 -345.546407)
			(xy 20.554216 -345.59874) (xy 20.531559 -345.648352) (xy 20.502071 -345.694236) (xy 20.466354 -345.735455)
			(xy 20.425134 -345.771172) (xy 20.379251 -345.80066) (xy 20.329638 -345.823317) (xy 20.277305 -345.838683)
			(xy 20.223319 -345.846445) (xy 20.196048 -345.846908) (xy 19.332448 -345.846908) (xy 19.305178 -345.846429)
			(xy 19.251194 -345.838667) (xy 19.198865 -345.823302) (xy 19.149254 -345.800645) (xy 19.103373 -345.771159)
			(xy 19.062155 -345.735443) (xy 19.02644 -345.694225) (xy 18.996954 -345.648344) (xy 18.974298 -345.598733)
			(xy 18.958932 -345.546404) (xy 18.95117 -345.49242) (xy 0.508 -345.49242) (xy 0.508 -348.976496)
			(xy 4.708641 -348.976496) (xy 4.708641 -348.847356) (xy 4.716591 -348.718461) (xy 4.732461 -348.590301)
			(xy 4.75619 -348.46336) (xy 4.787689 -348.338121) (xy 4.826838 -348.215058) (xy 4.873489 -348.094639)
			(xy 4.927464 -347.97732) (xy 4.988559 -347.863546) (xy 5.056542 -347.753749) (xy 5.131156 -347.648346)
			(xy 5.212117 -347.547736) (xy 5.299117 -347.452301) (xy 5.391828 -347.362402) (xy 5.489898 -347.278381)
			(xy 5.592953 -347.200557) (xy 5.700604 -347.129225) (xy 5.812443 -347.064655) (xy 5.928044 -347.007093)
			(xy 6.046969 -346.956756) (xy 6.168768 -346.913836) (xy 6.292978 -346.878495) (xy 6.419127 -346.850868)
			(xy 6.546739 -346.831059) (xy 6.675328 -346.819143) (xy 6.804406 -346.815167) (xy 6.933484 -346.819143)
			(xy 7.062073 -346.831059) (xy 7.189685 -346.850868) (xy 7.315834 -346.878495) (xy 7.440044 -346.913836)
			(xy 7.451736 -346.917956) (xy 245.50903 -346.917956) (xy 245.50903 -346.83326) (xy 245.517081 -346.748946)
			(xy 245.53311 -346.66578) (xy 245.556971 -346.584513) (xy 245.58845 -346.505883) (xy 245.627261 -346.430602)
			(xy 245.673051 -346.35935) (xy 245.725407 -346.292774) (xy 245.783855 -346.231476) (xy 245.847865 -346.176011)
			(xy 245.916857 -346.126882) (xy 245.990207 -346.084533) (xy 246.06725 -346.049349) (xy 246.147289 -346.021647)
			(xy 246.229598 -346.001679) (xy 246.313433 -345.989626) (xy 246.398034 -345.985596) (xy 246.482635 -345.989626)
			(xy 246.56647 -346.001679) (xy 246.648779 -346.021647) (xy 246.728818 -346.049349) (xy 246.805861 -346.084533)
			(xy 246.879211 -346.126882) (xy 246.948203 -346.176011) (xy 247.012213 -346.231476) (xy 247.070661 -346.292774)
			(xy 247.123017 -346.35935) (xy 247.168807 -346.430602) (xy 247.207618 -346.505883) (xy 247.239097 -346.584513)
			(xy 247.262958 -346.66578) (xy 247.278987 -346.748946) (xy 247.287038 -346.83326) (xy 247.287542 -346.875608)
			(xy 247.287038 -346.917956) (xy 247.278987 -347.00227) (xy 247.262958 -347.085436) (xy 247.239097 -347.166703)
			(xy 247.207618 -347.245333) (xy 247.168807 -347.320614) (xy 247.123017 -347.391866) (xy 247.070661 -347.458442)
			(xy 247.012213 -347.51974) (xy 246.948203 -347.575205) (xy 246.879211 -347.624334) (xy 246.805861 -347.666683)
			(xy 246.728818 -347.701867) (xy 246.648779 -347.729569) (xy 246.56647 -347.749537) (xy 246.482635 -347.76159)
			(xy 246.398034 -347.765621) (xy 246.313433 -347.76159) (xy 246.229598 -347.749537) (xy 246.147289 -347.729569)
			(xy 246.06725 -347.701867) (xy 245.990207 -347.666683) (xy 245.916857 -347.624334) (xy 245.847865 -347.575205)
			(xy 245.783855 -347.51974) (xy 245.725407 -347.458442) (xy 245.673051 -347.391866) (xy 245.627261 -347.320614)
			(xy 245.58845 -347.245333) (xy 245.556971 -347.166703) (xy 245.53311 -347.085436) (xy 245.517081 -347.00227)
			(xy 245.50903 -346.917956) (xy 7.451736 -346.917956) (xy 7.561843 -346.956756) (xy 7.680768 -347.007093)
			(xy 7.796369 -347.064655) (xy 7.908208 -347.129225) (xy 8.015859 -347.200557) (xy 8.118914 -347.278381)
			(xy 8.216984 -347.362402) (xy 8.309695 -347.452301) (xy 8.396695 -347.547736) (xy 8.477656 -347.648346)
			(xy 8.55227 -347.753749) (xy 8.620253 -347.863546) (xy 8.681348 -347.97732) (xy 8.735323 -348.094639)
			(xy 8.781974 -348.215058) (xy 8.821123 -348.338121) (xy 8.852622 -348.46336) (xy 8.876351 -348.590301)
			(xy 8.879169 -348.613059) (xy 18.951174 -348.613059) (xy 18.951174 -348.558521) (xy 18.958936 -348.504537)
			(xy 18.974301 -348.452208) (xy 18.996957 -348.402598) (xy 19.026443 -348.356717) (xy 19.062158 -348.315499)
			(xy 19.103375 -348.279784) (xy 19.149256 -348.250298) (xy 19.198866 -348.227642) (xy 19.251195 -348.212276)
			(xy 19.305179 -348.204515) (xy 19.332448 -348.204028) (xy 20.196048 -348.204028) (xy 20.223319 -348.204491)
			(xy 20.277306 -348.212253) (xy 20.329639 -348.227619) (xy 20.379253 -348.250277) (xy 20.425136 -348.279764)
			(xy 20.466357 -348.315482) (xy 20.502074 -348.356702) (xy 20.531562 -348.402586) (xy 20.55422 -348.452199)
			(xy 20.569586 -348.504532) (xy 20.577349 -348.558519) (xy 20.577349 -348.613061) (xy 20.577347 -348.613072)
			(xy 22.060092 -348.613072) (xy 22.060092 -348.558528) (xy 22.067854 -348.504539) (xy 22.083221 -348.452204)
			(xy 22.10588 -348.402589) (xy 22.135369 -348.356704) (xy 22.171088 -348.315483) (xy 22.21231 -348.279764)
			(xy 22.258196 -348.250276) (xy 22.307812 -348.227618) (xy 22.360147 -348.212252) (xy 22.414136 -348.204491)
			(xy 22.441408 -348.204028) (xy 23.305008 -348.204028) (xy 23.332276 -348.204535) (xy 23.386258 -348.212297)
			(xy 23.438585 -348.227663) (xy 23.488193 -348.250319) (xy 23.534071 -348.279804) (xy 23.575287 -348.315519)
			(xy 23.611 -348.356735) (xy 23.640485 -348.402614) (xy 23.66314 -348.452223) (xy 23.678504 -348.50455)
			(xy 23.686266 -348.558532) (xy 23.686266 -348.613068) (xy 23.686266 -348.613069) (xy 25.169114 -348.613069)
			(xy 25.169114 -348.558531) (xy 25.176875 -348.504549) (xy 25.19224 -348.452221) (xy 25.214894 -348.402611)
			(xy 25.244378 -348.356731) (xy 25.28009 -348.315513) (xy 25.321305 -348.279797) (xy 25.367183 -348.250309)
			(xy 25.416791 -348.227651) (xy 25.469118 -348.212282) (xy 25.523099 -348.204517) (xy 25.550368 -348.204028)
			(xy 26.413968 -348.204028) (xy 26.44124 -348.204509) (xy 26.495229 -348.212268) (xy 26.547564 -348.227631)
			(xy 26.59718 -348.250286) (xy 26.643066 -348.279772) (xy 26.684289 -348.315488) (xy 26.720009 -348.356708)
			(xy 26.749499 -348.402592) (xy 26.772158 -348.452206) (xy 26.787526 -348.50454) (xy 26.795288 -348.558528)
			(xy 26.795288 -348.613072) (xy 26.795288 -348.613073) (xy 28.277992 -348.613073) (xy 28.277992 -348.558527)
			(xy 28.285755 -348.504536) (xy 28.301123 -348.4522) (xy 28.323783 -348.402584) (xy 28.353274 -348.356697)
			(xy 28.388995 -348.315476) (xy 28.43022 -348.279757) (xy 28.476108 -348.25027) (xy 28.525726 -348.227613)
			(xy 28.578064 -348.212249) (xy 28.632055 -348.20449) (xy 28.659328 -348.204028) (xy 29.522928 -348.204028)
			(xy 29.550195 -348.204536) (xy 29.604175 -348.212301) (xy 29.656499 -348.227668) (xy 29.706105 -348.250326)
			(xy 29.751981 -348.279811) (xy 29.793194 -348.315526) (xy 29.828905 -348.356742) (xy 29.858388 -348.40262)
			(xy 29.881041 -348.452227) (xy 29.896405 -348.504553) (xy 29.904166 -348.558533) (xy 29.904166 -348.613067)
			(xy 29.904166 -348.61307) (xy 31.387014 -348.61307) (xy 31.387014 -348.55853) (xy 31.394776 -348.504546)
			(xy 31.410141 -348.452217) (xy 31.432797 -348.402606) (xy 31.462283 -348.356724) (xy 31.497997 -348.315506)
			(xy 31.539215 -348.27979) (xy 31.585095 -348.250303) (xy 31.634705 -348.227645) (xy 31.687035 -348.212279)
			(xy 31.741018 -348.204515) (xy 31.768288 -348.204028) (xy 32.631888 -348.204028) (xy 32.659159 -348.204511)
			(xy 32.713146 -348.212271) (xy 32.765478 -348.227636) (xy 32.815092 -348.250292) (xy 32.860976 -348.279779)
			(xy 32.902196 -348.315495) (xy 32.937914 -348.356715) (xy 32.967402 -348.402598) (xy 32.99006 -348.45221)
			(xy 33.005426 -348.504543) (xy 33.013189 -348.558529) (xy 33.013189 -348.613071) (xy 33.013189 -348.613074)
			(xy 34.495892 -348.613074) (xy 34.495892 -348.558526) (xy 34.503655 -348.504534) (xy 34.519024 -348.452196)
			(xy 34.541686 -348.402578) (xy 34.571179 -348.356691) (xy 34.606902 -348.315468) (xy 34.648129 -348.27975)
			(xy 34.69402 -348.250263) (xy 34.743641 -348.227608) (xy 34.795981 -348.212245) (xy 34.849974 -348.204488)
			(xy 34.877248 -348.204028) (xy 35.740848 -348.204028) (xy 35.768114 -348.204538) (xy 35.822091 -348.212305)
			(xy 35.874414 -348.227674) (xy 35.924017 -348.250332) (xy 35.96989 -348.279819) (xy 36.011101 -348.315533)
			(xy 36.04681 -348.356748) (xy 36.076291 -348.402626) (xy 36.098943 -348.452231) (xy 36.114306 -348.504556)
			(xy 36.122066 -348.558534) (xy 36.122066 -348.613066) (xy 36.122065 -348.613072) (xy 37.604892 -348.613072)
			(xy 37.604892 -348.558528) (xy 37.612654 -348.504539) (xy 37.628021 -348.452204) (xy 37.65068 -348.402589)
			(xy 37.680169 -348.356704) (xy 37.715888 -348.315483) (xy 37.75711 -348.279764) (xy 37.802996 -348.250276)
			(xy 37.852612 -348.227618) (xy 37.904947 -348.212252) (xy 37.958936 -348.204491) (xy 37.986208 -348.204028)
			(xy 38.849808 -348.204028) (xy 38.877076 -348.204535) (xy 38.931058 -348.212297) (xy 38.983385 -348.227663)
			(xy 39.032993 -348.250319) (xy 39.078871 -348.279804) (xy 39.120087 -348.315519) (xy 39.1558 -348.356735)
			(xy 39.185285 -348.402614) (xy 39.20794 -348.452223) (xy 39.223304 -348.50455) (xy 39.231066 -348.558532)
			(xy 39.231066 -348.613068) (xy 39.231066 -348.613069) (xy 40.713914 -348.613069) (xy 40.713914 -348.558531)
			(xy 40.721675 -348.504549) (xy 40.73704 -348.452221) (xy 40.759694 -348.402611) (xy 40.789178 -348.356731)
			(xy 40.82489 -348.315513) (xy 40.866105 -348.279797) (xy 40.911983 -348.250309) (xy 40.961591 -348.227651)
			(xy 41.013918 -348.212282) (xy 41.067899 -348.204517) (xy 41.095168 -348.204028) (xy 41.958768 -348.204028)
			(xy 41.98604 -348.204509) (xy 42.040029 -348.212268) (xy 42.092364 -348.227631) (xy 42.14198 -348.250286)
			(xy 42.187866 -348.279772) (xy 42.229089 -348.315488) (xy 42.264809 -348.356708) (xy 42.294299 -348.402592)
			(xy 42.316958 -348.452206) (xy 42.332326 -348.50454) (xy 42.340088 -348.558528) (xy 42.340088 -348.613072)
			(xy 42.340088 -348.613073) (xy 43.822792 -348.613073) (xy 43.822792 -348.558527) (xy 43.830555 -348.504536)
			(xy 43.845923 -348.4522) (xy 43.868583 -348.402584) (xy 43.898074 -348.356697) (xy 43.933795 -348.315476)
			(xy 43.97502 -348.279757) (xy 44.020908 -348.25027) (xy 44.070526 -348.227613) (xy 44.122864 -348.212249)
			(xy 44.176855 -348.20449) (xy 44.204128 -348.204028) (xy 45.067728 -348.204028) (xy 45.094995 -348.204536)
			(xy 45.148975 -348.212301) (xy 45.201299 -348.227668) (xy 45.250905 -348.250326) (xy 45.296781 -348.279811)
			(xy 45.337994 -348.315526) (xy 45.373705 -348.356742) (xy 45.403188 -348.40262) (xy 45.425841 -348.452227)
			(xy 45.441205 -348.504553) (xy 45.448966 -348.558533) (xy 45.448966 -348.613067) (xy 45.448966 -348.61307)
			(xy 46.931814 -348.61307) (xy 46.931814 -348.55853) (xy 46.939576 -348.504546) (xy 46.954941 -348.452217)
			(xy 46.977597 -348.402606) (xy 47.007083 -348.356724) (xy 47.042797 -348.315506) (xy 47.084015 -348.27979)
			(xy 47.129895 -348.250303) (xy 47.179505 -348.227645) (xy 47.231835 -348.212279) (xy 47.285818 -348.204515)
			(xy 47.313088 -348.204028) (xy 48.176688 -348.204028) (xy 48.203959 -348.204511) (xy 48.257946 -348.212271)
			(xy 48.310278 -348.227636) (xy 48.359892 -348.250292) (xy 48.405776 -348.279779) (xy 48.446996 -348.315495)
			(xy 48.482714 -348.356715) (xy 48.512202 -348.402598) (xy 48.53486 -348.45221) (xy 48.550226 -348.504543)
			(xy 48.557989 -348.558529) (xy 48.557989 -348.613071) (xy 48.557989 -348.613074) (xy 50.040692 -348.613074)
			(xy 50.040692 -348.558526) (xy 50.048455 -348.504534) (xy 50.063824 -348.452196) (xy 50.086486 -348.402578)
			(xy 50.115979 -348.356691) (xy 50.151702 -348.315468) (xy 50.192929 -348.27975) (xy 50.23882 -348.250263)
			(xy 50.288441 -348.227608) (xy 50.340781 -348.212245) (xy 50.394774 -348.204488) (xy 50.422048 -348.204028)
			(xy 51.285648 -348.204028) (xy 51.312914 -348.204538) (xy 51.366891 -348.212305) (xy 51.419214 -348.227674)
			(xy 51.468817 -348.250332) (xy 51.51469 -348.279819) (xy 51.555901 -348.315533) (xy 51.59161 -348.356748)
			(xy 51.621091 -348.402626) (xy 51.643743 -348.452231) (xy 51.659106 -348.504556) (xy 51.666866 -348.558534)
			(xy 51.666866 -348.613066) (xy 51.666865 -348.613074) (xy 60.990892 -348.613074) (xy 60.990892 -348.558526)
			(xy 60.998655 -348.504534) (xy 61.014024 -348.452197) (xy 61.036685 -348.40258) (xy 61.066177 -348.356693)
			(xy 61.1019 -348.315471) (xy 61.143127 -348.279752) (xy 61.189017 -348.250265) (xy 61.238636 -348.227609)
			(xy 61.290976 -348.212246) (xy 61.344968 -348.204489) (xy 61.372242 -348.204028) (xy 62.235842 -348.204028)
			(xy 62.263109 -348.204537) (xy 62.317086 -348.212304) (xy 62.369409 -348.227672) (xy 62.419013 -348.25033)
			(xy 62.464887 -348.279816) (xy 62.506099 -348.315531) (xy 62.541809 -348.356746) (xy 62.57129 -348.402624)
			(xy 62.593943 -348.45223) (xy 62.609305 -348.504555) (xy 62.617066 -348.558533) (xy 62.617066 -348.613067)
			(xy 62.617065 -348.613072) (xy 64.099892 -348.613072) (xy 64.099892 -348.558528) (xy 64.107654 -348.50454)
			(xy 64.123021 -348.452206) (xy 64.145679 -348.402591) (xy 64.175168 -348.356706) (xy 64.210886 -348.315485)
			(xy 64.252108 -348.279766) (xy 64.297993 -348.250278) (xy 64.347607 -348.22762) (xy 64.399942 -348.212253)
			(xy 64.45393 -348.204491) (xy 64.481202 -348.204028) (xy 65.344802 -348.204028) (xy 65.372071 -348.204535)
			(xy 65.426053 -348.212296) (xy 65.47838 -348.227661) (xy 65.527989 -348.250317) (xy 65.573869 -348.279802)
			(xy 65.615085 -348.315517) (xy 65.650799 -348.356733) (xy 65.680284 -348.402613) (xy 65.702939 -348.452221)
			(xy 65.718304 -348.504549) (xy 65.726066 -348.558531) (xy 65.726066 -348.613068) (xy 67.208914 -348.613068)
			(xy 67.208914 -348.558532) (xy 67.216675 -348.50455) (xy 67.232039 -348.452222) (xy 67.254693 -348.402613)
			(xy 67.284176 -348.356733) (xy 67.319888 -348.315515) (xy 67.361102 -348.279799) (xy 67.40698 -348.250311)
			(xy 67.456586 -348.227652) (xy 67.508913 -348.212283) (xy 67.562894 -348.204517) (xy 67.590162 -348.204028)
			(xy 68.453762 -348.204028) (xy 68.481034 -348.204509) (xy 68.535024 -348.212266) (xy 68.58736 -348.227629)
			(xy 68.636976 -348.250284) (xy 68.682863 -348.27977) (xy 68.724087 -348.315486) (xy 68.759808 -348.356706)
			(xy 68.789298 -348.40259) (xy 68.811958 -348.452205) (xy 68.827326 -348.504539) (xy 68.835088 -348.558528)
			(xy 68.835088 -348.613072) (xy 68.835088 -348.613073) (xy 70.317792 -348.613073) (xy 70.317792 -348.558527)
			(xy 70.325554 -348.504537) (xy 70.340922 -348.452201) (xy 70.363582 -348.402585) (xy 70.393072 -348.356699)
			(xy 70.428793 -348.315478) (xy 70.470017 -348.279759) (xy 70.515905 -348.250271) (xy 70.565522 -348.227615)
			(xy 70.617859 -348.21225) (xy 70.671849 -348.20449) (xy 70.699122 -348.204028) (xy 71.562722 -348.204028)
			(xy 71.58999 -348.204536) (xy 71.643969 -348.2123) (xy 71.696295 -348.227667) (xy 71.745901 -348.250324)
			(xy 71.791778 -348.279809) (xy 71.832992 -348.315524) (xy 71.868704 -348.35674) (xy 71.898187 -348.402618)
			(xy 71.920841 -348.452226) (xy 71.936205 -348.504552) (xy 71.943966 -348.558532) (xy 71.943966 -348.613068)
			(xy 71.943966 -348.613069) (xy 73.426814 -348.613069) (xy 73.426814 -348.558531) (xy 73.434576 -348.504547)
			(xy 73.449941 -348.452218) (xy 73.472596 -348.402608) (xy 73.502081 -348.356726) (xy 73.537795 -348.315508)
			(xy 73.579012 -348.279792) (xy 73.624892 -348.250305) (xy 73.674501 -348.227647) (xy 73.72683 -348.21228)
			(xy 73.780813 -348.204516) (xy 73.808082 -348.204028) (xy 74.671682 -348.204028) (xy 74.698953 -348.20451)
			(xy 74.752941 -348.21227) (xy 74.805274 -348.227634) (xy 74.854888 -348.25029) (xy 74.900773 -348.279777)
			(xy 74.941994 -348.315493) (xy 74.977712 -348.356713) (xy 75.007201 -348.402596) (xy 75.029859 -348.452209)
			(xy 75.045226 -348.504542) (xy 75.052988 -348.558529) (xy 75.052988 -348.613071) (xy 75.052988 -348.613074)
			(xy 76.535692 -348.613074) (xy 76.535692 -348.558526) (xy 76.543455 -348.504534) (xy 76.558824 -348.452197)
			(xy 76.581485 -348.40258) (xy 76.610977 -348.356693) (xy 76.6467 -348.315471) (xy 76.687927 -348.279752)
			(xy 76.733817 -348.250265) (xy 76.783436 -348.227609) (xy 76.835776 -348.212246) (xy 76.889768 -348.204489)
			(xy 76.917042 -348.204028) (xy 77.780642 -348.204028) (xy 77.807909 -348.204537) (xy 77.861886 -348.212304)
			(xy 77.914209 -348.227672) (xy 77.963813 -348.25033) (xy 78.009687 -348.279816) (xy 78.050899 -348.315531)
			(xy 78.086609 -348.356746) (xy 78.11609 -348.402624) (xy 78.138743 -348.45223) (xy 78.154105 -348.504555)
			(xy 78.161866 -348.558533) (xy 78.161866 -348.613067) (xy 78.161865 -348.613072) (xy 79.644692 -348.613072)
			(xy 79.644692 -348.558528) (xy 79.652454 -348.50454) (xy 79.667821 -348.452206) (xy 79.690479 -348.402591)
			(xy 79.719968 -348.356706) (xy 79.755686 -348.315485) (xy 79.796908 -348.279766) (xy 79.842793 -348.250278)
			(xy 79.892407 -348.22762) (xy 79.944742 -348.212253) (xy 79.99873 -348.204491) (xy 80.026002 -348.204028)
			(xy 80.889602 -348.204028) (xy 80.916871 -348.204535) (xy 80.970853 -348.212296) (xy 81.02318 -348.227661)
			(xy 81.072789 -348.250317) (xy 81.118669 -348.279802) (xy 81.159885 -348.315517) (xy 81.195599 -348.356733)
			(xy 81.225084 -348.402613) (xy 81.247739 -348.452221) (xy 81.263104 -348.504549) (xy 81.270866 -348.558531)
			(xy 81.270866 -348.613068) (xy 82.753714 -348.613068) (xy 82.753714 -348.558532) (xy 82.761475 -348.50455)
			(xy 82.776839 -348.452222) (xy 82.799493 -348.402613) (xy 82.828976 -348.356733) (xy 82.864688 -348.315515)
			(xy 82.905902 -348.279799) (xy 82.95178 -348.250311) (xy 83.001386 -348.227652) (xy 83.053713 -348.212283)
			(xy 83.107694 -348.204517) (xy 83.134962 -348.204028) (xy 83.998562 -348.204028) (xy 84.025834 -348.204509)
			(xy 84.079824 -348.212266) (xy 84.13216 -348.227629) (xy 84.181776 -348.250284) (xy 84.227663 -348.27977)
			(xy 84.268887 -348.315486) (xy 84.304608 -348.356706) (xy 84.334098 -348.40259) (xy 84.356758 -348.452205)
			(xy 84.372126 -348.504539) (xy 84.379888 -348.558528) (xy 84.379888 -348.613072) (xy 84.379888 -348.613073)
			(xy 85.862592 -348.613073) (xy 85.862592 -348.558527) (xy 85.870354 -348.504537) (xy 85.885722 -348.452201)
			(xy 85.908382 -348.402585) (xy 85.937872 -348.356699) (xy 85.973593 -348.315478) (xy 86.014817 -348.279759)
			(xy 86.060705 -348.250271) (xy 86.110322 -348.227615) (xy 86.162659 -348.21225) (xy 86.216649 -348.20449)
			(xy 86.243922 -348.204028) (xy 87.107522 -348.204028) (xy 87.13479 -348.204536) (xy 87.188769 -348.2123)
			(xy 87.241095 -348.227667) (xy 87.290701 -348.250324) (xy 87.336578 -348.279809) (xy 87.377792 -348.315524)
			(xy 87.413504 -348.35674) (xy 87.442987 -348.402618) (xy 87.465641 -348.452226) (xy 87.481005 -348.504552)
			(xy 87.488766 -348.558532) (xy 87.488766 -348.613068) (xy 87.488766 -348.613069) (xy 88.971614 -348.613069)
			(xy 88.971614 -348.558531) (xy 88.979376 -348.504547) (xy 88.994741 -348.452218) (xy 89.017396 -348.402608)
			(xy 89.046881 -348.356726) (xy 89.082595 -348.315508) (xy 89.123812 -348.279792) (xy 89.169692 -348.250305)
			(xy 89.219301 -348.227647) (xy 89.27163 -348.21228) (xy 89.325613 -348.204516) (xy 89.352882 -348.204028)
			(xy 90.216482 -348.204028) (xy 90.243753 -348.20451) (xy 90.297741 -348.21227) (xy 90.350074 -348.227634)
			(xy 90.399688 -348.25029) (xy 90.445573 -348.279777) (xy 90.486794 -348.315493) (xy 90.522512 -348.356713)
			(xy 90.552001 -348.402596) (xy 90.574659 -348.452209) (xy 90.590026 -348.504542) (xy 90.597788 -348.558529)
			(xy 90.597788 -348.613071) (xy 90.597788 -348.613074) (xy 92.080492 -348.613074) (xy 92.080492 -348.558526)
			(xy 92.088255 -348.504534) (xy 92.103624 -348.452197) (xy 92.126285 -348.40258) (xy 92.155777 -348.356693)
			(xy 92.1915 -348.315471) (xy 92.232727 -348.279752) (xy 92.278617 -348.250265) (xy 92.328236 -348.227609)
			(xy 92.380576 -348.212246) (xy 92.434568 -348.204489) (xy 92.461842 -348.204028) (xy 93.325442 -348.204028)
			(xy 93.352709 -348.204537) (xy 93.406686 -348.212304) (xy 93.459009 -348.227672) (xy 93.508613 -348.25033)
			(xy 93.554487 -348.279816) (xy 93.595699 -348.315531) (xy 93.631409 -348.356746) (xy 93.66089 -348.402624)
			(xy 93.683543 -348.45223) (xy 93.698905 -348.504555) (xy 93.706666 -348.558533) (xy 93.706666 -348.613067)
			(xy 93.706665 -348.613072) (xy 111.480792 -348.613072) (xy 111.480792 -348.558528) (xy 111.488554 -348.504539)
			(xy 111.503921 -348.452204) (xy 111.52658 -348.402589) (xy 111.556069 -348.356704) (xy 111.591788 -348.315483)
			(xy 111.63301 -348.279764) (xy 111.678896 -348.250276) (xy 111.728512 -348.227618) (xy 111.780847 -348.212252)
			(xy 111.834836 -348.204491) (xy 111.862108 -348.204028) (xy 112.725708 -348.204028) (xy 112.752976 -348.204535)
			(xy 112.806958 -348.212297) (xy 112.859285 -348.227663) (xy 112.908893 -348.250319) (xy 112.954771 -348.279804)
			(xy 112.995987 -348.315519) (xy 113.0317 -348.356735) (xy 113.061185 -348.402614) (xy 113.08384 -348.452223)
			(xy 113.099204 -348.50455) (xy 113.106966 -348.558532) (xy 113.106966 -348.613068) (xy 113.106966 -348.613069)
			(xy 114.589814 -348.613069) (xy 114.589814 -348.558531) (xy 114.597575 -348.504549) (xy 114.61294 -348.452221)
			(xy 114.635594 -348.402611) (xy 114.665078 -348.356731) (xy 114.70079 -348.315513) (xy 114.742005 -348.279797)
			(xy 114.787883 -348.250309) (xy 114.837491 -348.227651) (xy 114.889818 -348.212282) (xy 114.943799 -348.204517)
			(xy 114.971068 -348.204028) (xy 115.834668 -348.204028) (xy 115.86194 -348.204509) (xy 115.915929 -348.212268)
			(xy 115.968264 -348.227631) (xy 116.01788 -348.250286) (xy 116.063766 -348.279772) (xy 116.104989 -348.315488)
			(xy 116.140709 -348.356708) (xy 116.170199 -348.402592) (xy 116.192858 -348.452206) (xy 116.208226 -348.50454)
			(xy 116.215988 -348.558528) (xy 116.215988 -348.613072) (xy 116.215988 -348.613073) (xy 117.698692 -348.613073)
			(xy 117.698692 -348.558527) (xy 117.706455 -348.504536) (xy 117.721823 -348.4522) (xy 117.744483 -348.402584)
			(xy 117.773974 -348.356697) (xy 117.809695 -348.315476) (xy 117.85092 -348.279757) (xy 117.896808 -348.25027)
			(xy 117.946426 -348.227613) (xy 117.998764 -348.212249) (xy 118.052755 -348.20449) (xy 118.080028 -348.204028)
			(xy 118.943628 -348.204028) (xy 118.970895 -348.204536) (xy 119.024875 -348.212301) (xy 119.077199 -348.227668)
			(xy 119.126805 -348.250326) (xy 119.172681 -348.279811) (xy 119.213894 -348.315526) (xy 119.249605 -348.356742)
			(xy 119.279088 -348.40262) (xy 119.301741 -348.452227) (xy 119.317105 -348.504553) (xy 119.324866 -348.558533)
			(xy 119.324866 -348.613067) (xy 119.324866 -348.61307) (xy 120.807714 -348.61307) (xy 120.807714 -348.55853)
			(xy 120.815476 -348.504546) (xy 120.830841 -348.452217) (xy 120.853497 -348.402606) (xy 120.882983 -348.356724)
			(xy 120.918697 -348.315506) (xy 120.959915 -348.27979) (xy 121.005795 -348.250303) (xy 121.055405 -348.227645)
			(xy 121.107735 -348.212279) (xy 121.161718 -348.204515) (xy 121.188988 -348.204028) (xy 122.052588 -348.204028)
			(xy 122.079859 -348.204511) (xy 122.133846 -348.212271) (xy 122.186178 -348.227636) (xy 122.235792 -348.250292)
			(xy 122.281676 -348.279779) (xy 122.322896 -348.315495) (xy 122.358614 -348.356715) (xy 122.388102 -348.402598)
			(xy 122.41076 -348.45221) (xy 122.426126 -348.504543) (xy 122.433889 -348.558529) (xy 122.433889 -348.613071)
			(xy 122.433889 -348.613074) (xy 123.916592 -348.613074) (xy 123.916592 -348.558526) (xy 123.924355 -348.504534)
			(xy 123.939724 -348.452196) (xy 123.962386 -348.402578) (xy 123.991879 -348.356691) (xy 124.027602 -348.315468)
			(xy 124.068829 -348.27975) (xy 124.11472 -348.250263) (xy 124.164341 -348.227608) (xy 124.216681 -348.212245)
			(xy 124.270674 -348.204488) (xy 124.297948 -348.204028) (xy 125.161548 -348.204028) (xy 125.188814 -348.204538)
			(xy 125.242791 -348.212305) (xy 125.295114 -348.227674) (xy 125.344717 -348.250332) (xy 125.39059 -348.279819)
			(xy 125.431801 -348.315533) (xy 125.46751 -348.356748) (xy 125.496991 -348.402626) (xy 125.519643 -348.452231)
			(xy 125.535006 -348.504556) (xy 125.542766 -348.558534) (xy 125.542766 -348.613066) (xy 125.542765 -348.613072)
			(xy 127.025592 -348.613072) (xy 127.025592 -348.558528) (xy 127.033354 -348.504539) (xy 127.048721 -348.452204)
			(xy 127.07138 -348.402589) (xy 127.100869 -348.356704) (xy 127.136588 -348.315483) (xy 127.17781 -348.279764)
			(xy 127.223696 -348.250276) (xy 127.273312 -348.227618) (xy 127.325647 -348.212252) (xy 127.379636 -348.204491)
			(xy 127.406908 -348.204028) (xy 128.270508 -348.204028) (xy 128.297776 -348.204535) (xy 128.351758 -348.212297)
			(xy 128.404085 -348.227663) (xy 128.453693 -348.250319) (xy 128.499571 -348.279804) (xy 128.540787 -348.315519)
			(xy 128.5765 -348.356735) (xy 128.605985 -348.402614) (xy 128.62864 -348.452223) (xy 128.644004 -348.50455)
			(xy 128.651766 -348.558532) (xy 128.651766 -348.613068) (xy 128.651766 -348.613069) (xy 130.134614 -348.613069)
			(xy 130.134614 -348.558531) (xy 130.142375 -348.504549) (xy 130.15774 -348.452221) (xy 130.180394 -348.402611)
			(xy 130.209878 -348.356731) (xy 130.24559 -348.315513) (xy 130.286805 -348.279797) (xy 130.332683 -348.250309)
			(xy 130.382291 -348.227651) (xy 130.434618 -348.212282) (xy 130.488599 -348.204517) (xy 130.515868 -348.204028)
			(xy 131.379468 -348.204028) (xy 131.40674 -348.204509) (xy 131.460729 -348.212268) (xy 131.513064 -348.227631)
			(xy 131.56268 -348.250286) (xy 131.608566 -348.279772) (xy 131.649789 -348.315488) (xy 131.685509 -348.356708)
			(xy 131.714999 -348.402592) (xy 131.737658 -348.452206) (xy 131.753026 -348.50454) (xy 131.760788 -348.558528)
			(xy 131.760788 -348.613072) (xy 131.760788 -348.613073) (xy 133.243492 -348.613073) (xy 133.243492 -348.558527)
			(xy 133.251255 -348.504536) (xy 133.266623 -348.4522) (xy 133.289283 -348.402584) (xy 133.318774 -348.356697)
			(xy 133.354495 -348.315476) (xy 133.39572 -348.279757) (xy 133.441608 -348.25027) (xy 133.491226 -348.227613)
			(xy 133.543564 -348.212249) (xy 133.597555 -348.20449) (xy 133.624828 -348.204028) (xy 134.488428 -348.204028)
			(xy 134.515695 -348.204536) (xy 134.569675 -348.212301) (xy 134.621999 -348.227668) (xy 134.671605 -348.250326)
			(xy 134.717481 -348.279811) (xy 134.758694 -348.315526) (xy 134.794405 -348.356742) (xy 134.823888 -348.40262)
			(xy 134.846541 -348.452227) (xy 134.861905 -348.504553) (xy 134.869666 -348.558533) (xy 134.869666 -348.613067)
			(xy 134.869666 -348.61307) (xy 136.352514 -348.61307) (xy 136.352514 -348.55853) (xy 136.360276 -348.504546)
			(xy 136.375641 -348.452217) (xy 136.398297 -348.402606) (xy 136.427783 -348.356724) (xy 136.463497 -348.315506)
			(xy 136.504715 -348.27979) (xy 136.550595 -348.250303) (xy 136.600205 -348.227645) (xy 136.652535 -348.212279)
			(xy 136.706518 -348.204515) (xy 136.733788 -348.204028) (xy 137.597388 -348.204028) (xy 137.624659 -348.204511)
			(xy 137.678646 -348.212271) (xy 137.730978 -348.227636) (xy 137.780592 -348.250292) (xy 137.826476 -348.279779)
			(xy 137.867696 -348.315495) (xy 137.903414 -348.356715) (xy 137.932902 -348.402598) (xy 137.95556 -348.45221)
			(xy 137.970926 -348.504543) (xy 137.978689 -348.558529) (xy 137.978689 -348.613071) (xy 137.978689 -348.613074)
			(xy 139.461392 -348.613074) (xy 139.461392 -348.558526) (xy 139.469155 -348.504534) (xy 139.484524 -348.452196)
			(xy 139.507186 -348.402578) (xy 139.536679 -348.356691) (xy 139.572402 -348.315468) (xy 139.613629 -348.27975)
			(xy 139.65952 -348.250263) (xy 139.709141 -348.227608) (xy 139.761481 -348.212245) (xy 139.815474 -348.204488)
			(xy 139.842748 -348.204028) (xy 140.706348 -348.204028) (xy 140.733614 -348.204538) (xy 140.787591 -348.212305)
			(xy 140.839914 -348.227674) (xy 140.889517 -348.250332) (xy 140.93539 -348.279819) (xy 140.976601 -348.315533)
			(xy 141.01231 -348.356748) (xy 141.041791 -348.402626) (xy 141.064443 -348.452231) (xy 141.079806 -348.504556)
			(xy 141.087566 -348.558534) (xy 141.087566 -348.613066) (xy 141.087565 -348.613072) (xy 142.570392 -348.613072)
			(xy 142.570392 -348.558528) (xy 142.578154 -348.504539) (xy 142.593521 -348.452204) (xy 142.61618 -348.402589)
			(xy 142.645669 -348.356704) (xy 142.681388 -348.315483) (xy 142.72261 -348.279764) (xy 142.768496 -348.250276)
			(xy 142.818112 -348.227618) (xy 142.870447 -348.212252) (xy 142.924436 -348.204491) (xy 142.951708 -348.204028)
			(xy 143.815308 -348.204028) (xy 143.842576 -348.204535) (xy 143.896558 -348.212297) (xy 143.948885 -348.227663)
			(xy 143.998493 -348.250319) (xy 144.044371 -348.279804) (xy 144.085587 -348.315519) (xy 144.1213 -348.356735)
			(xy 144.150785 -348.402614) (xy 144.17344 -348.452223) (xy 144.188804 -348.50455) (xy 144.196566 -348.558532)
			(xy 144.196566 -348.613068) (xy 144.196565 -348.613072) (xy 161.804792 -348.613072) (xy 161.804792 -348.558528)
			(xy 161.812554 -348.504538) (xy 161.827921 -348.452203) (xy 161.850581 -348.402588) (xy 161.88007 -348.356703)
			(xy 161.91579 -348.315481) (xy 161.957012 -348.279763) (xy 162.002899 -348.250275) (xy 162.052515 -348.227617)
			(xy 162.10485 -348.212252) (xy 162.15884 -348.204491) (xy 162.186112 -348.204028) (xy 163.049712 -348.204028)
			(xy 163.07698 -348.204535) (xy 163.130961 -348.212298) (xy 163.183288 -348.227664) (xy 163.232895 -348.25032)
			(xy 163.278773 -348.279806) (xy 163.319988 -348.31552) (xy 163.355701 -348.356736) (xy 163.385185 -348.402615)
			(xy 163.40784 -348.452224) (xy 163.423204 -348.504551) (xy 163.430966 -348.558532) (xy 163.430966 -348.613068)
			(xy 163.430966 -348.613069) (xy 164.913814 -348.613069) (xy 164.913814 -348.558531) (xy 164.921576 -348.504549)
			(xy 164.93694 -348.45222) (xy 164.959595 -348.40261) (xy 164.989079 -348.35673) (xy 165.024792 -348.315512)
			(xy 165.066007 -348.279795) (xy 165.111886 -348.250308) (xy 165.161494 -348.22765) (xy 165.213821 -348.212281)
			(xy 165.267803 -348.204516) (xy 165.295072 -348.204028) (xy 166.158672 -348.204028) (xy 166.185944 -348.20451)
			(xy 166.239932 -348.212268) (xy 166.292267 -348.227632) (xy 166.341882 -348.250287) (xy 166.387768 -348.279773)
			(xy 166.42899 -348.31549) (xy 166.46471 -348.356709) (xy 166.494199 -348.402593) (xy 166.516859 -348.452207)
			(xy 166.532226 -348.504541) (xy 166.539988 -348.558528) (xy 166.539988 -348.613072) (xy 166.539988 -348.613073)
			(xy 168.022692 -348.613073) (xy 168.022692 -348.558527) (xy 168.030455 -348.504536) (xy 168.045823 -348.452199)
			(xy 168.068484 -348.402583) (xy 168.097975 -348.356696) (xy 168.133697 -348.315474) (xy 168.174922 -348.279756)
			(xy 168.220811 -348.250268) (xy 168.270429 -348.227612) (xy 168.322767 -348.212248) (xy 168.376759 -348.204489)
			(xy 168.404032 -348.204028) (xy 169.267632 -348.204028) (xy 169.294899 -348.204537) (xy 169.348878 -348.212302)
			(xy 169.401202 -348.227669) (xy 169.450807 -348.250327) (xy 169.496683 -348.279813) (xy 169.537895 -348.315527)
			(xy 169.573606 -348.356743) (xy 169.603088 -348.402621) (xy 169.625742 -348.452228) (xy 169.641105 -348.504553)
			(xy 169.648866 -348.558533) (xy 169.648866 -348.613067) (xy 169.648866 -348.61307) (xy 171.131714 -348.61307)
			(xy 171.131714 -348.55853) (xy 171.139476 -348.504546) (xy 171.154841 -348.452216) (xy 171.177498 -348.402605)
			(xy 171.206984 -348.356723) (xy 171.242699 -348.315505) (xy 171.283917 -348.279788) (xy 171.329798 -348.250301)
			(xy 171.379408 -348.227644) (xy 171.431738 -348.212278) (xy 171.485722 -348.204515) (xy 171.512992 -348.204028)
			(xy 172.376592 -348.204028) (xy 172.403863 -348.204511) (xy 172.457849 -348.212272) (xy 172.510181 -348.227637)
			(xy 172.559794 -348.250294) (xy 172.605678 -348.27978) (xy 172.646898 -348.315497) (xy 172.682615 -348.356716)
			(xy 172.712103 -348.402599) (xy 172.73476 -348.452211) (xy 172.750126 -348.504543) (xy 172.757889 -348.558529)
			(xy 172.757889 -348.613068) (xy 174.240714 -348.613068) (xy 174.240714 -348.558532) (xy 174.248475 -348.504551)
			(xy 174.263838 -348.452224) (xy 174.286492 -348.402616) (xy 174.315974 -348.356736) (xy 174.351685 -348.315519)
			(xy 174.392898 -348.279803) (xy 174.438774 -348.250315) (xy 174.488379 -348.227655) (xy 174.540704 -348.212285)
			(xy 174.594684 -348.204518) (xy 174.621952 -348.204028) (xy 175.485552 -348.204028) (xy 175.512825 -348.204508)
			(xy 175.566815 -348.212265) (xy 175.619152 -348.227626) (xy 175.66877 -348.250281) (xy 175.714659 -348.279766)
			(xy 175.755883 -348.315483) (xy 175.791605 -348.356703) (xy 175.821096 -348.402588) (xy 175.843757 -348.452203)
			(xy 175.859125 -348.504538) (xy 175.866888 -348.558528) (xy 175.866888 -348.613072) (xy 177.349592 -348.613072)
			(xy 177.349592 -348.558528) (xy 177.357354 -348.504538) (xy 177.372721 -348.452203) (xy 177.395381 -348.402588)
			(xy 177.42487 -348.356703) (xy 177.46059 -348.315481) (xy 177.501812 -348.279763) (xy 177.547699 -348.250275)
			(xy 177.597315 -348.227617) (xy 177.64965 -348.212252) (xy 177.70364 -348.204491) (xy 177.730912 -348.204028)
			(xy 178.594512 -348.204028) (xy 178.62178 -348.204535) (xy 178.675761 -348.212298) (xy 178.728088 -348.227664)
			(xy 178.777695 -348.25032) (xy 178.823573 -348.279806) (xy 178.864788 -348.31552) (xy 178.900501 -348.356736)
			(xy 178.929985 -348.402615) (xy 178.95264 -348.452224) (xy 178.968004 -348.504551) (xy 178.975766 -348.558532)
			(xy 178.975766 -348.613068) (xy 178.975766 -348.613069) (xy 180.458614 -348.613069) (xy 180.458614 -348.558531)
			(xy 180.466376 -348.504549) (xy 180.48174 -348.45222) (xy 180.504395 -348.40261) (xy 180.533879 -348.35673)
			(xy 180.569592 -348.315512) (xy 180.610807 -348.279795) (xy 180.656686 -348.250308) (xy 180.706294 -348.22765)
			(xy 180.758621 -348.212281) (xy 180.812603 -348.204516) (xy 180.839872 -348.204028) (xy 181.703472 -348.204028)
			(xy 181.730744 -348.20451) (xy 181.784732 -348.212268) (xy 181.837067 -348.227632) (xy 181.886682 -348.250287)
			(xy 181.932568 -348.279773) (xy 181.97379 -348.31549) (xy 182.00951 -348.356709) (xy 182.038999 -348.402593)
			(xy 182.061659 -348.452207) (xy 182.077026 -348.504541) (xy 182.084788 -348.558528) (xy 182.084788 -348.613072)
			(xy 182.084788 -348.613073) (xy 183.567492 -348.613073) (xy 183.567492 -348.558527) (xy 183.575255 -348.504536)
			(xy 183.590623 -348.452199) (xy 183.613284 -348.402583) (xy 183.642775 -348.356696) (xy 183.678497 -348.315474)
			(xy 183.719722 -348.279756) (xy 183.765611 -348.250268) (xy 183.815229 -348.227612) (xy 183.867567 -348.212248)
			(xy 183.921559 -348.204489) (xy 183.948832 -348.204028) (xy 184.812432 -348.204028) (xy 184.839699 -348.204537)
			(xy 184.893678 -348.212302) (xy 184.946002 -348.227669) (xy 184.995607 -348.250327) (xy 185.041483 -348.279813)
			(xy 185.082695 -348.315527) (xy 185.118406 -348.356743) (xy 185.147888 -348.402621) (xy 185.170542 -348.452228)
			(xy 185.185905 -348.504553) (xy 185.193666 -348.558533) (xy 185.193666 -348.613067) (xy 185.193666 -348.61307)
			(xy 186.676514 -348.61307) (xy 186.676514 -348.55853) (xy 186.684276 -348.504546) (xy 186.699641 -348.452216)
			(xy 186.722298 -348.402605) (xy 186.751784 -348.356723) (xy 186.787499 -348.315505) (xy 186.828717 -348.279788)
			(xy 186.874598 -348.250301) (xy 186.924208 -348.227644) (xy 186.976538 -348.212278) (xy 187.030522 -348.204515)
			(xy 187.057792 -348.204028) (xy 187.921392 -348.204028) (xy 187.948663 -348.204511) (xy 188.002649 -348.212272)
			(xy 188.054981 -348.227637) (xy 188.104594 -348.250294) (xy 188.150478 -348.27978) (xy 188.191698 -348.315497)
			(xy 188.227415 -348.356716) (xy 188.256903 -348.402599) (xy 188.27956 -348.452211) (xy 188.294926 -348.504543)
			(xy 188.302689 -348.558529) (xy 188.302689 -348.613068) (xy 189.785514 -348.613068) (xy 189.785514 -348.558532)
			(xy 189.793275 -348.504551) (xy 189.808638 -348.452224) (xy 189.831292 -348.402616) (xy 189.860774 -348.356736)
			(xy 189.896485 -348.315519) (xy 189.937698 -348.279803) (xy 189.983574 -348.250315) (xy 190.033179 -348.227655)
			(xy 190.085504 -348.212285) (xy 190.139484 -348.204518) (xy 190.166752 -348.204028) (xy 191.030352 -348.204028)
			(xy 191.057625 -348.204508) (xy 191.111615 -348.212265) (xy 191.163952 -348.227626) (xy 191.21357 -348.250281)
			(xy 191.259459 -348.279766) (xy 191.300683 -348.315483) (xy 191.336405 -348.356703) (xy 191.365896 -348.402588)
			(xy 191.388557 -348.452203) (xy 191.403925 -348.504538) (xy 191.411688 -348.558528) (xy 191.411688 -348.613072)
			(xy 192.894392 -348.613072) (xy 192.894392 -348.558528) (xy 192.902154 -348.504538) (xy 192.917521 -348.452203)
			(xy 192.940181 -348.402588) (xy 192.96967 -348.356703) (xy 193.00539 -348.315481) (xy 193.046612 -348.279763)
			(xy 193.092499 -348.250275) (xy 193.142115 -348.227617) (xy 193.19445 -348.212252) (xy 193.24844 -348.204491)
			(xy 193.275712 -348.204028) (xy 194.139312 -348.204028) (xy 194.16658 -348.204535) (xy 194.220561 -348.212298)
			(xy 194.272888 -348.227664) (xy 194.322495 -348.25032) (xy 194.368373 -348.279806) (xy 194.409588 -348.31552)
			(xy 194.445301 -348.356736) (xy 194.474785 -348.402615) (xy 194.49744 -348.452224) (xy 194.512804 -348.504551)
			(xy 194.520566 -348.558532) (xy 194.520566 -348.613068) (xy 194.520565 -348.613072) (xy 267.515792 -348.613072)
			(xy 267.515792 -348.558528) (xy 267.523554 -348.50454) (xy 267.538921 -348.452206) (xy 267.561579 -348.402591)
			(xy 267.591068 -348.356706) (xy 267.626786 -348.315485) (xy 267.668008 -348.279766) (xy 267.713893 -348.250278)
			(xy 267.763507 -348.22762) (xy 267.815842 -348.212253) (xy 267.86983 -348.204491) (xy 267.897102 -348.204028)
			(xy 268.760702 -348.204028) (xy 268.787971 -348.204535) (xy 268.841953 -348.212296) (xy 268.89428 -348.227661)
			(xy 268.943889 -348.250317) (xy 268.989769 -348.279802) (xy 269.030985 -348.315517) (xy 269.066699 -348.356733)
			(xy 269.096184 -348.402613) (xy 269.118839 -348.452221) (xy 269.134204 -348.504549) (xy 269.141966 -348.558531)
			(xy 269.141966 -348.613068) (xy 270.624814 -348.613068) (xy 270.624814 -348.558532) (xy 270.632575 -348.50455)
			(xy 270.647939 -348.452222) (xy 270.670593 -348.402613) (xy 270.700076 -348.356733) (xy 270.735788 -348.315515)
			(xy 270.777002 -348.279799) (xy 270.82288 -348.250311) (xy 270.872486 -348.227652) (xy 270.924813 -348.212283)
			(xy 270.978794 -348.204517) (xy 271.006062 -348.204028) (xy 271.869662 -348.204028) (xy 271.896934 -348.204509)
			(xy 271.950924 -348.212266) (xy 272.00326 -348.227629) (xy 272.052876 -348.250284) (xy 272.098763 -348.27977)
			(xy 272.139987 -348.315486) (xy 272.175708 -348.356706) (xy 272.205198 -348.40259) (xy 272.227858 -348.452205)
			(xy 272.243226 -348.504539) (xy 272.250988 -348.558528) (xy 272.250988 -348.613072) (xy 272.250988 -348.613073)
			(xy 273.733692 -348.613073) (xy 273.733692 -348.558527) (xy 273.741454 -348.504537) (xy 273.756822 -348.452201)
			(xy 273.779482 -348.402585) (xy 273.808972 -348.356699) (xy 273.844693 -348.315478) (xy 273.885917 -348.279759)
			(xy 273.931805 -348.250271) (xy 273.981422 -348.227615) (xy 274.033759 -348.21225) (xy 274.087749 -348.20449)
			(xy 274.115022 -348.204028) (xy 274.978622 -348.204028) (xy 275.00589 -348.204536) (xy 275.059869 -348.2123)
			(xy 275.112195 -348.227667) (xy 275.161801 -348.250324) (xy 275.207678 -348.279809) (xy 275.248892 -348.315524)
			(xy 275.284604 -348.35674) (xy 275.314087 -348.402618) (xy 275.336741 -348.452226) (xy 275.352105 -348.504552)
			(xy 275.359866 -348.558532) (xy 275.359866 -348.613068) (xy 275.359866 -348.613069) (xy 276.842714 -348.613069)
			(xy 276.842714 -348.558531) (xy 276.850476 -348.504547) (xy 276.865841 -348.452218) (xy 276.888496 -348.402608)
			(xy 276.917981 -348.356726) (xy 276.953695 -348.315508) (xy 276.994912 -348.279792) (xy 277.040792 -348.250305)
			(xy 277.090401 -348.227647) (xy 277.14273 -348.21228) (xy 277.196713 -348.204516) (xy 277.223982 -348.204028)
			(xy 278.087582 -348.204028) (xy 278.114853 -348.20451) (xy 278.168841 -348.21227) (xy 278.221174 -348.227634)
			(xy 278.270788 -348.25029) (xy 278.316673 -348.279777) (xy 278.357894 -348.315493) (xy 278.393612 -348.356713)
			(xy 278.423101 -348.402596) (xy 278.445759 -348.452209) (xy 278.461126 -348.504542) (xy 278.468888 -348.558529)
			(xy 278.468888 -348.613071) (xy 278.468888 -348.613074) (xy 279.951592 -348.613074) (xy 279.951592 -348.558526)
			(xy 279.959355 -348.504534) (xy 279.974724 -348.452197) (xy 279.997385 -348.40258) (xy 280.026877 -348.356693)
			(xy 280.0626 -348.315471) (xy 280.103827 -348.279752) (xy 280.149717 -348.250265) (xy 280.199336 -348.227609)
			(xy 280.251676 -348.212246) (xy 280.305668 -348.204489) (xy 280.332942 -348.204028) (xy 281.196542 -348.204028)
			(xy 281.223809 -348.204537) (xy 281.277786 -348.212304) (xy 281.330109 -348.227672) (xy 281.379713 -348.25033)
			(xy 281.425587 -348.279816) (xy 281.466799 -348.315531) (xy 281.502509 -348.356746) (xy 281.53199 -348.402624)
			(xy 281.554643 -348.45223) (xy 281.570005 -348.504555) (xy 281.577766 -348.558533) (xy 281.577766 -348.613067)
			(xy 281.577765 -348.613072) (xy 283.060592 -348.613072) (xy 283.060592 -348.558528) (xy 283.068354 -348.50454)
			(xy 283.083721 -348.452206) (xy 283.106379 -348.402591) (xy 283.135868 -348.356706) (xy 283.171586 -348.315485)
			(xy 283.212808 -348.279766) (xy 283.258693 -348.250278) (xy 283.308307 -348.22762) (xy 283.360642 -348.212253)
			(xy 283.41463 -348.204491) (xy 283.441902 -348.204028) (xy 284.305502 -348.204028) (xy 284.332771 -348.204535)
			(xy 284.386753 -348.212296) (xy 284.43908 -348.227661) (xy 284.488689 -348.250317) (xy 284.534569 -348.279802)
			(xy 284.575785 -348.315517) (xy 284.611499 -348.356733) (xy 284.640984 -348.402613) (xy 284.663639 -348.452221)
			(xy 284.679004 -348.504549) (xy 284.686766 -348.558531) (xy 284.686766 -348.613068) (xy 286.169614 -348.613068)
			(xy 286.169614 -348.558532) (xy 286.177375 -348.50455) (xy 286.192739 -348.452222) (xy 286.215393 -348.402613)
			(xy 286.244876 -348.356733) (xy 286.280588 -348.315515) (xy 286.321802 -348.279799) (xy 286.36768 -348.250311)
			(xy 286.417286 -348.227652) (xy 286.469613 -348.212283) (xy 286.523594 -348.204517) (xy 286.550862 -348.204028)
			(xy 287.414462 -348.204028) (xy 287.441734 -348.204509) (xy 287.495724 -348.212266) (xy 287.54806 -348.227629)
			(xy 287.597676 -348.250284) (xy 287.643563 -348.27977) (xy 287.684787 -348.315486) (xy 287.720508 -348.356706)
			(xy 287.749998 -348.40259) (xy 287.772658 -348.452205) (xy 287.788026 -348.504539) (xy 287.795788 -348.558528)
			(xy 287.795788 -348.613072) (xy 287.795788 -348.613073) (xy 289.278492 -348.613073) (xy 289.278492 -348.558527)
			(xy 289.286254 -348.504537) (xy 289.301622 -348.452201) (xy 289.324282 -348.402585) (xy 289.353772 -348.356699)
			(xy 289.389493 -348.315478) (xy 289.430717 -348.279759) (xy 289.476605 -348.250271) (xy 289.526222 -348.227615)
			(xy 289.578559 -348.21225) (xy 289.632549 -348.20449) (xy 289.659822 -348.204028) (xy 290.523422 -348.204028)
			(xy 290.55069 -348.204536) (xy 290.604669 -348.2123) (xy 290.656995 -348.227667) (xy 290.706601 -348.250324)
			(xy 290.752478 -348.279809) (xy 290.793692 -348.315524) (xy 290.829404 -348.35674) (xy 290.858887 -348.402618)
			(xy 290.881541 -348.452226) (xy 290.896905 -348.504552) (xy 290.904666 -348.558532) (xy 290.904666 -348.613068)
			(xy 290.904666 -348.613069) (xy 292.387514 -348.613069) (xy 292.387514 -348.558531) (xy 292.395276 -348.504547)
			(xy 292.410641 -348.452218) (xy 292.433296 -348.402608) (xy 292.462781 -348.356726) (xy 292.498495 -348.315508)
			(xy 292.539712 -348.279792) (xy 292.585592 -348.250305) (xy 292.635201 -348.227647) (xy 292.68753 -348.21228)
			(xy 292.741513 -348.204516) (xy 292.768782 -348.204028) (xy 293.632382 -348.204028) (xy 293.659653 -348.20451)
			(xy 293.713641 -348.21227) (xy 293.765974 -348.227634) (xy 293.815588 -348.25029) (xy 293.861473 -348.279777)
			(xy 293.902694 -348.315493) (xy 293.938412 -348.356713) (xy 293.967901 -348.402596) (xy 293.990559 -348.452209)
			(xy 294.005926 -348.504542) (xy 294.013688 -348.558529) (xy 294.013688 -348.613071) (xy 294.013688 -348.613074)
			(xy 295.496392 -348.613074) (xy 295.496392 -348.558526) (xy 295.504155 -348.504534) (xy 295.519524 -348.452197)
			(xy 295.542185 -348.40258) (xy 295.571677 -348.356693) (xy 295.6074 -348.315471) (xy 295.648627 -348.279752)
			(xy 295.694517 -348.250265) (xy 295.744136 -348.227609) (xy 295.796476 -348.212246) (xy 295.850468 -348.204489)
			(xy 295.877742 -348.204028) (xy 296.741342 -348.204028) (xy 296.768609 -348.204537) (xy 296.822586 -348.212304)
			(xy 296.874909 -348.227672) (xy 296.924513 -348.25033) (xy 296.970387 -348.279816) (xy 297.011599 -348.315531)
			(xy 297.047309 -348.356746) (xy 297.07679 -348.402624) (xy 297.099443 -348.45223) (xy 297.114805 -348.504555)
			(xy 297.122566 -348.558533) (xy 297.122566 -348.613067) (xy 297.122565 -348.613072) (xy 298.605392 -348.613072)
			(xy 298.605392 -348.558528) (xy 298.613154 -348.50454) (xy 298.628521 -348.452206) (xy 298.651179 -348.402591)
			(xy 298.680668 -348.356706) (xy 298.716386 -348.315485) (xy 298.757608 -348.279766) (xy 298.803493 -348.250278)
			(xy 298.853107 -348.22762) (xy 298.905442 -348.212253) (xy 298.95943 -348.204491) (xy 298.986702 -348.204028)
			(xy 299.850302 -348.204028) (xy 299.877571 -348.204535) (xy 299.931553 -348.212296) (xy 299.98388 -348.227661)
			(xy 300.033489 -348.250317) (xy 300.079369 -348.279802) (xy 300.120585 -348.315517) (xy 300.156299 -348.356733)
			(xy 300.185784 -348.402613) (xy 300.208439 -348.452221) (xy 300.223804 -348.504549) (xy 300.231566 -348.558531)
			(xy 300.231566 -348.613069) (xy 300.231566 -348.613072) (xy 312.121492 -348.613072) (xy 312.121492 -348.558528)
			(xy 312.129254 -348.504539) (xy 312.144621 -348.452205) (xy 312.167279 -348.40259) (xy 312.196768 -348.356705)
			(xy 312.232487 -348.315484) (xy 312.273709 -348.279766) (xy 312.319594 -348.250277) (xy 312.369209 -348.227619)
			(xy 312.421543 -348.212253) (xy 312.475532 -348.204491) (xy 312.502804 -348.204028) (xy 313.366404 -348.204028)
			(xy 313.393672 -348.204535) (xy 313.447654 -348.212297) (xy 313.499982 -348.227662) (xy 313.54959 -348.250318)
			(xy 313.595469 -348.279803) (xy 313.636686 -348.315517) (xy 313.672399 -348.356734) (xy 313.701884 -348.402613)
			(xy 313.72454 -348.452222) (xy 313.739904 -348.50455) (xy 313.747666 -348.558532) (xy 313.747666 -348.613068)
			(xy 315.230514 -348.613068) (xy 315.230514 -348.558532) (xy 315.238275 -348.50455) (xy 315.253639 -348.452222)
			(xy 315.276293 -348.402613) (xy 315.305777 -348.356732) (xy 315.341489 -348.315514) (xy 315.382703 -348.279798)
			(xy 315.428581 -348.250311) (xy 315.478188 -348.227652) (xy 315.530514 -348.212283) (xy 315.584496 -348.204517)
			(xy 315.611764 -348.204028) (xy 316.475364 -348.204028) (xy 316.502636 -348.204509) (xy 316.556625 -348.212267)
			(xy 316.608961 -348.22763) (xy 316.658577 -348.250284) (xy 316.704464 -348.27977) (xy 316.745688 -348.315487)
			(xy 316.781408 -348.356707) (xy 316.810898 -348.402591) (xy 316.833558 -348.452205) (xy 316.848926 -348.504539)
			(xy 316.856688 -348.558528) (xy 316.856688 -348.613072) (xy 316.856688 -348.613073) (xy 318.339392 -348.613073)
			(xy 318.339392 -348.558527) (xy 318.347155 -348.504537) (xy 318.362522 -348.452201) (xy 318.385182 -348.402585)
			(xy 318.414673 -348.356699) (xy 318.450394 -348.315477) (xy 318.491618 -348.279759) (xy 318.537506 -348.250271)
			(xy 318.587123 -348.227614) (xy 318.63946 -348.212249) (xy 318.693451 -348.20449) (xy 318.720724 -348.204028)
			(xy 319.584324 -348.204028) (xy 319.611592 -348.204536) (xy 319.665571 -348.2123) (xy 319.717896 -348.227667)
			(xy 319.767502 -348.250324) (xy 319.813379 -348.27981) (xy 319.854593 -348.315524) (xy 319.890304 -348.35674)
			(xy 319.919787 -348.402619) (xy 319.942441 -348.452226) (xy 319.957805 -348.504552) (xy 319.965566 -348.558532)
			(xy 319.965566 -348.613068) (xy 319.965566 -348.613069) (xy 321.448414 -348.613069) (xy 321.448414 -348.558531)
			(xy 321.456176 -348.504547) (xy 321.471541 -348.452217) (xy 321.494196 -348.402607) (xy 321.523682 -348.356726)
			(xy 321.559396 -348.315507) (xy 321.600613 -348.279791) (xy 321.646493 -348.250304) (xy 321.696102 -348.227646)
			(xy 321.748431 -348.212279) (xy 321.802415 -348.204516) (xy 321.829684 -348.204028) (xy 322.693284 -348.204028)
			(xy 322.720555 -348.20451) (xy 322.774542 -348.21227) (xy 322.826875 -348.227635) (xy 322.876489 -348.250291)
			(xy 322.922374 -348.279777) (xy 322.963595 -348.315494) (xy 322.999313 -348.356713) (xy 323.028801 -348.402597)
			(xy 323.051459 -348.45221) (xy 323.066826 -348.504542) (xy 323.074588 -348.558529) (xy 323.074588 -348.613071)
			(xy 323.074588 -348.613074) (xy 324.557292 -348.613074) (xy 324.557292 -348.558526) (xy 324.565055 -348.504534)
			(xy 324.580424 -348.452197) (xy 324.603085 -348.402579) (xy 324.632578 -348.356692) (xy 324.668301 -348.31547)
			(xy 324.709527 -348.279751) (xy 324.755418 -348.250264) (xy 324.805038 -348.227609) (xy 324.857377 -348.212246)
			(xy 324.91137 -348.204489) (xy 324.938644 -348.204028) (xy 325.802244 -348.204028) (xy 325.829511 -348.204537)
			(xy 325.883488 -348.212304) (xy 325.935811 -348.227673) (xy 325.985414 -348.250331) (xy 326.031288 -348.279817)
			(xy 326.0725 -348.315531) (xy 326.108209 -348.356747) (xy 326.13769 -348.402624) (xy 326.160343 -348.45223)
			(xy 326.175705 -348.504555) (xy 326.183466 -348.558533) (xy 326.183466 -348.613067) (xy 326.183465 -348.613072)
			(xy 327.666292 -348.613072) (xy 327.666292 -348.558528) (xy 327.674054 -348.504539) (xy 327.689421 -348.452205)
			(xy 327.712079 -348.40259) (xy 327.741568 -348.356705) (xy 327.777287 -348.315484) (xy 327.818509 -348.279766)
			(xy 327.864394 -348.250277) (xy 327.914009 -348.227619) (xy 327.966343 -348.212253) (xy 328.020332 -348.204491)
			(xy 328.047604 -348.204028) (xy 328.911204 -348.204028) (xy 328.938472 -348.204535) (xy 328.992454 -348.212297)
			(xy 329.044782 -348.227662) (xy 329.09439 -348.250318) (xy 329.140269 -348.279803) (xy 329.181486 -348.315517)
			(xy 329.217199 -348.356734) (xy 329.246684 -348.402613) (xy 329.26934 -348.452222) (xy 329.284704 -348.50455)
			(xy 329.292466 -348.558532) (xy 329.292466 -348.613068) (xy 330.775314 -348.613068) (xy 330.775314 -348.558532)
			(xy 330.783075 -348.50455) (xy 330.798439 -348.452222) (xy 330.821093 -348.402613) (xy 330.850577 -348.356732)
			(xy 330.886289 -348.315514) (xy 330.927503 -348.279798) (xy 330.973381 -348.250311) (xy 331.022988 -348.227652)
			(xy 331.075314 -348.212283) (xy 331.129296 -348.204517) (xy 331.156564 -348.204028) (xy 332.020164 -348.204028)
			(xy 332.047436 -348.204509) (xy 332.101425 -348.212267) (xy 332.153761 -348.22763) (xy 332.203377 -348.250284)
			(xy 332.249264 -348.27977) (xy 332.290488 -348.315487) (xy 332.326208 -348.356707) (xy 332.355698 -348.402591)
			(xy 332.378358 -348.452205) (xy 332.393726 -348.504539) (xy 332.401488 -348.558528) (xy 332.401488 -348.613072)
			(xy 332.401488 -348.613073) (xy 333.884192 -348.613073) (xy 333.884192 -348.558527) (xy 333.891955 -348.504537)
			(xy 333.907322 -348.452201) (xy 333.929982 -348.402585) (xy 333.959473 -348.356699) (xy 333.995194 -348.315477)
			(xy 334.036418 -348.279759) (xy 334.082306 -348.250271) (xy 334.131923 -348.227614) (xy 334.18426 -348.212249)
			(xy 334.238251 -348.20449) (xy 334.265524 -348.204028) (xy 335.129124 -348.204028) (xy 335.156392 -348.204536)
			(xy 335.210371 -348.2123) (xy 335.262696 -348.227667) (xy 335.312302 -348.250324) (xy 335.358179 -348.27981)
			(xy 335.399393 -348.315524) (xy 335.435104 -348.35674) (xy 335.464587 -348.402619) (xy 335.487241 -348.452226)
			(xy 335.502605 -348.504552) (xy 335.510366 -348.558532) (xy 335.510366 -348.613068) (xy 335.510366 -348.613069)
			(xy 336.993214 -348.613069) (xy 336.993214 -348.558531) (xy 337.000976 -348.504547) (xy 337.016341 -348.452217)
			(xy 337.038996 -348.402607) (xy 337.068482 -348.356726) (xy 337.104196 -348.315507) (xy 337.145413 -348.279791)
			(xy 337.191293 -348.250304) (xy 337.240902 -348.227646) (xy 337.293231 -348.212279) (xy 337.347215 -348.204516)
			(xy 337.374484 -348.204028) (xy 338.238084 -348.204028) (xy 338.265355 -348.20451) (xy 338.319342 -348.21227)
			(xy 338.371675 -348.227635) (xy 338.421289 -348.250291) (xy 338.467174 -348.279777) (xy 338.508395 -348.315494)
			(xy 338.544113 -348.356713) (xy 338.573601 -348.402597) (xy 338.596259 -348.45221) (xy 338.611626 -348.504542)
			(xy 338.619388 -348.558529) (xy 338.619388 -348.613071) (xy 338.619388 -348.613074) (xy 340.102092 -348.613074)
			(xy 340.102092 -348.558526) (xy 340.109855 -348.504534) (xy 340.125224 -348.452197) (xy 340.147885 -348.402579)
			(xy 340.177378 -348.356692) (xy 340.213101 -348.31547) (xy 340.254327 -348.279751) (xy 340.300218 -348.250264)
			(xy 340.349838 -348.227609) (xy 340.402177 -348.212246) (xy 340.45617 -348.204489) (xy 340.483444 -348.204028)
			(xy 341.347044 -348.204028) (xy 341.374311 -348.204537) (xy 341.428288 -348.212304) (xy 341.480611 -348.227673)
			(xy 341.530214 -348.250331) (xy 341.576088 -348.279817) (xy 341.6173 -348.315531) (xy 341.653009 -348.356747)
			(xy 341.68249 -348.402624) (xy 341.705143 -348.45223) (xy 341.720505 -348.504555) (xy 341.728266 -348.558533)
			(xy 341.728266 -348.613067) (xy 341.728265 -348.613072) (xy 343.211092 -348.613072) (xy 343.211092 -348.558528)
			(xy 343.218854 -348.504539) (xy 343.234221 -348.452205) (xy 343.256879 -348.40259) (xy 343.286368 -348.356705)
			(xy 343.322087 -348.315484) (xy 343.363309 -348.279766) (xy 343.409194 -348.250277) (xy 343.458809 -348.227619)
			(xy 343.511143 -348.212253) (xy 343.565132 -348.204491) (xy 343.592404 -348.204028) (xy 344.456004 -348.204028)
			(xy 344.483272 -348.204535) (xy 344.537254 -348.212297) (xy 344.589582 -348.227662) (xy 344.63919 -348.250318)
			(xy 344.685069 -348.279803) (xy 344.726286 -348.315517) (xy 344.761999 -348.356734) (xy 344.791484 -348.402613)
			(xy 344.81414 -348.452222) (xy 344.829504 -348.50455) (xy 344.837266 -348.558532) (xy 344.837266 -348.613068)
			(xy 344.837266 -348.613069) (xy 370.806714 -348.613069) (xy 370.806714 -348.558531) (xy 370.814476 -348.504548)
			(xy 370.82984 -348.452218) (xy 370.852496 -348.402608) (xy 370.881981 -348.356727) (xy 370.917695 -348.315509)
			(xy 370.958911 -348.279793) (xy 371.004791 -348.250305) (xy 371.054399 -348.227647) (xy 371.106728 -348.21228)
			(xy 371.160711 -348.204516) (xy 371.18798 -348.204028) (xy 372.05158 -348.204028) (xy 372.078851 -348.20451)
			(xy 372.132839 -348.21227) (xy 372.185173 -348.227634) (xy 372.234787 -348.25029) (xy 372.280672 -348.279776)
			(xy 372.321893 -348.315493) (xy 372.357612 -348.356712) (xy 372.387101 -348.402595) (xy 372.409759 -348.452209)
			(xy 372.425126 -348.504542) (xy 372.432888 -348.558529) (xy 372.432888 -348.613071) (xy 372.432888 -348.613074)
			(xy 373.915592 -348.613074) (xy 373.915592 -348.558526) (xy 373.923355 -348.504535) (xy 373.938724 -348.452197)
			(xy 373.961385 -348.40258) (xy 373.990877 -348.356694) (xy 374.0266 -348.315471) (xy 374.067826 -348.279753)
			(xy 374.113715 -348.250266) (xy 374.163335 -348.22761) (xy 374.215674 -348.212246) (xy 374.269666 -348.204489)
			(xy 374.29694 -348.204028) (xy 375.16054 -348.204028) (xy 375.187807 -348.204537) (xy 375.241785 -348.212303)
			(xy 375.294108 -348.227672) (xy 375.343712 -348.25033) (xy 375.389587 -348.279816) (xy 375.430798 -348.31553)
			(xy 375.466508 -348.356746) (xy 375.49599 -348.402623) (xy 375.518642 -348.45223) (xy 375.534005 -348.504554)
			(xy 375.541766 -348.558533) (xy 375.541766 -348.613067) (xy 375.541766 -348.61307) (xy 377.024614 -348.61307)
			(xy 377.024614 -348.55853) (xy 377.032376 -348.504545) (xy 377.047742 -348.452214) (xy 377.070399 -348.402603)
			(xy 377.099886 -348.35672) (xy 377.135602 -348.315502) (xy 377.17682 -348.279786) (xy 377.222703 -348.250299)
			(xy 377.272314 -348.227642) (xy 377.324645 -348.212276) (xy 377.37863 -348.204514) (xy 377.4059 -348.204028)
			(xy 378.2695 -348.204028) (xy 378.296769 -348.204534) (xy 378.350751 -348.212296) (xy 378.403079 -348.227661)
			(xy 378.452688 -348.250316) (xy 378.498568 -348.279802) (xy 378.539784 -348.315516) (xy 378.575498 -348.356732)
			(xy 378.604984 -348.402612) (xy 378.627639 -348.452221) (xy 378.643004 -348.504549) (xy 378.650766 -348.558531)
			(xy 378.650766 -348.613068) (xy 380.133614 -348.613068) (xy 380.133614 -348.558532) (xy 380.141375 -348.50455)
			(xy 380.156739 -348.452223) (xy 380.179393 -348.402614) (xy 380.208876 -348.356734) (xy 380.244588 -348.315516)
			(xy 380.285801 -348.2798) (xy 380.331679 -348.250312) (xy 380.381285 -348.227653) (xy 380.433611 -348.212284)
			(xy 380.487592 -348.204517) (xy 380.51486 -348.204028) (xy 381.37846 -348.204028) (xy 381.405732 -348.204509)
			(xy 381.459722 -348.212266) (xy 381.512058 -348.227628) (xy 381.561675 -348.250283) (xy 381.607562 -348.279769)
			(xy 381.648786 -348.315485) (xy 381.684507 -348.356706) (xy 381.713998 -348.40259) (xy 381.736658 -348.452204)
			(xy 381.752025 -348.504539) (xy 381.759788 -348.558528) (xy 381.759788 -348.613072) (xy 381.759788 -348.613073)
			(xy 383.242492 -348.613073) (xy 383.242492 -348.558527) (xy 383.250254 -348.504537) (xy 383.265622 -348.452202)
			(xy 383.288282 -348.402586) (xy 383.317772 -348.3567) (xy 383.353493 -348.315478) (xy 383.394716 -348.27976)
			(xy 383.440603 -348.250272) (xy 383.49022 -348.227615) (xy 383.542557 -348.21225) (xy 383.596547 -348.20449)
			(xy 383.62382 -348.204028) (xy 384.48742 -348.204028) (xy 384.514688 -348.204536) (xy 384.568668 -348.2123)
			(xy 384.620994 -348.227666) (xy 384.6706 -348.250323) (xy 384.716477 -348.279809) (xy 384.757691 -348.315523)
			(xy 384.793403 -348.356739) (xy 384.822887 -348.402618) (xy 384.845541 -348.452225) (xy 384.860905 -348.504552)
			(xy 384.868666 -348.558532) (xy 384.868666 -348.613068) (xy 384.868666 -348.613069) (xy 386.351514 -348.613069)
			(xy 386.351514 -348.558531) (xy 386.359276 -348.504548) (xy 386.37464 -348.452218) (xy 386.397296 -348.402608)
			(xy 386.426781 -348.356727) (xy 386.462495 -348.315509) (xy 386.503711 -348.279793) (xy 386.549591 -348.250305)
			(xy 386.599199 -348.227647) (xy 386.651528 -348.21228) (xy 386.705511 -348.204516) (xy 386.73278 -348.204028)
			(xy 387.59638 -348.204028) (xy 387.623651 -348.20451) (xy 387.677639 -348.21227) (xy 387.729973 -348.227634)
			(xy 387.779587 -348.25029) (xy 387.825472 -348.279776) (xy 387.866693 -348.315493) (xy 387.902412 -348.356712)
			(xy 387.931901 -348.402595) (xy 387.954559 -348.452209) (xy 387.969926 -348.504542) (xy 387.977688 -348.558529)
			(xy 387.977688 -348.613071) (xy 387.977688 -348.613074) (xy 389.460392 -348.613074) (xy 389.460392 -348.558526)
			(xy 389.468155 -348.504535) (xy 389.483524 -348.452197) (xy 389.506185 -348.40258) (xy 389.535677 -348.356694)
			(xy 389.5714 -348.315471) (xy 389.612626 -348.279753) (xy 389.658515 -348.250266) (xy 389.708135 -348.22761)
			(xy 389.760474 -348.212246) (xy 389.814466 -348.204489) (xy 389.84174 -348.204028) (xy 390.70534 -348.204028)
			(xy 390.732607 -348.204537) (xy 390.786585 -348.212303) (xy 390.838908 -348.227672) (xy 390.888512 -348.25033)
			(xy 390.934387 -348.279816) (xy 390.975598 -348.31553) (xy 391.011308 -348.356746) (xy 391.04079 -348.402623)
			(xy 391.063442 -348.45223) (xy 391.078805 -348.504554) (xy 391.086566 -348.558533) (xy 391.086566 -348.613067)
			(xy 391.086566 -348.61307) (xy 392.569414 -348.61307) (xy 392.569414 -348.55853) (xy 392.577176 -348.504545)
			(xy 392.592542 -348.452214) (xy 392.615199 -348.402603) (xy 392.644686 -348.35672) (xy 392.680402 -348.315502)
			(xy 392.72162 -348.279786) (xy 392.767503 -348.250299) (xy 392.817114 -348.227642) (xy 392.869445 -348.212276)
			(xy 392.92343 -348.204514) (xy 392.9507 -348.204028) (xy 393.8143 -348.204028) (xy 393.841569 -348.204534)
			(xy 393.895551 -348.212296) (xy 393.947879 -348.227661) (xy 393.997488 -348.250316) (xy 394.043368 -348.279802)
			(xy 394.084584 -348.315516) (xy 394.120298 -348.356732) (xy 394.149784 -348.402612) (xy 394.172439 -348.452221)
			(xy 394.187804 -348.504549) (xy 394.195566 -348.558531) (xy 394.195566 -348.613068) (xy 395.678414 -348.613068)
			(xy 395.678414 -348.558532) (xy 395.686175 -348.50455) (xy 395.701539 -348.452223) (xy 395.724193 -348.402614)
			(xy 395.753676 -348.356734) (xy 395.789388 -348.315516) (xy 395.830601 -348.2798) (xy 395.876479 -348.250312)
			(xy 395.926085 -348.227653) (xy 395.978411 -348.212284) (xy 396.032392 -348.204517) (xy 396.05966 -348.204028)
			(xy 396.92326 -348.204028) (xy 396.950532 -348.204509) (xy 397.004522 -348.212266) (xy 397.056858 -348.227628)
			(xy 397.106475 -348.250283) (xy 397.152362 -348.279769) (xy 397.193586 -348.315485) (xy 397.229307 -348.356706)
			(xy 397.258798 -348.40259) (xy 397.281458 -348.452204) (xy 397.296825 -348.504539) (xy 397.304588 -348.558528)
			(xy 397.304588 -348.613072) (xy 397.304588 -348.613073) (xy 398.787292 -348.613073) (xy 398.787292 -348.558527)
			(xy 398.795054 -348.504537) (xy 398.810422 -348.452202) (xy 398.833082 -348.402586) (xy 398.862572 -348.3567)
			(xy 398.898293 -348.315478) (xy 398.939516 -348.27976) (xy 398.985403 -348.250272) (xy 399.03502 -348.227615)
			(xy 399.087357 -348.21225) (xy 399.141347 -348.20449) (xy 399.16862 -348.204028) (xy 400.03222 -348.204028)
			(xy 400.059488 -348.204536) (xy 400.113468 -348.2123) (xy 400.165794 -348.227666) (xy 400.2154 -348.250323)
			(xy 400.261277 -348.279809) (xy 400.302491 -348.315523) (xy 400.338203 -348.356739) (xy 400.367687 -348.402618)
			(xy 400.390341 -348.452225) (xy 400.405705 -348.504552) (xy 400.413466 -348.558532) (xy 400.413466 -348.613068)
			(xy 400.413466 -348.613069) (xy 401.896314 -348.613069) (xy 401.896314 -348.558531) (xy 401.904076 -348.504548)
			(xy 401.91944 -348.452218) (xy 401.942096 -348.402608) (xy 401.971581 -348.356727) (xy 402.007295 -348.315509)
			(xy 402.048511 -348.279793) (xy 402.094391 -348.250305) (xy 402.143999 -348.227647) (xy 402.196328 -348.21228)
			(xy 402.250311 -348.204516) (xy 402.27758 -348.204028) (xy 403.14118 -348.204028) (xy 403.168451 -348.20451)
			(xy 403.222439 -348.21227) (xy 403.274773 -348.227634) (xy 403.324387 -348.25029) (xy 403.370272 -348.279776)
			(xy 403.411493 -348.315493) (xy 403.447212 -348.356712) (xy 403.476701 -348.402595) (xy 403.499359 -348.452209)
			(xy 403.514726 -348.504542) (xy 403.522488 -348.558529) (xy 403.522488 -348.61307) (xy 408.913814 -348.61307)
			(xy 408.913814 -348.55853) (xy 408.921576 -348.504546) (xy 408.936941 -348.452216) (xy 408.959598 -348.402605)
			(xy 408.989084 -348.356723) (xy 409.024799 -348.315505) (xy 409.066017 -348.279788) (xy 409.111898 -348.250301)
			(xy 409.161508 -348.227644) (xy 409.213838 -348.212278) (xy 409.267822 -348.204515) (xy 409.295092 -348.204028)
			(xy 410.158692 -348.204028) (xy 410.185963 -348.204511) (xy 410.239949 -348.212272) (xy 410.292281 -348.227637)
			(xy 410.341894 -348.250294) (xy 410.387778 -348.27978) (xy 410.428998 -348.315497) (xy 410.464715 -348.356716)
			(xy 410.494203 -348.402599) (xy 410.51686 -348.452211) (xy 410.532226 -348.504543) (xy 410.539989 -348.558529)
			(xy 410.539989 -348.613068) (xy 412.022814 -348.613068) (xy 412.022814 -348.558532) (xy 412.030575 -348.504551)
			(xy 412.045938 -348.452224) (xy 412.068592 -348.402616) (xy 412.098074 -348.356736) (xy 412.133785 -348.315519)
			(xy 412.174998 -348.279803) (xy 412.220874 -348.250315) (xy 412.270479 -348.227655) (xy 412.322804 -348.212285)
			(xy 412.376784 -348.204518) (xy 412.404052 -348.204028) (xy 413.267652 -348.204028) (xy 413.294925 -348.204508)
			(xy 413.348915 -348.212265) (xy 413.401252 -348.227626) (xy 413.45087 -348.250281) (xy 413.496759 -348.279766)
			(xy 413.537983 -348.315483) (xy 413.573705 -348.356703) (xy 413.603196 -348.402588) (xy 413.625857 -348.452203)
			(xy 413.641225 -348.504538) (xy 413.648988 -348.558528) (xy 413.648988 -348.613072) (xy 415.131692 -348.613072)
			(xy 415.131692 -348.558528) (xy 415.139454 -348.504538) (xy 415.154821 -348.452203) (xy 415.177481 -348.402588)
			(xy 415.20697 -348.356703) (xy 415.24269 -348.315481) (xy 415.283912 -348.279763) (xy 415.329799 -348.250275)
			(xy 415.379415 -348.227617) (xy 415.43175 -348.212252) (xy 415.48574 -348.204491) (xy 415.513012 -348.204028)
			(xy 416.376612 -348.204028) (xy 416.40388 -348.204535) (xy 416.457861 -348.212298) (xy 416.510188 -348.227664)
			(xy 416.559795 -348.25032) (xy 416.605673 -348.279806) (xy 416.646888 -348.31552) (xy 416.682601 -348.356736)
			(xy 416.712085 -348.402615) (xy 416.73474 -348.452224) (xy 416.750104 -348.504551) (xy 416.757866 -348.558532)
			(xy 416.757866 -348.613068) (xy 416.757866 -348.613069) (xy 418.240714 -348.613069) (xy 418.240714 -348.558531)
			(xy 418.248476 -348.504549) (xy 418.26384 -348.45222) (xy 418.286495 -348.40261) (xy 418.315979 -348.35673)
			(xy 418.351692 -348.315512) (xy 418.392907 -348.279795) (xy 418.438786 -348.250308) (xy 418.488394 -348.22765)
			(xy 418.540721 -348.212281) (xy 418.594703 -348.204516) (xy 418.621972 -348.204028) (xy 419.485572 -348.204028)
			(xy 419.512844 -348.20451) (xy 419.566832 -348.212268) (xy 419.619167 -348.227632) (xy 419.668782 -348.250287)
			(xy 419.714668 -348.279773) (xy 419.75589 -348.31549) (xy 419.79161 -348.356709) (xy 419.821099 -348.402593)
			(xy 419.843759 -348.452207) (xy 419.859126 -348.504541) (xy 419.866888 -348.558528) (xy 419.866888 -348.613072)
			(xy 419.866888 -348.613073) (xy 421.349592 -348.613073) (xy 421.349592 -348.558527) (xy 421.357355 -348.504536)
			(xy 421.372723 -348.452199) (xy 421.395384 -348.402583) (xy 421.424875 -348.356696) (xy 421.460597 -348.315474)
			(xy 421.501822 -348.279756) (xy 421.547711 -348.250268) (xy 421.597329 -348.227612) (xy 421.649667 -348.212248)
			(xy 421.703659 -348.204489) (xy 421.730932 -348.204028) (xy 422.594532 -348.204028) (xy 422.621799 -348.204537)
			(xy 422.675778 -348.212302) (xy 422.728102 -348.227669) (xy 422.777707 -348.250327) (xy 422.823583 -348.279813)
			(xy 422.864795 -348.315527) (xy 422.900506 -348.356743) (xy 422.929988 -348.402621) (xy 422.952642 -348.452228)
			(xy 422.968005 -348.504553) (xy 422.975766 -348.558533) (xy 422.975766 -348.613067) (xy 422.975766 -348.61307)
			(xy 424.458614 -348.61307) (xy 424.458614 -348.55853) (xy 424.466376 -348.504546) (xy 424.481741 -348.452216)
			(xy 424.504398 -348.402605) (xy 424.533884 -348.356723) (xy 424.569599 -348.315505) (xy 424.610817 -348.279788)
			(xy 424.656698 -348.250301) (xy 424.706308 -348.227644) (xy 424.758638 -348.212278) (xy 424.812622 -348.204515)
			(xy 424.839892 -348.204028) (xy 425.703492 -348.204028) (xy 425.730763 -348.204511) (xy 425.784749 -348.212272)
			(xy 425.837081 -348.227637) (xy 425.886694 -348.250294) (xy 425.932578 -348.27978) (xy 425.973798 -348.315497)
			(xy 426.009515 -348.356716) (xy 426.039003 -348.402599) (xy 426.06166 -348.452211) (xy 426.077026 -348.504543)
			(xy 426.084789 -348.558529) (xy 426.084789 -348.613068) (xy 427.567614 -348.613068) (xy 427.567614 -348.558532)
			(xy 427.575375 -348.504551) (xy 427.590738 -348.452224) (xy 427.613392 -348.402616) (xy 427.642874 -348.356736)
			(xy 427.678585 -348.315519) (xy 427.719798 -348.279803) (xy 427.765674 -348.250315) (xy 427.815279 -348.227655)
			(xy 427.867604 -348.212285) (xy 427.921584 -348.204518) (xy 427.948852 -348.204028) (xy 428.812452 -348.204028)
			(xy 428.839725 -348.204508) (xy 428.893715 -348.212265) (xy 428.946052 -348.227626) (xy 428.99567 -348.250281)
			(xy 429.041559 -348.279766) (xy 429.082783 -348.315483) (xy 429.118505 -348.356703) (xy 429.147996 -348.402588)
			(xy 429.170657 -348.452203) (xy 429.186025 -348.504538) (xy 429.193788 -348.558528) (xy 429.193788 -348.613072)
			(xy 430.676492 -348.613072) (xy 430.676492 -348.558528) (xy 430.684254 -348.504538) (xy 430.699621 -348.452203)
			(xy 430.722281 -348.402588) (xy 430.75177 -348.356703) (xy 430.78749 -348.315481) (xy 430.828712 -348.279763)
			(xy 430.874599 -348.250275) (xy 430.924215 -348.227617) (xy 430.97655 -348.212252) (xy 431.03054 -348.204491)
			(xy 431.057812 -348.204028) (xy 431.921412 -348.204028) (xy 431.94868 -348.204535) (xy 432.002661 -348.212298)
			(xy 432.054988 -348.227664) (xy 432.104595 -348.25032) (xy 432.150473 -348.279806) (xy 432.191688 -348.31552)
			(xy 432.227401 -348.356736) (xy 432.256885 -348.402615) (xy 432.27954 -348.452224) (xy 432.294904 -348.504551)
			(xy 432.302666 -348.558532) (xy 432.302666 -348.613068) (xy 432.302666 -348.613069) (xy 433.785514 -348.613069)
			(xy 433.785514 -348.558531) (xy 433.793276 -348.504549) (xy 433.80864 -348.45222) (xy 433.831295 -348.40261)
			(xy 433.860779 -348.35673) (xy 433.896492 -348.315512) (xy 433.937707 -348.279795) (xy 433.983586 -348.250308)
			(xy 434.033194 -348.22765) (xy 434.085521 -348.212281) (xy 434.139503 -348.204516) (xy 434.166772 -348.204028)
			(xy 435.030372 -348.204028) (xy 435.057644 -348.20451) (xy 435.111632 -348.212268) (xy 435.163967 -348.227632)
			(xy 435.213582 -348.250287) (xy 435.259468 -348.279773) (xy 435.30069 -348.31549) (xy 435.33641 -348.356709)
			(xy 435.365899 -348.402593) (xy 435.388559 -348.452207) (xy 435.403926 -348.504541) (xy 435.411688 -348.558528)
			(xy 435.411688 -348.613072) (xy 435.411688 -348.613073) (xy 436.894392 -348.613073) (xy 436.894392 -348.558527)
			(xy 436.902155 -348.504536) (xy 436.917523 -348.452199) (xy 436.940184 -348.402583) (xy 436.969675 -348.356696)
			(xy 437.005397 -348.315474) (xy 437.046622 -348.279756) (xy 437.092511 -348.250268) (xy 437.142129 -348.227612)
			(xy 437.194467 -348.212248) (xy 437.248459 -348.204489) (xy 437.275732 -348.204028) (xy 438.139332 -348.204028)
			(xy 438.166599 -348.204537) (xy 438.220578 -348.212302) (xy 438.272902 -348.227669) (xy 438.322507 -348.250327)
			(xy 438.368383 -348.279813) (xy 438.409595 -348.315527) (xy 438.445306 -348.356743) (xy 438.474788 -348.402621)
			(xy 438.497442 -348.452228) (xy 438.512805 -348.504553) (xy 438.520566 -348.558533) (xy 438.520566 -348.613067)
			(xy 438.520566 -348.61307) (xy 440.003414 -348.61307) (xy 440.003414 -348.55853) (xy 440.011176 -348.504546)
			(xy 440.026541 -348.452216) (xy 440.049198 -348.402605) (xy 440.078684 -348.356723) (xy 440.114399 -348.315505)
			(xy 440.155617 -348.279788) (xy 440.201498 -348.250301) (xy 440.251108 -348.227644) (xy 440.303438 -348.212278)
			(xy 440.357422 -348.204515) (xy 440.384692 -348.204028) (xy 441.248292 -348.204028) (xy 441.275563 -348.204511)
			(xy 441.329549 -348.212272) (xy 441.381881 -348.227637) (xy 441.431494 -348.250294) (xy 441.477378 -348.27978)
			(xy 441.518598 -348.315497) (xy 441.554315 -348.356716) (xy 441.583803 -348.402599) (xy 441.60646 -348.452211)
			(xy 441.621826 -348.504543) (xy 441.629589 -348.558529) (xy 441.629589 -348.613071) (xy 441.621826 -348.667057)
			(xy 441.60646 -348.719389) (xy 441.583803 -348.769001) (xy 441.554315 -348.814884) (xy 441.518598 -348.856103)
			(xy 441.477378 -348.89182) (xy 441.431494 -348.921306) (xy 441.381881 -348.943963) (xy 441.329549 -348.959328)
			(xy 441.275563 -348.967089) (xy 441.248292 -348.967552) (xy 440.384692 -348.967552) (xy 440.357422 -348.967085)
			(xy 440.303438 -348.959322) (xy 440.251108 -348.943956) (xy 440.201498 -348.921299) (xy 440.155617 -348.891812)
			(xy 440.114399 -348.856095) (xy 440.078684 -348.814877) (xy 440.049198 -348.768995) (xy 440.026541 -348.719384)
			(xy 440.011176 -348.667054) (xy 440.003414 -348.61307) (xy 438.520566 -348.61307) (xy 438.512805 -348.667047)
			(xy 438.497442 -348.719372) (xy 438.474788 -348.768979) (xy 438.445306 -348.814857) (xy 438.409595 -348.856073)
			(xy 438.368383 -348.891787) (xy 438.322507 -348.921273) (xy 438.272902 -348.943931) (xy 438.220578 -348.959298)
			(xy 438.166599 -348.967063) (xy 438.139332 -348.967552) (xy 437.275732 -348.967552) (xy 437.248459 -348.967111)
			(xy 437.194467 -348.959352) (xy 437.142129 -348.943988) (xy 437.092511 -348.921332) (xy 437.046622 -348.891844)
			(xy 437.005397 -348.856126) (xy 436.969675 -348.814904) (xy 436.940184 -348.769017) (xy 436.917523 -348.719401)
			(xy 436.902155 -348.667064) (xy 436.894392 -348.613073) (xy 435.411688 -348.613073) (xy 435.403926 -348.667059)
			(xy 435.388559 -348.719393) (xy 435.365899 -348.769007) (xy 435.33641 -348.814891) (xy 435.30069 -348.85611)
			(xy 435.259468 -348.891827) (xy 435.213582 -348.921313) (xy 435.163967 -348.943968) (xy 435.111632 -348.959332)
			(xy 435.057644 -348.96709) (xy 435.030372 -348.967552) (xy 434.166772 -348.967552) (xy 434.139503 -348.967084)
			(xy 434.085521 -348.959319) (xy 434.033194 -348.94395) (xy 433.983586 -348.921292) (xy 433.937707 -348.891805)
			(xy 433.896492 -348.856088) (xy 433.860779 -348.81487) (xy 433.831295 -348.76899) (xy 433.80864 -348.71938)
			(xy 433.793276 -348.667051) (xy 433.785514 -348.613069) (xy 432.302666 -348.613069) (xy 432.294904 -348.667049)
			(xy 432.27954 -348.719376) (xy 432.256885 -348.768985) (xy 432.227401 -348.814864) (xy 432.191688 -348.85608)
			(xy 432.150473 -348.891794) (xy 432.104595 -348.92128) (xy 432.054988 -348.943936) (xy 432.002661 -348.959302)
			(xy 431.94868 -348.967065) (xy 431.921412 -348.967552) (xy 431.057812 -348.967552) (xy 431.03054 -348.967109)
			(xy 430.97655 -348.959348) (xy 430.924215 -348.943983) (xy 430.874599 -348.921325) (xy 430.828712 -348.891837)
			(xy 430.78749 -348.856119) (xy 430.75177 -348.814897) (xy 430.722281 -348.769012) (xy 430.699621 -348.719397)
			(xy 430.684254 -348.667062) (xy 430.676492 -348.613072) (xy 429.193788 -348.613072) (xy 429.186025 -348.667062)
			(xy 429.170657 -348.719397) (xy 429.147996 -348.769012) (xy 429.118505 -348.814897) (xy 429.082783 -348.856117)
			(xy 429.041559 -348.891834) (xy 428.99567 -348.921319) (xy 428.946052 -348.943974) (xy 428.893715 -348.959335)
			(xy 428.839725 -348.967092) (xy 428.812452 -348.967552) (xy 427.948852 -348.967552) (xy 427.921584 -348.967082)
			(xy 427.867604 -348.959315) (xy 427.815279 -348.943945) (xy 427.765674 -348.921285) (xy 427.719798 -348.891797)
			(xy 427.678585 -348.856081) (xy 427.642874 -348.814864) (xy 427.613392 -348.768984) (xy 427.590738 -348.719376)
			(xy 427.575375 -348.667049) (xy 427.567614 -348.613068) (xy 426.084789 -348.613068) (xy 426.084789 -348.613071)
			(xy 426.077026 -348.667057) (xy 426.06166 -348.719389) (xy 426.039003 -348.769001) (xy 426.009515 -348.814884)
			(xy 425.973798 -348.856103) (xy 425.932578 -348.89182) (xy 425.886694 -348.921306) (xy 425.837081 -348.943963)
			(xy 425.784749 -348.959328) (xy 425.730763 -348.967089) (xy 425.703492 -348.967552) (xy 424.839892 -348.967552)
			(xy 424.812622 -348.967085) (xy 424.758638 -348.959322) (xy 424.706308 -348.943956) (xy 424.656698 -348.921299)
			(xy 424.610817 -348.891812) (xy 424.569599 -348.856095) (xy 424.533884 -348.814877) (xy 424.504398 -348.768995)
			(xy 424.481741 -348.719384) (xy 424.466376 -348.667054) (xy 424.458614 -348.61307) (xy 422.975766 -348.61307)
			(xy 422.968005 -348.667047) (xy 422.952642 -348.719372) (xy 422.929988 -348.768979) (xy 422.900506 -348.814857)
			(xy 422.864795 -348.856073) (xy 422.823583 -348.891787) (xy 422.777707 -348.921273) (xy 422.728102 -348.943931)
			(xy 422.675778 -348.959298) (xy 422.621799 -348.967063) (xy 422.594532 -348.967552) (xy 421.730932 -348.967552)
			(xy 421.703659 -348.967111) (xy 421.649667 -348.959352) (xy 421.597329 -348.943988) (xy 421.547711 -348.921332)
			(xy 421.501822 -348.891844) (xy 421.460597 -348.856126) (xy 421.424875 -348.814904) (xy 421.395384 -348.769017)
			(xy 421.372723 -348.719401) (xy 421.357355 -348.667064) (xy 421.349592 -348.613073) (xy 419.866888 -348.613073)
			(xy 419.859126 -348.667059) (xy 419.843759 -348.719393) (xy 419.821099 -348.769007) (xy 419.79161 -348.814891)
			(xy 419.75589 -348.85611) (xy 419.714668 -348.891827) (xy 419.668782 -348.921313) (xy 419.619167 -348.943968)
			(xy 419.566832 -348.959332) (xy 419.512844 -348.96709) (xy 419.485572 -348.967552) (xy 418.621972 -348.967552)
			(xy 418.594703 -348.967084) (xy 418.540721 -348.959319) (xy 418.488394 -348.94395) (xy 418.438786 -348.921292)
			(xy 418.392907 -348.891805) (xy 418.351692 -348.856088) (xy 418.315979 -348.81487) (xy 418.286495 -348.76899)
			(xy 418.26384 -348.71938) (xy 418.248476 -348.667051) (xy 418.240714 -348.613069) (xy 416.757866 -348.613069)
			(xy 416.750104 -348.667049) (xy 416.73474 -348.719376) (xy 416.712085 -348.768985) (xy 416.682601 -348.814864)
			(xy 416.646888 -348.85608) (xy 416.605673 -348.891794) (xy 416.559795 -348.92128) (xy 416.510188 -348.943936)
			(xy 416.457861 -348.959302) (xy 416.40388 -348.967065) (xy 416.376612 -348.967552) (xy 415.513012 -348.967552)
			(xy 415.48574 -348.967109) (xy 415.43175 -348.959348) (xy 415.379415 -348.943983) (xy 415.329799 -348.921325)
			(xy 415.283912 -348.891837) (xy 415.24269 -348.856119) (xy 415.20697 -348.814897) (xy 415.177481 -348.769012)
			(xy 415.154821 -348.719397) (xy 415.139454 -348.667062) (xy 415.131692 -348.613072) (xy 413.648988 -348.613072)
			(xy 413.641225 -348.667062) (xy 413.625857 -348.719397) (xy 413.603196 -348.769012) (xy 413.573705 -348.814897)
			(xy 413.537983 -348.856117) (xy 413.496759 -348.891834) (xy 413.45087 -348.921319) (xy 413.401252 -348.943974)
			(xy 413.348915 -348.959335) (xy 413.294925 -348.967092) (xy 413.267652 -348.967552) (xy 412.404052 -348.967552)
			(xy 412.376784 -348.967082) (xy 412.322804 -348.959315) (xy 412.270479 -348.943945) (xy 412.220874 -348.921285)
			(xy 412.174998 -348.891797) (xy 412.133785 -348.856081) (xy 412.098074 -348.814864) (xy 412.068592 -348.768984)
			(xy 412.045938 -348.719376) (xy 412.030575 -348.667049) (xy 412.022814 -348.613068) (xy 410.539989 -348.613068)
			(xy 410.539989 -348.613071) (xy 410.532226 -348.667057) (xy 410.51686 -348.719389) (xy 410.494203 -348.769001)
			(xy 410.464715 -348.814884) (xy 410.428998 -348.856103) (xy 410.387778 -348.89182) (xy 410.341894 -348.921306)
			(xy 410.292281 -348.943963) (xy 410.239949 -348.959328) (xy 410.185963 -348.967089) (xy 410.158692 -348.967552)
			(xy 409.295092 -348.967552) (xy 409.267822 -348.967085) (xy 409.213838 -348.959322) (xy 409.161508 -348.943956)
			(xy 409.111898 -348.921299) (xy 409.066017 -348.891812) (xy 409.024799 -348.856095) (xy 408.989084 -348.814877)
			(xy 408.959598 -348.768995) (xy 408.936941 -348.719384) (xy 408.921576 -348.667054) (xy 408.913814 -348.61307)
			(xy 403.522488 -348.61307) (xy 403.522488 -348.613071) (xy 403.514726 -348.667058) (xy 403.499359 -348.719391)
			(xy 403.476701 -348.769005) (xy 403.447212 -348.814888) (xy 403.411493 -348.856107) (xy 403.370272 -348.891824)
			(xy 403.324387 -348.92131) (xy 403.274773 -348.943966) (xy 403.222439 -348.95933) (xy 403.168451 -348.96709)
			(xy 403.14118 -348.967552) (xy 402.27758 -348.967552) (xy 402.250311 -348.967084) (xy 402.196328 -348.95932)
			(xy 402.143999 -348.943953) (xy 402.094391 -348.921295) (xy 402.048511 -348.891807) (xy 402.007295 -348.856091)
			(xy 401.971581 -348.814873) (xy 401.942096 -348.768992) (xy 401.91944 -348.719382) (xy 401.904076 -348.667052)
			(xy 401.896314 -348.613069) (xy 400.413466 -348.613069) (xy 400.405705 -348.667048) (xy 400.390341 -348.719375)
			(xy 400.367687 -348.768982) (xy 400.338203 -348.814861) (xy 400.302491 -348.856077) (xy 400.261277 -348.891791)
			(xy 400.2154 -348.921277) (xy 400.165794 -348.943934) (xy 400.113468 -348.9593) (xy 400.059488 -348.967064)
			(xy 400.03222 -348.967552) (xy 399.16862 -348.967552) (xy 399.141347 -348.96711) (xy 399.087357 -348.95935)
			(xy 399.03502 -348.943985) (xy 398.985403 -348.921328) (xy 398.939516 -348.89184) (xy 398.898293 -348.856122)
			(xy 398.862572 -348.8149) (xy 398.833082 -348.769014) (xy 398.810422 -348.719398) (xy 398.795054 -348.667063)
			(xy 398.787292 -348.613073) (xy 397.304588 -348.613073) (xy 397.296825 -348.667061) (xy 397.281458 -348.719396)
			(xy 397.258798 -348.76901) (xy 397.229307 -348.814894) (xy 397.193586 -348.856115) (xy 397.152362 -348.891831)
			(xy 397.106475 -348.921317) (xy 397.056858 -348.943972) (xy 397.004522 -348.959334) (xy 396.950532 -348.967091)
			(xy 396.92326 -348.967552) (xy 396.05966 -348.967552) (xy 396.032392 -348.967083) (xy 395.978411 -348.959316)
			(xy 395.926085 -348.943947) (xy 395.876479 -348.921288) (xy 395.830601 -348.8918) (xy 395.789388 -348.856084)
			(xy 395.753676 -348.814866) (xy 395.724193 -348.768986) (xy 395.701539 -348.719377) (xy 395.686175 -348.66705)
			(xy 395.678414 -348.613068) (xy 394.195566 -348.613068) (xy 394.195566 -348.613069) (xy 394.187804 -348.667051)
			(xy 394.172439 -348.719379) (xy 394.149784 -348.768988) (xy 394.120298 -348.814868) (xy 394.084584 -348.856084)
			(xy 394.043368 -348.891798) (xy 393.997488 -348.921284) (xy 393.947879 -348.943939) (xy 393.895551 -348.959304)
			(xy 393.841569 -348.967066) (xy 393.8143 -348.967552) (xy 392.9507 -348.967552) (xy 392.92343 -348.967086)
			(xy 392.869445 -348.959324) (xy 392.817114 -348.943958) (xy 392.767503 -348.921301) (xy 392.72162 -348.891814)
			(xy 392.680402 -348.856098) (xy 392.644686 -348.81488) (xy 392.615199 -348.768997) (xy 392.592542 -348.719386)
			(xy 392.577176 -348.667055) (xy 392.569414 -348.61307) (xy 391.086566 -348.61307) (xy 391.078805 -348.667046)
			(xy 391.063442 -348.71937) (xy 391.04079 -348.768977) (xy 391.011308 -348.814854) (xy 390.975598 -348.85607)
			(xy 390.934387 -348.891784) (xy 390.888512 -348.92127) (xy 390.838908 -348.943928) (xy 390.786585 -348.959297)
			(xy 390.732607 -348.967063) (xy 390.70534 -348.967552) (xy 389.84174 -348.967552) (xy 389.814466 -348.967111)
			(xy 389.760474 -348.959354) (xy 389.708135 -348.94399) (xy 389.658515 -348.921334) (xy 389.612626 -348.891847)
			(xy 389.5714 -348.856129) (xy 389.535677 -348.814906) (xy 389.506185 -348.76902) (xy 389.483524 -348.719403)
			(xy 389.468155 -348.667065) (xy 389.460392 -348.613074) (xy 387.977688 -348.613074) (xy 387.969926 -348.667058)
			(xy 387.954559 -348.719391) (xy 387.931901 -348.769005) (xy 387.902412 -348.814888) (xy 387.866693 -348.856107)
			(xy 387.825472 -348.891824) (xy 387.779587 -348.92131) (xy 387.729973 -348.943966) (xy 387.677639 -348.95933)
			(xy 387.623651 -348.96709) (xy 387.59638 -348.967552) (xy 386.73278 -348.967552) (xy 386.705511 -348.967084)
			(xy 386.651528 -348.95932) (xy 386.599199 -348.943953) (xy 386.549591 -348.921295) (xy 386.503711 -348.891807)
			(xy 386.462495 -348.856091) (xy 386.426781 -348.814873) (xy 386.397296 -348.768992) (xy 386.37464 -348.719382)
			(xy 386.359276 -348.667052) (xy 386.351514 -348.613069) (xy 384.868666 -348.613069) (xy 384.860905 -348.667048)
			(xy 384.845541 -348.719375) (xy 384.822887 -348.768982) (xy 384.793403 -348.814861) (xy 384.757691 -348.856077)
			(xy 384.716477 -348.891791) (xy 384.6706 -348.921277) (xy 384.620994 -348.943934) (xy 384.568668 -348.9593)
			(xy 384.514688 -348.967064) (xy 384.48742 -348.967552) (xy 383.62382 -348.967552) (xy 383.596547 -348.96711)
			(xy 383.542557 -348.95935) (xy 383.49022 -348.943985) (xy 383.440603 -348.921328) (xy 383.394716 -348.89184)
			(xy 383.353493 -348.856122) (xy 383.317772 -348.8149) (xy 383.288282 -348.769014) (xy 383.265622 -348.719398)
			(xy 383.250254 -348.667063) (xy 383.242492 -348.613073) (xy 381.759788 -348.613073) (xy 381.752025 -348.667061)
			(xy 381.736658 -348.719396) (xy 381.713998 -348.76901) (xy 381.684507 -348.814894) (xy 381.648786 -348.856115)
			(xy 381.607562 -348.891831) (xy 381.561675 -348.921317) (xy 381.512058 -348.943972) (xy 381.459722 -348.959334)
			(xy 381.405732 -348.967091) (xy 381.37846 -348.967552) (xy 380.51486 -348.967552) (xy 380.487592 -348.967083)
			(xy 380.433611 -348.959316) (xy 380.381285 -348.943947) (xy 380.331679 -348.921288) (xy 380.285801 -348.8918)
			(xy 380.244588 -348.856084) (xy 380.208876 -348.814866) (xy 380.179393 -348.768986) (xy 380.156739 -348.719377)
			(xy 380.141375 -348.66705) (xy 380.133614 -348.613068) (xy 378.650766 -348.613068) (xy 378.650766 -348.613069)
			(xy 378.643004 -348.667051) (xy 378.627639 -348.719379) (xy 378.604984 -348.768988) (xy 378.575498 -348.814868)
			(xy 378.539784 -348.856084) (xy 378.498568 -348.891798) (xy 378.452688 -348.921284) (xy 378.403079 -348.943939)
			(xy 378.350751 -348.959304) (xy 378.296769 -348.967066) (xy 378.2695 -348.967552) (xy 377.4059 -348.967552)
			(xy 377.37863 -348.967086) (xy 377.324645 -348.959324) (xy 377.272314 -348.943958) (xy 377.222703 -348.921301)
			(xy 377.17682 -348.891814) (xy 377.135602 -348.856098) (xy 377.099886 -348.81488) (xy 377.070399 -348.768997)
			(xy 377.047742 -348.719386) (xy 377.032376 -348.667055) (xy 377.024614 -348.61307) (xy 375.541766 -348.61307)
			(xy 375.534005 -348.667046) (xy 375.518642 -348.71937) (xy 375.49599 -348.768977) (xy 375.466508 -348.814854)
			(xy 375.430798 -348.85607) (xy 375.389587 -348.891784) (xy 375.343712 -348.92127) (xy 375.294108 -348.943928)
			(xy 375.241785 -348.959297) (xy 375.187807 -348.967063) (xy 375.16054 -348.967552) (xy 374.29694 -348.967552)
			(xy 374.269666 -348.967111) (xy 374.215674 -348.959354) (xy 374.163335 -348.94399) (xy 374.113715 -348.921334)
			(xy 374.067826 -348.891847) (xy 374.0266 -348.856129) (xy 373.990877 -348.814906) (xy 373.961385 -348.76902)
			(xy 373.938724 -348.719403) (xy 373.923355 -348.667065) (xy 373.915592 -348.613074) (xy 372.432888 -348.613074)
			(xy 372.425126 -348.667058) (xy 372.409759 -348.719391) (xy 372.387101 -348.769005) (xy 372.357612 -348.814888)
			(xy 372.321893 -348.856107) (xy 372.280672 -348.891824) (xy 372.234787 -348.92131) (xy 372.185173 -348.943966)
			(xy 372.132839 -348.95933) (xy 372.078851 -348.96709) (xy 372.05158 -348.967552) (xy 371.18798 -348.967552)
			(xy 371.160711 -348.967084) (xy 371.106728 -348.95932) (xy 371.054399 -348.943953) (xy 371.004791 -348.921295)
			(xy 370.958911 -348.891807) (xy 370.917695 -348.856091) (xy 370.881981 -348.814873) (xy 370.852496 -348.768992)
			(xy 370.82984 -348.719382) (xy 370.814476 -348.667052) (xy 370.806714 -348.613069) (xy 344.837266 -348.613069)
			(xy 344.829504 -348.66705) (xy 344.81414 -348.719378) (xy 344.791484 -348.768987) (xy 344.761999 -348.814866)
			(xy 344.726286 -348.856083) (xy 344.685069 -348.891797) (xy 344.63919 -348.921282) (xy 344.589582 -348.943938)
			(xy 344.537254 -348.959303) (xy 344.483272 -348.967065) (xy 344.456004 -348.967552) (xy 343.592404 -348.967552)
			(xy 343.565132 -348.967109) (xy 343.511143 -348.959347) (xy 343.458809 -348.943981) (xy 343.409194 -348.921323)
			(xy 343.363309 -348.891834) (xy 343.322087 -348.856116) (xy 343.286368 -348.814895) (xy 343.256879 -348.76901)
			(xy 343.234221 -348.719395) (xy 343.218854 -348.667061) (xy 343.211092 -348.613072) (xy 341.728265 -348.613072)
			(xy 341.720505 -348.667045) (xy 341.705143 -348.71937) (xy 341.68249 -348.768976) (xy 341.653009 -348.814853)
			(xy 341.6173 -348.856069) (xy 341.576088 -348.891783) (xy 341.530214 -348.921269) (xy 341.480611 -348.943927)
			(xy 341.428288 -348.959296) (xy 341.374311 -348.967063) (xy 341.347044 -348.967552) (xy 340.483444 -348.967552)
			(xy 340.45617 -348.967111) (xy 340.402177 -348.959354) (xy 340.349838 -348.943991) (xy 340.300218 -348.921336)
			(xy 340.254327 -348.891849) (xy 340.213101 -348.85613) (xy 340.177378 -348.814908) (xy 340.147885 -348.769021)
			(xy 340.125224 -348.719403) (xy 340.109855 -348.667066) (xy 340.102092 -348.613074) (xy 338.619388 -348.613074)
			(xy 338.611626 -348.667058) (xy 338.596259 -348.71939) (xy 338.573601 -348.769003) (xy 338.544113 -348.814887)
			(xy 338.508395 -348.856106) (xy 338.467174 -348.891823) (xy 338.421289 -348.921309) (xy 338.371675 -348.943965)
			(xy 338.319342 -348.95933) (xy 338.265355 -348.96709) (xy 338.238084 -348.967552) (xy 337.374484 -348.967552)
			(xy 337.347215 -348.967084) (xy 337.293231 -348.959321) (xy 337.240902 -348.943954) (xy 337.191293 -348.921296)
			(xy 337.145413 -348.891809) (xy 337.104196 -348.856093) (xy 337.068482 -348.814874) (xy 337.038996 -348.768993)
			(xy 337.016341 -348.719383) (xy 337.000976 -348.667053) (xy 336.993214 -348.613069) (xy 335.510366 -348.613069)
			(xy 335.502605 -348.667048) (xy 335.487241 -348.719374) (xy 335.464587 -348.768981) (xy 335.435104 -348.81486)
			(xy 335.399393 -348.856076) (xy 335.358179 -348.89179) (xy 335.312302 -348.921276) (xy 335.262696 -348.943933)
			(xy 335.210371 -348.9593) (xy 335.156392 -348.967064) (xy 335.129124 -348.967552) (xy 334.265524 -348.967552)
			(xy 334.238251 -348.96711) (xy 334.18426 -348.959351) (xy 334.131923 -348.943986) (xy 334.082306 -348.921329)
			(xy 334.036418 -348.891841) (xy 333.995194 -348.856123) (xy 333.959473 -348.814901) (xy 333.929982 -348.769015)
			(xy 333.907322 -348.719399) (xy 333.891955 -348.667063) (xy 333.884192 -348.613073) (xy 332.401488 -348.613073)
			(xy 332.393726 -348.667061) (xy 332.378358 -348.719395) (xy 332.355698 -348.769009) (xy 332.326208 -348.814893)
			(xy 332.290488 -348.856113) (xy 332.249264 -348.89183) (xy 332.203377 -348.921316) (xy 332.153761 -348.94397)
			(xy 332.101425 -348.959333) (xy 332.047436 -348.967091) (xy 332.020164 -348.967552) (xy 331.156564 -348.967552)
			(xy 331.129296 -348.967083) (xy 331.075314 -348.959317) (xy 331.022988 -348.943948) (xy 330.973381 -348.921289)
			(xy 330.927503 -348.891802) (xy 330.886289 -348.856086) (xy 330.850577 -348.814868) (xy 330.821093 -348.768987)
			(xy 330.798439 -348.719378) (xy 330.783075 -348.66705) (xy 330.775314 -348.613068) (xy 329.292466 -348.613068)
			(xy 329.284704 -348.66705) (xy 329.26934 -348.719378) (xy 329.246684 -348.768987) (xy 329.217199 -348.814866)
			(xy 329.181486 -348.856083) (xy 329.140269 -348.891797) (xy 329.09439 -348.921282) (xy 329.044782 -348.943938)
			(xy 328.992454 -348.959303) (xy 328.938472 -348.967065) (xy 328.911204 -348.967552) (xy 328.047604 -348.967552)
			(xy 328.020332 -348.967109) (xy 327.966343 -348.959347) (xy 327.914009 -348.943981) (xy 327.864394 -348.921323)
			(xy 327.818509 -348.891834) (xy 327.777287 -348.856116) (xy 327.741568 -348.814895) (xy 327.712079 -348.76901)
			(xy 327.689421 -348.719395) (xy 327.674054 -348.667061) (xy 327.666292 -348.613072) (xy 326.183465 -348.613072)
			(xy 326.175705 -348.667045) (xy 326.160343 -348.71937) (xy 326.13769 -348.768976) (xy 326.108209 -348.814853)
			(xy 326.0725 -348.856069) (xy 326.031288 -348.891783) (xy 325.985414 -348.921269) (xy 325.935811 -348.943927)
			(xy 325.883488 -348.959296) (xy 325.829511 -348.967063) (xy 325.802244 -348.967552) (xy 324.938644 -348.967552)
			(xy 324.91137 -348.967111) (xy 324.857377 -348.959354) (xy 324.805038 -348.943991) (xy 324.755418 -348.921336)
			(xy 324.709527 -348.891849) (xy 324.668301 -348.85613) (xy 324.632578 -348.814908) (xy 324.603085 -348.769021)
			(xy 324.580424 -348.719403) (xy 324.565055 -348.667066) (xy 324.557292 -348.613074) (xy 323.074588 -348.613074)
			(xy 323.066826 -348.667058) (xy 323.051459 -348.71939) (xy 323.028801 -348.769003) (xy 322.999313 -348.814887)
			(xy 322.963595 -348.856106) (xy 322.922374 -348.891823) (xy 322.876489 -348.921309) (xy 322.826875 -348.943965)
			(xy 322.774542 -348.95933) (xy 322.720555 -348.96709) (xy 322.693284 -348.967552) (xy 321.829684 -348.967552)
			(xy 321.802415 -348.967084) (xy 321.748431 -348.959321) (xy 321.696102 -348.943954) (xy 321.646493 -348.921296)
			(xy 321.600613 -348.891809) (xy 321.559396 -348.856093) (xy 321.523682 -348.814874) (xy 321.494196 -348.768993)
			(xy 321.471541 -348.719383) (xy 321.456176 -348.667053) (xy 321.448414 -348.613069) (xy 319.965566 -348.613069)
			(xy 319.957805 -348.667048) (xy 319.942441 -348.719374) (xy 319.919787 -348.768981) (xy 319.890304 -348.81486)
			(xy 319.854593 -348.856076) (xy 319.813379 -348.89179) (xy 319.767502 -348.921276) (xy 319.717896 -348.943933)
			(xy 319.665571 -348.9593) (xy 319.611592 -348.967064) (xy 319.584324 -348.967552) (xy 318.720724 -348.967552)
			(xy 318.693451 -348.96711) (xy 318.63946 -348.959351) (xy 318.587123 -348.943986) (xy 318.537506 -348.921329)
			(xy 318.491618 -348.891841) (xy 318.450394 -348.856123) (xy 318.414673 -348.814901) (xy 318.385182 -348.769015)
			(xy 318.362522 -348.719399) (xy 318.347155 -348.667063) (xy 318.339392 -348.613073) (xy 316.856688 -348.613073)
			(xy 316.848926 -348.667061) (xy 316.833558 -348.719395) (xy 316.810898 -348.769009) (xy 316.781408 -348.814893)
			(xy 316.745688 -348.856113) (xy 316.704464 -348.89183) (xy 316.658577 -348.921316) (xy 316.608961 -348.94397)
			(xy 316.556625 -348.959333) (xy 316.502636 -348.967091) (xy 316.475364 -348.967552) (xy 315.611764 -348.967552)
			(xy 315.584496 -348.967083) (xy 315.530514 -348.959317) (xy 315.478188 -348.943948) (xy 315.428581 -348.921289)
			(xy 315.382703 -348.891802) (xy 315.341489 -348.856086) (xy 315.305777 -348.814868) (xy 315.276293 -348.768987)
			(xy 315.253639 -348.719378) (xy 315.238275 -348.66705) (xy 315.230514 -348.613068) (xy 313.747666 -348.613068)
			(xy 313.739904 -348.66705) (xy 313.72454 -348.719378) (xy 313.701884 -348.768987) (xy 313.672399 -348.814866)
			(xy 313.636686 -348.856083) (xy 313.595469 -348.891797) (xy 313.54959 -348.921282) (xy 313.499982 -348.943938)
			(xy 313.447654 -348.959303) (xy 313.393672 -348.967065) (xy 313.366404 -348.967552) (xy 312.502804 -348.967552)
			(xy 312.475532 -348.967109) (xy 312.421543 -348.959347) (xy 312.369209 -348.943981) (xy 312.319594 -348.921323)
			(xy 312.273709 -348.891834) (xy 312.232487 -348.856116) (xy 312.196768 -348.814895) (xy 312.167279 -348.76901)
			(xy 312.144621 -348.719395) (xy 312.129254 -348.667061) (xy 312.121492 -348.613072) (xy 300.231566 -348.613072)
			(xy 300.223804 -348.667051) (xy 300.208439 -348.719379) (xy 300.185784 -348.768987) (xy 300.156299 -348.814867)
			(xy 300.120585 -348.856083) (xy 300.079369 -348.891798) (xy 300.033489 -348.921283) (xy 299.98388 -348.943939)
			(xy 299.931553 -348.959304) (xy 299.877571 -348.967065) (xy 299.850302 -348.967552) (xy 298.986702 -348.967552)
			(xy 298.95943 -348.967109) (xy 298.905442 -348.959347) (xy 298.853107 -348.94398) (xy 298.803493 -348.921322)
			(xy 298.757608 -348.891834) (xy 298.716386 -348.856115) (xy 298.680668 -348.814894) (xy 298.651179 -348.769009)
			(xy 298.628521 -348.719394) (xy 298.613154 -348.66706) (xy 298.605392 -348.613072) (xy 297.122565 -348.613072)
			(xy 297.114805 -348.667045) (xy 297.099443 -348.71937) (xy 297.07679 -348.768976) (xy 297.047309 -348.814854)
			(xy 297.011599 -348.856069) (xy 296.970387 -348.891784) (xy 296.924513 -348.92127) (xy 296.874909 -348.943928)
			(xy 296.822586 -348.959296) (xy 296.768609 -348.967063) (xy 296.741342 -348.967552) (xy 295.877742 -348.967552)
			(xy 295.850468 -348.967111) (xy 295.796476 -348.959354) (xy 295.744136 -348.943991) (xy 295.694517 -348.921335)
			(xy 295.648627 -348.891848) (xy 295.6074 -348.856129) (xy 295.571677 -348.814907) (xy 295.542185 -348.76902)
			(xy 295.519524 -348.719403) (xy 295.504155 -348.667066) (xy 295.496392 -348.613074) (xy 294.013688 -348.613074)
			(xy 294.005926 -348.667058) (xy 293.990559 -348.719391) (xy 293.967901 -348.769004) (xy 293.938412 -348.814887)
			(xy 293.902694 -348.856107) (xy 293.861473 -348.891823) (xy 293.815588 -348.92131) (xy 293.765974 -348.943966)
			(xy 293.713641 -348.95933) (xy 293.659653 -348.96709) (xy 293.632382 -348.967552) (xy 292.768782 -348.967552)
			(xy 292.741513 -348.967084) (xy 292.68753 -348.95932) (xy 292.635201 -348.943953) (xy 292.585592 -348.921295)
			(xy 292.539712 -348.891808) (xy 292.498495 -348.856092) (xy 292.462781 -348.814874) (xy 292.433296 -348.768992)
			(xy 292.410641 -348.719382) (xy 292.395276 -348.667053) (xy 292.387514 -348.613069) (xy 290.904666 -348.613069)
			(xy 290.896905 -348.667048) (xy 290.881541 -348.719374) (xy 290.858887 -348.768982) (xy 290.829404 -348.81486)
			(xy 290.793692 -348.856076) (xy 290.752478 -348.891791) (xy 290.706601 -348.921276) (xy 290.656995 -348.943933)
			(xy 290.604669 -348.9593) (xy 290.55069 -348.967064) (xy 290.523422 -348.967552) (xy 289.659822 -348.967552)
			(xy 289.632549 -348.96711) (xy 289.578559 -348.95935) (xy 289.526222 -348.943985) (xy 289.476605 -348.921329)
			(xy 289.430717 -348.891841) (xy 289.389493 -348.856122) (xy 289.353772 -348.814901) (xy 289.324282 -348.769015)
			(xy 289.301622 -348.719399) (xy 289.286254 -348.667063) (xy 289.278492 -348.613073) (xy 287.795788 -348.613073)
			(xy 287.788026 -348.667061) (xy 287.772658 -348.719395) (xy 287.749998 -348.76901) (xy 287.720508 -348.814894)
			(xy 287.684787 -348.856114) (xy 287.643563 -348.89183) (xy 287.597676 -348.921316) (xy 287.54806 -348.943971)
			(xy 287.495724 -348.959334) (xy 287.441734 -348.967091) (xy 287.414462 -348.967552) (xy 286.550862 -348.967552)
			(xy 286.523594 -348.967083) (xy 286.469613 -348.959317) (xy 286.417286 -348.943948) (xy 286.36768 -348.921289)
			(xy 286.321802 -348.891801) (xy 286.280588 -348.856085) (xy 286.244876 -348.814867) (xy 286.215393 -348.768987)
			(xy 286.192739 -348.719378) (xy 286.177375 -348.66705) (xy 286.169614 -348.613068) (xy 284.686766 -348.613068)
			(xy 284.686766 -348.613069) (xy 284.679004 -348.667051) (xy 284.663639 -348.719379) (xy 284.640984 -348.768987)
			(xy 284.611499 -348.814867) (xy 284.575785 -348.856083) (xy 284.534569 -348.891798) (xy 284.488689 -348.921283)
			(xy 284.43908 -348.943939) (xy 284.386753 -348.959304) (xy 284.332771 -348.967065) (xy 284.305502 -348.967552)
			(xy 283.441902 -348.967552) (xy 283.41463 -348.967109) (xy 283.360642 -348.959347) (xy 283.308307 -348.94398)
			(xy 283.258693 -348.921322) (xy 283.212808 -348.891834) (xy 283.171586 -348.856115) (xy 283.135868 -348.814894)
			(xy 283.106379 -348.769009) (xy 283.083721 -348.719394) (xy 283.068354 -348.66706) (xy 283.060592 -348.613072)
			(xy 281.577765 -348.613072) (xy 281.570005 -348.667045) (xy 281.554643 -348.71937) (xy 281.53199 -348.768976)
			(xy 281.502509 -348.814854) (xy 281.466799 -348.856069) (xy 281.425587 -348.891784) (xy 281.379713 -348.92127)
			(xy 281.330109 -348.943928) (xy 281.277786 -348.959296) (xy 281.223809 -348.967063) (xy 281.196542 -348.967552)
			(xy 280.332942 -348.967552) (xy 280.305668 -348.967111) (xy 280.251676 -348.959354) (xy 280.199336 -348.943991)
			(xy 280.149717 -348.921335) (xy 280.103827 -348.891848) (xy 280.0626 -348.856129) (xy 280.026877 -348.814907)
			(xy 279.997385 -348.76902) (xy 279.974724 -348.719403) (xy 279.959355 -348.667066) (xy 279.951592 -348.613074)
			(xy 278.468888 -348.613074) (xy 278.461126 -348.667058) (xy 278.445759 -348.719391) (xy 278.423101 -348.769004)
			(xy 278.393612 -348.814887) (xy 278.357894 -348.856107) (xy 278.316673 -348.891823) (xy 278.270788 -348.92131)
			(xy 278.221174 -348.943966) (xy 278.168841 -348.95933) (xy 278.114853 -348.96709) (xy 278.087582 -348.967552)
			(xy 277.223982 -348.967552) (xy 277.196713 -348.967084) (xy 277.14273 -348.95932) (xy 277.090401 -348.943953)
			(xy 277.040792 -348.921295) (xy 276.994912 -348.891808) (xy 276.953695 -348.856092) (xy 276.917981 -348.814874)
			(xy 276.888496 -348.768992) (xy 276.865841 -348.719382) (xy 276.850476 -348.667053) (xy 276.842714 -348.613069)
			(xy 275.359866 -348.613069) (xy 275.352105 -348.667048) (xy 275.336741 -348.719374) (xy 275.314087 -348.768982)
			(xy 275.284604 -348.81486) (xy 275.248892 -348.856076) (xy 275.207678 -348.891791) (xy 275.161801 -348.921276)
			(xy 275.112195 -348.943933) (xy 275.059869 -348.9593) (xy 275.00589 -348.967064) (xy 274.978622 -348.967552)
			(xy 274.115022 -348.967552) (xy 274.087749 -348.96711) (xy 274.033759 -348.95935) (xy 273.981422 -348.943985)
			(xy 273.931805 -348.921329) (xy 273.885917 -348.891841) (xy 273.844693 -348.856122) (xy 273.808972 -348.814901)
			(xy 273.779482 -348.769015) (xy 273.756822 -348.719399) (xy 273.741454 -348.667063) (xy 273.733692 -348.613073)
			(xy 272.250988 -348.613073) (xy 272.243226 -348.667061) (xy 272.227858 -348.719395) (xy 272.205198 -348.76901)
			(xy 272.175708 -348.814894) (xy 272.139987 -348.856114) (xy 272.098763 -348.89183) (xy 272.052876 -348.921316)
			(xy 272.00326 -348.943971) (xy 271.950924 -348.959334) (xy 271.896934 -348.967091) (xy 271.869662 -348.967552)
			(xy 271.006062 -348.967552) (xy 270.978794 -348.967083) (xy 270.924813 -348.959317) (xy 270.872486 -348.943948)
			(xy 270.82288 -348.921289) (xy 270.777002 -348.891801) (xy 270.735788 -348.856085) (xy 270.700076 -348.814867)
			(xy 270.670593 -348.768987) (xy 270.647939 -348.719378) (xy 270.632575 -348.66705) (xy 270.624814 -348.613068)
			(xy 269.141966 -348.613068) (xy 269.141966 -348.613069) (xy 269.134204 -348.667051) (xy 269.118839 -348.719379)
			(xy 269.096184 -348.768987) (xy 269.066699 -348.814867) (xy 269.030985 -348.856083) (xy 268.989769 -348.891798)
			(xy 268.943889 -348.921283) (xy 268.89428 -348.943939) (xy 268.841953 -348.959304) (xy 268.787971 -348.967065)
			(xy 268.760702 -348.967552) (xy 267.897102 -348.967552) (xy 267.86983 -348.967109) (xy 267.815842 -348.959347)
			(xy 267.763507 -348.94398) (xy 267.713893 -348.921322) (xy 267.668008 -348.891834) (xy 267.626786 -348.856115)
			(xy 267.591068 -348.814894) (xy 267.561579 -348.769009) (xy 267.538921 -348.719394) (xy 267.523554 -348.66706)
			(xy 267.515792 -348.613072) (xy 194.520565 -348.613072) (xy 194.512804 -348.667049) (xy 194.49744 -348.719376)
			(xy 194.474785 -348.768985) (xy 194.445301 -348.814864) (xy 194.409588 -348.85608) (xy 194.368373 -348.891794)
			(xy 194.322495 -348.92128) (xy 194.272888 -348.943936) (xy 194.220561 -348.959302) (xy 194.16658 -348.967065)
			(xy 194.139312 -348.967552) (xy 193.275712 -348.967552) (xy 193.24844 -348.967109) (xy 193.19445 -348.959348)
			(xy 193.142115 -348.943983) (xy 193.092499 -348.921325) (xy 193.046612 -348.891837) (xy 193.00539 -348.856119)
			(xy 192.96967 -348.814897) (xy 192.940181 -348.769012) (xy 192.917521 -348.719397) (xy 192.902154 -348.667062)
			(xy 192.894392 -348.613072) (xy 191.411688 -348.613072) (xy 191.403925 -348.667062) (xy 191.388557 -348.719397)
			(xy 191.365896 -348.769012) (xy 191.336405 -348.814897) (xy 191.300683 -348.856117) (xy 191.259459 -348.891834)
			(xy 191.21357 -348.921319) (xy 191.163952 -348.943974) (xy 191.111615 -348.959335) (xy 191.057625 -348.967092)
			(xy 191.030352 -348.967552) (xy 190.166752 -348.967552) (xy 190.139484 -348.967082) (xy 190.085504 -348.959315)
			(xy 190.033179 -348.943945) (xy 189.983574 -348.921285) (xy 189.937698 -348.891797) (xy 189.896485 -348.856081)
			(xy 189.860774 -348.814864) (xy 189.831292 -348.768984) (xy 189.808638 -348.719376) (xy 189.793275 -348.667049)
			(xy 189.785514 -348.613068) (xy 188.302689 -348.613068) (xy 188.302689 -348.613071) (xy 188.294926 -348.667057)
			(xy 188.27956 -348.719389) (xy 188.256903 -348.769001) (xy 188.227415 -348.814884) (xy 188.191698 -348.856103)
			(xy 188.150478 -348.89182) (xy 188.104594 -348.921306) (xy 188.054981 -348.943963) (xy 188.002649 -348.959328)
			(xy 187.948663 -348.967089) (xy 187.921392 -348.967552) (xy 187.057792 -348.967552) (xy 187.030522 -348.967085)
			(xy 186.976538 -348.959322) (xy 186.924208 -348.943956) (xy 186.874598 -348.921299) (xy 186.828717 -348.891812)
			(xy 186.787499 -348.856095) (xy 186.751784 -348.814877) (xy 186.722298 -348.768995) (xy 186.699641 -348.719384)
			(xy 186.684276 -348.667054) (xy 186.676514 -348.61307) (xy 185.193666 -348.61307) (xy 185.185905 -348.667047)
			(xy 185.170542 -348.719372) (xy 185.147888 -348.768979) (xy 185.118406 -348.814857) (xy 185.082695 -348.856073)
			(xy 185.041483 -348.891787) (xy 184.995607 -348.921273) (xy 184.946002 -348.943931) (xy 184.893678 -348.959298)
			(xy 184.839699 -348.967063) (xy 184.812432 -348.967552) (xy 183.948832 -348.967552) (xy 183.921559 -348.967111)
			(xy 183.867567 -348.959352) (xy 183.815229 -348.943988) (xy 183.765611 -348.921332) (xy 183.719722 -348.891844)
			(xy 183.678497 -348.856126) (xy 183.642775 -348.814904) (xy 183.613284 -348.769017) (xy 183.590623 -348.719401)
			(xy 183.575255 -348.667064) (xy 183.567492 -348.613073) (xy 182.084788 -348.613073) (xy 182.077026 -348.667059)
			(xy 182.061659 -348.719393) (xy 182.038999 -348.769007) (xy 182.00951 -348.814891) (xy 181.97379 -348.85611)
			(xy 181.932568 -348.891827) (xy 181.886682 -348.921313) (xy 181.837067 -348.943968) (xy 181.784732 -348.959332)
			(xy 181.730744 -348.96709) (xy 181.703472 -348.967552) (xy 180.839872 -348.967552) (xy 180.812603 -348.967084)
			(xy 180.758621 -348.959319) (xy 180.706294 -348.94395) (xy 180.656686 -348.921292) (xy 180.610807 -348.891805)
			(xy 180.569592 -348.856088) (xy 180.533879 -348.81487) (xy 180.504395 -348.76899) (xy 180.48174 -348.71938)
			(xy 180.466376 -348.667051) (xy 180.458614 -348.613069) (xy 178.975766 -348.613069) (xy 178.968004 -348.667049)
			(xy 178.95264 -348.719376) (xy 178.929985 -348.768985) (xy 178.900501 -348.814864) (xy 178.864788 -348.85608)
			(xy 178.823573 -348.891794) (xy 178.777695 -348.92128) (xy 178.728088 -348.943936) (xy 178.675761 -348.959302)
			(xy 178.62178 -348.967065) (xy 178.594512 -348.967552) (xy 177.730912 -348.967552) (xy 177.70364 -348.967109)
			(xy 177.64965 -348.959348) (xy 177.597315 -348.943983) (xy 177.547699 -348.921325) (xy 177.501812 -348.891837)
			(xy 177.46059 -348.856119) (xy 177.42487 -348.814897) (xy 177.395381 -348.769012) (xy 177.372721 -348.719397)
			(xy 177.357354 -348.667062) (xy 177.349592 -348.613072) (xy 175.866888 -348.613072) (xy 175.859125 -348.667062)
			(xy 175.843757 -348.719397) (xy 175.821096 -348.769012) (xy 175.791605 -348.814897) (xy 175.755883 -348.856117)
			(xy 175.714659 -348.891834) (xy 175.66877 -348.921319) (xy 175.619152 -348.943974) (xy 175.566815 -348.959335)
			(xy 175.512825 -348.967092) (xy 175.485552 -348.967552) (xy 174.621952 -348.967552) (xy 174.594684 -348.967082)
			(xy 174.540704 -348.959315) (xy 174.488379 -348.943945) (xy 174.438774 -348.921285) (xy 174.392898 -348.891797)
			(xy 174.351685 -348.856081) (xy 174.315974 -348.814864) (xy 174.286492 -348.768984) (xy 174.263838 -348.719376)
			(xy 174.248475 -348.667049) (xy 174.240714 -348.613068) (xy 172.757889 -348.613068) (xy 172.757889 -348.613071)
			(xy 172.750126 -348.667057) (xy 172.73476 -348.719389) (xy 172.712103 -348.769001) (xy 172.682615 -348.814884)
			(xy 172.646898 -348.856103) (xy 172.605678 -348.89182) (xy 172.559794 -348.921306) (xy 172.510181 -348.943963)
			(xy 172.457849 -348.959328) (xy 172.403863 -348.967089) (xy 172.376592 -348.967552) (xy 171.512992 -348.967552)
			(xy 171.485722 -348.967085) (xy 171.431738 -348.959322) (xy 171.379408 -348.943956) (xy 171.329798 -348.921299)
			(xy 171.283917 -348.891812) (xy 171.242699 -348.856095) (xy 171.206984 -348.814877) (xy 171.177498 -348.768995)
			(xy 171.154841 -348.719384) (xy 171.139476 -348.667054) (xy 171.131714 -348.61307) (xy 169.648866 -348.61307)
			(xy 169.641105 -348.667047) (xy 169.625742 -348.719372) (xy 169.603088 -348.768979) (xy 169.573606 -348.814857)
			(xy 169.537895 -348.856073) (xy 169.496683 -348.891787) (xy 169.450807 -348.921273) (xy 169.401202 -348.943931)
			(xy 169.348878 -348.959298) (xy 169.294899 -348.967063) (xy 169.267632 -348.967552) (xy 168.404032 -348.967552)
			(xy 168.376759 -348.967111) (xy 168.322767 -348.959352) (xy 168.270429 -348.943988) (xy 168.220811 -348.921332)
			(xy 168.174922 -348.891844) (xy 168.133697 -348.856126) (xy 168.097975 -348.814904) (xy 168.068484 -348.769017)
			(xy 168.045823 -348.719401) (xy 168.030455 -348.667064) (xy 168.022692 -348.613073) (xy 166.539988 -348.613073)
			(xy 166.532226 -348.667059) (xy 166.516859 -348.719393) (xy 166.494199 -348.769007) (xy 166.46471 -348.814891)
			(xy 166.42899 -348.85611) (xy 166.387768 -348.891827) (xy 166.341882 -348.921313) (xy 166.292267 -348.943968)
			(xy 166.239932 -348.959332) (xy 166.185944 -348.96709) (xy 166.158672 -348.967552) (xy 165.295072 -348.967552)
			(xy 165.267803 -348.967084) (xy 165.213821 -348.959319) (xy 165.161494 -348.94395) (xy 165.111886 -348.921292)
			(xy 165.066007 -348.891805) (xy 165.024792 -348.856088) (xy 164.989079 -348.81487) (xy 164.959595 -348.76899)
			(xy 164.93694 -348.71938) (xy 164.921576 -348.667051) (xy 164.913814 -348.613069) (xy 163.430966 -348.613069)
			(xy 163.423204 -348.667049) (xy 163.40784 -348.719376) (xy 163.385185 -348.768985) (xy 163.355701 -348.814864)
			(xy 163.319988 -348.85608) (xy 163.278773 -348.891794) (xy 163.232895 -348.92128) (xy 163.183288 -348.943936)
			(xy 163.130961 -348.959302) (xy 163.07698 -348.967065) (xy 163.049712 -348.967552) (xy 162.186112 -348.967552)
			(xy 162.15884 -348.967109) (xy 162.10485 -348.959348) (xy 162.052515 -348.943983) (xy 162.002899 -348.921325)
			(xy 161.957012 -348.891837) (xy 161.91579 -348.856119) (xy 161.88007 -348.814897) (xy 161.850581 -348.769012)
			(xy 161.827921 -348.719397) (xy 161.812554 -348.667062) (xy 161.804792 -348.613072) (xy 144.196565 -348.613072)
			(xy 144.188804 -348.66705) (xy 144.17344 -348.719377) (xy 144.150785 -348.768986) (xy 144.1213 -348.814865)
			(xy 144.085587 -348.856081) (xy 144.044371 -348.891796) (xy 143.998493 -348.921281) (xy 143.948885 -348.943937)
			(xy 143.896558 -348.959303) (xy 143.842576 -348.967065) (xy 143.815308 -348.967552) (xy 142.951708 -348.967552)
			(xy 142.924436 -348.967109) (xy 142.870447 -348.959348) (xy 142.818112 -348.943982) (xy 142.768496 -348.921324)
			(xy 142.72261 -348.891836) (xy 142.681388 -348.856117) (xy 142.645669 -348.814896) (xy 142.61618 -348.769011)
			(xy 142.593521 -348.719396) (xy 142.578154 -348.667061) (xy 142.570392 -348.613072) (xy 141.087565 -348.613072)
			(xy 141.079806 -348.667044) (xy 141.064443 -348.719369) (xy 141.041791 -348.768974) (xy 141.01231 -348.814852)
			(xy 140.976601 -348.856067) (xy 140.93539 -348.891781) (xy 140.889517 -348.921268) (xy 140.839914 -348.943926)
			(xy 140.787591 -348.959295) (xy 140.733614 -348.967062) (xy 140.706348 -348.967552) (xy 139.842748 -348.967552)
			(xy 139.815474 -348.967112) (xy 139.761481 -348.959355) (xy 139.709141 -348.943992) (xy 139.65952 -348.921337)
			(xy 139.613629 -348.89185) (xy 139.572402 -348.856132) (xy 139.536679 -348.814909) (xy 139.507186 -348.769022)
			(xy 139.484524 -348.719404) (xy 139.469155 -348.667066) (xy 139.461392 -348.613074) (xy 137.978689 -348.613074)
			(xy 137.970926 -348.667057) (xy 137.95556 -348.71939) (xy 137.932902 -348.769002) (xy 137.903414 -348.814885)
			(xy 137.867696 -348.856105) (xy 137.826476 -348.891821) (xy 137.780592 -348.921308) (xy 137.730978 -348.943964)
			(xy 137.678646 -348.959329) (xy 137.624659 -348.967089) (xy 137.597388 -348.967552) (xy 136.733788 -348.967552)
			(xy 136.706518 -348.967085) (xy 136.652535 -348.959321) (xy 136.600205 -348.943955) (xy 136.550595 -348.921297)
			(xy 136.504715 -348.89181) (xy 136.463497 -348.856094) (xy 136.427783 -348.814876) (xy 136.398297 -348.768994)
			(xy 136.375641 -348.719383) (xy 136.360276 -348.667053) (xy 136.352514 -348.61307) (xy 134.869666 -348.61307)
			(xy 134.861905 -348.667047) (xy 134.846541 -348.719373) (xy 134.823888 -348.76898) (xy 134.794405 -348.814858)
			(xy 134.758694 -348.856074) (xy 134.717481 -348.891789) (xy 134.671605 -348.921274) (xy 134.621999 -348.943932)
			(xy 134.569675 -348.959299) (xy 134.515695 -348.967064) (xy 134.488428 -348.967552) (xy 133.624828 -348.967552)
			(xy 133.597555 -348.96711) (xy 133.543564 -348.959351) (xy 133.491226 -348.943987) (xy 133.441608 -348.92133)
			(xy 133.39572 -348.891843) (xy 133.354495 -348.856124) (xy 133.318774 -348.814903) (xy 133.289283 -348.769016)
			(xy 133.266623 -348.7194) (xy 133.251255 -348.667064) (xy 133.243492 -348.613073) (xy 131.760788 -348.613073)
			(xy 131.753026 -348.66706) (xy 131.737658 -348.719394) (xy 131.714999 -348.769008) (xy 131.685509 -348.814892)
			(xy 131.649789 -348.856112) (xy 131.608566 -348.891828) (xy 131.56268 -348.921314) (xy 131.513064 -348.943969)
			(xy 131.460729 -348.959332) (xy 131.40674 -348.967091) (xy 131.379468 -348.967552) (xy 130.515868 -348.967552)
			(xy 130.488599 -348.967083) (xy 130.434618 -348.959318) (xy 130.382291 -348.943949) (xy 130.332683 -348.921291)
			(xy 130.286805 -348.891803) (xy 130.24559 -348.856087) (xy 130.209878 -348.814869) (xy 130.180394 -348.768989)
			(xy 130.15774 -348.719379) (xy 130.142375 -348.667051) (xy 130.134614 -348.613069) (xy 128.651766 -348.613069)
			(xy 128.644004 -348.66705) (xy 128.62864 -348.719377) (xy 128.605985 -348.768986) (xy 128.5765 -348.814865)
			(xy 128.540787 -348.856081) (xy 128.499571 -348.891796) (xy 128.453693 -348.921281) (xy 128.404085 -348.943937)
			(xy 128.351758 -348.959303) (xy 128.297776 -348.967065) (xy 128.270508 -348.967552) (xy 127.406908 -348.967552)
			(xy 127.379636 -348.967109) (xy 127.325647 -348.959348) (xy 127.273312 -348.943982) (xy 127.223696 -348.921324)
			(xy 127.17781 -348.891836) (xy 127.136588 -348.856117) (xy 127.100869 -348.814896) (xy 127.07138 -348.769011)
			(xy 127.048721 -348.719396) (xy 127.033354 -348.667061) (xy 127.025592 -348.613072) (xy 125.542765 -348.613072)
			(xy 125.535006 -348.667044) (xy 125.519643 -348.719369) (xy 125.496991 -348.768974) (xy 125.46751 -348.814852)
			(xy 125.431801 -348.856067) (xy 125.39059 -348.891781) (xy 125.344717 -348.921268) (xy 125.295114 -348.943926)
			(xy 125.242791 -348.959295) (xy 125.188814 -348.967062) (xy 125.161548 -348.967552) (xy 124.297948 -348.967552)
			(xy 124.270674 -348.967112) (xy 124.216681 -348.959355) (xy 124.164341 -348.943992) (xy 124.11472 -348.921337)
			(xy 124.068829 -348.89185) (xy 124.027602 -348.856132) (xy 123.991879 -348.814909) (xy 123.962386 -348.769022)
			(xy 123.939724 -348.719404) (xy 123.924355 -348.667066) (xy 123.916592 -348.613074) (xy 122.433889 -348.613074)
			(xy 122.426126 -348.667057) (xy 122.41076 -348.71939) (xy 122.388102 -348.769002) (xy 122.358614 -348.814885)
			(xy 122.322896 -348.856105) (xy 122.281676 -348.891821) (xy 122.235792 -348.921308) (xy 122.186178 -348.943964)
			(xy 122.133846 -348.959329) (xy 122.079859 -348.967089) (xy 122.052588 -348.967552) (xy 121.188988 -348.967552)
			(xy 121.161718 -348.967085) (xy 121.107735 -348.959321) (xy 121.055405 -348.943955) (xy 121.005795 -348.921297)
			(xy 120.959915 -348.89181) (xy 120.918697 -348.856094) (xy 120.882983 -348.814876) (xy 120.853497 -348.768994)
			(xy 120.830841 -348.719383) (xy 120.815476 -348.667053) (xy 120.807714 -348.61307) (xy 119.324866 -348.61307)
			(xy 119.317105 -348.667047) (xy 119.301741 -348.719373) (xy 119.279088 -348.76898) (xy 119.249605 -348.814858)
			(xy 119.213894 -348.856074) (xy 119.172681 -348.891789) (xy 119.126805 -348.921274) (xy 119.077199 -348.943932)
			(xy 119.024875 -348.959299) (xy 118.970895 -348.967064) (xy 118.943628 -348.967552) (xy 118.080028 -348.967552)
			(xy 118.052755 -348.96711) (xy 117.998764 -348.959351) (xy 117.946426 -348.943987) (xy 117.896808 -348.92133)
			(xy 117.85092 -348.891843) (xy 117.809695 -348.856124) (xy 117.773974 -348.814903) (xy 117.744483 -348.769016)
			(xy 117.721823 -348.7194) (xy 117.706455 -348.667064) (xy 117.698692 -348.613073) (xy 116.215988 -348.613073)
			(xy 116.208226 -348.66706) (xy 116.192858 -348.719394) (xy 116.170199 -348.769008) (xy 116.140709 -348.814892)
			(xy 116.104989 -348.856112) (xy 116.063766 -348.891828) (xy 116.01788 -348.921314) (xy 115.968264 -348.943969)
			(xy 115.915929 -348.959332) (xy 115.86194 -348.967091) (xy 115.834668 -348.967552) (xy 114.971068 -348.967552)
			(xy 114.943799 -348.967083) (xy 114.889818 -348.959318) (xy 114.837491 -348.943949) (xy 114.787883 -348.921291)
			(xy 114.742005 -348.891803) (xy 114.70079 -348.856087) (xy 114.665078 -348.814869) (xy 114.635594 -348.768989)
			(xy 114.61294 -348.719379) (xy 114.597575 -348.667051) (xy 114.589814 -348.613069) (xy 113.106966 -348.613069)
			(xy 113.099204 -348.66705) (xy 113.08384 -348.719377) (xy 113.061185 -348.768986) (xy 113.0317 -348.814865)
			(xy 112.995987 -348.856081) (xy 112.954771 -348.891796) (xy 112.908893 -348.921281) (xy 112.859285 -348.943937)
			(xy 112.806958 -348.959303) (xy 112.752976 -348.967065) (xy 112.725708 -348.967552) (xy 111.862108 -348.967552)
			(xy 111.834836 -348.967109) (xy 111.780847 -348.959348) (xy 111.728512 -348.943982) (xy 111.678896 -348.921324)
			(xy 111.63301 -348.891836) (xy 111.591788 -348.856117) (xy 111.556069 -348.814896) (xy 111.52658 -348.769011)
			(xy 111.503921 -348.719396) (xy 111.488554 -348.667061) (xy 111.480792 -348.613072) (xy 93.706665 -348.613072)
			(xy 93.698905 -348.667045) (xy 93.683543 -348.71937) (xy 93.66089 -348.768976) (xy 93.631409 -348.814854)
			(xy 93.595699 -348.856069) (xy 93.554487 -348.891784) (xy 93.508613 -348.92127) (xy 93.459009 -348.943928)
			(xy 93.406686 -348.959296) (xy 93.352709 -348.967063) (xy 93.325442 -348.967552) (xy 92.461842 -348.967552)
			(xy 92.434568 -348.967111) (xy 92.380576 -348.959354) (xy 92.328236 -348.943991) (xy 92.278617 -348.921335)
			(xy 92.232727 -348.891848) (xy 92.1915 -348.856129) (xy 92.155777 -348.814907) (xy 92.126285 -348.76902)
			(xy 92.103624 -348.719403) (xy 92.088255 -348.667066) (xy 92.080492 -348.613074) (xy 90.597788 -348.613074)
			(xy 90.590026 -348.667058) (xy 90.574659 -348.719391) (xy 90.552001 -348.769004) (xy 90.522512 -348.814887)
			(xy 90.486794 -348.856107) (xy 90.445573 -348.891823) (xy 90.399688 -348.92131) (xy 90.350074 -348.943966)
			(xy 90.297741 -348.95933) (xy 90.243753 -348.96709) (xy 90.216482 -348.967552) (xy 89.352882 -348.967552)
			(xy 89.325613 -348.967084) (xy 89.27163 -348.95932) (xy 89.219301 -348.943953) (xy 89.169692 -348.921295)
			(xy 89.123812 -348.891808) (xy 89.082595 -348.856092) (xy 89.046881 -348.814874) (xy 89.017396 -348.768992)
			(xy 88.994741 -348.719382) (xy 88.979376 -348.667053) (xy 88.971614 -348.613069) (xy 87.488766 -348.613069)
			(xy 87.481005 -348.667048) (xy 87.465641 -348.719374) (xy 87.442987 -348.768982) (xy 87.413504 -348.81486)
			(xy 87.377792 -348.856076) (xy 87.336578 -348.891791) (xy 87.290701 -348.921276) (xy 87.241095 -348.943933)
			(xy 87.188769 -348.9593) (xy 87.13479 -348.967064) (xy 87.107522 -348.967552) (xy 86.243922 -348.967552)
			(xy 86.216649 -348.96711) (xy 86.162659 -348.95935) (xy 86.110322 -348.943985) (xy 86.060705 -348.921329)
			(xy 86.014817 -348.891841) (xy 85.973593 -348.856122) (xy 85.937872 -348.814901) (xy 85.908382 -348.769015)
			(xy 85.885722 -348.719399) (xy 85.870354 -348.667063) (xy 85.862592 -348.613073) (xy 84.379888 -348.613073)
			(xy 84.372126 -348.667061) (xy 84.356758 -348.719395) (xy 84.334098 -348.76901) (xy 84.304608 -348.814894)
			(xy 84.268887 -348.856114) (xy 84.227663 -348.89183) (xy 84.181776 -348.921316) (xy 84.13216 -348.943971)
			(xy 84.079824 -348.959334) (xy 84.025834 -348.967091) (xy 83.998562 -348.967552) (xy 83.134962 -348.967552)
			(xy 83.107694 -348.967083) (xy 83.053713 -348.959317) (xy 83.001386 -348.943948) (xy 82.95178 -348.921289)
			(xy 82.905902 -348.891801) (xy 82.864688 -348.856085) (xy 82.828976 -348.814867) (xy 82.799493 -348.768987)
			(xy 82.776839 -348.719378) (xy 82.761475 -348.66705) (xy 82.753714 -348.613068) (xy 81.270866 -348.613068)
			(xy 81.270866 -348.613069) (xy 81.263104 -348.667051) (xy 81.247739 -348.719379) (xy 81.225084 -348.768987)
			(xy 81.195599 -348.814867) (xy 81.159885 -348.856083) (xy 81.118669 -348.891798) (xy 81.072789 -348.921283)
			(xy 81.02318 -348.943939) (xy 80.970853 -348.959304) (xy 80.916871 -348.967065) (xy 80.889602 -348.967552)
			(xy 80.026002 -348.967552) (xy 79.99873 -348.967109) (xy 79.944742 -348.959347) (xy 79.892407 -348.94398)
			(xy 79.842793 -348.921322) (xy 79.796908 -348.891834) (xy 79.755686 -348.856115) (xy 79.719968 -348.814894)
			(xy 79.690479 -348.769009) (xy 79.667821 -348.719394) (xy 79.652454 -348.66706) (xy 79.644692 -348.613072)
			(xy 78.161865 -348.613072) (xy 78.154105 -348.667045) (xy 78.138743 -348.71937) (xy 78.11609 -348.768976)
			(xy 78.086609 -348.814854) (xy 78.050899 -348.856069) (xy 78.009687 -348.891784) (xy 77.963813 -348.92127)
			(xy 77.914209 -348.943928) (xy 77.861886 -348.959296) (xy 77.807909 -348.967063) (xy 77.780642 -348.967552)
			(xy 76.917042 -348.967552) (xy 76.889768 -348.967111) (xy 76.835776 -348.959354) (xy 76.783436 -348.943991)
			(xy 76.733817 -348.921335) (xy 76.687927 -348.891848) (xy 76.6467 -348.856129) (xy 76.610977 -348.814907)
			(xy 76.581485 -348.76902) (xy 76.558824 -348.719403) (xy 76.543455 -348.667066) (xy 76.535692 -348.613074)
			(xy 75.052988 -348.613074) (xy 75.045226 -348.667058) (xy 75.029859 -348.719391) (xy 75.007201 -348.769004)
			(xy 74.977712 -348.814887) (xy 74.941994 -348.856107) (xy 74.900773 -348.891823) (xy 74.854888 -348.92131)
			(xy 74.805274 -348.943966) (xy 74.752941 -348.95933) (xy 74.698953 -348.96709) (xy 74.671682 -348.967552)
			(xy 73.808082 -348.967552) (xy 73.780813 -348.967084) (xy 73.72683 -348.95932) (xy 73.674501 -348.943953)
			(xy 73.624892 -348.921295) (xy 73.579012 -348.891808) (xy 73.537795 -348.856092) (xy 73.502081 -348.814874)
			(xy 73.472596 -348.768992) (xy 73.449941 -348.719382) (xy 73.434576 -348.667053) (xy 73.426814 -348.613069)
			(xy 71.943966 -348.613069) (xy 71.936205 -348.667048) (xy 71.920841 -348.719374) (xy 71.898187 -348.768982)
			(xy 71.868704 -348.81486) (xy 71.832992 -348.856076) (xy 71.791778 -348.891791) (xy 71.745901 -348.921276)
			(xy 71.696295 -348.943933) (xy 71.643969 -348.9593) (xy 71.58999 -348.967064) (xy 71.562722 -348.967552)
			(xy 70.699122 -348.967552) (xy 70.671849 -348.96711) (xy 70.617859 -348.95935) (xy 70.565522 -348.943985)
			(xy 70.515905 -348.921329) (xy 70.470017 -348.891841) (xy 70.428793 -348.856122) (xy 70.393072 -348.814901)
			(xy 70.363582 -348.769015) (xy 70.340922 -348.719399) (xy 70.325554 -348.667063) (xy 70.317792 -348.613073)
			(xy 68.835088 -348.613073) (xy 68.827326 -348.667061) (xy 68.811958 -348.719395) (xy 68.789298 -348.76901)
			(xy 68.759808 -348.814894) (xy 68.724087 -348.856114) (xy 68.682863 -348.89183) (xy 68.636976 -348.921316)
			(xy 68.58736 -348.943971) (xy 68.535024 -348.959334) (xy 68.481034 -348.967091) (xy 68.453762 -348.967552)
			(xy 67.590162 -348.967552) (xy 67.562894 -348.967083) (xy 67.508913 -348.959317) (xy 67.456586 -348.943948)
			(xy 67.40698 -348.921289) (xy 67.361102 -348.891801) (xy 67.319888 -348.856085) (xy 67.284176 -348.814867)
			(xy 67.254693 -348.768987) (xy 67.232039 -348.719378) (xy 67.216675 -348.66705) (xy 67.208914 -348.613068)
			(xy 65.726066 -348.613068) (xy 65.726066 -348.613069) (xy 65.718304 -348.667051) (xy 65.702939 -348.719379)
			(xy 65.680284 -348.768987) (xy 65.650799 -348.814867) (xy 65.615085 -348.856083) (xy 65.573869 -348.891798)
			(xy 65.527989 -348.921283) (xy 65.47838 -348.943939) (xy 65.426053 -348.959304) (xy 65.372071 -348.967065)
			(xy 65.344802 -348.967552) (xy 64.481202 -348.967552) (xy 64.45393 -348.967109) (xy 64.399942 -348.959347)
			(xy 64.347607 -348.94398) (xy 64.297993 -348.921322) (xy 64.252108 -348.891834) (xy 64.210886 -348.856115)
			(xy 64.175168 -348.814894) (xy 64.145679 -348.769009) (xy 64.123021 -348.719394) (xy 64.107654 -348.66706)
			(xy 64.099892 -348.613072) (xy 62.617065 -348.613072) (xy 62.609305 -348.667045) (xy 62.593943 -348.71937)
			(xy 62.57129 -348.768976) (xy 62.541809 -348.814854) (xy 62.506099 -348.856069) (xy 62.464887 -348.891784)
			(xy 62.419013 -348.92127) (xy 62.369409 -348.943928) (xy 62.317086 -348.959296) (xy 62.263109 -348.967063)
			(xy 62.235842 -348.967552) (xy 61.372242 -348.967552) (xy 61.344968 -348.967111) (xy 61.290976 -348.959354)
			(xy 61.238636 -348.943991) (xy 61.189017 -348.921335) (xy 61.143127 -348.891848) (xy 61.1019 -348.856129)
			(xy 61.066177 -348.814907) (xy 61.036685 -348.76902) (xy 61.014024 -348.719403) (xy 60.998655 -348.667066)
			(xy 60.990892 -348.613074) (xy 51.666865 -348.613074) (xy 51.659106 -348.667044) (xy 51.643743 -348.719369)
			(xy 51.621091 -348.768974) (xy 51.59161 -348.814852) (xy 51.555901 -348.856067) (xy 51.51469 -348.891781)
			(xy 51.468817 -348.921268) (xy 51.419214 -348.943926) (xy 51.366891 -348.959295) (xy 51.312914 -348.967062)
			(xy 51.285648 -348.967552) (xy 50.422048 -348.967552) (xy 50.394774 -348.967112) (xy 50.340781 -348.959355)
			(xy 50.288441 -348.943992) (xy 50.23882 -348.921337) (xy 50.192929 -348.89185) (xy 50.151702 -348.856132)
			(xy 50.115979 -348.814909) (xy 50.086486 -348.769022) (xy 50.063824 -348.719404) (xy 50.048455 -348.667066)
			(xy 50.040692 -348.613074) (xy 48.557989 -348.613074) (xy 48.550226 -348.667057) (xy 48.53486 -348.71939)
			(xy 48.512202 -348.769002) (xy 48.482714 -348.814885) (xy 48.446996 -348.856105) (xy 48.405776 -348.891821)
			(xy 48.359892 -348.921308) (xy 48.310278 -348.943964) (xy 48.257946 -348.959329) (xy 48.203959 -348.967089)
			(xy 48.176688 -348.967552) (xy 47.313088 -348.967552) (xy 47.285818 -348.967085) (xy 47.231835 -348.959321)
			(xy 47.179505 -348.943955) (xy 47.129895 -348.921297) (xy 47.084015 -348.89181) (xy 47.042797 -348.856094)
			(xy 47.007083 -348.814876) (xy 46.977597 -348.768994) (xy 46.954941 -348.719383) (xy 46.939576 -348.667053)
			(xy 46.931814 -348.61307) (xy 45.448966 -348.61307) (xy 45.441205 -348.667047) (xy 45.425841 -348.719373)
			(xy 45.403188 -348.76898) (xy 45.373705 -348.814858) (xy 45.337994 -348.856074) (xy 45.296781 -348.891789)
			(xy 45.250905 -348.921274) (xy 45.201299 -348.943932) (xy 45.148975 -348.959299) (xy 45.094995 -348.967064)
			(xy 45.067728 -348.967552) (xy 44.204128 -348.967552) (xy 44.176855 -348.96711) (xy 44.122864 -348.959351)
			(xy 44.070526 -348.943987) (xy 44.020908 -348.92133) (xy 43.97502 -348.891843) (xy 43.933795 -348.856124)
			(xy 43.898074 -348.814903) (xy 43.868583 -348.769016) (xy 43.845923 -348.7194) (xy 43.830555 -348.667064)
			(xy 43.822792 -348.613073) (xy 42.340088 -348.613073) (xy 42.332326 -348.66706) (xy 42.316958 -348.719394)
			(xy 42.294299 -348.769008) (xy 42.264809 -348.814892) (xy 42.229089 -348.856112) (xy 42.187866 -348.891828)
			(xy 42.14198 -348.921314) (xy 42.092364 -348.943969) (xy 42.040029 -348.959332) (xy 41.98604 -348.967091)
			(xy 41.958768 -348.967552) (xy 41.095168 -348.967552) (xy 41.067899 -348.967083) (xy 41.013918 -348.959318)
			(xy 40.961591 -348.943949) (xy 40.911983 -348.921291) (xy 40.866105 -348.891803) (xy 40.82489 -348.856087)
			(xy 40.789178 -348.814869) (xy 40.759694 -348.768989) (xy 40.73704 -348.719379) (xy 40.721675 -348.667051)
			(xy 40.713914 -348.613069) (xy 39.231066 -348.613069) (xy 39.223304 -348.66705) (xy 39.20794 -348.719377)
			(xy 39.185285 -348.768986) (xy 39.1558 -348.814865) (xy 39.120087 -348.856081) (xy 39.078871 -348.891796)
			(xy 39.032993 -348.921281) (xy 38.983385 -348.943937) (xy 38.931058 -348.959303) (xy 38.877076 -348.967065)
			(xy 38.849808 -348.967552) (xy 37.986208 -348.967552) (xy 37.958936 -348.967109) (xy 37.904947 -348.959348)
			(xy 37.852612 -348.943982) (xy 37.802996 -348.921324) (xy 37.75711 -348.891836) (xy 37.715888 -348.856117)
			(xy 37.680169 -348.814896) (xy 37.65068 -348.769011) (xy 37.628021 -348.719396) (xy 37.612654 -348.667061)
			(xy 37.604892 -348.613072) (xy 36.122065 -348.613072) (xy 36.114306 -348.667044) (xy 36.098943 -348.719369)
			(xy 36.076291 -348.768974) (xy 36.04681 -348.814852) (xy 36.011101 -348.856067) (xy 35.96989 -348.891781)
			(xy 35.924017 -348.921268) (xy 35.874414 -348.943926) (xy 35.822091 -348.959295) (xy 35.768114 -348.967062)
			(xy 35.740848 -348.967552) (xy 34.877248 -348.967552) (xy 34.849974 -348.967112) (xy 34.795981 -348.959355)
			(xy 34.743641 -348.943992) (xy 34.69402 -348.921337) (xy 34.648129 -348.89185) (xy 34.606902 -348.856132)
			(xy 34.571179 -348.814909) (xy 34.541686 -348.769022) (xy 34.519024 -348.719404) (xy 34.503655 -348.667066)
			(xy 34.495892 -348.613074) (xy 33.013189 -348.613074) (xy 33.005426 -348.667057) (xy 32.99006 -348.71939)
			(xy 32.967402 -348.769002) (xy 32.937914 -348.814885) (xy 32.902196 -348.856105) (xy 32.860976 -348.891821)
			(xy 32.815092 -348.921308) (xy 32.765478 -348.943964) (xy 32.713146 -348.959329) (xy 32.659159 -348.967089)
			(xy 32.631888 -348.967552) (xy 31.768288 -348.967552) (xy 31.741018 -348.967085) (xy 31.687035 -348.959321)
			(xy 31.634705 -348.943955) (xy 31.585095 -348.921297) (xy 31.539215 -348.89181) (xy 31.497997 -348.856094)
			(xy 31.462283 -348.814876) (xy 31.432797 -348.768994) (xy 31.410141 -348.719383) (xy 31.394776 -348.667053)
			(xy 31.387014 -348.61307) (xy 29.904166 -348.61307) (xy 29.896405 -348.667047) (xy 29.881041 -348.719373)
			(xy 29.858388 -348.76898) (xy 29.828905 -348.814858) (xy 29.793194 -348.856074) (xy 29.751981 -348.891789)
			(xy 29.706105 -348.921274) (xy 29.656499 -348.943932) (xy 29.604175 -348.959299) (xy 29.550195 -348.967064)
			(xy 29.522928 -348.967552) (xy 28.659328 -348.967552) (xy 28.632055 -348.96711) (xy 28.578064 -348.959351)
			(xy 28.525726 -348.943987) (xy 28.476108 -348.92133) (xy 28.43022 -348.891843) (xy 28.388995 -348.856124)
			(xy 28.353274 -348.814903) (xy 28.323783 -348.769016) (xy 28.301123 -348.7194) (xy 28.285755 -348.667064)
			(xy 28.277992 -348.613073) (xy 26.795288 -348.613073) (xy 26.787526 -348.66706) (xy 26.772158 -348.719394)
			(xy 26.749499 -348.769008) (xy 26.720009 -348.814892) (xy 26.684289 -348.856112) (xy 26.643066 -348.891828)
			(xy 26.59718 -348.921314) (xy 26.547564 -348.943969) (xy 26.495229 -348.959332) (xy 26.44124 -348.967091)
			(xy 26.413968 -348.967552) (xy 25.550368 -348.967552) (xy 25.523099 -348.967083) (xy 25.469118 -348.959318)
			(xy 25.416791 -348.943949) (xy 25.367183 -348.921291) (xy 25.321305 -348.891803) (xy 25.28009 -348.856087)
			(xy 25.244378 -348.814869) (xy 25.214894 -348.768989) (xy 25.19224 -348.719379) (xy 25.176875 -348.667051)
			(xy 25.169114 -348.613069) (xy 23.686266 -348.613069) (xy 23.678504 -348.66705) (xy 23.66314 -348.719377)
			(xy 23.640485 -348.768986) (xy 23.611 -348.814865) (xy 23.575287 -348.856081) (xy 23.534071 -348.891796)
			(xy 23.488193 -348.921281) (xy 23.438585 -348.943937) (xy 23.386258 -348.959303) (xy 23.332276 -348.967065)
			(xy 23.305008 -348.967552) (xy 22.441408 -348.967552) (xy 22.414136 -348.967109) (xy 22.360147 -348.959348)
			(xy 22.307812 -348.943982) (xy 22.258196 -348.921324) (xy 22.21231 -348.891836) (xy 22.171088 -348.856117)
			(xy 22.135369 -348.814896) (xy 22.10588 -348.769011) (xy 22.083221 -348.719396) (xy 22.067854 -348.667061)
			(xy 22.060092 -348.613072) (xy 20.577347 -348.613072) (xy 20.569586 -348.667048) (xy 20.55422 -348.719381)
			(xy 20.531562 -348.768994) (xy 20.502074 -348.814878) (xy 20.466357 -348.856098) (xy 20.425136 -348.891816)
			(xy 20.379253 -348.921303) (xy 20.329639 -348.943961) (xy 20.277306 -348.959327) (xy 20.223319 -348.967089)
			(xy 20.196048 -348.967552) (xy 19.332448 -348.967552) (xy 19.305179 -348.967065) (xy 19.251195 -348.959304)
			(xy 19.198866 -348.943938) (xy 19.149256 -348.921282) (xy 19.103375 -348.891796) (xy 19.062158 -348.856081)
			(xy 19.026443 -348.814863) (xy 18.996957 -348.768982) (xy 18.974301 -348.719372) (xy 18.958936 -348.667043)
			(xy 18.951174 -348.613059) (xy 8.879169 -348.613059) (xy 8.892221 -348.718461) (xy 8.900171 -348.847356)
			(xy 8.900668 -348.911926) (xy 8.900171 -348.976496) (xy 8.892221 -349.105391) (xy 8.876351 -349.233551)
			(xy 8.852622 -349.360492) (xy 8.821123 -349.485731) (xy 8.781974 -349.608794) (xy 8.735323 -349.729213)
			(xy 8.681348 -349.846532) (xy 8.620253 -349.960306) (xy 8.55227 -350.070103) (xy 8.477656 -350.175506)
			(xy 8.396695 -350.276116) (xy 8.309695 -350.371551) (xy 8.216984 -350.46145) (xy 8.118914 -350.545471)
			(xy 8.015859 -350.623295) (xy 7.908208 -350.694627) (xy 7.796369 -350.759197) (xy 7.680768 -350.816759)
			(xy 7.561843 -350.867096) (xy 7.440044 -350.910016) (xy 7.315834 -350.945357) (xy 7.189685 -350.972984)
			(xy 7.062073 -350.992793) (xy 6.933484 -351.004709) (xy 6.804406 -351.008686) (xy 6.675328 -351.004709)
			(xy 6.546739 -350.992793) (xy 6.419127 -350.972984) (xy 6.292978 -350.945357) (xy 6.168768 -350.910016)
			(xy 6.046969 -350.867096) (xy 5.928044 -350.816759) (xy 5.812443 -350.759197) (xy 5.700604 -350.694627)
			(xy 5.592953 -350.623295) (xy 5.489898 -350.545471) (xy 5.391828 -350.46145) (xy 5.299117 -350.371551)
			(xy 5.212117 -350.276116) (xy 5.131156 -350.175506) (xy 5.056542 -350.070103) (xy 4.988559 -349.960306)
			(xy 4.927464 -349.846532) (xy 4.873489 -349.729213) (xy 4.826838 -349.608794) (xy 4.787689 -349.485731)
			(xy 4.75619 -349.360492) (xy 4.732461 -349.233551) (xy 4.716591 -349.105391) (xy 4.708641 -348.976496)
			(xy 0.508 -348.976496) (xy 0.508 -351.638709) (xy 18.951172 -351.638709) (xy 18.951172 -351.584171)
			(xy 18.958934 -351.530187) (xy 18.974299 -351.477857) (xy 18.996956 -351.428247) (xy 19.026441 -351.382366)
			(xy 19.062157 -351.341148) (xy 19.103374 -351.305433) (xy 19.149255 -351.275947) (xy 19.198865 -351.25329)
			(xy 19.251195 -351.237925) (xy 19.305179 -351.230163) (xy 19.332448 -351.229676) (xy 20.196048 -351.229676)
			(xy 20.223319 -351.230143) (xy 20.277306 -351.237905) (xy 20.329638 -351.253271) (xy 20.379252 -351.275929)
			(xy 20.425135 -351.305416) (xy 20.466355 -351.341133) (xy 20.502073 -351.382353) (xy 20.53156 -351.428237)
			(xy 20.554218 -351.47785) (xy 20.569584 -351.530182) (xy 20.577347 -351.584169) (xy 20.577347 -351.638669)
			(xy 22.060139 -351.638669) (xy 22.060139 -351.584131) (xy 22.067901 -351.530149) (xy 22.083266 -351.477821)
			(xy 22.105922 -351.428212) (xy 22.135407 -351.382333) (xy 22.171122 -351.341117) (xy 22.212339 -351.305403)
			(xy 22.258219 -351.275918) (xy 22.307829 -351.253263) (xy 22.360157 -351.237899) (xy 22.414139 -351.230139)
			(xy 22.441408 -351.229676) (xy 23.305008 -351.229676) (xy 23.33228 -351.230087) (xy 23.386268 -351.23785)
			(xy 23.438602 -351.253218) (xy 23.488216 -351.275877) (xy 23.5341 -351.305366) (xy 23.575321 -351.341085)
			(xy 23.611039 -351.382306) (xy 23.640527 -351.428191) (xy 23.663185 -351.477806) (xy 23.678551 -351.53014)
			(xy 23.686314 -351.584128) (xy 23.686314 -351.638665) (xy 25.169162 -351.638665) (xy 25.169162 -351.584135)
			(xy 25.176922 -351.530159) (xy 25.192284 -351.477838) (xy 25.214936 -351.428234) (xy 25.244416 -351.38236)
			(xy 25.280124 -351.341147) (xy 25.321334 -351.305435) (xy 25.367206 -351.275951) (xy 25.416808 -351.253296)
			(xy 25.469128 -351.237929) (xy 25.523103 -351.230165) (xy 25.550368 -351.229676) (xy 26.413968 -351.229676)
			(xy 26.441243 -351.230061) (xy 26.495239 -351.237821) (xy 26.547581 -351.253186) (xy 26.597203 -351.275844)
			(xy 26.643095 -351.305333) (xy 26.684323 -351.341054) (xy 26.720047 -351.382279) (xy 26.749541 -351.428169)
			(xy 26.772203 -351.477789) (xy 26.787573 -351.53013) (xy 26.795336 -351.584125) (xy 26.795336 -351.63867)
			(xy 28.278039 -351.63867) (xy 28.278039 -351.58413) (xy 28.285802 -351.530146) (xy 28.301168 -351.477817)
			(xy 28.323825 -351.428207) (xy 28.353312 -351.382326) (xy 28.389029 -351.341109) (xy 28.430249 -351.305396)
			(xy 28.476131 -351.275912) (xy 28.525743 -351.253258) (xy 28.578074 -351.237896) (xy 28.632058 -351.230137)
			(xy 28.659328 -351.229676) (xy 29.522928 -351.229676) (xy 29.550199 -351.230088) (xy 29.604185 -351.237854)
			(xy 29.656516 -351.253223) (xy 29.706128 -351.275883) (xy 29.75201 -351.305373) (xy 29.793228 -351.341092)
			(xy 29.828944 -351.382313) (xy 29.85843 -351.428197) (xy 29.881086 -351.47781) (xy 29.896452 -351.530143)
			(xy 29.904214 -351.584129) (xy 29.904214 -351.638666) (xy 31.387062 -351.638666) (xy 31.387062 -351.584134)
			(xy 31.394823 -351.530157) (xy 31.410186 -351.477833) (xy 31.432839 -351.428229) (xy 31.462321 -351.382353)
			(xy 31.498031 -351.34114) (xy 31.539243 -351.305428) (xy 31.585118 -351.275945) (xy 31.634722 -351.25329)
			(xy 31.687045 -351.237925) (xy 31.741022 -351.230163) (xy 31.768288 -351.229676) (xy 32.631888 -351.229676)
			(xy 32.659162 -351.230063) (xy 32.713156 -351.237824) (xy 32.765495 -351.253191) (xy 32.815115 -351.27585)
			(xy 32.861004 -351.30534) (xy 32.90223 -351.341061) (xy 32.937952 -351.382286) (xy 32.967444 -351.428175)
			(xy 32.990105 -351.477794) (xy 33.005473 -351.530132) (xy 33.013236 -351.584126) (xy 33.013236 -351.63867)
			(xy 34.49594 -351.63867) (xy 34.49594 -351.58413) (xy 34.503702 -351.530144) (xy 34.519069 -351.477812)
			(xy 34.541728 -351.428201) (xy 34.571217 -351.38232) (xy 34.606936 -351.341102) (xy 34.648158 -351.305388)
			(xy 34.694043 -351.275905) (xy 34.743658 -351.253253) (xy 34.795991 -351.237892) (xy 34.849977 -351.230136)
			(xy 34.877248 -351.229676) (xy 35.740848 -351.229676) (xy 35.768118 -351.23009) (xy 35.822102 -351.237858)
			(xy 35.874431 -351.253229) (xy 35.92404 -351.27589) (xy 35.969919 -351.30538) (xy 36.011135 -351.341099)
			(xy 36.046849 -351.382319) (xy 36.076333 -351.428203) (xy 36.098988 -351.477814) (xy 36.114352 -351.530145)
			(xy 36.122114 -351.58413) (xy 36.122114 -351.638669) (xy 37.604939 -351.638669) (xy 37.604939 -351.584131)
			(xy 37.612701 -351.530149) (xy 37.628066 -351.477821) (xy 37.650722 -351.428212) (xy 37.680207 -351.382333)
			(xy 37.715922 -351.341117) (xy 37.757139 -351.305403) (xy 37.803019 -351.275918) (xy 37.852629 -351.253263)
			(xy 37.904957 -351.237899) (xy 37.958939 -351.230139) (xy 37.986208 -351.229676) (xy 38.849808 -351.229676)
			(xy 38.87708 -351.230087) (xy 38.931068 -351.23785) (xy 38.983402 -351.253218) (xy 39.033016 -351.275877)
			(xy 39.0789 -351.305366) (xy 39.120121 -351.341085) (xy 39.155839 -351.382306) (xy 39.185327 -351.428191)
			(xy 39.207985 -351.477806) (xy 39.223351 -351.53014) (xy 39.231114 -351.584128) (xy 39.231114 -351.638665)
			(xy 40.713962 -351.638665) (xy 40.713962 -351.584135) (xy 40.721722 -351.530159) (xy 40.737084 -351.477838)
			(xy 40.759736 -351.428234) (xy 40.789216 -351.38236) (xy 40.824924 -351.341147) (xy 40.866134 -351.305435)
			(xy 40.912006 -351.275951) (xy 40.961608 -351.253296) (xy 41.013928 -351.237929) (xy 41.067903 -351.230165)
			(xy 41.095168 -351.229676) (xy 41.958768 -351.229676) (xy 41.986043 -351.230061) (xy 42.040039 -351.237821)
			(xy 42.092381 -351.253186) (xy 42.142003 -351.275844) (xy 42.187895 -351.305333) (xy 42.229123 -351.341054)
			(xy 42.264847 -351.382279) (xy 42.294341 -351.428169) (xy 42.317003 -351.477789) (xy 42.332373 -351.53013)
			(xy 42.340136 -351.584125) (xy 42.340136 -351.63867) (xy 43.822839 -351.63867) (xy 43.822839 -351.58413)
			(xy 43.830602 -351.530146) (xy 43.845968 -351.477817) (xy 43.868625 -351.428207) (xy 43.898112 -351.382326)
			(xy 43.933829 -351.341109) (xy 43.975049 -351.305396) (xy 44.020931 -351.275912) (xy 44.070543 -351.253258)
			(xy 44.122874 -351.237896) (xy 44.176858 -351.230137) (xy 44.204128 -351.229676) (xy 45.067728 -351.229676)
			(xy 45.094999 -351.230088) (xy 45.148985 -351.237854) (xy 45.201316 -351.253223) (xy 45.250928 -351.275883)
			(xy 45.29681 -351.305373) (xy 45.338028 -351.341092) (xy 45.373744 -351.382313) (xy 45.40323 -351.428197)
			(xy 45.425886 -351.47781) (xy 45.441252 -351.530143) (xy 45.449014 -351.584129) (xy 45.449014 -351.638666)
			(xy 46.931862 -351.638666) (xy 46.931862 -351.584134) (xy 46.939623 -351.530157) (xy 46.954986 -351.477833)
			(xy 46.977639 -351.428229) (xy 47.007121 -351.382353) (xy 47.042831 -351.34114) (xy 47.084043 -351.305428)
			(xy 47.129918 -351.275945) (xy 47.179522 -351.25329) (xy 47.231845 -351.237925) (xy 47.285822 -351.230163)
			(xy 47.313088 -351.229676) (xy 48.176688 -351.229676) (xy 48.203962 -351.230063) (xy 48.257956 -351.237824)
			(xy 48.310295 -351.253191) (xy 48.359915 -351.27585) (xy 48.405804 -351.30534) (xy 48.44703 -351.341061)
			(xy 48.482752 -351.382286) (xy 48.512244 -351.428175) (xy 48.534905 -351.477794) (xy 48.550273 -351.530132)
			(xy 48.558036 -351.584126) (xy 48.558036 -351.63867) (xy 50.04074 -351.63867) (xy 50.04074 -351.58413)
			(xy 50.048502 -351.530144) (xy 50.063869 -351.477812) (xy 50.086528 -351.428201) (xy 50.116017 -351.38232)
			(xy 50.151736 -351.341102) (xy 50.192958 -351.305388) (xy 50.238843 -351.275905) (xy 50.288458 -351.253253)
			(xy 50.340791 -351.237892) (xy 50.394777 -351.230136) (xy 50.422048 -351.229676) (xy 51.285648 -351.229676)
			(xy 51.312918 -351.23009) (xy 51.366902 -351.237858) (xy 51.419231 -351.253229) (xy 51.46884 -351.27589)
			(xy 51.514719 -351.30538) (xy 51.555935 -351.341099) (xy 51.591649 -351.382319) (xy 51.621133 -351.428203)
			(xy 51.643788 -351.477814) (xy 51.659152 -351.530145) (xy 51.666914 -351.58413) (xy 51.666914 -351.63867)
			(xy 60.99094 -351.63867) (xy 60.99094 -351.58413) (xy 60.998702 -351.530145) (xy 61.014069 -351.477814)
			(xy 61.036727 -351.428203) (xy 61.066216 -351.382322) (xy 61.101934 -351.341105) (xy 61.143155 -351.305391)
			(xy 61.18904 -351.275907) (xy 61.238653 -351.253254) (xy 61.290986 -351.237893) (xy 61.344972 -351.230137)
			(xy 61.372242 -351.229676) (xy 62.235842 -351.229676) (xy 62.263112 -351.230089) (xy 62.317097 -351.237857)
			(xy 62.369426 -351.253227) (xy 62.419036 -351.275888) (xy 62.464916 -351.305378) (xy 62.506133 -351.341097)
			(xy 62.541847 -351.382317) (xy 62.571332 -351.428201) (xy 62.593988 -351.477813) (xy 62.609352 -351.530145)
			(xy 62.617114 -351.58413) (xy 62.617114 -351.638668) (xy 64.099939 -351.638668) (xy 64.099939 -351.584132)
			(xy 64.107701 -351.53015) (xy 64.123066 -351.477822) (xy 64.145721 -351.428214) (xy 64.175206 -351.382335)
			(xy 64.21092 -351.341119) (xy 64.252136 -351.305405) (xy 64.298016 -351.27592) (xy 64.347624 -351.253265)
			(xy 64.399952 -351.2379) (xy 64.453934 -351.230139) (xy 64.481202 -351.229676) (xy 65.344802 -351.229676)
			(xy 65.372074 -351.230087) (xy 65.426063 -351.237849) (xy 65.478397 -351.253216) (xy 65.528012 -351.275875)
			(xy 65.573897 -351.305364) (xy 65.615119 -351.341083) (xy 65.650837 -351.382304) (xy 65.680326 -351.42819)
			(xy 65.702984 -351.477805) (xy 65.718351 -351.530139) (xy 65.726113 -351.584128) (xy 65.726113 -351.638665)
			(xy 67.208962 -351.638665) (xy 67.208962 -351.584135) (xy 67.216722 -351.53016) (xy 67.232084 -351.477839)
			(xy 67.254735 -351.428236) (xy 67.284215 -351.382362) (xy 67.319922 -351.341149) (xy 67.361131 -351.305437)
			(xy 67.407003 -351.275953) (xy 67.456603 -351.253297) (xy 67.508923 -351.23793) (xy 67.562897 -351.230165)
			(xy 67.590162 -351.229676) (xy 68.453762 -351.229676) (xy 68.481037 -351.230061) (xy 68.535034 -351.23782)
			(xy 68.587376 -351.253184) (xy 68.636999 -351.275842) (xy 68.682892 -351.305331) (xy 68.724121 -351.341052)
			(xy 68.759846 -351.382277) (xy 68.78934 -351.428167) (xy 68.812003 -351.477788) (xy 68.827372 -351.530129)
			(xy 68.835136 -351.584125) (xy 68.835136 -351.638669) (xy 70.317839 -351.638669) (xy 70.317839 -351.584131)
			(xy 70.325601 -351.530147) (xy 70.340967 -351.477818) (xy 70.363624 -351.428208) (xy 70.393111 -351.382328)
			(xy 70.428827 -351.341112) (xy 70.470046 -351.305398) (xy 70.515928 -351.275914) (xy 70.565539 -351.25326)
			(xy 70.617869 -351.237897) (xy 70.671853 -351.230138) (xy 70.699122 -351.229676) (xy 71.562722 -351.229676)
			(xy 71.589993 -351.230088) (xy 71.64398 -351.237853) (xy 71.696312 -351.253222) (xy 71.745924 -351.275881)
			(xy 71.791807 -351.305371) (xy 71.833026 -351.34109) (xy 71.868742 -351.382311) (xy 71.898229 -351.428195)
			(xy 71.920886 -351.477809) (xy 71.936252 -351.530142) (xy 71.944014 -351.584129) (xy 71.944014 -351.638666)
			(xy 73.426862 -351.638666) (xy 73.426862 -351.584134) (xy 73.434623 -351.530158) (xy 73.449986 -351.477835)
			(xy 73.472638 -351.428231) (xy 73.50212 -351.382355) (xy 73.537829 -351.341142) (xy 73.579041 -351.30543)
			(xy 73.624915 -351.275947) (xy 73.674518 -351.253292) (xy 73.72684 -351.237927) (xy 73.780816 -351.230164)
			(xy 73.808082 -351.229676) (xy 74.671682 -351.229676) (xy 74.698957 -351.230062) (xy 74.752951 -351.237823)
			(xy 74.805291 -351.253189) (xy 74.854911 -351.275848) (xy 74.900802 -351.305338) (xy 74.942028 -351.341059)
			(xy 74.977751 -351.382284) (xy 75.007243 -351.428173) (xy 75.029904 -351.477792) (xy 75.045273 -351.530132)
			(xy 75.053036 -351.584125) (xy 75.053036 -351.63867) (xy 76.53574 -351.63867) (xy 76.53574 -351.58413)
			(xy 76.543502 -351.530145) (xy 76.558869 -351.477814) (xy 76.581527 -351.428203) (xy 76.611016 -351.382322)
			(xy 76.646734 -351.341105) (xy 76.687955 -351.305391) (xy 76.73384 -351.275907) (xy 76.783453 -351.253254)
			(xy 76.835786 -351.237893) (xy 76.889772 -351.230137) (xy 76.917042 -351.229676) (xy 77.780642 -351.229676)
			(xy 77.807912 -351.230089) (xy 77.861897 -351.237857) (xy 77.914226 -351.253227) (xy 77.963836 -351.275888)
			(xy 78.009716 -351.305378) (xy 78.050933 -351.341097) (xy 78.086647 -351.382317) (xy 78.116132 -351.428201)
			(xy 78.138788 -351.477813) (xy 78.154152 -351.530145) (xy 78.161914 -351.58413) (xy 78.161914 -351.638668)
			(xy 79.644739 -351.638668) (xy 79.644739 -351.584132) (xy 79.652501 -351.53015) (xy 79.667866 -351.477822)
			(xy 79.690521 -351.428214) (xy 79.720006 -351.382335) (xy 79.75572 -351.341119) (xy 79.796936 -351.305405)
			(xy 79.842816 -351.27592) (xy 79.892424 -351.253265) (xy 79.944752 -351.2379) (xy 79.998734 -351.230139)
			(xy 80.026002 -351.229676) (xy 80.889602 -351.229676) (xy 80.916874 -351.230087) (xy 80.970863 -351.237849)
			(xy 81.023197 -351.253216) (xy 81.072812 -351.275875) (xy 81.118697 -351.305364) (xy 81.159919 -351.341083)
			(xy 81.195637 -351.382304) (xy 81.225126 -351.42819) (xy 81.247784 -351.477805) (xy 81.263151 -351.530139)
			(xy 81.270913 -351.584128) (xy 81.270913 -351.638665) (xy 82.753762 -351.638665) (xy 82.753762 -351.584135)
			(xy 82.761522 -351.53016) (xy 82.776884 -351.477839) (xy 82.799535 -351.428236) (xy 82.829015 -351.382362)
			(xy 82.864722 -351.341149) (xy 82.905931 -351.305437) (xy 82.951803 -351.275953) (xy 83.001403 -351.253297)
			(xy 83.053723 -351.23793) (xy 83.107697 -351.230165) (xy 83.134962 -351.229676) (xy 83.998562 -351.229676)
			(xy 84.025837 -351.230061) (xy 84.079834 -351.23782) (xy 84.132176 -351.253184) (xy 84.181799 -351.275842)
			(xy 84.227692 -351.305331) (xy 84.268921 -351.341052) (xy 84.304646 -351.382277) (xy 84.33414 -351.428167)
			(xy 84.356803 -351.477788) (xy 84.372172 -351.530129) (xy 84.379936 -351.584125) (xy 84.379936 -351.638669)
			(xy 85.862639 -351.638669) (xy 85.862639 -351.584131) (xy 85.870401 -351.530147) (xy 85.885767 -351.477818)
			(xy 85.908424 -351.428208) (xy 85.937911 -351.382328) (xy 85.973627 -351.341112) (xy 86.014846 -351.305398)
			(xy 86.060728 -351.275914) (xy 86.110339 -351.25326) (xy 86.162669 -351.237897) (xy 86.216653 -351.230138)
			(xy 86.243922 -351.229676) (xy 87.107522 -351.229676) (xy 87.134793 -351.230088) (xy 87.18878 -351.237853)
			(xy 87.241112 -351.253222) (xy 87.290724 -351.275881) (xy 87.336607 -351.305371) (xy 87.377826 -351.34109)
			(xy 87.413542 -351.382311) (xy 87.443029 -351.428195) (xy 87.465686 -351.477809) (xy 87.481052 -351.530142)
			(xy 87.488814 -351.584129) (xy 87.488814 -351.638666) (xy 88.971662 -351.638666) (xy 88.971662 -351.584134)
			(xy 88.979423 -351.530158) (xy 88.994786 -351.477835) (xy 89.017438 -351.428231) (xy 89.04692 -351.382355)
			(xy 89.082629 -351.341142) (xy 89.123841 -351.30543) (xy 89.169715 -351.275947) (xy 89.219318 -351.253292)
			(xy 89.27164 -351.237927) (xy 89.325616 -351.230164) (xy 89.352882 -351.229676) (xy 90.216482 -351.229676)
			(xy 90.243757 -351.230062) (xy 90.297751 -351.237823) (xy 90.350091 -351.253189) (xy 90.399711 -351.275848)
			(xy 90.445602 -351.305338) (xy 90.486828 -351.341059) (xy 90.522551 -351.382284) (xy 90.552043 -351.428173)
			(xy 90.574704 -351.477792) (xy 90.590073 -351.530132) (xy 90.597836 -351.584125) (xy 90.597836 -351.63867)
			(xy 92.08054 -351.63867) (xy 92.08054 -351.58413) (xy 92.088302 -351.530145) (xy 92.103669 -351.477814)
			(xy 92.126327 -351.428203) (xy 92.155816 -351.382322) (xy 92.191534 -351.341105) (xy 92.232755 -351.305391)
			(xy 92.27864 -351.275907) (xy 92.328253 -351.253254) (xy 92.380586 -351.237893) (xy 92.434572 -351.230137)
			(xy 92.461842 -351.229676) (xy 93.325442 -351.229676) (xy 93.352712 -351.230089) (xy 93.406697 -351.237857)
			(xy 93.459026 -351.253227) (xy 93.508636 -351.275888) (xy 93.554516 -351.305378) (xy 93.595733 -351.341097)
			(xy 93.631447 -351.382317) (xy 93.660932 -351.428201) (xy 93.683588 -351.477813) (xy 93.698952 -351.530145)
			(xy 93.706714 -351.58413) (xy 93.706714 -351.638669) (xy 111.480839 -351.638669) (xy 111.480839 -351.584131)
			(xy 111.488601 -351.530149) (xy 111.503966 -351.477821) (xy 111.526622 -351.428212) (xy 111.556107 -351.382333)
			(xy 111.591822 -351.341117) (xy 111.633039 -351.305403) (xy 111.678919 -351.275918) (xy 111.728529 -351.253263)
			(xy 111.780857 -351.237899) (xy 111.834839 -351.230139) (xy 111.862108 -351.229676) (xy 112.725708 -351.229676)
			(xy 112.75298 -351.230087) (xy 112.806968 -351.23785) (xy 112.859302 -351.253218) (xy 112.908916 -351.275877)
			(xy 112.9548 -351.305366) (xy 112.996021 -351.341085) (xy 113.031739 -351.382306) (xy 113.061227 -351.428191)
			(xy 113.083885 -351.477806) (xy 113.099251 -351.53014) (xy 113.107014 -351.584128) (xy 113.107014 -351.638665)
			(xy 114.589862 -351.638665) (xy 114.589862 -351.584135) (xy 114.597622 -351.530159) (xy 114.612984 -351.477838)
			(xy 114.635636 -351.428234) (xy 114.665116 -351.38236) (xy 114.700824 -351.341147) (xy 114.742034 -351.305435)
			(xy 114.787906 -351.275951) (xy 114.837508 -351.253296) (xy 114.889828 -351.237929) (xy 114.943803 -351.230165)
			(xy 114.971068 -351.229676) (xy 115.834668 -351.229676) (xy 115.861943 -351.230061) (xy 115.915939 -351.237821)
			(xy 115.968281 -351.253186) (xy 116.017903 -351.275844) (xy 116.063795 -351.305333) (xy 116.105023 -351.341054)
			(xy 116.140747 -351.382279) (xy 116.170241 -351.428169) (xy 116.192903 -351.477789) (xy 116.208273 -351.53013)
			(xy 116.216036 -351.584125) (xy 116.216036 -351.63867) (xy 117.698739 -351.63867) (xy 117.698739 -351.58413)
			(xy 117.706502 -351.530146) (xy 117.721868 -351.477817) (xy 117.744525 -351.428207) (xy 117.774012 -351.382326)
			(xy 117.809729 -351.341109) (xy 117.850949 -351.305396) (xy 117.896831 -351.275912) (xy 117.946443 -351.253258)
			(xy 117.998774 -351.237896) (xy 118.052758 -351.230137) (xy 118.080028 -351.229676) (xy 118.943628 -351.229676)
			(xy 118.970899 -351.230088) (xy 119.024885 -351.237854) (xy 119.077216 -351.253223) (xy 119.126828 -351.275883)
			(xy 119.17271 -351.305373) (xy 119.213928 -351.341092) (xy 119.249644 -351.382313) (xy 119.27913 -351.428197)
			(xy 119.301786 -351.47781) (xy 119.317152 -351.530143) (xy 119.324914 -351.584129) (xy 119.324914 -351.638666)
			(xy 120.807762 -351.638666) (xy 120.807762 -351.584134) (xy 120.815523 -351.530157) (xy 120.830886 -351.477833)
			(xy 120.853539 -351.428229) (xy 120.883021 -351.382353) (xy 120.918731 -351.34114) (xy 120.959943 -351.305428)
			(xy 121.005818 -351.275945) (xy 121.055422 -351.25329) (xy 121.107745 -351.237925) (xy 121.161722 -351.230163)
			(xy 121.188988 -351.229676) (xy 122.052588 -351.229676) (xy 122.079862 -351.230063) (xy 122.133856 -351.237824)
			(xy 122.186195 -351.253191) (xy 122.235815 -351.27585) (xy 122.281704 -351.30534) (xy 122.32293 -351.341061)
			(xy 122.358652 -351.382286) (xy 122.388144 -351.428175) (xy 122.410805 -351.477794) (xy 122.426173 -351.530132)
			(xy 122.433936 -351.584126) (xy 122.433936 -351.63867) (xy 123.91664 -351.63867) (xy 123.91664 -351.58413)
			(xy 123.924402 -351.530144) (xy 123.939769 -351.477812) (xy 123.962428 -351.428201) (xy 123.991917 -351.38232)
			(xy 124.027636 -351.341102) (xy 124.068858 -351.305388) (xy 124.114743 -351.275905) (xy 124.164358 -351.253253)
			(xy 124.216691 -351.237892) (xy 124.270677 -351.230136) (xy 124.297948 -351.229676) (xy 125.161548 -351.229676)
			(xy 125.188818 -351.23009) (xy 125.242802 -351.237858) (xy 125.295131 -351.253229) (xy 125.34474 -351.27589)
			(xy 125.390619 -351.30538) (xy 125.431835 -351.341099) (xy 125.467549 -351.382319) (xy 125.497033 -351.428203)
			(xy 125.519688 -351.477814) (xy 125.535052 -351.530145) (xy 125.542814 -351.58413) (xy 125.542814 -351.638669)
			(xy 127.025639 -351.638669) (xy 127.025639 -351.584131) (xy 127.033401 -351.530149) (xy 127.048766 -351.477821)
			(xy 127.071422 -351.428212) (xy 127.100907 -351.382333) (xy 127.136622 -351.341117) (xy 127.177839 -351.305403)
			(xy 127.223719 -351.275918) (xy 127.273329 -351.253263) (xy 127.325657 -351.237899) (xy 127.379639 -351.230139)
			(xy 127.406908 -351.229676) (xy 128.270508 -351.229676) (xy 128.29778 -351.230087) (xy 128.351768 -351.23785)
			(xy 128.404102 -351.253218) (xy 128.453716 -351.275877) (xy 128.4996 -351.305366) (xy 128.540821 -351.341085)
			(xy 128.576539 -351.382306) (xy 128.606027 -351.428191) (xy 128.628685 -351.477806) (xy 128.644051 -351.53014)
			(xy 128.651814 -351.584128) (xy 128.651814 -351.638665) (xy 130.134662 -351.638665) (xy 130.134662 -351.584135)
			(xy 130.142422 -351.530159) (xy 130.157784 -351.477838) (xy 130.180436 -351.428234) (xy 130.209916 -351.38236)
			(xy 130.245624 -351.341147) (xy 130.286834 -351.305435) (xy 130.332706 -351.275951) (xy 130.382308 -351.253296)
			(xy 130.434628 -351.237929) (xy 130.488603 -351.230165) (xy 130.515868 -351.229676) (xy 131.379468 -351.229676)
			(xy 131.406743 -351.230061) (xy 131.460739 -351.237821) (xy 131.513081 -351.253186) (xy 131.562703 -351.275844)
			(xy 131.608595 -351.305333) (xy 131.649823 -351.341054) (xy 131.685547 -351.382279) (xy 131.715041 -351.428169)
			(xy 131.737703 -351.477789) (xy 131.753073 -351.53013) (xy 131.760836 -351.584125) (xy 131.760836 -351.63867)
			(xy 133.243539 -351.63867) (xy 133.243539 -351.58413) (xy 133.251302 -351.530146) (xy 133.266668 -351.477817)
			(xy 133.289325 -351.428207) (xy 133.318812 -351.382326) (xy 133.354529 -351.341109) (xy 133.395749 -351.305396)
			(xy 133.441631 -351.275912) (xy 133.491243 -351.253258) (xy 133.543574 -351.237896) (xy 133.597558 -351.230137)
			(xy 133.624828 -351.229676) (xy 134.488428 -351.229676) (xy 134.515699 -351.230088) (xy 134.569685 -351.237854)
			(xy 134.622016 -351.253223) (xy 134.671628 -351.275883) (xy 134.71751 -351.305373) (xy 134.758728 -351.341092)
			(xy 134.794444 -351.382313) (xy 134.82393 -351.428197) (xy 134.846586 -351.47781) (xy 134.861952 -351.530143)
			(xy 134.869714 -351.584129) (xy 134.869714 -351.638666) (xy 136.352562 -351.638666) (xy 136.352562 -351.584134)
			(xy 136.360323 -351.530157) (xy 136.375686 -351.477833) (xy 136.398339 -351.428229) (xy 136.427821 -351.382353)
			(xy 136.463531 -351.34114) (xy 136.504743 -351.305428) (xy 136.550618 -351.275945) (xy 136.600222 -351.25329)
			(xy 136.652545 -351.237925) (xy 136.706522 -351.230163) (xy 136.733788 -351.229676) (xy 137.597388 -351.229676)
			(xy 137.624662 -351.230063) (xy 137.678656 -351.237824) (xy 137.730995 -351.253191) (xy 137.780615 -351.27585)
			(xy 137.826504 -351.30534) (xy 137.86773 -351.341061) (xy 137.903452 -351.382286) (xy 137.932944 -351.428175)
			(xy 137.955605 -351.477794) (xy 137.970973 -351.530132) (xy 137.978736 -351.584126) (xy 137.978736 -351.63867)
			(xy 139.46144 -351.63867) (xy 139.46144 -351.58413) (xy 139.469202 -351.530144) (xy 139.484569 -351.477812)
			(xy 139.507228 -351.428201) (xy 139.536717 -351.38232) (xy 139.572436 -351.341102) (xy 139.613658 -351.305388)
			(xy 139.659543 -351.275905) (xy 139.709158 -351.253253) (xy 139.761491 -351.237892) (xy 139.815477 -351.230136)
			(xy 139.842748 -351.229676) (xy 140.706348 -351.229676) (xy 140.733618 -351.23009) (xy 140.787602 -351.237858)
			(xy 140.839931 -351.253229) (xy 140.88954 -351.27589) (xy 140.935419 -351.30538) (xy 140.976635 -351.341099)
			(xy 141.012349 -351.382319) (xy 141.041833 -351.428203) (xy 141.064488 -351.477814) (xy 141.079852 -351.530145)
			(xy 141.087614 -351.58413) (xy 141.087614 -351.638669) (xy 142.570439 -351.638669) (xy 142.570439 -351.584131)
			(xy 142.578201 -351.530149) (xy 142.593566 -351.477821) (xy 142.616222 -351.428212) (xy 142.645707 -351.382333)
			(xy 142.681422 -351.341117) (xy 142.722639 -351.305403) (xy 142.768519 -351.275918) (xy 142.818129 -351.253263)
			(xy 142.870457 -351.237899) (xy 142.924439 -351.230139) (xy 142.951708 -351.229676) (xy 143.815308 -351.229676)
			(xy 143.84258 -351.230087) (xy 143.896568 -351.23785) (xy 143.948902 -351.253218) (xy 143.998516 -351.275877)
			(xy 144.0444 -351.305366) (xy 144.085621 -351.341085) (xy 144.121339 -351.382306) (xy 144.150827 -351.428191)
			(xy 144.173485 -351.477806) (xy 144.188851 -351.53014) (xy 144.196614 -351.584128) (xy 144.196614 -351.638669)
			(xy 161.804839 -351.638669) (xy 161.804839 -351.584131) (xy 161.812601 -351.530149) (xy 161.827966 -351.47782)
			(xy 161.850623 -351.428211) (xy 161.880108 -351.382331) (xy 161.915824 -351.341115) (xy 161.957041 -351.305401)
			(xy 162.002922 -351.275917) (xy 162.052531 -351.253262) (xy 162.10486 -351.237899) (xy 162.158843 -351.230139)
			(xy 162.186112 -351.229676) (xy 163.049712 -351.229676) (xy 163.076984 -351.230087) (xy 163.130971 -351.237851)
			(xy 163.183304 -351.253219) (xy 163.232918 -351.275878) (xy 163.278802 -351.305367) (xy 163.320022 -351.341086)
			(xy 163.35574 -351.382308) (xy 163.385228 -351.428192) (xy 163.407885 -351.477807) (xy 163.423251 -351.530141)
			(xy 163.431014 -351.584128) (xy 163.431014 -351.638665) (xy 164.913862 -351.638665) (xy 164.913862 -351.584135)
			(xy 164.921622 -351.530159) (xy 164.936985 -351.477837) (xy 164.959637 -351.428233) (xy 164.989117 -351.382358)
			(xy 165.024826 -351.341146) (xy 165.066036 -351.305434) (xy 165.111909 -351.27595) (xy 165.16151 -351.253295)
			(xy 165.213831 -351.237928) (xy 165.267807 -351.230164) (xy 165.295072 -351.229676) (xy 166.158672 -351.229676)
			(xy 166.185947 -351.230062) (xy 166.239942 -351.237821) (xy 166.292284 -351.253187) (xy 166.341905 -351.275845)
			(xy 166.387797 -351.305335) (xy 166.429024 -351.341056) (xy 166.464748 -351.382281) (xy 166.494242 -351.42817)
			(xy 166.516903 -351.47779) (xy 166.532273 -351.53013) (xy 166.540036 -351.584125) (xy 166.540036 -351.63867)
			(xy 168.022739 -351.63867) (xy 168.022739 -351.58413) (xy 168.030502 -351.530146) (xy 168.045868 -351.477816)
			(xy 168.068526 -351.428206) (xy 168.098013 -351.382325) (xy 168.133731 -351.341108) (xy 168.174951 -351.305394)
			(xy 168.220834 -351.27591) (xy 168.270446 -351.253257) (xy 168.322777 -351.237895) (xy 168.376762 -351.230137)
			(xy 168.404032 -351.229676) (xy 169.267632 -351.229676) (xy 169.294903 -351.230089) (xy 169.348888 -351.237855)
			(xy 169.401219 -351.253224) (xy 169.45083 -351.275885) (xy 169.496712 -351.305374) (xy 169.537929 -351.341093)
			(xy 169.573645 -351.382314) (xy 169.603131 -351.428198) (xy 169.625787 -351.477811) (xy 169.641152 -351.530143)
			(xy 169.648914 -351.584129) (xy 169.648914 -351.638666) (xy 171.131762 -351.638666) (xy 171.131762 -351.584134)
			(xy 171.139523 -351.530156) (xy 171.154886 -351.477832) (xy 171.17754 -351.428228) (xy 171.207022 -351.382352)
			(xy 171.242733 -351.341138) (xy 171.283945 -351.305427) (xy 171.329821 -351.275944) (xy 171.379425 -351.253289)
			(xy 171.431748 -351.237925) (xy 171.485726 -351.230163) (xy 171.512992 -351.229676) (xy 172.376592 -351.229676)
			(xy 172.403866 -351.230063) (xy 172.457859 -351.237825) (xy 172.510198 -351.253192) (xy 172.559817 -351.275851)
			(xy 172.605706 -351.305342) (xy 172.646932 -351.341063) (xy 172.682653 -351.382287) (xy 172.712145 -351.428176)
			(xy 172.734805 -351.477794) (xy 172.750173 -351.530133) (xy 172.757936 -351.584126) (xy 172.757936 -351.638664)
			(xy 174.240762 -351.638664) (xy 174.240762 -351.584136) (xy 174.248522 -351.530162) (xy 174.263883 -351.477841)
			(xy 174.286534 -351.428239) (xy 174.316012 -351.382365) (xy 174.351719 -351.341153) (xy 174.392926 -351.305441)
			(xy 174.438797 -351.275957) (xy 174.488396 -351.2533) (xy 174.540715 -351.237932) (xy 174.594688 -351.230166)
			(xy 174.621952 -351.229676) (xy 175.485552 -351.229676) (xy 175.512828 -351.23006) (xy 175.566825 -351.237818)
			(xy 175.619169 -351.253181) (xy 175.668793 -351.275838) (xy 175.714687 -351.305328) (xy 175.755917 -351.341049)
			(xy 175.791644 -351.382274) (xy 175.821139 -351.428165) (xy 175.843802 -351.477786) (xy 175.859172 -351.530128)
			(xy 175.866936 -351.584124) (xy 175.866936 -351.638669) (xy 177.349639 -351.638669) (xy 177.349639 -351.584131)
			(xy 177.357401 -351.530149) (xy 177.372766 -351.47782) (xy 177.395423 -351.428211) (xy 177.424908 -351.382331)
			(xy 177.460624 -351.341115) (xy 177.501841 -351.305401) (xy 177.547722 -351.275917) (xy 177.597331 -351.253262)
			(xy 177.64966 -351.237899) (xy 177.703643 -351.230139) (xy 177.730912 -351.229676) (xy 178.594512 -351.229676)
			(xy 178.621784 -351.230087) (xy 178.675771 -351.237851) (xy 178.728104 -351.253219) (xy 178.777718 -351.275878)
			(xy 178.823602 -351.305367) (xy 178.864822 -351.341086) (xy 178.90054 -351.382308) (xy 178.930028 -351.428192)
			(xy 178.952685 -351.477807) (xy 178.968051 -351.530141) (xy 178.975814 -351.584128) (xy 178.975814 -351.638665)
			(xy 180.458662 -351.638665) (xy 180.458662 -351.584135) (xy 180.466422 -351.530159) (xy 180.481785 -351.477837)
			(xy 180.504437 -351.428233) (xy 180.533917 -351.382358) (xy 180.569626 -351.341146) (xy 180.610836 -351.305434)
			(xy 180.656709 -351.27595) (xy 180.70631 -351.253295) (xy 180.758631 -351.237928) (xy 180.812607 -351.230164)
			(xy 180.839872 -351.229676) (xy 181.703472 -351.229676) (xy 181.730747 -351.230062) (xy 181.784742 -351.237821)
			(xy 181.837084 -351.253187) (xy 181.886705 -351.275845) (xy 181.932597 -351.305335) (xy 181.973824 -351.341056)
			(xy 182.009548 -351.382281) (xy 182.039042 -351.42817) (xy 182.061703 -351.47779) (xy 182.077073 -351.53013)
			(xy 182.084836 -351.584125) (xy 182.084836 -351.63867) (xy 183.567539 -351.63867) (xy 183.567539 -351.58413)
			(xy 183.575302 -351.530146) (xy 183.590668 -351.477816) (xy 183.613326 -351.428206) (xy 183.642813 -351.382325)
			(xy 183.678531 -351.341108) (xy 183.719751 -351.305394) (xy 183.765634 -351.27591) (xy 183.815246 -351.253257)
			(xy 183.867577 -351.237895) (xy 183.921562 -351.230137) (xy 183.948832 -351.229676) (xy 184.812432 -351.229676)
			(xy 184.839703 -351.230089) (xy 184.893688 -351.237855) (xy 184.946019 -351.253224) (xy 184.99563 -351.275885)
			(xy 185.041512 -351.305374) (xy 185.082729 -351.341093) (xy 185.118445 -351.382314) (xy 185.147931 -351.428198)
			(xy 185.170587 -351.477811) (xy 185.185952 -351.530143) (xy 185.193714 -351.584129) (xy 185.193714 -351.638666)
			(xy 186.676562 -351.638666) (xy 186.676562 -351.584134) (xy 186.684323 -351.530156) (xy 186.699686 -351.477832)
			(xy 186.72234 -351.428228) (xy 186.751822 -351.382352) (xy 186.787533 -351.341138) (xy 186.828745 -351.305427)
			(xy 186.874621 -351.275944) (xy 186.924225 -351.253289) (xy 186.976548 -351.237925) (xy 187.030526 -351.230163)
			(xy 187.057792 -351.229676) (xy 187.921392 -351.229676) (xy 187.948666 -351.230063) (xy 188.002659 -351.237825)
			(xy 188.054998 -351.253192) (xy 188.104617 -351.275851) (xy 188.150506 -351.305342) (xy 188.191732 -351.341063)
			(xy 188.227453 -351.382287) (xy 188.256945 -351.428176) (xy 188.279605 -351.477794) (xy 188.294973 -351.530133)
			(xy 188.302736 -351.584126) (xy 188.302736 -351.638664) (xy 189.785562 -351.638664) (xy 189.785562 -351.584136)
			(xy 189.793322 -351.530162) (xy 189.808683 -351.477841) (xy 189.831334 -351.428239) (xy 189.860812 -351.382365)
			(xy 189.896519 -351.341153) (xy 189.937726 -351.305441) (xy 189.983597 -351.275957) (xy 190.033196 -351.2533)
			(xy 190.085515 -351.237932) (xy 190.139488 -351.230166) (xy 190.166752 -351.229676) (xy 191.030352 -351.229676)
			(xy 191.057628 -351.23006) (xy 191.111625 -351.237818) (xy 191.163969 -351.253181) (xy 191.213593 -351.275838)
			(xy 191.259487 -351.305328) (xy 191.300717 -351.341049) (xy 191.336444 -351.382274) (xy 191.365939 -351.428165)
			(xy 191.388602 -351.477786) (xy 191.403972 -351.530128) (xy 191.411736 -351.584124) (xy 191.411736 -351.638669)
			(xy 192.894439 -351.638669) (xy 192.894439 -351.584131) (xy 192.902201 -351.530149) (xy 192.917566 -351.47782)
			(xy 192.940223 -351.428211) (xy 192.969708 -351.382331) (xy 193.005424 -351.341115) (xy 193.046641 -351.305401)
			(xy 193.092522 -351.275917) (xy 193.142131 -351.253262) (xy 193.19446 -351.237899) (xy 193.248443 -351.230139)
			(xy 193.275712 -351.229676) (xy 194.139312 -351.229676) (xy 194.166584 -351.230087) (xy 194.220571 -351.237851)
			(xy 194.272904 -351.253219) (xy 194.322518 -351.275878) (xy 194.368402 -351.305367) (xy 194.409622 -351.341086)
			(xy 194.44534 -351.382308) (xy 194.474828 -351.428192) (xy 194.497485 -351.477807) (xy 194.512851 -351.530141)
			(xy 194.520614 -351.584128) (xy 194.520614 -351.638668) (xy 267.515839 -351.638668) (xy 267.515839 -351.584132)
			(xy 267.523601 -351.53015) (xy 267.538966 -351.477822) (xy 267.561621 -351.428214) (xy 267.591106 -351.382335)
			(xy 267.62682 -351.341119) (xy 267.668036 -351.305405) (xy 267.713916 -351.27592) (xy 267.763524 -351.253265)
			(xy 267.815852 -351.2379) (xy 267.869834 -351.230139) (xy 267.897102 -351.229676) (xy 268.760702 -351.229676)
			(xy 268.787974 -351.230087) (xy 268.841963 -351.237849) (xy 268.894297 -351.253216) (xy 268.943912 -351.275875)
			(xy 268.989797 -351.305364) (xy 269.031019 -351.341083) (xy 269.066737 -351.382304) (xy 269.096226 -351.42819)
			(xy 269.118884 -351.477805) (xy 269.134251 -351.530139) (xy 269.142013 -351.584128) (xy 269.142013 -351.638665)
			(xy 270.624862 -351.638665) (xy 270.624862 -351.584135) (xy 270.632622 -351.53016) (xy 270.647984 -351.477839)
			(xy 270.670635 -351.428236) (xy 270.700115 -351.382362) (xy 270.735822 -351.341149) (xy 270.777031 -351.305437)
			(xy 270.822903 -351.275953) (xy 270.872503 -351.253297) (xy 270.924823 -351.23793) (xy 270.978797 -351.230165)
			(xy 271.006062 -351.229676) (xy 271.869662 -351.229676) (xy 271.896937 -351.230061) (xy 271.950934 -351.23782)
			(xy 272.003276 -351.253184) (xy 272.052899 -351.275842) (xy 272.098792 -351.305331) (xy 272.140021 -351.341052)
			(xy 272.175746 -351.382277) (xy 272.20524 -351.428167) (xy 272.227903 -351.477788) (xy 272.243272 -351.530129)
			(xy 272.251036 -351.584125) (xy 272.251036 -351.638669) (xy 273.733739 -351.638669) (xy 273.733739 -351.584131)
			(xy 273.741501 -351.530147) (xy 273.756867 -351.477818) (xy 273.779524 -351.428208) (xy 273.809011 -351.382328)
			(xy 273.844727 -351.341112) (xy 273.885946 -351.305398) (xy 273.931828 -351.275914) (xy 273.981439 -351.25326)
			(xy 274.033769 -351.237897) (xy 274.087753 -351.230138) (xy 274.115022 -351.229676) (xy 274.978622 -351.229676)
			(xy 275.005893 -351.230088) (xy 275.05988 -351.237853) (xy 275.112212 -351.253222) (xy 275.161824 -351.275881)
			(xy 275.207707 -351.305371) (xy 275.248926 -351.34109) (xy 275.284642 -351.382311) (xy 275.314129 -351.428195)
			(xy 275.336786 -351.477809) (xy 275.352152 -351.530142) (xy 275.359914 -351.584129) (xy 275.359914 -351.638666)
			(xy 276.842762 -351.638666) (xy 276.842762 -351.584134) (xy 276.850523 -351.530158) (xy 276.865886 -351.477835)
			(xy 276.888538 -351.428231) (xy 276.91802 -351.382355) (xy 276.953729 -351.341142) (xy 276.994941 -351.30543)
			(xy 277.040815 -351.275947) (xy 277.090418 -351.253292) (xy 277.14274 -351.237927) (xy 277.196716 -351.230164)
			(xy 277.223982 -351.229676) (xy 278.087582 -351.229676) (xy 278.114857 -351.230062) (xy 278.168851 -351.237823)
			(xy 278.221191 -351.253189) (xy 278.270811 -351.275848) (xy 278.316702 -351.305338) (xy 278.357928 -351.341059)
			(xy 278.393651 -351.382284) (xy 278.423143 -351.428173) (xy 278.445804 -351.477792) (xy 278.461173 -351.530132)
			(xy 278.468936 -351.584125) (xy 278.468936 -351.63867) (xy 279.95164 -351.63867) (xy 279.95164 -351.58413)
			(xy 279.959402 -351.530145) (xy 279.974769 -351.477814) (xy 279.997427 -351.428203) (xy 280.026916 -351.382322)
			(xy 280.062634 -351.341105) (xy 280.103855 -351.305391) (xy 280.14974 -351.275907) (xy 280.199353 -351.253254)
			(xy 280.251686 -351.237893) (xy 280.305672 -351.230137) (xy 280.332942 -351.229676) (xy 281.196542 -351.229676)
			(xy 281.223812 -351.230089) (xy 281.277797 -351.237857) (xy 281.330126 -351.253227) (xy 281.379736 -351.275888)
			(xy 281.425616 -351.305378) (xy 281.466833 -351.341097) (xy 281.502547 -351.382317) (xy 281.532032 -351.428201)
			(xy 281.554688 -351.477813) (xy 281.570052 -351.530145) (xy 281.577814 -351.58413) (xy 281.577814 -351.638668)
			(xy 283.060639 -351.638668) (xy 283.060639 -351.584132) (xy 283.068401 -351.53015) (xy 283.083766 -351.477822)
			(xy 283.106421 -351.428214) (xy 283.135906 -351.382335) (xy 283.17162 -351.341119) (xy 283.212836 -351.305405)
			(xy 283.258716 -351.27592) (xy 283.308324 -351.253265) (xy 283.360652 -351.2379) (xy 283.414634 -351.230139)
			(xy 283.441902 -351.229676) (xy 284.305502 -351.229676) (xy 284.332774 -351.230087) (xy 284.386763 -351.237849)
			(xy 284.439097 -351.253216) (xy 284.488712 -351.275875) (xy 284.534597 -351.305364) (xy 284.575819 -351.341083)
			(xy 284.611537 -351.382304) (xy 284.641026 -351.42819) (xy 284.663684 -351.477805) (xy 284.679051 -351.530139)
			(xy 284.686813 -351.584128) (xy 284.686813 -351.638665) (xy 286.169662 -351.638665) (xy 286.169662 -351.584135)
			(xy 286.177422 -351.53016) (xy 286.192784 -351.477839) (xy 286.215435 -351.428236) (xy 286.244915 -351.382362)
			(xy 286.280622 -351.341149) (xy 286.321831 -351.305437) (xy 286.367703 -351.275953) (xy 286.417303 -351.253297)
			(xy 286.469623 -351.23793) (xy 286.523597 -351.230165) (xy 286.550862 -351.229676) (xy 287.414462 -351.229676)
			(xy 287.441737 -351.230061) (xy 287.495734 -351.23782) (xy 287.548076 -351.253184) (xy 287.597699 -351.275842)
			(xy 287.643592 -351.305331) (xy 287.684821 -351.341052) (xy 287.720546 -351.382277) (xy 287.75004 -351.428167)
			(xy 287.772703 -351.477788) (xy 287.788072 -351.530129) (xy 287.795836 -351.584125) (xy 287.795836 -351.638669)
			(xy 289.278539 -351.638669) (xy 289.278539 -351.584131) (xy 289.286301 -351.530147) (xy 289.301667 -351.477818)
			(xy 289.324324 -351.428208) (xy 289.353811 -351.382328) (xy 289.389527 -351.341112) (xy 289.430746 -351.305398)
			(xy 289.476628 -351.275914) (xy 289.526239 -351.25326) (xy 289.578569 -351.237897) (xy 289.632553 -351.230138)
			(xy 289.659822 -351.229676) (xy 290.523422 -351.229676) (xy 290.550693 -351.230088) (xy 290.60468 -351.237853)
			(xy 290.657012 -351.253222) (xy 290.706624 -351.275881) (xy 290.752507 -351.305371) (xy 290.793726 -351.34109)
			(xy 290.829442 -351.382311) (xy 290.858929 -351.428195) (xy 290.881586 -351.477809) (xy 290.896952 -351.530142)
			(xy 290.904714 -351.584129) (xy 290.904714 -351.638666) (xy 292.387562 -351.638666) (xy 292.387562 -351.584134)
			(xy 292.395323 -351.530158) (xy 292.410686 -351.477835) (xy 292.433338 -351.428231) (xy 292.46282 -351.382355)
			(xy 292.498529 -351.341142) (xy 292.539741 -351.30543) (xy 292.585615 -351.275947) (xy 292.635218 -351.253292)
			(xy 292.68754 -351.237927) (xy 292.741516 -351.230164) (xy 292.768782 -351.229676) (xy 293.632382 -351.229676)
			(xy 293.659657 -351.230062) (xy 293.713651 -351.237823) (xy 293.765991 -351.253189) (xy 293.815611 -351.275848)
			(xy 293.861502 -351.305338) (xy 293.902728 -351.341059) (xy 293.938451 -351.382284) (xy 293.967943 -351.428173)
			(xy 293.990604 -351.477792) (xy 294.005973 -351.530132) (xy 294.013736 -351.584125) (xy 294.013736 -351.63867)
			(xy 295.49644 -351.63867) (xy 295.49644 -351.58413) (xy 295.504202 -351.530145) (xy 295.519569 -351.477814)
			(xy 295.542227 -351.428203) (xy 295.571716 -351.382322) (xy 295.607434 -351.341105) (xy 295.648655 -351.305391)
			(xy 295.69454 -351.275907) (xy 295.744153 -351.253254) (xy 295.796486 -351.237893) (xy 295.850472 -351.230137)
			(xy 295.877742 -351.229676) (xy 296.741342 -351.229676) (xy 296.768612 -351.230089) (xy 296.822597 -351.237857)
			(xy 296.874926 -351.253227) (xy 296.924536 -351.275888) (xy 296.970416 -351.305378) (xy 297.011633 -351.341097)
			(xy 297.047347 -351.382317) (xy 297.076832 -351.428201) (xy 297.099488 -351.477813) (xy 297.114852 -351.530145)
			(xy 297.122614 -351.58413) (xy 297.122614 -351.638668) (xy 298.605439 -351.638668) (xy 298.605439 -351.584132)
			(xy 298.613201 -351.53015) (xy 298.628566 -351.477822) (xy 298.651221 -351.428214) (xy 298.680706 -351.382335)
			(xy 298.71642 -351.341119) (xy 298.757636 -351.305405) (xy 298.803516 -351.27592) (xy 298.853124 -351.253265)
			(xy 298.905452 -351.2379) (xy 298.959434 -351.230139) (xy 298.986702 -351.229676) (xy 299.850302 -351.229676)
			(xy 299.877574 -351.230087) (xy 299.931563 -351.237849) (xy 299.983897 -351.253216) (xy 300.033512 -351.275875)
			(xy 300.079397 -351.305364) (xy 300.120619 -351.341083) (xy 300.156337 -351.382304) (xy 300.185826 -351.42819)
			(xy 300.208484 -351.477805) (xy 300.223851 -351.530139) (xy 300.231613 -351.584128) (xy 300.231613 -351.638668)
			(xy 312.121539 -351.638668) (xy 312.121539 -351.584132) (xy 312.129301 -351.53015) (xy 312.144666 -351.477822)
			(xy 312.167321 -351.428213) (xy 312.196807 -351.382334) (xy 312.232521 -351.341118) (xy 312.273737 -351.305404)
			(xy 312.319617 -351.27592) (xy 312.369226 -351.253264) (xy 312.421554 -351.2379) (xy 312.475536 -351.230139)
			(xy 312.502804 -351.229676) (xy 313.366404 -351.229676) (xy 313.393676 -351.230087) (xy 313.447664 -351.23785)
			(xy 313.499999 -351.253217) (xy 313.549613 -351.275876) (xy 313.595498 -351.305365) (xy 313.63672 -351.341083)
			(xy 313.672438 -351.382305) (xy 313.701926 -351.42819) (xy 313.724584 -351.477805) (xy 313.739951 -351.530139)
			(xy 313.747713 -351.584128) (xy 313.747713 -351.638665) (xy 315.230562 -351.638665) (xy 315.230562 -351.584135)
			(xy 315.238322 -351.53016) (xy 315.253684 -351.477838) (xy 315.276335 -351.428236) (xy 315.305815 -351.382361)
			(xy 315.341523 -351.341148) (xy 315.382732 -351.305437) (xy 315.428604 -351.275953) (xy 315.478205 -351.253297)
			(xy 315.530525 -351.23793) (xy 315.584499 -351.230165) (xy 315.611764 -351.229676) (xy 316.475364 -351.229676)
			(xy 316.502639 -351.230061) (xy 316.556636 -351.23782) (xy 316.608978 -351.253185) (xy 316.6586 -351.275842)
			(xy 316.704493 -351.305332) (xy 316.745722 -351.341053) (xy 316.781446 -351.382278) (xy 316.81094 -351.428168)
			(xy 316.833603 -351.477788) (xy 316.848972 -351.530129) (xy 316.856736 -351.584125) (xy 316.856736 -351.638669)
			(xy 318.339439 -351.638669) (xy 318.339439 -351.584131) (xy 318.347201 -351.530147) (xy 318.362567 -351.477818)
			(xy 318.385224 -351.428208) (xy 318.414711 -351.382328) (xy 318.450428 -351.341111) (xy 318.491647 -351.305397)
			(xy 318.537529 -351.275913) (xy 318.58714 -351.253259) (xy 318.63947 -351.237896) (xy 318.693455 -351.230138)
			(xy 318.720724 -351.229676) (xy 319.584324 -351.229676) (xy 319.611595 -351.230088) (xy 319.665581 -351.237853)
			(xy 319.717913 -351.253222) (xy 319.767525 -351.275882) (xy 319.813408 -351.305372) (xy 319.854627 -351.34109)
			(xy 319.890343 -351.382312) (xy 319.919829 -351.428196) (xy 319.942486 -351.477809) (xy 319.957852 -351.530142)
			(xy 319.965614 -351.584129) (xy 319.965614 -351.638666) (xy 321.448462 -351.638666) (xy 321.448462 -351.584134)
			(xy 321.456223 -351.530157) (xy 321.471586 -351.477834) (xy 321.494239 -351.42823) (xy 321.52372 -351.382354)
			(xy 321.55943 -351.341141) (xy 321.600642 -351.30543) (xy 321.646516 -351.275946) (xy 321.696119 -351.253291)
			(xy 321.748442 -351.237926) (xy 321.802418 -351.230163) (xy 321.829684 -351.229676) (xy 322.693284 -351.229676)
			(xy 322.720558 -351.230062) (xy 322.774552 -351.237824) (xy 322.826892 -351.25319) (xy 322.876512 -351.275849)
			(xy 322.922403 -351.305339) (xy 322.963629 -351.34106) (xy 322.999351 -351.382285) (xy 323.028843 -351.428174)
			(xy 323.051504 -351.477793) (xy 323.066873 -351.530132) (xy 323.074636 -351.584126) (xy 323.074636 -351.63867)
			(xy 324.55734 -351.63867) (xy 324.55734 -351.58413) (xy 324.565102 -351.530144) (xy 324.580469 -351.477813)
			(xy 324.603128 -351.428202) (xy 324.632616 -351.382321) (xy 324.668335 -351.341104) (xy 324.709556 -351.30539)
			(xy 324.755441 -351.275906) (xy 324.805055 -351.253254) (xy 324.857387 -351.237893) (xy 324.911374 -351.230136)
			(xy 324.938644 -351.229676) (xy 325.802244 -351.229676) (xy 325.829514 -351.23009) (xy 325.883498 -351.237857)
			(xy 325.935828 -351.253228) (xy 325.985437 -351.275889) (xy 326.031317 -351.305379) (xy 326.072534 -351.341097)
			(xy 326.108248 -351.382318) (xy 326.137732 -351.428201) (xy 326.160388 -351.477814) (xy 326.175752 -351.530145)
			(xy 326.183514 -351.58413) (xy 326.183514 -351.638668) (xy 327.666339 -351.638668) (xy 327.666339 -351.584132)
			(xy 327.674101 -351.53015) (xy 327.689466 -351.477822) (xy 327.712121 -351.428213) (xy 327.741607 -351.382334)
			(xy 327.777321 -351.341118) (xy 327.818537 -351.305404) (xy 327.864417 -351.27592) (xy 327.914026 -351.253264)
			(xy 327.966354 -351.2379) (xy 328.020336 -351.230139) (xy 328.047604 -351.229676) (xy 328.911204 -351.229676)
			(xy 328.938476 -351.230087) (xy 328.992464 -351.23785) (xy 329.044799 -351.253217) (xy 329.094413 -351.275876)
			(xy 329.140298 -351.305365) (xy 329.18152 -351.341083) (xy 329.217238 -351.382305) (xy 329.246726 -351.42819)
			(xy 329.269384 -351.477805) (xy 329.284751 -351.530139) (xy 329.292513 -351.584128) (xy 329.292513 -351.638665)
			(xy 330.775362 -351.638665) (xy 330.775362 -351.584135) (xy 330.783122 -351.53016) (xy 330.798484 -351.477838)
			(xy 330.821135 -351.428236) (xy 330.850615 -351.382361) (xy 330.886323 -351.341148) (xy 330.927532 -351.305437)
			(xy 330.973404 -351.275953) (xy 331.023005 -351.253297) (xy 331.075325 -351.23793) (xy 331.129299 -351.230165)
			(xy 331.156564 -351.229676) (xy 332.020164 -351.229676) (xy 332.047439 -351.230061) (xy 332.101436 -351.23782)
			(xy 332.153778 -351.253185) (xy 332.2034 -351.275842) (xy 332.249293 -351.305332) (xy 332.290522 -351.341053)
			(xy 332.326246 -351.382278) (xy 332.35574 -351.428168) (xy 332.378403 -351.477788) (xy 332.393772 -351.530129)
			(xy 332.401536 -351.584125) (xy 332.401536 -351.638669) (xy 333.884239 -351.638669) (xy 333.884239 -351.584131)
			(xy 333.892001 -351.530147) (xy 333.907367 -351.477818) (xy 333.930024 -351.428208) (xy 333.959511 -351.382328)
			(xy 333.995228 -351.341111) (xy 334.036447 -351.305397) (xy 334.082329 -351.275913) (xy 334.13194 -351.253259)
			(xy 334.18427 -351.237896) (xy 334.238255 -351.230138) (xy 334.265524 -351.229676) (xy 335.129124 -351.229676)
			(xy 335.156395 -351.230088) (xy 335.210381 -351.237853) (xy 335.262713 -351.253222) (xy 335.312325 -351.275882)
			(xy 335.358208 -351.305372) (xy 335.399427 -351.34109) (xy 335.435143 -351.382312) (xy 335.464629 -351.428196)
			(xy 335.487286 -351.477809) (xy 335.502652 -351.530142) (xy 335.510414 -351.584129) (xy 335.510414 -351.638666)
			(xy 336.993262 -351.638666) (xy 336.993262 -351.584134) (xy 337.001023 -351.530157) (xy 337.016386 -351.477834)
			(xy 337.039039 -351.42823) (xy 337.06852 -351.382354) (xy 337.10423 -351.341141) (xy 337.145442 -351.30543)
			(xy 337.191316 -351.275946) (xy 337.240919 -351.253291) (xy 337.293242 -351.237926) (xy 337.347218 -351.230163)
			(xy 337.374484 -351.229676) (xy 338.238084 -351.229676) (xy 338.265358 -351.230062) (xy 338.319352 -351.237824)
			(xy 338.371692 -351.25319) (xy 338.421312 -351.275849) (xy 338.467203 -351.305339) (xy 338.508429 -351.34106)
			(xy 338.544151 -351.382285) (xy 338.573643 -351.428174) (xy 338.596304 -351.477793) (xy 338.611673 -351.530132)
			(xy 338.619436 -351.584126) (xy 338.619436 -351.63867) (xy 340.10214 -351.63867) (xy 340.10214 -351.58413)
			(xy 340.109902 -351.530144) (xy 340.125269 -351.477813) (xy 340.147928 -351.428202) (xy 340.177416 -351.382321)
			(xy 340.213135 -351.341104) (xy 340.254356 -351.30539) (xy 340.300241 -351.275906) (xy 340.349855 -351.253254)
			(xy 340.402187 -351.237893) (xy 340.456174 -351.230136) (xy 340.483444 -351.229676) (xy 341.347044 -351.229676)
			(xy 341.374314 -351.23009) (xy 341.428298 -351.237857) (xy 341.480628 -351.253228) (xy 341.530237 -351.275889)
			(xy 341.576117 -351.305379) (xy 341.617334 -351.341097) (xy 341.653048 -351.382318) (xy 341.682532 -351.428201)
			(xy 341.705188 -351.477814) (xy 341.720552 -351.530145) (xy 341.728314 -351.58413) (xy 341.728314 -351.638668)
			(xy 343.211139 -351.638668) (xy 343.211139 -351.584132) (xy 343.218901 -351.53015) (xy 343.234266 -351.477822)
			(xy 343.256921 -351.428213) (xy 343.286407 -351.382334) (xy 343.322121 -351.341118) (xy 343.363337 -351.305404)
			(xy 343.409217 -351.27592) (xy 343.458826 -351.253264) (xy 343.511154 -351.2379) (xy 343.565136 -351.230139)
			(xy 343.592404 -351.229676) (xy 344.456004 -351.229676) (xy 344.483276 -351.230087) (xy 344.537264 -351.23785)
			(xy 344.589599 -351.253217) (xy 344.639213 -351.275876) (xy 344.685098 -351.305365) (xy 344.72632 -351.341083)
			(xy 344.762038 -351.382305) (xy 344.791526 -351.42819) (xy 344.814184 -351.477805) (xy 344.829551 -351.530139)
			(xy 344.837313 -351.584128) (xy 344.837313 -351.638666) (xy 370.806762 -351.638666) (xy 370.806762 -351.584134)
			(xy 370.814523 -351.530158) (xy 370.829885 -351.477835) (xy 370.852538 -351.428231) (xy 370.882019 -351.382356)
			(xy 370.917729 -351.341143) (xy 370.95894 -351.305431) (xy 371.004814 -351.275948) (xy 371.054416 -351.253292)
			(xy 371.106738 -351.237927) (xy 371.160714 -351.230164) (xy 371.18798 -351.229676) (xy 372.05158 -351.229676)
			(xy 372.078855 -351.230062) (xy 372.132849 -351.237823) (xy 372.185189 -351.253189) (xy 372.23481 -351.275848)
			(xy 372.280701 -351.305338) (xy 372.321927 -351.341059) (xy 372.35765 -351.382283) (xy 372.387143 -351.428172)
			(xy 372.409804 -351.477792) (xy 372.425173 -351.530131) (xy 372.432936 -351.584125) (xy 372.432936 -351.63867)
			(xy 373.91564 -351.63867) (xy 373.91564 -351.58413) (xy 373.923402 -351.530145) (xy 373.938769 -351.477814)
			(xy 373.961427 -351.428203) (xy 373.990915 -351.382322) (xy 374.026634 -351.341105) (xy 374.067854 -351.305391)
			(xy 374.113738 -351.275908) (xy 374.163352 -351.253255) (xy 374.215684 -351.237893) (xy 374.26967 -351.230137)
			(xy 374.29694 -351.229676) (xy 375.16054 -351.229676) (xy 375.18781 -351.230089) (xy 375.241795 -351.237856)
			(xy 375.294125 -351.253227) (xy 375.343735 -351.275887) (xy 375.389615 -351.305377) (xy 375.430832 -351.341096)
			(xy 375.466547 -351.382317) (xy 375.496032 -351.4282) (xy 375.518687 -351.477813) (xy 375.534052 -351.530144)
			(xy 375.541814 -351.58413) (xy 375.541814 -351.638667) (xy 377.024662 -351.638667) (xy 377.024662 -351.584133)
			(xy 377.032423 -351.530155) (xy 377.047787 -351.477831) (xy 377.070441 -351.428226) (xy 377.099924 -351.382349)
			(xy 377.135636 -351.341136) (xy 377.176849 -351.305424) (xy 377.222726 -351.275941) (xy 377.272331 -351.253287)
			(xy 377.324655 -351.237923) (xy 377.378633 -351.230162) (xy 377.4059 -351.229676) (xy 378.2695 -351.229676)
			(xy 378.296772 -351.230087) (xy 378.350761 -351.237849) (xy 378.403096 -351.253216) (xy 378.452711 -351.275874)
			(xy 378.498596 -351.305363) (xy 378.539818 -351.341082) (xy 378.575537 -351.382304) (xy 378.605026 -351.428189)
			(xy 378.627684 -351.477804) (xy 378.643051 -351.530139) (xy 378.650813 -351.584128) (xy 378.650813 -351.638665)
			(xy 380.133662 -351.638665) (xy 380.133662 -351.584135) (xy 380.141422 -351.53016) (xy 380.156784 -351.477839)
			(xy 380.179435 -351.428237) (xy 380.208914 -351.382362) (xy 380.244621 -351.34115) (xy 380.28583 -351.305438)
			(xy 380.331702 -351.275954) (xy 380.381302 -351.253298) (xy 380.433621 -351.237931) (xy 380.487595 -351.230165)
			(xy 380.51486 -351.229676) (xy 381.37846 -351.229676) (xy 381.405736 -351.230061) (xy 381.459732 -351.237819)
			(xy 381.512075 -351.253183) (xy 381.561698 -351.275841) (xy 381.607591 -351.30533) (xy 381.64882 -351.341051)
			(xy 381.684546 -351.382277) (xy 381.71404 -351.428167) (xy 381.736703 -351.477788) (xy 381.752072 -351.530129)
			(xy 381.759836 -351.584124) (xy 381.759836 -351.638669) (xy 383.242539 -351.638669) (xy 383.242539 -351.584131)
			(xy 383.250301 -351.530148) (xy 383.265667 -351.477818) (xy 383.288324 -351.428209) (xy 383.31781 -351.382329)
			(xy 383.353526 -351.341112) (xy 383.394745 -351.305398) (xy 383.440626 -351.275914) (xy 383.490237 -351.25326)
			(xy 383.542567 -351.237897) (xy 383.596551 -351.230138) (xy 383.62382 -351.229676) (xy 384.48742 -351.229676)
			(xy 384.514691 -351.230088) (xy 384.568678 -351.237853) (xy 384.62101 -351.253221) (xy 384.670623 -351.275881)
			(xy 384.716506 -351.30537) (xy 384.757725 -351.341089) (xy 384.793442 -351.38231) (xy 384.822929 -351.428195)
			(xy 384.845586 -351.477808) (xy 384.860952 -351.530142) (xy 384.868714 -351.584129) (xy 384.868714 -351.638666)
			(xy 386.351562 -351.638666) (xy 386.351562 -351.584134) (xy 386.359323 -351.530158) (xy 386.374685 -351.477835)
			(xy 386.397338 -351.428231) (xy 386.426819 -351.382356) (xy 386.462529 -351.341143) (xy 386.50374 -351.305431)
			(xy 386.549614 -351.275948) (xy 386.599216 -351.253292) (xy 386.651538 -351.237927) (xy 386.705514 -351.230164)
			(xy 386.73278 -351.229676) (xy 387.59638 -351.229676) (xy 387.623655 -351.230062) (xy 387.677649 -351.237823)
			(xy 387.729989 -351.253189) (xy 387.77961 -351.275848) (xy 387.825501 -351.305338) (xy 387.866727 -351.341059)
			(xy 387.90245 -351.382283) (xy 387.931943 -351.428172) (xy 387.954604 -351.477792) (xy 387.969973 -351.530131)
			(xy 387.977736 -351.584125) (xy 387.977736 -351.63867) (xy 389.46044 -351.63867) (xy 389.46044 -351.58413)
			(xy 389.468202 -351.530145) (xy 389.483569 -351.477814) (xy 389.506227 -351.428203) (xy 389.535715 -351.382322)
			(xy 389.571434 -351.341105) (xy 389.612654 -351.305391) (xy 389.658538 -351.275908) (xy 389.708152 -351.253255)
			(xy 389.760484 -351.237893) (xy 389.81447 -351.230137) (xy 389.84174 -351.229676) (xy 390.70534 -351.229676)
			(xy 390.73261 -351.230089) (xy 390.786595 -351.237856) (xy 390.838925 -351.253227) (xy 390.888535 -351.275887)
			(xy 390.934415 -351.305377) (xy 390.975632 -351.341096) (xy 391.011347 -351.382317) (xy 391.040832 -351.4282)
			(xy 391.063487 -351.477813) (xy 391.078852 -351.530144) (xy 391.086614 -351.58413) (xy 391.086614 -351.638667)
			(xy 392.569462 -351.638667) (xy 392.569462 -351.584133) (xy 392.577223 -351.530155) (xy 392.592587 -351.477831)
			(xy 392.615241 -351.428226) (xy 392.644724 -351.382349) (xy 392.680436 -351.341136) (xy 392.721649 -351.305424)
			(xy 392.767526 -351.275941) (xy 392.817131 -351.253287) (xy 392.869455 -351.237923) (xy 392.923433 -351.230162)
			(xy 392.9507 -351.229676) (xy 393.8143 -351.229676) (xy 393.841572 -351.230087) (xy 393.895561 -351.237849)
			(xy 393.947896 -351.253216) (xy 393.997511 -351.275874) (xy 394.043396 -351.305363) (xy 394.084618 -351.341082)
			(xy 394.120337 -351.382304) (xy 394.149826 -351.428189) (xy 394.172484 -351.477804) (xy 394.187851 -351.530139)
			(xy 394.195613 -351.584128) (xy 394.195613 -351.638665) (xy 395.678462 -351.638665) (xy 395.678462 -351.584135)
			(xy 395.686222 -351.53016) (xy 395.701584 -351.477839) (xy 395.724235 -351.428237) (xy 395.753714 -351.382362)
			(xy 395.789421 -351.34115) (xy 395.83063 -351.305438) (xy 395.876502 -351.275954) (xy 395.926102 -351.253298)
			(xy 395.978421 -351.237931) (xy 396.032395 -351.230165) (xy 396.05966 -351.229676) (xy 396.92326 -351.229676)
			(xy 396.950536 -351.230061) (xy 397.004532 -351.237819) (xy 397.056875 -351.253183) (xy 397.106498 -351.275841)
			(xy 397.152391 -351.30533) (xy 397.19362 -351.341051) (xy 397.229346 -351.382277) (xy 397.25884 -351.428167)
			(xy 397.281503 -351.477788) (xy 397.296872 -351.530129) (xy 397.304636 -351.584124) (xy 397.304636 -351.638669)
			(xy 398.787339 -351.638669) (xy 398.787339 -351.584131) (xy 398.795101 -351.530148) (xy 398.810467 -351.477818)
			(xy 398.833124 -351.428209) (xy 398.86261 -351.382329) (xy 398.898326 -351.341112) (xy 398.939545 -351.305398)
			(xy 398.985426 -351.275914) (xy 399.035037 -351.25326) (xy 399.087367 -351.237897) (xy 399.141351 -351.230138)
			(xy 399.16862 -351.229676) (xy 400.03222 -351.229676) (xy 400.059491 -351.230088) (xy 400.113478 -351.237853)
			(xy 400.16581 -351.253221) (xy 400.215423 -351.275881) (xy 400.261306 -351.30537) (xy 400.302525 -351.341089)
			(xy 400.338242 -351.38231) (xy 400.367729 -351.428195) (xy 400.390386 -351.477808) (xy 400.405752 -351.530142)
			(xy 400.413514 -351.584129) (xy 400.413514 -351.638666) (xy 401.896362 -351.638666) (xy 401.896362 -351.584134)
			(xy 401.904123 -351.530158) (xy 401.919485 -351.477835) (xy 401.942138 -351.428231) (xy 401.971619 -351.382356)
			(xy 402.007329 -351.341143) (xy 402.04854 -351.305431) (xy 402.094414 -351.275948) (xy 402.144016 -351.253292)
			(xy 402.196338 -351.237927) (xy 402.250314 -351.230164) (xy 402.27758 -351.229676) (xy 403.14118 -351.229676)
			(xy 403.168455 -351.230062) (xy 403.222449 -351.237823) (xy 403.274789 -351.253189) (xy 403.32441 -351.275848)
			(xy 403.370301 -351.305338) (xy 403.411527 -351.341059) (xy 403.44725 -351.382283) (xy 403.476743 -351.428172)
			(xy 403.499404 -351.477792) (xy 403.514773 -351.530131) (xy 403.522536 -351.584125) (xy 403.522536 -351.638666)
			(xy 408.913862 -351.638666) (xy 408.913862 -351.584134) (xy 408.921623 -351.530156) (xy 408.936986 -351.477832)
			(xy 408.95964 -351.428228) (xy 408.989122 -351.382352) (xy 409.024833 -351.341138) (xy 409.066045 -351.305427)
			(xy 409.111921 -351.275944) (xy 409.161525 -351.253289) (xy 409.213848 -351.237925) (xy 409.267826 -351.230163)
			(xy 409.295092 -351.229676) (xy 410.158692 -351.229676) (xy 410.185966 -351.230063) (xy 410.239959 -351.237825)
			(xy 410.292298 -351.253192) (xy 410.341917 -351.275851) (xy 410.387806 -351.305342) (xy 410.429032 -351.341063)
			(xy 410.464753 -351.382287) (xy 410.494245 -351.428176) (xy 410.516905 -351.477794) (xy 410.532273 -351.530133)
			(xy 410.540036 -351.584126) (xy 410.540036 -351.638664) (xy 412.022862 -351.638664) (xy 412.022862 -351.584136)
			(xy 412.030622 -351.530162) (xy 412.045983 -351.477841) (xy 412.068634 -351.428239) (xy 412.098112 -351.382365)
			(xy 412.133819 -351.341153) (xy 412.175026 -351.305441) (xy 412.220897 -351.275957) (xy 412.270496 -351.2533)
			(xy 412.322815 -351.237932) (xy 412.376788 -351.230166) (xy 412.404052 -351.229676) (xy 413.267652 -351.229676)
			(xy 413.294928 -351.23006) (xy 413.348925 -351.237818) (xy 413.401269 -351.253181) (xy 413.450893 -351.275838)
			(xy 413.496787 -351.305328) (xy 413.538017 -351.341049) (xy 413.573744 -351.382274) (xy 413.603239 -351.428165)
			(xy 413.625902 -351.477786) (xy 413.641272 -351.530128) (xy 413.649036 -351.584124) (xy 413.649036 -351.638669)
			(xy 415.131739 -351.638669) (xy 415.131739 -351.584131) (xy 415.139501 -351.530149) (xy 415.154866 -351.47782)
			(xy 415.177523 -351.428211) (xy 415.207008 -351.382331) (xy 415.242724 -351.341115) (xy 415.283941 -351.305401)
			(xy 415.329822 -351.275917) (xy 415.379431 -351.253262) (xy 415.43176 -351.237899) (xy 415.485743 -351.230139)
			(xy 415.513012 -351.229676) (xy 416.376612 -351.229676) (xy 416.403884 -351.230087) (xy 416.457871 -351.237851)
			(xy 416.510204 -351.253219) (xy 416.559818 -351.275878) (xy 416.605702 -351.305367) (xy 416.646922 -351.341086)
			(xy 416.68264 -351.382308) (xy 416.712128 -351.428192) (xy 416.734785 -351.477807) (xy 416.750151 -351.530141)
			(xy 416.757914 -351.584128) (xy 416.757914 -351.638665) (xy 418.240762 -351.638665) (xy 418.240762 -351.584135)
			(xy 418.248522 -351.530159) (xy 418.263885 -351.477837) (xy 418.286537 -351.428233) (xy 418.316017 -351.382358)
			(xy 418.351726 -351.341146) (xy 418.392936 -351.305434) (xy 418.438809 -351.27595) (xy 418.48841 -351.253295)
			(xy 418.540731 -351.237928) (xy 418.594707 -351.230164) (xy 418.621972 -351.229676) (xy 419.485572 -351.229676)
			(xy 419.512847 -351.230062) (xy 419.566842 -351.237821) (xy 419.619184 -351.253187) (xy 419.668805 -351.275845)
			(xy 419.714697 -351.305335) (xy 419.755924 -351.341056) (xy 419.791648 -351.382281) (xy 419.821142 -351.42817)
			(xy 419.843803 -351.47779) (xy 419.859173 -351.53013) (xy 419.866936 -351.584125) (xy 419.866936 -351.63867)
			(xy 421.349639 -351.63867) (xy 421.349639 -351.58413) (xy 421.357402 -351.530146) (xy 421.372768 -351.477816)
			(xy 421.395426 -351.428206) (xy 421.424913 -351.382325) (xy 421.460631 -351.341108) (xy 421.501851 -351.305394)
			(xy 421.547734 -351.27591) (xy 421.597346 -351.253257) (xy 421.649677 -351.237895) (xy 421.703662 -351.230137)
			(xy 421.730932 -351.229676) (xy 422.594532 -351.229676) (xy 422.621803 -351.230089) (xy 422.675788 -351.237855)
			(xy 422.728119 -351.253224) (xy 422.77773 -351.275885) (xy 422.823612 -351.305374) (xy 422.864829 -351.341093)
			(xy 422.900545 -351.382314) (xy 422.930031 -351.428198) (xy 422.952687 -351.477811) (xy 422.968052 -351.530143)
			(xy 422.975814 -351.584129) (xy 422.975814 -351.638666) (xy 424.458662 -351.638666) (xy 424.458662 -351.584134)
			(xy 424.466423 -351.530156) (xy 424.481786 -351.477832) (xy 424.50444 -351.428228) (xy 424.533922 -351.382352)
			(xy 424.569633 -351.341138) (xy 424.610845 -351.305427) (xy 424.656721 -351.275944) (xy 424.706325 -351.253289)
			(xy 424.758648 -351.237925) (xy 424.812626 -351.230163) (xy 424.839892 -351.229676) (xy 425.703492 -351.229676)
			(xy 425.730766 -351.230063) (xy 425.784759 -351.237825) (xy 425.837098 -351.253192) (xy 425.886717 -351.275851)
			(xy 425.932606 -351.305342) (xy 425.973832 -351.341063) (xy 426.009553 -351.382287) (xy 426.039045 -351.428176)
			(xy 426.061705 -351.477794) (xy 426.077073 -351.530133) (xy 426.084836 -351.584126) (xy 426.084836 -351.638664)
			(xy 427.567662 -351.638664) (xy 427.567662 -351.584136) (xy 427.575422 -351.530162) (xy 427.590783 -351.477841)
			(xy 427.613434 -351.428239) (xy 427.642912 -351.382365) (xy 427.678619 -351.341153) (xy 427.719826 -351.305441)
			(xy 427.765697 -351.275957) (xy 427.815296 -351.2533) (xy 427.867615 -351.237932) (xy 427.921588 -351.230166)
			(xy 427.948852 -351.229676) (xy 428.812452 -351.229676) (xy 428.839728 -351.23006) (xy 428.893725 -351.237818)
			(xy 428.946069 -351.253181) (xy 428.995693 -351.275838) (xy 429.041587 -351.305328) (xy 429.082817 -351.341049)
			(xy 429.118544 -351.382274) (xy 429.148039 -351.428165) (xy 429.170702 -351.477786) (xy 429.186072 -351.530128)
			(xy 429.193836 -351.584124) (xy 429.193836 -351.638669) (xy 430.676539 -351.638669) (xy 430.676539 -351.584131)
			(xy 430.684301 -351.530149) (xy 430.699666 -351.47782) (xy 430.722323 -351.428211) (xy 430.751808 -351.382331)
			(xy 430.787524 -351.341115) (xy 430.828741 -351.305401) (xy 430.874622 -351.275917) (xy 430.924231 -351.253262)
			(xy 430.97656 -351.237899) (xy 431.030543 -351.230139) (xy 431.057812 -351.229676) (xy 431.921412 -351.229676)
			(xy 431.948684 -351.230087) (xy 432.002671 -351.237851) (xy 432.055004 -351.253219) (xy 432.104618 -351.275878)
			(xy 432.150502 -351.305367) (xy 432.191722 -351.341086) (xy 432.22744 -351.382308) (xy 432.256928 -351.428192)
			(xy 432.279585 -351.477807) (xy 432.294951 -351.530141) (xy 432.302714 -351.584128) (xy 432.302714 -351.638665)
			(xy 433.785562 -351.638665) (xy 433.785562 -351.584135) (xy 433.793322 -351.530159) (xy 433.808685 -351.477837)
			(xy 433.831337 -351.428233) (xy 433.860817 -351.382358) (xy 433.896526 -351.341146) (xy 433.937736 -351.305434)
			(xy 433.983609 -351.27595) (xy 434.03321 -351.253295) (xy 434.085531 -351.237928) (xy 434.139507 -351.230164)
			(xy 434.166772 -351.229676) (xy 435.030372 -351.229676) (xy 435.057647 -351.230062) (xy 435.111642 -351.237821)
			(xy 435.163984 -351.253187) (xy 435.213605 -351.275845) (xy 435.259497 -351.305335) (xy 435.300724 -351.341056)
			(xy 435.336448 -351.382281) (xy 435.365942 -351.42817) (xy 435.388603 -351.47779) (xy 435.403973 -351.53013)
			(xy 435.411736 -351.584125) (xy 435.411736 -351.63867) (xy 436.894439 -351.63867) (xy 436.894439 -351.58413)
			(xy 436.902202 -351.530146) (xy 436.917568 -351.477816) (xy 436.940226 -351.428206) (xy 436.969713 -351.382325)
			(xy 437.005431 -351.341108) (xy 437.046651 -351.305394) (xy 437.092534 -351.27591) (xy 437.142146 -351.253257)
			(xy 437.194477 -351.237895) (xy 437.248462 -351.230137) (xy 437.275732 -351.229676) (xy 438.139332 -351.229676)
			(xy 438.166603 -351.230089) (xy 438.220588 -351.237855) (xy 438.272919 -351.253224) (xy 438.32253 -351.275885)
			(xy 438.368412 -351.305374) (xy 438.409629 -351.341093) (xy 438.445345 -351.382314) (xy 438.474831 -351.428198)
			(xy 438.497487 -351.477811) (xy 438.512852 -351.530143) (xy 438.520614 -351.584129) (xy 438.520614 -351.638666)
			(xy 440.003462 -351.638666) (xy 440.003462 -351.584134) (xy 440.011223 -351.530156) (xy 440.026586 -351.477832)
			(xy 440.04924 -351.428228) (xy 440.078722 -351.382352) (xy 440.114433 -351.341138) (xy 440.155645 -351.305427)
			(xy 440.201521 -351.275944) (xy 440.251125 -351.253289) (xy 440.303448 -351.237925) (xy 440.357426 -351.230163)
			(xy 440.384692 -351.229676) (xy 441.248292 -351.229676) (xy 441.275566 -351.230063) (xy 441.329559 -351.237825)
			(xy 441.381898 -351.253192) (xy 441.431517 -351.275851) (xy 441.477406 -351.305342) (xy 441.518632 -351.341063)
			(xy 441.554353 -351.382287) (xy 441.583845 -351.428176) (xy 441.606505 -351.477794) (xy 441.621873 -351.530133)
			(xy 441.629636 -351.584126) (xy 441.629636 -351.638674) (xy 441.621873 -351.692667) (xy 441.606505 -351.745006)
			(xy 441.583845 -351.794624) (xy 441.554353 -351.840513) (xy 441.518632 -351.881737) (xy 441.477406 -351.917458)
			(xy 441.431517 -351.946949) (xy 441.381898 -351.969608) (xy 441.329559 -351.984975) (xy 441.275566 -351.992737)
			(xy 441.248292 -351.9932) (xy 440.384692 -351.9932) (xy 440.357426 -351.992637) (xy 440.303448 -351.984875)
			(xy 440.251125 -351.969511) (xy 440.201521 -351.946856) (xy 440.155645 -351.917373) (xy 440.114433 -351.881662)
			(xy 440.078722 -351.840448) (xy 440.04924 -351.794572) (xy 440.026586 -351.744968) (xy 440.011223 -351.692644)
			(xy 440.003462 -351.638666) (xy 438.520614 -351.638666) (xy 438.520614 -351.638671) (xy 438.512852 -351.692657)
			(xy 438.497487 -351.744989) (xy 438.474831 -351.794602) (xy 438.445345 -351.840486) (xy 438.409629 -351.881707)
			(xy 438.368412 -351.917426) (xy 438.32253 -351.946915) (xy 438.272919 -351.969576) (xy 438.220588 -351.984945)
			(xy 438.166603 -351.992711) (xy 438.139332 -351.9932) (xy 437.275732 -351.9932) (xy 437.248462 -351.992663)
			(xy 437.194477 -351.984905) (xy 437.142146 -351.969543) (xy 437.092534 -351.94689) (xy 437.046651 -351.917406)
			(xy 437.005431 -351.881692) (xy 436.969713 -351.840475) (xy 436.940226 -351.794594) (xy 436.917568 -351.744984)
			(xy 436.902202 -351.692654) (xy 436.894439 -351.63867) (xy 435.411736 -351.63867) (xy 435.411736 -351.638675)
			(xy 435.403973 -351.69267) (xy 435.388603 -351.74501) (xy 435.365942 -351.79463) (xy 435.336448 -351.840519)
			(xy 435.300724 -351.881744) (xy 435.259497 -351.917465) (xy 435.213605 -351.946955) (xy 435.163984 -351.969613)
			(xy 435.111642 -351.984979) (xy 435.057647 -351.992738) (xy 435.030372 -351.9932) (xy 434.166772 -351.9932)
			(xy 434.139507 -351.992636) (xy 434.085531 -351.984872) (xy 434.03321 -351.969505) (xy 433.983609 -351.94685)
			(xy 433.937736 -351.917366) (xy 433.896526 -351.881654) (xy 433.860817 -351.840442) (xy 433.831337 -351.794567)
			(xy 433.808685 -351.744963) (xy 433.793322 -351.692641) (xy 433.785562 -351.638665) (xy 432.302714 -351.638665)
			(xy 432.302714 -351.638672) (xy 432.294951 -351.692659) (xy 432.279585 -351.744993) (xy 432.256928 -351.794608)
			(xy 432.22744 -351.840492) (xy 432.191722 -351.881714) (xy 432.150502 -351.917433) (xy 432.104618 -351.946922)
			(xy 432.055004 -351.969581) (xy 432.002671 -351.984949) (xy 431.948684 -351.992713) (xy 431.921412 -351.9932)
			(xy 431.057812 -351.9932) (xy 431.030543 -351.992661) (xy 430.97656 -351.984901) (xy 430.924231 -351.969538)
			(xy 430.874622 -351.946883) (xy 430.828741 -351.917399) (xy 430.787524 -351.881685) (xy 430.751808 -351.840469)
			(xy 430.722323 -351.794589) (xy 430.699666 -351.74498) (xy 430.684301 -351.692651) (xy 430.676539 -351.638669)
			(xy 429.193836 -351.638669) (xy 429.193836 -351.638676) (xy 429.186072 -351.692672) (xy 429.170702 -351.745014)
			(xy 429.148039 -351.794635) (xy 429.118544 -351.840526) (xy 429.082817 -351.881751) (xy 429.041587 -351.917472)
			(xy 428.995693 -351.946962) (xy 428.946069 -351.969619) (xy 428.893725 -351.984982) (xy 428.839728 -351.99274)
			(xy 428.812452 -351.9932) (xy 427.948852 -351.9932) (xy 427.921588 -351.992634) (xy 427.867615 -351.984868)
			(xy 427.815296 -351.9695) (xy 427.765697 -351.946843) (xy 427.719826 -351.917359) (xy 427.678619 -351.881647)
			(xy 427.642912 -351.840435) (xy 427.613434 -351.794561) (xy 427.590783 -351.744959) (xy 427.575422 -351.692639)
			(xy 427.567662 -351.638664) (xy 426.084836 -351.638664) (xy 426.084836 -351.638674) (xy 426.077073 -351.692667)
			(xy 426.061705 -351.745006) (xy 426.039045 -351.794624) (xy 426.009553 -351.840513) (xy 425.973832 -351.881737)
			(xy 425.932606 -351.917458) (xy 425.886717 -351.946949) (xy 425.837098 -351.969608) (xy 425.784759 -351.984975)
			(xy 425.730766 -351.992737) (xy 425.703492 -351.9932) (xy 424.839892 -351.9932) (xy 424.812626 -351.992637)
			(xy 424.758648 -351.984875) (xy 424.706325 -351.969511) (xy 424.656721 -351.946856) (xy 424.610845 -351.917373)
			(xy 424.569633 -351.881662) (xy 424.533922 -351.840448) (xy 424.50444 -351.794572) (xy 424.481786 -351.744968)
			(xy 424.466423 -351.692644) (xy 424.458662 -351.638666) (xy 422.975814 -351.638666) (xy 422.975814 -351.638671)
			(xy 422.968052 -351.692657) (xy 422.952687 -351.744989) (xy 422.930031 -351.794602) (xy 422.900545 -351.840486)
			(xy 422.864829 -351.881707) (xy 422.823612 -351.917426) (xy 422.77773 -351.946915) (xy 422.728119 -351.969576)
			(xy 422.675788 -351.984945) (xy 422.621803 -351.992711) (xy 422.594532 -351.9932) (xy 421.730932 -351.9932)
			(xy 421.703662 -351.992663) (xy 421.649677 -351.984905) (xy 421.597346 -351.969543) (xy 421.547734 -351.94689)
			(xy 421.501851 -351.917406) (xy 421.460631 -351.881692) (xy 421.424913 -351.840475) (xy 421.395426 -351.794594)
			(xy 421.372768 -351.744984) (xy 421.357402 -351.692654) (xy 421.349639 -351.63867) (xy 419.866936 -351.63867)
			(xy 419.866936 -351.638675) (xy 419.859173 -351.69267) (xy 419.843803 -351.74501) (xy 419.821142 -351.79463)
			(xy 419.791648 -351.840519) (xy 419.755924 -351.881744) (xy 419.714697 -351.917465) (xy 419.668805 -351.946955)
			(xy 419.619184 -351.969613) (xy 419.566842 -351.984979) (xy 419.512847 -351.992738) (xy 419.485572 -351.9932)
			(xy 418.621972 -351.9932) (xy 418.594707 -351.992636) (xy 418.540731 -351.984872) (xy 418.48841 -351.969505)
			(xy 418.438809 -351.94685) (xy 418.392936 -351.917366) (xy 418.351726 -351.881654) (xy 418.316017 -351.840442)
			(xy 418.286537 -351.794567) (xy 418.263885 -351.744963) (xy 418.248522 -351.692641) (xy 418.240762 -351.638665)
			(xy 416.757914 -351.638665) (xy 416.757914 -351.638672) (xy 416.750151 -351.692659) (xy 416.734785 -351.744993)
			(xy 416.712128 -351.794608) (xy 416.68264 -351.840492) (xy 416.646922 -351.881714) (xy 416.605702 -351.917433)
			(xy 416.559818 -351.946922) (xy 416.510204 -351.969581) (xy 416.457871 -351.984949) (xy 416.403884 -351.992713)
			(xy 416.376612 -351.9932) (xy 415.513012 -351.9932) (xy 415.485743 -351.992661) (xy 415.43176 -351.984901)
			(xy 415.379431 -351.969538) (xy 415.329822 -351.946883) (xy 415.283941 -351.917399) (xy 415.242724 -351.881685)
			(xy 415.207008 -351.840469) (xy 415.177523 -351.794589) (xy 415.154866 -351.74498) (xy 415.139501 -351.692651)
			(xy 415.131739 -351.638669) (xy 413.649036 -351.638669) (xy 413.649036 -351.638676) (xy 413.641272 -351.692672)
			(xy 413.625902 -351.745014) (xy 413.603239 -351.794635) (xy 413.573744 -351.840526) (xy 413.538017 -351.881751)
			(xy 413.496787 -351.917472) (xy 413.450893 -351.946962) (xy 413.401269 -351.969619) (xy 413.348925 -351.984982)
			(xy 413.294928 -351.99274) (xy 413.267652 -351.9932) (xy 412.404052 -351.9932) (xy 412.376788 -351.992634)
			(xy 412.322815 -351.984868) (xy 412.270496 -351.9695) (xy 412.220897 -351.946843) (xy 412.175026 -351.917359)
			(xy 412.133819 -351.881647) (xy 412.098112 -351.840435) (xy 412.068634 -351.794561) (xy 412.045983 -351.744959)
			(xy 412.030622 -351.692639) (xy 412.022862 -351.638664) (xy 410.540036 -351.638664) (xy 410.540036 -351.638674)
			(xy 410.532273 -351.692667) (xy 410.516905 -351.745006) (xy 410.494245 -351.794624) (xy 410.464753 -351.840513)
			(xy 410.429032 -351.881737) (xy 410.387806 -351.917458) (xy 410.341917 -351.946949) (xy 410.292298 -351.969608)
			(xy 410.239959 -351.984975) (xy 410.185966 -351.992737) (xy 410.158692 -351.9932) (xy 409.295092 -351.9932)
			(xy 409.267826 -351.992637) (xy 409.213848 -351.984875) (xy 409.161525 -351.969511) (xy 409.111921 -351.946856)
			(xy 409.066045 -351.917373) (xy 409.024833 -351.881662) (xy 408.989122 -351.840448) (xy 408.95964 -351.794572)
			(xy 408.936986 -351.744968) (xy 408.921623 -351.692644) (xy 408.913862 -351.638666) (xy 403.522536 -351.638666)
			(xy 403.522536 -351.638675) (xy 403.514773 -351.692669) (xy 403.499404 -351.745008) (xy 403.476743 -351.794628)
			(xy 403.44725 -351.840517) (xy 403.411527 -351.881741) (xy 403.370301 -351.917462) (xy 403.32441 -351.946952)
			(xy 403.274789 -351.969611) (xy 403.222449 -351.984977) (xy 403.168455 -351.992738) (xy 403.14118 -351.9932)
			(xy 402.27758 -351.9932) (xy 402.250314 -351.992636) (xy 402.196338 -351.984873) (xy 402.144016 -351.969508)
			(xy 402.094414 -351.946852) (xy 402.04854 -351.917369) (xy 402.007329 -351.881657) (xy 401.971619 -351.840444)
			(xy 401.942138 -351.794569) (xy 401.919485 -351.744965) (xy 401.904123 -351.692642) (xy 401.896362 -351.638666)
			(xy 400.413514 -351.638666) (xy 400.413514 -351.638671) (xy 400.405752 -351.692658) (xy 400.390386 -351.744992)
			(xy 400.367729 -351.794605) (xy 400.338242 -351.84049) (xy 400.302525 -351.881711) (xy 400.261306 -351.91743)
			(xy 400.215423 -351.946919) (xy 400.16581 -351.969579) (xy 400.113478 -351.984947) (xy 400.059491 -351.992712)
			(xy 400.03222 -351.9932) (xy 399.16862 -351.9932) (xy 399.141351 -351.992662) (xy 399.087367 -351.984903)
			(xy 399.035037 -351.96954) (xy 398.985426 -351.946886) (xy 398.939545 -351.917402) (xy 398.898326 -351.881688)
			(xy 398.86261 -351.840471) (xy 398.833124 -351.794591) (xy 398.810467 -351.744982) (xy 398.795101 -351.692652)
			(xy 398.787339 -351.638669) (xy 397.304636 -351.638669) (xy 397.304636 -351.638676) (xy 397.296872 -351.692671)
			(xy 397.281503 -351.745012) (xy 397.25884 -351.794633) (xy 397.229346 -351.840523) (xy 397.19362 -351.881749)
			(xy 397.152391 -351.91747) (xy 397.106498 -351.946959) (xy 397.056875 -351.969617) (xy 397.004532 -351.984981)
			(xy 396.950536 -351.992739) (xy 396.92326 -351.9932) (xy 396.05966 -351.9932) (xy 396.032395 -351.992635)
			(xy 395.978421 -351.984869) (xy 395.926102 -351.969502) (xy 395.876502 -351.946846) (xy 395.83063 -351.917362)
			(xy 395.789421 -351.88165) (xy 395.753714 -351.840438) (xy 395.724235 -351.794563) (xy 395.701584 -351.744961)
			(xy 395.686222 -351.69264) (xy 395.678462 -351.638665) (xy 394.195613 -351.638665) (xy 394.195613 -351.638672)
			(xy 394.187851 -351.692661) (xy 394.172484 -351.744996) (xy 394.149826 -351.794611) (xy 394.120337 -351.840496)
			(xy 394.084618 -351.881718) (xy 394.043396 -351.917437) (xy 393.997511 -351.946926) (xy 393.947896 -351.969584)
			(xy 393.895561 -351.984951) (xy 393.841572 -351.992713) (xy 393.8143 -351.9932) (xy 392.9507 -351.9932)
			(xy 392.923433 -351.992638) (xy 392.869455 -351.984877) (xy 392.817131 -351.969513) (xy 392.767526 -351.946859)
			(xy 392.721649 -351.917376) (xy 392.680436 -351.881664) (xy 392.644724 -351.840451) (xy 392.615241 -351.794574)
			(xy 392.592587 -351.744969) (xy 392.577223 -351.692645) (xy 392.569462 -351.638667) (xy 391.086614 -351.638667)
			(xy 391.086614 -351.63867) (xy 391.078852 -351.692656) (xy 391.063487 -351.744987) (xy 391.040832 -351.7946)
			(xy 391.011347 -351.840483) (xy 390.975632 -351.881704) (xy 390.934415 -351.917423) (xy 390.888535 -351.946913)
			(xy 390.838925 -351.969573) (xy 390.786595 -351.984944) (xy 390.73261 -351.992711) (xy 390.70534 -351.9932)
			(xy 389.84174 -351.9932) (xy 389.81447 -351.992663) (xy 389.760484 -351.984907) (xy 389.708152 -351.969545)
			(xy 389.658538 -351.946892) (xy 389.612654 -351.917409) (xy 389.571434 -351.881695) (xy 389.535715 -351.840478)
			(xy 389.506227 -351.794597) (xy 389.483569 -351.744986) (xy 389.468202 -351.692655) (xy 389.46044 -351.63867)
			(xy 387.977736 -351.63867) (xy 387.977736 -351.638675) (xy 387.969973 -351.692669) (xy 387.954604 -351.745008)
			(xy 387.931943 -351.794628) (xy 387.90245 -351.840517) (xy 387.866727 -351.881741) (xy 387.825501 -351.917462)
			(xy 387.77961 -351.946952) (xy 387.729989 -351.969611) (xy 387.677649 -351.984977) (xy 387.623655 -351.992738)
			(xy 387.59638 -351.9932) (xy 386.73278 -351.9932) (xy 386.705514 -351.992636) (xy 386.651538 -351.984873)
			(xy 386.599216 -351.969508) (xy 386.549614 -351.946852) (xy 386.50374 -351.917369) (xy 386.462529 -351.881657)
			(xy 386.426819 -351.840444) (xy 386.397338 -351.794569) (xy 386.374685 -351.744965) (xy 386.359323 -351.692642)
			(xy 386.351562 -351.638666) (xy 384.868714 -351.638666) (xy 384.868714 -351.638671) (xy 384.860952 -351.692658)
			(xy 384.845586 -351.744992) (xy 384.822929 -351.794605) (xy 384.793442 -351.84049) (xy 384.757725 -351.881711)
			(xy 384.716506 -351.91743) (xy 384.670623 -351.946919) (xy 384.62101 -351.969579) (xy 384.568678 -351.984947)
			(xy 384.514691 -351.992712) (xy 384.48742 -351.9932) (xy 383.62382 -351.9932) (xy 383.596551 -351.992662)
			(xy 383.542567 -351.984903) (xy 383.490237 -351.96954) (xy 383.440626 -351.946886) (xy 383.394745 -351.917402)
			(xy 383.353526 -351.881688) (xy 383.31781 -351.840471) (xy 383.288324 -351.794591) (xy 383.265667 -351.744982)
			(xy 383.250301 -351.692652) (xy 383.242539 -351.638669) (xy 381.759836 -351.638669) (xy 381.759836 -351.638676)
			(xy 381.752072 -351.692671) (xy 381.736703 -351.745012) (xy 381.71404 -351.794633) (xy 381.684546 -351.840523)
			(xy 381.64882 -351.881749) (xy 381.607591 -351.91747) (xy 381.561698 -351.946959) (xy 381.512075 -351.969617)
			(xy 381.459732 -351.984981) (xy 381.405736 -351.992739) (xy 381.37846 -351.9932) (xy 380.51486 -351.9932)
			(xy 380.487595 -351.992635) (xy 380.433621 -351.984869) (xy 380.381302 -351.969502) (xy 380.331702 -351.946846)
			(xy 380.28583 -351.917362) (xy 380.244621 -351.88165) (xy 380.208914 -351.840438) (xy 380.179435 -351.794563)
			(xy 380.156784 -351.744961) (xy 380.141422 -351.69264) (xy 380.133662 -351.638665) (xy 378.650813 -351.638665)
			(xy 378.650813 -351.638672) (xy 378.643051 -351.692661) (xy 378.627684 -351.744996) (xy 378.605026 -351.794611)
			(xy 378.575537 -351.840496) (xy 378.539818 -351.881718) (xy 378.498596 -351.917437) (xy 378.452711 -351.946926)
			(xy 378.403096 -351.969584) (xy 378.350761 -351.984951) (xy 378.296772 -351.992713) (xy 378.2695 -351.9932)
			(xy 377.4059 -351.9932) (xy 377.378633 -351.992638) (xy 377.324655 -351.984877) (xy 377.272331 -351.969513)
			(xy 377.222726 -351.946859) (xy 377.176849 -351.917376) (xy 377.135636 -351.881664) (xy 377.099924 -351.840451)
			(xy 377.070441 -351.794574) (xy 377.047787 -351.744969) (xy 377.032423 -351.692645) (xy 377.024662 -351.638667)
			(xy 375.541814 -351.638667) (xy 375.541814 -351.63867) (xy 375.534052 -351.692656) (xy 375.518687 -351.744987)
			(xy 375.496032 -351.7946) (xy 375.466547 -351.840483) (xy 375.430832 -351.881704) (xy 375.389615 -351.917423)
			(xy 375.343735 -351.946913) (xy 375.294125 -351.969573) (xy 375.241795 -351.984944) (xy 375.18781 -351.992711)
			(xy 375.16054 -351.9932) (xy 374.29694 -351.9932) (xy 374.26967 -351.992663) (xy 374.215684 -351.984907)
			(xy 374.163352 -351.969545) (xy 374.113738 -351.946892) (xy 374.067854 -351.917409) (xy 374.026634 -351.881695)
			(xy 373.990915 -351.840478) (xy 373.961427 -351.794597) (xy 373.938769 -351.744986) (xy 373.923402 -351.692655)
			(xy 373.91564 -351.63867) (xy 372.432936 -351.63867) (xy 372.432936 -351.638675) (xy 372.425173 -351.692669)
			(xy 372.409804 -351.745008) (xy 372.387143 -351.794628) (xy 372.35765 -351.840517) (xy 372.321927 -351.881741)
			(xy 372.280701 -351.917462) (xy 372.23481 -351.946952) (xy 372.185189 -351.969611) (xy 372.132849 -351.984977)
			(xy 372.078855 -351.992738) (xy 372.05158 -351.9932) (xy 371.18798 -351.9932) (xy 371.160714 -351.992636)
			(xy 371.106738 -351.984873) (xy 371.054416 -351.969508) (xy 371.004814 -351.946852) (xy 370.95894 -351.917369)
			(xy 370.917729 -351.881657) (xy 370.882019 -351.840444) (xy 370.852538 -351.794569) (xy 370.829885 -351.744965)
			(xy 370.814523 -351.692642) (xy 370.806762 -351.638666) (xy 344.837313 -351.638666) (xy 344.837313 -351.638672)
			(xy 344.829551 -351.692661) (xy 344.814184 -351.744995) (xy 344.791526 -351.79461) (xy 344.762038 -351.840495)
			(xy 344.726319 -351.881717) (xy 344.685098 -351.917435) (xy 344.639213 -351.946924) (xy 344.589599 -351.969583)
			(xy 344.537264 -351.98495) (xy 344.483276 -351.992713) (xy 344.456004 -351.9932) (xy 343.592404 -351.9932)
			(xy 343.565136 -351.992661) (xy 343.511154 -351.9849) (xy 343.458826 -351.969536) (xy 343.409217 -351.94688)
			(xy 343.363337 -351.917396) (xy 343.322121 -351.881682) (xy 343.286407 -351.840466) (xy 343.256921 -351.794587)
			(xy 343.234266 -351.744978) (xy 343.218901 -351.69265) (xy 343.211139 -351.638668) (xy 341.728314 -351.638668)
			(xy 341.728314 -351.63867) (xy 341.720552 -351.692655) (xy 341.705188 -351.744986) (xy 341.682532 -351.794599)
			(xy 341.653048 -351.840482) (xy 341.617334 -351.881703) (xy 341.576117 -351.917421) (xy 341.530237 -351.946911)
			(xy 341.480628 -351.969572) (xy 341.428298 -351.984943) (xy 341.374314 -351.99271) (xy 341.347044 -351.9932)
			(xy 340.483444 -351.9932) (xy 340.456174 -351.992664) (xy 340.402187 -351.984907) (xy 340.349855 -351.969546)
			(xy 340.300241 -351.946894) (xy 340.254356 -351.91741) (xy 340.213135 -351.881696) (xy 340.177416 -351.840479)
			(xy 340.147928 -351.794598) (xy 340.125269 -351.744987) (xy 340.109902 -351.692656) (xy 340.10214 -351.63867)
			(xy 338.619436 -351.63867) (xy 338.619436 -351.638674) (xy 338.611673 -351.692668) (xy 338.596304 -351.745007)
			(xy 338.573643 -351.794626) (xy 338.544151 -351.840515) (xy 338.508429 -351.88174) (xy 338.467203 -351.917461)
			(xy 338.421312 -351.946951) (xy 338.371692 -351.96961) (xy 338.319352 -351.984976) (xy 338.265358 -351.992738)
			(xy 338.238084 -351.9932) (xy 337.374484 -351.9932) (xy 337.347218 -351.992637) (xy 337.293242 -351.984874)
			(xy 337.240919 -351.969509) (xy 337.191316 -351.946854) (xy 337.145442 -351.91737) (xy 337.10423 -351.881659)
			(xy 337.06852 -351.840446) (xy 337.039039 -351.79457) (xy 337.016386 -351.744966) (xy 337.001023 -351.692643)
			(xy 336.993262 -351.638666) (xy 335.510414 -351.638666) (xy 335.510414 -351.638671) (xy 335.502652 -351.692658)
			(xy 335.487286 -351.744991) (xy 335.464629 -351.794604) (xy 335.435143 -351.840488) (xy 335.399427 -351.88171)
			(xy 335.358208 -351.917428) (xy 335.312325 -351.946918) (xy 335.262713 -351.969578) (xy 335.210381 -351.984947)
			(xy 335.156395 -351.992712) (xy 335.129124 -351.9932) (xy 334.265524 -351.9932) (xy 334.238255 -351.992662)
			(xy 334.18427 -351.984904) (xy 334.13194 -351.969541) (xy 334.082329 -351.946887) (xy 334.036447 -351.917403)
			(xy 333.995228 -351.881689) (xy 333.959511 -351.840472) (xy 333.930024 -351.794592) (xy 333.907367 -351.744982)
			(xy 333.892001 -351.692653) (xy 333.884239 -351.638669) (xy 332.401536 -351.638669) (xy 332.401536 -351.638675)
			(xy 332.393772 -351.692671) (xy 332.378403 -351.745011) (xy 332.35574 -351.794632) (xy 332.326246 -351.840522)
			(xy 332.290522 -351.881747) (xy 332.249293 -351.917468) (xy 332.2034 -351.946958) (xy 332.153778 -351.969615)
			(xy 332.101436 -351.98498) (xy 332.047439 -351.992739) (xy 332.020164 -351.9932) (xy 331.156564 -351.9932)
			(xy 331.129299 -351.992635) (xy 331.075325 -351.98487) (xy 331.023005 -351.969503) (xy 330.973404 -351.946847)
			(xy 330.927532 -351.917363) (xy 330.886323 -351.881652) (xy 330.850615 -351.840439) (xy 330.821136 -351.794564)
			(xy 330.798484 -351.744962) (xy 330.783122 -351.69264) (xy 330.775362 -351.638665) (xy 329.292513 -351.638665)
			(xy 329.292513 -351.638672) (xy 329.284751 -351.692661) (xy 329.269384 -351.744995) (xy 329.246726 -351.79461)
			(xy 329.217238 -351.840495) (xy 329.181519 -351.881717) (xy 329.140298 -351.917435) (xy 329.094413 -351.946924)
			(xy 329.044799 -351.969583) (xy 328.992464 -351.98495) (xy 328.938476 -351.992713) (xy 328.911204 -351.9932)
			(xy 328.047604 -351.9932) (xy 328.020336 -351.992661) (xy 327.966354 -351.9849) (xy 327.914026 -351.969536)
			(xy 327.864417 -351.94688) (xy 327.818537 -351.917396) (xy 327.777321 -351.881682) (xy 327.741607 -351.840466)
			(xy 327.712121 -351.794587) (xy 327.689466 -351.744978) (xy 327.674101 -351.69265) (xy 327.666339 -351.638668)
			(xy 326.183514 -351.638668) (xy 326.183514 -351.63867) (xy 326.175752 -351.692655) (xy 326.160388 -351.744986)
			(xy 326.137732 -351.794599) (xy 326.108248 -351.840482) (xy 326.072534 -351.881703) (xy 326.031317 -351.917421)
			(xy 325.985437 -351.946911) (xy 325.935828 -351.969572) (xy 325.883498 -351.984943) (xy 325.829514 -351.99271)
			(xy 325.802244 -351.9932) (xy 324.938644 -351.9932) (xy 324.911374 -351.992664) (xy 324.857387 -351.984907)
			(xy 324.805055 -351.969546) (xy 324.755441 -351.946894) (xy 324.709556 -351.91741) (xy 324.668335 -351.881696)
			(xy 324.632616 -351.840479) (xy 324.603128 -351.794598) (xy 324.580469 -351.744987) (xy 324.565102 -351.692656)
			(xy 324.55734 -351.63867) (xy 323.074636 -351.63867) (xy 323.074636 -351.638674) (xy 323.066873 -351.692668)
			(xy 323.051504 -351.745007) (xy 323.028843 -351.794626) (xy 322.999351 -351.840515) (xy 322.963629 -351.88174)
			(xy 322.922403 -351.917461) (xy 322.876512 -351.946951) (xy 322.826892 -351.96961) (xy 322.774552 -351.984976)
			(xy 322.720558 -351.992738) (xy 322.693284 -351.9932) (xy 321.829684 -351.9932) (xy 321.802418 -351.992637)
			(xy 321.748442 -351.984874) (xy 321.696119 -351.969509) (xy 321.646516 -351.946854) (xy 321.600642 -351.91737)
			(xy 321.55943 -351.881659) (xy 321.52372 -351.840446) (xy 321.494239 -351.79457) (xy 321.471586 -351.744966)
			(xy 321.456223 -351.692643) (xy 321.448462 -351.638666) (xy 319.965614 -351.638666) (xy 319.965614 -351.638671)
			(xy 319.957852 -351.692658) (xy 319.942486 -351.744991) (xy 319.919829 -351.794604) (xy 319.890343 -351.840488)
			(xy 319.854627 -351.88171) (xy 319.813408 -351.917428) (xy 319.767525 -351.946918) (xy 319.717913 -351.969578)
			(xy 319.665581 -351.984947) (xy 319.611595 -351.992712) (xy 319.584324 -351.9932) (xy 318.720724 -351.9932)
			(xy 318.693455 -351.992662) (xy 318.63947 -351.984904) (xy 318.58714 -351.969541) (xy 318.537529 -351.946887)
			(xy 318.491647 -351.917403) (xy 318.450428 -351.881689) (xy 318.414711 -351.840472) (xy 318.385224 -351.794592)
			(xy 318.362567 -351.744982) (xy 318.347201 -351.692653) (xy 318.339439 -351.638669) (xy 316.856736 -351.638669)
			(xy 316.856736 -351.638675) (xy 316.848972 -351.692671) (xy 316.833603 -351.745011) (xy 316.81094 -351.794632)
			(xy 316.781446 -351.840522) (xy 316.745722 -351.881747) (xy 316.704493 -351.917468) (xy 316.6586 -351.946958)
			(xy 316.608978 -351.969615) (xy 316.556636 -351.98498) (xy 316.502639 -351.992739) (xy 316.475364 -351.9932)
			(xy 315.611764 -351.9932) (xy 315.584499 -351.992635) (xy 315.530525 -351.98487) (xy 315.478205 -351.969503)
			(xy 315.428604 -351.946847) (xy 315.382732 -351.917363) (xy 315.341523 -351.881652) (xy 315.305815 -351.840439)
			(xy 315.276336 -351.794564) (xy 315.253684 -351.744962) (xy 315.238322 -351.69264) (xy 315.230562 -351.638665)
			(xy 313.747713 -351.638665) (xy 313.747713 -351.638672) (xy 313.739951 -351.692661) (xy 313.724584 -351.744995)
			(xy 313.701926 -351.79461) (xy 313.672438 -351.840495) (xy 313.636719 -351.881717) (xy 313.595498 -351.917435)
			(xy 313.549613 -351.946924) (xy 313.499999 -351.969583) (xy 313.447664 -351.98495) (xy 313.393676 -351.992713)
			(xy 313.366404 -351.9932) (xy 312.502804 -351.9932) (xy 312.475536 -351.992661) (xy 312.421554 -351.9849)
			(xy 312.369226 -351.969536) (xy 312.319617 -351.94688) (xy 312.273737 -351.917396) (xy 312.232521 -351.881682)
			(xy 312.196807 -351.840466) (xy 312.167321 -351.794587) (xy 312.144666 -351.744978) (xy 312.129301 -351.69265)
			(xy 312.121539 -351.638668) (xy 300.231613 -351.638668) (xy 300.231613 -351.638672) (xy 300.223851 -351.692661)
			(xy 300.208484 -351.744995) (xy 300.185826 -351.79461) (xy 300.156337 -351.840496) (xy 300.120619 -351.881717)
			(xy 300.079397 -351.917436) (xy 300.033512 -351.946925) (xy 299.983897 -351.969584) (xy 299.931563 -351.984951)
			(xy 299.877574 -351.992713) (xy 299.850302 -351.9932) (xy 298.986702 -351.9932) (xy 298.959434 -351.992661)
			(xy 298.905452 -351.9849) (xy 298.853124 -351.969535) (xy 298.803516 -351.94688) (xy 298.757636 -351.917395)
			(xy 298.71642 -351.881681) (xy 298.680706 -351.840465) (xy 298.651221 -351.794586) (xy 298.628566 -351.744978)
			(xy 298.613201 -351.69265) (xy 298.605439 -351.638668) (xy 297.122614 -351.638668) (xy 297.122614 -351.63867)
			(xy 297.114852 -351.692655) (xy 297.099488 -351.744987) (xy 297.076832 -351.794599) (xy 297.047347 -351.840483)
			(xy 297.011633 -351.881703) (xy 296.970416 -351.917422) (xy 296.924536 -351.946912) (xy 296.874926 -351.969573)
			(xy 296.822597 -351.984943) (xy 296.768612 -351.992711) (xy 296.741342 -351.9932) (xy 295.877742 -351.9932)
			(xy 295.850472 -351.992663) (xy 295.796486 -351.984907) (xy 295.744153 -351.969546) (xy 295.69454 -351.946893)
			(xy 295.648655 -351.917409) (xy 295.607434 -351.881695) (xy 295.571716 -351.840478) (xy 295.542227 -351.794597)
			(xy 295.519569 -351.744986) (xy 295.504202 -351.692655) (xy 295.49644 -351.63867) (xy 294.013736 -351.63867)
			(xy 294.013736 -351.638675) (xy 294.005973 -351.692668) (xy 293.990604 -351.745008) (xy 293.967943 -351.794627)
			(xy 293.938451 -351.840516) (xy 293.902728 -351.881741) (xy 293.861502 -351.917462) (xy 293.815611 -351.946952)
			(xy 293.765991 -351.969611) (xy 293.713651 -351.984977) (xy 293.659657 -351.992738) (xy 293.632382 -351.9932)
			(xy 292.768782 -351.9932) (xy 292.741516 -351.992636) (xy 292.68754 -351.984873) (xy 292.635218 -351.969508)
			(xy 292.585615 -351.946853) (xy 292.539741 -351.91737) (xy 292.498529 -351.881658) (xy 292.46282 -351.840445)
			(xy 292.433338 -351.794569) (xy 292.410686 -351.744965) (xy 292.395323 -351.692642) (xy 292.387562 -351.638666)
			(xy 290.904714 -351.638666) (xy 290.904714 -351.638671) (xy 290.896952 -351.692658) (xy 290.881586 -351.744991)
			(xy 290.858929 -351.794605) (xy 290.829442 -351.840489) (xy 290.793726 -351.88171) (xy 290.752507 -351.917429)
			(xy 290.706624 -351.946919) (xy 290.657012 -351.969578) (xy 290.60468 -351.984947) (xy 290.550693 -351.992712)
			(xy 290.523422 -351.9932) (xy 289.659822 -351.9932) (xy 289.632553 -351.992662) (xy 289.578569 -351.984903)
			(xy 289.526239 -351.96954) (xy 289.476628 -351.946886) (xy 289.430746 -351.917402) (xy 289.389527 -351.881688)
			(xy 289.353811 -351.840472) (xy 289.324324 -351.794592) (xy 289.301667 -351.744982) (xy 289.286301 -351.692653)
			(xy 289.278539 -351.638669) (xy 287.795836 -351.638669) (xy 287.795836 -351.638675) (xy 287.788072 -351.692671)
			(xy 287.772703 -351.745012) (xy 287.75004 -351.794633) (xy 287.720546 -351.840523) (xy 287.684821 -351.881748)
			(xy 287.643592 -351.917469) (xy 287.597699 -351.946958) (xy 287.548076 -351.969616) (xy 287.495734 -351.98498)
			(xy 287.441737 -351.992739) (xy 287.414462 -351.9932) (xy 286.550862 -351.9932) (xy 286.523597 -351.992635)
			(xy 286.469623 -351.98487) (xy 286.417303 -351.969503) (xy 286.367703 -351.946847) (xy 286.321831 -351.917363)
			(xy 286.280622 -351.881651) (xy 286.244915 -351.840438) (xy 286.215435 -351.794564) (xy 286.192784 -351.744961)
			(xy 286.177422 -351.69264) (xy 286.169662 -351.638665) (xy 284.686813 -351.638665) (xy 284.686813 -351.638672)
			(xy 284.679051 -351.692661) (xy 284.663684 -351.744995) (xy 284.641026 -351.79461) (xy 284.611537 -351.840496)
			(xy 284.575819 -351.881717) (xy 284.534597 -351.917436) (xy 284.488712 -351.946925) (xy 284.439097 -351.969584)
			(xy 284.386763 -351.984951) (xy 284.332774 -351.992713) (xy 284.305502 -351.9932) (xy 283.441902 -351.9932)
			(xy 283.414634 -351.992661) (xy 283.360652 -351.9849) (xy 283.308324 -351.969535) (xy 283.258716 -351.94688)
			(xy 283.212836 -351.917395) (xy 283.17162 -351.881681) (xy 283.135906 -351.840465) (xy 283.106421 -351.794586)
			(xy 283.083766 -351.744978) (xy 283.068401 -351.69265) (xy 283.060639 -351.638668) (xy 281.577814 -351.638668)
			(xy 281.577814 -351.63867) (xy 281.570052 -351.692655) (xy 281.554688 -351.744987) (xy 281.532032 -351.794599)
			(xy 281.502547 -351.840483) (xy 281.466833 -351.881703) (xy 281.425616 -351.917422) (xy 281.379736 -351.946912)
			(xy 281.330126 -351.969573) (xy 281.277797 -351.984943) (xy 281.223812 -351.992711) (xy 281.196542 -351.9932)
			(xy 280.332942 -351.9932) (xy 280.305672 -351.992663) (xy 280.251686 -351.984907) (xy 280.199353 -351.969546)
			(xy 280.14974 -351.946893) (xy 280.103855 -351.917409) (xy 280.062634 -351.881695) (xy 280.026916 -351.840478)
			(xy 279.997427 -351.794597) (xy 279.974769 -351.744986) (xy 279.959402 -351.692655) (xy 279.95164 -351.63867)
			(xy 278.468936 -351.63867) (xy 278.468936 -351.638675) (xy 278.461173 -351.692668) (xy 278.445804 -351.745008)
			(xy 278.423143 -351.794627) (xy 278.393651 -351.840516) (xy 278.357928 -351.881741) (xy 278.316702 -351.917462)
			(xy 278.270811 -351.946952) (xy 278.221191 -351.969611) (xy 278.168851 -351.984977) (xy 278.114857 -351.992738)
			(xy 278.087582 -351.9932) (xy 277.223982 -351.9932) (xy 277.196716 -351.992636) (xy 277.14274 -351.984873)
			(xy 277.090418 -351.969508) (xy 277.040815 -351.946853) (xy 276.994941 -351.91737) (xy 276.953729 -351.881658)
			(xy 276.91802 -351.840445) (xy 276.888538 -351.794569) (xy 276.865886 -351.744965) (xy 276.850523 -351.692642)
			(xy 276.842762 -351.638666) (xy 275.359914 -351.638666) (xy 275.359914 -351.638671) (xy 275.352152 -351.692658)
			(xy 275.336786 -351.744991) (xy 275.314129 -351.794605) (xy 275.284642 -351.840489) (xy 275.248926 -351.88171)
			(xy 275.207707 -351.917429) (xy 275.161824 -351.946919) (xy 275.112212 -351.969578) (xy 275.05988 -351.984947)
			(xy 275.005893 -351.992712) (xy 274.978622 -351.9932) (xy 274.115022 -351.9932) (xy 274.087753 -351.992662)
			(xy 274.033769 -351.984903) (xy 273.981439 -351.96954) (xy 273.931828 -351.946886) (xy 273.885946 -351.917402)
			(xy 273.844727 -351.881688) (xy 273.809011 -351.840472) (xy 273.779524 -351.794592) (xy 273.756867 -351.744982)
			(xy 273.741501 -351.692653) (xy 273.733739 -351.638669) (xy 272.251036 -351.638669) (xy 272.251036 -351.638675)
			(xy 272.243272 -351.692671) (xy 272.227903 -351.745012) (xy 272.20524 -351.794633) (xy 272.175746 -351.840523)
			(xy 272.140021 -351.881748) (xy 272.098792 -351.917469) (xy 272.052899 -351.946958) (xy 272.003276 -351.969616)
			(xy 271.950934 -351.98498) (xy 271.896937 -351.992739) (xy 271.869662 -351.9932) (xy 271.006062 -351.9932)
			(xy 270.978797 -351.992635) (xy 270.924823 -351.98487) (xy 270.872503 -351.969503) (xy 270.822903 -351.946847)
			(xy 270.777031 -351.917363) (xy 270.735822 -351.881651) (xy 270.700115 -351.840438) (xy 270.670635 -351.794564)
			(xy 270.647984 -351.744961) (xy 270.632622 -351.69264) (xy 270.624862 -351.638665) (xy 269.142013 -351.638665)
			(xy 269.142013 -351.638672) (xy 269.134251 -351.692661) (xy 269.118884 -351.744995) (xy 269.096226 -351.79461)
			(xy 269.066737 -351.840496) (xy 269.031019 -351.881717) (xy 268.989797 -351.917436) (xy 268.943912 -351.946925)
			(xy 268.894297 -351.969584) (xy 268.841963 -351.984951) (xy 268.787974 -351.992713) (xy 268.760702 -351.9932)
			(xy 267.897102 -351.9932) (xy 267.869834 -351.992661) (xy 267.815852 -351.9849) (xy 267.763524 -351.969535)
			(xy 267.713916 -351.94688) (xy 267.668036 -351.917395) (xy 267.62682 -351.881681) (xy 267.591106 -351.840465)
			(xy 267.561621 -351.794586) (xy 267.538966 -351.744978) (xy 267.523601 -351.69265) (xy 267.515839 -351.638668)
			(xy 194.520614 -351.638668) (xy 194.520614 -351.638672) (xy 194.512851 -351.692659) (xy 194.497485 -351.744993)
			(xy 194.474828 -351.794608) (xy 194.44534 -351.840492) (xy 194.409622 -351.881714) (xy 194.368402 -351.917433)
			(xy 194.322518 -351.946922) (xy 194.272904 -351.969581) (xy 194.220571 -351.984949) (xy 194.166584 -351.992713)
			(xy 194.139312 -351.9932) (xy 193.275712 -351.9932) (xy 193.248443 -351.992661) (xy 193.19446 -351.984901)
			(xy 193.142131 -351.969538) (xy 193.092522 -351.946883) (xy 193.046641 -351.917399) (xy 193.005424 -351.881685)
			(xy 192.969708 -351.840469) (xy 192.940223 -351.794589) (xy 192.917566 -351.74498) (xy 192.902201 -351.692651)
			(xy 192.894439 -351.638669) (xy 191.411736 -351.638669) (xy 191.411736 -351.638676) (xy 191.403972 -351.692672)
			(xy 191.388602 -351.745014) (xy 191.365939 -351.794635) (xy 191.336444 -351.840526) (xy 191.300717 -351.881751)
			(xy 191.259487 -351.917472) (xy 191.213593 -351.946962) (xy 191.163969 -351.969619) (xy 191.111625 -351.984982)
			(xy 191.057628 -351.99274) (xy 191.030352 -351.9932) (xy 190.166752 -351.9932) (xy 190.139488 -351.992634)
			(xy 190.085515 -351.984868) (xy 190.033196 -351.9695) (xy 189.983597 -351.946843) (xy 189.937726 -351.917359)
			(xy 189.896519 -351.881647) (xy 189.860812 -351.840435) (xy 189.831334 -351.794561) (xy 189.808683 -351.744959)
			(xy 189.793322 -351.692639) (xy 189.785562 -351.638664) (xy 188.302736 -351.638664) (xy 188.302736 -351.638674)
			(xy 188.294973 -351.692667) (xy 188.279605 -351.745006) (xy 188.256945 -351.794624) (xy 188.227453 -351.840513)
			(xy 188.191732 -351.881737) (xy 188.150506 -351.917458) (xy 188.104617 -351.946949) (xy 188.054998 -351.969608)
			(xy 188.002659 -351.984975) (xy 187.948666 -351.992737) (xy 187.921392 -351.9932) (xy 187.057792 -351.9932)
			(xy 187.030526 -351.992637) (xy 186.976548 -351.984875) (xy 186.924225 -351.969511) (xy 186.874621 -351.946856)
			(xy 186.828745 -351.917373) (xy 186.787533 -351.881662) (xy 186.751822 -351.840448) (xy 186.72234 -351.794572)
			(xy 186.699686 -351.744968) (xy 186.684323 -351.692644) (xy 186.676562 -351.638666) (xy 185.193714 -351.638666)
			(xy 185.193714 -351.638671) (xy 185.185952 -351.692657) (xy 185.170587 -351.744989) (xy 185.147931 -351.794602)
			(xy 185.118445 -351.840486) (xy 185.082729 -351.881707) (xy 185.041512 -351.917426) (xy 184.99563 -351.946915)
			(xy 184.946019 -351.969576) (xy 184.893688 -351.984945) (xy 184.839703 -351.992711) (xy 184.812432 -351.9932)
			(xy 183.948832 -351.9932) (xy 183.921562 -351.992663) (xy 183.867577 -351.984905) (xy 183.815246 -351.969543)
			(xy 183.765634 -351.94689) (xy 183.719751 -351.917406) (xy 183.678531 -351.881692) (xy 183.642813 -351.840475)
			(xy 183.613326 -351.794594) (xy 183.590668 -351.744984) (xy 183.575302 -351.692654) (xy 183.567539 -351.63867)
			(xy 182.084836 -351.63867) (xy 182.084836 -351.638675) (xy 182.077073 -351.69267) (xy 182.061703 -351.74501)
			(xy 182.039042 -351.79463) (xy 182.009548 -351.840519) (xy 181.973824 -351.881744) (xy 181.932597 -351.917465)
			(xy 181.886705 -351.946955) (xy 181.837084 -351.969613) (xy 181.784742 -351.984979) (xy 181.730747 -351.992738)
			(xy 181.703472 -351.9932) (xy 180.839872 -351.9932) (xy 180.812607 -351.992636) (xy 180.758631 -351.984872)
			(xy 180.70631 -351.969505) (xy 180.656709 -351.94685) (xy 180.610836 -351.917366) (xy 180.569626 -351.881654)
			(xy 180.533917 -351.840442) (xy 180.504437 -351.794567) (xy 180.481785 -351.744963) (xy 180.466422 -351.692641)
			(xy 180.458662 -351.638665) (xy 178.975814 -351.638665) (xy 178.975814 -351.638672) (xy 178.968051 -351.692659)
			(xy 178.952685 -351.744993) (xy 178.930028 -351.794608) (xy 178.90054 -351.840492) (xy 178.864822 -351.881714)
			(xy 178.823602 -351.917433) (xy 178.777718 -351.946922) (xy 178.728104 -351.969581) (xy 178.675771 -351.984949)
			(xy 178.621784 -351.992713) (xy 178.594512 -351.9932) (xy 177.730912 -351.9932) (xy 177.703643 -351.992661)
			(xy 177.64966 -351.984901) (xy 177.597331 -351.969538) (xy 177.547722 -351.946883) (xy 177.501841 -351.917399)
			(xy 177.460624 -351.881685) (xy 177.424908 -351.840469) (xy 177.395423 -351.794589) (xy 177.372766 -351.74498)
			(xy 177.357401 -351.692651) (xy 177.349639 -351.638669) (xy 175.866936 -351.638669) (xy 175.866936 -351.638676)
			(xy 175.859172 -351.692672) (xy 175.843802 -351.745014) (xy 175.821139 -351.794635) (xy 175.791644 -351.840526)
			(xy 175.755917 -351.881751) (xy 175.714687 -351.917472) (xy 175.668793 -351.946962) (xy 175.619169 -351.969619)
			(xy 175.566825 -351.984982) (xy 175.512828 -351.99274) (xy 175.485552 -351.9932) (xy 174.621952 -351.9932)
			(xy 174.594688 -351.992634) (xy 174.540715 -351.984868) (xy 174.488396 -351.9695) (xy 174.438797 -351.946843)
			(xy 174.392926 -351.917359) (xy 174.351719 -351.881647) (xy 174.316012 -351.840435) (xy 174.286534 -351.794561)
			(xy 174.263883 -351.744959) (xy 174.248522 -351.692639) (xy 174.240762 -351.638664) (xy 172.757936 -351.638664)
			(xy 172.757936 -351.638674) (xy 172.750173 -351.692667) (xy 172.734805 -351.745006) (xy 172.712145 -351.794624)
			(xy 172.682653 -351.840513) (xy 172.646932 -351.881737) (xy 172.605706 -351.917458) (xy 172.559817 -351.946949)
			(xy 172.510198 -351.969608) (xy 172.457859 -351.984975) (xy 172.403866 -351.992737) (xy 172.376592 -351.9932)
			(xy 171.512992 -351.9932) (xy 171.485726 -351.992637) (xy 171.431748 -351.984875) (xy 171.379425 -351.969511)
			(xy 171.329821 -351.946856) (xy 171.283945 -351.917373) (xy 171.242733 -351.881662) (xy 171.207022 -351.840448)
			(xy 171.17754 -351.794572) (xy 171.154886 -351.744968) (xy 171.139523 -351.692644) (xy 171.131762 -351.638666)
			(xy 169.648914 -351.638666) (xy 169.648914 -351.638671) (xy 169.641152 -351.692657) (xy 169.625787 -351.744989)
			(xy 169.603131 -351.794602) (xy 169.573645 -351.840486) (xy 169.537929 -351.881707) (xy 169.496712 -351.917426)
			(xy 169.45083 -351.946915) (xy 169.401219 -351.969576) (xy 169.348888 -351.984945) (xy 169.294903 -351.992711)
			(xy 169.267632 -351.9932) (xy 168.404032 -351.9932) (xy 168.376762 -351.992663) (xy 168.322777 -351.984905)
			(xy 168.270446 -351.969543) (xy 168.220834 -351.94689) (xy 168.174951 -351.917406) (xy 168.133731 -351.881692)
			(xy 168.098013 -351.840475) (xy 168.068526 -351.794594) (xy 168.045868 -351.744984) (xy 168.030502 -351.692654)
			(xy 168.022739 -351.63867) (xy 166.540036 -351.63867) (xy 166.540036 -351.638675) (xy 166.532273 -351.69267)
			(xy 166.516903 -351.74501) (xy 166.494242 -351.79463) (xy 166.464748 -351.840519) (xy 166.429024 -351.881744)
			(xy 166.387797 -351.917465) (xy 166.341905 -351.946955) (xy 166.292284 -351.969613) (xy 166.239942 -351.984979)
			(xy 166.185947 -351.992738) (xy 166.158672 -351.9932) (xy 165.295072 -351.9932) (xy 165.267807 -351.992636)
			(xy 165.213831 -351.984872) (xy 165.16151 -351.969505) (xy 165.111909 -351.94685) (xy 165.066036 -351.917366)
			(xy 165.024826 -351.881654) (xy 164.989117 -351.840442) (xy 164.959637 -351.794567) (xy 164.936985 -351.744963)
			(xy 164.921622 -351.692641) (xy 164.913862 -351.638665) (xy 163.431014 -351.638665) (xy 163.431014 -351.638672)
			(xy 163.423251 -351.692659) (xy 163.407885 -351.744993) (xy 163.385228 -351.794608) (xy 163.35574 -351.840492)
			(xy 163.320022 -351.881714) (xy 163.278802 -351.917433) (xy 163.232918 -351.946922) (xy 163.183304 -351.969581)
			(xy 163.130971 -351.984949) (xy 163.076984 -351.992713) (xy 163.049712 -351.9932) (xy 162.186112 -351.9932)
			(xy 162.158843 -351.992661) (xy 162.10486 -351.984901) (xy 162.052531 -351.969538) (xy 162.002922 -351.946883)
			(xy 161.957041 -351.917399) (xy 161.915824 -351.881685) (xy 161.880108 -351.840469) (xy 161.850623 -351.794589)
			(xy 161.827966 -351.74498) (xy 161.812601 -351.692651) (xy 161.804839 -351.638669) (xy 144.196614 -351.638669)
			(xy 144.196614 -351.638672) (xy 144.188851 -351.69266) (xy 144.173485 -351.744994) (xy 144.150827 -351.794609)
			(xy 144.121339 -351.840494) (xy 144.085621 -351.881715) (xy 144.0444 -351.917434) (xy 143.998516 -351.946923)
			(xy 143.948902 -351.969582) (xy 143.896568 -351.98495) (xy 143.84258 -351.992713) (xy 143.815308 -351.9932)
			(xy 142.951708 -351.9932) (xy 142.924439 -351.992661) (xy 142.870457 -351.984901) (xy 142.818129 -351.969537)
			(xy 142.768519 -351.946882) (xy 142.722639 -351.917397) (xy 142.681422 -351.881683) (xy 142.645707 -351.840467)
			(xy 142.616222 -351.794588) (xy 142.593566 -351.744979) (xy 142.578201 -351.692651) (xy 142.570439 -351.638669)
			(xy 141.087614 -351.638669) (xy 141.087614 -351.63867) (xy 141.079852 -351.692655) (xy 141.064488 -351.744986)
			(xy 141.041833 -351.794597) (xy 141.012349 -351.840481) (xy 140.976635 -351.881701) (xy 140.935419 -351.91742)
			(xy 140.88954 -351.94691) (xy 140.839931 -351.969571) (xy 140.787602 -351.984942) (xy 140.733618 -351.99271)
			(xy 140.706348 -351.9932) (xy 139.842748 -351.9932) (xy 139.815477 -351.992664) (xy 139.761491 -351.984908)
			(xy 139.709158 -351.969547) (xy 139.659543 -351.946895) (xy 139.613658 -351.917411) (xy 139.572436 -351.881698)
			(xy 139.536717 -351.84048) (xy 139.507228 -351.794599) (xy 139.484569 -351.744987) (xy 139.469202 -351.692656)
			(xy 139.46144 -351.63867) (xy 137.978736 -351.63867) (xy 137.978736 -351.638674) (xy 137.970973 -351.692668)
			(xy 137.955605 -351.745006) (xy 137.932944 -351.794625) (xy 137.903452 -351.840514) (xy 137.86773 -351.881739)
			(xy 137.826504 -351.91746) (xy 137.780615 -351.94695) (xy 137.730995 -351.969609) (xy 137.678656 -351.984976)
			(xy 137.624662 -351.992737) (xy 137.597388 -351.9932) (xy 136.733788 -351.9932) (xy 136.706522 -351.992637)
			(xy 136.652545 -351.984875) (xy 136.600222 -351.96951) (xy 136.550618 -351.946855) (xy 136.504744 -351.917372)
			(xy 136.463531 -351.88166) (xy 136.427821 -351.840447) (xy 136.398339 -351.794571) (xy 136.375686 -351.744967)
			(xy 136.360323 -351.692643) (xy 136.352562 -351.638666) (xy 134.869714 -351.638666) (xy 134.869714 -351.638671)
			(xy 134.861952 -351.692657) (xy 134.846586 -351.74499) (xy 134.82393 -351.794603) (xy 134.794444 -351.840487)
			(xy 134.758728 -351.881708) (xy 134.71751 -351.917427) (xy 134.671628 -351.946917) (xy 134.622016 -351.969577)
			(xy 134.569685 -351.984946) (xy 134.515699 -351.992712) (xy 134.488428 -351.9932) (xy 133.624828 -351.9932)
			(xy 133.597558 -351.992663) (xy 133.543574 -351.984904) (xy 133.491243 -351.969542) (xy 133.441631 -351.946888)
			(xy 133.395749 -351.917404) (xy 133.354529 -351.881691) (xy 133.318812 -351.840474) (xy 133.289325 -351.794593)
			(xy 133.266668 -351.744983) (xy 133.251302 -351.692654) (xy 133.243539 -351.63867) (xy 131.760836 -351.63867)
			(xy 131.760836 -351.638675) (xy 131.753073 -351.69267) (xy 131.737703 -351.745011) (xy 131.715041 -351.794631)
			(xy 131.685547 -351.840521) (xy 131.649823 -351.881746) (xy 131.608595 -351.917467) (xy 131.562703 -351.946956)
			(xy 131.513081 -351.969614) (xy 131.460739 -351.984979) (xy 131.406743 -351.992739) (xy 131.379468 -351.9932)
			(xy 130.515868 -351.9932) (xy 130.488603 -351.992635) (xy 130.434628 -351.984871) (xy 130.382308 -351.969504)
			(xy 130.332706 -351.946849) (xy 130.286834 -351.917365) (xy 130.245624 -351.881653) (xy 130.209916 -351.84044)
			(xy 130.180436 -351.794566) (xy 130.157784 -351.744962) (xy 130.142422 -351.692641) (xy 130.134662 -351.638665)
			(xy 128.651814 -351.638665) (xy 128.651814 -351.638672) (xy 128.644051 -351.69266) (xy 128.628685 -351.744994)
			(xy 128.606027 -351.794609) (xy 128.576539 -351.840494) (xy 128.540821 -351.881715) (xy 128.4996 -351.917434)
			(xy 128.453716 -351.946923) (xy 128.404102 -351.969582) (xy 128.351768 -351.98495) (xy 128.29778 -351.992713)
			(xy 128.270508 -351.9932) (xy 127.406908 -351.9932) (xy 127.379639 -351.992661) (xy 127.325657 -351.984901)
			(xy 127.273329 -351.969537) (xy 127.223719 -351.946882) (xy 127.177839 -351.917397) (xy 127.136622 -351.881683)
			(xy 127.100907 -351.840467) (xy 127.071422 -351.794588) (xy 127.048766 -351.744979) (xy 127.033401 -351.692651)
			(xy 127.025639 -351.638669) (xy 125.542814 -351.638669) (xy 125.542814 -351.63867) (xy 125.535052 -351.692655)
			(xy 125.519688 -351.744986) (xy 125.497033 -351.794597) (xy 125.467549 -351.840481) (xy 125.431835 -351.881701)
			(xy 125.390619 -351.91742) (xy 125.34474 -351.94691) (xy 125.295131 -351.969571) (xy 125.242802 -351.984942)
			(xy 125.188818 -351.99271) (xy 125.161548 -351.9932) (xy 124.297948 -351.9932) (xy 124.270677 -351.992664)
			(xy 124.216691 -351.984908) (xy 124.164358 -351.969547) (xy 124.114743 -351.946895) (xy 124.068858 -351.917411)
			(xy 124.027636 -351.881698) (xy 123.991917 -351.84048) (xy 123.962428 -351.794599) (xy 123.939769 -351.744987)
			(xy 123.924402 -351.692656) (xy 123.91664 -351.63867) (xy 122.433936 -351.63867) (xy 122.433936 -351.638674)
			(xy 122.426173 -351.692668) (xy 122.410805 -351.745006) (xy 122.388144 -351.794625) (xy 122.358652 -351.840514)
			(xy 122.32293 -351.881739) (xy 122.281704 -351.91746) (xy 122.235815 -351.94695) (xy 122.186195 -351.969609)
			(xy 122.133856 -351.984976) (xy 122.079862 -351.992737) (xy 122.052588 -351.9932) (xy 121.188988 -351.9932)
			(xy 121.161722 -351.992637) (xy 121.107745 -351.984875) (xy 121.055422 -351.96951) (xy 121.005818 -351.946855)
			(xy 120.959944 -351.917372) (xy 120.918731 -351.88166) (xy 120.883021 -351.840447) (xy 120.853539 -351.794571)
			(xy 120.830886 -351.744967) (xy 120.815523 -351.692643) (xy 120.807762 -351.638666) (xy 119.324914 -351.638666)
			(xy 119.324914 -351.638671) (xy 119.317152 -351.692657) (xy 119.301786 -351.74499) (xy 119.27913 -351.794603)
			(xy 119.249644 -351.840487) (xy 119.213928 -351.881708) (xy 119.17271 -351.917427) (xy 119.126828 -351.946917)
			(xy 119.077216 -351.969577) (xy 119.024885 -351.984946) (xy 118.970899 -351.992712) (xy 118.943628 -351.9932)
			(xy 118.080028 -351.9932) (xy 118.052758 -351.992663) (xy 117.998774 -351.984904) (xy 117.946443 -351.969542)
			(xy 117.896831 -351.946888) (xy 117.850949 -351.917404) (xy 117.809729 -351.881691) (xy 117.774012 -351.840474)
			(xy 117.744525 -351.794593) (xy 117.721868 -351.744983) (xy 117.706502 -351.692654) (xy 117.698739 -351.63867)
			(xy 116.216036 -351.63867) (xy 116.216036 -351.638675) (xy 116.208273 -351.69267) (xy 116.192903 -351.745011)
			(xy 116.170241 -351.794631) (xy 116.140747 -351.840521) (xy 116.105023 -351.881746) (xy 116.063795 -351.917467)
			(xy 116.017903 -351.946956) (xy 115.968281 -351.969614) (xy 115.915939 -351.984979) (xy 115.861943 -351.992739)
			(xy 115.834668 -351.9932) (xy 114.971068 -351.9932) (xy 114.943803 -351.992635) (xy 114.889828 -351.984871)
			(xy 114.837508 -351.969504) (xy 114.787906 -351.946849) (xy 114.742034 -351.917365) (xy 114.700824 -351.881653)
			(xy 114.665116 -351.84044) (xy 114.635636 -351.794566) (xy 114.612984 -351.744962) (xy 114.597622 -351.692641)
			(xy 114.589862 -351.638665) (xy 113.107014 -351.638665) (xy 113.107014 -351.638672) (xy 113.099251 -351.69266)
			(xy 113.083885 -351.744994) (xy 113.061227 -351.794609) (xy 113.031739 -351.840494) (xy 112.996021 -351.881715)
			(xy 112.9548 -351.917434) (xy 112.908916 -351.946923) (xy 112.859302 -351.969582) (xy 112.806968 -351.98495)
			(xy 112.75298 -351.992713) (xy 112.725708 -351.9932) (xy 111.862108 -351.9932) (xy 111.834839 -351.992661)
			(xy 111.780857 -351.984901) (xy 111.728529 -351.969537) (xy 111.678919 -351.946882) (xy 111.633039 -351.917397)
			(xy 111.591822 -351.881683) (xy 111.556107 -351.840467) (xy 111.526622 -351.794588) (xy 111.503966 -351.744979)
			(xy 111.488601 -351.692651) (xy 111.480839 -351.638669) (xy 93.706714 -351.638669) (xy 93.706714 -351.63867)
			(xy 93.698952 -351.692655) (xy 93.683588 -351.744987) (xy 93.660932 -351.794599) (xy 93.631447 -351.840483)
			(xy 93.595733 -351.881703) (xy 93.554516 -351.917422) (xy 93.508636 -351.946912) (xy 93.459026 -351.969573)
			(xy 93.406697 -351.984943) (xy 93.352712 -351.992711) (xy 93.325442 -351.9932) (xy 92.461842 -351.9932)
			(xy 92.434572 -351.992663) (xy 92.380586 -351.984907) (xy 92.328253 -351.969546) (xy 92.27864 -351.946893)
			(xy 92.232755 -351.917409) (xy 92.191534 -351.881695) (xy 92.155816 -351.840478) (xy 92.126327 -351.794597)
			(xy 92.103669 -351.744986) (xy 92.088302 -351.692655) (xy 92.08054 -351.63867) (xy 90.597836 -351.63867)
			(xy 90.597836 -351.638675) (xy 90.590073 -351.692668) (xy 90.574704 -351.745008) (xy 90.552043 -351.794627)
			(xy 90.522551 -351.840516) (xy 90.486828 -351.881741) (xy 90.445602 -351.917462) (xy 90.399711 -351.946952)
			(xy 90.350091 -351.969611) (xy 90.297751 -351.984977) (xy 90.243757 -351.992738) (xy 90.216482 -351.9932)
			(xy 89.352882 -351.9932) (xy 89.325616 -351.992636) (xy 89.27164 -351.984873) (xy 89.219318 -351.969508)
			(xy 89.169715 -351.946853) (xy 89.123841 -351.91737) (xy 89.082629 -351.881658) (xy 89.04692 -351.840445)
			(xy 89.017438 -351.794569) (xy 88.994786 -351.744965) (xy 88.979423 -351.692642) (xy 88.971662 -351.638666)
			(xy 87.488814 -351.638666) (xy 87.488814 -351.638671) (xy 87.481052 -351.692658) (xy 87.465686 -351.744991)
			(xy 87.443029 -351.794605) (xy 87.413542 -351.840489) (xy 87.377826 -351.88171) (xy 87.336607 -351.917429)
			(xy 87.290724 -351.946919) (xy 87.241112 -351.969578) (xy 87.18878 -351.984947) (xy 87.134793 -351.992712)
			(xy 87.107522 -351.9932) (xy 86.243922 -351.9932) (xy 86.216653 -351.992662) (xy 86.162669 -351.984903)
			(xy 86.110339 -351.96954) (xy 86.060728 -351.946886) (xy 86.014846 -351.917402) (xy 85.973627 -351.881688)
			(xy 85.937911 -351.840472) (xy 85.908424 -351.794592) (xy 85.885767 -351.744982) (xy 85.870401 -351.692653)
			(xy 85.862639 -351.638669) (xy 84.379936 -351.638669) (xy 84.379936 -351.638675) (xy 84.372172 -351.692671)
			(xy 84.356803 -351.745012) (xy 84.33414 -351.794633) (xy 84.304646 -351.840523) (xy 84.268921 -351.881748)
			(xy 84.227692 -351.917469) (xy 84.181799 -351.946958) (xy 84.132176 -351.969616) (xy 84.079834 -351.98498)
			(xy 84.025837 -351.992739) (xy 83.998562 -351.9932) (xy 83.134962 -351.9932) (xy 83.107697 -351.992635)
			(xy 83.053723 -351.98487) (xy 83.001403 -351.969503) (xy 82.951803 -351.946847) (xy 82.905931 -351.917363)
			(xy 82.864722 -351.881651) (xy 82.829015 -351.840438) (xy 82.799535 -351.794564) (xy 82.776884 -351.744961)
			(xy 82.761522 -351.69264) (xy 82.753762 -351.638665) (xy 81.270913 -351.638665) (xy 81.270913 -351.638672)
			(xy 81.263151 -351.692661) (xy 81.247784 -351.744995) (xy 81.225126 -351.79461) (xy 81.195637 -351.840496)
			(xy 81.159919 -351.881717) (xy 81.118697 -351.917436) (xy 81.072812 -351.946925) (xy 81.023197 -351.969584)
			(xy 80.970863 -351.984951) (xy 80.916874 -351.992713) (xy 80.889602 -351.9932) (xy 80.026002 -351.9932)
			(xy 79.998734 -351.992661) (xy 79.944752 -351.9849) (xy 79.892424 -351.969535) (xy 79.842816 -351.94688)
			(xy 79.796936 -351.917395) (xy 79.75572 -351.881681) (xy 79.720006 -351.840465) (xy 79.690521 -351.794586)
			(xy 79.667866 -351.744978) (xy 79.652501 -351.69265) (xy 79.644739 -351.638668) (xy 78.161914 -351.638668)
			(xy 78.161914 -351.63867) (xy 78.154152 -351.692655) (xy 78.138788 -351.744987) (xy 78.116132 -351.794599)
			(xy 78.086647 -351.840483) (xy 78.050933 -351.881703) (xy 78.009716 -351.917422) (xy 77.963836 -351.946912)
			(xy 77.914226 -351.969573) (xy 77.861897 -351.984943) (xy 77.807912 -351.992711) (xy 77.780642 -351.9932)
			(xy 76.917042 -351.9932) (xy 76.889772 -351.992663) (xy 76.835786 -351.984907) (xy 76.783453 -351.969546)
			(xy 76.73384 -351.946893) (xy 76.687955 -351.917409) (xy 76.646734 -351.881695) (xy 76.611016 -351.840478)
			(xy 76.581527 -351.794597) (xy 76.558869 -351.744986) (xy 76.543502 -351.692655) (xy 76.53574 -351.63867)
			(xy 75.053036 -351.63867) (xy 75.053036 -351.638675) (xy 75.045273 -351.692668) (xy 75.029904 -351.745008)
			(xy 75.007243 -351.794627) (xy 74.977751 -351.840516) (xy 74.942028 -351.881741) (xy 74.900802 -351.917462)
			(xy 74.854911 -351.946952) (xy 74.805291 -351.969611) (xy 74.752951 -351.984977) (xy 74.698957 -351.992738)
			(xy 74.671682 -351.9932) (xy 73.808082 -351.9932) (xy 73.780816 -351.992636) (xy 73.72684 -351.984873)
			(xy 73.674518 -351.969508) (xy 73.624915 -351.946853) (xy 73.579041 -351.91737) (xy 73.537829 -351.881658)
			(xy 73.50212 -351.840445) (xy 73.472638 -351.794569) (xy 73.449986 -351.744965) (xy 73.434623 -351.692642)
			(xy 73.426862 -351.638666) (xy 71.944014 -351.638666) (xy 71.944014 -351.638671) (xy 71.936252 -351.692658)
			(xy 71.920886 -351.744991) (xy 71.898229 -351.794605) (xy 71.868742 -351.840489) (xy 71.833026 -351.88171)
			(xy 71.791807 -351.917429) (xy 71.745924 -351.946919) (xy 71.696312 -351.969578) (xy 71.64398 -351.984947)
			(xy 71.589993 -351.992712) (xy 71.562722 -351.9932) (xy 70.699122 -351.9932) (xy 70.671853 -351.992662)
			(xy 70.617869 -351.984903) (xy 70.565539 -351.96954) (xy 70.515928 -351.946886) (xy 70.470046 -351.917402)
			(xy 70.428827 -351.881688) (xy 70.393111 -351.840472) (xy 70.363624 -351.794592) (xy 70.340967 -351.744982)
			(xy 70.325601 -351.692653) (xy 70.317839 -351.638669) (xy 68.835136 -351.638669) (xy 68.835136 -351.638675)
			(xy 68.827372 -351.692671) (xy 68.812003 -351.745012) (xy 68.78934 -351.794633) (xy 68.759846 -351.840523)
			(xy 68.724121 -351.881748) (xy 68.682892 -351.917469) (xy 68.636999 -351.946958) (xy 68.587376 -351.969616)
			(xy 68.535034 -351.98498) (xy 68.481037 -351.992739) (xy 68.453762 -351.9932) (xy 67.590162 -351.9932)
			(xy 67.562897 -351.992635) (xy 67.508923 -351.98487) (xy 67.456603 -351.969503) (xy 67.407003 -351.946847)
			(xy 67.361131 -351.917363) (xy 67.319922 -351.881651) (xy 67.284215 -351.840438) (xy 67.254735 -351.794564)
			(xy 67.232084 -351.744961) (xy 67.216722 -351.69264) (xy 67.208962 -351.638665) (xy 65.726113 -351.638665)
			(xy 65.726113 -351.638672) (xy 65.718351 -351.692661) (xy 65.702984 -351.744995) (xy 65.680326 -351.79461)
			(xy 65.650837 -351.840496) (xy 65.615119 -351.881717) (xy 65.573897 -351.917436) (xy 65.528012 -351.946925)
			(xy 65.478397 -351.969584) (xy 65.426063 -351.984951) (xy 65.372074 -351.992713) (xy 65.344802 -351.9932)
			(xy 64.481202 -351.9932) (xy 64.453934 -351.992661) (xy 64.399952 -351.9849) (xy 64.347624 -351.969535)
			(xy 64.298016 -351.94688) (xy 64.252136 -351.917395) (xy 64.21092 -351.881681) (xy 64.175206 -351.840465)
			(xy 64.145721 -351.794586) (xy 64.123066 -351.744978) (xy 64.107701 -351.69265) (xy 64.099939 -351.638668)
			(xy 62.617114 -351.638668) (xy 62.617114 -351.63867) (xy 62.609352 -351.692655) (xy 62.593988 -351.744987)
			(xy 62.571332 -351.794599) (xy 62.541847 -351.840483) (xy 62.506133 -351.881703) (xy 62.464916 -351.917422)
			(xy 62.419036 -351.946912) (xy 62.369426 -351.969573) (xy 62.317097 -351.984943) (xy 62.263112 -351.992711)
			(xy 62.235842 -351.9932) (xy 61.372242 -351.9932) (xy 61.344972 -351.992663) (xy 61.290986 -351.984907)
			(xy 61.238653 -351.969546) (xy 61.18904 -351.946893) (xy 61.143155 -351.917409) (xy 61.101934 -351.881695)
			(xy 61.066216 -351.840478) (xy 61.036727 -351.794597) (xy 61.014069 -351.744986) (xy 60.998702 -351.692655)
			(xy 60.99094 -351.63867) (xy 51.666914 -351.63867) (xy 51.659152 -351.692655) (xy 51.643788 -351.744986)
			(xy 51.621133 -351.794597) (xy 51.591649 -351.840481) (xy 51.555935 -351.881701) (xy 51.514719 -351.91742)
			(xy 51.46884 -351.94691) (xy 51.419231 -351.969571) (xy 51.366902 -351.984942) (xy 51.312918 -351.99271)
			(xy 51.285648 -351.9932) (xy 50.422048 -351.9932) (xy 50.394777 -351.992664) (xy 50.340791 -351.984908)
			(xy 50.288458 -351.969547) (xy 50.238843 -351.946895) (xy 50.192958 -351.917411) (xy 50.151736 -351.881698)
			(xy 50.116017 -351.84048) (xy 50.086528 -351.794599) (xy 50.063869 -351.744987) (xy 50.048502 -351.692656)
			(xy 50.04074 -351.63867) (xy 48.558036 -351.63867) (xy 48.558036 -351.638674) (xy 48.550273 -351.692668)
			(xy 48.534905 -351.745006) (xy 48.512244 -351.794625) (xy 48.482752 -351.840514) (xy 48.44703 -351.881739)
			(xy 48.405804 -351.91746) (xy 48.359915 -351.94695) (xy 48.310295 -351.969609) (xy 48.257956 -351.984976)
			(xy 48.203962 -351.992737) (xy 48.176688 -351.9932) (xy 47.313088 -351.9932) (xy 47.285822 -351.992637)
			(xy 47.231845 -351.984875) (xy 47.179522 -351.96951) (xy 47.129918 -351.946855) (xy 47.084044 -351.917372)
			(xy 47.042831 -351.88166) (xy 47.007121 -351.840447) (xy 46.977639 -351.794571) (xy 46.954986 -351.744967)
			(xy 46.939623 -351.692643) (xy 46.931862 -351.638666) (xy 45.449014 -351.638666) (xy 45.449014 -351.638671)
			(xy 45.441252 -351.692657) (xy 45.425886 -351.74499) (xy 45.40323 -351.794603) (xy 45.373744 -351.840487)
			(xy 45.338028 -351.881708) (xy 45.29681 -351.917427) (xy 45.250928 -351.946917) (xy 45.201316 -351.969577)
			(xy 45.148985 -351.984946) (xy 45.094999 -351.992712) (xy 45.067728 -351.9932) (xy 44.204128 -351.9932)
			(xy 44.176858 -351.992663) (xy 44.122874 -351.984904) (xy 44.070543 -351.969542) (xy 44.020931 -351.946888)
			(xy 43.975049 -351.917404) (xy 43.933829 -351.881691) (xy 43.898112 -351.840474) (xy 43.868625 -351.794593)
			(xy 43.845968 -351.744983) (xy 43.830602 -351.692654) (xy 43.822839 -351.63867) (xy 42.340136 -351.63867)
			(xy 42.340136 -351.638675) (xy 42.332373 -351.69267) (xy 42.317003 -351.745011) (xy 42.294341 -351.794631)
			(xy 42.264847 -351.840521) (xy 42.229123 -351.881746) (xy 42.187895 -351.917467) (xy 42.142003 -351.946956)
			(xy 42.092381 -351.969614) (xy 42.040039 -351.984979) (xy 41.986043 -351.992739) (xy 41.958768 -351.9932)
			(xy 41.095168 -351.9932) (xy 41.067903 -351.992635) (xy 41.013928 -351.984871) (xy 40.961608 -351.969504)
			(xy 40.912006 -351.946849) (xy 40.866134 -351.917365) (xy 40.824924 -351.881653) (xy 40.789216 -351.84044)
			(xy 40.759736 -351.794566) (xy 40.737084 -351.744962) (xy 40.721722 -351.692641) (xy 40.713962 -351.638665)
			(xy 39.231114 -351.638665) (xy 39.231114 -351.638672) (xy 39.223351 -351.69266) (xy 39.207985 -351.744994)
			(xy 39.185327 -351.794609) (xy 39.155839 -351.840494) (xy 39.120121 -351.881715) (xy 39.0789 -351.917434)
			(xy 39.033016 -351.946923) (xy 38.983402 -351.969582) (xy 38.931068 -351.98495) (xy 38.87708 -351.992713)
			(xy 38.849808 -351.9932) (xy 37.986208 -351.9932) (xy 37.958939 -351.992661) (xy 37.904957 -351.984901)
			(xy 37.852629 -351.969537) (xy 37.803019 -351.946882) (xy 37.757139 -351.917397) (xy 37.715922 -351.881683)
			(xy 37.680207 -351.840467) (xy 37.650722 -351.794588) (xy 37.628066 -351.744979) (xy 37.612701 -351.692651)
			(xy 37.604939 -351.638669) (xy 36.122114 -351.638669) (xy 36.122114 -351.63867) (xy 36.114352 -351.692655)
			(xy 36.098988 -351.744986) (xy 36.076333 -351.794597) (xy 36.046849 -351.840481) (xy 36.011135 -351.881701)
			(xy 35.969919 -351.91742) (xy 35.92404 -351.94691) (xy 35.874431 -351.969571) (xy 35.822102 -351.984942)
			(xy 35.768118 -351.99271) (xy 35.740848 -351.9932) (xy 34.877248 -351.9932) (xy 34.849977 -351.992664)
			(xy 34.795991 -351.984908) (xy 34.743658 -351.969547) (xy 34.694043 -351.946895) (xy 34.648158 -351.917411)
			(xy 34.606936 -351.881698) (xy 34.571217 -351.84048) (xy 34.541728 -351.794599) (xy 34.519069 -351.744987)
			(xy 34.503702 -351.692656) (xy 34.49594 -351.63867) (xy 33.013236 -351.63867) (xy 33.013236 -351.638674)
			(xy 33.005473 -351.692668) (xy 32.990105 -351.745006) (xy 32.967444 -351.794625) (xy 32.937952 -351.840514)
			(xy 32.90223 -351.881739) (xy 32.861004 -351.91746) (xy 32.815115 -351.94695) (xy 32.765495 -351.969609)
			(xy 32.713156 -351.984976) (xy 32.659162 -351.992737) (xy 32.631888 -351.9932) (xy 31.768288 -351.9932)
			(xy 31.741022 -351.992637) (xy 31.687045 -351.984875) (xy 31.634722 -351.96951) (xy 31.585118 -351.946855)
			(xy 31.539244 -351.917372) (xy 31.498031 -351.88166) (xy 31.462321 -351.840447) (xy 31.432839 -351.794571)
			(xy 31.410186 -351.744967) (xy 31.394823 -351.692643) (xy 31.387062 -351.638666) (xy 29.904214 -351.638666)
			(xy 29.904214 -351.638671) (xy 29.896452 -351.692657) (xy 29.881086 -351.74499) (xy 29.85843 -351.794603)
			(xy 29.828944 -351.840487) (xy 29.793228 -351.881708) (xy 29.75201 -351.917427) (xy 29.706128 -351.946917)
			(xy 29.656516 -351.969577) (xy 29.604185 -351.984946) (xy 29.550199 -351.992712) (xy 29.522928 -351.9932)
			(xy 28.659328 -351.9932) (xy 28.632058 -351.992663) (xy 28.578074 -351.984904) (xy 28.525743 -351.969542)
			(xy 28.476131 -351.946888) (xy 28.430249 -351.917404) (xy 28.389029 -351.881691) (xy 28.353312 -351.840474)
			(xy 28.323825 -351.794593) (xy 28.301168 -351.744983) (xy 28.285802 -351.692654) (xy 28.278039 -351.63867)
			(xy 26.795336 -351.63867) (xy 26.795336 -351.638675) (xy 26.787573 -351.69267) (xy 26.772203 -351.745011)
			(xy 26.749541 -351.794631) (xy 26.720047 -351.840521) (xy 26.684323 -351.881746) (xy 26.643095 -351.917467)
			(xy 26.597203 -351.946956) (xy 26.547581 -351.969614) (xy 26.495239 -351.984979) (xy 26.441243 -351.992739)
			(xy 26.413968 -351.9932) (xy 25.550368 -351.9932) (xy 25.523103 -351.992635) (xy 25.469128 -351.984871)
			(xy 25.416808 -351.969504) (xy 25.367206 -351.946849) (xy 25.321334 -351.917365) (xy 25.280124 -351.881653)
			(xy 25.244416 -351.84044) (xy 25.214936 -351.794566) (xy 25.192284 -351.744962) (xy 25.176922 -351.692641)
			(xy 25.169162 -351.638665) (xy 23.686314 -351.638665) (xy 23.686314 -351.638672) (xy 23.678551 -351.69266)
			(xy 23.663185 -351.744994) (xy 23.640527 -351.794609) (xy 23.611039 -351.840494) (xy 23.575321 -351.881715)
			(xy 23.5341 -351.917434) (xy 23.488216 -351.946923) (xy 23.438602 -351.969582) (xy 23.386268 -351.98495)
			(xy 23.33228 -351.992713) (xy 23.305008 -351.9932) (xy 22.441408 -351.9932) (xy 22.414139 -351.992661)
			(xy 22.360157 -351.984901) (xy 22.307829 -351.969537) (xy 22.258219 -351.946882) (xy 22.212339 -351.917397)
			(xy 22.171122 -351.881683) (xy 22.135407 -351.840467) (xy 22.105922 -351.794588) (xy 22.083266 -351.744979)
			(xy 22.067901 -351.692651) (xy 22.060139 -351.638669) (xy 20.577347 -351.638669) (xy 20.577347 -351.638711)
			(xy 20.569584 -351.692698) (xy 20.554218 -351.74503) (xy 20.53156 -351.794643) (xy 20.502073 -351.840527)
			(xy 20.466355 -351.881747) (xy 20.425135 -351.917464) (xy 20.379252 -351.946951) (xy 20.329638 -351.969609)
			(xy 20.277306 -351.984975) (xy 20.223319 -351.992737) (xy 20.196048 -351.9932) (xy 19.332448 -351.9932)
			(xy 19.305179 -351.992717) (xy 19.251195 -351.984955) (xy 19.198865 -351.96959) (xy 19.149255 -351.946933)
			(xy 19.103374 -351.917447) (xy 19.062157 -351.881732) (xy 19.026441 -351.840514) (xy 18.996956 -351.794633)
			(xy 18.974299 -351.745023) (xy 18.958934 -351.692693) (xy 18.951172 -351.638709) (xy 0.508 -351.638709)
			(xy 0.508 -354.759373) (xy 22.060084 -354.759373) (xy 22.060084 -354.704827) (xy 22.067846 -354.650837)
			(xy 22.083214 -354.598501) (xy 22.105873 -354.548885) (xy 22.135363 -354.502999) (xy 22.171083 -354.461777)
			(xy 22.212306 -354.426058) (xy 22.258192 -354.396569) (xy 22.307809 -354.373911) (xy 22.360145 -354.358545)
			(xy 22.414135 -354.350783) (xy 22.441408 -354.35032) (xy 23.305008 -354.35032) (xy 23.332276 -354.350843)
			(xy 23.386256 -354.358605) (xy 23.438582 -354.37397) (xy 23.488189 -354.396626) (xy 23.534067 -354.426111)
			(xy 23.575281 -354.461824) (xy 23.610994 -354.50304) (xy 23.640478 -354.548918) (xy 23.663132 -354.598525)
			(xy 23.678497 -354.650852) (xy 23.686258 -354.704832) (xy 23.686258 -354.759368) (xy 23.686258 -354.759369)
			(xy 25.169106 -354.759369) (xy 25.169106 -354.704831) (xy 25.176868 -354.650847) (xy 25.192232 -354.598518)
			(xy 25.214887 -354.548908) (xy 25.244371 -354.503026) (xy 25.280085 -354.461807) (xy 25.3213 -354.42609)
			(xy 25.36718 -354.396602) (xy 25.416788 -354.373943) (xy 25.469116 -354.358574) (xy 25.523099 -354.350809)
			(xy 25.550368 -354.35032) (xy 26.413968 -354.35032) (xy 26.441239 -354.350817) (xy 26.495227 -354.358575)
			(xy 26.547561 -354.373938) (xy 26.597176 -354.396593) (xy 26.643061 -354.426078) (xy 26.684283 -354.461794)
			(xy 26.720003 -354.503013) (xy 26.749492 -354.548896) (xy 26.772151 -354.598509) (xy 26.787518 -354.650842)
			(xy 26.79528 -354.704829) (xy 26.79528 -354.759371) (xy 26.79528 -354.759374) (xy 28.277984 -354.759374)
			(xy 28.277984 -354.704826) (xy 28.285747 -354.650835) (xy 28.301115 -354.598497) (xy 28.323776 -354.54888)
			(xy 28.353268 -354.502993) (xy 28.38899 -354.46177) (xy 28.430215 -354.426051) (xy 28.476104 -354.396562)
			(xy 28.525723 -354.373905) (xy 28.578062 -354.358541) (xy 28.632054 -354.350782) (xy 28.659328 -354.35032)
			(xy 29.522928 -354.35032) (xy 29.550195 -354.350844) (xy 29.604173 -354.358609) (xy 29.656497 -354.373976)
			(xy 29.706101 -354.396633) (xy 29.751976 -354.426118) (xy 29.793188 -354.461831) (xy 29.828899 -354.503046)
			(xy 29.858381 -354.548924) (xy 29.881034 -354.59853) (xy 29.896397 -354.650855) (xy 29.904158 -354.704833)
			(xy 29.904158 -354.759367) (xy 29.904158 -354.75937) (xy 31.387006 -354.75937) (xy 31.387006 -354.70483)
			(xy 31.394768 -354.650845) (xy 31.410134 -354.598514) (xy 31.43279 -354.548902) (xy 31.462276 -354.50302)
			(xy 31.497992 -354.4618) (xy 31.53921 -354.426083) (xy 31.585091 -354.396596) (xy 31.634703 -354.373938)
			(xy 31.687033 -354.358571) (xy 31.741018 -354.350807) (xy 31.768288 -354.35032) (xy 32.631888 -354.35032)
			(xy 32.659158 -354.350819) (xy 32.713144 -354.358579) (xy 32.765476 -354.373944) (xy 32.815088 -354.396599)
			(xy 32.860971 -354.426085) (xy 32.902191 -354.461801) (xy 32.937908 -354.503019) (xy 32.967395 -354.548902)
			(xy 32.990052 -354.598513) (xy 33.005418 -354.650844) (xy 33.013181 -354.70483) (xy 33.013181 -354.75937)
			(xy 33.01318 -354.759374) (xy 34.495884 -354.759374) (xy 34.495884 -354.704826) (xy 34.503647 -354.650832)
			(xy 34.519017 -354.598493) (xy 34.541679 -354.548874) (xy 34.571172 -354.502986) (xy 34.606897 -354.461763)
			(xy 34.648125 -354.426044) (xy 34.694016 -354.396556) (xy 34.743638 -354.3739) (xy 34.795979 -354.358537)
			(xy 34.849973 -354.35078) (xy 34.877248 -354.35032) (xy 35.740848 -354.35032) (xy 35.768114 -354.350846)
			(xy 35.82209 -354.358613) (xy 35.874411 -354.373981) (xy 35.924013 -354.396639) (xy 35.969886 -354.426125)
			(xy 36.011095 -354.461839) (xy 36.046804 -354.503053) (xy 36.076284 -354.548929) (xy 36.098936 -354.598534)
			(xy 36.114298 -354.650857) (xy 36.122058 -354.704834) (xy 36.122058 -354.759366) (xy 36.122057 -354.759373)
			(xy 37.604884 -354.759373) (xy 37.604884 -354.704827) (xy 37.612646 -354.650837) (xy 37.628014 -354.598501)
			(xy 37.650673 -354.548885) (xy 37.680163 -354.502999) (xy 37.715883 -354.461777) (xy 37.757106 -354.426058)
			(xy 37.802992 -354.396569) (xy 37.852609 -354.373911) (xy 37.904945 -354.358545) (xy 37.958935 -354.350783)
			(xy 37.986208 -354.35032) (xy 38.849808 -354.35032) (xy 38.877076 -354.350843) (xy 38.931056 -354.358605)
			(xy 38.983382 -354.37397) (xy 39.032989 -354.396626) (xy 39.078867 -354.426111) (xy 39.120081 -354.461824)
			(xy 39.155794 -354.50304) (xy 39.185278 -354.548918) (xy 39.207932 -354.598525) (xy 39.223297 -354.650852)
			(xy 39.231058 -354.704832) (xy 39.231058 -354.759368) (xy 39.231058 -354.759369) (xy 40.713906 -354.759369)
			(xy 40.713906 -354.704831) (xy 40.721668 -354.650847) (xy 40.737032 -354.598518) (xy 40.759687 -354.548908)
			(xy 40.789171 -354.503026) (xy 40.824885 -354.461807) (xy 40.8661 -354.42609) (xy 40.91198 -354.396602)
			(xy 40.961588 -354.373943) (xy 41.013916 -354.358574) (xy 41.067899 -354.350809) (xy 41.095168 -354.35032)
			(xy 41.958768 -354.35032) (xy 41.986039 -354.350817) (xy 42.040027 -354.358575) (xy 42.092361 -354.373938)
			(xy 42.141976 -354.396593) (xy 42.187861 -354.426078) (xy 42.229083 -354.461794) (xy 42.264803 -354.503013)
			(xy 42.294292 -354.548896) (xy 42.316951 -354.598509) (xy 42.332318 -354.650842) (xy 42.34008 -354.704829)
			(xy 42.34008 -354.759371) (xy 42.34008 -354.759374) (xy 43.822784 -354.759374) (xy 43.822784 -354.704826)
			(xy 43.830547 -354.650835) (xy 43.845915 -354.598497) (xy 43.868576 -354.54888) (xy 43.898068 -354.502993)
			(xy 43.93379 -354.46177) (xy 43.975015 -354.426051) (xy 44.020904 -354.396562) (xy 44.070523 -354.373905)
			(xy 44.122862 -354.358541) (xy 44.176854 -354.350782) (xy 44.204128 -354.35032) (xy 45.067728 -354.35032)
			(xy 45.094995 -354.350844) (xy 45.148973 -354.358609) (xy 45.201297 -354.373976) (xy 45.250901 -354.396633)
			(xy 45.296776 -354.426118) (xy 45.337988 -354.461831) (xy 45.373699 -354.503046) (xy 45.403181 -354.548924)
			(xy 45.425834 -354.59853) (xy 45.441197 -354.650855) (xy 45.448958 -354.704833) (xy 45.448958 -354.759367)
			(xy 45.448958 -354.75937) (xy 46.931806 -354.75937) (xy 46.931806 -354.70483) (xy 46.939568 -354.650845)
			(xy 46.954934 -354.598514) (xy 46.97759 -354.548902) (xy 47.007076 -354.50302) (xy 47.042792 -354.4618)
			(xy 47.08401 -354.426083) (xy 47.129891 -354.396596) (xy 47.179503 -354.373938) (xy 47.231833 -354.358571)
			(xy 47.285818 -354.350807) (xy 47.313088 -354.35032) (xy 48.176688 -354.35032) (xy 48.203958 -354.350819)
			(xy 48.257944 -354.358579) (xy 48.310276 -354.373944) (xy 48.359888 -354.396599) (xy 48.405771 -354.426085)
			(xy 48.446991 -354.461801) (xy 48.482708 -354.503019) (xy 48.512195 -354.548902) (xy 48.534852 -354.598513)
			(xy 48.550218 -354.650844) (xy 48.557981 -354.70483) (xy 48.557981 -354.75937) (xy 48.55798 -354.759374)
			(xy 50.040684 -354.759374) (xy 50.040684 -354.704826) (xy 50.048447 -354.650832) (xy 50.063817 -354.598493)
			(xy 50.086479 -354.548874) (xy 50.115972 -354.502986) (xy 50.151697 -354.461763) (xy 50.192925 -354.426044)
			(xy 50.238816 -354.396556) (xy 50.288438 -354.3739) (xy 50.340779 -354.358537) (xy 50.394773 -354.35078)
			(xy 50.422048 -354.35032) (xy 51.285648 -354.35032) (xy 51.312914 -354.350846) (xy 51.36689 -354.358613)
			(xy 51.419211 -354.373981) (xy 51.468813 -354.396639) (xy 51.514686 -354.426125) (xy 51.555895 -354.461839)
			(xy 51.591604 -354.503053) (xy 51.621084 -354.548929) (xy 51.643736 -354.598534) (xy 51.659098 -354.650857)
			(xy 51.666858 -354.704834) (xy 51.666858 -354.759366) (xy 51.666857 -354.759372) (xy 64.099884 -354.759372)
			(xy 64.099884 -354.704828) (xy 64.107646 -354.650838) (xy 64.123013 -354.598503) (xy 64.145672 -354.548887)
			(xy 64.175161 -354.503001) (xy 64.210881 -354.461779) (xy 64.252103 -354.42606) (xy 64.297989 -354.396571)
			(xy 64.347605 -354.373912) (xy 64.39994 -354.358546) (xy 64.45393 -354.350783) (xy 64.481202 -354.35032)
			(xy 65.344802 -354.35032) (xy 65.37207 -354.350843) (xy 65.426051 -354.358604) (xy 65.478378 -354.373969)
			(xy 65.527985 -354.396624) (xy 65.573864 -354.426109) (xy 65.615079 -354.461822) (xy 65.650793 -354.503038)
			(xy 65.680277 -354.548917) (xy 65.702932 -354.598524) (xy 65.718296 -354.650851) (xy 65.726058 -354.704832)
			(xy 65.726058 -354.759368) (xy 65.726058 -354.759369) (xy 67.208906 -354.759369) (xy 67.208906 -354.704831)
			(xy 67.216667 -354.650848) (xy 67.232032 -354.598519) (xy 67.254686 -354.548909) (xy 67.28417 -354.503028)
			(xy 67.319883 -354.46181) (xy 67.361098 -354.426093) (xy 67.406976 -354.396604) (xy 67.456584 -354.373945)
			(xy 67.508911 -354.358575) (xy 67.562893 -354.350809) (xy 67.590162 -354.35032) (xy 68.453762 -354.35032)
			(xy 68.481033 -354.350817) (xy 68.535022 -354.358574) (xy 68.587357 -354.373936) (xy 68.636972 -354.396591)
			(xy 68.682859 -354.426076) (xy 68.724081 -354.461792) (xy 68.759801 -354.503011) (xy 68.789291 -354.548894)
			(xy 68.81195 -354.598508) (xy 68.827318 -354.650841) (xy 68.83508 -354.704829) (xy 68.83508 -354.759371)
			(xy 68.83508 -354.759373) (xy 70.317784 -354.759373) (xy 70.317784 -354.704827) (xy 70.325547 -354.650835)
			(xy 70.340915 -354.598498) (xy 70.363575 -354.548882) (xy 70.393066 -354.502995) (xy 70.428788 -354.461772)
			(xy 70.470012 -354.426053) (xy 70.515901 -354.396564) (xy 70.565519 -354.373907) (xy 70.617857 -354.358542)
			(xy 70.671849 -354.350782) (xy 70.699122 -354.35032) (xy 71.562722 -354.35032) (xy 71.589989 -354.350844)
			(xy 71.643968 -354.358608) (xy 71.696292 -354.373974) (xy 71.745897 -354.396631) (xy 71.791773 -354.426116)
			(xy 71.832986 -354.461829) (xy 71.868697 -354.503044) (xy 71.89818 -354.548922) (xy 71.920833 -354.598528)
			(xy 71.936197 -354.650854) (xy 71.943958 -354.704833) (xy 71.943958 -354.759367) (xy 71.943958 -354.75937)
			(xy 73.426806 -354.75937) (xy 73.426806 -354.70483) (xy 73.434568 -354.650846) (xy 73.449933 -354.598515)
			(xy 73.472589 -354.548904) (xy 73.502075 -354.503022) (xy 73.53779 -354.461802) (xy 73.579007 -354.426085)
			(xy 73.624888 -354.396598) (xy 73.674498 -354.373939) (xy 73.726828 -354.358572) (xy 73.780812 -354.350808)
			(xy 73.808082 -354.35032) (xy 74.671682 -354.35032) (xy 74.698953 -354.350818) (xy 74.752939 -354.358578)
			(xy 74.805271 -354.373942) (xy 74.854884 -354.396597) (xy 74.900768 -354.426083) (xy 74.941988 -354.461799)
			(xy 74.977706 -354.503018) (xy 75.007194 -354.5489) (xy 75.029852 -354.598512) (xy 75.045218 -354.650844)
			(xy 75.052981 -354.704829) (xy 75.052981 -354.759371) (xy 75.052981 -354.759374) (xy 76.535684 -354.759374)
			(xy 76.535684 -354.704826) (xy 76.543447 -354.650833) (xy 76.558816 -354.598494) (xy 76.581478 -354.548876)
			(xy 76.610971 -354.502988) (xy 76.646695 -354.461765) (xy 76.687922 -354.426046) (xy 76.733813 -354.396558)
			(xy 76.783434 -354.373902) (xy 76.835774 -354.358538) (xy 76.889768 -354.350781) (xy 76.917042 -354.35032)
			(xy 77.780642 -354.35032) (xy 77.807908 -354.350845) (xy 77.861885 -354.358611) (xy 77.914207 -354.37398)
			(xy 77.963809 -354.396637) (xy 78.009683 -354.426123) (xy 78.050893 -354.461836) (xy 78.086602 -354.503051)
			(xy 78.116083 -354.548928) (xy 78.138735 -354.598533) (xy 78.154098 -354.650856) (xy 78.161858 -354.704834)
			(xy 78.161858 -354.759366) (xy 78.161857 -354.759372) (xy 79.644684 -354.759372) (xy 79.644684 -354.704828)
			(xy 79.652446 -354.650838) (xy 79.667813 -354.598503) (xy 79.690472 -354.548887) (xy 79.719961 -354.503001)
			(xy 79.755681 -354.461779) (xy 79.796903 -354.42606) (xy 79.842789 -354.396571) (xy 79.892405 -354.373912)
			(xy 79.94474 -354.358546) (xy 79.99873 -354.350783) (xy 80.026002 -354.35032) (xy 80.889602 -354.35032)
			(xy 80.91687 -354.350843) (xy 80.970851 -354.358604) (xy 81.023178 -354.373969) (xy 81.072785 -354.396624)
			(xy 81.118664 -354.426109) (xy 81.159879 -354.461822) (xy 81.195593 -354.503038) (xy 81.225077 -354.548917)
			(xy 81.247732 -354.598524) (xy 81.263096 -354.650851) (xy 81.270858 -354.704832) (xy 81.270858 -354.759368)
			(xy 81.270858 -354.759369) (xy 82.753706 -354.759369) (xy 82.753706 -354.704831) (xy 82.761467 -354.650848)
			(xy 82.776832 -354.598519) (xy 82.799486 -354.548909) (xy 82.82897 -354.503028) (xy 82.864683 -354.46181)
			(xy 82.905898 -354.426093) (xy 82.951776 -354.396604) (xy 83.001384 -354.373945) (xy 83.053711 -354.358575)
			(xy 83.107693 -354.350809) (xy 83.134962 -354.35032) (xy 83.998562 -354.35032) (xy 84.025833 -354.350817)
			(xy 84.079822 -354.358574) (xy 84.132157 -354.373936) (xy 84.181772 -354.396591) (xy 84.227659 -354.426076)
			(xy 84.268881 -354.461792) (xy 84.304601 -354.503011) (xy 84.334091 -354.548894) (xy 84.35675 -354.598508)
			(xy 84.372118 -354.650841) (xy 84.37988 -354.704829) (xy 84.37988 -354.759371) (xy 84.37988 -354.759373)
			(xy 85.862584 -354.759373) (xy 85.862584 -354.704827) (xy 85.870347 -354.650835) (xy 85.885715 -354.598498)
			(xy 85.908375 -354.548882) (xy 85.937866 -354.502995) (xy 85.973588 -354.461772) (xy 86.014812 -354.426053)
			(xy 86.060701 -354.396564) (xy 86.110319 -354.373907) (xy 86.162657 -354.358542) (xy 86.216649 -354.350782)
			(xy 86.243922 -354.35032) (xy 87.107522 -354.35032) (xy 87.134789 -354.350844) (xy 87.188768 -354.358608)
			(xy 87.241092 -354.373974) (xy 87.290697 -354.396631) (xy 87.336573 -354.426116) (xy 87.377786 -354.461829)
			(xy 87.413497 -354.503044) (xy 87.44298 -354.548922) (xy 87.465633 -354.598528) (xy 87.480997 -354.650854)
			(xy 87.488758 -354.704833) (xy 87.488758 -354.759367) (xy 87.488758 -354.75937) (xy 88.971606 -354.75937)
			(xy 88.971606 -354.70483) (xy 88.979368 -354.650846) (xy 88.994733 -354.598515) (xy 89.017389 -354.548904)
			(xy 89.046875 -354.503022) (xy 89.08259 -354.461802) (xy 89.123807 -354.426085) (xy 89.169688 -354.396598)
			(xy 89.219298 -354.373939) (xy 89.271628 -354.358572) (xy 89.325612 -354.350808) (xy 89.352882 -354.35032)
			(xy 90.216482 -354.35032) (xy 90.243753 -354.350818) (xy 90.297739 -354.358578) (xy 90.350071 -354.373942)
			(xy 90.399684 -354.396597) (xy 90.445568 -354.426083) (xy 90.486788 -354.461799) (xy 90.522506 -354.503018)
			(xy 90.551994 -354.5489) (xy 90.574652 -354.598512) (xy 90.590018 -354.650844) (xy 90.597781 -354.704829)
			(xy 90.597781 -354.759371) (xy 90.597781 -354.759374) (xy 92.080484 -354.759374) (xy 92.080484 -354.704826)
			(xy 92.088247 -354.650833) (xy 92.103616 -354.598494) (xy 92.126278 -354.548876) (xy 92.155771 -354.502988)
			(xy 92.191495 -354.461765) (xy 92.232722 -354.426046) (xy 92.278613 -354.396558) (xy 92.328234 -354.373902)
			(xy 92.380574 -354.358538) (xy 92.434568 -354.350781) (xy 92.461842 -354.35032) (xy 93.325442 -354.35032)
			(xy 93.352708 -354.350845) (xy 93.406685 -354.358611) (xy 93.459007 -354.37398) (xy 93.508609 -354.396637)
			(xy 93.554483 -354.426123) (xy 93.595693 -354.461836) (xy 93.631402 -354.503051) (xy 93.660883 -354.548928)
			(xy 93.683535 -354.598533) (xy 93.698898 -354.650856) (xy 93.706658 -354.704834) (xy 93.706658 -354.759366)
			(xy 93.706658 -354.759369) (xy 114.589806 -354.759369) (xy 114.589806 -354.704831) (xy 114.597568 -354.650847)
			(xy 114.612932 -354.598518) (xy 114.635587 -354.548908) (xy 114.665071 -354.503026) (xy 114.700785 -354.461807)
			(xy 114.742 -354.42609) (xy 114.78788 -354.396602) (xy 114.837488 -354.373943) (xy 114.889816 -354.358574)
			(xy 114.943799 -354.350809) (xy 114.971068 -354.35032) (xy 115.834668 -354.35032) (xy 115.861939 -354.350817)
			(xy 115.915927 -354.358575) (xy 115.968261 -354.373938) (xy 116.017876 -354.396593) (xy 116.063761 -354.426078)
			(xy 116.104983 -354.461794) (xy 116.140703 -354.503013) (xy 116.170192 -354.548896) (xy 116.192851 -354.598509)
			(xy 116.208218 -354.650842) (xy 116.21598 -354.704829) (xy 116.21598 -354.759371) (xy 116.21598 -354.759374)
			(xy 117.698684 -354.759374) (xy 117.698684 -354.704826) (xy 117.706447 -354.650835) (xy 117.721815 -354.598497)
			(xy 117.744476 -354.54888) (xy 117.773968 -354.502993) (xy 117.80969 -354.46177) (xy 117.850915 -354.426051)
			(xy 117.896804 -354.396562) (xy 117.946423 -354.373905) (xy 117.998762 -354.358541) (xy 118.052754 -354.350782)
			(xy 118.080028 -354.35032) (xy 118.943628 -354.35032) (xy 118.970895 -354.350844) (xy 119.024873 -354.358609)
			(xy 119.077197 -354.373976) (xy 119.126801 -354.396633) (xy 119.172676 -354.426118) (xy 119.213888 -354.461831)
			(xy 119.249599 -354.503046) (xy 119.279081 -354.548924) (xy 119.301734 -354.59853) (xy 119.317097 -354.650855)
			(xy 119.324858 -354.704833) (xy 119.324858 -354.759367) (xy 119.324858 -354.75937) (xy 120.807706 -354.75937)
			(xy 120.807706 -354.70483) (xy 120.815468 -354.650845) (xy 120.830834 -354.598514) (xy 120.85349 -354.548902)
			(xy 120.882976 -354.50302) (xy 120.918692 -354.4618) (xy 120.95991 -354.426083) (xy 121.005791 -354.396596)
			(xy 121.055403 -354.373938) (xy 121.107733 -354.358571) (xy 121.161718 -354.350807) (xy 121.188988 -354.35032)
			(xy 122.052588 -354.35032) (xy 122.079858 -354.350819) (xy 122.133844 -354.358579) (xy 122.186176 -354.373944)
			(xy 122.235788 -354.396599) (xy 122.281671 -354.426085) (xy 122.322891 -354.461801) (xy 122.358608 -354.503019)
			(xy 122.388095 -354.548902) (xy 122.410752 -354.598513) (xy 122.426118 -354.650844) (xy 122.433881 -354.70483)
			(xy 122.433881 -354.75937) (xy 122.43388 -354.759374) (xy 123.916584 -354.759374) (xy 123.916584 -354.704826)
			(xy 123.924347 -354.650832) (xy 123.939717 -354.598493) (xy 123.962379 -354.548874) (xy 123.991872 -354.502986)
			(xy 124.027597 -354.461763) (xy 124.068825 -354.426044) (xy 124.114716 -354.396556) (xy 124.164338 -354.3739)
			(xy 124.216679 -354.358537) (xy 124.270673 -354.35078) (xy 124.297948 -354.35032) (xy 125.161548 -354.35032)
			(xy 125.188814 -354.350846) (xy 125.24279 -354.358613) (xy 125.295111 -354.373981) (xy 125.344713 -354.396639)
			(xy 125.390586 -354.426125) (xy 125.431795 -354.461839) (xy 125.467504 -354.503053) (xy 125.496984 -354.548929)
			(xy 125.519636 -354.598534) (xy 125.534998 -354.650857) (xy 125.542758 -354.704834) (xy 125.542758 -354.759366)
			(xy 125.542757 -354.759373) (xy 127.025584 -354.759373) (xy 127.025584 -354.704827) (xy 127.033346 -354.650837)
			(xy 127.048714 -354.598501) (xy 127.071373 -354.548885) (xy 127.100863 -354.502999) (xy 127.136583 -354.461777)
			(xy 127.177806 -354.426058) (xy 127.223692 -354.396569) (xy 127.273309 -354.373911) (xy 127.325645 -354.358545)
			(xy 127.379635 -354.350783) (xy 127.406908 -354.35032) (xy 128.270508 -354.35032) (xy 128.297776 -354.350843)
			(xy 128.351756 -354.358605) (xy 128.404082 -354.37397) (xy 128.453689 -354.396626) (xy 128.499567 -354.426111)
			(xy 128.540781 -354.461824) (xy 128.576494 -354.50304) (xy 128.605978 -354.548918) (xy 128.628632 -354.598525)
			(xy 128.643997 -354.650852) (xy 128.651758 -354.704832) (xy 128.651758 -354.759368) (xy 128.651758 -354.759369)
			(xy 130.134606 -354.759369) (xy 130.134606 -354.704831) (xy 130.142368 -354.650847) (xy 130.157732 -354.598518)
			(xy 130.180387 -354.548908) (xy 130.209871 -354.503026) (xy 130.245585 -354.461807) (xy 130.2868 -354.42609)
			(xy 130.33268 -354.396602) (xy 130.382288 -354.373943) (xy 130.434616 -354.358574) (xy 130.488599 -354.350809)
			(xy 130.515868 -354.35032) (xy 131.379468 -354.35032) (xy 131.406739 -354.350817) (xy 131.460727 -354.358575)
			(xy 131.513061 -354.373938) (xy 131.562676 -354.396593) (xy 131.608561 -354.426078) (xy 131.649783 -354.461794)
			(xy 131.685503 -354.503013) (xy 131.714992 -354.548896) (xy 131.737651 -354.598509) (xy 131.753018 -354.650842)
			(xy 131.76078 -354.704829) (xy 131.76078 -354.759371) (xy 131.76078 -354.759374) (xy 133.243484 -354.759374)
			(xy 133.243484 -354.704826) (xy 133.251247 -354.650835) (xy 133.266615 -354.598497) (xy 133.289276 -354.54888)
			(xy 133.318768 -354.502993) (xy 133.35449 -354.46177) (xy 133.395715 -354.426051) (xy 133.441604 -354.396562)
			(xy 133.491223 -354.373905) (xy 133.543562 -354.358541) (xy 133.597554 -354.350782) (xy 133.624828 -354.35032)
			(xy 134.488428 -354.35032) (xy 134.515695 -354.350844) (xy 134.569673 -354.358609) (xy 134.621997 -354.373976)
			(xy 134.671601 -354.396633) (xy 134.717476 -354.426118) (xy 134.758688 -354.461831) (xy 134.794399 -354.503046)
			(xy 134.823881 -354.548924) (xy 134.846534 -354.59853) (xy 134.861897 -354.650855) (xy 134.869658 -354.704833)
			(xy 134.869658 -354.759367) (xy 134.869658 -354.75937) (xy 136.352506 -354.75937) (xy 136.352506 -354.70483)
			(xy 136.360268 -354.650845) (xy 136.375634 -354.598514) (xy 136.39829 -354.548902) (xy 136.427776 -354.50302)
			(xy 136.463492 -354.4618) (xy 136.50471 -354.426083) (xy 136.550591 -354.396596) (xy 136.600203 -354.373938)
			(xy 136.652533 -354.358571) (xy 136.706518 -354.350807) (xy 136.733788 -354.35032) (xy 137.597388 -354.35032)
			(xy 137.624658 -354.350819) (xy 137.678644 -354.358579) (xy 137.730976 -354.373944) (xy 137.780588 -354.396599)
			(xy 137.826471 -354.426085) (xy 137.867691 -354.461801) (xy 137.903408 -354.503019) (xy 137.932895 -354.548902)
			(xy 137.955552 -354.598513) (xy 137.970918 -354.650844) (xy 137.978681 -354.70483) (xy 137.978681 -354.75937)
			(xy 137.97868 -354.759374) (xy 139.461384 -354.759374) (xy 139.461384 -354.704826) (xy 139.469147 -354.650832)
			(xy 139.484517 -354.598493) (xy 139.507179 -354.548874) (xy 139.536672 -354.502986) (xy 139.572397 -354.461763)
			(xy 139.613625 -354.426044) (xy 139.659516 -354.396556) (xy 139.709138 -354.3739) (xy 139.761479 -354.358537)
			(xy 139.815473 -354.35078) (xy 139.842748 -354.35032) (xy 140.706348 -354.35032) (xy 140.733614 -354.350846)
			(xy 140.78759 -354.358613) (xy 140.839911 -354.373981) (xy 140.889513 -354.396639) (xy 140.935386 -354.426125)
			(xy 140.976595 -354.461839) (xy 141.012304 -354.503053) (xy 141.041784 -354.548929) (xy 141.064436 -354.598534)
			(xy 141.079798 -354.650857) (xy 141.087558 -354.704834) (xy 141.087558 -354.759366) (xy 141.087557 -354.759373)
			(xy 142.570384 -354.759373) (xy 142.570384 -354.704827) (xy 142.578146 -354.650837) (xy 142.593514 -354.598501)
			(xy 142.616173 -354.548885) (xy 142.645663 -354.502999) (xy 142.681383 -354.461777) (xy 142.722606 -354.426058)
			(xy 142.768492 -354.396569) (xy 142.818109 -354.373911) (xy 142.870445 -354.358545) (xy 142.924435 -354.350783)
			(xy 142.951708 -354.35032) (xy 143.815308 -354.35032) (xy 143.842576 -354.350843) (xy 143.896556 -354.358605)
			(xy 143.948882 -354.37397) (xy 143.998489 -354.396626) (xy 144.044367 -354.426111) (xy 144.085581 -354.461824)
			(xy 144.121294 -354.50304) (xy 144.150778 -354.548918) (xy 144.173432 -354.598525) (xy 144.188797 -354.650852)
			(xy 144.196558 -354.704832) (xy 144.196558 -354.759368) (xy 158.695906 -354.759368) (xy 158.695906 -354.704832)
			(xy 158.703667 -354.65085) (xy 158.719031 -354.598521) (xy 158.741685 -354.548912) (xy 158.771167 -354.503031)
			(xy 158.806879 -354.461813) (xy 158.848093 -354.426096) (xy 158.89397 -354.396608) (xy 158.943576 -354.373948)
			(xy 158.995903 -354.358577) (xy 159.049884 -354.35081) (xy 159.077152 -354.35032) (xy 159.940752 -354.35032)
			(xy 159.968024 -354.350816) (xy 160.022013 -354.358572) (xy 160.074349 -354.373934) (xy 160.123966 -354.396588)
			(xy 160.169854 -354.426072) (xy 160.211078 -354.461788) (xy 160.246799 -354.503008) (xy 160.276289 -354.548891)
			(xy 160.298949 -354.598506) (xy 160.314317 -354.65084) (xy 160.32208 -354.704828) (xy 160.32208 -354.759372)
			(xy 160.32208 -354.759373) (xy 161.804784 -354.759373) (xy 161.804784 -354.704827) (xy 161.812546 -354.650837)
			(xy 161.827914 -354.598501) (xy 161.850573 -354.548884) (xy 161.880064 -354.502998) (xy 161.915784 -354.461776)
			(xy 161.957008 -354.426056) (xy 162.002895 -354.396568) (xy 162.052512 -354.37391) (xy 162.104848 -354.358544)
			(xy 162.158839 -354.350783) (xy 162.186112 -354.35032) (xy 163.049712 -354.35032) (xy 163.07698 -354.350843)
			(xy 163.130959 -354.358606) (xy 163.183285 -354.373972) (xy 163.232891 -354.396627) (xy 163.278768 -354.426112)
			(xy 163.319983 -354.461826) (xy 163.355695 -354.503041) (xy 163.385178 -354.548919) (xy 163.407833 -354.598526)
			(xy 163.423197 -354.650852) (xy 163.430958 -354.704832) (xy 163.430958 -354.759368) (xy 163.430958 -354.759369)
			(xy 164.913806 -354.759369) (xy 164.913806 -354.704831) (xy 164.921568 -354.650847) (xy 164.936932 -354.598517)
			(xy 164.959588 -354.548907) (xy 164.989072 -354.503025) (xy 165.024786 -354.461806) (xy 165.066002 -354.426089)
			(xy 165.111882 -354.396601) (xy 165.161491 -354.373942) (xy 165.21382 -354.358574) (xy 165.267803 -354.350808)
			(xy 165.295072 -354.35032) (xy 166.158672 -354.35032) (xy 166.185943 -354.350818) (xy 166.23993 -354.358576)
			(xy 166.292264 -354.373939) (xy 166.341878 -354.396594) (xy 166.387763 -354.42608) (xy 166.428985 -354.461795)
			(xy 166.464704 -354.503014) (xy 166.494192 -354.548897) (xy 166.516851 -354.59851) (xy 166.532218 -354.650842)
			(xy 166.53998 -354.704829) (xy 166.53998 -354.759371) (xy 166.53998 -354.759374) (xy 168.022684 -354.759374)
			(xy 168.022684 -354.704826) (xy 168.030447 -354.650834) (xy 168.045816 -354.598496) (xy 168.068477 -354.548879)
			(xy 168.097969 -354.502991) (xy 168.133691 -354.461768) (xy 168.174917 -354.426049) (xy 168.220807 -354.396561)
			(xy 168.270426 -354.373904) (xy 168.322765 -354.35854) (xy 168.376758 -354.350781) (xy 168.404032 -354.35032)
			(xy 169.267632 -354.35032) (xy 169.294899 -354.350845) (xy 169.348876 -354.35861) (xy 169.401199 -354.373977)
			(xy 169.450803 -354.396634) (xy 169.496678 -354.426119) (xy 169.53789 -354.461833) (xy 169.5736 -354.503048)
			(xy 169.603081 -354.548925) (xy 169.625734 -354.598531) (xy 169.641097 -354.650855) (xy 169.648858 -354.704833)
			(xy 169.648858 -354.759367) (xy 169.648858 -354.75937) (xy 171.131706 -354.75937) (xy 171.131706 -354.70483)
			(xy 171.139468 -354.650844) (xy 171.154834 -354.598513) (xy 171.177491 -354.548901) (xy 171.206977 -354.503018)
			(xy 171.242693 -354.461799) (xy 171.283912 -354.426082) (xy 171.329794 -354.396594) (xy 171.379405 -354.373937)
			(xy 171.431736 -354.35857) (xy 171.485722 -354.350807) (xy 171.512992 -354.35032) (xy 172.376592 -354.35032)
			(xy 172.403862 -354.350819) (xy 172.457847 -354.35858) (xy 172.510178 -354.373945) (xy 172.55979 -354.396601)
			(xy 172.605673 -354.426087) (xy 172.646892 -354.461802) (xy 172.682609 -354.503021) (xy 172.712096 -354.548903)
			(xy 172.734753 -354.598514) (xy 172.750119 -354.650845) (xy 172.757881 -354.70483) (xy 172.757881 -354.759368)
			(xy 174.240706 -354.759368) (xy 174.240706 -354.704832) (xy 174.248467 -354.65085) (xy 174.263831 -354.598521)
			(xy 174.286485 -354.548912) (xy 174.315967 -354.503031) (xy 174.351679 -354.461813) (xy 174.392893 -354.426096)
			(xy 174.43877 -354.396608) (xy 174.488376 -354.373948) (xy 174.540703 -354.358577) (xy 174.594684 -354.35081)
			(xy 174.621952 -354.35032) (xy 175.485552 -354.35032) (xy 175.512824 -354.350816) (xy 175.566813 -354.358572)
			(xy 175.619149 -354.373934) (xy 175.668766 -354.396588) (xy 175.714654 -354.426072) (xy 175.755878 -354.461788)
			(xy 175.791599 -354.503008) (xy 175.821089 -354.548891) (xy 175.843749 -354.598506) (xy 175.859117 -354.65084)
			(xy 175.86688 -354.704828) (xy 175.86688 -354.759372) (xy 175.86688 -354.759373) (xy 177.349584 -354.759373)
			(xy 177.349584 -354.704827) (xy 177.357346 -354.650837) (xy 177.372714 -354.598501) (xy 177.395373 -354.548884)
			(xy 177.424864 -354.502998) (xy 177.460584 -354.461776) (xy 177.501808 -354.426056) (xy 177.547695 -354.396568)
			(xy 177.597312 -354.37391) (xy 177.649648 -354.358544) (xy 177.703639 -354.350783) (xy 177.730912 -354.35032)
			(xy 178.594512 -354.35032) (xy 178.62178 -354.350843) (xy 178.675759 -354.358606) (xy 178.728085 -354.373972)
			(xy 178.777691 -354.396627) (xy 178.823568 -354.426112) (xy 178.864783 -354.461826) (xy 178.900495 -354.503041)
			(xy 178.929978 -354.548919) (xy 178.952633 -354.598526) (xy 178.967997 -354.650852) (xy 178.975758 -354.704832)
			(xy 178.975758 -354.759368) (xy 178.975758 -354.759369) (xy 180.458606 -354.759369) (xy 180.458606 -354.704831)
			(xy 180.466368 -354.650847) (xy 180.481732 -354.598517) (xy 180.504388 -354.548907) (xy 180.533872 -354.503025)
			(xy 180.569586 -354.461806) (xy 180.610802 -354.426089) (xy 180.656682 -354.396601) (xy 180.706291 -354.373942)
			(xy 180.75862 -354.358574) (xy 180.812603 -354.350808) (xy 180.839872 -354.35032) (xy 181.703472 -354.35032)
			(xy 181.730743 -354.350818) (xy 181.78473 -354.358576) (xy 181.837064 -354.373939) (xy 181.886678 -354.396594)
			(xy 181.932563 -354.42608) (xy 181.973785 -354.461795) (xy 182.009504 -354.503014) (xy 182.038992 -354.548897)
			(xy 182.061651 -354.59851) (xy 182.077018 -354.650842) (xy 182.08478 -354.704829) (xy 182.08478 -354.735472)
			(xy 183.567508 -354.735472) (xy 183.567508 -354.680928) (xy 183.57527 -354.626939) (xy 183.590638 -354.574605)
			(xy 183.613298 -354.52499) (xy 183.642788 -354.479106) (xy 183.678508 -354.437885) (xy 183.719731 -354.402169)
			(xy 183.765618 -354.372682) (xy 183.815235 -354.350027) (xy 183.86757 -354.334664) (xy 183.92156 -354.326905)
			(xy 183.948832 -354.326444) (xy 184.812432 -354.326444) (xy 184.8397 -354.326921) (xy 184.893681 -354.334686)
			(xy 184.946008 -354.350054) (xy 184.995615 -354.372713) (xy 185.041492 -354.4022) (xy 185.082707 -354.437916)
			(xy 185.118419 -354.479133) (xy 185.147903 -354.525013) (xy 185.170557 -354.574622) (xy 185.185921 -354.62695)
			(xy 185.193682 -354.680932) (xy 185.193682 -354.735468) (xy 185.193682 -354.735469) (xy 186.67653 -354.735469)
			(xy 186.67653 -354.680931) (xy 186.684292 -354.626949) (xy 186.699656 -354.574621) (xy 186.722312 -354.525012)
			(xy 186.751796 -354.479133) (xy 186.78751 -354.437916) (xy 186.828726 -354.402201) (xy 186.874605 -354.372716)
			(xy 186.924214 -354.350059) (xy 186.976542 -354.334693) (xy 187.030523 -354.326931) (xy 187.057792 -354.326444)
			(xy 187.921392 -354.326444) (xy 187.948664 -354.326895) (xy 188.002652 -354.334656) (xy 188.054987 -354.350022)
			(xy 188.104602 -354.37268) (xy 188.150487 -354.402167) (xy 188.191709 -354.437885) (xy 188.227428 -354.479106)
			(xy 188.256917 -354.524991) (xy 188.279575 -354.574606) (xy 188.294942 -354.62694) (xy 188.302704 -354.680928)
			(xy 188.302704 -354.735472) (xy 188.299268 -354.759369) (xy 270.624806 -354.759369) (xy 270.624806 -354.704831)
			(xy 270.632567 -354.650848) (xy 270.647932 -354.598519) (xy 270.670586 -354.548909) (xy 270.70007 -354.503028)
			(xy 270.735783 -354.46181) (xy 270.776998 -354.426093) (xy 270.822876 -354.396604) (xy 270.872484 -354.373945)
			(xy 270.924811 -354.358575) (xy 270.978793 -354.350809) (xy 271.006062 -354.35032) (xy 271.869662 -354.35032)
			(xy 271.896933 -354.350817) (xy 271.950922 -354.358574) (xy 272.003257 -354.373936) (xy 272.052872 -354.396591)
			(xy 272.098759 -354.426076) (xy 272.139981 -354.461792) (xy 272.175701 -354.503011) (xy 272.205191 -354.548894)
			(xy 272.22785 -354.598508) (xy 272.243218 -354.650841) (xy 272.25098 -354.704829) (xy 272.25098 -354.759371)
			(xy 272.25098 -354.759373) (xy 273.733684 -354.759373) (xy 273.733684 -354.704827) (xy 273.741447 -354.650835)
			(xy 273.756815 -354.598498) (xy 273.779475 -354.548882) (xy 273.808966 -354.502995) (xy 273.844688 -354.461772)
			(xy 273.885912 -354.426053) (xy 273.931801 -354.396564) (xy 273.981419 -354.373907) (xy 274.033757 -354.358542)
			(xy 274.087749 -354.350782) (xy 274.115022 -354.35032) (xy 274.978622 -354.35032) (xy 275.005889 -354.350844)
			(xy 275.059868 -354.358608) (xy 275.112192 -354.373974) (xy 275.161797 -354.396631) (xy 275.207673 -354.426116)
			(xy 275.248886 -354.461829) (xy 275.284597 -354.503044) (xy 275.31408 -354.548922) (xy 275.336733 -354.598528)
			(xy 275.352097 -354.650854) (xy 275.359858 -354.704833) (xy 275.359858 -354.759367) (xy 275.359858 -354.75937)
			(xy 276.842706 -354.75937) (xy 276.842706 -354.70483) (xy 276.850468 -354.650846) (xy 276.865833 -354.598515)
			(xy 276.888489 -354.548904) (xy 276.917975 -354.503022) (xy 276.95369 -354.461802) (xy 276.994907 -354.426085)
			(xy 277.040788 -354.396598) (xy 277.090398 -354.373939) (xy 277.142728 -354.358572) (xy 277.196712 -354.350808)
			(xy 277.223982 -354.35032) (xy 278.087582 -354.35032) (xy 278.114853 -354.350818) (xy 278.168839 -354.358578)
			(xy 278.221171 -354.373942) (xy 278.270784 -354.396597) (xy 278.316668 -354.426083) (xy 278.357888 -354.461799)
			(xy 278.393606 -354.503018) (xy 278.423094 -354.5489) (xy 278.445752 -354.598512) (xy 278.461118 -354.650844)
			(xy 278.468881 -354.704829) (xy 278.468881 -354.759371) (xy 278.468881 -354.759374) (xy 279.951584 -354.759374)
			(xy 279.951584 -354.704826) (xy 279.959347 -354.650833) (xy 279.974716 -354.598494) (xy 279.997378 -354.548876)
			(xy 280.026871 -354.502988) (xy 280.062595 -354.461765) (xy 280.103822 -354.426046) (xy 280.149713 -354.396558)
			(xy 280.199334 -354.373902) (xy 280.251674 -354.358538) (xy 280.305668 -354.350781) (xy 280.332942 -354.35032)
			(xy 281.196542 -354.35032) (xy 281.223808 -354.350845) (xy 281.277785 -354.358611) (xy 281.330107 -354.37398)
			(xy 281.379709 -354.396637) (xy 281.425583 -354.426123) (xy 281.466793 -354.461836) (xy 281.502502 -354.503051)
			(xy 281.531983 -354.548928) (xy 281.554635 -354.598533) (xy 281.569998 -354.650856) (xy 281.577758 -354.704834)
			(xy 281.577758 -354.759366) (xy 281.577757 -354.759372) (xy 283.060584 -354.759372) (xy 283.060584 -354.704828)
			(xy 283.068346 -354.650838) (xy 283.083713 -354.598503) (xy 283.106372 -354.548887) (xy 283.135861 -354.503001)
			(xy 283.171581 -354.461779) (xy 283.212803 -354.42606) (xy 283.258689 -354.396571) (xy 283.308305 -354.373912)
			(xy 283.36064 -354.358546) (xy 283.41463 -354.350783) (xy 283.441902 -354.35032) (xy 284.305502 -354.35032)
			(xy 284.33277 -354.350843) (xy 284.386751 -354.358604) (xy 284.439078 -354.373969) (xy 284.488685 -354.396624)
			(xy 284.534564 -354.426109) (xy 284.575779 -354.461822) (xy 284.611493 -354.503038) (xy 284.640977 -354.548917)
			(xy 284.663632 -354.598524) (xy 284.678996 -354.650851) (xy 284.686758 -354.704832) (xy 284.686758 -354.759368)
			(xy 284.686758 -354.759369) (xy 286.169606 -354.759369) (xy 286.169606 -354.704831) (xy 286.177367 -354.650848)
			(xy 286.192732 -354.598519) (xy 286.215386 -354.548909) (xy 286.24487 -354.503028) (xy 286.280583 -354.46181)
			(xy 286.321798 -354.426093) (xy 286.367676 -354.396604) (xy 286.417284 -354.373945) (xy 286.469611 -354.358575)
			(xy 286.523593 -354.350809) (xy 286.550862 -354.35032) (xy 287.414462 -354.35032) (xy 287.441733 -354.350817)
			(xy 287.495722 -354.358574) (xy 287.548057 -354.373936) (xy 287.597672 -354.396591) (xy 287.643559 -354.426076)
			(xy 287.684781 -354.461792) (xy 287.720501 -354.503011) (xy 287.749991 -354.548894) (xy 287.77265 -354.598508)
			(xy 287.788018 -354.650841) (xy 287.79578 -354.704829) (xy 287.79578 -354.759371) (xy 287.79578 -354.759373)
			(xy 289.278484 -354.759373) (xy 289.278484 -354.704827) (xy 289.286247 -354.650835) (xy 289.301615 -354.598498)
			(xy 289.324275 -354.548882) (xy 289.353766 -354.502995) (xy 289.389488 -354.461772) (xy 289.430712 -354.426053)
			(xy 289.476601 -354.396564) (xy 289.526219 -354.373907) (xy 289.578557 -354.358542) (xy 289.632549 -354.350782)
			(xy 289.659822 -354.35032) (xy 290.523422 -354.35032) (xy 290.550689 -354.350844) (xy 290.604668 -354.358608)
			(xy 290.656992 -354.373974) (xy 290.706597 -354.396631) (xy 290.752473 -354.426116) (xy 290.793686 -354.461829)
			(xy 290.829397 -354.503044) (xy 290.85888 -354.548922) (xy 290.881533 -354.598528) (xy 290.896897 -354.650854)
			(xy 290.904658 -354.704833) (xy 290.904658 -354.759367) (xy 290.904658 -354.75937) (xy 292.387506 -354.75937)
			(xy 292.387506 -354.70483) (xy 292.395268 -354.650846) (xy 292.410633 -354.598515) (xy 292.433289 -354.548904)
			(xy 292.462775 -354.503022) (xy 292.49849 -354.461802) (xy 292.539707 -354.426085) (xy 292.585588 -354.396598)
			(xy 292.635198 -354.373939) (xy 292.687528 -354.358572) (xy 292.741512 -354.350808) (xy 292.768782 -354.35032)
			(xy 293.632382 -354.35032) (xy 293.659653 -354.350818) (xy 293.713639 -354.358578) (xy 293.765971 -354.373942)
			(xy 293.815584 -354.396597) (xy 293.861468 -354.426083) (xy 293.902688 -354.461799) (xy 293.938406 -354.503018)
			(xy 293.967894 -354.5489) (xy 293.990552 -354.598512) (xy 294.005918 -354.650844) (xy 294.013681 -354.704829)
			(xy 294.013681 -354.759371) (xy 294.013681 -354.759374) (xy 295.496384 -354.759374) (xy 295.496384 -354.704826)
			(xy 295.504147 -354.650833) (xy 295.519516 -354.598494) (xy 295.542178 -354.548876) (xy 295.571671 -354.502988)
			(xy 295.607395 -354.461765) (xy 295.648622 -354.426046) (xy 295.694513 -354.396558) (xy 295.744134 -354.373902)
			(xy 295.796474 -354.358538) (xy 295.850468 -354.350781) (xy 295.877742 -354.35032) (xy 296.741342 -354.35032)
			(xy 296.768608 -354.350845) (xy 296.822585 -354.358611) (xy 296.874907 -354.37398) (xy 296.924509 -354.396637)
			(xy 296.970383 -354.426123) (xy 297.011593 -354.461836) (xy 297.047302 -354.503051) (xy 297.076783 -354.548928)
			(xy 297.099435 -354.598533) (xy 297.114798 -354.650856) (xy 297.122558 -354.704834) (xy 297.122558 -354.759366)
			(xy 297.122557 -354.759372) (xy 298.605384 -354.759372) (xy 298.605384 -354.704828) (xy 298.613146 -354.650838)
			(xy 298.628513 -354.598503) (xy 298.651172 -354.548887) (xy 298.680661 -354.503001) (xy 298.716381 -354.461779)
			(xy 298.757603 -354.42606) (xy 298.803489 -354.396571) (xy 298.853105 -354.373912) (xy 298.90544 -354.358546)
			(xy 298.95943 -354.350783) (xy 298.986702 -354.35032) (xy 299.850302 -354.35032) (xy 299.87757 -354.350843)
			(xy 299.931551 -354.358604) (xy 299.983878 -354.373969) (xy 300.033485 -354.396624) (xy 300.079364 -354.426109)
			(xy 300.120579 -354.461822) (xy 300.156293 -354.503038) (xy 300.185777 -354.548917) (xy 300.208432 -354.598524)
			(xy 300.223796 -354.650851) (xy 300.231558 -354.704832) (xy 300.231558 -354.759368) (xy 300.231558 -354.759369)
			(xy 315.230506 -354.759369) (xy 315.230506 -354.704831) (xy 315.238267 -354.650848) (xy 315.253632 -354.598519)
			(xy 315.276286 -354.548909) (xy 315.30577 -354.503027) (xy 315.341483 -354.461809) (xy 315.382699 -354.426092)
			(xy 315.428577 -354.396604) (xy 315.478185 -354.373944) (xy 315.530513 -354.358575) (xy 315.584495 -354.350809)
			(xy 315.611764 -354.35032) (xy 316.475364 -354.35032) (xy 316.502635 -354.350817) (xy 316.556624 -354.358575)
			(xy 316.608958 -354.373937) (xy 316.658574 -354.396591) (xy 316.70446 -354.426077) (xy 316.745682 -354.461793)
			(xy 316.781402 -354.503012) (xy 316.810891 -354.548895) (xy 316.83355 -354.598508) (xy 316.848918 -354.650841)
			(xy 316.85668 -354.704829) (xy 316.85668 -354.759371) (xy 316.85668 -354.759373) (xy 318.339384 -354.759373)
			(xy 318.339384 -354.704827) (xy 318.347147 -354.650835) (xy 318.362515 -354.598498) (xy 318.385175 -354.548881)
			(xy 318.414667 -354.502994) (xy 318.450388 -354.461771) (xy 318.491613 -354.426052) (xy 318.537502 -354.396564)
			(xy 318.587121 -354.373907) (xy 318.639459 -354.358542) (xy 318.693451 -354.350782) (xy 318.720724 -354.35032)
			(xy 319.584324 -354.35032) (xy 319.611591 -354.350844) (xy 319.665569 -354.358608) (xy 319.717894 -354.373975)
			(xy 319.767498 -354.396631) (xy 319.813374 -354.426116) (xy 319.854587 -354.46183) (xy 319.890298 -354.503045)
			(xy 319.91978 -354.548923) (xy 319.942434 -354.598529) (xy 319.957797 -354.650854) (xy 319.965558 -354.704833)
			(xy 319.965558 -354.759367) (xy 319.965558 -354.75937) (xy 321.448406 -354.75937) (xy 321.448406 -354.70483)
			(xy 321.456168 -354.650845) (xy 321.471533 -354.598515) (xy 321.494189 -354.548903) (xy 321.523675 -354.503021)
			(xy 321.55939 -354.461802) (xy 321.600608 -354.426085) (xy 321.646489 -354.396597) (xy 321.6961 -354.373939)
			(xy 321.74843 -354.358571) (xy 321.802414 -354.350808) (xy 321.829684 -354.35032) (xy 322.693284 -354.35032)
			(xy 322.720554 -354.350818) (xy 322.774541 -354.358578) (xy 322.826873 -354.373942) (xy 322.876485 -354.396598)
			(xy 322.922369 -354.426084) (xy 322.963589 -354.4618) (xy 322.999307 -354.503018) (xy 323.028794 -354.5489)
			(xy 323.051452 -354.598512) (xy 323.066818 -354.650844) (xy 323.074581 -354.70483) (xy 323.074581 -354.75937)
			(xy 323.07458 -354.759374) (xy 324.557284 -354.759374) (xy 324.557284 -354.704826) (xy 324.565047 -354.650832)
			(xy 324.580417 -354.598494) (xy 324.603078 -354.548875) (xy 324.632571 -354.502987) (xy 324.668295 -354.461764)
			(xy 324.709523 -354.426045) (xy 324.755414 -354.396557) (xy 324.805035 -354.373901) (xy 324.857375 -354.358538)
			(xy 324.91137 -354.350781) (xy 324.938644 -354.35032) (xy 325.802244 -354.35032) (xy 325.82951 -354.350845)
			(xy 325.883486 -354.358612) (xy 325.935808 -354.37398) (xy 325.98541 -354.396638) (xy 326.031284 -354.426124)
			(xy 326.072494 -354.461837) (xy 326.108203 -354.503052) (xy 326.137683 -354.548928) (xy 326.160335 -354.598533)
			(xy 326.175698 -354.650857) (xy 326.183458 -354.704834) (xy 326.183458 -354.759366) (xy 326.183457 -354.759372)
			(xy 327.666284 -354.759372) (xy 327.666284 -354.704828) (xy 327.674046 -354.650838) (xy 327.689413 -354.598502)
			(xy 327.712072 -354.548887) (xy 327.741562 -354.503001) (xy 327.777281 -354.461778) (xy 327.818504 -354.426059)
			(xy 327.86439 -354.39657) (xy 327.914006 -354.373912) (xy 327.966342 -354.358545) (xy 328.020332 -354.350783)
			(xy 328.047604 -354.35032) (xy 328.911204 -354.35032) (xy 328.938472 -354.350843) (xy 328.992453 -354.358604)
			(xy 329.044779 -354.373969) (xy 329.094386 -354.396625) (xy 329.140265 -354.426109) (xy 329.18148 -354.461823)
			(xy 329.217193 -354.503039) (xy 329.246677 -354.548917) (xy 329.269332 -354.598525) (xy 329.284696 -354.650851)
			(xy 329.292458 -354.704832) (xy 329.292458 -354.759368) (xy 329.292458 -354.759369) (xy 330.775306 -354.759369)
			(xy 330.775306 -354.704831) (xy 330.783067 -354.650848) (xy 330.798432 -354.598519) (xy 330.821086 -354.548909)
			(xy 330.85057 -354.503027) (xy 330.886283 -354.461809) (xy 330.927499 -354.426092) (xy 330.973377 -354.396604)
			(xy 331.022985 -354.373944) (xy 331.075313 -354.358575) (xy 331.129295 -354.350809) (xy 331.156564 -354.35032)
			(xy 332.020164 -354.35032) (xy 332.047435 -354.350817) (xy 332.101424 -354.358575) (xy 332.153758 -354.373937)
			(xy 332.203374 -354.396591) (xy 332.24926 -354.426077) (xy 332.290482 -354.461793) (xy 332.326202 -354.503012)
			(xy 332.355691 -354.548895) (xy 332.37835 -354.598508) (xy 332.393718 -354.650841) (xy 332.40148 -354.704829)
			(xy 332.40148 -354.759371) (xy 332.40148 -354.759373) (xy 333.884184 -354.759373) (xy 333.884184 -354.704827)
			(xy 333.891947 -354.650835) (xy 333.907315 -354.598498) (xy 333.929975 -354.548881) (xy 333.959467 -354.502994)
			(xy 333.995188 -354.461771) (xy 334.036413 -354.426052) (xy 334.082302 -354.396564) (xy 334.131921 -354.373907)
			(xy 334.184259 -354.358542) (xy 334.238251 -354.350782) (xy 334.265524 -354.35032) (xy 335.129124 -354.35032)
			(xy 335.156391 -354.350844) (xy 335.210369 -354.358608) (xy 335.262694 -354.373975) (xy 335.312298 -354.396631)
			(xy 335.358174 -354.426116) (xy 335.399387 -354.46183) (xy 335.435098 -354.503045) (xy 335.46458 -354.548923)
			(xy 335.487234 -354.598529) (xy 335.502597 -354.650854) (xy 335.510358 -354.704833) (xy 335.510358 -354.759367)
			(xy 335.510358 -354.75937) (xy 336.993206 -354.75937) (xy 336.993206 -354.70483) (xy 337.000968 -354.650845)
			(xy 337.016333 -354.598515) (xy 337.038989 -354.548903) (xy 337.068475 -354.503021) (xy 337.10419 -354.461802)
			(xy 337.145408 -354.426085) (xy 337.191289 -354.396597) (xy 337.2409 -354.373939) (xy 337.29323 -354.358571)
			(xy 337.347214 -354.350808) (xy 337.374484 -354.35032) (xy 338.238084 -354.35032) (xy 338.265354 -354.350818)
			(xy 338.319341 -354.358578) (xy 338.371673 -354.373942) (xy 338.421285 -354.396598) (xy 338.467169 -354.426084)
			(xy 338.508389 -354.4618) (xy 338.544107 -354.503018) (xy 338.573594 -354.5489) (xy 338.596252 -354.598512)
			(xy 338.611618 -354.650844) (xy 338.619381 -354.70483) (xy 338.619381 -354.75937) (xy 338.61938 -354.759374)
			(xy 340.102084 -354.759374) (xy 340.102084 -354.704826) (xy 340.109847 -354.650832) (xy 340.125217 -354.598494)
			(xy 340.147878 -354.548875) (xy 340.177371 -354.502987) (xy 340.213095 -354.461764) (xy 340.254323 -354.426045)
			(xy 340.300214 -354.396557) (xy 340.349835 -354.373901) (xy 340.402175 -354.358538) (xy 340.45617 -354.350781)
			(xy 340.483444 -354.35032) (xy 341.347044 -354.35032) (xy 341.37431 -354.350845) (xy 341.428286 -354.358612)
			(xy 341.480608 -354.37398) (xy 341.53021 -354.396638) (xy 341.576084 -354.426124) (xy 341.617294 -354.461837)
			(xy 341.653003 -354.503052) (xy 341.682483 -354.548928) (xy 341.705135 -354.598533) (xy 341.720498 -354.650857)
			(xy 341.728258 -354.704834) (xy 341.728258 -354.759366) (xy 341.728257 -354.759372) (xy 343.211084 -354.759372)
			(xy 343.211084 -354.704828) (xy 343.218846 -354.650838) (xy 343.234213 -354.598502) (xy 343.256872 -354.548887)
			(xy 343.286362 -354.503001) (xy 343.322081 -354.461778) (xy 343.363304 -354.426059) (xy 343.40919 -354.39657)
			(xy 343.458806 -354.373912) (xy 343.511142 -354.358545) (xy 343.565132 -354.350783) (xy 343.592404 -354.35032)
			(xy 344.456004 -354.35032) (xy 344.483272 -354.350843) (xy 344.537253 -354.358604) (xy 344.589579 -354.373969)
			(xy 344.639186 -354.396625) (xy 344.685065 -354.426109) (xy 344.72628 -354.461823) (xy 344.761993 -354.503039)
			(xy 344.791477 -354.548917) (xy 344.814132 -354.598525) (xy 344.829496 -354.650851) (xy 344.837258 -354.704832)
			(xy 344.837258 -354.759368) (xy 344.837257 -354.759374) (xy 373.915584 -354.759374) (xy 373.915584 -354.704826)
			(xy 373.923347 -354.650833) (xy 373.938716 -354.598495) (xy 373.961378 -354.548876) (xy 373.990871 -354.502989)
			(xy 374.026594 -354.461766) (xy 374.067821 -354.426047) (xy 374.113712 -354.396559) (xy 374.163332 -354.373902)
			(xy 374.215672 -354.358539) (xy 374.269666 -354.350781) (xy 374.29694 -354.35032) (xy 375.16054 -354.35032)
			(xy 375.187806 -354.350845) (xy 375.241783 -354.358611) (xy 375.294105 -354.373979) (xy 375.343708 -354.396637)
			(xy 375.389582 -354.426122) (xy 375.430793 -354.461836) (xy 375.466502 -354.50305) (xy 375.495983 -354.548927)
			(xy 375.518635 -354.598532) (xy 375.533997 -354.650856) (xy 375.541758 -354.704834) (xy 375.541758 -354.759366)
			(xy 375.541757 -354.759371) (xy 377.024606 -354.759371) (xy 377.024606 -354.704829) (xy 377.032369 -354.650843)
			(xy 377.047735 -354.598511) (xy 377.070392 -354.548899) (xy 377.099879 -354.503016) (xy 377.135596 -354.461796)
			(xy 377.176816 -354.426079) (xy 377.222699 -354.396592) (xy 377.272311 -354.373935) (xy 377.324643 -354.358569)
			(xy 377.378629 -354.350806) (xy 377.4059 -354.35032) (xy 378.2695 -354.35032) (xy 378.296768 -354.350842)
			(xy 378.350749 -354.358604) (xy 378.403076 -354.373968) (xy 378.452684 -354.396623) (xy 378.498563 -354.426108)
			(xy 378.539778 -354.461822) (xy 378.575492 -354.503037) (xy 378.604977 -354.548916) (xy 378.627632 -354.598524)
			(xy 378.642996 -354.650851) (xy 378.650758 -354.704832) (xy 378.650758 -354.759368) (xy 378.650758 -354.759369)
			(xy 380.133606 -354.759369) (xy 380.133606 -354.704831) (xy 380.141367 -354.650849) (xy 380.156731 -354.59852)
			(xy 380.179386 -354.54891) (xy 380.208869 -354.503029) (xy 380.244582 -354.46181) (xy 380.285797 -354.426093)
			(xy 380.331675 -354.396605) (xy 380.381282 -354.373945) (xy 380.433609 -354.358576) (xy 380.487591 -354.350809)
			(xy 380.51486 -354.35032) (xy 381.37846 -354.35032) (xy 381.405732 -354.350817) (xy 381.45972 -354.358574)
			(xy 381.512055 -354.373936) (xy 381.561671 -354.39659) (xy 381.607558 -354.426075) (xy 381.648781 -354.461791)
			(xy 381.684501 -354.50301) (xy 381.713991 -354.548894) (xy 381.73665 -354.598507) (xy 381.752018 -354.650841)
			(xy 381.75978 -354.704828) (xy 381.75978 -354.759372) (xy 381.75978 -354.759373) (xy 383.242484 -354.759373)
			(xy 383.242484 -354.704827) (xy 383.250247 -354.650836) (xy 383.265615 -354.598499) (xy 383.288275 -354.548882)
			(xy 383.317766 -354.502995) (xy 383.353487 -354.461773) (xy 383.394711 -354.426054) (xy 383.4406 -354.396565)
			(xy 383.490218 -354.373908) (xy 383.542555 -354.358542) (xy 383.596547 -354.350782) (xy 383.62382 -354.35032)
			(xy 384.48742 -354.35032) (xy 384.514687 -354.350844) (xy 384.568666 -354.358607) (xy 384.620991 -354.373974)
			(xy 384.670596 -354.39663) (xy 384.716472 -354.426115) (xy 384.757686 -354.461829) (xy 384.793397 -354.503044)
			(xy 384.82288 -354.548922) (xy 384.845533 -354.598528) (xy 384.860897 -354.650854) (xy 384.868658 -354.704833)
			(xy 384.868658 -354.759367) (xy 384.868658 -354.75937) (xy 386.351506 -354.75937) (xy 386.351506 -354.70483)
			(xy 386.359268 -354.650846) (xy 386.374633 -354.598515) (xy 386.397289 -354.548904) (xy 386.426774 -354.503022)
			(xy 386.462489 -354.461803) (xy 386.503706 -354.426086) (xy 386.549587 -354.396598) (xy 386.599197 -354.37394)
			(xy 386.651526 -354.358572) (xy 386.70551 -354.350808) (xy 386.73278 -354.35032) (xy 387.59638 -354.35032)
			(xy 387.623651 -354.350818) (xy 387.677637 -354.358578) (xy 387.72997 -354.373941) (xy 387.779583 -354.396597)
			(xy 387.825467 -354.426082) (xy 387.866688 -354.461798) (xy 387.902406 -354.503017) (xy 387.931894 -354.548899)
			(xy 387.954552 -354.598511) (xy 387.969918 -354.650843) (xy 387.97768 -354.704829) (xy 387.97768 -354.759371)
			(xy 387.97768 -354.759374) (xy 389.460384 -354.759374) (xy 389.460384 -354.704826) (xy 389.468147 -354.650833)
			(xy 389.483516 -354.598495) (xy 389.506178 -354.548876) (xy 389.535671 -354.502989) (xy 389.571394 -354.461766)
			(xy 389.612621 -354.426047) (xy 389.658512 -354.396559) (xy 389.708132 -354.373902) (xy 389.760472 -354.358539)
			(xy 389.814466 -354.350781) (xy 389.84174 -354.35032) (xy 390.70534 -354.35032) (xy 390.732606 -354.350845)
			(xy 390.786583 -354.358611) (xy 390.838905 -354.373979) (xy 390.888508 -354.396637) (xy 390.934382 -354.426122)
			(xy 390.975593 -354.461836) (xy 391.011302 -354.50305) (xy 391.040783 -354.548927) (xy 391.063435 -354.598532)
			(xy 391.078797 -354.650856) (xy 391.086558 -354.704834) (xy 391.086558 -354.759366) (xy 391.086557 -354.759371)
			(xy 392.569406 -354.759371) (xy 392.569406 -354.704829) (xy 392.577169 -354.650843) (xy 392.592535 -354.598511)
			(xy 392.615192 -354.548899) (xy 392.644679 -354.503016) (xy 392.680396 -354.461796) (xy 392.721616 -354.426079)
			(xy 392.767499 -354.396592) (xy 392.817111 -354.373935) (xy 392.869443 -354.358569) (xy 392.923429 -354.350806)
			(xy 392.9507 -354.35032) (xy 393.8143 -354.35032) (xy 393.841568 -354.350842) (xy 393.895549 -354.358604)
			(xy 393.947876 -354.373968) (xy 393.997484 -354.396623) (xy 394.043363 -354.426108) (xy 394.084578 -354.461822)
			(xy 394.120292 -354.503037) (xy 394.149777 -354.548916) (xy 394.172432 -354.598524) (xy 394.187796 -354.650851)
			(xy 394.195558 -354.704832) (xy 394.195558 -354.759368) (xy 394.195558 -354.759369) (xy 395.678406 -354.759369)
			(xy 395.678406 -354.704831) (xy 395.686167 -354.650849) (xy 395.701531 -354.59852) (xy 395.724186 -354.54891)
			(xy 395.753669 -354.503029) (xy 395.789382 -354.46181) (xy 395.830597 -354.426093) (xy 395.876475 -354.396605)
			(xy 395.926082 -354.373945) (xy 395.978409 -354.358576) (xy 396.032391 -354.350809) (xy 396.05966 -354.35032)
			(xy 396.92326 -354.35032) (xy 396.950532 -354.350817) (xy 397.00452 -354.358574) (xy 397.056855 -354.373936)
			(xy 397.106471 -354.39659) (xy 397.152358 -354.426075) (xy 397.193581 -354.461791) (xy 397.229301 -354.50301)
			(xy 397.258791 -354.548894) (xy 397.28145 -354.598507) (xy 397.296818 -354.650841) (xy 397.30458 -354.704828)
			(xy 397.30458 -354.759372) (xy 397.30458 -354.759373) (xy 398.787284 -354.759373) (xy 398.787284 -354.704827)
			(xy 398.795047 -354.650836) (xy 398.810415 -354.598499) (xy 398.833075 -354.548882) (xy 398.862566 -354.502995)
			(xy 398.898287 -354.461773) (xy 398.939511 -354.426054) (xy 398.9854 -354.396565) (xy 399.035018 -354.373908)
			(xy 399.087355 -354.358542) (xy 399.141347 -354.350782) (xy 399.16862 -354.35032) (xy 400.03222 -354.35032)
			(xy 400.059487 -354.350844) (xy 400.113466 -354.358607) (xy 400.165791 -354.373974) (xy 400.215396 -354.39663)
			(xy 400.261272 -354.426115) (xy 400.302486 -354.461829) (xy 400.338197 -354.503044) (xy 400.36768 -354.548922)
			(xy 400.390333 -354.598528) (xy 400.405697 -354.650854) (xy 400.413458 -354.704833) (xy 400.413458 -354.759367)
			(xy 400.413458 -354.75937) (xy 401.896306 -354.75937) (xy 401.896306 -354.70483) (xy 401.904068 -354.650846)
			(xy 401.919433 -354.598515) (xy 401.942089 -354.548904) (xy 401.971574 -354.503022) (xy 402.007289 -354.461803)
			(xy 402.048506 -354.426086) (xy 402.094387 -354.396598) (xy 402.143997 -354.37394) (xy 402.196326 -354.358572)
			(xy 402.25031 -354.350808) (xy 402.27758 -354.35032) (xy 403.14118 -354.35032) (xy 403.168451 -354.350818)
			(xy 403.222437 -354.358578) (xy 403.27477 -354.373941) (xy 403.324383 -354.396597) (xy 403.370267 -354.426082)
			(xy 403.411488 -354.461798) (xy 403.447206 -354.503017) (xy 403.476694 -354.548899) (xy 403.499352 -354.598511)
			(xy 403.514718 -354.650843) (xy 403.52248 -354.704829) (xy 403.52248 -354.759368) (xy 412.022806 -354.759368)
			(xy 412.022806 -354.704832) (xy 412.030567 -354.65085) (xy 412.045931 -354.598521) (xy 412.068585 -354.548912)
			(xy 412.098067 -354.503031) (xy 412.133779 -354.461813) (xy 412.174993 -354.426096) (xy 412.22087 -354.396608)
			(xy 412.270476 -354.373948) (xy 412.322803 -354.358577) (xy 412.376784 -354.35081) (xy 412.404052 -354.35032)
			(xy 413.267652 -354.35032) (xy 413.294924 -354.350816) (xy 413.348913 -354.358572) (xy 413.401249 -354.373934)
			(xy 413.450866 -354.396588) (xy 413.496754 -354.426072) (xy 413.537978 -354.461788) (xy 413.573699 -354.503008)
			(xy 413.603189 -354.548891) (xy 413.625849 -354.598506) (xy 413.641217 -354.65084) (xy 413.64898 -354.704828)
			(xy 413.64898 -354.759372) (xy 413.64898 -354.759373) (xy 415.131684 -354.759373) (xy 415.131684 -354.704827)
			(xy 415.139446 -354.650837) (xy 415.154814 -354.598501) (xy 415.177473 -354.548884) (xy 415.206964 -354.502998)
			(xy 415.242684 -354.461776) (xy 415.283908 -354.426056) (xy 415.329795 -354.396568) (xy 415.379412 -354.37391)
			(xy 415.431748 -354.358544) (xy 415.485739 -354.350783) (xy 415.513012 -354.35032) (xy 416.376612 -354.35032)
			(xy 416.40388 -354.350843) (xy 416.457859 -354.358606) (xy 416.510185 -354.373972) (xy 416.559791 -354.396627)
			(xy 416.605668 -354.426112) (xy 416.646883 -354.461826) (xy 416.682595 -354.503041) (xy 416.712078 -354.548919)
			(xy 416.734733 -354.598526) (xy 416.750097 -354.650852) (xy 416.757858 -354.704832) (xy 416.757858 -354.759368)
			(xy 416.757858 -354.759369) (xy 418.240706 -354.759369) (xy 418.240706 -354.704831) (xy 418.248468 -354.650847)
			(xy 418.263832 -354.598517) (xy 418.286488 -354.548907) (xy 418.315972 -354.503025) (xy 418.351686 -354.461806)
			(xy 418.392902 -354.426089) (xy 418.438782 -354.396601) (xy 418.488391 -354.373942) (xy 418.54072 -354.358574)
			(xy 418.594703 -354.350808) (xy 418.621972 -354.35032) (xy 419.485572 -354.35032) (xy 419.512843 -354.350818)
			(xy 419.56683 -354.358576) (xy 419.619164 -354.373939) (xy 419.668778 -354.396594) (xy 419.714663 -354.42608)
			(xy 419.755885 -354.461795) (xy 419.791604 -354.503014) (xy 419.821092 -354.548897) (xy 419.843751 -354.59851)
			(xy 419.859118 -354.650842) (xy 419.86688 -354.704829) (xy 419.86688 -354.759371) (xy 419.86688 -354.759374)
			(xy 421.349584 -354.759374) (xy 421.349584 -354.704826) (xy 421.357347 -354.650834) (xy 421.372716 -354.598496)
			(xy 421.395377 -354.548879) (xy 421.424869 -354.502991) (xy 421.460591 -354.461768) (xy 421.501817 -354.426049)
			(xy 421.547707 -354.396561) (xy 421.597326 -354.373904) (xy 421.649665 -354.35854) (xy 421.703658 -354.350781)
			(xy 421.730932 -354.35032) (xy 422.594532 -354.35032) (xy 422.621799 -354.350845) (xy 422.675776 -354.35861)
			(xy 422.728099 -354.373977) (xy 422.777703 -354.396634) (xy 422.823578 -354.426119) (xy 422.86479 -354.461833)
			(xy 422.9005 -354.503048) (xy 422.929981 -354.548925) (xy 422.952634 -354.598531) (xy 422.967997 -354.650855)
			(xy 422.975758 -354.704833) (xy 422.975758 -354.759367) (xy 422.975758 -354.75937) (xy 424.458606 -354.75937)
			(xy 424.458606 -354.70483) (xy 424.466368 -354.650844) (xy 424.481734 -354.598513) (xy 424.504391 -354.548901)
			(xy 424.533877 -354.503018) (xy 424.569593 -354.461799) (xy 424.610812 -354.426082) (xy 424.656694 -354.396594)
			(xy 424.706305 -354.373937) (xy 424.758636 -354.35857) (xy 424.812622 -354.350807) (xy 424.839892 -354.35032)
			(xy 425.703492 -354.35032) (xy 425.730762 -354.350819) (xy 425.784747 -354.35858) (xy 425.837078 -354.373945)
			(xy 425.88669 -354.396601) (xy 425.932573 -354.426087) (xy 425.973792 -354.461802) (xy 426.009509 -354.503021)
			(xy 426.038996 -354.548903) (xy 426.061653 -354.598514) (xy 426.077019 -354.650845) (xy 426.084781 -354.70483)
			(xy 426.084781 -354.759368) (xy 427.567606 -354.759368) (xy 427.567606 -354.704832) (xy 427.575367 -354.65085)
			(xy 427.590731 -354.598521) (xy 427.613385 -354.548912) (xy 427.642867 -354.503031) (xy 427.678579 -354.461813)
			(xy 427.719793 -354.426096) (xy 427.76567 -354.396608) (xy 427.815276 -354.373948) (xy 427.867603 -354.358577)
			(xy 427.921584 -354.35081) (xy 427.948852 -354.35032) (xy 428.812452 -354.35032) (xy 428.839724 -354.350816)
			(xy 428.893713 -354.358572) (xy 428.946049 -354.373934) (xy 428.995666 -354.396588) (xy 429.041554 -354.426072)
			(xy 429.082778 -354.461788) (xy 429.118499 -354.503008) (xy 429.147989 -354.548891) (xy 429.170649 -354.598506)
			(xy 429.186017 -354.65084) (xy 429.19378 -354.704828) (xy 429.19378 -354.759372) (xy 429.19378 -354.759373)
			(xy 430.676484 -354.759373) (xy 430.676484 -354.704827) (xy 430.684246 -354.650837) (xy 430.699614 -354.598501)
			(xy 430.722273 -354.548884) (xy 430.751764 -354.502998) (xy 430.787484 -354.461776) (xy 430.828708 -354.426056)
			(xy 430.874595 -354.396568) (xy 430.924212 -354.37391) (xy 430.976548 -354.358544) (xy 431.030539 -354.350783)
			(xy 431.057812 -354.35032) (xy 431.921412 -354.35032) (xy 431.94868 -354.350843) (xy 432.002659 -354.358606)
			(xy 432.054985 -354.373972) (xy 432.104591 -354.396627) (xy 432.150468 -354.426112) (xy 432.191683 -354.461826)
			(xy 432.227395 -354.503041) (xy 432.256878 -354.548919) (xy 432.279533 -354.598526) (xy 432.294897 -354.650852)
			(xy 432.302658 -354.704832) (xy 432.302658 -354.759368) (xy 432.302658 -354.759369) (xy 433.785506 -354.759369)
			(xy 433.785506 -354.704831) (xy 433.793268 -354.650847) (xy 433.808632 -354.598517) (xy 433.831288 -354.548907)
			(xy 433.860772 -354.503025) (xy 433.896486 -354.461806) (xy 433.937702 -354.426089) (xy 433.983582 -354.396601)
			(xy 434.033191 -354.373942) (xy 434.08552 -354.358574) (xy 434.139503 -354.350808) (xy 434.166772 -354.35032)
			(xy 435.030372 -354.35032) (xy 435.057643 -354.350818) (xy 435.11163 -354.358576) (xy 435.163964 -354.373939)
			(xy 435.213578 -354.396594) (xy 435.259463 -354.42608) (xy 435.300685 -354.461795) (xy 435.336404 -354.503014)
			(xy 435.365892 -354.548897) (xy 435.388551 -354.59851) (xy 435.403918 -354.650842) (xy 435.41168 -354.704829)
			(xy 435.41168 -354.759371) (xy 435.41168 -354.759374) (xy 436.894384 -354.759374) (xy 436.894384 -354.704826)
			(xy 436.902147 -354.650834) (xy 436.917516 -354.598496) (xy 436.940177 -354.548879) (xy 436.969669 -354.502991)
			(xy 437.005391 -354.461768) (xy 437.046617 -354.426049) (xy 437.092507 -354.396561) (xy 437.142126 -354.373904)
			(xy 437.194465 -354.35854) (xy 437.248458 -354.350781) (xy 437.275732 -354.35032) (xy 438.139332 -354.35032)
			(xy 438.166599 -354.350845) (xy 438.220576 -354.35861) (xy 438.272899 -354.373977) (xy 438.322503 -354.396634)
			(xy 438.368378 -354.426119) (xy 438.40959 -354.461833) (xy 438.4453 -354.503048) (xy 438.474781 -354.548925)
			(xy 438.497434 -354.598531) (xy 438.512797 -354.650855) (xy 438.520558 -354.704833) (xy 438.520558 -354.759367)
			(xy 438.520558 -354.75937) (xy 440.003406 -354.75937) (xy 440.003406 -354.70483) (xy 440.011168 -354.650844)
			(xy 440.026534 -354.598513) (xy 440.049191 -354.548901) (xy 440.078677 -354.503018) (xy 440.114393 -354.461799)
			(xy 440.155612 -354.426082) (xy 440.201494 -354.396594) (xy 440.251105 -354.373937) (xy 440.303436 -354.35857)
			(xy 440.357422 -354.350807) (xy 440.384692 -354.35032) (xy 441.248292 -354.35032) (xy 441.275562 -354.350819)
			(xy 441.329547 -354.35858) (xy 441.381878 -354.373945) (xy 441.43149 -354.396601) (xy 441.477373 -354.426087)
			(xy 441.518592 -354.461802) (xy 441.554309 -354.503021) (xy 441.583796 -354.548903) (xy 441.606453 -354.598514)
			(xy 441.621819 -354.650845) (xy 441.629581 -354.70483) (xy 441.629581 -354.75937) (xy 441.621819 -354.813355)
			(xy 441.606453 -354.865686) (xy 441.583796 -354.915297) (xy 441.554309 -354.961179) (xy 441.518592 -355.002398)
			(xy 441.477373 -355.038113) (xy 441.43149 -355.067599) (xy 441.381878 -355.090255) (xy 441.329547 -355.10562)
			(xy 441.275562 -355.113381) (xy 441.248292 -355.113844) (xy 440.384692 -355.113844) (xy 440.357422 -355.113393)
			(xy 440.303436 -355.10563) (xy 440.251105 -355.090263) (xy 440.201494 -355.067606) (xy 440.155612 -355.038118)
			(xy 440.114393 -355.002401) (xy 440.078677 -354.961182) (xy 440.049191 -354.915299) (xy 440.026534 -354.865687)
			(xy 440.011168 -354.813356) (xy 440.003406 -354.75937) (xy 438.520558 -354.75937) (xy 438.512797 -354.813345)
			(xy 438.497434 -354.865669) (xy 438.474781 -354.915275) (xy 438.4453 -354.961152) (xy 438.40959 -355.002367)
			(xy 438.368378 -355.038081) (xy 438.322503 -355.067566) (xy 438.272899 -355.090223) (xy 438.220576 -355.10559)
			(xy 438.166599 -355.113355) (xy 438.139332 -355.113844) (xy 437.275732 -355.113844) (xy 437.248458 -355.113419)
			(xy 437.194465 -355.10566) (xy 437.142126 -355.090296) (xy 437.092507 -355.067639) (xy 437.046617 -355.038151)
			(xy 437.005391 -355.002432) (xy 436.969669 -354.961209) (xy 436.940177 -354.915321) (xy 436.917516 -354.865704)
			(xy 436.902147 -354.813366) (xy 436.894384 -354.759374) (xy 435.41168 -354.759374) (xy 435.403918 -354.813358)
			(xy 435.388551 -354.86569) (xy 435.365892 -354.915303) (xy 435.336404 -354.961186) (xy 435.300685 -355.002405)
			(xy 435.259463 -355.03812) (xy 435.213578 -355.067606) (xy 435.163964 -355.090261) (xy 435.11163 -355.105624)
			(xy 435.057643 -355.113382) (xy 435.030372 -355.113844) (xy 434.166772 -355.113844) (xy 434.139503 -355.113392)
			(xy 434.08552 -355.105626) (xy 434.033191 -355.090258) (xy 433.983582 -355.067599) (xy 433.937702 -355.038111)
			(xy 433.896486 -355.002394) (xy 433.860772 -354.961175) (xy 433.831288 -354.915293) (xy 433.808632 -354.865683)
			(xy 433.793268 -354.813353) (xy 433.785506 -354.759369) (xy 432.302658 -354.759369) (xy 432.294897 -354.813348)
			(xy 432.279533 -354.865674) (xy 432.256878 -354.915281) (xy 432.227395 -354.961159) (xy 432.191683 -355.002374)
			(xy 432.150468 -355.038088) (xy 432.104591 -355.067573) (xy 432.054985 -355.090228) (xy 432.002659 -355.105594)
			(xy 431.94868 -355.113357) (xy 431.921412 -355.113844) (xy 431.057812 -355.113844) (xy 431.030539 -355.113417)
			(xy 430.976548 -355.105656) (xy 430.924212 -355.09029) (xy 430.874595 -355.067632) (xy 430.828708 -355.038144)
			(xy 430.787484 -355.002424) (xy 430.751764 -354.961202) (xy 430.722273 -354.915316) (xy 430.699614 -354.865699)
			(xy 430.684246 -354.813363) (xy 430.676484 -354.759373) (xy 429.19378 -354.759373) (xy 429.186017 -354.81336)
			(xy 429.170649 -354.865694) (xy 429.147989 -354.915309) (xy 429.118499 -354.961192) (xy 429.082778 -355.002412)
			(xy 429.041554 -355.038128) (xy 428.995666 -355.067612) (xy 428.946049 -355.090266) (xy 428.893713 -355.105628)
			(xy 428.839724 -355.113384) (xy 428.812452 -355.113844) (xy 427.948852 -355.113844) (xy 427.921584 -355.11339)
			(xy 427.867603 -355.105623) (xy 427.815276 -355.090252) (xy 427.76567 -355.067592) (xy 427.719793 -355.038104)
			(xy 427.678579 -355.002387) (xy 427.642867 -354.961169) (xy 427.613385 -354.915288) (xy 427.590731 -354.865679)
			(xy 427.575367 -354.81335) (xy 427.567606 -354.759368) (xy 426.084781 -354.759368) (xy 426.084781 -354.75937)
			(xy 426.077019 -354.813355) (xy 426.061653 -354.865686) (xy 426.038996 -354.915297) (xy 426.009509 -354.961179)
			(xy 425.973792 -355.002398) (xy 425.932573 -355.038113) (xy 425.88669 -355.067599) (xy 425.837078 -355.090255)
			(xy 425.784747 -355.10562) (xy 425.730762 -355.113381) (xy 425.703492 -355.113844) (xy 424.839892 -355.113844)
			(xy 424.812622 -355.113393) (xy 424.758636 -355.10563) (xy 424.706305 -355.090263) (xy 424.656694 -355.067606)
			(xy 424.610812 -355.038118) (xy 424.569593 -355.002401) (xy 424.533877 -354.961182) (xy 424.504391 -354.915299)
			(xy 424.481734 -354.865687) (xy 424.466368 -354.813356) (xy 424.458606 -354.75937) (xy 422.975758 -354.75937)
			(xy 422.967997 -354.813345) (xy 422.952634 -354.865669) (xy 422.929981 -354.915275) (xy 422.9005 -354.961152)
			(xy 422.86479 -355.002367) (xy 422.823578 -355.038081) (xy 422.777703 -355.067566) (xy 422.728099 -355.090223)
			(xy 422.675776 -355.10559) (xy 422.621799 -355.113355) (xy 422.594532 -355.113844) (xy 421.730932 -355.113844)
			(xy 421.703658 -355.113419) (xy 421.649665 -355.10566) (xy 421.597326 -355.090296) (xy 421.547707 -355.067639)
			(xy 421.501817 -355.038151) (xy 421.460591 -355.002432) (xy 421.424869 -354.961209) (xy 421.395377 -354.915321)
			(xy 421.372716 -354.865704) (xy 421.357347 -354.813366) (xy 421.349584 -354.759374) (xy 419.86688 -354.759374)
			(xy 419.859118 -354.813358) (xy 419.843751 -354.86569) (xy 419.821092 -354.915303) (xy 419.791604 -354.961186)
			(xy 419.755885 -355.002405) (xy 419.714663 -355.03812) (xy 419.668778 -355.067606) (xy 419.619164 -355.090261)
			(xy 419.56683 -355.105624) (xy 419.512843 -355.113382) (xy 419.485572 -355.113844) (xy 418.621972 -355.113844)
			(xy 418.594703 -355.113392) (xy 418.54072 -355.105626) (xy 418.488391 -355.090258) (xy 418.438782 -355.067599)
			(xy 418.392902 -355.038111) (xy 418.351686 -355.002394) (xy 418.315972 -354.961175) (xy 418.286488 -354.915293)
			(xy 418.263832 -354.865683) (xy 418.248468 -354.813353) (xy 418.240706 -354.759369) (xy 416.757858 -354.759369)
			(xy 416.750097 -354.813348) (xy 416.734733 -354.865674) (xy 416.712078 -354.915281) (xy 416.682595 -354.961159)
			(xy 416.646883 -355.002374) (xy 416.605668 -355.038088) (xy 416.559791 -355.067573) (xy 416.510185 -355.090228)
			(xy 416.457859 -355.105594) (xy 416.40388 -355.113357) (xy 416.376612 -355.113844) (xy 415.513012 -355.113844)
			(xy 415.485739 -355.113417) (xy 415.431748 -355.105656) (xy 415.379412 -355.09029) (xy 415.329795 -355.067632)
			(xy 415.283908 -355.038144) (xy 415.242684 -355.002424) (xy 415.206964 -354.961202) (xy 415.177473 -354.915316)
			(xy 415.154814 -354.865699) (xy 415.139446 -354.813363) (xy 415.131684 -354.759373) (xy 413.64898 -354.759373)
			(xy 413.641217 -354.81336) (xy 413.625849 -354.865694) (xy 413.603189 -354.915309) (xy 413.573699 -354.961192)
			(xy 413.537978 -355.002412) (xy 413.496754 -355.038128) (xy 413.450866 -355.067612) (xy 413.401249 -355.090266)
			(xy 413.348913 -355.105628) (xy 413.294924 -355.113384) (xy 413.267652 -355.113844) (xy 412.404052 -355.113844)
			(xy 412.376784 -355.11339) (xy 412.322803 -355.105623) (xy 412.270476 -355.090252) (xy 412.22087 -355.067592)
			(xy 412.174993 -355.038104) (xy 412.133779 -355.002387) (xy 412.098067 -354.961169) (xy 412.068585 -354.915288)
			(xy 412.045931 -354.865679) (xy 412.030567 -354.81335) (xy 412.022806 -354.759368) (xy 403.52248 -354.759368)
			(xy 403.52248 -354.759371) (xy 403.514718 -354.813357) (xy 403.499352 -354.865689) (xy 403.476694 -354.915301)
			(xy 403.447206 -354.961183) (xy 403.411488 -355.002402) (xy 403.370267 -355.038118) (xy 403.324383 -355.067603)
			(xy 403.27477 -355.090259) (xy 403.222437 -355.105622) (xy 403.168451 -355.113382) (xy 403.14118 -355.113844)
			(xy 402.27758 -355.113844) (xy 402.25031 -355.113392) (xy 402.196326 -355.105628) (xy 402.143997 -355.09026)
			(xy 402.094387 -355.067602) (xy 402.048506 -355.038114) (xy 402.007289 -355.002397) (xy 401.971574 -354.961178)
			(xy 401.942089 -354.915296) (xy 401.919433 -354.865685) (xy 401.904068 -354.813354) (xy 401.896306 -354.75937)
			(xy 400.413458 -354.75937) (xy 400.405697 -354.813346) (xy 400.390333 -354.865672) (xy 400.36768 -354.915278)
			(xy 400.338197 -354.961156) (xy 400.302486 -355.002371) (xy 400.261272 -355.038085) (xy 400.215396 -355.06757)
			(xy 400.165791 -355.090226) (xy 400.113466 -355.105593) (xy 400.059487 -355.113356) (xy 400.03222 -355.113844)
			(xy 399.16862 -355.113844) (xy 399.141347 -355.113418) (xy 399.087355 -355.105658) (xy 399.035018 -355.090292)
			(xy 398.9854 -355.067635) (xy 398.939511 -355.038146) (xy 398.898287 -355.002427) (xy 398.862566 -354.961205)
			(xy 398.833075 -354.915318) (xy 398.810415 -354.865701) (xy 398.795047 -354.813364) (xy 398.787284 -354.759373)
			(xy 397.30458 -354.759373) (xy 397.296818 -354.813359) (xy 397.28145 -354.865693) (xy 397.258791 -354.915306)
			(xy 397.229301 -354.96119) (xy 397.193581 -355.002409) (xy 397.152358 -355.038125) (xy 397.106471 -355.06761)
			(xy 397.056855 -355.090264) (xy 397.00452 -355.105626) (xy 396.950532 -355.113383) (xy 396.92326 -355.113844)
			(xy 396.05966 -355.113844) (xy 396.032391 -355.113391) (xy 395.978409 -355.105624) (xy 395.926082 -355.090255)
			(xy 395.876475 -355.067595) (xy 395.830597 -355.038107) (xy 395.789382 -355.00239) (xy 395.753669 -354.961171)
			(xy 395.724186 -354.91529) (xy 395.701531 -354.86568) (xy 395.686167 -354.813351) (xy 395.678406 -354.759369)
			(xy 394.195558 -354.759369) (xy 394.187796 -354.813349) (xy 394.172432 -354.865676) (xy 394.149777 -354.915284)
			(xy 394.120292 -354.961163) (xy 394.084578 -355.002378) (xy 394.043363 -355.038092) (xy 393.997484 -355.067577)
			(xy 393.947876 -355.090232) (xy 393.895549 -355.105596) (xy 393.841568 -355.113358) (xy 393.8143 -355.113844)
			(xy 392.9507 -355.113844) (xy 392.923429 -355.113394) (xy 392.869443 -355.105631) (xy 392.817111 -355.090265)
			(xy 392.767499 -355.067608) (xy 392.721616 -355.038121) (xy 392.680396 -355.002404) (xy 392.644679 -354.961184)
			(xy 392.615192 -354.915301) (xy 392.592535 -354.865689) (xy 392.577169 -354.813357) (xy 392.569406 -354.759371)
			(xy 391.086557 -354.759371) (xy 391.078797 -354.813344) (xy 391.063435 -354.865668) (xy 391.040783 -354.915273)
			(xy 391.011302 -354.96115) (xy 390.975593 -355.002364) (xy 390.934382 -355.038078) (xy 390.888508 -355.067563)
			(xy 390.838905 -355.090221) (xy 390.786583 -355.105589) (xy 390.732606 -355.113355) (xy 390.70534 -355.113844)
			(xy 389.84174 -355.113844) (xy 389.814466 -355.113419) (xy 389.760472 -355.105661) (xy 389.708132 -355.090298)
			(xy 389.658512 -355.067641) (xy 389.612621 -355.038153) (xy 389.571394 -355.002434) (xy 389.535671 -354.961211)
			(xy 389.506178 -354.915324) (xy 389.483516 -354.865705) (xy 389.468147 -354.813367) (xy 389.460384 -354.759374)
			(xy 387.97768 -354.759374) (xy 387.969918 -354.813357) (xy 387.954552 -354.865689) (xy 387.931894 -354.915301)
			(xy 387.902406 -354.961183) (xy 387.866688 -355.002402) (xy 387.825467 -355.038118) (xy 387.779583 -355.067603)
			(xy 387.72997 -355.090259) (xy 387.677637 -355.105622) (xy 387.623651 -355.113382) (xy 387.59638 -355.113844)
			(xy 386.73278 -355.113844) (xy 386.70551 -355.113392) (xy 386.651526 -355.105628) (xy 386.599197 -355.09026)
			(xy 386.549587 -355.067602) (xy 386.503706 -355.038114) (xy 386.462489 -355.002397) (xy 386.426774 -354.961178)
			(xy 386.397289 -354.915296) (xy 386.374633 -354.865685) (xy 386.359268 -354.813354) (xy 386.351506 -354.75937)
			(xy 384.868658 -354.75937) (xy 384.860897 -354.813346) (xy 384.845533 -354.865672) (xy 384.82288 -354.915278)
			(xy 384.793397 -354.961156) (xy 384.757686 -355.002371) (xy 384.716472 -355.038085) (xy 384.670596 -355.06757)
			(xy 384.620991 -355.090226) (xy 384.568666 -355.105593) (xy 384.514687 -355.113356) (xy 384.48742 -355.113844)
			(xy 383.62382 -355.113844) (xy 383.596547 -355.113418) (xy 383.542555 -355.105658) (xy 383.490218 -355.090292)
			(xy 383.4406 -355.067635) (xy 383.394711 -355.038146) (xy 383.353487 -355.002427) (xy 383.317766 -354.961205)
			(xy 383.288275 -354.915318) (xy 383.265615 -354.865701) (xy 383.250247 -354.813364) (xy 383.242484 -354.759373)
			(xy 381.75978 -354.759373) (xy 381.752018 -354.813359) (xy 381.73665 -354.865693) (xy 381.713991 -354.915306)
			(xy 381.684501 -354.96119) (xy 381.648781 -355.002409) (xy 381.607558 -355.038125) (xy 381.561671 -355.06761)
			(xy 381.512055 -355.090264) (xy 381.45972 -355.105626) (xy 381.405732 -355.113383) (xy 381.37846 -355.113844)
			(xy 380.51486 -355.113844) (xy 380.487591 -355.113391) (xy 380.433609 -355.105624) (xy 380.381282 -355.090255)
			(xy 380.331675 -355.067595) (xy 380.285797 -355.038107) (xy 380.244582 -355.00239) (xy 380.208869 -354.961171)
			(xy 380.179386 -354.91529) (xy 380.156731 -354.86568) (xy 380.141367 -354.813351) (xy 380.133606 -354.759369)
			(xy 378.650758 -354.759369) (xy 378.642996 -354.813349) (xy 378.627632 -354.865676) (xy 378.604977 -354.915284)
			(xy 378.575492 -354.961163) (xy 378.539778 -355.002378) (xy 378.498563 -355.038092) (xy 378.452684 -355.067577)
			(xy 378.403076 -355.090232) (xy 378.350749 -355.105596) (xy 378.296768 -355.113358) (xy 378.2695 -355.113844)
			(xy 377.4059 -355.113844) (xy 377.378629 -355.113394) (xy 377.324643 -355.105631) (xy 377.272311 -355.090265)
			(xy 377.222699 -355.067608) (xy 377.176816 -355.038121) (xy 377.135596 -355.002404) (xy 377.099879 -354.961184)
			(xy 377.070392 -354.915301) (xy 377.047735 -354.865689) (xy 377.032369 -354.813357) (xy 377.024606 -354.759371)
			(xy 375.541757 -354.759371) (xy 375.533997 -354.813344) (xy 375.518635 -354.865668) (xy 375.495983 -354.915273)
			(xy 375.466502 -354.96115) (xy 375.430793 -355.002364) (xy 375.389582 -355.038078) (xy 375.343708 -355.067563)
			(xy 375.294105 -355.090221) (xy 375.241783 -355.105589) (xy 375.187806 -355.113355) (xy 375.16054 -355.113844)
			(xy 374.29694 -355.113844) (xy 374.269666 -355.113419) (xy 374.215672 -355.105661) (xy 374.163332 -355.090298)
			(xy 374.113712 -355.067641) (xy 374.067821 -355.038153) (xy 374.026594 -355.002434) (xy 373.990871 -354.961211)
			(xy 373.961378 -354.915324) (xy 373.938716 -354.865705) (xy 373.923347 -354.813367) (xy 373.915584 -354.759374)
			(xy 344.837257 -354.759374) (xy 344.829496 -354.813349) (xy 344.814132 -354.865675) (xy 344.791477 -354.915283)
			(xy 344.761993 -354.961161) (xy 344.72628 -355.002377) (xy 344.685065 -355.038091) (xy 344.639186 -355.067575)
			(xy 344.589579 -355.090231) (xy 344.537253 -355.105596) (xy 344.483272 -355.113357) (xy 344.456004 -355.113844)
			(xy 343.592404 -355.113844) (xy 343.565132 -355.113417) (xy 343.511142 -355.105655) (xy 343.458806 -355.090288)
			(xy 343.40919 -355.06763) (xy 343.363304 -355.038141) (xy 343.322081 -355.002422) (xy 343.286362 -354.961199)
			(xy 343.256872 -354.915313) (xy 343.234213 -354.865698) (xy 343.218846 -354.813362) (xy 343.211084 -354.759372)
			(xy 341.728257 -354.759372) (xy 341.720498 -354.813343) (xy 341.705135 -354.865667) (xy 341.682483 -354.915272)
			(xy 341.653003 -354.961148) (xy 341.617294 -355.002363) (xy 341.576084 -355.038076) (xy 341.53021 -355.067562)
			(xy 341.480608 -355.09022) (xy 341.428286 -355.105588) (xy 341.37431 -355.113355) (xy 341.347044 -355.113844)
			(xy 340.483444 -355.113844) (xy 340.45617 -355.113419) (xy 340.402175 -355.105662) (xy 340.349835 -355.090299)
			(xy 340.300214 -355.067643) (xy 340.254323 -355.038155) (xy 340.213095 -355.002436) (xy 340.177371 -354.961213)
			(xy 340.147878 -354.915325) (xy 340.125217 -354.865706) (xy 340.109847 -354.813368) (xy 340.102084 -354.759374)
			(xy 338.61938 -354.759374) (xy 338.611618 -354.813356) (xy 338.596252 -354.865688) (xy 338.573594 -354.9153)
			(xy 338.544107 -354.961182) (xy 338.508389 -355.0024) (xy 338.467169 -355.038116) (xy 338.421285 -355.067602)
			(xy 338.371673 -355.090258) (xy 338.319341 -355.105622) (xy 338.265354 -355.113382) (xy 338.238084 -355.113844)
			(xy 337.374484 -355.113844) (xy 337.347214 -355.113392) (xy 337.29323 -355.105629) (xy 337.2409 -355.090261)
			(xy 337.191289 -355.067603) (xy 337.145408 -355.038115) (xy 337.10419 -355.002398) (xy 337.068475 -354.961179)
			(xy 337.038989 -354.915297) (xy 337.016333 -354.865685) (xy 337.000968 -354.813355) (xy 336.993206 -354.75937)
			(xy 335.510358 -354.75937) (xy 335.502597 -354.813346) (xy 335.487234 -354.865671) (xy 335.46458 -354.915277)
			(xy 335.435098 -354.961155) (xy 335.399387 -355.00237) (xy 335.358174 -355.038084) (xy 335.312298 -355.067569)
			(xy 335.262694 -355.090225) (xy 335.210369 -355.105592) (xy 335.156391 -355.113356) (xy 335.129124 -355.113844)
			(xy 334.265524 -355.113844) (xy 334.238251 -355.113418) (xy 334.184259 -355.105658) (xy 334.131921 -355.090293)
			(xy 334.082302 -355.067636) (xy 334.036413 -355.038148) (xy 333.995188 -355.002429) (xy 333.959467 -354.961206)
			(xy 333.929975 -354.915319) (xy 333.907315 -354.865702) (xy 333.891947 -354.813365) (xy 333.884184 -354.759373)
			(xy 332.40148 -354.759373) (xy 332.393718 -354.813359) (xy 332.37835 -354.865692) (xy 332.355691 -354.915305)
			(xy 332.326202 -354.961188) (xy 332.290482 -355.002407) (xy 332.24926 -355.038123) (xy 332.203374 -355.067609)
			(xy 332.153758 -355.090263) (xy 332.101424 -355.105625) (xy 332.047435 -355.113383) (xy 332.020164 -355.113844)
			(xy 331.156564 -355.113844) (xy 331.129295 -355.113391) (xy 331.075313 -355.105625) (xy 331.022985 -355.090256)
			(xy 330.973377 -355.067596) (xy 330.927499 -355.038108) (xy 330.886283 -355.002391) (xy 330.85057 -354.961173)
			(xy 330.821086 -354.915291) (xy 330.798432 -354.865681) (xy 330.783067 -354.813352) (xy 330.775306 -354.759369)
			(xy 329.292458 -354.759369) (xy 329.284696 -354.813349) (xy 329.269332 -354.865675) (xy 329.246677 -354.915283)
			(xy 329.217193 -354.961161) (xy 329.18148 -355.002377) (xy 329.140265 -355.038091) (xy 329.094386 -355.067575)
			(xy 329.044779 -355.090231) (xy 328.992453 -355.105596) (xy 328.938472 -355.113357) (xy 328.911204 -355.113844)
			(xy 328.047604 -355.113844) (xy 328.020332 -355.113417) (xy 327.966342 -355.105655) (xy 327.914006 -355.090288)
			(xy 327.86439 -355.06763) (xy 327.818504 -355.038141) (xy 327.777281 -355.002422) (xy 327.741562 -354.961199)
			(xy 327.712072 -354.915313) (xy 327.689413 -354.865698) (xy 327.674046 -354.813362) (xy 327.666284 -354.759372)
			(xy 326.183457 -354.759372) (xy 326.175698 -354.813343) (xy 326.160335 -354.865667) (xy 326.137683 -354.915272)
			(xy 326.108203 -354.961148) (xy 326.072494 -355.002363) (xy 326.031284 -355.038076) (xy 325.98541 -355.067562)
			(xy 325.935808 -355.09022) (xy 325.883486 -355.105588) (xy 325.82951 -355.113355) (xy 325.802244 -355.113844)
			(xy 324.938644 -355.113844) (xy 324.91137 -355.113419) (xy 324.857375 -355.105662) (xy 324.805035 -355.090299)
			(xy 324.755414 -355.067643) (xy 324.709523 -355.038155) (xy 324.668295 -355.002436) (xy 324.632571 -354.961213)
			(xy 324.603078 -354.915325) (xy 324.580417 -354.865706) (xy 324.565047 -354.813368) (xy 324.557284 -354.759374)
			(xy 323.07458 -354.759374) (xy 323.066818 -354.813356) (xy 323.051452 -354.865688) (xy 323.028794 -354.9153)
			(xy 322.999307 -354.961182) (xy 322.963589 -355.0024) (xy 322.922369 -355.038116) (xy 322.876485 -355.067602)
			(xy 322.826873 -355.090258) (xy 322.774541 -355.105622) (xy 322.720554 -355.113382) (xy 322.693284 -355.113844)
			(xy 321.829684 -355.113844) (xy 321.802414 -355.113392) (xy 321.74843 -355.105629) (xy 321.6961 -355.090261)
			(xy 321.646489 -355.067603) (xy 321.600608 -355.038115) (xy 321.55939 -355.002398) (xy 321.523675 -354.961179)
			(xy 321.494189 -354.915297) (xy 321.471533 -354.865685) (xy 321.456168 -354.813355) (xy 321.448406 -354.75937)
			(xy 319.965558 -354.75937) (xy 319.957797 -354.813346) (xy 319.942434 -354.865671) (xy 319.91978 -354.915277)
			(xy 319.890298 -354.961155) (xy 319.854587 -355.00237) (xy 319.813374 -355.038084) (xy 319.767498 -355.067569)
			(xy 319.717894 -355.090225) (xy 319.665569 -355.105592) (xy 319.611591 -355.113356) (xy 319.584324 -355.113844)
			(xy 318.720724 -355.113844) (xy 318.693451 -355.113418) (xy 318.639459 -355.105658) (xy 318.587121 -355.090293)
			(xy 318.537502 -355.067636) (xy 318.491613 -355.038148) (xy 318.450388 -355.002429) (xy 318.414667 -354.961206)
			(xy 318.385175 -354.915319) (xy 318.362515 -354.865702) (xy 318.347147 -354.813365) (xy 318.339384 -354.759373)
			(xy 316.85668 -354.759373) (xy 316.848918 -354.813359) (xy 316.83355 -354.865692) (xy 316.810891 -354.915305)
			(xy 316.781402 -354.961188) (xy 316.745682 -355.002407) (xy 316.70446 -355.038123) (xy 316.658574 -355.067609)
			(xy 316.608958 -355.090263) (xy 316.556624 -355.105625) (xy 316.502635 -355.113383) (xy 316.475364 -355.113844)
			(xy 315.611764 -355.113844) (xy 315.584495 -355.113391) (xy 315.530513 -355.105625) (xy 315.478185 -355.090256)
			(xy 315.428577 -355.067596) (xy 315.382699 -355.038108) (xy 315.341483 -355.002391) (xy 315.30577 -354.961173)
			(xy 315.276286 -354.915291) (xy 315.253632 -354.865681) (xy 315.238267 -354.813352) (xy 315.230506 -354.759369)
			(xy 300.231558 -354.759369) (xy 300.223796 -354.813349) (xy 300.208432 -354.865676) (xy 300.185777 -354.915283)
			(xy 300.156293 -354.961162) (xy 300.120579 -355.002378) (xy 300.079364 -355.038091) (xy 300.033485 -355.067576)
			(xy 299.983878 -355.090231) (xy 299.931551 -355.105596) (xy 299.87757 -355.113357) (xy 299.850302 -355.113844)
			(xy 298.986702 -355.113844) (xy 298.95943 -355.113417) (xy 298.90544 -355.105654) (xy 298.853105 -355.090288)
			(xy 298.803489 -355.067629) (xy 298.757603 -355.03814) (xy 298.716381 -355.002421) (xy 298.680661 -354.961199)
			(xy 298.651172 -354.915313) (xy 298.628513 -354.865697) (xy 298.613146 -354.813362) (xy 298.605384 -354.759372)
			(xy 297.122557 -354.759372) (xy 297.114798 -354.813344) (xy 297.099435 -354.865667) (xy 297.076783 -354.915272)
			(xy 297.047302 -354.961149) (xy 297.011593 -355.002364) (xy 296.970383 -355.038077) (xy 296.924509 -355.067563)
			(xy 296.874907 -355.09022) (xy 296.822585 -355.105589) (xy 296.768608 -355.113355) (xy 296.741342 -355.113844)
			(xy 295.877742 -355.113844) (xy 295.850468 -355.113419) (xy 295.796474 -355.105662) (xy 295.744134 -355.090298)
			(xy 295.694513 -355.067642) (xy 295.648622 -355.038154) (xy 295.607395 -355.002435) (xy 295.571671 -354.961212)
			(xy 295.542178 -354.915324) (xy 295.519516 -354.865706) (xy 295.504147 -354.813367) (xy 295.496384 -354.759374)
			(xy 294.013681 -354.759374) (xy 294.005918 -354.813356) (xy 293.990552 -354.865688) (xy 293.967894 -354.9153)
			(xy 293.938406 -354.961182) (xy 293.902688 -355.002401) (xy 293.861468 -355.038117) (xy 293.815584 -355.067603)
			(xy 293.765971 -355.090258) (xy 293.713639 -355.105622) (xy 293.659653 -355.113382) (xy 293.632382 -355.113844)
			(xy 292.768782 -355.113844) (xy 292.741512 -355.113392) (xy 292.687528 -355.105628) (xy 292.635198 -355.090261)
			(xy 292.585588 -355.067602) (xy 292.539707 -355.038115) (xy 292.49849 -355.002398) (xy 292.462775 -354.961178)
			(xy 292.433289 -354.915296) (xy 292.410633 -354.865685) (xy 292.395268 -354.813354) (xy 292.387506 -354.75937)
			(xy 290.904658 -354.75937) (xy 290.896897 -354.813346) (xy 290.881533 -354.865672) (xy 290.85888 -354.915278)
			(xy 290.829397 -354.961156) (xy 290.793686 -355.002371) (xy 290.752473 -355.038084) (xy 290.706597 -355.067569)
			(xy 290.656992 -355.090226) (xy 290.604668 -355.105592) (xy 290.550689 -355.113356) (xy 290.523422 -355.113844)
			(xy 289.659822 -355.113844) (xy 289.632549 -355.113418) (xy 289.578557 -355.105658) (xy 289.526219 -355.090293)
			(xy 289.476601 -355.067636) (xy 289.430712 -355.038147) (xy 289.389488 -355.002428) (xy 289.353766 -354.961205)
			(xy 289.324275 -354.915318) (xy 289.301615 -354.865702) (xy 289.286247 -354.813365) (xy 289.278484 -354.759373)
			(xy 287.79578 -354.759373) (xy 287.788018 -354.813359) (xy 287.77265 -354.865692) (xy 287.749991 -354.915306)
			(xy 287.720501 -354.961189) (xy 287.684781 -355.002408) (xy 287.643559 -355.038124) (xy 287.597672 -355.067609)
			(xy 287.548057 -355.090264) (xy 287.495722 -355.105626) (xy 287.441733 -355.113383) (xy 287.414462 -355.113844)
			(xy 286.550862 -355.113844) (xy 286.523593 -355.113391) (xy 286.469611 -355.105625) (xy 286.417284 -355.090255)
			(xy 286.367676 -355.067596) (xy 286.321798 -355.038107) (xy 286.280583 -355.00239) (xy 286.24487 -354.961172)
			(xy 286.215386 -354.915291) (xy 286.192732 -354.865681) (xy 286.177367 -354.813352) (xy 286.169606 -354.759369)
			(xy 284.686758 -354.759369) (xy 284.678996 -354.813349) (xy 284.663632 -354.865676) (xy 284.640977 -354.915283)
			(xy 284.611493 -354.961162) (xy 284.575779 -355.002378) (xy 284.534564 -355.038091) (xy 284.488685 -355.067576)
			(xy 284.439078 -355.090231) (xy 284.386751 -355.105596) (xy 284.33277 -355.113357) (xy 284.305502 -355.113844)
			(xy 283.441902 -355.113844) (xy 283.41463 -355.113417) (xy 283.36064 -355.105654) (xy 283.308305 -355.090288)
			(xy 283.258689 -355.067629) (xy 283.212803 -355.03814) (xy 283.171581 -355.002421) (xy 283.135861 -354.961199)
			(xy 283.106372 -354.915313) (xy 283.083713 -354.865697) (xy 283.068346 -354.813362) (xy 283.060584 -354.759372)
			(xy 281.577757 -354.759372) (xy 281.569998 -354.813344) (xy 281.554635 -354.865667) (xy 281.531983 -354.915272)
			(xy 281.502502 -354.961149) (xy 281.466793 -355.002364) (xy 281.425583 -355.038077) (xy 281.379709 -355.067563)
			(xy 281.330107 -355.09022) (xy 281.277785 -355.105589) (xy 281.223808 -355.113355) (xy 281.196542 -355.113844)
			(xy 280.332942 -355.113844) (xy 280.305668 -355.113419) (xy 280.251674 -355.105662) (xy 280.199334 -355.090298)
			(xy 280.149713 -355.067642) (xy 280.103822 -355.038154) (xy 280.062595 -355.002435) (xy 280.026871 -354.961212)
			(xy 279.997378 -354.915324) (xy 279.974716 -354.865706) (xy 279.959347 -354.813367) (xy 279.951584 -354.759374)
			(xy 278.468881 -354.759374) (xy 278.461118 -354.813356) (xy 278.445752 -354.865688) (xy 278.423094 -354.9153)
			(xy 278.393606 -354.961182) (xy 278.357888 -355.002401) (xy 278.316668 -355.038117) (xy 278.270784 -355.067603)
			(xy 278.221171 -355.090258) (xy 278.168839 -355.105622) (xy 278.114853 -355.113382) (xy 278.087582 -355.113844)
			(xy 277.223982 -355.113844) (xy 277.196712 -355.113392) (xy 277.142728 -355.105628) (xy 277.090398 -355.090261)
			(xy 277.040788 -355.067602) (xy 276.994907 -355.038115) (xy 276.95369 -355.002398) (xy 276.917975 -354.961178)
			(xy 276.888489 -354.915296) (xy 276.865833 -354.865685) (xy 276.850468 -354.813354) (xy 276.842706 -354.75937)
			(xy 275.359858 -354.75937) (xy 275.352097 -354.813346) (xy 275.336733 -354.865672) (xy 275.31408 -354.915278)
			(xy 275.284597 -354.961156) (xy 275.248886 -355.002371) (xy 275.207673 -355.038084) (xy 275.161797 -355.067569)
			(xy 275.112192 -355.090226) (xy 275.059868 -355.105592) (xy 275.005889 -355.113356) (xy 274.978622 -355.113844)
			(xy 274.115022 -355.113844) (xy 274.087749 -355.113418) (xy 274.033757 -355.105658) (xy 273.981419 -355.090293)
			(xy 273.931801 -355.067636) (xy 273.885912 -355.038147) (xy 273.844688 -355.002428) (xy 273.808966 -354.961205)
			(xy 273.779475 -354.915318) (xy 273.756815 -354.865702) (xy 273.741447 -354.813365) (xy 273.733684 -354.759373)
			(xy 272.25098 -354.759373) (xy 272.243218 -354.813359) (xy 272.22785 -354.865692) (xy 272.205191 -354.915306)
			(xy 272.175701 -354.961189) (xy 272.139981 -355.002408) (xy 272.098759 -355.038124) (xy 272.052872 -355.067609)
			(xy 272.003257 -355.090264) (xy 271.950922 -355.105626) (xy 271.896933 -355.113383) (xy 271.869662 -355.113844)
			(xy 271.006062 -355.113844) (xy 270.978793 -355.113391) (xy 270.924811 -355.105625) (xy 270.872484 -355.090255)
			(xy 270.822876 -355.067596) (xy 270.776998 -355.038107) (xy 270.735783 -355.00239) (xy 270.70007 -354.961172)
			(xy 270.670586 -354.915291) (xy 270.647932 -354.865681) (xy 270.632567 -354.813352) (xy 270.624806 -354.759369)
			(xy 188.299268 -354.759369) (xy 188.294942 -354.78946) (xy 188.279575 -354.841794) (xy 188.256917 -354.891409)
			(xy 188.227428 -354.937294) (xy 188.191709 -354.978515) (xy 188.150487 -355.014233) (xy 188.104602 -355.04372)
			(xy 188.054987 -355.066378) (xy 188.002652 -355.081744) (xy 187.948664 -355.089505) (xy 187.921392 -355.089968)
			(xy 187.057792 -355.089968) (xy 187.030523 -355.089469) (xy 186.976542 -355.081707) (xy 186.924214 -355.066341)
			(xy 186.874605 -355.043684) (xy 186.828726 -355.014199) (xy 186.78751 -354.978484) (xy 186.751796 -354.937267)
			(xy 186.722312 -354.891388) (xy 186.699656 -354.841779) (xy 186.684292 -354.789451) (xy 186.67653 -354.735469)
			(xy 185.193682 -354.735469) (xy 185.185921 -354.78945) (xy 185.170557 -354.841778) (xy 185.147903 -354.891387)
			(xy 185.118419 -354.937267) (xy 185.082707 -354.978484) (xy 185.041492 -355.0142) (xy 184.995615 -355.043687)
			(xy 184.946008 -355.066346) (xy 184.893681 -355.081714) (xy 184.8397 -355.089479) (xy 184.812432 -355.089968)
			(xy 183.948832 -355.089968) (xy 183.92156 -355.089495) (xy 183.86757 -355.081736) (xy 183.815235 -355.066373)
			(xy 183.765618 -355.043718) (xy 183.719731 -355.014231) (xy 183.678508 -354.978515) (xy 183.642788 -354.937294)
			(xy 183.613298 -354.89141) (xy 183.590638 -354.841795) (xy 183.57527 -354.789461) (xy 183.567508 -354.735472)
			(xy 182.08478 -354.735472) (xy 182.08478 -354.759371) (xy 182.077018 -354.813358) (xy 182.061651 -354.86569)
			(xy 182.038992 -354.915303) (xy 182.009504 -354.961186) (xy 181.973785 -355.002405) (xy 181.932563 -355.03812)
			(xy 181.886678 -355.067606) (xy 181.837064 -355.090261) (xy 181.78473 -355.105624) (xy 181.730743 -355.113382)
			(xy 181.703472 -355.113844) (xy 180.839872 -355.113844) (xy 180.812603 -355.113392) (xy 180.75862 -355.105626)
			(xy 180.706291 -355.090258) (xy 180.656682 -355.067599) (xy 180.610802 -355.038111) (xy 180.569586 -355.002394)
			(xy 180.533872 -354.961175) (xy 180.504388 -354.915293) (xy 180.481732 -354.865683) (xy 180.466368 -354.813353)
			(xy 180.458606 -354.759369) (xy 178.975758 -354.759369) (xy 178.967997 -354.813348) (xy 178.952633 -354.865674)
			(xy 178.929978 -354.915281) (xy 178.900495 -354.961159) (xy 178.864783 -355.002374) (xy 178.823568 -355.038088)
			(xy 178.777691 -355.067573) (xy 178.728085 -355.090228) (xy 178.675759 -355.105594) (xy 178.62178 -355.113357)
			(xy 178.594512 -355.113844) (xy 177.730912 -355.113844) (xy 177.703639 -355.113417) (xy 177.649648 -355.105656)
			(xy 177.597312 -355.09029) (xy 177.547695 -355.067632) (xy 177.501808 -355.038144) (xy 177.460584 -355.002424)
			(xy 177.424864 -354.961202) (xy 177.395373 -354.915316) (xy 177.372714 -354.865699) (xy 177.357346 -354.813363)
			(xy 177.349584 -354.759373) (xy 175.86688 -354.759373) (xy 175.859117 -354.81336) (xy 175.843749 -354.865694)
			(xy 175.821089 -354.915309) (xy 175.791599 -354.961192) (xy 175.755878 -355.002412) (xy 175.714654 -355.038128)
			(xy 175.668766 -355.067612) (xy 175.619149 -355.090266) (xy 175.566813 -355.105628) (xy 175.512824 -355.113384)
			(xy 175.485552 -355.113844) (xy 174.621952 -355.113844) (xy 174.594684 -355.11339) (xy 174.540703 -355.105623)
			(xy 174.488376 -355.090252) (xy 174.43877 -355.067592) (xy 174.392893 -355.038104) (xy 174.351679 -355.002387)
			(xy 174.315967 -354.961169) (xy 174.286485 -354.915288) (xy 174.263831 -354.865679) (xy 174.248467 -354.81335)
			(xy 174.240706 -354.759368) (xy 172.757881 -354.759368) (xy 172.757881 -354.75937) (xy 172.750119 -354.813355)
			(xy 172.734753 -354.865686) (xy 172.712096 -354.915297) (xy 172.682609 -354.961179) (xy 172.646892 -355.002398)
			(xy 172.605673 -355.038113) (xy 172.55979 -355.067599) (xy 172.510178 -355.090255) (xy 172.457847 -355.10562)
			(xy 172.403862 -355.113381) (xy 172.376592 -355.113844) (xy 171.512992 -355.113844) (xy 171.485722 -355.113393)
			(xy 171.431736 -355.10563) (xy 171.379405 -355.090263) (xy 171.329794 -355.067606) (xy 171.283912 -355.038118)
			(xy 171.242693 -355.002401) (xy 171.206977 -354.961182) (xy 171.177491 -354.915299) (xy 171.154834 -354.865687)
			(xy 171.139468 -354.813356) (xy 171.131706 -354.75937) (xy 169.648858 -354.75937) (xy 169.641097 -354.813345)
			(xy 169.625734 -354.865669) (xy 169.603081 -354.915275) (xy 169.5736 -354.961152) (xy 169.53789 -355.002367)
			(xy 169.496678 -355.038081) (xy 169.450803 -355.067566) (xy 169.401199 -355.090223) (xy 169.348876 -355.10559)
			(xy 169.294899 -355.113355) (xy 169.267632 -355.113844) (xy 168.404032 -355.113844) (xy 168.376758 -355.113419)
			(xy 168.322765 -355.10566) (xy 168.270426 -355.090296) (xy 168.220807 -355.067639) (xy 168.174917 -355.038151)
			(xy 168.133691 -355.002432) (xy 168.097969 -354.961209) (xy 168.068477 -354.915321) (xy 168.045816 -354.865704)
			(xy 168.030447 -354.813366) (xy 168.022684 -354.759374) (xy 166.53998 -354.759374) (xy 166.532218 -354.813358)
			(xy 166.516851 -354.86569) (xy 166.494192 -354.915303) (xy 166.464704 -354.961186) (xy 166.428985 -355.002405)
			(xy 166.387763 -355.03812) (xy 166.341878 -355.067606) (xy 166.292264 -355.090261) (xy 166.23993 -355.105624)
			(xy 166.185943 -355.113382) (xy 166.158672 -355.113844) (xy 165.295072 -355.113844) (xy 165.267803 -355.113392)
			(xy 165.21382 -355.105626) (xy 165.161491 -355.090258) (xy 165.111882 -355.067599) (xy 165.066002 -355.038111)
			(xy 165.024786 -355.002394) (xy 164.989072 -354.961175) (xy 164.959588 -354.915293) (xy 164.936932 -354.865683)
			(xy 164.921568 -354.813353) (xy 164.913806 -354.759369) (xy 163.430958 -354.759369) (xy 163.423197 -354.813348)
			(xy 163.407833 -354.865674) (xy 163.385178 -354.915281) (xy 163.355695 -354.961159) (xy 163.319983 -355.002374)
			(xy 163.278768 -355.038088) (xy 163.232891 -355.067573) (xy 163.183285 -355.090228) (xy 163.130959 -355.105594)
			(xy 163.07698 -355.113357) (xy 163.049712 -355.113844) (xy 162.186112 -355.113844) (xy 162.158839 -355.113417)
			(xy 162.104848 -355.105656) (xy 162.052512 -355.09029) (xy 162.002895 -355.067632) (xy 161.957008 -355.038144)
			(xy 161.915784 -355.002424) (xy 161.880064 -354.961202) (xy 161.850573 -354.915316) (xy 161.827914 -354.865699)
			(xy 161.812546 -354.813363) (xy 161.804784 -354.759373) (xy 160.32208 -354.759373) (xy 160.314317 -354.81336)
			(xy 160.298949 -354.865694) (xy 160.276289 -354.915309) (xy 160.246799 -354.961192) (xy 160.211078 -355.002412)
			(xy 160.169854 -355.038128) (xy 160.123966 -355.067612) (xy 160.074349 -355.090266) (xy 160.022013 -355.105628)
			(xy 159.968024 -355.113384) (xy 159.940752 -355.113844) (xy 159.077152 -355.113844) (xy 159.049884 -355.11339)
			(xy 158.995903 -355.105623) (xy 158.943576 -355.090252) (xy 158.89397 -355.067592) (xy 158.848093 -355.038104)
			(xy 158.806879 -355.002387) (xy 158.771167 -354.961169) (xy 158.741685 -354.915288) (xy 158.719031 -354.865679)
			(xy 158.703667 -354.81335) (xy 158.695906 -354.759368) (xy 144.196558 -354.759368) (xy 144.188797 -354.813348)
			(xy 144.173432 -354.865675) (xy 144.150778 -354.915282) (xy 144.121294 -354.96116) (xy 144.085581 -355.002376)
			(xy 144.044367 -355.038089) (xy 143.998489 -355.067574) (xy 143.948882 -355.09023) (xy 143.896556 -355.105595)
			(xy 143.842576 -355.113357) (xy 143.815308 -355.113844) (xy 142.951708 -355.113844) (xy 142.924435 -355.113417)
			(xy 142.870445 -355.105655) (xy 142.818109 -355.090289) (xy 142.768492 -355.067631) (xy 142.722606 -355.038142)
			(xy 142.681383 -355.002423) (xy 142.645663 -354.961201) (xy 142.616173 -354.915315) (xy 142.593514 -354.865699)
			(xy 142.578146 -354.813363) (xy 142.570384 -354.759373) (xy 141.087557 -354.759373) (xy 141.079798 -354.813343)
			(xy 141.064436 -354.865666) (xy 141.041784 -354.915271) (xy 141.012304 -354.961147) (xy 140.976595 -355.002361)
			(xy 140.935386 -355.038075) (xy 140.889513 -355.067561) (xy 140.839911 -355.090219) (xy 140.78759 -355.105587)
			(xy 140.733614 -355.113354) (xy 140.706348 -355.113844) (xy 139.842748 -355.113844) (xy 139.815473 -355.11342)
			(xy 139.761479 -355.105663) (xy 139.709138 -355.0903) (xy 139.659516 -355.067644) (xy 139.613625 -355.038156)
			(xy 139.572397 -355.002437) (xy 139.536672 -354.961214) (xy 139.507179 -354.915326) (xy 139.484517 -354.865707)
			(xy 139.469147 -354.813368) (xy 139.461384 -354.759374) (xy 137.97868 -354.759374) (xy 137.970918 -354.813356)
			(xy 137.955552 -354.865687) (xy 137.932895 -354.915298) (xy 137.903408 -354.961181) (xy 137.867691 -355.002399)
			(xy 137.826471 -355.038115) (xy 137.780588 -355.067601) (xy 137.730976 -355.090256) (xy 137.678644 -355.105621)
			(xy 137.624658 -355.113381) (xy 137.597388 -355.113844) (xy 136.733788 -355.113844) (xy 136.706518 -355.113393)
			(xy 136.652533 -355.105629) (xy 136.600203 -355.090262) (xy 136.550591 -355.067604) (xy 136.50471 -355.038117)
			(xy 136.463492 -355.0024) (xy 136.427776 -354.96118) (xy 136.39829 -354.915298) (xy 136.375634 -354.865686)
			(xy 136.360268 -354.813355) (xy 136.352506 -354.75937) (xy 134.869658 -354.75937) (xy 134.861897 -354.813345)
			(xy 134.846534 -354.86567) (xy 134.823881 -354.915276) (xy 134.794399 -354.961154) (xy 134.758688 -355.002369)
			(xy 134.717476 -355.038082) (xy 134.671601 -355.067567) (xy 134.621997 -355.090224) (xy 134.569673 -355.105591)
			(xy 134.515695 -355.113356) (xy 134.488428 -355.113844) (xy 133.624828 -355.113844) (xy 133.597554 -355.113418)
			(xy 133.543562 -355.105659) (xy 133.491223 -355.090295) (xy 133.441604 -355.067638) (xy 133.395715 -355.038149)
			(xy 133.35449 -355.00243) (xy 133.318768 -354.961207) (xy 133.289276 -354.91532) (xy 133.266615 -354.865703)
			(xy 133.251247 -354.813365) (xy 133.243484 -354.759374) (xy 131.76078 -354.759374) (xy 131.753018 -354.813358)
			(xy 131.737651 -354.865691) (xy 131.714992 -354.915304) (xy 131.685503 -354.961187) (xy 131.649783 -355.002406)
			(xy 131.608561 -355.038122) (xy 131.562676 -355.067607) (xy 131.513061 -355.090262) (xy 131.460727 -355.105625)
			(xy 131.406739 -355.113383) (xy 131.379468 -355.113844) (xy 130.515868 -355.113844) (xy 130.488599 -355.113391)
			(xy 130.434616 -355.105626) (xy 130.382288 -355.090257) (xy 130.33268 -355.067598) (xy 130.2868 -355.03811)
			(xy 130.245585 -355.002393) (xy 130.209871 -354.961174) (xy 130.180387 -354.915292) (xy 130.157732 -354.865682)
			(xy 130.142368 -354.813353) (xy 130.134606 -354.759369) (xy 128.651758 -354.759369) (xy 128.643997 -354.813348)
			(xy 128.628632 -354.865675) (xy 128.605978 -354.915282) (xy 128.576494 -354.96116) (xy 128.540781 -355.002376)
			(xy 128.499567 -355.038089) (xy 128.453689 -355.067574) (xy 128.404082 -355.09023) (xy 128.351756 -355.105595)
			(xy 128.297776 -355.113357) (xy 128.270508 -355.113844) (xy 127.406908 -355.113844) (xy 127.379635 -355.113417)
			(xy 127.325645 -355.105655) (xy 127.273309 -355.090289) (xy 127.223692 -355.067631) (xy 127.177806 -355.038142)
			(xy 127.136583 -355.002423) (xy 127.100863 -354.961201) (xy 127.071373 -354.915315) (xy 127.048714 -354.865699)
			(xy 127.033346 -354.813363) (xy 127.025584 -354.759373) (xy 125.542757 -354.759373) (xy 125.534998 -354.813343)
			(xy 125.519636 -354.865666) (xy 125.496984 -354.915271) (xy 125.467504 -354.961147) (xy 125.431795 -355.002361)
			(xy 125.390586 -355.038075) (xy 125.344713 -355.067561) (xy 125.295111 -355.090219) (xy 125.24279 -355.105587)
			(xy 125.188814 -355.113354) (xy 125.161548 -355.113844) (xy 124.297948 -355.113844) (xy 124.270673 -355.11342)
			(xy 124.216679 -355.105663) (xy 124.164338 -355.0903) (xy 124.114716 -355.067644) (xy 124.068825 -355.038156)
			(xy 124.027597 -355.002437) (xy 123.991872 -354.961214) (xy 123.962379 -354.915326) (xy 123.939717 -354.865707)
			(xy 123.924347 -354.813368) (xy 123.916584 -354.759374) (xy 122.43388 -354.759374) (xy 122.426118 -354.813356)
			(xy 122.410752 -354.865687) (xy 122.388095 -354.915298) (xy 122.358608 -354.961181) (xy 122.322891 -355.002399)
			(xy 122.281671 -355.038115) (xy 122.235788 -355.067601) (xy 122.186176 -355.090256) (xy 122.133844 -355.105621)
			(xy 122.079858 -355.113381) (xy 122.052588 -355.113844) (xy 121.188988 -355.113844) (xy 121.161718 -355.113393)
			(xy 121.107733 -355.105629) (xy 121.055403 -355.090262) (xy 121.005791 -355.067604) (xy 120.95991 -355.038117)
			(xy 120.918692 -355.0024) (xy 120.882976 -354.96118) (xy 120.85349 -354.915298) (xy 120.830834 -354.865686)
			(xy 120.815468 -354.813355) (xy 120.807706 -354.75937) (xy 119.324858 -354.75937) (xy 119.317097 -354.813345)
			(xy 119.301734 -354.86567) (xy 119.279081 -354.915276) (xy 119.249599 -354.961154) (xy 119.213888 -355.002369)
			(xy 119.172676 -355.038082) (xy 119.126801 -355.067567) (xy 119.077197 -355.090224) (xy 119.024873 -355.105591)
			(xy 118.970895 -355.113356) (xy 118.943628 -355.113844) (xy 118.080028 -355.113844) (xy 118.052754 -355.113418)
			(xy 117.998762 -355.105659) (xy 117.946423 -355.090295) (xy 117.896804 -355.067638) (xy 117.850915 -355.038149)
			(xy 117.80969 -355.00243) (xy 117.773968 -354.961207) (xy 117.744476 -354.91532) (xy 117.721815 -354.865703)
			(xy 117.706447 -354.813365) (xy 117.698684 -354.759374) (xy 116.21598 -354.759374) (xy 116.208218 -354.813358)
			(xy 116.192851 -354.865691) (xy 116.170192 -354.915304) (xy 116.140703 -354.961187) (xy 116.104983 -355.002406)
			(xy 116.063761 -355.038122) (xy 116.017876 -355.067607) (xy 115.968261 -355.090262) (xy 115.915927 -355.105625)
			(xy 115.861939 -355.113383) (xy 115.834668 -355.113844) (xy 114.971068 -355.113844) (xy 114.943799 -355.113391)
			(xy 114.889816 -355.105626) (xy 114.837488 -355.090257) (xy 114.78788 -355.067598) (xy 114.742 -355.03811)
			(xy 114.700785 -355.002393) (xy 114.665071 -354.961174) (xy 114.635587 -354.915292) (xy 114.612932 -354.865682)
			(xy 114.597568 -354.813353) (xy 114.589806 -354.759369) (xy 93.706658 -354.759369) (xy 93.698898 -354.813344)
			(xy 93.683535 -354.865667) (xy 93.660883 -354.915272) (xy 93.631402 -354.961149) (xy 93.595693 -355.002364)
			(xy 93.554483 -355.038077) (xy 93.508609 -355.067563) (xy 93.459007 -355.09022) (xy 93.406685 -355.105589)
			(xy 93.352708 -355.113355) (xy 93.325442 -355.113844) (xy 92.461842 -355.113844) (xy 92.434568 -355.113419)
			(xy 92.380574 -355.105662) (xy 92.328234 -355.090298) (xy 92.278613 -355.067642) (xy 92.232722 -355.038154)
			(xy 92.191495 -355.002435) (xy 92.155771 -354.961212) (xy 92.126278 -354.915324) (xy 92.103616 -354.865706)
			(xy 92.088247 -354.813367) (xy 92.080484 -354.759374) (xy 90.597781 -354.759374) (xy 90.590018 -354.813356)
			(xy 90.574652 -354.865688) (xy 90.551994 -354.9153) (xy 90.522506 -354.961182) (xy 90.486788 -355.002401)
			(xy 90.445568 -355.038117) (xy 90.399684 -355.067603) (xy 90.350071 -355.090258) (xy 90.297739 -355.105622)
			(xy 90.243753 -355.113382) (xy 90.216482 -355.113844) (xy 89.352882 -355.113844) (xy 89.325612 -355.113392)
			(xy 89.271628 -355.105628) (xy 89.219298 -355.090261) (xy 89.169688 -355.067602) (xy 89.123807 -355.038115)
			(xy 89.08259 -355.002398) (xy 89.046875 -354.961178) (xy 89.017389 -354.915296) (xy 88.994733 -354.865685)
			(xy 88.979368 -354.813354) (xy 88.971606 -354.75937) (xy 87.488758 -354.75937) (xy 87.480997 -354.813346)
			(xy 87.465633 -354.865672) (xy 87.44298 -354.915278) (xy 87.413497 -354.961156) (xy 87.377786 -355.002371)
			(xy 87.336573 -355.038084) (xy 87.290697 -355.067569) (xy 87.241092 -355.090226) (xy 87.188768 -355.105592)
			(xy 87.134789 -355.113356) (xy 87.107522 -355.113844) (xy 86.243922 -355.113844) (xy 86.216649 -355.113418)
			(xy 86.162657 -355.105658) (xy 86.110319 -355.090293) (xy 86.060701 -355.067636) (xy 86.014812 -355.038147)
			(xy 85.973588 -355.002428) (xy 85.937866 -354.961205) (xy 85.908375 -354.915318) (xy 85.885715 -354.865702)
			(xy 85.870347 -354.813365) (xy 85.862584 -354.759373) (xy 84.37988 -354.759373) (xy 84.372118 -354.813359)
			(xy 84.35675 -354.865692) (xy 84.334091 -354.915306) (xy 84.304601 -354.961189) (xy 84.268881 -355.002408)
			(xy 84.227659 -355.038124) (xy 84.181772 -355.067609) (xy 84.132157 -355.090264) (xy 84.079822 -355.105626)
			(xy 84.025833 -355.113383) (xy 83.998562 -355.113844) (xy 83.134962 -355.113844) (xy 83.107693 -355.113391)
			(xy 83.053711 -355.105625) (xy 83.001384 -355.090255) (xy 82.951776 -355.067596) (xy 82.905898 -355.038107)
			(xy 82.864683 -355.00239) (xy 82.82897 -354.961172) (xy 82.799486 -354.915291) (xy 82.776832 -354.865681)
			(xy 82.761467 -354.813352) (xy 82.753706 -354.759369) (xy 81.270858 -354.759369) (xy 81.263096 -354.813349)
			(xy 81.247732 -354.865676) (xy 81.225077 -354.915283) (xy 81.195593 -354.961162) (xy 81.159879 -355.002378)
			(xy 81.118664 -355.038091) (xy 81.072785 -355.067576) (xy 81.023178 -355.090231) (xy 80.970851 -355.105596)
			(xy 80.91687 -355.113357) (xy 80.889602 -355.113844) (xy 80.026002 -355.113844) (xy 79.99873 -355.113417)
			(xy 79.94474 -355.105654) (xy 79.892405 -355.090288) (xy 79.842789 -355.067629) (xy 79.796903 -355.03814)
			(xy 79.755681 -355.002421) (xy 79.719961 -354.961199) (xy 79.690472 -354.915313) (xy 79.667813 -354.865697)
			(xy 79.652446 -354.813362) (xy 79.644684 -354.759372) (xy 78.161857 -354.759372) (xy 78.154098 -354.813344)
			(xy 78.138735 -354.865667) (xy 78.116083 -354.915272) (xy 78.086602 -354.961149) (xy 78.050893 -355.002364)
			(xy 78.009683 -355.038077) (xy 77.963809 -355.067563) (xy 77.914207 -355.09022) (xy 77.861885 -355.105589)
			(xy 77.807908 -355.113355) (xy 77.780642 -355.113844) (xy 76.917042 -355.113844) (xy 76.889768 -355.113419)
			(xy 76.835774 -355.105662) (xy 76.783434 -355.090298) (xy 76.733813 -355.067642) (xy 76.687922 -355.038154)
			(xy 76.646695 -355.002435) (xy 76.610971 -354.961212) (xy 76.581478 -354.915324) (xy 76.558816 -354.865706)
			(xy 76.543447 -354.813367) (xy 76.535684 -354.759374) (xy 75.052981 -354.759374) (xy 75.045218 -354.813356)
			(xy 75.029852 -354.865688) (xy 75.007194 -354.9153) (xy 74.977706 -354.961182) (xy 74.941988 -355.002401)
			(xy 74.900768 -355.038117) (xy 74.854884 -355.067603) (xy 74.805271 -355.090258) (xy 74.752939 -355.105622)
			(xy 74.698953 -355.113382) (xy 74.671682 -355.113844) (xy 73.808082 -355.113844) (xy 73.780812 -355.113392)
			(xy 73.726828 -355.105628) (xy 73.674498 -355.090261) (xy 73.624888 -355.067602) (xy 73.579007 -355.038115)
			(xy 73.53779 -355.002398) (xy 73.502075 -354.961178) (xy 73.472589 -354.915296) (xy 73.449933 -354.865685)
			(xy 73.434568 -354.813354) (xy 73.426806 -354.75937) (xy 71.943958 -354.75937) (xy 71.936197 -354.813346)
			(xy 71.920833 -354.865672) (xy 71.89818 -354.915278) (xy 71.868697 -354.961156) (xy 71.832986 -355.002371)
			(xy 71.791773 -355.038084) (xy 71.745897 -355.067569) (xy 71.696292 -355.090226) (xy 71.643968 -355.105592)
			(xy 71.589989 -355.113356) (xy 71.562722 -355.113844) (xy 70.699122 -355.113844) (xy 70.671849 -355.113418)
			(xy 70.617857 -355.105658) (xy 70.565519 -355.090293) (xy 70.515901 -355.067636) (xy 70.470012 -355.038147)
			(xy 70.428788 -355.002428) (xy 70.393066 -354.961205) (xy 70.363575 -354.915318) (xy 70.340915 -354.865702)
			(xy 70.325547 -354.813365) (xy 70.317784 -354.759373) (xy 68.83508 -354.759373) (xy 68.827318 -354.813359)
			(xy 68.81195 -354.865692) (xy 68.789291 -354.915306) (xy 68.759801 -354.961189) (xy 68.724081 -355.002408)
			(xy 68.682859 -355.038124) (xy 68.636972 -355.067609) (xy 68.587357 -355.090264) (xy 68.535022 -355.105626)
			(xy 68.481033 -355.113383) (xy 68.453762 -355.113844) (xy 67.590162 -355.113844) (xy 67.562893 -355.113391)
			(xy 67.508911 -355.105625) (xy 67.456584 -355.090255) (xy 67.406976 -355.067596) (xy 67.361098 -355.038107)
			(xy 67.319883 -355.00239) (xy 67.28417 -354.961172) (xy 67.254686 -354.915291) (xy 67.232032 -354.865681)
			(xy 67.216667 -354.813352) (xy 67.208906 -354.759369) (xy 65.726058 -354.759369) (xy 65.718296 -354.813349)
			(xy 65.702932 -354.865676) (xy 65.680277 -354.915283) (xy 65.650793 -354.961162) (xy 65.615079 -355.002378)
			(xy 65.573864 -355.038091) (xy 65.527985 -355.067576) (xy 65.478378 -355.090231) (xy 65.426051 -355.105596)
			(xy 65.37207 -355.113357) (xy 65.344802 -355.113844) (xy 64.481202 -355.113844) (xy 64.45393 -355.113417)
			(xy 64.39994 -355.105654) (xy 64.347605 -355.090288) (xy 64.297989 -355.067629) (xy 64.252103 -355.03814)
			(xy 64.210881 -355.002421) (xy 64.175161 -354.961199) (xy 64.145672 -354.915313) (xy 64.123013 -354.865697)
			(xy 64.107646 -354.813362) (xy 64.099884 -354.759372) (xy 51.666857 -354.759372) (xy 51.659098 -354.813343)
			(xy 51.643736 -354.865666) (xy 51.621084 -354.915271) (xy 51.591604 -354.961147) (xy 51.555895 -355.002361)
			(xy 51.514686 -355.038075) (xy 51.468813 -355.067561) (xy 51.419211 -355.090219) (xy 51.36689 -355.105587)
			(xy 51.312914 -355.113354) (xy 51.285648 -355.113844) (xy 50.422048 -355.113844) (xy 50.394773 -355.11342)
			(xy 50.340779 -355.105663) (xy 50.288438 -355.0903) (xy 50.238816 -355.067644) (xy 50.192925 -355.038156)
			(xy 50.151697 -355.002437) (xy 50.115972 -354.961214) (xy 50.086479 -354.915326) (xy 50.063817 -354.865707)
			(xy 50.048447 -354.813368) (xy 50.040684 -354.759374) (xy 48.55798 -354.759374) (xy 48.550218 -354.813356)
			(xy 48.534852 -354.865687) (xy 48.512195 -354.915298) (xy 48.482708 -354.961181) (xy 48.446991 -355.002399)
			(xy 48.405771 -355.038115) (xy 48.359888 -355.067601) (xy 48.310276 -355.090256) (xy 48.257944 -355.105621)
			(xy 48.203958 -355.113381) (xy 48.176688 -355.113844) (xy 47.313088 -355.113844) (xy 47.285818 -355.113393)
			(xy 47.231833 -355.105629) (xy 47.179503 -355.090262) (xy 47.129891 -355.067604) (xy 47.08401 -355.038117)
			(xy 47.042792 -355.0024) (xy 47.007076 -354.96118) (xy 46.97759 -354.915298) (xy 46.954934 -354.865686)
			(xy 46.939568 -354.813355) (xy 46.931806 -354.75937) (xy 45.448958 -354.75937) (xy 45.441197 -354.813345)
			(xy 45.425834 -354.86567) (xy 45.403181 -354.915276) (xy 45.373699 -354.961154) (xy 45.337988 -355.002369)
			(xy 45.296776 -355.038082) (xy 45.250901 -355.067567) (xy 45.201297 -355.090224) (xy 45.148973 -355.105591)
			(xy 45.094995 -355.113356) (xy 45.067728 -355.113844) (xy 44.204128 -355.113844) (xy 44.176854 -355.113418)
			(xy 44.122862 -355.105659) (xy 44.070523 -355.090295) (xy 44.020904 -355.067638) (xy 43.975015 -355.038149)
			(xy 43.93379 -355.00243) (xy 43.898068 -354.961207) (xy 43.868576 -354.91532) (xy 43.845915 -354.865703)
			(xy 43.830547 -354.813365) (xy 43.822784 -354.759374) (xy 42.34008 -354.759374) (xy 42.332318 -354.813358)
			(xy 42.316951 -354.865691) (xy 42.294292 -354.915304) (xy 42.264803 -354.961187) (xy 42.229083 -355.002406)
			(xy 42.187861 -355.038122) (xy 42.141976 -355.067607) (xy 42.092361 -355.090262) (xy 42.040027 -355.105625)
			(xy 41.986039 -355.113383) (xy 41.958768 -355.113844) (xy 41.095168 -355.113844) (xy 41.067899 -355.113391)
			(xy 41.013916 -355.105626) (xy 40.961588 -355.090257) (xy 40.91198 -355.067598) (xy 40.8661 -355.03811)
			(xy 40.824885 -355.002393) (xy 40.789171 -354.961174) (xy 40.759687 -354.915292) (xy 40.737032 -354.865682)
			(xy 40.721668 -354.813353) (xy 40.713906 -354.759369) (xy 39.231058 -354.759369) (xy 39.223297 -354.813348)
			(xy 39.207932 -354.865675) (xy 39.185278 -354.915282) (xy 39.155794 -354.96116) (xy 39.120081 -355.002376)
			(xy 39.078867 -355.038089) (xy 39.032989 -355.067574) (xy 38.983382 -355.09023) (xy 38.931056 -355.105595)
			(xy 38.877076 -355.113357) (xy 38.849808 -355.113844) (xy 37.986208 -355.113844) (xy 37.958935 -355.113417)
			(xy 37.904945 -355.105655) (xy 37.852609 -355.090289) (xy 37.802992 -355.067631) (xy 37.757106 -355.038142)
			(xy 37.715883 -355.002423) (xy 37.680163 -354.961201) (xy 37.650673 -354.915315) (xy 37.628014 -354.865699)
			(xy 37.612646 -354.813363) (xy 37.604884 -354.759373) (xy 36.122057 -354.759373) (xy 36.114298 -354.813343)
			(xy 36.098936 -354.865666) (xy 36.076284 -354.915271) (xy 36.046804 -354.961147) (xy 36.011095 -355.002361)
			(xy 35.969886 -355.038075) (xy 35.924013 -355.067561) (xy 35.874411 -355.090219) (xy 35.82209 -355.105587)
			(xy 35.768114 -355.113354) (xy 35.740848 -355.113844) (xy 34.877248 -355.113844) (xy 34.849973 -355.11342)
			(xy 34.795979 -355.105663) (xy 34.743638 -355.0903) (xy 34.694016 -355.067644) (xy 34.648125 -355.038156)
			(xy 34.606897 -355.002437) (xy 34.571172 -354.961214) (xy 34.541679 -354.915326) (xy 34.519017 -354.865707)
			(xy 34.503647 -354.813368) (xy 34.495884 -354.759374) (xy 33.01318 -354.759374) (xy 33.005418 -354.813356)
			(xy 32.990052 -354.865687) (xy 32.967395 -354.915298) (xy 32.937908 -354.961181) (xy 32.902191 -355.002399)
			(xy 32.860971 -355.038115) (xy 32.815088 -355.067601) (xy 32.765476 -355.090256) (xy 32.713144 -355.105621)
			(xy 32.659158 -355.113381) (xy 32.631888 -355.113844) (xy 31.768288 -355.113844) (xy 31.741018 -355.113393)
			(xy 31.687033 -355.105629) (xy 31.634703 -355.090262) (xy 31.585091 -355.067604) (xy 31.53921 -355.038117)
			(xy 31.497992 -355.0024) (xy 31.462276 -354.96118) (xy 31.43279 -354.915298) (xy 31.410134 -354.865686)
			(xy 31.394768 -354.813355) (xy 31.387006 -354.75937) (xy 29.904158 -354.75937) (xy 29.896397 -354.813345)
			(xy 29.881034 -354.86567) (xy 29.858381 -354.915276) (xy 29.828899 -354.961154) (xy 29.793188 -355.002369)
			(xy 29.751976 -355.038082) (xy 29.706101 -355.067567) (xy 29.656497 -355.090224) (xy 29.604173 -355.105591)
			(xy 29.550195 -355.113356) (xy 29.522928 -355.113844) (xy 28.659328 -355.113844) (xy 28.632054 -355.113418)
			(xy 28.578062 -355.105659) (xy 28.525723 -355.090295) (xy 28.476104 -355.067638) (xy 28.430215 -355.038149)
			(xy 28.38899 -355.00243) (xy 28.353268 -354.961207) (xy 28.323776 -354.91532) (xy 28.301115 -354.865703)
			(xy 28.285747 -354.813365) (xy 28.277984 -354.759374) (xy 26.79528 -354.759374) (xy 26.787518 -354.813358)
			(xy 26.772151 -354.865691) (xy 26.749492 -354.915304) (xy 26.720003 -354.961187) (xy 26.684283 -355.002406)
			(xy 26.643061 -355.038122) (xy 26.597176 -355.067607) (xy 26.547561 -355.090262) (xy 26.495227 -355.105625)
			(xy 26.441239 -355.113383) (xy 26.413968 -355.113844) (xy 25.550368 -355.113844) (xy 25.523099 -355.113391)
			(xy 25.469116 -355.105626) (xy 25.416788 -355.090257) (xy 25.36718 -355.067598) (xy 25.3213 -355.03811)
			(xy 25.280085 -355.002393) (xy 25.244371 -354.961174) (xy 25.214887 -354.915292) (xy 25.192232 -354.865682)
			(xy 25.176868 -354.813353) (xy 25.169106 -354.759369) (xy 23.686258 -354.759369) (xy 23.678497 -354.813348)
			(xy 23.663132 -354.865675) (xy 23.640478 -354.915282) (xy 23.610994 -354.96116) (xy 23.575281 -355.002376)
			(xy 23.534067 -355.038089) (xy 23.488189 -355.067574) (xy 23.438582 -355.09023) (xy 23.386256 -355.105595)
			(xy 23.332276 -355.113357) (xy 23.305008 -355.113844) (xy 22.441408 -355.113844) (xy 22.414135 -355.113417)
			(xy 22.360145 -355.105655) (xy 22.307809 -355.090289) (xy 22.258192 -355.067631) (xy 22.212306 -355.038142)
			(xy 22.171083 -355.002423) (xy 22.135363 -354.961201) (xy 22.105873 -354.915315) (xy 22.083214 -354.865699)
			(xy 22.067846 -354.813363) (xy 22.060084 -354.759373) (xy 0.508 -354.759373) (xy 0.508 -357.784969)
			(xy 22.060131 -357.784969) (xy 22.060131 -357.730431) (xy 22.067893 -357.676447) (xy 22.083259 -357.624118)
			(xy 22.105915 -357.574508) (xy 22.135401 -357.528628) (xy 22.171117 -357.487411) (xy 22.212334 -357.451696)
			(xy 22.258215 -357.422211) (xy 22.307826 -357.399556) (xy 22.360155 -357.384191) (xy 22.414139 -357.376431)
			(xy 22.441408 -357.375968) (xy 23.305008 -357.375968) (xy 23.332279 -357.376395) (xy 23.386266 -357.384158)
			(xy 23.438599 -357.399525) (xy 23.488212 -357.422184) (xy 23.534095 -357.451672) (xy 23.575315 -357.48739)
			(xy 23.611032 -357.528611) (xy 23.64052 -357.574495) (xy 23.663177 -357.624109) (xy 23.678543 -357.676442)
			(xy 23.686306 -357.730429) (xy 23.686306 -357.784966) (xy 25.169154 -357.784966) (xy 25.169154 -357.730434)
			(xy 25.176914 -357.676458) (xy 25.192277 -357.624135) (xy 25.214929 -357.574531) (xy 25.24441 -357.528655)
			(xy 25.280119 -357.487441) (xy 25.321329 -357.451729) (xy 25.367203 -357.422244) (xy 25.416805 -357.399588)
			(xy 25.469126 -357.384221) (xy 25.523102 -357.376457) (xy 25.550368 -357.375968) (xy 26.413968 -357.375968)
			(xy 26.441243 -357.376369) (xy 26.495237 -357.384128) (xy 26.547578 -357.399493) (xy 26.597199 -357.422151)
			(xy 26.64309 -357.45164) (xy 26.684317 -357.48736) (xy 26.720041 -357.528584) (xy 26.749534 -357.574473)
			(xy 26.772196 -357.624092) (xy 26.787565 -357.676431) (xy 26.795328 -357.730425) (xy 26.795328 -357.78497)
			(xy 28.278031 -357.78497) (xy 28.278032 -357.73043) (xy 28.285794 -357.676445) (xy 28.30116 -357.624114)
			(xy 28.323818 -357.574503) (xy 28.353306 -357.528621) (xy 28.389024 -357.487404) (xy 28.430244 -357.451689)
			(xy 28.476127 -357.422205) (xy 28.52574 -357.39955) (xy 28.578072 -357.384188) (xy 28.632058 -357.37643)
			(xy 28.659328 -357.375968) (xy 29.522928 -357.375968) (xy 29.550198 -357.376396) (xy 29.604183 -357.384162)
			(xy 29.656513 -357.399531) (xy 29.706124 -357.42219) (xy 29.752005 -357.451679) (xy 29.793222 -357.487397)
			(xy 29.828937 -357.528618) (xy 29.858423 -357.574501) (xy 29.881079 -357.624113) (xy 29.896444 -357.676444)
			(xy 29.904206 -357.73043) (xy 29.904206 -357.784967) (xy 31.387054 -357.784967) (xy 31.387054 -357.730433)
			(xy 31.394815 -357.676455) (xy 31.410179 -357.624131) (xy 31.432832 -357.574525) (xy 31.462315 -357.528648)
			(xy 31.498026 -357.487434) (xy 31.539239 -357.451722) (xy 31.585115 -357.422238) (xy 31.634719 -357.399583)
			(xy 31.687043 -357.384218) (xy 31.741021 -357.376455) (xy 31.768288 -357.375968) (xy 32.631888 -357.375968)
			(xy 32.659162 -357.376371) (xy 32.713154 -357.384132) (xy 32.765492 -357.399499) (xy 32.815111 -357.422157)
			(xy 32.861 -357.451647) (xy 32.902224 -357.487367) (xy 32.937946 -357.528591) (xy 32.967437 -357.574479)
			(xy 32.990097 -357.624096) (xy 33.005465 -357.676434) (xy 33.013228 -357.730426) (xy 33.013228 -357.784971)
			(xy 34.495932 -357.784971) (xy 34.495932 -357.730429) (xy 34.503694 -357.676442) (xy 34.519062 -357.62411)
			(xy 34.541721 -357.574497) (xy 34.571211 -357.528615) (xy 34.606931 -357.487397) (xy 34.648153 -357.451682)
			(xy 34.694039 -357.422198) (xy 34.743655 -357.399545) (xy 34.795989 -357.384184) (xy 34.849977 -357.376428)
			(xy 34.877248 -357.375968) (xy 35.740848 -357.375968) (xy 35.768117 -357.376398) (xy 35.8221 -357.384166)
			(xy 35.874428 -357.399536) (xy 35.924036 -357.422197) (xy 35.969914 -357.451687) (xy 36.011129 -357.487405)
			(xy 36.046842 -357.528624) (xy 36.076326 -357.574506) (xy 36.09898 -357.624117) (xy 36.114345 -357.676447)
			(xy 36.122106 -357.730431) (xy 36.122106 -357.784969) (xy 37.604931 -357.784969) (xy 37.604931 -357.730431)
			(xy 37.612693 -357.676447) (xy 37.628059 -357.624118) (xy 37.650715 -357.574508) (xy 37.680201 -357.528628)
			(xy 37.715917 -357.487411) (xy 37.757134 -357.451696) (xy 37.803015 -357.422211) (xy 37.852626 -357.399556)
			(xy 37.904955 -357.384191) (xy 37.958939 -357.376431) (xy 37.986208 -357.375968) (xy 38.849808 -357.375968)
			(xy 38.877079 -357.376395) (xy 38.931066 -357.384158) (xy 38.983399 -357.399525) (xy 39.033012 -357.422184)
			(xy 39.078895 -357.451672) (xy 39.120115 -357.48739) (xy 39.155832 -357.528611) (xy 39.18532 -357.574495)
			(xy 39.207977 -357.624109) (xy 39.223343 -357.676442) (xy 39.231106 -357.730429) (xy 39.231106 -357.784966)
			(xy 40.713954 -357.784966) (xy 40.713954 -357.730434) (xy 40.721714 -357.676458) (xy 40.737077 -357.624135)
			(xy 40.759729 -357.574531) (xy 40.78921 -357.528655) (xy 40.824919 -357.487441) (xy 40.866129 -357.451729)
			(xy 40.912003 -357.422244) (xy 40.961605 -357.399588) (xy 41.013926 -357.384221) (xy 41.067902 -357.376457)
			(xy 41.095168 -357.375968) (xy 41.958768 -357.375968) (xy 41.986043 -357.376369) (xy 42.040037 -357.384128)
			(xy 42.092378 -357.399493) (xy 42.141999 -357.422151) (xy 42.18789 -357.45164) (xy 42.229117 -357.48736)
			(xy 42.264841 -357.528584) (xy 42.294334 -357.574473) (xy 42.316996 -357.624092) (xy 42.332365 -357.676431)
			(xy 42.340128 -357.730425) (xy 42.340128 -357.78497) (xy 43.822831 -357.78497) (xy 43.822832 -357.73043)
			(xy 43.830594 -357.676445) (xy 43.84596 -357.624114) (xy 43.868618 -357.574503) (xy 43.898106 -357.528621)
			(xy 43.933824 -357.487404) (xy 43.975044 -357.451689) (xy 44.020927 -357.422205) (xy 44.07054 -357.39955)
			(xy 44.122872 -357.384188) (xy 44.176858 -357.37643) (xy 44.204128 -357.375968) (xy 45.067728 -357.375968)
			(xy 45.094998 -357.376396) (xy 45.148983 -357.384162) (xy 45.201313 -357.399531) (xy 45.250924 -357.42219)
			(xy 45.296805 -357.451679) (xy 45.338022 -357.487397) (xy 45.373737 -357.528618) (xy 45.403223 -357.574501)
			(xy 45.425879 -357.624113) (xy 45.441244 -357.676444) (xy 45.449006 -357.73043) (xy 45.449006 -357.784967)
			(xy 46.931854 -357.784967) (xy 46.931854 -357.730433) (xy 46.939615 -357.676455) (xy 46.954979 -357.624131)
			(xy 46.977632 -357.574525) (xy 47.007115 -357.528648) (xy 47.042826 -357.487434) (xy 47.084039 -357.451722)
			(xy 47.129915 -357.422238) (xy 47.179519 -357.399583) (xy 47.231843 -357.384218) (xy 47.285821 -357.376455)
			(xy 47.313088 -357.375968) (xy 48.176688 -357.375968) (xy 48.203962 -357.376371) (xy 48.257954 -357.384132)
			(xy 48.310292 -357.399499) (xy 48.359911 -357.422157) (xy 48.4058 -357.451647) (xy 48.447024 -357.487367)
			(xy 48.482746 -357.528591) (xy 48.512237 -357.574479) (xy 48.534897 -357.624096) (xy 48.550265 -357.676434)
			(xy 48.558028 -357.730426) (xy 48.558028 -357.784971) (xy 50.040732 -357.784971) (xy 50.040732 -357.730429)
			(xy 50.048494 -357.676442) (xy 50.063862 -357.62411) (xy 50.086521 -357.574497) (xy 50.116011 -357.528615)
			(xy 50.151731 -357.487397) (xy 50.192953 -357.451682) (xy 50.238839 -357.422198) (xy 50.288455 -357.399545)
			(xy 50.340789 -357.384184) (xy 50.394777 -357.376428) (xy 50.422048 -357.375968) (xy 51.285648 -357.375968)
			(xy 51.312917 -357.376398) (xy 51.3669 -357.384166) (xy 51.419228 -357.399536) (xy 51.468836 -357.422197)
			(xy 51.514714 -357.451687) (xy 51.555929 -357.487405) (xy 51.591642 -357.528624) (xy 51.621126 -357.574506)
			(xy 51.64378 -357.624117) (xy 51.659145 -357.676447) (xy 51.666906 -357.730431) (xy 51.666906 -357.784969)
			(xy 64.099931 -357.784969) (xy 64.099931 -357.730431) (xy 64.107693 -357.676448) (xy 64.123058 -357.62412)
			(xy 64.145714 -357.57451) (xy 64.1752 -357.52863) (xy 64.210914 -357.487413) (xy 64.252132 -357.451698)
			(xy 64.298012 -357.422213) (xy 64.347621 -357.399557) (xy 64.39995 -357.384193) (xy 64.453933 -357.376431)
			(xy 64.481202 -357.375968) (xy 65.344802 -357.375968) (xy 65.372073 -357.376395) (xy 65.426061 -357.384157)
			(xy 65.478394 -357.399524) (xy 65.528008 -357.422182) (xy 65.573893 -357.45167) (xy 65.615113 -357.487388)
			(xy 65.650831 -357.528609) (xy 65.680319 -357.574493) (xy 65.702977 -357.624107) (xy 65.718343 -357.676441)
			(xy 65.726106 -357.730429) (xy 65.726106 -357.784966) (xy 67.208954 -357.784966) (xy 67.208954 -357.730435)
			(xy 67.216714 -357.676458) (xy 67.232077 -357.624136) (xy 67.254728 -357.574532) (xy 67.284208 -357.528657)
			(xy 67.319917 -357.487443) (xy 67.361126 -357.451731) (xy 67.406999 -357.422246) (xy 67.4566 -357.39959)
			(xy 67.508921 -357.384222) (xy 67.562897 -357.376457) (xy 67.590162 -357.375968) (xy 68.453762 -357.375968)
			(xy 68.481037 -357.376369) (xy 68.535032 -357.384127) (xy 68.587373 -357.399491) (xy 68.636995 -357.422149)
			(xy 68.682887 -357.451638) (xy 68.724115 -357.487358) (xy 68.75984 -357.528582) (xy 68.789333 -357.574471)
			(xy 68.811995 -357.624091) (xy 68.827365 -357.676431) (xy 68.835128 -357.730425) (xy 68.835128 -357.78497)
			(xy 70.317831 -357.78497) (xy 70.317831 -357.73043) (xy 70.325594 -357.676446) (xy 70.34096 -357.624115)
			(xy 70.363617 -357.574505) (xy 70.393105 -357.528623) (xy 70.428822 -357.487406) (xy 70.470041 -357.451691)
			(xy 70.515924 -357.422207) (xy 70.565536 -357.399552) (xy 70.617867 -357.384189) (xy 70.671852 -357.37643)
			(xy 70.699122 -357.375968) (xy 71.562722 -357.375968) (xy 71.589992 -357.376396) (xy 71.643978 -357.384161)
			(xy 71.696309 -357.399529) (xy 71.74592 -357.422189) (xy 71.791802 -357.451677) (xy 71.83302 -357.487395)
			(xy 71.868736 -357.528616) (xy 71.898222 -357.574499) (xy 71.920878 -357.624112) (xy 71.936244 -357.676444)
			(xy 71.944006 -357.730429) (xy 71.944006 -357.784966) (xy 73.426854 -357.784966) (xy 73.426854 -357.730434)
			(xy 73.434615 -357.676456) (xy 73.449978 -357.624132) (xy 73.472631 -357.574527) (xy 73.502113 -357.52865)
			(xy 73.537824 -357.487436) (xy 73.579036 -357.451724) (xy 73.624911 -357.42224) (xy 73.674515 -357.399584)
			(xy 73.726838 -357.384219) (xy 73.780816 -357.376456) (xy 73.808082 -357.375968) (xy 74.671682 -357.375968)
			(xy 74.698956 -357.37637) (xy 74.752949 -357.384131) (xy 74.805288 -357.399497) (xy 74.854907 -357.422155)
			(xy 74.900797 -357.451645) (xy 74.942022 -357.487365) (xy 74.977744 -357.528589) (xy 75.007236 -357.574477)
			(xy 75.029897 -357.624095) (xy 75.045265 -357.676433) (xy 75.053028 -357.730426) (xy 75.053028 -357.784971)
			(xy 76.535732 -357.784971) (xy 76.535732 -357.730429) (xy 76.543494 -357.676443) (xy 76.558861 -357.624111)
			(xy 76.58152 -357.574499) (xy 76.611009 -357.528617) (xy 76.646729 -357.487399) (xy 76.687951 -357.451684)
			(xy 76.733836 -357.4222) (xy 76.78345 -357.399547) (xy 76.835784 -357.384185) (xy 76.889771 -357.376429)
			(xy 76.917042 -357.375968) (xy 77.780642 -357.375968) (xy 77.807912 -357.376397) (xy 77.861895 -357.384165)
			(xy 77.914223 -357.399535) (xy 77.963832 -357.422195) (xy 78.009711 -357.451684) (xy 78.050927 -357.487402)
			(xy 78.086641 -357.528622) (xy 78.116125 -357.574505) (xy 78.13878 -357.624116) (xy 78.154144 -357.676446)
			(xy 78.161906 -357.73043) (xy 78.161906 -357.784969) (xy 79.644731 -357.784969) (xy 79.644731 -357.730431)
			(xy 79.652493 -357.676448) (xy 79.667858 -357.62412) (xy 79.690514 -357.57451) (xy 79.72 -357.52863)
			(xy 79.755714 -357.487413) (xy 79.796932 -357.451698) (xy 79.842812 -357.422213) (xy 79.892421 -357.399557)
			(xy 79.94475 -357.384193) (xy 79.998733 -357.376431) (xy 80.026002 -357.375968) (xy 80.889602 -357.375968)
			(xy 80.916873 -357.376395) (xy 80.970861 -357.384157) (xy 81.023194 -357.399524) (xy 81.072808 -357.422182)
			(xy 81.118693 -357.45167) (xy 81.159913 -357.487388) (xy 81.195631 -357.528609) (xy 81.225119 -357.574493)
			(xy 81.247777 -357.624107) (xy 81.263143 -357.676441) (xy 81.270906 -357.730429) (xy 81.270906 -357.784966)
			(xy 82.753754 -357.784966) (xy 82.753754 -357.730435) (xy 82.761514 -357.676458) (xy 82.776877 -357.624136)
			(xy 82.799528 -357.574532) (xy 82.829008 -357.528657) (xy 82.864717 -357.487443) (xy 82.905926 -357.451731)
			(xy 82.951799 -357.422246) (xy 83.0014 -357.39959) (xy 83.053721 -357.384222) (xy 83.107697 -357.376457)
			(xy 83.134962 -357.375968) (xy 83.998562 -357.375968) (xy 84.025837 -357.376369) (xy 84.079832 -357.384127)
			(xy 84.132173 -357.399491) (xy 84.181795 -357.422149) (xy 84.227687 -357.451638) (xy 84.268915 -357.487358)
			(xy 84.30464 -357.528582) (xy 84.334133 -357.574471) (xy 84.356795 -357.624091) (xy 84.372165 -357.676431)
			(xy 84.379928 -357.730425) (xy 84.379928 -357.78497) (xy 85.862631 -357.78497) (xy 85.862631 -357.73043)
			(xy 85.870394 -357.676446) (xy 85.88576 -357.624115) (xy 85.908417 -357.574505) (xy 85.937905 -357.528623)
			(xy 85.973622 -357.487406) (xy 86.014841 -357.451691) (xy 86.060724 -357.422207) (xy 86.110336 -357.399552)
			(xy 86.162667 -357.384189) (xy 86.216652 -357.37643) (xy 86.243922 -357.375968) (xy 87.107522 -357.375968)
			(xy 87.134792 -357.376396) (xy 87.188778 -357.384161) (xy 87.241109 -357.399529) (xy 87.29072 -357.422189)
			(xy 87.336602 -357.451677) (xy 87.37782 -357.487395) (xy 87.413536 -357.528616) (xy 87.443022 -357.574499)
			(xy 87.465678 -357.624112) (xy 87.481044 -357.676444) (xy 87.488806 -357.730429) (xy 87.488806 -357.784966)
			(xy 88.971654 -357.784966) (xy 88.971654 -357.730434) (xy 88.979415 -357.676456) (xy 88.994778 -357.624132)
			(xy 89.017431 -357.574527) (xy 89.046913 -357.52865) (xy 89.082624 -357.487436) (xy 89.123836 -357.451724)
			(xy 89.169711 -357.42224) (xy 89.219315 -357.399584) (xy 89.271638 -357.384219) (xy 89.325616 -357.376456)
			(xy 89.352882 -357.375968) (xy 90.216482 -357.375968) (xy 90.243756 -357.37637) (xy 90.297749 -357.384131)
			(xy 90.350088 -357.399497) (xy 90.399707 -357.422155) (xy 90.445597 -357.451645) (xy 90.486822 -357.487365)
			(xy 90.522544 -357.528589) (xy 90.552036 -357.574477) (xy 90.574697 -357.624095) (xy 90.590065 -357.676433)
			(xy 90.597828 -357.730426) (xy 90.597828 -357.784971) (xy 92.080532 -357.784971) (xy 92.080532 -357.730429)
			(xy 92.088294 -357.676443) (xy 92.103661 -357.624111) (xy 92.12632 -357.574499) (xy 92.155809 -357.528617)
			(xy 92.191529 -357.487399) (xy 92.232751 -357.451684) (xy 92.278636 -357.4222) (xy 92.32825 -357.399547)
			(xy 92.380584 -357.384185) (xy 92.434571 -357.376429) (xy 92.461842 -357.375968) (xy 93.325442 -357.375968)
			(xy 93.352712 -357.376397) (xy 93.406695 -357.384165) (xy 93.459023 -357.399535) (xy 93.508632 -357.422195)
			(xy 93.554511 -357.451684) (xy 93.595727 -357.487402) (xy 93.631441 -357.528622) (xy 93.660925 -357.574505)
			(xy 93.68358 -357.624116) (xy 93.698944 -357.676446) (xy 93.706706 -357.73043) (xy 93.706706 -357.784966)
			(xy 114.589854 -357.784966) (xy 114.589854 -357.730434) (xy 114.597614 -357.676458) (xy 114.612977 -357.624135)
			(xy 114.635629 -357.574531) (xy 114.66511 -357.528655) (xy 114.700819 -357.487441) (xy 114.742029 -357.451729)
			(xy 114.787903 -357.422244) (xy 114.837505 -357.399588) (xy 114.889826 -357.384221) (xy 114.943802 -357.376457)
			(xy 114.971068 -357.375968) (xy 115.834668 -357.375968) (xy 115.861943 -357.376369) (xy 115.915937 -357.384128)
			(xy 115.968278 -357.399493) (xy 116.017899 -357.422151) (xy 116.06379 -357.45164) (xy 116.105017 -357.48736)
			(xy 116.140741 -357.528584) (xy 116.170234 -357.574473) (xy 116.192896 -357.624092) (xy 116.208265 -357.676431)
			(xy 116.216028 -357.730425) (xy 116.216028 -357.78497) (xy 117.698731 -357.78497) (xy 117.698732 -357.73043)
			(xy 117.706494 -357.676445) (xy 117.72186 -357.624114) (xy 117.744518 -357.574503) (xy 117.774006 -357.528621)
			(xy 117.809724 -357.487404) (xy 117.850944 -357.451689) (xy 117.896827 -357.422205) (xy 117.94644 -357.39955)
			(xy 117.998772 -357.384188) (xy 118.052758 -357.37643) (xy 118.080028 -357.375968) (xy 118.943628 -357.375968)
			(xy 118.970898 -357.376396) (xy 119.024883 -357.384162) (xy 119.077213 -357.399531) (xy 119.126824 -357.42219)
			(xy 119.172705 -357.451679) (xy 119.213922 -357.487397) (xy 119.249637 -357.528618) (xy 119.279123 -357.574501)
			(xy 119.301779 -357.624113) (xy 119.317144 -357.676444) (xy 119.324906 -357.73043) (xy 119.324906 -357.784967)
			(xy 120.807754 -357.784967) (xy 120.807754 -357.730433) (xy 120.815515 -357.676455) (xy 120.830879 -357.624131)
			(xy 120.853532 -357.574525) (xy 120.883015 -357.528648) (xy 120.918726 -357.487434) (xy 120.959939 -357.451722)
			(xy 121.005815 -357.422238) (xy 121.055419 -357.399583) (xy 121.107743 -357.384218) (xy 121.161721 -357.376455)
			(xy 121.188988 -357.375968) (xy 122.052588 -357.375968) (xy 122.079862 -357.376371) (xy 122.133854 -357.384132)
			(xy 122.186192 -357.399499) (xy 122.235811 -357.422157) (xy 122.2817 -357.451647) (xy 122.322924 -357.487367)
			(xy 122.358646 -357.528591) (xy 122.388137 -357.574479) (xy 122.410797 -357.624096) (xy 122.426165 -357.676434)
			(xy 122.433928 -357.730426) (xy 122.433928 -357.784971) (xy 123.916632 -357.784971) (xy 123.916632 -357.730429)
			(xy 123.924394 -357.676442) (xy 123.939762 -357.62411) (xy 123.962421 -357.574497) (xy 123.991911 -357.528615)
			(xy 124.027631 -357.487397) (xy 124.068853 -357.451682) (xy 124.114739 -357.422198) (xy 124.164355 -357.399545)
			(xy 124.216689 -357.384184) (xy 124.270677 -357.376428) (xy 124.297948 -357.375968) (xy 125.161548 -357.375968)
			(xy 125.188817 -357.376398) (xy 125.2428 -357.384166) (xy 125.295128 -357.399536) (xy 125.344736 -357.422197)
			(xy 125.390614 -357.451687) (xy 125.431829 -357.487405) (xy 125.467542 -357.528624) (xy 125.497026 -357.574506)
			(xy 125.51968 -357.624117) (xy 125.535045 -357.676447) (xy 125.542806 -357.730431) (xy 125.542806 -357.784969)
			(xy 127.025631 -357.784969) (xy 127.025631 -357.730431) (xy 127.033393 -357.676447) (xy 127.048759 -357.624118)
			(xy 127.071415 -357.574508) (xy 127.100901 -357.528628) (xy 127.136617 -357.487411) (xy 127.177834 -357.451696)
			(xy 127.223715 -357.422211) (xy 127.273326 -357.399556) (xy 127.325655 -357.384191) (xy 127.379639 -357.376431)
			(xy 127.406908 -357.375968) (xy 128.270508 -357.375968) (xy 128.297779 -357.376395) (xy 128.351766 -357.384158)
			(xy 128.404099 -357.399525) (xy 128.453712 -357.422184) (xy 128.499595 -357.451672) (xy 128.540815 -357.48739)
			(xy 128.576532 -357.528611) (xy 128.60602 -357.574495) (xy 128.628677 -357.624109) (xy 128.644043 -357.676442)
			(xy 128.651806 -357.730429) (xy 128.651806 -357.784966) (xy 130.134654 -357.784966) (xy 130.134654 -357.730434)
			(xy 130.142414 -357.676458) (xy 130.157777 -357.624135) (xy 130.180429 -357.574531) (xy 130.20991 -357.528655)
			(xy 130.245619 -357.487441) (xy 130.286829 -357.451729) (xy 130.332703 -357.422244) (xy 130.382305 -357.399588)
			(xy 130.434626 -357.384221) (xy 130.488602 -357.376457) (xy 130.515868 -357.375968) (xy 131.379468 -357.375968)
			(xy 131.406743 -357.376369) (xy 131.460737 -357.384128) (xy 131.513078 -357.399493) (xy 131.562699 -357.422151)
			(xy 131.60859 -357.45164) (xy 131.649817 -357.48736) (xy 131.685541 -357.528584) (xy 131.715034 -357.574473)
			(xy 131.737696 -357.624092) (xy 131.753065 -357.676431) (xy 131.760828 -357.730425) (xy 131.760828 -357.78497)
			(xy 133.243531 -357.78497) (xy 133.243532 -357.73043) (xy 133.251294 -357.676445) (xy 133.26666 -357.624114)
			(xy 133.289318 -357.574503) (xy 133.318806 -357.528621) (xy 133.354524 -357.487404) (xy 133.395744 -357.451689)
			(xy 133.441627 -357.422205) (xy 133.49124 -357.39955) (xy 133.543572 -357.384188) (xy 133.597558 -357.37643)
			(xy 133.624828 -357.375968) (xy 134.488428 -357.375968) (xy 134.515698 -357.376396) (xy 134.569683 -357.384162)
			(xy 134.622013 -357.399531) (xy 134.671624 -357.42219) (xy 134.717505 -357.451679) (xy 134.758722 -357.487397)
			(xy 134.794437 -357.528618) (xy 134.823923 -357.574501) (xy 134.846579 -357.624113) (xy 134.861944 -357.676444)
			(xy 134.869706 -357.73043) (xy 134.869706 -357.784967) (xy 136.352554 -357.784967) (xy 136.352554 -357.730433)
			(xy 136.360315 -357.676455) (xy 136.375679 -357.624131) (xy 136.398332 -357.574525) (xy 136.427815 -357.528648)
			(xy 136.463526 -357.487434) (xy 136.504739 -357.451722) (xy 136.550615 -357.422238) (xy 136.600219 -357.399583)
			(xy 136.652543 -357.384218) (xy 136.706521 -357.376455) (xy 136.733788 -357.375968) (xy 137.597388 -357.375968)
			(xy 137.624662 -357.376371) (xy 137.678654 -357.384132) (xy 137.730992 -357.399499) (xy 137.780611 -357.422157)
			(xy 137.8265 -357.451647) (xy 137.867724 -357.487367) (xy 137.903446 -357.528591) (xy 137.932937 -357.574479)
			(xy 137.955597 -357.624096) (xy 137.970965 -357.676434) (xy 137.978728 -357.730426) (xy 137.978728 -357.784971)
			(xy 139.461432 -357.784971) (xy 139.461432 -357.730429) (xy 139.469194 -357.676442) (xy 139.484562 -357.62411)
			(xy 139.507221 -357.574497) (xy 139.536711 -357.528615) (xy 139.572431 -357.487397) (xy 139.613653 -357.451682)
			(xy 139.659539 -357.422198) (xy 139.709155 -357.399545) (xy 139.761489 -357.384184) (xy 139.815477 -357.376428)
			(xy 139.842748 -357.375968) (xy 140.706348 -357.375968) (xy 140.733617 -357.376398) (xy 140.7876 -357.384166)
			(xy 140.839928 -357.399536) (xy 140.889536 -357.422197) (xy 140.935414 -357.451687) (xy 140.976629 -357.487405)
			(xy 141.012342 -357.528624) (xy 141.041826 -357.574506) (xy 141.06448 -357.624117) (xy 141.079845 -357.676447)
			(xy 141.087606 -357.730431) (xy 141.087606 -357.784969) (xy 142.570431 -357.784969) (xy 142.570431 -357.730431)
			(xy 142.578193 -357.676447) (xy 142.593559 -357.624118) (xy 142.616215 -357.574508) (xy 142.645701 -357.528628)
			(xy 142.681417 -357.487411) (xy 142.722634 -357.451696) (xy 142.768515 -357.422211) (xy 142.818126 -357.399556)
			(xy 142.870455 -357.384191) (xy 142.924439 -357.376431) (xy 142.951708 -357.375968) (xy 143.815308 -357.375968)
			(xy 143.842579 -357.376395) (xy 143.896566 -357.384158) (xy 143.948899 -357.399525) (xy 143.998512 -357.422184)
			(xy 144.044395 -357.451672) (xy 144.085615 -357.48739) (xy 144.121332 -357.528611) (xy 144.15082 -357.574495)
			(xy 144.173477 -357.624109) (xy 144.188843 -357.676442) (xy 144.196606 -357.730429) (xy 144.196606 -357.784965)
			(xy 158.695954 -357.784965) (xy 158.695954 -357.730435) (xy 158.703714 -357.67646) (xy 158.719076 -357.624138)
			(xy 158.741727 -357.574535) (xy 158.771206 -357.52866) (xy 158.806913 -357.487447) (xy 158.848122 -357.451735)
			(xy 158.893993 -357.42225) (xy 158.943593 -357.399593) (xy 158.995913 -357.384224) (xy 159.049887 -357.376458)
			(xy 159.077152 -357.375968) (xy 159.940752 -357.375968) (xy 159.968027 -357.376368) (xy 160.022024 -357.384125)
			(xy 160.074366 -357.399489) (xy 160.123989 -357.422145) (xy 160.169883 -357.451634) (xy 160.211112 -357.487354)
			(xy 160.246837 -357.528579) (xy 160.276332 -357.574468) (xy 160.298994 -357.624089) (xy 160.314364 -357.676429)
			(xy 160.322128 -357.730425) (xy 160.322128 -357.784969) (xy 161.804831 -357.784969) (xy 161.804831 -357.730431)
			(xy 161.812593 -357.676447) (xy 161.827959 -357.624117) (xy 161.850616 -357.574507) (xy 161.880102 -357.528627)
			(xy 161.915818 -357.487409) (xy 161.957036 -357.451695) (xy 162.002918 -357.42221) (xy 162.052529 -357.399555)
			(xy 162.104859 -357.384191) (xy 162.158843 -357.376431) (xy 162.186112 -357.375968) (xy 163.049712 -357.375968)
			(xy 163.076983 -357.376395) (xy 163.130969 -357.384159) (xy 163.183302 -357.399527) (xy 163.232914 -357.422185)
			(xy 163.278797 -357.451674) (xy 163.320017 -357.487392) (xy 163.355733 -357.528612) (xy 163.385221 -357.574496)
			(xy 163.407878 -357.62411) (xy 163.423244 -357.676442) (xy 163.431006 -357.730429) (xy 163.431006 -357.784966)
			(xy 164.913854 -357.784966) (xy 164.913854 -357.730434) (xy 164.921615 -357.676457) (xy 164.936977 -357.624134)
			(xy 164.95963 -357.57453) (xy 164.989111 -357.528654) (xy 165.02482 -357.48744) (xy 165.066031 -357.451727)
			(xy 165.111905 -357.422243) (xy 165.161508 -357.399587) (xy 165.21383 -357.384221) (xy 165.267806 -357.376456)
			(xy 165.295072 -357.375968) (xy 166.158672 -357.375968) (xy 166.185946 -357.37637) (xy 166.239941 -357.384129)
			(xy 166.292281 -357.399494) (xy 166.341901 -357.422152) (xy 166.387792 -357.451641) (xy 166.429019 -357.487361)
			(xy 166.464742 -357.528585) (xy 166.494235 -357.574474) (xy 166.516896 -357.624093) (xy 166.532265 -357.676432)
			(xy 166.540028 -357.730426) (xy 166.540028 -357.78497) (xy 168.022732 -357.78497) (xy 168.022732 -357.73043)
			(xy 168.030494 -357.676444) (xy 168.045861 -357.624113) (xy 168.068519 -357.574502) (xy 168.098007 -357.52862)
			(xy 168.133725 -357.487402) (xy 168.174946 -357.451688) (xy 168.22083 -357.422203) (xy 168.270443 -357.399549)
			(xy 168.322776 -357.384187) (xy 168.376762 -357.376429) (xy 168.404032 -357.375968) (xy 169.267632 -357.375968)
			(xy 169.294902 -357.376397) (xy 169.348886 -357.384163) (xy 169.401216 -357.399532) (xy 169.450826 -357.422192)
			(xy 169.496707 -357.451681) (xy 169.537924 -357.487399) (xy 169.573638 -357.528619) (xy 169.603124 -357.574502)
			(xy 169.625779 -357.624114) (xy 169.641144 -357.676445) (xy 169.648906 -357.73043) (xy 169.648906 -357.784967)
			(xy 171.131754 -357.784967) (xy 171.131754 -357.730433) (xy 171.139515 -357.676454) (xy 171.154879 -357.62413)
			(xy 171.177533 -357.574524) (xy 171.207016 -357.528647) (xy 171.242727 -357.487433) (xy 171.283941 -357.45172)
			(xy 171.329817 -357.422237) (xy 171.379422 -357.399582) (xy 171.431747 -357.384217) (xy 171.485725 -357.376455)
			(xy 171.512992 -357.375968) (xy 172.376592 -357.375968) (xy 172.403866 -357.376371) (xy 172.457857 -357.384133)
			(xy 172.510195 -357.3995) (xy 172.559813 -357.422159) (xy 172.605702 -357.451648) (xy 172.646926 -357.487368)
			(xy 172.682647 -357.528592) (xy 172.712138 -357.57448) (xy 172.734798 -357.624097) (xy 172.750165 -357.676435)
			(xy 172.757928 -357.730426) (xy 172.757928 -357.784965) (xy 174.240754 -357.784965) (xy 174.240754 -357.730435)
			(xy 174.248514 -357.67646) (xy 174.263876 -357.624138) (xy 174.286527 -357.574535) (xy 174.316006 -357.52866)
			(xy 174.351713 -357.487447) (xy 174.392922 -357.451735) (xy 174.438793 -357.42225) (xy 174.488393 -357.399593)
			(xy 174.540713 -357.384224) (xy 174.594687 -357.376458) (xy 174.621952 -357.375968) (xy 175.485552 -357.375968)
			(xy 175.512827 -357.376368) (xy 175.566824 -357.384125) (xy 175.619166 -357.399489) (xy 175.668789 -357.422145)
			(xy 175.714683 -357.451634) (xy 175.755912 -357.487354) (xy 175.791637 -357.528579) (xy 175.821132 -357.574468)
			(xy 175.843794 -357.624089) (xy 175.859164 -357.676429) (xy 175.866928 -357.730425) (xy 175.866928 -357.784969)
			(xy 177.349631 -357.784969) (xy 177.349631 -357.730431) (xy 177.357393 -357.676447) (xy 177.372759 -357.624117)
			(xy 177.395416 -357.574507) (xy 177.424902 -357.528627) (xy 177.460618 -357.487409) (xy 177.501836 -357.451695)
			(xy 177.547718 -357.42221) (xy 177.597329 -357.399555) (xy 177.649659 -357.384191) (xy 177.703643 -357.376431)
			(xy 177.730912 -357.375968) (xy 178.594512 -357.375968) (xy 178.621783 -357.376395) (xy 178.675769 -357.384159)
			(xy 178.728102 -357.399527) (xy 178.777714 -357.422185) (xy 178.823597 -357.451674) (xy 178.864817 -357.487392)
			(xy 178.900533 -357.528612) (xy 178.930021 -357.574496) (xy 178.952678 -357.62411) (xy 178.968044 -357.676442)
			(xy 178.975806 -357.730429) (xy 178.975806 -357.784966) (xy 180.458654 -357.784966) (xy 180.458654 -357.730434)
			(xy 180.466415 -357.676457) (xy 180.481777 -357.624134) (xy 180.50443 -357.57453) (xy 180.533911 -357.528654)
			(xy 180.56962 -357.48744) (xy 180.610831 -357.451727) (xy 180.656705 -357.422243) (xy 180.706308 -357.399587)
			(xy 180.75863 -357.384221) (xy 180.812606 -357.376456) (xy 180.839872 -357.375968) (xy 181.703472 -357.375968)
			(xy 181.730746 -357.37637) (xy 181.784741 -357.384129) (xy 181.837081 -357.399494) (xy 181.886701 -357.422152)
			(xy 181.932592 -357.451641) (xy 181.973819 -357.487361) (xy 182.009542 -357.528585) (xy 182.039035 -357.574474)
			(xy 182.061696 -357.624093) (xy 182.077065 -357.676432) (xy 182.084828 -357.730426) (xy 182.084828 -357.761176)
			(xy 183.567456 -357.761176) (xy 183.567456 -357.706624) (xy 183.57522 -357.652628) (xy 183.590589 -357.600287)
			(xy 183.613252 -357.550665) (xy 183.642746 -357.504775) (xy 183.678471 -357.463549) (xy 183.7197 -357.427827)
			(xy 183.765593 -357.398337) (xy 183.815217 -357.375678) (xy 183.867559 -357.360313) (xy 183.921556 -357.352553)
			(xy 183.948832 -357.352092) (xy 184.812432 -357.352092) (xy 184.839697 -357.352672) (xy 184.89367 -357.360437)
			(xy 184.94599 -357.375803) (xy 184.99559 -357.398458) (xy 185.041461 -357.427942) (xy 185.08267 -357.463653)
			(xy 185.118378 -357.504864) (xy 185.147857 -357.550738) (xy 185.170508 -357.60034) (xy 185.18587 -357.652661)
			(xy 185.19363 -357.706635) (xy 185.19363 -357.761165) (xy 185.193629 -357.761172) (xy 186.676479 -357.761172)
			(xy 186.676479 -357.706628) (xy 186.684241 -357.652638) (xy 186.699608 -357.600303) (xy 186.722266 -357.550688)
			(xy 186.751755 -357.504801) (xy 186.787473 -357.463579) (xy 186.828695 -357.42786) (xy 186.87458 -357.39837)
			(xy 186.924196 -357.37571) (xy 186.97653 -357.360343) (xy 187.03052 -357.352579) (xy 187.057792 -357.352092)
			(xy 187.921392 -357.352092) (xy 187.94866 -357.352647) (xy 188.002641 -357.360407) (xy 188.054969 -357.375771)
			(xy 188.104577 -357.398425) (xy 188.150456 -357.427909) (xy 188.191672 -357.463622) (xy 188.227386 -357.504838)
			(xy 188.256871 -357.550716) (xy 188.279526 -357.600324) (xy 188.294891 -357.652651) (xy 188.302653 -357.706632)
			(xy 188.302653 -357.761168) (xy 188.294891 -357.815149) (xy 188.279526 -357.867476) (xy 188.256871 -357.917084)
			(xy 188.227386 -357.962962) (xy 188.223925 -357.966956) (xy 245.50903 -357.966956) (xy 245.50903 -357.88226)
			(xy 245.517081 -357.797946) (xy 245.53311 -357.71478) (xy 245.556971 -357.633513) (xy 245.58845 -357.554883)
			(xy 245.627261 -357.479602) (xy 245.673051 -357.40835) (xy 245.725407 -357.341774) (xy 245.783855 -357.280476)
			(xy 245.847865 -357.225011) (xy 245.916857 -357.175882) (xy 245.990207 -357.133533) (xy 246.06725 -357.098349)
			(xy 246.147289 -357.070647) (xy 246.229598 -357.050679) (xy 246.313433 -357.038626) (xy 246.398034 -357.034596)
			(xy 246.482635 -357.038626) (xy 246.56647 -357.050679) (xy 246.648779 -357.070647) (xy 246.728818 -357.098349)
			(xy 246.805861 -357.133533) (xy 246.879211 -357.175882) (xy 246.948203 -357.225011) (xy 247.012213 -357.280476)
			(xy 247.070661 -357.341774) (xy 247.123017 -357.40835) (xy 247.168807 -357.479602) (xy 247.207618 -357.554883)
			(xy 247.239097 -357.633513) (xy 247.262958 -357.71478) (xy 247.276485 -357.784966) (xy 270.624854 -357.784966)
			(xy 270.624854 -357.730435) (xy 270.632614 -357.676458) (xy 270.647977 -357.624136) (xy 270.670628 -357.574532)
			(xy 270.700108 -357.528657) (xy 270.735817 -357.487443) (xy 270.777026 -357.451731) (xy 270.822899 -357.422246)
			(xy 270.8725 -357.39959) (xy 270.924821 -357.384222) (xy 270.978797 -357.376457) (xy 271.006062 -357.375968)
			(xy 271.869662 -357.375968) (xy 271.896937 -357.376369) (xy 271.950932 -357.384127) (xy 272.003273 -357.399491)
			(xy 272.052895 -357.422149) (xy 272.098787 -357.451638) (xy 272.140015 -357.487358) (xy 272.17574 -357.528582)
			(xy 272.205233 -357.574471) (xy 272.227895 -357.624091) (xy 272.243265 -357.676431) (xy 272.251028 -357.730425)
			(xy 272.251028 -357.78497) (xy 273.733731 -357.78497) (xy 273.733731 -357.73043) (xy 273.741494 -357.676446)
			(xy 273.75686 -357.624115) (xy 273.779517 -357.574505) (xy 273.809005 -357.528623) (xy 273.844722 -357.487406)
			(xy 273.885941 -357.451691) (xy 273.931824 -357.422207) (xy 273.981436 -357.399552) (xy 274.033767 -357.384189)
			(xy 274.087752 -357.37643) (xy 274.115022 -357.375968) (xy 274.978622 -357.375968) (xy 275.005892 -357.376396)
			(xy 275.059878 -357.384161) (xy 275.112209 -357.399529) (xy 275.16182 -357.422189) (xy 275.207702 -357.451677)
			(xy 275.24892 -357.487395) (xy 275.284636 -357.528616) (xy 275.314122 -357.574499) (xy 275.336778 -357.624112)
			(xy 275.352144 -357.676444) (xy 275.359906 -357.730429) (xy 275.359906 -357.784966) (xy 276.842754 -357.784966)
			(xy 276.842754 -357.730434) (xy 276.850515 -357.676456) (xy 276.865878 -357.624132) (xy 276.888531 -357.574527)
			(xy 276.918013 -357.52865) (xy 276.953724 -357.487436) (xy 276.994936 -357.451724) (xy 277.040811 -357.42224)
			(xy 277.090415 -357.399584) (xy 277.142738 -357.384219) (xy 277.196716 -357.376456) (xy 277.223982 -357.375968)
			(xy 278.087582 -357.375968) (xy 278.114856 -357.37637) (xy 278.168849 -357.384131) (xy 278.221188 -357.399497)
			(xy 278.270807 -357.422155) (xy 278.316697 -357.451645) (xy 278.357922 -357.487365) (xy 278.393644 -357.528589)
			(xy 278.423136 -357.574477) (xy 278.445797 -357.624095) (xy 278.461165 -357.676433) (xy 278.468928 -357.730426)
			(xy 278.468928 -357.784971) (xy 279.951632 -357.784971) (xy 279.951632 -357.730429) (xy 279.959394 -357.676443)
			(xy 279.974761 -357.624111) (xy 279.99742 -357.574499) (xy 280.026909 -357.528617) (xy 280.062629 -357.487399)
			(xy 280.103851 -357.451684) (xy 280.149736 -357.4222) (xy 280.19935 -357.399547) (xy 280.251684 -357.384185)
			(xy 280.305671 -357.376429) (xy 280.332942 -357.375968) (xy 281.196542 -357.375968) (xy 281.223812 -357.376397)
			(xy 281.277795 -357.384165) (xy 281.330123 -357.399535) (xy 281.379732 -357.422195) (xy 281.425611 -357.451684)
			(xy 281.466827 -357.487402) (xy 281.502541 -357.528622) (xy 281.532025 -357.574505) (xy 281.55468 -357.624116)
			(xy 281.570044 -357.676446) (xy 281.577806 -357.73043) (xy 281.577806 -357.784969) (xy 283.060631 -357.784969)
			(xy 283.060631 -357.730431) (xy 283.068393 -357.676448) (xy 283.083758 -357.62412) (xy 283.106414 -357.57451)
			(xy 283.1359 -357.52863) (xy 283.171614 -357.487413) (xy 283.212832 -357.451698) (xy 283.258712 -357.422213)
			(xy 283.308321 -357.399557) (xy 283.36065 -357.384193) (xy 283.414633 -357.376431) (xy 283.441902 -357.375968)
			(xy 284.305502 -357.375968) (xy 284.332773 -357.376395) (xy 284.386761 -357.384157) (xy 284.439094 -357.399524)
			(xy 284.488708 -357.422182) (xy 284.534593 -357.45167) (xy 284.575813 -357.487388) (xy 284.611531 -357.528609)
			(xy 284.641019 -357.574493) (xy 284.663677 -357.624107) (xy 284.679043 -357.676441) (xy 284.686806 -357.730429)
			(xy 284.686806 -357.784966) (xy 286.169654 -357.784966) (xy 286.169654 -357.730435) (xy 286.177414 -357.676458)
			(xy 286.192777 -357.624136) (xy 286.215428 -357.574532) (xy 286.244908 -357.528657) (xy 286.280617 -357.487443)
			(xy 286.321826 -357.451731) (xy 286.367699 -357.422246) (xy 286.4173 -357.39959) (xy 286.469621 -357.384222)
			(xy 286.523597 -357.376457) (xy 286.550862 -357.375968) (xy 287.414462 -357.375968) (xy 287.441737 -357.376369)
			(xy 287.495732 -357.384127) (xy 287.548073 -357.399491) (xy 287.597695 -357.422149) (xy 287.643587 -357.451638)
			(xy 287.684815 -357.487358) (xy 287.72054 -357.528582) (xy 287.750033 -357.574471) (xy 287.772695 -357.624091)
			(xy 287.788065 -357.676431) (xy 287.795828 -357.730425) (xy 287.795828 -357.78497) (xy 289.278531 -357.78497)
			(xy 289.278531 -357.73043) (xy 289.286294 -357.676446) (xy 289.30166 -357.624115) (xy 289.324317 -357.574505)
			(xy 289.353805 -357.528623) (xy 289.389522 -357.487406) (xy 289.430741 -357.451691) (xy 289.476624 -357.422207)
			(xy 289.526236 -357.399552) (xy 289.578567 -357.384189) (xy 289.632552 -357.37643) (xy 289.659822 -357.375968)
			(xy 290.523422 -357.375968) (xy 290.550692 -357.376396) (xy 290.604678 -357.384161) (xy 290.657009 -357.399529)
			(xy 290.70662 -357.422189) (xy 290.752502 -357.451677) (xy 290.79372 -357.487395) (xy 290.829436 -357.528616)
			(xy 290.858922 -357.574499) (xy 290.881578 -357.624112) (xy 290.896944 -357.676444) (xy 290.904706 -357.730429)
			(xy 290.904706 -357.784966) (xy 292.387554 -357.784966) (xy 292.387554 -357.730434) (xy 292.395315 -357.676456)
			(xy 292.410678 -357.624132) (xy 292.433331 -357.574527) (xy 292.462813 -357.52865) (xy 292.498524 -357.487436)
			(xy 292.539736 -357.451724) (xy 292.585611 -357.42224) (xy 292.635215 -357.399584) (xy 292.687538 -357.384219)
			(xy 292.741516 -357.376456) (xy 292.768782 -357.375968) (xy 293.632382 -357.375968) (xy 293.659656 -357.37637)
			(xy 293.713649 -357.384131) (xy 293.765988 -357.399497) (xy 293.815607 -357.422155) (xy 293.861497 -357.451645)
			(xy 293.902722 -357.487365) (xy 293.938444 -357.528589) (xy 293.967936 -357.574477) (xy 293.990597 -357.624095)
			(xy 294.005965 -357.676433) (xy 294.013728 -357.730426) (xy 294.013728 -357.784971) (xy 295.496432 -357.784971)
			(xy 295.496432 -357.730429) (xy 295.504194 -357.676443) (xy 295.519561 -357.624111) (xy 295.54222 -357.574499)
			(xy 295.571709 -357.528617) (xy 295.607429 -357.487399) (xy 295.648651 -357.451684) (xy 295.694536 -357.4222)
			(xy 295.74415 -357.399547) (xy 295.796484 -357.384185) (xy 295.850471 -357.376429) (xy 295.877742 -357.375968)
			(xy 296.741342 -357.375968) (xy 296.768612 -357.376397) (xy 296.822595 -357.384165) (xy 296.874923 -357.399535)
			(xy 296.924532 -357.422195) (xy 296.970411 -357.451684) (xy 297.011627 -357.487402) (xy 297.047341 -357.528622)
			(xy 297.076825 -357.574505) (xy 297.09948 -357.624116) (xy 297.114844 -357.676446) (xy 297.122606 -357.73043)
			(xy 297.122606 -357.784969) (xy 298.605431 -357.784969) (xy 298.605431 -357.730431) (xy 298.613193 -357.676448)
			(xy 298.628558 -357.62412) (xy 298.651214 -357.57451) (xy 298.6807 -357.52863) (xy 298.716414 -357.487413)
			(xy 298.757632 -357.451698) (xy 298.803512 -357.422213) (xy 298.853121 -357.399557) (xy 298.90545 -357.384193)
			(xy 298.959433 -357.376431) (xy 298.986702 -357.375968) (xy 299.850302 -357.375968) (xy 299.877573 -357.376395)
			(xy 299.931561 -357.384157) (xy 299.983894 -357.399524) (xy 300.033508 -357.422182) (xy 300.079393 -357.45167)
			(xy 300.120613 -357.487388) (xy 300.156331 -357.528609) (xy 300.185819 -357.574493) (xy 300.208477 -357.624107)
			(xy 300.223843 -357.676441) (xy 300.231606 -357.730429) (xy 300.231606 -357.784966) (xy 315.230554 -357.784966)
			(xy 315.230554 -357.730434) (xy 315.238314 -357.676458) (xy 315.253677 -357.624136) (xy 315.276328 -357.574532)
			(xy 315.305809 -357.528656) (xy 315.341517 -357.487443) (xy 315.382727 -357.45173) (xy 315.4286 -357.422246)
			(xy 315.478202 -357.399589) (xy 315.530523 -357.384222) (xy 315.584498 -357.376457) (xy 315.611764 -357.375968)
			(xy 316.475364 -357.375968) (xy 316.502639 -357.376369) (xy 316.556634 -357.384128) (xy 316.608975 -357.399492)
			(xy 316.658597 -357.422149) (xy 316.704488 -357.451638) (xy 316.745716 -357.487359) (xy 316.78144 -357.528583)
			(xy 316.810933 -357.574472) (xy 316.833595 -357.624091) (xy 316.848965 -357.676431) (xy 316.856728 -357.730425)
			(xy 316.856728 -357.78497) (xy 318.339431 -357.78497) (xy 318.339431 -357.73043) (xy 318.347194 -357.676445)
			(xy 318.36256 -357.624115) (xy 318.385217 -357.574504) (xy 318.414705 -357.528623) (xy 318.450422 -357.487405)
			(xy 318.491642 -357.451691) (xy 318.537525 -357.422206) (xy 318.587137 -357.399552) (xy 318.639469 -357.384189)
			(xy 318.693454 -357.37643) (xy 318.720724 -357.375968) (xy 319.584324 -357.375968) (xy 319.611594 -357.376396)
			(xy 319.66558 -357.384161) (xy 319.71791 -357.39953) (xy 319.767521 -357.422189) (xy 319.813403 -357.451678)
			(xy 319.854621 -357.487396) (xy 319.890336 -357.528616) (xy 319.919822 -357.5745) (xy 319.942479 -357.624112)
			(xy 319.957844 -357.676444) (xy 319.965606 -357.73043) (xy 319.965606 -357.784967) (xy 321.448454 -357.784967)
			(xy 321.448454 -357.730434) (xy 321.456215 -357.676456) (xy 321.471578 -357.624131) (xy 321.494232 -357.574526)
			(xy 321.523714 -357.52865) (xy 321.559424 -357.487436) (xy 321.600637 -357.451723) (xy 321.646512 -357.422239)
			(xy 321.696116 -357.399584) (xy 321.74844 -357.384218) (xy 321.802418 -357.376455) (xy 321.829684 -357.375968)
			(xy 322.693284 -357.375968) (xy 322.720558 -357.37637) (xy 322.774551 -357.384131) (xy 322.826889 -357.399497)
			(xy 322.876508 -357.422156) (xy 322.922398 -357.451645) (xy 322.963623 -357.487366) (xy 322.999345 -357.528589)
			(xy 323.028836 -357.574477) (xy 323.051497 -357.624096) (xy 323.066865 -357.676434) (xy 323.074628 -357.730426)
			(xy 323.074628 -357.784971) (xy 324.557332 -357.784971) (xy 324.557332 -357.730429) (xy 324.565094 -357.676443)
			(xy 324.580461 -357.624111) (xy 324.603121 -357.574498) (xy 324.63261 -357.528616) (xy 324.668329 -357.487398)
			(xy 324.709551 -357.451684) (xy 324.755437 -357.422199) (xy 324.805052 -357.399546) (xy 324.857386 -357.384185)
			(xy 324.911373 -357.376428) (xy 324.938644 -357.375968) (xy 325.802244 -357.375968) (xy 325.829513 -357.376398)
			(xy 325.883497 -357.384165) (xy 325.935825 -357.399535) (xy 325.985433 -357.422196) (xy 326.031312 -357.451685)
			(xy 326.072528 -357.487403) (xy 326.108241 -357.528623) (xy 326.137725 -357.574505) (xy 326.16038 -357.624116)
			(xy 326.175744 -357.676447) (xy 326.183506 -357.73043) (xy 326.183506 -357.784969) (xy 327.666331 -357.784969)
			(xy 327.666331 -357.730431) (xy 327.674093 -357.676448) (xy 327.689458 -357.624119) (xy 327.712114 -357.57451)
			(xy 327.7416 -357.528629) (xy 327.777315 -357.487412) (xy 327.818533 -357.451698) (xy 327.864413 -357.422212)
			(xy 327.914023 -357.399557) (xy 327.966352 -357.384192) (xy 328.020335 -357.376431) (xy 328.047604 -357.375968)
			(xy 328.911204 -357.375968) (xy 328.938475 -357.376395) (xy 328.992463 -357.384158) (xy 329.044796 -357.399524)
			(xy 329.094409 -357.422183) (xy 329.140293 -357.451671) (xy 329.181514 -357.487389) (xy 329.217231 -357.52861)
			(xy 329.246719 -357.574494) (xy 329.269377 -357.624108) (xy 329.284743 -357.676441) (xy 329.292506 -357.730429)
			(xy 329.292506 -357.784966) (xy 330.775354 -357.784966) (xy 330.775354 -357.730434) (xy 330.783114 -357.676458)
			(xy 330.798477 -357.624136) (xy 330.821128 -357.574532) (xy 330.850609 -357.528656) (xy 330.886317 -357.487443)
			(xy 330.927527 -357.45173) (xy 330.9734 -357.422246) (xy 331.023002 -357.399589) (xy 331.075323 -357.384222)
			(xy 331.129298 -357.376457) (xy 331.156564 -357.375968) (xy 332.020164 -357.375968) (xy 332.047439 -357.376369)
			(xy 332.101434 -357.384128) (xy 332.153775 -357.399492) (xy 332.203397 -357.422149) (xy 332.249288 -357.451638)
			(xy 332.290516 -357.487359) (xy 332.32624 -357.528583) (xy 332.355733 -357.574472) (xy 332.378395 -357.624091)
			(xy 332.393765 -357.676431) (xy 332.401528 -357.730425) (xy 332.401528 -357.78497) (xy 333.884231 -357.78497)
			(xy 333.884231 -357.73043) (xy 333.891994 -357.676445) (xy 333.90736 -357.624115) (xy 333.930017 -357.574504)
			(xy 333.959505 -357.528623) (xy 333.995222 -357.487405) (xy 334.036442 -357.451691) (xy 334.082325 -357.422206)
			(xy 334.131937 -357.399552) (xy 334.184269 -357.384189) (xy 334.238254 -357.37643) (xy 334.265524 -357.375968)
			(xy 335.129124 -357.375968) (xy 335.156394 -357.376396) (xy 335.21038 -357.384161) (xy 335.26271 -357.39953)
			(xy 335.312321 -357.422189) (xy 335.358203 -357.451678) (xy 335.399421 -357.487396) (xy 335.435136 -357.528616)
			(xy 335.464622 -357.5745) (xy 335.487279 -357.624112) (xy 335.502644 -357.676444) (xy 335.510406 -357.73043)
			(xy 335.510406 -357.784967) (xy 336.993254 -357.784967) (xy 336.993254 -357.730434) (xy 337.001015 -357.676456)
			(xy 337.016378 -357.624131) (xy 337.039032 -357.574526) (xy 337.068514 -357.52865) (xy 337.104224 -357.487436)
			(xy 337.145437 -357.451723) (xy 337.191312 -357.422239) (xy 337.240916 -357.399584) (xy 337.29324 -357.384218)
			(xy 337.347218 -357.376455) (xy 337.374484 -357.375968) (xy 338.238084 -357.375968) (xy 338.265358 -357.37637)
			(xy 338.319351 -357.384131) (xy 338.371689 -357.399497) (xy 338.421308 -357.422156) (xy 338.467198 -357.451645)
			(xy 338.508423 -357.487366) (xy 338.544145 -357.528589) (xy 338.573636 -357.574477) (xy 338.596297 -357.624096)
			(xy 338.611665 -357.676434) (xy 338.619428 -357.730426) (xy 338.619428 -357.784971) (xy 340.102132 -357.784971)
			(xy 340.102132 -357.730429) (xy 340.109894 -357.676443) (xy 340.125261 -357.624111) (xy 340.147921 -357.574498)
			(xy 340.17741 -357.528616) (xy 340.213129 -357.487398) (xy 340.254351 -357.451684) (xy 340.300237 -357.422199)
			(xy 340.349852 -357.399546) (xy 340.402186 -357.384185) (xy 340.456173 -357.376428) (xy 340.483444 -357.375968)
			(xy 341.347044 -357.375968) (xy 341.374313 -357.376398) (xy 341.428297 -357.384165) (xy 341.480625 -357.399535)
			(xy 341.530233 -357.422196) (xy 341.576112 -357.451685) (xy 341.617328 -357.487403) (xy 341.653041 -357.528623)
			(xy 341.682525 -357.574505) (xy 341.70518 -357.624116) (xy 341.720544 -357.676447) (xy 341.728306 -357.73043)
			(xy 341.728306 -357.784969) (xy 343.211131 -357.784969) (xy 343.211131 -357.730431) (xy 343.218893 -357.676448)
			(xy 343.234258 -357.624119) (xy 343.256914 -357.57451) (xy 343.2864 -357.528629) (xy 343.322115 -357.487412)
			(xy 343.363333 -357.451698) (xy 343.409213 -357.422212) (xy 343.458823 -357.399557) (xy 343.511152 -357.384192)
			(xy 343.565135 -357.376431) (xy 343.592404 -357.375968) (xy 344.456004 -357.375968) (xy 344.483275 -357.376395)
			(xy 344.537263 -357.384158) (xy 344.589596 -357.399524) (xy 344.639209 -357.422183) (xy 344.685093 -357.451671)
			(xy 344.726314 -357.487389) (xy 344.762031 -357.52861) (xy 344.791519 -357.574494) (xy 344.814177 -357.624108)
			(xy 344.829543 -357.676441) (xy 344.837306 -357.730429) (xy 344.837306 -357.784971) (xy 373.915632 -357.784971)
			(xy 373.915632 -357.730429) (xy 373.923394 -357.676443) (xy 373.938761 -357.624111) (xy 373.96142 -357.574499)
			(xy 373.990909 -357.528617) (xy 374.026628 -357.4874) (xy 374.06785 -357.451685) (xy 374.113735 -357.422201)
			(xy 374.163349 -357.399547) (xy 374.215682 -357.384186) (xy 374.269669 -357.376429) (xy 374.29694 -357.375968)
			(xy 375.16054 -357.375968) (xy 375.18781 -357.376397) (xy 375.241793 -357.384164) (xy 375.294122 -357.399534)
			(xy 375.343731 -357.422194) (xy 375.389611 -357.451684) (xy 375.430827 -357.487402) (xy 375.46654 -357.528622)
			(xy 375.496025 -357.574504) (xy 375.51868 -357.624116) (xy 375.534044 -357.676446) (xy 375.541806 -357.73043)
			(xy 375.541806 -357.784967) (xy 377.024654 -357.784967) (xy 377.024654 -357.730433) (xy 377.032415 -357.676453)
			(xy 377.04778 -357.624128) (xy 377.070434 -357.574522) (xy 377.099918 -357.528644) (xy 377.13563 -357.48743)
			(xy 377.176844 -357.451718) (xy 377.222722 -357.422234) (xy 377.272328 -357.39958) (xy 377.324653 -357.384215)
			(xy 377.378633 -357.376454) (xy 377.4059 -357.375968) (xy 378.2695 -357.375968) (xy 378.296772 -357.376395)
			(xy 378.350759 -357.384157) (xy 378.403093 -357.399523) (xy 378.452707 -357.422181) (xy 378.498592 -357.451669)
			(xy 378.539812 -357.487388) (xy 378.575531 -357.528608) (xy 378.605019 -357.574493) (xy 378.627677 -357.624107)
			(xy 378.643043 -357.676441) (xy 378.650805 -357.730428) (xy 378.650805 -357.784965) (xy 380.133654 -357.784965)
			(xy 380.133654 -357.730435) (xy 380.141414 -357.676459) (xy 380.156776 -357.624137) (xy 380.179428 -357.574533)
			(xy 380.208908 -357.528658) (xy 380.244616 -357.487444) (xy 380.285825 -357.451732) (xy 380.331698 -357.422247)
			(xy 380.381299 -357.39959) (xy 380.43362 -357.384223) (xy 380.487595 -357.376457) (xy 380.51486 -357.375968)
			(xy 381.37846 -357.375968) (xy 381.405735 -357.376369) (xy 381.45973 -357.384127) (xy 381.512072 -357.399491)
			(xy 381.561694 -357.422148) (xy 381.607586 -357.451637) (xy 381.648815 -357.487357) (xy 381.684539 -357.528582)
			(xy 381.714033 -357.574471) (xy 381.736695 -357.62409) (xy 381.752065 -357.67643) (xy 381.759828 -357.730425)
			(xy 381.759828 -357.78497) (xy 383.242531 -357.78497) (xy 383.242531 -357.73043) (xy 383.250294 -357.676446)
			(xy 383.26566 -357.624116) (xy 383.288317 -357.574505) (xy 383.317804 -357.528624) (xy 383.353521 -357.487407)
			(xy 383.39474 -357.451692) (xy 383.440623 -357.422207) (xy 383.490234 -357.399553) (xy 383.542565 -357.384189)
			(xy 383.59655 -357.37643) (xy 383.62382 -357.375968) (xy 384.48742 -357.375968) (xy 384.514691 -357.376396)
			(xy 384.568676 -357.38416) (xy 384.621007 -357.399529) (xy 384.670619 -357.422188) (xy 384.716501 -357.451677)
			(xy 384.75772 -357.487395) (xy 384.793435 -357.528615) (xy 384.822922 -357.574499) (xy 384.845578 -357.624111)
			(xy 384.860944 -357.676443) (xy 384.868706 -357.730429) (xy 384.868706 -357.784966) (xy 386.351554 -357.784966)
			(xy 386.351554 -357.730434) (xy 386.359315 -357.676456) (xy 386.374678 -357.624132) (xy 386.397331 -357.574527)
			(xy 386.426813 -357.528651) (xy 386.462523 -357.487437) (xy 386.503735 -357.451725) (xy 386.54961 -357.422241)
			(xy 386.599213 -357.399585) (xy 386.651537 -357.384219) (xy 386.705514 -357.376456) (xy 386.73278 -357.375968)
			(xy 387.59638 -357.375968) (xy 387.623654 -357.37637) (xy 387.677647 -357.384131) (xy 387.729987 -357.399496)
			(xy 387.779606 -357.422155) (xy 387.825496 -357.451644) (xy 387.866722 -357.487364) (xy 387.902444 -357.528588)
			(xy 387.931936 -357.574476) (xy 387.954597 -357.624095) (xy 387.969965 -357.676433) (xy 387.977728 -357.730426)
			(xy 387.977728 -357.784971) (xy 389.460432 -357.784971) (xy 389.460432 -357.730429) (xy 389.468194 -357.676443)
			(xy 389.483561 -357.624111) (xy 389.50622 -357.574499) (xy 389.535709 -357.528617) (xy 389.571428 -357.4874)
			(xy 389.61265 -357.451685) (xy 389.658535 -357.422201) (xy 389.708149 -357.399547) (xy 389.760482 -357.384186)
			(xy 389.814469 -357.376429) (xy 389.84174 -357.375968) (xy 390.70534 -357.375968) (xy 390.73261 -357.376397)
			(xy 390.786593 -357.384164) (xy 390.838922 -357.399534) (xy 390.888531 -357.422194) (xy 390.934411 -357.451684)
			(xy 390.975627 -357.487402) (xy 391.01134 -357.528622) (xy 391.040825 -357.574504) (xy 391.06348 -357.624116)
			(xy 391.078844 -357.676446) (xy 391.086606 -357.73043) (xy 391.086606 -357.784967) (xy 392.569454 -357.784967)
			(xy 392.569454 -357.730433) (xy 392.577215 -357.676453) (xy 392.59258 -357.624128) (xy 392.615234 -357.574522)
			(xy 392.644718 -357.528644) (xy 392.68043 -357.48743) (xy 392.721644 -357.451718) (xy 392.767522 -357.422234)
			(xy 392.817128 -357.39958) (xy 392.869453 -357.384215) (xy 392.923433 -357.376454) (xy 392.9507 -357.375968)
			(xy 393.8143 -357.375968) (xy 393.841572 -357.376395) (xy 393.895559 -357.384157) (xy 393.947893 -357.399523)
			(xy 393.997507 -357.422181) (xy 394.043392 -357.451669) (xy 394.084612 -357.487388) (xy 394.120331 -357.528608)
			(xy 394.149819 -357.574493) (xy 394.172477 -357.624107) (xy 394.187843 -357.676441) (xy 394.195605 -357.730428)
			(xy 394.195605 -357.784965) (xy 395.678454 -357.784965) (xy 395.678454 -357.730435) (xy 395.686214 -357.676459)
			(xy 395.701576 -357.624137) (xy 395.724228 -357.574533) (xy 395.753708 -357.528658) (xy 395.789416 -357.487444)
			(xy 395.830625 -357.451732) (xy 395.876498 -357.422247) (xy 395.926099 -357.39959) (xy 395.97842 -357.384223)
			(xy 396.032395 -357.376457) (xy 396.05966 -357.375968) (xy 396.92326 -357.375968) (xy 396.950535 -357.376369)
			(xy 397.00453 -357.384127) (xy 397.056872 -357.399491) (xy 397.106494 -357.422148) (xy 397.152386 -357.451637)
			(xy 397.193615 -357.487357) (xy 397.229339 -357.528582) (xy 397.258833 -357.574471) (xy 397.281495 -357.62409)
			(xy 397.296865 -357.67643) (xy 397.304628 -357.730425) (xy 397.304628 -357.78497) (xy 398.787331 -357.78497)
			(xy 398.787331 -357.73043) (xy 398.795094 -357.676446) (xy 398.81046 -357.624116) (xy 398.833117 -357.574505)
			(xy 398.862604 -357.528624) (xy 398.898321 -357.487407) (xy 398.93954 -357.451692) (xy 398.985423 -357.422207)
			(xy 399.035034 -357.399553) (xy 399.087365 -357.384189) (xy 399.14135 -357.37643) (xy 399.16862 -357.375968)
			(xy 400.03222 -357.375968) (xy 400.059491 -357.376396) (xy 400.113476 -357.38416) (xy 400.165807 -357.399529)
			(xy 400.215419 -357.422188) (xy 400.261301 -357.451677) (xy 400.30252 -357.487395) (xy 400.338235 -357.528615)
			(xy 400.367722 -357.574499) (xy 400.390378 -357.624111) (xy 400.405744 -357.676443) (xy 400.413506 -357.730429)
			(xy 400.413506 -357.784966) (xy 401.896354 -357.784966) (xy 401.896354 -357.730434) (xy 401.904115 -357.676456)
			(xy 401.919478 -357.624132) (xy 401.942131 -357.574527) (xy 401.971613 -357.528651) (xy 402.007323 -357.487437)
			(xy 402.048535 -357.451725) (xy 402.09441 -357.422241) (xy 402.144013 -357.399585) (xy 402.196337 -357.384219)
			(xy 402.250314 -357.376456) (xy 402.27758 -357.375968) (xy 403.14118 -357.375968) (xy 403.168454 -357.37637)
			(xy 403.222447 -357.384131) (xy 403.274787 -357.399496) (xy 403.324406 -357.422155) (xy 403.370296 -357.451644)
			(xy 403.411522 -357.487364) (xy 403.447244 -357.528588) (xy 403.476736 -357.574476) (xy 403.499397 -357.624095)
			(xy 403.514765 -357.676433) (xy 403.522528 -357.730426) (xy 403.522528 -357.784965) (xy 412.022854 -357.784965)
			(xy 412.022854 -357.730435) (xy 412.030614 -357.67646) (xy 412.045976 -357.624138) (xy 412.068627 -357.574535)
			(xy 412.098106 -357.52866) (xy 412.133813 -357.487447) (xy 412.175022 -357.451735) (xy 412.220893 -357.42225)
			(xy 412.270493 -357.399593) (xy 412.322813 -357.384224) (xy 412.376787 -357.376458) (xy 412.404052 -357.375968)
			(xy 413.267652 -357.375968) (xy 413.294927 -357.376368) (xy 413.348924 -357.384125) (xy 413.401266 -357.399489)
			(xy 413.450889 -357.422145) (xy 413.496783 -357.451634) (xy 413.538012 -357.487354) (xy 413.573737 -357.528579)
			(xy 413.603232 -357.574468) (xy 413.625894 -357.624089) (xy 413.641264 -357.676429) (xy 413.649028 -357.730425)
			(xy 413.649028 -357.784969) (xy 415.131731 -357.784969) (xy 415.131731 -357.730431) (xy 415.139493 -357.676447)
			(xy 415.154859 -357.624117) (xy 415.177516 -357.574507) (xy 415.207002 -357.528627) (xy 415.242718 -357.487409)
			(xy 415.283936 -357.451695) (xy 415.329818 -357.42221) (xy 415.379429 -357.399555) (xy 415.431759 -357.384191)
			(xy 415.485743 -357.376431) (xy 415.513012 -357.375968) (xy 416.376612 -357.375968) (xy 416.403883 -357.376395)
			(xy 416.457869 -357.384159) (xy 416.510202 -357.399527) (xy 416.559814 -357.422185) (xy 416.605697 -357.451674)
			(xy 416.646917 -357.487392) (xy 416.682633 -357.528612) (xy 416.712121 -357.574496) (xy 416.734778 -357.62411)
			(xy 416.750144 -357.676442) (xy 416.757906 -357.730429) (xy 416.757906 -357.784966) (xy 418.240754 -357.784966)
			(xy 418.240754 -357.730434) (xy 418.248515 -357.676457) (xy 418.263877 -357.624134) (xy 418.28653 -357.57453)
			(xy 418.316011 -357.528654) (xy 418.35172 -357.48744) (xy 418.392931 -357.451727) (xy 418.438805 -357.422243)
			(xy 418.488408 -357.399587) (xy 418.54073 -357.384221) (xy 418.594706 -357.376456) (xy 418.621972 -357.375968)
			(xy 419.485572 -357.375968) (xy 419.512846 -357.37637) (xy 419.566841 -357.384129) (xy 419.619181 -357.399494)
			(xy 419.668801 -357.422152) (xy 419.714692 -357.451641) (xy 419.755919 -357.487361) (xy 419.791642 -357.528585)
			(xy 419.821135 -357.574474) (xy 419.843796 -357.624093) (xy 419.859165 -357.676432) (xy 419.866928 -357.730426)
			(xy 419.866928 -357.78497) (xy 421.349632 -357.78497) (xy 421.349632 -357.73043) (xy 421.357394 -357.676444)
			(xy 421.372761 -357.624113) (xy 421.395419 -357.574502) (xy 421.424907 -357.52862) (xy 421.460625 -357.487402)
			(xy 421.501846 -357.451688) (xy 421.54773 -357.422203) (xy 421.597343 -357.399549) (xy 421.649676 -357.384187)
			(xy 421.703662 -357.376429) (xy 421.730932 -357.375968) (xy 422.594532 -357.375968) (xy 422.621802 -357.376397)
			(xy 422.675786 -357.384163) (xy 422.728116 -357.399532) (xy 422.777726 -357.422192) (xy 422.823607 -357.451681)
			(xy 422.864824 -357.487399) (xy 422.900538 -357.528619) (xy 422.930024 -357.574502) (xy 422.952679 -357.624114)
			(xy 422.968044 -357.676445) (xy 422.975806 -357.73043) (xy 422.975806 -357.784967) (xy 424.458654 -357.784967)
			(xy 424.458654 -357.730433) (xy 424.466415 -357.676454) (xy 424.481779 -357.62413) (xy 424.504433 -357.574524)
			(xy 424.533916 -357.528647) (xy 424.569627 -357.487433) (xy 424.610841 -357.45172) (xy 424.656717 -357.422237)
			(xy 424.706322 -357.399582) (xy 424.758647 -357.384217) (xy 424.812625 -357.376455) (xy 424.839892 -357.375968)
			(xy 425.703492 -357.375968) (xy 425.730766 -357.376371) (xy 425.784757 -357.384133) (xy 425.837095 -357.3995)
			(xy 425.886713 -357.422159) (xy 425.932602 -357.451648) (xy 425.973826 -357.487368) (xy 426.009547 -357.528592)
			(xy 426.039038 -357.57448) (xy 426.061698 -357.624097) (xy 426.077065 -357.676435) (xy 426.084828 -357.730426)
			(xy 426.084828 -357.784965) (xy 427.567654 -357.784965) (xy 427.567654 -357.730435) (xy 427.575414 -357.67646)
			(xy 427.590776 -357.624138) (xy 427.613427 -357.574535) (xy 427.642906 -357.52866) (xy 427.678613 -357.487447)
			(xy 427.719822 -357.451735) (xy 427.765693 -357.42225) (xy 427.815293 -357.399593) (xy 427.867613 -357.384224)
			(xy 427.921587 -357.376458) (xy 427.948852 -357.375968) (xy 428.812452 -357.375968) (xy 428.839727 -357.376368)
			(xy 428.893724 -357.384125) (xy 428.946066 -357.399489) (xy 428.995689 -357.422145) (xy 429.041583 -357.451634)
			(xy 429.082812 -357.487354) (xy 429.118537 -357.528579) (xy 429.148032 -357.574468) (xy 429.170694 -357.624089)
			(xy 429.186064 -357.676429) (xy 429.193828 -357.730425) (xy 429.193828 -357.784969) (xy 430.676531 -357.784969)
			(xy 430.676531 -357.730431) (xy 430.684293 -357.676447) (xy 430.699659 -357.624117) (xy 430.722316 -357.574507)
			(xy 430.751802 -357.528627) (xy 430.787518 -357.487409) (xy 430.828736 -357.451695) (xy 430.874618 -357.42221)
			(xy 430.924229 -357.399555) (xy 430.976559 -357.384191) (xy 431.030543 -357.376431) (xy 431.057812 -357.375968)
			(xy 431.921412 -357.375968) (xy 431.948683 -357.376395) (xy 432.002669 -357.384159) (xy 432.055002 -357.399527)
			(xy 432.104614 -357.422185) (xy 432.150497 -357.451674) (xy 432.191717 -357.487392) (xy 432.227433 -357.528612)
			(xy 432.256921 -357.574496) (xy 432.279578 -357.62411) (xy 432.294944 -357.676442) (xy 432.302706 -357.730429)
			(xy 432.302706 -357.784966) (xy 433.785554 -357.784966) (xy 433.785554 -357.730434) (xy 433.793315 -357.676457)
			(xy 433.808677 -357.624134) (xy 433.83133 -357.57453) (xy 433.860811 -357.528654) (xy 433.89652 -357.48744)
			(xy 433.937731 -357.451727) (xy 433.983605 -357.422243) (xy 434.033208 -357.399587) (xy 434.08553 -357.384221)
			(xy 434.139506 -357.376456) (xy 434.166772 -357.375968) (xy 435.030372 -357.375968) (xy 435.057646 -357.37637)
			(xy 435.111641 -357.384129) (xy 435.163981 -357.399494) (xy 435.213601 -357.422152) (xy 435.259492 -357.451641)
			(xy 435.300719 -357.487361) (xy 435.336442 -357.528585) (xy 435.365935 -357.574474) (xy 435.388596 -357.624093)
			(xy 435.403965 -357.676432) (xy 435.411728 -357.730426) (xy 435.411728 -357.78497) (xy 436.894432 -357.78497)
			(xy 436.894432 -357.73043) (xy 436.902194 -357.676444) (xy 436.917561 -357.624113) (xy 436.940219 -357.574502)
			(xy 436.969707 -357.52862) (xy 437.005425 -357.487402) (xy 437.046646 -357.451688) (xy 437.09253 -357.422203)
			(xy 437.142143 -357.399549) (xy 437.194476 -357.384187) (xy 437.248462 -357.376429) (xy 437.275732 -357.375968)
			(xy 438.139332 -357.375968) (xy 438.166602 -357.376397) (xy 438.220586 -357.384163) (xy 438.272916 -357.399532)
			(xy 438.322526 -357.422192) (xy 438.368407 -357.451681) (xy 438.409624 -357.487399) (xy 438.445338 -357.528619)
			(xy 438.474824 -357.574502) (xy 438.497479 -357.624114) (xy 438.512844 -357.676445) (xy 438.520606 -357.73043)
			(xy 438.520606 -357.784967) (xy 440.003454 -357.784967) (xy 440.003454 -357.730433) (xy 440.011215 -357.676454)
			(xy 440.026579 -357.62413) (xy 440.049233 -357.574524) (xy 440.078716 -357.528647) (xy 440.114427 -357.487433)
			(xy 440.155641 -357.45172) (xy 440.201517 -357.422237) (xy 440.251122 -357.399582) (xy 440.303447 -357.384217)
			(xy 440.357425 -357.376455) (xy 440.384692 -357.375968) (xy 441.248292 -357.375968) (xy 441.275566 -357.376371)
			(xy 441.329557 -357.384133) (xy 441.381895 -357.3995) (xy 441.431513 -357.422159) (xy 441.477402 -357.451648)
			(xy 441.518626 -357.487368) (xy 441.554347 -357.528592) (xy 441.583838 -357.57448) (xy 441.606498 -357.624097)
			(xy 441.621865 -357.676435) (xy 441.629628 -357.730426) (xy 441.629628 -357.784974) (xy 441.621865 -357.838965)
			(xy 441.606498 -357.891303) (xy 441.583838 -357.94092) (xy 441.554347 -357.986808) (xy 441.518626 -358.028032)
			(xy 441.477402 -358.063752) (xy 441.431513 -358.093241) (xy 441.381895 -358.1159) (xy 441.329557 -358.131267)
			(xy 441.275566 -358.139029) (xy 441.248292 -358.139492) (xy 440.384692 -358.139492) (xy 440.357425 -358.138945)
			(xy 440.303447 -358.131183) (xy 440.251122 -358.115818) (xy 440.201517 -358.093163) (xy 440.155641 -358.06368)
			(xy 440.114427 -358.027967) (xy 440.078716 -357.986753) (xy 440.049233 -357.940876) (xy 440.026579 -357.89127)
			(xy 440.011215 -357.838946) (xy 440.003454 -357.784967) (xy 438.520606 -357.784967) (xy 438.520606 -357.78497)
			(xy 438.512844 -357.838955) (xy 438.497479 -357.891286) (xy 438.474824 -357.940898) (xy 438.445338 -357.986781)
			(xy 438.409624 -358.028001) (xy 438.368407 -358.063719) (xy 438.322526 -358.093208) (xy 438.272916 -358.115868)
			(xy 438.220586 -358.131237) (xy 438.166602 -358.139003) (xy 438.139332 -358.139492) (xy 437.275732 -358.139492)
			(xy 437.248462 -358.138971) (xy 437.194476 -358.131213) (xy 437.142143 -358.115851) (xy 437.09253 -358.093197)
			(xy 437.046646 -358.063712) (xy 437.005425 -358.027998) (xy 436.969707 -357.98678) (xy 436.940219 -357.940898)
			(xy 436.917561 -357.891287) (xy 436.902194 -357.838956) (xy 436.894432 -357.78497) (xy 435.411728 -357.78497)
			(xy 435.411728 -357.784974) (xy 435.403965 -357.838968) (xy 435.388596 -357.891307) (xy 435.365935 -357.940926)
			(xy 435.336442 -357.986815) (xy 435.300719 -358.028039) (xy 435.259492 -358.063759) (xy 435.213601 -358.093248)
			(xy 435.163981 -358.115906) (xy 435.111641 -358.131271) (xy 435.057646 -358.13903) (xy 435.030372 -358.139492)
			(xy 434.166772 -358.139492) (xy 434.139506 -358.138944) (xy 434.08553 -358.131179) (xy 434.033208 -358.115813)
			(xy 433.983605 -358.093157) (xy 433.937731 -358.063673) (xy 433.89652 -358.02796) (xy 433.860811 -357.986746)
			(xy 433.83133 -357.94087) (xy 433.808677 -357.891266) (xy 433.793315 -357.838943) (xy 433.785554 -357.784966)
			(xy 432.302706 -357.784966) (xy 432.302706 -357.784971) (xy 432.294944 -357.838958) (xy 432.279578 -357.89129)
			(xy 432.256921 -357.940904) (xy 432.227433 -357.986788) (xy 432.191717 -358.028008) (xy 432.150497 -358.063726)
			(xy 432.104614 -358.093215) (xy 432.055002 -358.115873) (xy 432.002669 -358.131241) (xy 431.948683 -358.139005)
			(xy 431.921412 -358.139492) (xy 431.057812 -358.139492) (xy 431.030543 -358.138969) (xy 430.976559 -358.131209)
			(xy 430.924229 -358.115845) (xy 430.874618 -358.09319) (xy 430.828736 -358.063705) (xy 430.787518 -358.027991)
			(xy 430.751802 -357.986773) (xy 430.722316 -357.940893) (xy 430.699659 -357.891283) (xy 430.684293 -357.838953)
			(xy 430.676531 -357.784969) (xy 429.193828 -357.784969) (xy 429.193828 -357.784975) (xy 429.186064 -357.838971)
			(xy 429.170694 -357.891311) (xy 429.148032 -357.940932) (xy 429.118537 -357.986821) (xy 429.082812 -358.028046)
			(xy 429.041583 -358.063766) (xy 428.995689 -358.093255) (xy 428.946066 -358.115911) (xy 428.893724 -358.131275)
			(xy 428.839727 -358.139032) (xy 428.812452 -358.139492) (xy 427.948852 -358.139492) (xy 427.921587 -358.138942)
			(xy 427.867613 -358.131176) (xy 427.815293 -358.115807) (xy 427.765693 -358.09315) (xy 427.719822 -358.063665)
			(xy 427.678613 -358.027953) (xy 427.642906 -357.98674) (xy 427.613427 -357.940865) (xy 427.590776 -357.891262)
			(xy 427.575414 -357.83894) (xy 427.567654 -357.784965) (xy 426.084828 -357.784965) (xy 426.084828 -357.784974)
			(xy 426.077065 -357.838965) (xy 426.061698 -357.891303) (xy 426.039038 -357.94092) (xy 426.009547 -357.986808)
			(xy 425.973826 -358.028032) (xy 425.932602 -358.063752) (xy 425.886713 -358.093241) (xy 425.837095 -358.1159)
			(xy 425.784757 -358.131267) (xy 425.730766 -358.139029) (xy 425.703492 -358.139492) (xy 424.839892 -358.139492)
			(xy 424.812625 -358.138945) (xy 424.758647 -358.131183) (xy 424.706322 -358.115818) (xy 424.656717 -358.093163)
			(xy 424.610841 -358.06368) (xy 424.569627 -358.027967) (xy 424.533916 -357.986753) (xy 424.504433 -357.940876)
			(xy 424.481779 -357.89127) (xy 424.466415 -357.838946) (xy 424.458654 -357.784967) (xy 422.975806 -357.784967)
			(xy 422.975806 -357.78497) (xy 422.968044 -357.838955) (xy 422.952679 -357.891286) (xy 422.930024 -357.940898)
			(xy 422.900538 -357.986781) (xy 422.864824 -358.028001) (xy 422.823607 -358.063719) (xy 422.777726 -358.093208)
			(xy 422.728116 -358.115868) (xy 422.675786 -358.131237) (xy 422.621802 -358.139003) (xy 422.594532 -358.139492)
			(xy 421.730932 -358.139492) (xy 421.703662 -358.138971) (xy 421.649676 -358.131213) (xy 421.597343 -358.115851)
			(xy 421.54773 -358.093197) (xy 421.501846 -358.063712) (xy 421.460625 -358.027998) (xy 421.424907 -357.98678)
			(xy 421.395419 -357.940898) (xy 421.372761 -357.891287) (xy 421.357394 -357.838956) (xy 421.349632 -357.78497)
			(xy 419.866928 -357.78497) (xy 419.866928 -357.784974) (xy 419.859165 -357.838968) (xy 419.843796 -357.891307)
			(xy 419.821135 -357.940926) (xy 419.791642 -357.986815) (xy 419.755919 -358.028039) (xy 419.714692 -358.063759)
			(xy 419.668801 -358.093248) (xy 419.619181 -358.115906) (xy 419.566841 -358.131271) (xy 419.512846 -358.13903)
			(xy 419.485572 -358.139492) (xy 418.621972 -358.139492) (xy 418.594706 -358.138944) (xy 418.54073 -358.131179)
			(xy 418.488408 -358.115813) (xy 418.438805 -358.093157) (xy 418.392931 -358.063673) (xy 418.35172 -358.02796)
			(xy 418.316011 -357.986746) (xy 418.28653 -357.94087) (xy 418.263877 -357.891266) (xy 418.248515 -357.838943)
			(xy 418.240754 -357.784966) (xy 416.757906 -357.784966) (xy 416.757906 -357.784971) (xy 416.750144 -357.838958)
			(xy 416.734778 -357.89129) (xy 416.712121 -357.940904) (xy 416.682633 -357.986788) (xy 416.646917 -358.028008)
			(xy 416.605697 -358.063726) (xy 416.559814 -358.093215) (xy 416.510202 -358.115873) (xy 416.457869 -358.131241)
			(xy 416.403883 -358.139005) (xy 416.376612 -358.139492) (xy 415.513012 -358.139492) (xy 415.485743 -358.138969)
			(xy 415.431759 -358.131209) (xy 415.379429 -358.115845) (xy 415.329818 -358.09319) (xy 415.283936 -358.063705)
			(xy 415.242718 -358.027991) (xy 415.207002 -357.986773) (xy 415.177516 -357.940893) (xy 415.154859 -357.891283)
			(xy 415.139493 -357.838953) (xy 415.131731 -357.784969) (xy 413.649028 -357.784969) (xy 413.649028 -357.784975)
			(xy 413.641264 -357.838971) (xy 413.625894 -357.891311) (xy 413.603232 -357.940932) (xy 413.573737 -357.986821)
			(xy 413.538012 -358.028046) (xy 413.496783 -358.063766) (xy 413.450889 -358.093255) (xy 413.401266 -358.115911)
			(xy 413.348924 -358.131275) (xy 413.294927 -358.139032) (xy 413.267652 -358.139492) (xy 412.404052 -358.139492)
			(xy 412.376787 -358.138942) (xy 412.322813 -358.131176) (xy 412.270493 -358.115807) (xy 412.220893 -358.09315)
			(xy 412.175022 -358.063665) (xy 412.133813 -358.027953) (xy 412.098106 -357.98674) (xy 412.068627 -357.940865)
			(xy 412.045976 -357.891262) (xy 412.030614 -357.83894) (xy 412.022854 -357.784965) (xy 403.522528 -357.784965)
			(xy 403.522528 -357.784974) (xy 403.514765 -357.838967) (xy 403.499397 -357.891305) (xy 403.476736 -357.940924)
			(xy 403.447244 -357.986812) (xy 403.411522 -358.028036) (xy 403.370296 -358.063756) (xy 403.324406 -358.093245)
			(xy 403.274787 -358.115904) (xy 403.222447 -358.131269) (xy 403.168454 -358.13903) (xy 403.14118 -358.139492)
			(xy 402.27758 -358.139492) (xy 402.250314 -358.138944) (xy 402.196337 -358.131181) (xy 402.144013 -358.115815)
			(xy 402.09441 -358.093159) (xy 402.048535 -358.063675) (xy 402.007323 -358.027963) (xy 401.971613 -357.986749)
			(xy 401.942131 -357.940873) (xy 401.919478 -357.891268) (xy 401.904115 -357.838944) (xy 401.896354 -357.784966)
			(xy 400.413506 -357.784966) (xy 400.413506 -357.784971) (xy 400.405744 -357.838957) (xy 400.390378 -357.891289)
			(xy 400.367722 -357.940901) (xy 400.338235 -357.986785) (xy 400.30252 -358.028005) (xy 400.261301 -358.063723)
			(xy 400.215419 -358.093212) (xy 400.165807 -358.115871) (xy 400.113476 -358.13124) (xy 400.059491 -358.139004)
			(xy 400.03222 -358.139492) (xy 399.16862 -358.139492) (xy 399.14135 -358.13897) (xy 399.087365 -358.131211)
			(xy 399.035034 -358.115847) (xy 398.985423 -358.093193) (xy 398.93954 -358.063708) (xy 398.898321 -358.027993)
			(xy 398.862604 -357.986776) (xy 398.833117 -357.940895) (xy 398.81046 -357.891284) (xy 398.795094 -357.838954)
			(xy 398.787331 -357.78497) (xy 397.304628 -357.78497) (xy 397.304628 -357.784975) (xy 397.296865 -357.83897)
			(xy 397.281495 -357.89131) (xy 397.258833 -357.940929) (xy 397.229339 -357.986818) (xy 397.193615 -358.028043)
			(xy 397.152386 -358.063763) (xy 397.106494 -358.093252) (xy 397.056872 -358.115909) (xy 397.00453 -358.131273)
			(xy 396.950535 -358.139031) (xy 396.92326 -358.139492) (xy 396.05966 -358.139492) (xy 396.032395 -358.138943)
			(xy 395.97842 -358.131177) (xy 395.926099 -358.11581) (xy 395.876498 -358.093153) (xy 395.830625 -358.063668)
			(xy 395.789416 -358.027956) (xy 395.753708 -357.986742) (xy 395.724228 -357.940867) (xy 395.701576 -357.891263)
			(xy 395.686214 -357.838941) (xy 395.678454 -357.784965) (xy 394.195605 -357.784965) (xy 394.195605 -357.784972)
			(xy 394.187843 -357.838959) (xy 394.172477 -357.891293) (xy 394.149819 -357.940907) (xy 394.120331 -357.986792)
			(xy 394.084612 -358.028012) (xy 394.043392 -358.063731) (xy 393.997507 -358.093219) (xy 393.947893 -358.115877)
			(xy 393.895559 -358.131243) (xy 393.841572 -358.139005) (xy 393.8143 -358.139492) (xy 392.9507 -358.139492)
			(xy 392.923433 -358.138946) (xy 392.869453 -358.131185) (xy 392.817128 -358.11582) (xy 392.767522 -358.093166)
			(xy 392.721644 -358.063682) (xy 392.68043 -358.02797) (xy 392.644718 -357.986756) (xy 392.615234 -357.940878)
			(xy 392.59258 -357.891272) (xy 392.577215 -357.838947) (xy 392.569454 -357.784967) (xy 391.086606 -357.784967)
			(xy 391.086606 -357.78497) (xy 391.078844 -357.838954) (xy 391.06348 -357.891284) (xy 391.040825 -357.940896)
			(xy 391.01134 -357.986778) (xy 390.975627 -358.027998) (xy 390.934411 -358.063716) (xy 390.888531 -358.093206)
			(xy 390.838922 -358.115866) (xy 390.786593 -358.131236) (xy 390.73261 -358.139003) (xy 390.70534 -358.139492)
			(xy 389.84174 -358.139492) (xy 389.814469 -358.138971) (xy 389.760482 -358.131214) (xy 389.708149 -358.115853)
			(xy 389.658535 -358.093199) (xy 389.61265 -358.063715) (xy 389.571428 -358.028) (xy 389.535709 -357.986783)
			(xy 389.50622 -357.940901) (xy 389.483561 -357.891289) (xy 389.468194 -357.838957) (xy 389.460432 -357.784971)
			(xy 387.977728 -357.784971) (xy 387.977728 -357.784974) (xy 387.969965 -357.838967) (xy 387.954597 -357.891305)
			(xy 387.931936 -357.940924) (xy 387.902444 -357.986812) (xy 387.866722 -358.028036) (xy 387.825496 -358.063756)
			(xy 387.779606 -358.093245) (xy 387.729987 -358.115904) (xy 387.677647 -358.131269) (xy 387.623654 -358.13903)
			(xy 387.59638 -358.139492) (xy 386.73278 -358.139492) (xy 386.705514 -358.138944) (xy 386.651537 -358.131181)
			(xy 386.599213 -358.115815) (xy 386.54961 -358.093159) (xy 386.503735 -358.063675) (xy 386.462523 -358.027963)
			(xy 386.426813 -357.986749) (xy 386.397331 -357.940873) (xy 386.374678 -357.891268) (xy 386.359315 -357.838944)
			(xy 386.351554 -357.784966) (xy 384.868706 -357.784966) (xy 384.868706 -357.784971) (xy 384.860944 -357.838957)
			(xy 384.845578 -357.891289) (xy 384.822922 -357.940901) (xy 384.793435 -357.986785) (xy 384.75772 -358.028005)
			(xy 384.716501 -358.063723) (xy 384.670619 -358.093212) (xy 384.621007 -358.115871) (xy 384.568676 -358.13124)
			(xy 384.514691 -358.139004) (xy 384.48742 -358.139492) (xy 383.62382 -358.139492) (xy 383.59655 -358.13897)
			(xy 383.542565 -358.131211) (xy 383.490234 -358.115847) (xy 383.440623 -358.093193) (xy 383.39474 -358.063708)
			(xy 383.353521 -358.027993) (xy 383.317804 -357.986776) (xy 383.288317 -357.940895) (xy 383.26566 -357.891284)
			(xy 383.250294 -357.838954) (xy 383.242531 -357.78497) (xy 381.759828 -357.78497) (xy 381.759828 -357.784975)
			(xy 381.752065 -357.83897) (xy 381.736695 -357.89131) (xy 381.714033 -357.940929) (xy 381.684539 -357.986818)
			(xy 381.648815 -358.028043) (xy 381.607586 -358.063763) (xy 381.561694 -358.093252) (xy 381.512072 -358.115909)
			(xy 381.45973 -358.131273) (xy 381.405735 -358.139031) (xy 381.37846 -358.139492) (xy 380.51486 -358.139492)
			(xy 380.487595 -358.138943) (xy 380.43362 -358.131177) (xy 380.381299 -358.11581) (xy 380.331698 -358.093153)
			(xy 380.285825 -358.063668) (xy 380.244616 -358.027956) (xy 380.208908 -357.986742) (xy 380.179428 -357.940867)
			(xy 380.156776 -357.891263) (xy 380.141414 -357.838941) (xy 380.133654 -357.784965) (xy 378.650805 -357.784965)
			(xy 378.650805 -357.784972) (xy 378.643043 -357.838959) (xy 378.627677 -357.891293) (xy 378.605019 -357.940907)
			(xy 378.575531 -357.986792) (xy 378.539812 -358.028012) (xy 378.498592 -358.063731) (xy 378.452707 -358.093219)
			(xy 378.403093 -358.115877) (xy 378.350759 -358.131243) (xy 378.296772 -358.139005) (xy 378.2695 -358.139492)
			(xy 377.4059 -358.139492) (xy 377.378633 -358.138946) (xy 377.324653 -358.131185) (xy 377.272328 -358.11582)
			(xy 377.222722 -358.093166) (xy 377.176844 -358.063682) (xy 377.13563 -358.02797) (xy 377.099918 -357.986756)
			(xy 377.070434 -357.940878) (xy 377.04778 -357.891272) (xy 377.032415 -357.838947) (xy 377.024654 -357.784967)
			(xy 375.541806 -357.784967) (xy 375.541806 -357.78497) (xy 375.534044 -357.838954) (xy 375.51868 -357.891284)
			(xy 375.496025 -357.940896) (xy 375.46654 -357.986778) (xy 375.430827 -358.027998) (xy 375.389611 -358.063716)
			(xy 375.343731 -358.093206) (xy 375.294122 -358.115866) (xy 375.241793 -358.131236) (xy 375.18781 -358.139003)
			(xy 375.16054 -358.139492) (xy 374.29694 -358.139492) (xy 374.269669 -358.138971) (xy 374.215682 -358.131214)
			(xy 374.163349 -358.115853) (xy 374.113735 -358.093199) (xy 374.06785 -358.063715) (xy 374.026628 -358.028)
			(xy 373.990909 -357.986783) (xy 373.96142 -357.940901) (xy 373.938761 -357.891289) (xy 373.923394 -357.838957)
			(xy 373.915632 -357.784971) (xy 344.837306 -357.784971) (xy 344.829543 -357.838959) (xy 344.814177 -357.891292)
			(xy 344.791519 -357.940906) (xy 344.762031 -357.98679) (xy 344.726314 -358.028011) (xy 344.685093 -358.063729)
			(xy 344.639209 -358.093217) (xy 344.589596 -358.115876) (xy 344.537263 -358.131242) (xy 344.483275 -358.139005)
			(xy 344.456004 -358.139492) (xy 343.592404 -358.139492) (xy 343.565135 -358.138969) (xy 343.511152 -358.131208)
			(xy 343.458823 -358.115843) (xy 343.409213 -358.093188) (xy 343.363333 -358.063702) (xy 343.322115 -358.027988)
			(xy 343.2864 -357.986771) (xy 343.256914 -357.94089) (xy 343.234258 -357.891281) (xy 343.218893 -357.838952)
			(xy 343.211131 -357.784969) (xy 341.728306 -357.784969) (xy 341.728306 -357.78497) (xy 341.720544 -357.838953)
			(xy 341.70518 -357.891284) (xy 341.682525 -357.940895) (xy 341.653041 -357.986777) (xy 341.617328 -358.027997)
			(xy 341.576112 -358.063715) (xy 341.530233 -358.093204) (xy 341.480625 -358.115865) (xy 341.428297 -358.131235)
			(xy 341.374313 -358.139002) (xy 341.347044 -358.139492) (xy 340.483444 -358.139492) (xy 340.456173 -358.138972)
			(xy 340.402186 -358.131215) (xy 340.349852 -358.115854) (xy 340.300237 -358.093201) (xy 340.254351 -358.063716)
			(xy 340.213129 -358.028002) (xy 340.17741 -357.986784) (xy 340.147921 -357.940902) (xy 340.125261 -357.891289)
			(xy 340.109894 -357.838957) (xy 340.102132 -357.784971) (xy 338.619428 -357.784971) (xy 338.619428 -357.784974)
			(xy 338.611665 -357.838966) (xy 338.596297 -357.891304) (xy 338.573636 -357.940923) (xy 338.544145 -357.986811)
			(xy 338.508423 -358.028034) (xy 338.467198 -358.063755) (xy 338.421308 -358.093244) (xy 338.371689 -358.115903)
			(xy 338.319351 -358.131269) (xy 338.265358 -358.13903) (xy 338.238084 -358.139492) (xy 337.374484 -358.139492)
			(xy 337.347218 -358.138945) (xy 337.29324 -358.131182) (xy 337.240916 -358.115816) (xy 337.191312 -358.093161)
			(xy 337.145437 -358.063677) (xy 337.104224 -358.027964) (xy 337.068514 -357.98675) (xy 337.039032 -357.940874)
			(xy 337.016378 -357.891269) (xy 337.001015 -357.838944) (xy 336.993254 -357.784967) (xy 335.510406 -357.784967)
			(xy 335.510406 -357.78497) (xy 335.502644 -357.838956) (xy 335.487279 -357.891288) (xy 335.464622 -357.9409)
			(xy 335.435136 -357.986784) (xy 335.399421 -358.028004) (xy 335.358203 -358.063722) (xy 335.312321 -358.093211)
			(xy 335.26271 -358.11587) (xy 335.21038 -358.131239) (xy 335.156394 -358.139004) (xy 335.129124 -358.139492)
			(xy 334.265524 -358.139492) (xy 334.238254 -358.13897) (xy 334.184269 -358.131211) (xy 334.131937 -358.115848)
			(xy 334.082325 -358.093194) (xy 334.036442 -358.063709) (xy 333.995222 -358.027995) (xy 333.959505 -357.986777)
			(xy 333.930017 -357.940896) (xy 333.90736 -357.891285) (xy 333.891994 -357.838955) (xy 333.884231 -357.78497)
			(xy 332.401528 -357.78497) (xy 332.401528 -357.784975) (xy 332.393765 -357.838969) (xy 332.378395 -357.891309)
			(xy 332.355733 -357.940928) (xy 332.32624 -357.986817) (xy 332.290516 -358.028041) (xy 332.249288 -358.063762)
			(xy 332.203397 -358.093251) (xy 332.153775 -358.115908) (xy 332.101434 -358.131272) (xy 332.047439 -358.139031)
			(xy 332.020164 -358.139492) (xy 331.156564 -358.139492) (xy 331.129298 -358.138943) (xy 331.075323 -358.131178)
			(xy 331.023002 -358.115811) (xy 330.9734 -358.093154) (xy 330.927527 -358.06367) (xy 330.886317 -358.027957)
			(xy 330.850609 -357.986744) (xy 330.821128 -357.940868) (xy 330.798477 -357.891264) (xy 330.783114 -357.838942)
			(xy 330.775354 -357.784966) (xy 329.292506 -357.784966) (xy 329.292506 -357.784971) (xy 329.284743 -357.838959)
			(xy 329.269377 -357.891292) (xy 329.246719 -357.940906) (xy 329.217231 -357.98679) (xy 329.181514 -358.028011)
			(xy 329.140293 -358.063729) (xy 329.094409 -358.093217) (xy 329.044796 -358.115876) (xy 328.992463 -358.131242)
			(xy 328.938475 -358.139005) (xy 328.911204 -358.139492) (xy 328.047604 -358.139492) (xy 328.020335 -358.138969)
			(xy 327.966352 -358.131208) (xy 327.914023 -358.115843) (xy 327.864413 -358.093188) (xy 327.818533 -358.063702)
			(xy 327.777315 -358.027988) (xy 327.7416 -357.986771) (xy 327.712114 -357.94089) (xy 327.689458 -357.891281)
			(xy 327.674093 -357.838952) (xy 327.666331 -357.784969) (xy 326.183506 -357.784969) (xy 326.183506 -357.78497)
			(xy 326.175744 -357.838953) (xy 326.16038 -357.891284) (xy 326.137725 -357.940895) (xy 326.108241 -357.986777)
			(xy 326.072528 -358.027997) (xy 326.031312 -358.063715) (xy 325.985433 -358.093204) (xy 325.935825 -358.115865)
			(xy 325.883497 -358.131235) (xy 325.829513 -358.139002) (xy 325.802244 -358.139492) (xy 324.938644 -358.139492)
			(xy 324.911373 -358.138972) (xy 324.857386 -358.131215) (xy 324.805052 -358.115854) (xy 324.755437 -358.093201)
			(xy 324.709551 -358.063716) (xy 324.668329 -358.028002) (xy 324.63261 -357.986784) (xy 324.603121 -357.940902)
			(xy 324.580461 -357.891289) (xy 324.565094 -357.838957) (xy 324.557332 -357.784971) (xy 323.074628 -357.784971)
			(xy 323.074628 -357.784974) (xy 323.066865 -357.838966) (xy 323.051497 -357.891304) (xy 323.028836 -357.940923)
			(xy 322.999345 -357.986811) (xy 322.963623 -358.028034) (xy 322.922398 -358.063755) (xy 322.876508 -358.093244)
			(xy 322.826889 -358.115903) (xy 322.774551 -358.131269) (xy 322.720558 -358.13903) (xy 322.693284 -358.139492)
			(xy 321.829684 -358.139492) (xy 321.802418 -358.138945) (xy 321.74844 -358.131182) (xy 321.696116 -358.115816)
			(xy 321.646512 -358.093161) (xy 321.600637 -358.063677) (xy 321.559424 -358.027964) (xy 321.523714 -357.98675)
			(xy 321.494232 -357.940874) (xy 321.471578 -357.891269) (xy 321.456215 -357.838944) (xy 321.448454 -357.784967)
			(xy 319.965606 -357.784967) (xy 319.965606 -357.78497) (xy 319.957844 -357.838956) (xy 319.942479 -357.891288)
			(xy 319.919822 -357.9409) (xy 319.890336 -357.986784) (xy 319.854621 -358.028004) (xy 319.813403 -358.063722)
			(xy 319.767521 -358.093211) (xy 319.71791 -358.11587) (xy 319.66558 -358.131239) (xy 319.611594 -358.139004)
			(xy 319.584324 -358.139492) (xy 318.720724 -358.139492) (xy 318.693454 -358.13897) (xy 318.639469 -358.131211)
			(xy 318.587137 -358.115848) (xy 318.537525 -358.093194) (xy 318.491642 -358.063709) (xy 318.450422 -358.027995)
			(xy 318.414705 -357.986777) (xy 318.385217 -357.940896) (xy 318.36256 -357.891285) (xy 318.347194 -357.838955)
			(xy 318.339431 -357.78497) (xy 316.856728 -357.78497) (xy 316.856728 -357.784975) (xy 316.848965 -357.838969)
			(xy 316.833595 -357.891309) (xy 316.810933 -357.940928) (xy 316.78144 -357.986817) (xy 316.745716 -358.028041)
			(xy 316.704488 -358.063762) (xy 316.658597 -358.093251) (xy 316.608975 -358.115908) (xy 316.556634 -358.131272)
			(xy 316.502639 -358.139031) (xy 316.475364 -358.139492) (xy 315.611764 -358.139492) (xy 315.584498 -358.138943)
			(xy 315.530523 -358.131178) (xy 315.478202 -358.115811) (xy 315.4286 -358.093154) (xy 315.382727 -358.06367)
			(xy 315.341517 -358.027957) (xy 315.305809 -357.986744) (xy 315.276328 -357.940868) (xy 315.253677 -357.891264)
			(xy 315.238314 -357.838942) (xy 315.230554 -357.784966) (xy 300.231606 -357.784966) (xy 300.231606 -357.784971)
			(xy 300.223843 -357.838959) (xy 300.208477 -357.891293) (xy 300.185819 -357.940907) (xy 300.156331 -357.986791)
			(xy 300.120613 -358.028012) (xy 300.079393 -358.06373) (xy 300.033508 -358.093218) (xy 299.983894 -358.115876)
			(xy 299.931561 -358.131243) (xy 299.877573 -358.139005) (xy 299.850302 -358.139492) (xy 298.986702 -358.139492)
			(xy 298.959433 -358.138969) (xy 298.90545 -358.131207) (xy 298.853121 -358.115843) (xy 298.803512 -358.093187)
			(xy 298.757632 -358.063702) (xy 298.716414 -358.027987) (xy 298.6807 -357.98677) (xy 298.651214 -357.94089)
			(xy 298.628558 -357.89128) (xy 298.613193 -357.838952) (xy 298.605431 -357.784969) (xy 297.122606 -357.784969)
			(xy 297.122606 -357.78497) (xy 297.114844 -357.838954) (xy 297.09948 -357.891284) (xy 297.076825 -357.940895)
			(xy 297.047341 -357.986778) (xy 297.011627 -358.027998) (xy 296.970411 -358.063716) (xy 296.924532 -358.093205)
			(xy 296.874923 -358.115865) (xy 296.822595 -358.131235) (xy 296.768612 -358.139003) (xy 296.741342 -358.139492)
			(xy 295.877742 -358.139492) (xy 295.850471 -358.138971) (xy 295.796484 -358.131215) (xy 295.74415 -358.115853)
			(xy 295.694536 -358.0932) (xy 295.64865 -358.063716) (xy 295.607429 -358.028001) (xy 295.571709 -357.986783)
			(xy 295.54222 -357.940901) (xy 295.519561 -357.891289) (xy 295.504194 -357.838957) (xy 295.496432 -357.784971)
			(xy 294.013728 -357.784971) (xy 294.013728 -357.784974) (xy 294.005965 -357.838967) (xy 293.990597 -357.891305)
			(xy 293.967936 -357.940923) (xy 293.938444 -357.986811) (xy 293.902722 -358.028035) (xy 293.861497 -358.063755)
			(xy 293.815607 -358.093245) (xy 293.765988 -358.115903) (xy 293.713649 -358.131269) (xy 293.659656 -358.13903)
			(xy 293.632382 -358.139492) (xy 292.768782 -358.139492) (xy 292.741516 -358.138944) (xy 292.687538 -358.131181)
			(xy 292.635215 -358.115816) (xy 292.585611 -358.09316) (xy 292.539736 -358.063676) (xy 292.498524 -358.027964)
			(xy 292.462813 -357.98675) (xy 292.433331 -357.940873) (xy 292.410678 -357.891268) (xy 292.395315 -357.838944)
			(xy 292.387554 -357.784966) (xy 290.904706 -357.784966) (xy 290.904706 -357.784971) (xy 290.896944 -357.838956)
			(xy 290.881578 -357.891288) (xy 290.858922 -357.940901) (xy 290.829436 -357.986784) (xy 290.79372 -358.028005)
			(xy 290.752502 -358.063723) (xy 290.70662 -358.093211) (xy 290.657009 -358.115871) (xy 290.604678 -358.131239)
			(xy 290.550692 -358.139004) (xy 290.523422 -358.139492) (xy 289.659822 -358.139492) (xy 289.632552 -358.13897)
			(xy 289.578567 -358.131211) (xy 289.526236 -358.115848) (xy 289.476624 -358.093193) (xy 289.430741 -358.063709)
			(xy 289.389522 -358.027994) (xy 289.353805 -357.986777) (xy 289.324317 -357.940895) (xy 289.30166 -357.891285)
			(xy 289.286294 -357.838954) (xy 289.278531 -357.78497) (xy 287.795828 -357.78497) (xy 287.795828 -357.784975)
			(xy 287.788065 -357.838969) (xy 287.772695 -357.891309) (xy 287.750033 -357.940929) (xy 287.72054 -357.986818)
			(xy 287.684815 -358.028042) (xy 287.643587 -358.063762) (xy 287.597695 -358.093251) (xy 287.548073 -358.115908)
			(xy 287.495732 -358.131273) (xy 287.441737 -358.139031) (xy 287.414462 -358.139492) (xy 286.550862 -358.139492)
			(xy 286.523597 -358.138943) (xy 286.469621 -358.131178) (xy 286.4173 -358.11581) (xy 286.367699 -358.093154)
			(xy 286.321826 -358.063669) (xy 286.280617 -358.027957) (xy 286.244908 -357.986743) (xy 286.215428 -357.940868)
			(xy 286.192777 -357.891264) (xy 286.177414 -357.838942) (xy 286.169654 -357.784966) (xy 284.686806 -357.784966)
			(xy 284.686806 -357.784971) (xy 284.679043 -357.838959) (xy 284.663677 -357.891293) (xy 284.641019 -357.940907)
			(xy 284.611531 -357.986791) (xy 284.575813 -358.028012) (xy 284.534593 -358.06373) (xy 284.488708 -358.093218)
			(xy 284.439094 -358.115876) (xy 284.386761 -358.131243) (xy 284.332773 -358.139005) (xy 284.305502 -358.139492)
			(xy 283.441902 -358.139492) (xy 283.414633 -358.138969) (xy 283.36065 -358.131207) (xy 283.308321 -358.115843)
			(xy 283.258712 -358.093187) (xy 283.212832 -358.063702) (xy 283.171614 -358.027987) (xy 283.1359 -357.98677)
			(xy 283.106414 -357.94089) (xy 283.083758 -357.89128) (xy 283.068393 -357.838952) (xy 283.060631 -357.784969)
			(xy 281.577806 -357.784969) (xy 281.577806 -357.78497) (xy 281.570044 -357.838954) (xy 281.55468 -357.891284)
			(xy 281.532025 -357.940895) (xy 281.502541 -357.986778) (xy 281.466827 -358.027998) (xy 281.425611 -358.063716)
			(xy 281.379732 -358.093205) (xy 281.330123 -358.115865) (xy 281.277795 -358.131235) (xy 281.223812 -358.139003)
			(xy 281.196542 -358.139492) (xy 280.332942 -358.139492) (xy 280.305671 -358.138971) (xy 280.251684 -358.131215)
			(xy 280.19935 -358.115853) (xy 280.149736 -358.0932) (xy 280.10385 -358.063716) (xy 280.062629 -358.028001)
			(xy 280.026909 -357.986783) (xy 279.99742 -357.940901) (xy 279.974761 -357.891289) (xy 279.959394 -357.838957)
			(xy 279.951632 -357.784971) (xy 278.468928 -357.784971) (xy 278.468928 -357.784974) (xy 278.461165 -357.838967)
			(xy 278.445797 -357.891305) (xy 278.423136 -357.940923) (xy 278.393644 -357.986811) (xy 278.357922 -358.028035)
			(xy 278.316697 -358.063755) (xy 278.270807 -358.093245) (xy 278.221188 -358.115903) (xy 278.168849 -358.131269)
			(xy 278.114856 -358.13903) (xy 278.087582 -358.139492) (xy 277.223982 -358.139492) (xy 277.196716 -358.138944)
			(xy 277.142738 -358.131181) (xy 277.090415 -358.115816) (xy 277.040811 -358.09316) (xy 276.994936 -358.063676)
			(xy 276.953724 -358.027964) (xy 276.918013 -357.98675) (xy 276.888531 -357.940873) (xy 276.865878 -357.891268)
			(xy 276.850515 -357.838944) (xy 276.842754 -357.784966) (xy 275.359906 -357.784966) (xy 275.359906 -357.784971)
			(xy 275.352144 -357.838956) (xy 275.336778 -357.891288) (xy 275.314122 -357.940901) (xy 275.284636 -357.986784)
			(xy 275.24892 -358.028005) (xy 275.207702 -358.063723) (xy 275.16182 -358.093211) (xy 275.112209 -358.115871)
			(xy 275.059878 -358.131239) (xy 275.005892 -358.139004) (xy 274.978622 -358.139492) (xy 274.115022 -358.139492)
			(xy 274.087752 -358.13897) (xy 274.033767 -358.131211) (xy 273.981436 -358.115848) (xy 273.931824 -358.093193)
			(xy 273.885941 -358.063709) (xy 273.844722 -358.027994) (xy 273.809005 -357.986777) (xy 273.779517 -357.940895)
			(xy 273.75686 -357.891285) (xy 273.741494 -357.838954) (xy 273.733731 -357.78497) (xy 272.251028 -357.78497)
			(xy 272.251028 -357.784975) (xy 272.243265 -357.838969) (xy 272.227895 -357.891309) (xy 272.205233 -357.940929)
			(xy 272.17574 -357.986818) (xy 272.140015 -358.028042) (xy 272.098787 -358.063762) (xy 272.052895 -358.093251)
			(xy 272.003273 -358.115908) (xy 271.950932 -358.131273) (xy 271.896937 -358.139031) (xy 271.869662 -358.139492)
			(xy 271.006062 -358.139492) (xy 270.978797 -358.138943) (xy 270.924821 -358.131178) (xy 270.8725 -358.11581)
			(xy 270.822899 -358.093154) (xy 270.777026 -358.063669) (xy 270.735817 -358.027957) (xy 270.700108 -357.986743)
			(xy 270.670628 -357.940868) (xy 270.647977 -357.891264) (xy 270.632614 -357.838942) (xy 270.624854 -357.784966)
			(xy 247.276485 -357.784966) (xy 247.278987 -357.797946) (xy 247.287038 -357.88226) (xy 247.287542 -357.924608)
			(xy 247.287038 -357.966956) (xy 247.278987 -358.05127) (xy 247.262958 -358.134436) (xy 247.239097 -358.215703)
			(xy 247.207618 -358.294333) (xy 247.168807 -358.369614) (xy 247.123017 -358.440866) (xy 247.070661 -358.507442)
			(xy 247.012213 -358.56874) (xy 246.948203 -358.624205) (xy 246.879211 -358.673334) (xy 246.805861 -358.715683)
			(xy 246.728818 -358.750867) (xy 246.648779 -358.778569) (xy 246.56647 -358.798537) (xy 246.482635 -358.81059)
			(xy 246.398034 -358.814621) (xy 246.313433 -358.81059) (xy 246.229598 -358.798537) (xy 246.147289 -358.778569)
			(xy 246.06725 -358.750867) (xy 245.990207 -358.715683) (xy 245.916857 -358.673334) (xy 245.847865 -358.624205)
			(xy 245.783855 -358.56874) (xy 245.725407 -358.507442) (xy 245.673051 -358.440866) (xy 245.627261 -358.369614)
			(xy 245.58845 -358.294333) (xy 245.556971 -358.215703) (xy 245.53311 -358.134436) (xy 245.517081 -358.05127)
			(xy 245.50903 -357.966956) (xy 188.223925 -357.966956) (xy 188.191672 -358.004178) (xy 188.150456 -358.039891)
			(xy 188.104577 -358.069375) (xy 188.054969 -358.092029) (xy 188.002641 -358.107393) (xy 187.94866 -358.115153)
			(xy 187.921392 -358.115616) (xy 187.057792 -358.115616) (xy 187.03052 -358.115221) (xy 186.97653 -358.107457)
			(xy 186.924196 -358.092089) (xy 186.87458 -358.06943) (xy 186.828695 -358.03994) (xy 186.787473 -358.004221)
			(xy 186.751755 -357.962999) (xy 186.722266 -357.917112) (xy 186.699608 -357.867497) (xy 186.684241 -357.815162)
			(xy 186.676479 -357.761172) (xy 185.193629 -357.761172) (xy 185.18587 -357.815139) (xy 185.170508 -357.86746)
			(xy 185.147857 -357.917062) (xy 185.118378 -357.962936) (xy 185.08267 -358.004147) (xy 185.041461 -358.039858)
			(xy 184.99559 -358.069342) (xy 184.94599 -358.091997) (xy 184.89367 -358.107363) (xy 184.839697 -358.115128)
			(xy 184.812432 -358.115616) (xy 183.948832 -358.115616) (xy 183.921556 -358.115247) (xy 183.867559 -358.107487)
			(xy 183.815217 -358.092122) (xy 183.765593 -358.069463) (xy 183.7197 -358.039973) (xy 183.678471 -358.004251)
			(xy 183.642746 -357.963025) (xy 183.613252 -357.917135) (xy 183.590589 -357.867513) (xy 183.57522 -357.815172)
			(xy 183.567456 -357.761176) (xy 182.084828 -357.761176) (xy 182.084828 -357.784974) (xy 182.077065 -357.838968)
			(xy 182.061696 -357.891307) (xy 182.039035 -357.940926) (xy 182.009542 -357.986815) (xy 181.973819 -358.028039)
			(xy 181.932592 -358.063759) (xy 181.886701 -358.093248) (xy 181.837081 -358.115906) (xy 181.784741 -358.131271)
			(xy 181.730746 -358.13903) (xy 181.703472 -358.139492) (xy 180.839872 -358.139492) (xy 180.812606 -358.138944)
			(xy 180.75863 -358.131179) (xy 180.706308 -358.115813) (xy 180.656705 -358.093157) (xy 180.610831 -358.063673)
			(xy 180.56962 -358.02796) (xy 180.533911 -357.986746) (xy 180.50443 -357.94087) (xy 180.481777 -357.891266)
			(xy 180.466415 -357.838943) (xy 180.458654 -357.784966) (xy 178.975806 -357.784966) (xy 178.975806 -357.784971)
			(xy 178.968044 -357.838958) (xy 178.952678 -357.89129) (xy 178.930021 -357.940904) (xy 178.900533 -357.986788)
			(xy 178.864817 -358.028008) (xy 178.823597 -358.063726) (xy 178.777714 -358.093215) (xy 178.728102 -358.115873)
			(xy 178.675769 -358.131241) (xy 178.621783 -358.139005) (xy 178.594512 -358.139492) (xy 177.730912 -358.139492)
			(xy 177.703643 -358.138969) (xy 177.649659 -358.131209) (xy 177.597329 -358.115845) (xy 177.547718 -358.09319)
			(xy 177.501836 -358.063705) (xy 177.460618 -358.027991) (xy 177.424902 -357.986773) (xy 177.395416 -357.940893)
			(xy 177.372759 -357.891283) (xy 177.357393 -357.838953) (xy 177.349631 -357.784969) (xy 175.866928 -357.784969)
			(xy 175.866928 -357.784975) (xy 175.859164 -357.838971) (xy 175.843794 -357.891311) (xy 175.821132 -357.940932)
			(xy 175.791637 -357.986821) (xy 175.755912 -358.028046) (xy 175.714683 -358.063766) (xy 175.668789 -358.093255)
			(xy 175.619166 -358.115911) (xy 175.566824 -358.131275) (xy 175.512827 -358.139032) (xy 175.485552 -358.139492)
			(xy 174.621952 -358.139492) (xy 174.594687 -358.138942) (xy 174.540713 -358.131176) (xy 174.488393 -358.115807)
			(xy 174.438793 -358.09315) (xy 174.392922 -358.063665) (xy 174.351713 -358.027953) (xy 174.316006 -357.98674)
			(xy 174.286527 -357.940865) (xy 174.263876 -357.891262) (xy 174.248514 -357.83894) (xy 174.240754 -357.784965)
			(xy 172.757928 -357.784965) (xy 172.757928 -357.784974) (xy 172.750165 -357.838965) (xy 172.734798 -357.891303)
			(xy 172.712138 -357.94092) (xy 172.682647 -357.986808) (xy 172.646926 -358.028032) (xy 172.605702 -358.063752)
			(xy 172.559813 -358.093241) (xy 172.510195 -358.1159) (xy 172.457857 -358.131267) (xy 172.403866 -358.139029)
			(xy 172.376592 -358.139492) (xy 171.512992 -358.139492) (xy 171.485725 -358.138945) (xy 171.431747 -358.131183)
			(xy 171.379422 -358.115818) (xy 171.329817 -358.093163) (xy 171.283941 -358.06368) (xy 171.242727 -358.027967)
			(xy 171.207016 -357.986753) (xy 171.177533 -357.940876) (xy 171.154879 -357.89127) (xy 171.139515 -357.838946)
			(xy 171.131754 -357.784967) (xy 169.648906 -357.784967) (xy 169.648906 -357.78497) (xy 169.641144 -357.838955)
			(xy 169.625779 -357.891286) (xy 169.603124 -357.940898) (xy 169.573638 -357.986781) (xy 169.537924 -358.028001)
			(xy 169.496707 -358.063719) (xy 169.450826 -358.093208) (xy 169.401216 -358.115868) (xy 169.348886 -358.131237)
			(xy 169.294902 -358.139003) (xy 169.267632 -358.139492) (xy 168.404032 -358.139492) (xy 168.376762 -358.138971)
			(xy 168.322776 -358.131213) (xy 168.270443 -358.115851) (xy 168.22083 -358.093197) (xy 168.174946 -358.063712)
			(xy 168.133725 -358.027998) (xy 168.098007 -357.98678) (xy 168.068519 -357.940898) (xy 168.045861 -357.891287)
			(xy 168.030494 -357.838956) (xy 168.022732 -357.78497) (xy 166.540028 -357.78497) (xy 166.540028 -357.784974)
			(xy 166.532265 -357.838968) (xy 166.516896 -357.891307) (xy 166.494235 -357.940926) (xy 166.464742 -357.986815)
			(xy 166.429019 -358.028039) (xy 166.387792 -358.063759) (xy 166.341901 -358.093248) (xy 166.292281 -358.115906)
			(xy 166.239941 -358.131271) (xy 166.185946 -358.13903) (xy 166.158672 -358.139492) (xy 165.295072 -358.139492)
			(xy 165.267806 -358.138944) (xy 165.21383 -358.131179) (xy 165.161508 -358.115813) (xy 165.111905 -358.093157)
			(xy 165.066031 -358.063673) (xy 165.02482 -358.02796) (xy 164.989111 -357.986746) (xy 164.95963 -357.94087)
			(xy 164.936977 -357.891266) (xy 164.921615 -357.838943) (xy 164.913854 -357.784966) (xy 163.431006 -357.784966)
			(xy 163.431006 -357.784971) (xy 163.423244 -357.838958) (xy 163.407878 -357.89129) (xy 163.385221 -357.940904)
			(xy 163.355733 -357.986788) (xy 163.320017 -358.028008) (xy 163.278797 -358.063726) (xy 163.232914 -358.093215)
			(xy 163.183302 -358.115873) (xy 163.130969 -358.131241) (xy 163.076983 -358.139005) (xy 163.049712 -358.139492)
			(xy 162.186112 -358.139492) (xy 162.158843 -358.138969) (xy 162.104859 -358.131209) (xy 162.052529 -358.115845)
			(xy 162.002918 -358.09319) (xy 161.957036 -358.063705) (xy 161.915818 -358.027991) (xy 161.880102 -357.986773)
			(xy 161.850616 -357.940893) (xy 161.827959 -357.891283) (xy 161.812593 -357.838953) (xy 161.804831 -357.784969)
			(xy 160.322128 -357.784969) (xy 160.322128 -357.784975) (xy 160.314364 -357.838971) (xy 160.298994 -357.891311)
			(xy 160.276332 -357.940932) (xy 160.246837 -357.986821) (xy 160.211112 -358.028046) (xy 160.169883 -358.063766)
			(xy 160.123989 -358.093255) (xy 160.074366 -358.115911) (xy 160.022024 -358.131275) (xy 159.968027 -358.139032)
			(xy 159.940752 -358.139492) (xy 159.077152 -358.139492) (xy 159.049887 -358.138942) (xy 158.995913 -358.131176)
			(xy 158.943593 -358.115807) (xy 158.893993 -358.09315) (xy 158.848122 -358.063665) (xy 158.806913 -358.027953)
			(xy 158.771206 -357.98674) (xy 158.741727 -357.940865) (xy 158.719076 -357.891262) (xy 158.703714 -357.83894)
			(xy 158.695954 -357.784965) (xy 144.196606 -357.784965) (xy 144.196606 -357.784971) (xy 144.188843 -357.838958)
			(xy 144.173477 -357.891291) (xy 144.15082 -357.940905) (xy 144.121332 -357.986789) (xy 144.085615 -358.02801)
			(xy 144.044395 -358.063728) (xy 143.998512 -358.093216) (xy 143.948899 -358.115875) (xy 143.896566 -358.131242)
			(xy 143.842579 -358.139005) (xy 143.815308 -358.139492) (xy 142.951708 -358.139492) (xy 142.924439 -358.138969)
			(xy 142.870455 -358.131209) (xy 142.818126 -358.115844) (xy 142.768515 -358.093189) (xy 142.722634 -358.063704)
			(xy 142.681417 -358.027989) (xy 142.645701 -357.986772) (xy 142.616215 -357.940892) (xy 142.593559 -357.891282)
			(xy 142.578193 -357.838953) (xy 142.570431 -357.784969) (xy 141.087606 -357.784969) (xy 141.079845 -357.838953)
			(xy 141.06448 -357.891283) (xy 141.041826 -357.940894) (xy 141.012342 -357.986776) (xy 140.976629 -358.027995)
			(xy 140.935414 -358.063713) (xy 140.889536 -358.093203) (xy 140.839928 -358.115864) (xy 140.7876 -358.131234)
			(xy 140.733617 -358.139002) (xy 140.706348 -358.139492) (xy 139.842748 -358.139492) (xy 139.815477 -358.138972)
			(xy 139.761489 -358.131216) (xy 139.709155 -358.115855) (xy 139.659539 -358.093202) (xy 139.613653 -358.063718)
			(xy 139.572431 -358.028003) (xy 139.536711 -357.986785) (xy 139.507221 -357.940903) (xy 139.484562 -357.89129)
			(xy 139.469194 -357.838958) (xy 139.461432 -357.784971) (xy 137.978728 -357.784971) (xy 137.978728 -357.784974)
			(xy 137.970965 -357.838966) (xy 137.955597 -357.891304) (xy 137.932937 -357.940921) (xy 137.903446 -357.986809)
			(xy 137.867724 -358.028033) (xy 137.8265 -358.063753) (xy 137.780611 -358.093243) (xy 137.730992 -358.115901)
			(xy 137.678654 -358.131268) (xy 137.624662 -358.139029) (xy 137.597388 -358.139492) (xy 136.733788 -358.139492)
			(xy 136.706521 -358.138945) (xy 136.652543 -358.131182) (xy 136.600219 -358.115817) (xy 136.550615 -358.093162)
			(xy 136.504739 -358.063678) (xy 136.463526 -358.027966) (xy 136.427815 -357.986752) (xy 136.398332 -357.940875)
			(xy 136.375679 -357.891269) (xy 136.360315 -357.838945) (xy 136.352554 -357.784967) (xy 134.869706 -357.784967)
			(xy 134.869706 -357.78497) (xy 134.861944 -357.838956) (xy 134.846579 -357.891287) (xy 134.823923 -357.940899)
			(xy 134.794437 -357.986782) (xy 134.758722 -358.028003) (xy 134.717505 -358.063721) (xy 134.671624 -358.09321)
			(xy 134.622013 -358.115869) (xy 134.569683 -358.131238) (xy 134.515698 -358.139004) (xy 134.488428 -358.139492)
			(xy 133.624828 -358.139492) (xy 133.597558 -358.13897) (xy 133.543572 -358.131212) (xy 133.49124 -358.11585)
			(xy 133.441627 -358.093195) (xy 133.395744 -358.063711) (xy 133.354524 -358.027996) (xy 133.318806 -357.986779)
			(xy 133.289318 -357.940897) (xy 133.26666 -357.891286) (xy 133.251294 -357.838955) (xy 133.243531 -357.78497)
			(xy 131.760828 -357.78497) (xy 131.760828 -357.784975) (xy 131.753065 -357.838969) (xy 131.737696 -357.891308)
			(xy 131.715034 -357.940927) (xy 131.685541 -357.986816) (xy 131.649817 -358.02804) (xy 131.60859 -358.06376)
			(xy 131.562699 -358.093249) (xy 131.513078 -358.115907) (xy 131.460737 -358.131272) (xy 131.406743 -358.139031)
			(xy 131.379468 -358.139492) (xy 130.515868 -358.139492) (xy 130.488602 -358.138943) (xy 130.434626 -358.131179)
			(xy 130.382305 -358.115812) (xy 130.332703 -358.093156) (xy 130.286829 -358.063671) (xy 130.245619 -358.027959)
			(xy 130.20991 -357.986745) (xy 130.180429 -357.940869) (xy 130.157777 -357.891265) (xy 130.142414 -357.838942)
			(xy 130.134654 -357.784966) (xy 128.651806 -357.784966) (xy 128.651806 -357.784971) (xy 128.644043 -357.838958)
			(xy 128.628677 -357.891291) (xy 128.60602 -357.940905) (xy 128.576532 -357.986789) (xy 128.540815 -358.02801)
			(xy 128.499595 -358.063728) (xy 128.453712 -358.093216) (xy 128.404099 -358.115875) (xy 128.351766 -358.131242)
			(xy 128.297779 -358.139005) (xy 128.270508 -358.139492) (xy 127.406908 -358.139492) (xy 127.379639 -358.138969)
			(xy 127.325655 -358.131209) (xy 127.273326 -358.115844) (xy 127.223715 -358.093189) (xy 127.177834 -358.063704)
			(xy 127.136617 -358.027989) (xy 127.100901 -357.986772) (xy 127.071415 -357.940892) (xy 127.048759 -357.891282)
			(xy 127.033393 -357.838953) (xy 127.025631 -357.784969) (xy 125.542806 -357.784969) (xy 125.535045 -357.838953)
			(xy 125.51968 -357.891283) (xy 125.497026 -357.940894) (xy 125.467542 -357.986776) (xy 125.431829 -358.027995)
			(xy 125.390614 -358.063713) (xy 125.344736 -358.093203) (xy 125.295128 -358.115864) (xy 125.2428 -358.131234)
			(xy 125.188817 -358.139002) (xy 125.161548 -358.139492) (xy 124.297948 -358.139492) (xy 124.270677 -358.138972)
			(xy 124.216689 -358.131216) (xy 124.164355 -358.115855) (xy 124.114739 -358.093202) (xy 124.068853 -358.063718)
			(xy 124.027631 -358.028003) (xy 123.991911 -357.986785) (xy 123.962421 -357.940903) (xy 123.939762 -357.89129)
			(xy 123.924394 -357.838958) (xy 123.916632 -357.784971) (xy 122.433928 -357.784971) (xy 122.433928 -357.784974)
			(xy 122.426165 -357.838966) (xy 122.410797 -357.891304) (xy 122.388137 -357.940921) (xy 122.358646 -357.986809)
			(xy 122.322924 -358.028033) (xy 122.2817 -358.063753) (xy 122.235811 -358.093243) (xy 122.186192 -358.115901)
			(xy 122.133854 -358.131268) (xy 122.079862 -358.139029) (xy 122.052588 -358.139492) (xy 121.188988 -358.139492)
			(xy 121.161721 -358.138945) (xy 121.107743 -358.131182) (xy 121.055419 -358.115817) (xy 121.005815 -358.093162)
			(xy 120.959939 -358.063678) (xy 120.918726 -358.027966) (xy 120.883015 -357.986752) (xy 120.853532 -357.940875)
			(xy 120.830879 -357.891269) (xy 120.815515 -357.838945) (xy 120.807754 -357.784967) (xy 119.324906 -357.784967)
			(xy 119.324906 -357.78497) (xy 119.317144 -357.838956) (xy 119.301779 -357.891287) (xy 119.279123 -357.940899)
			(xy 119.249637 -357.986782) (xy 119.213922 -358.028003) (xy 119.172705 -358.063721) (xy 119.126824 -358.09321)
			(xy 119.077213 -358.115869) (xy 119.024883 -358.131238) (xy 118.970898 -358.139004) (xy 118.943628 -358.139492)
			(xy 118.080028 -358.139492) (xy 118.052758 -358.13897) (xy 117.998772 -358.131212) (xy 117.94644 -358.11585)
			(xy 117.896827 -358.093195) (xy 117.850944 -358.063711) (xy 117.809724 -358.027996) (xy 117.774006 -357.986779)
			(xy 117.744518 -357.940897) (xy 117.72186 -357.891286) (xy 117.706494 -357.838955) (xy 117.698731 -357.78497)
			(xy 116.216028 -357.78497) (xy 116.216028 -357.784975) (xy 116.208265 -357.838969) (xy 116.192896 -357.891308)
			(xy 116.170234 -357.940927) (xy 116.140741 -357.986816) (xy 116.105017 -358.02804) (xy 116.06379 -358.06376)
			(xy 116.017899 -358.093249) (xy 115.968278 -358.115907) (xy 115.915937 -358.131272) (xy 115.861943 -358.139031)
			(xy 115.834668 -358.139492) (xy 114.971068 -358.139492) (xy 114.943802 -358.138943) (xy 114.889826 -358.131179)
			(xy 114.837505 -358.115812) (xy 114.787903 -358.093156) (xy 114.742029 -358.063671) (xy 114.700819 -358.027959)
			(xy 114.66511 -357.986745) (xy 114.635629 -357.940869) (xy 114.612977 -357.891265) (xy 114.597614 -357.838942)
			(xy 114.589854 -357.784966) (xy 93.706706 -357.784966) (xy 93.706706 -357.78497) (xy 93.698944 -357.838954)
			(xy 93.68358 -357.891284) (xy 93.660925 -357.940895) (xy 93.631441 -357.986778) (xy 93.595727 -358.027998)
			(xy 93.554511 -358.063716) (xy 93.508632 -358.093205) (xy 93.459023 -358.115865) (xy 93.406695 -358.131235)
			(xy 93.352712 -358.139003) (xy 93.325442 -358.139492) (xy 92.461842 -358.139492) (xy 92.434571 -358.138971)
			(xy 92.380584 -358.131215) (xy 92.32825 -358.115853) (xy 92.278636 -358.0932) (xy 92.23275 -358.063716)
			(xy 92.191529 -358.028001) (xy 92.155809 -357.986783) (xy 92.12632 -357.940901) (xy 92.103661 -357.891289)
			(xy 92.088294 -357.838957) (xy 92.080532 -357.784971) (xy 90.597828 -357.784971) (xy 90.597828 -357.784974)
			(xy 90.590065 -357.838967) (xy 90.574697 -357.891305) (xy 90.552036 -357.940923) (xy 90.522544 -357.986811)
			(xy 90.486822 -358.028035) (xy 90.445597 -358.063755) (xy 90.399707 -358.093245) (xy 90.350088 -358.115903)
			(xy 90.297749 -358.131269) (xy 90.243756 -358.13903) (xy 90.216482 -358.139492) (xy 89.352882 -358.139492)
			(xy 89.325616 -358.138944) (xy 89.271638 -358.131181) (xy 89.219315 -358.115816) (xy 89.169711 -358.09316)
			(xy 89.123836 -358.063676) (xy 89.082624 -358.027964) (xy 89.046913 -357.98675) (xy 89.017431 -357.940873)
			(xy 88.994778 -357.891268) (xy 88.979415 -357.838944) (xy 88.971654 -357.784966) (xy 87.488806 -357.784966)
			(xy 87.488806 -357.784971) (xy 87.481044 -357.838956) (xy 87.465678 -357.891288) (xy 87.443022 -357.940901)
			(xy 87.413536 -357.986784) (xy 87.37782 -358.028005) (xy 87.336602 -358.063723) (xy 87.29072 -358.093211)
			(xy 87.241109 -358.115871) (xy 87.188778 -358.131239) (xy 87.134792 -358.139004) (xy 87.107522 -358.139492)
			(xy 86.243922 -358.139492) (xy 86.216652 -358.13897) (xy 86.162667 -358.131211) (xy 86.110336 -358.115848)
			(xy 86.060724 -358.093193) (xy 86.014841 -358.063709) (xy 85.973622 -358.027994) (xy 85.937905 -357.986777)
			(xy 85.908417 -357.940895) (xy 85.88576 -357.891285) (xy 85.870394 -357.838954) (xy 85.862631 -357.78497)
			(xy 84.379928 -357.78497) (xy 84.379928 -357.784975) (xy 84.372165 -357.838969) (xy 84.356795 -357.891309)
			(xy 84.334133 -357.940929) (xy 84.30464 -357.986818) (xy 84.268915 -358.028042) (xy 84.227687 -358.063762)
			(xy 84.181795 -358.093251) (xy 84.132173 -358.115908) (xy 84.079832 -358.131273) (xy 84.025837 -358.139031)
			(xy 83.998562 -358.139492) (xy 83.134962 -358.139492) (xy 83.107697 -358.138943) (xy 83.053721 -358.131178)
			(xy 83.0014 -358.11581) (xy 82.951799 -358.093154) (xy 82.905926 -358.063669) (xy 82.864717 -358.027957)
			(xy 82.829008 -357.986743) (xy 82.799528 -357.940868) (xy 82.776877 -357.891264) (xy 82.761514 -357.838942)
			(xy 82.753754 -357.784966) (xy 81.270906 -357.784966) (xy 81.270906 -357.784971) (xy 81.263143 -357.838959)
			(xy 81.247777 -357.891293) (xy 81.225119 -357.940907) (xy 81.195631 -357.986791) (xy 81.159913 -358.028012)
			(xy 81.118693 -358.06373) (xy 81.072808 -358.093218) (xy 81.023194 -358.115876) (xy 80.970861 -358.131243)
			(xy 80.916873 -358.139005) (xy 80.889602 -358.139492) (xy 80.026002 -358.139492) (xy 79.998733 -358.138969)
			(xy 79.94475 -358.131207) (xy 79.892421 -358.115843) (xy 79.842812 -358.093187) (xy 79.796932 -358.063702)
			(xy 79.755714 -358.027987) (xy 79.72 -357.98677) (xy 79.690514 -357.94089) (xy 79.667858 -357.89128)
			(xy 79.652493 -357.838952) (xy 79.644731 -357.784969) (xy 78.161906 -357.784969) (xy 78.161906 -357.78497)
			(xy 78.154144 -357.838954) (xy 78.13878 -357.891284) (xy 78.116125 -357.940895) (xy 78.086641 -357.986778)
			(xy 78.050927 -358.027998) (xy 78.009711 -358.063716) (xy 77.963832 -358.093205) (xy 77.914223 -358.115865)
			(xy 77.861895 -358.131235) (xy 77.807912 -358.139003) (xy 77.780642 -358.139492) (xy 76.917042 -358.139492)
			(xy 76.889771 -358.138971) (xy 76.835784 -358.131215) (xy 76.78345 -358.115853) (xy 76.733836 -358.0932)
			(xy 76.68795 -358.063716) (xy 76.646729 -358.028001) (xy 76.611009 -357.986783) (xy 76.58152 -357.940901)
			(xy 76.558861 -357.891289) (xy 76.543494 -357.838957) (xy 76.535732 -357.784971) (xy 75.053028 -357.784971)
			(xy 75.053028 -357.784974) (xy 75.045265 -357.838967) (xy 75.029897 -357.891305) (xy 75.007236 -357.940923)
			(xy 74.977744 -357.986811) (xy 74.942022 -358.028035) (xy 74.900797 -358.063755) (xy 74.854907 -358.093245)
			(xy 74.805288 -358.115903) (xy 74.752949 -358.131269) (xy 74.698956 -358.13903) (xy 74.671682 -358.139492)
			(xy 73.808082 -358.139492) (xy 73.780816 -358.138944) (xy 73.726838 -358.131181) (xy 73.674515 -358.115816)
			(xy 73.624911 -358.09316) (xy 73.579036 -358.063676) (xy 73.537824 -358.027964) (xy 73.502113 -357.98675)
			(xy 73.472631 -357.940873) (xy 73.449978 -357.891268) (xy 73.434615 -357.838944) (xy 73.426854 -357.784966)
			(xy 71.944006 -357.784966) (xy 71.944006 -357.784971) (xy 71.936244 -357.838956) (xy 71.920878 -357.891288)
			(xy 71.898222 -357.940901) (xy 71.868736 -357.986784) (xy 71.83302 -358.028005) (xy 71.791802 -358.063723)
			(xy 71.74592 -358.093211) (xy 71.696309 -358.115871) (xy 71.643978 -358.131239) (xy 71.589992 -358.139004)
			(xy 71.562722 -358.139492) (xy 70.699122 -358.139492) (xy 70.671852 -358.13897) (xy 70.617867 -358.131211)
			(xy 70.565536 -358.115848) (xy 70.515924 -358.093193) (xy 70.470041 -358.063709) (xy 70.428822 -358.027994)
			(xy 70.393105 -357.986777) (xy 70.363617 -357.940895) (xy 70.34096 -357.891285) (xy 70.325594 -357.838954)
			(xy 70.317831 -357.78497) (xy 68.835128 -357.78497) (xy 68.835128 -357.784975) (xy 68.827365 -357.838969)
			(xy 68.811995 -357.891309) (xy 68.789333 -357.940929) (xy 68.75984 -357.986818) (xy 68.724115 -358.028042)
			(xy 68.682887 -358.063762) (xy 68.636995 -358.093251) (xy 68.587373 -358.115908) (xy 68.535032 -358.131273)
			(xy 68.481037 -358.139031) (xy 68.453762 -358.139492) (xy 67.590162 -358.139492) (xy 67.562897 -358.138943)
			(xy 67.508921 -358.131178) (xy 67.4566 -358.11581) (xy 67.406999 -358.093154) (xy 67.361126 -358.063669)
			(xy 67.319917 -358.027957) (xy 67.284208 -357.986743) (xy 67.254728 -357.940868) (xy 67.232077 -357.891264)
			(xy 67.216714 -357.838942) (xy 67.208954 -357.784966) (xy 65.726106 -357.784966) (xy 65.726106 -357.784971)
			(xy 65.718343 -357.838959) (xy 65.702977 -357.891293) (xy 65.680319 -357.940907) (xy 65.650831 -357.986791)
			(xy 65.615113 -358.028012) (xy 65.573893 -358.06373) (xy 65.528008 -358.093218) (xy 65.478394 -358.115876)
			(xy 65.426061 -358.131243) (xy 65.372073 -358.139005) (xy 65.344802 -358.139492) (xy 64.481202 -358.139492)
			(xy 64.453933 -358.138969) (xy 64.39995 -358.131207) (xy 64.347621 -358.115843) (xy 64.298012 -358.093187)
			(xy 64.252132 -358.063702) (xy 64.210914 -358.027987) (xy 64.1752 -357.98677) (xy 64.145714 -357.94089)
			(xy 64.123058 -357.89128) (xy 64.107693 -357.838952) (xy 64.099931 -357.784969) (xy 51.666906 -357.784969)
			(xy 51.659145 -357.838953) (xy 51.64378 -357.891283) (xy 51.621126 -357.940894) (xy 51.591642 -357.986776)
			(xy 51.555929 -358.027995) (xy 51.514714 -358.063713) (xy 51.468836 -358.093203) (xy 51.419228 -358.115864)
			(xy 51.3669 -358.131234) (xy 51.312917 -358.139002) (xy 51.285648 -358.139492) (xy 50.422048 -358.139492)
			(xy 50.394777 -358.138972) (xy 50.340789 -358.131216) (xy 50.288455 -358.115855) (xy 50.238839 -358.093202)
			(xy 50.192953 -358.063718) (xy 50.151731 -358.028003) (xy 50.116011 -357.986785) (xy 50.086521 -357.940903)
			(xy 50.063862 -357.89129) (xy 50.048494 -357.838958) (xy 50.040732 -357.784971) (xy 48.558028 -357.784971)
			(xy 48.558028 -357.784974) (xy 48.550265 -357.838966) (xy 48.534897 -357.891304) (xy 48.512237 -357.940921)
			(xy 48.482746 -357.986809) (xy 48.447024 -358.028033) (xy 48.4058 -358.063753) (xy 48.359911 -358.093243)
			(xy 48.310292 -358.115901) (xy 48.257954 -358.131268) (xy 48.203962 -358.139029) (xy 48.176688 -358.139492)
			(xy 47.313088 -358.139492) (xy 47.285821 -358.138945) (xy 47.231843 -358.131182) (xy 47.179519 -358.115817)
			(xy 47.129915 -358.093162) (xy 47.084039 -358.063678) (xy 47.042826 -358.027966) (xy 47.007115 -357.986752)
			(xy 46.977632 -357.940875) (xy 46.954979 -357.891269) (xy 46.939615 -357.838945) (xy 46.931854 -357.784967)
			(xy 45.449006 -357.784967) (xy 45.449006 -357.78497) (xy 45.441244 -357.838956) (xy 45.425879 -357.891287)
			(xy 45.403223 -357.940899) (xy 45.373737 -357.986782) (xy 45.338022 -358.028003) (xy 45.296805 -358.063721)
			(xy 45.250924 -358.09321) (xy 45.201313 -358.115869) (xy 45.148983 -358.131238) (xy 45.094998 -358.139004)
			(xy 45.067728 -358.139492) (xy 44.204128 -358.139492) (xy 44.176858 -358.13897) (xy 44.122872 -358.131212)
			(xy 44.07054 -358.11585) (xy 44.020927 -358.093195) (xy 43.975044 -358.063711) (xy 43.933824 -358.027996)
			(xy 43.898106 -357.986779) (xy 43.868618 -357.940897) (xy 43.84596 -357.891286) (xy 43.830594 -357.838955)
			(xy 43.822831 -357.78497) (xy 42.340128 -357.78497) (xy 42.340128 -357.784975) (xy 42.332365 -357.838969)
			(xy 42.316996 -357.891308) (xy 42.294334 -357.940927) (xy 42.264841 -357.986816) (xy 42.229117 -358.02804)
			(xy 42.18789 -358.06376) (xy 42.141999 -358.093249) (xy 42.092378 -358.115907) (xy 42.040037 -358.131272)
			(xy 41.986043 -358.139031) (xy 41.958768 -358.139492) (xy 41.095168 -358.139492) (xy 41.067902 -358.138943)
			(xy 41.013926 -358.131179) (xy 40.961605 -358.115812) (xy 40.912003 -358.093156) (xy 40.866129 -358.063671)
			(xy 40.824919 -358.027959) (xy 40.78921 -357.986745) (xy 40.759729 -357.940869) (xy 40.737077 -357.891265)
			(xy 40.721714 -357.838942) (xy 40.713954 -357.784966) (xy 39.231106 -357.784966) (xy 39.231106 -357.784971)
			(xy 39.223343 -357.838958) (xy 39.207977 -357.891291) (xy 39.18532 -357.940905) (xy 39.155832 -357.986789)
			(xy 39.120115 -358.02801) (xy 39.078895 -358.063728) (xy 39.033012 -358.093216) (xy 38.983399 -358.115875)
			(xy 38.931066 -358.131242) (xy 38.877079 -358.139005) (xy 38.849808 -358.139492) (xy 37.986208 -358.139492)
			(xy 37.958939 -358.138969) (xy 37.904955 -358.131209) (xy 37.852626 -358.115844) (xy 37.803015 -358.093189)
			(xy 37.757134 -358.063704) (xy 37.715917 -358.027989) (xy 37.680201 -357.986772) (xy 37.650715 -357.940892)
			(xy 37.628059 -357.891282) (xy 37.612693 -357.838953) (xy 37.604931 -357.784969) (xy 36.122106 -357.784969)
			(xy 36.114345 -357.838953) (xy 36.09898 -357.891283) (xy 36.076326 -357.940894) (xy 36.046842 -357.986776)
			(xy 36.011129 -358.027995) (xy 35.969914 -358.063713) (xy 35.924036 -358.093203) (xy 35.874428 -358.115864)
			(xy 35.8221 -358.131234) (xy 35.768117 -358.139002) (xy 35.740848 -358.139492) (xy 34.877248 -358.139492)
			(xy 34.849977 -358.138972) (xy 34.795989 -358.131216) (xy 34.743655 -358.115855) (xy 34.694039 -358.093202)
			(xy 34.648153 -358.063718) (xy 34.606931 -358.028003) (xy 34.571211 -357.986785) (xy 34.541721 -357.940903)
			(xy 34.519062 -357.89129) (xy 34.503694 -357.838958) (xy 34.495932 -357.784971) (xy 33.013228 -357.784971)
			(xy 33.013228 -357.784974) (xy 33.005465 -357.838966) (xy 32.990097 -357.891304) (xy 32.967437 -357.940921)
			(xy 32.937946 -357.986809) (xy 32.902224 -358.028033) (xy 32.861 -358.063753) (xy 32.815111 -358.093243)
			(xy 32.765492 -358.115901) (xy 32.713154 -358.131268) (xy 32.659162 -358.139029) (xy 32.631888 -358.139492)
			(xy 31.768288 -358.139492) (xy 31.741021 -358.138945) (xy 31.687043 -358.131182) (xy 31.634719 -358.115817)
			(xy 31.585115 -358.093162) (xy 31.539239 -358.063678) (xy 31.498026 -358.027966) (xy 31.462315 -357.986752)
			(xy 31.432832 -357.940875) (xy 31.410179 -357.891269) (xy 31.394815 -357.838945) (xy 31.387054 -357.784967)
			(xy 29.904206 -357.784967) (xy 29.904206 -357.78497) (xy 29.896444 -357.838956) (xy 29.881079 -357.891287)
			(xy 29.858423 -357.940899) (xy 29.828937 -357.986782) (xy 29.793222 -358.028003) (xy 29.752005 -358.063721)
			(xy 29.706124 -358.09321) (xy 29.656513 -358.115869) (xy 29.604183 -358.131238) (xy 29.550198 -358.139004)
			(xy 29.522928 -358.139492) (xy 28.659328 -358.139492) (xy 28.632058 -358.13897) (xy 28.578072 -358.131212)
			(xy 28.52574 -358.11585) (xy 28.476127 -358.093195) (xy 28.430244 -358.063711) (xy 28.389024 -358.027996)
			(xy 28.353306 -357.986779) (xy 28.323818 -357.940897) (xy 28.30116 -357.891286) (xy 28.285794 -357.838955)
			(xy 28.278031 -357.78497) (xy 26.795328 -357.78497) (xy 26.795328 -357.784975) (xy 26.787565 -357.838969)
			(xy 26.772196 -357.891308) (xy 26.749534 -357.940927) (xy 26.720041 -357.986816) (xy 26.684317 -358.02804)
			(xy 26.64309 -358.06376) (xy 26.597199 -358.093249) (xy 26.547578 -358.115907) (xy 26.495237 -358.131272)
			(xy 26.441243 -358.139031) (xy 26.413968 -358.139492) (xy 25.550368 -358.139492) (xy 25.523102 -358.138943)
			(xy 25.469126 -358.131179) (xy 25.416805 -358.115812) (xy 25.367203 -358.093156) (xy 25.321329 -358.063671)
			(xy 25.280119 -358.027959) (xy 25.24441 -357.986745) (xy 25.214929 -357.940869) (xy 25.192277 -357.891265)
			(xy 25.176914 -357.838942) (xy 25.169154 -357.784966) (xy 23.686306 -357.784966) (xy 23.686306 -357.784971)
			(xy 23.678543 -357.838958) (xy 23.663177 -357.891291) (xy 23.64052 -357.940905) (xy 23.611032 -357.986789)
			(xy 23.575315 -358.02801) (xy 23.534095 -358.063728) (xy 23.488212 -358.093216) (xy 23.438599 -358.115875)
			(xy 23.386266 -358.131242) (xy 23.332279 -358.139005) (xy 23.305008 -358.139492) (xy 22.441408 -358.139492)
			(xy 22.414139 -358.138969) (xy 22.360155 -358.131209) (xy 22.307826 -358.115844) (xy 22.258215 -358.093189)
			(xy 22.212334 -358.063704) (xy 22.171117 -358.027989) (xy 22.135401 -357.986772) (xy 22.105915 -357.940892)
			(xy 22.083259 -357.891282) (xy 22.067893 -357.838953) (xy 22.060131 -357.784969) (xy 0.508 -357.784969)
			(xy 0.508 -360.017783) (xy 101.774757 -360.017783) (xy 101.774757 -359.957817) (xy 101.782584 -359.898365)
			(xy 101.798104 -359.840443) (xy 101.821052 -359.785042) (xy 101.851035 -359.733111) (xy 101.88754 -359.685538)
			(xy 101.929942 -359.643136) (xy 101.977516 -359.606632) (xy 102.029448 -359.57665) (xy 102.084849 -359.553703)
			(xy 102.142771 -359.538183) (xy 102.202223 -359.530357) (xy 102.232206 -359.529888) (xy 103.095806 -359.529888)
			(xy 103.125793 -359.530279) (xy 103.185255 -359.538108) (xy 103.243186 -359.553631) (xy 103.298595 -359.576583)
			(xy 103.350534 -359.60657) (xy 103.398115 -359.643081) (xy 103.440523 -359.68549) (xy 103.477033 -359.733071)
			(xy 103.50702 -359.785011) (xy 103.529971 -359.84042) (xy 103.545494 -359.898351) (xy 103.553322 -359.957813)
			(xy 103.553322 -360.017787) (xy 103.545494 -360.077249) (xy 103.529971 -360.13518) (xy 103.50702 -360.190589)
			(xy 103.477033 -360.242529) (xy 103.440523 -360.29011) (xy 103.398115 -360.332519) (xy 103.350534 -360.36903)
			(xy 103.298595 -360.399017) (xy 103.243186 -360.421969) (xy 103.185255 -360.437492) (xy 103.125793 -360.445321)
			(xy 103.095806 -360.445812) (xy 102.232206 -360.445812) (xy 102.202223 -360.445243) (xy 102.142771 -360.437417)
			(xy 102.084849 -360.421897) (xy 102.029448 -360.39895) (xy 101.977516 -360.368968) (xy 101.929942 -360.332464)
			(xy 101.88754 -360.290062) (xy 101.851035 -360.242489) (xy 101.821052 -360.190558) (xy 101.798104 -360.135157)
			(xy 101.782584 -360.077235) (xy 101.774757 -360.017783) (xy 0.508 -360.017783) (xy 0.508 -363.334808)
			(xy 54.890416 -363.334808) (xy 54.890416 -362.471208) (xy 54.890906 -362.441224) (xy 54.898734 -362.381768)
			(xy 54.914255 -362.323843) (xy 54.937204 -362.268439) (xy 54.967188 -362.216505) (xy 55.003694 -362.168929)
			(xy 55.046099 -362.126524) (xy 55.093675 -362.090018) (xy 55.145609 -362.060034) (xy 55.201013 -362.037085)
			(xy 55.258938 -362.021564) (xy 55.318394 -362.013736) (xy 55.378362 -362.013736) (xy 55.437818 -362.021564)
			(xy 55.495743 -362.037085) (xy 55.551147 -362.060034) (xy 55.603081 -362.090018) (xy 55.650657 -362.126524)
			(xy 55.693062 -362.168929) (xy 55.729568 -362.216505) (xy 55.759552 -362.268439) (xy 55.782501 -362.323843)
			(xy 55.798022 -362.381768) (xy 55.80585 -362.441224) (xy 55.80634 -362.471208) (xy 55.80634 -363.334808)
			(xy 55.80585 -363.364792) (xy 55.798022 -363.424248) (xy 55.782501 -363.482173) (xy 55.759552 -363.537577)
			(xy 55.729568 -363.589511) (xy 55.693062 -363.637087) (xy 55.650657 -363.679492) (xy 55.603081 -363.715998)
			(xy 55.551147 -363.745982) (xy 55.495743 -363.768931) (xy 55.437818 -363.784452) (xy 55.378362 -363.79228)
			(xy 55.318394 -363.79228) (xy 55.258938 -363.784452) (xy 55.201013 -363.768931) (xy 55.145609 -363.745982)
			(xy 55.093675 -363.715998) (xy 55.046099 -363.679492) (xy 55.003694 -363.637087) (xy 54.967188 -363.589511)
			(xy 54.937204 -363.537577) (xy 54.914255 -363.482173) (xy 54.898734 -363.424248) (xy 54.890906 -363.364792)
			(xy 54.890416 -363.334808) (xy 0.508 -363.334808) (xy 0.508 -365.797384) (xy 54.438294 -365.797384)
			(xy 54.438294 -365.737416) (xy 54.446121 -365.67796) (xy 54.461641 -365.620034) (xy 54.484589 -365.564629)
			(xy 54.514571 -365.512694) (xy 54.551076 -365.465115) (xy 54.593478 -365.422709) (xy 54.641052 -365.386199)
			(xy 54.692984 -365.356211) (xy 54.748387 -365.333257) (xy 54.806311 -365.317731) (xy 54.865766 -365.309897)
			(xy 54.89575 -365.309404) (xy 55.75935 -365.309404) (xy 55.789336 -365.309938) (xy 55.848794 -365.31776)
			(xy 55.906723 -365.333276) (xy 55.962131 -365.356222) (xy 56.01407 -365.386203) (xy 56.06165 -365.422708)
			(xy 56.104059 -365.465112) (xy 56.140569 -365.512689) (xy 56.170556 -365.564624) (xy 56.193508 -365.620029)
			(xy 56.20903 -365.677957) (xy 56.216859 -365.737414) (xy 56.216859 -365.797386) (xy 56.20903 -365.856843)
			(xy 56.193508 -365.914771) (xy 56.170556 -365.970176) (xy 56.140569 -366.022112) (xy 56.104059 -366.069688)
			(xy 56.06165 -366.112092) (xy 56.01407 -366.148597) (xy 55.962131 -366.178578) (xy 55.906723 -366.201524)
			(xy 55.848794 -366.21704) (xy 55.789336 -366.224862) (xy 55.75935 -366.225328) (xy 54.89575 -366.225328)
			(xy 54.865766 -366.224903) (xy 54.806311 -366.217069) (xy 54.748386 -366.201543) (xy 54.692984 -366.178589)
			(xy 54.641052 -366.148601) (xy 54.593478 -366.112091) (xy 54.551076 -366.069685) (xy 54.514571 -366.022106)
			(xy 54.484589 -365.970171) (xy 54.461641 -365.914766) (xy 54.446121 -365.85684) (xy 54.438294 -365.797384)
			(xy 0.508 -365.797384) (xy 0.508 -368.516662) (xy 53.966364 -368.516662) (xy 53.966364 -367.653062)
			(xy 53.96685 -367.625793) (xy 53.974612 -367.571809) (xy 53.989977 -367.519479) (xy 54.012634 -367.469869)
			(xy 54.04212 -367.423988) (xy 54.077835 -367.382771) (xy 54.119052 -367.347056) (xy 54.164933 -367.31757)
			(xy 54.214543 -367.294913) (xy 54.266873 -367.279548) (xy 54.320857 -367.271786) (xy 54.375395 -367.271786)
			(xy 54.429379 -367.279548) (xy 54.481709 -367.294913) (xy 54.531319 -367.31757) (xy 54.5772 -367.347056)
			(xy 54.618417 -367.382771) (xy 54.654132 -367.423988) (xy 54.683618 -367.469869) (xy 54.706275 -367.519479)
			(xy 54.72164 -367.571809) (xy 54.729402 -367.625793) (xy 54.729888 -367.653062) (xy 54.729888 -368.516662)
			(xy 57.339484 -368.516662) (xy 57.339484 -367.653062) (xy 57.33997 -367.625793) (xy 57.347732 -367.571809)
			(xy 57.363097 -367.519479) (xy 57.385754 -367.469869) (xy 57.41524 -367.423988) (xy 57.450955 -367.382771)
			(xy 57.492172 -367.347056) (xy 57.538053 -367.31757) (xy 57.587663 -367.294913) (xy 57.639993 -367.279548)
			(xy 57.693977 -367.271786) (xy 57.748515 -367.271786) (xy 57.802499 -367.279548) (xy 57.854829 -367.294913)
			(xy 57.904439 -367.31757) (xy 57.95032 -367.347056) (xy 57.991537 -367.382771) (xy 58.027252 -367.423988)
			(xy 58.056738 -367.469869) (xy 58.079395 -367.519479) (xy 58.09476 -367.571809) (xy 58.102522 -367.625793)
			(xy 58.103008 -367.653062) (xy 58.103008 -368.516662) (xy 58.102522 -368.543931) (xy 58.09476 -368.597915)
			(xy 58.079395 -368.650245) (xy 58.056738 -368.699855) (xy 58.027252 -368.745736) (xy 57.991537 -368.786953)
			(xy 57.95032 -368.822668) (xy 57.904439 -368.852154) (xy 57.854829 -368.874811) (xy 57.802499 -368.890176)
			(xy 57.748515 -368.897938) (xy 57.693977 -368.897938) (xy 57.639993 -368.890176) (xy 57.587663 -368.874811)
			(xy 57.538053 -368.852154) (xy 57.492172 -368.822668) (xy 57.450955 -368.786953) (xy 57.41524 -368.745736)
			(xy 57.385754 -368.699855) (xy 57.363097 -368.650245) (xy 57.347732 -368.597915) (xy 57.33997 -368.543931)
			(xy 57.339484 -368.516662) (xy 54.729888 -368.516662) (xy 54.729402 -368.543931) (xy 54.72164 -368.597915)
			(xy 54.706275 -368.650245) (xy 54.683618 -368.699855) (xy 54.654132 -368.745736) (xy 54.618417 -368.786953)
			(xy 54.5772 -368.822668) (xy 54.531319 -368.852154) (xy 54.481709 -368.874811) (xy 54.429379 -368.890176)
			(xy 54.375395 -368.897938) (xy 54.320857 -368.897938) (xy 54.266873 -368.890176) (xy 54.214543 -368.874811)
			(xy 54.164933 -368.852154) (xy 54.119052 -368.822668) (xy 54.077835 -368.786953) (xy 54.04212 -368.745736)
			(xy 54.012634 -368.699855) (xy 53.989977 -368.650245) (xy 53.974612 -368.597915) (xy 53.96685 -368.543931)
			(xy 53.966364 -368.516662) (xy 0.508 -368.516662) (xy 0.508 -370.523703) (xy 27.348898 -370.523703)
			(xy 27.348899 -370.456279) (xy 27.356975 -370.38934) (xy 27.373012 -370.323851) (xy 27.396776 -370.260753)
			(xy 27.427927 -370.200957) (xy 27.466016 -370.145322) (xy 27.48788 -370.119656) (xy 27.493675 -370.11251)
			(xy 27.500191 -370.09532) (xy 27.50058 -370.086128) (xy 27.50058 -369.928902) (xy 27.501029 -369.918771)
			(xy 27.508764 -369.900042) (xy 27.523062 -369.885684) (xy 27.541759 -369.877872) (xy 27.551888 -369.87734)
			(xy 28.268168 -369.87734) (xy 28.278293 -369.877743) (xy 28.297004 -369.885488) (xy 28.311321 -369.899809)
			(xy 28.31906 -369.918522) (xy 28.319476 -369.928648) (xy 28.319476 -370.086128) (xy 28.319878 -370.095316)
			(xy 28.326398 -370.1125) (xy 28.332176 -370.119656) (xy 28.354029 -370.145331) (xy 28.39212 -370.200963)
			(xy 28.423272 -370.260758) (xy 28.447038 -370.323854) (xy 28.463075 -370.389342) (xy 28.471152 -370.456279)
			(xy 28.471153 -370.523644) (xy 31.749193 -370.523644) (xy 31.749194 -370.456338) (xy 31.75724 -370.389514)
			(xy 31.773215 -370.324131) (xy 31.79689 -370.261126) (xy 31.827927 -370.201402) (xy 31.865879 -370.145816)
			(xy 31.887668 -370.120164) (xy 31.893471 -370.113023) (xy 31.89998 -370.095829) (xy 31.900368 -370.086636)
			(xy 31.900368 -369.928902) (xy 31.900766 -369.918727) (xy 31.908556 -369.899926) (xy 31.92295 -369.88554)
			(xy 31.941755 -369.877761) (xy 31.95193 -369.87734) (xy 32.66821 -369.87734) (xy 32.678369 -369.877825)
			(xy 32.697138 -369.885603) (xy 32.711503 -369.899972) (xy 32.719277 -369.918743) (xy 32.719772 -369.928902)
			(xy 32.719772 -370.086636) (xy 32.720171 -370.095824) (xy 32.726693 -370.113008) (xy 32.732472 -370.120164)
			(xy 32.754248 -370.145826) (xy 32.792196 -370.201411) (xy 32.823229 -370.261134) (xy 32.846902 -370.324137)
			(xy 32.862876 -370.389518) (xy 32.870921 -370.456339) (xy 32.870922 -370.523643) (xy 32.870915 -370.523703)
			(xy 36.148986 -370.523703) (xy 36.148987 -370.456279) (xy 36.157063 -370.389341) (xy 36.173099 -370.323851)
			(xy 36.196863 -370.260754) (xy 36.228013 -370.200957) (xy 36.266101 -370.145322) (xy 36.287964 -370.119656)
			(xy 36.29377 -370.112518) (xy 36.300277 -370.095322) (xy 36.300664 -370.086128) (xy 36.300664 -369.928902)
			(xy 36.301129 -369.918772) (xy 36.308861 -369.900047) (xy 36.323154 -369.88569) (xy 36.341845 -369.877875)
			(xy 36.351972 -369.87734) (xy 37.068252 -369.87734) (xy 37.078408 -369.877762) (xy 37.097167 -369.885549)
			(xy 37.111494 -369.899947) (xy 37.119188 -369.918744) (xy 37.11956 -369.928902) (xy 37.11956 -370.086128)
			(xy 37.119966 -370.095315) (xy 37.126483 -370.112499) (xy 37.13226 -370.119656) (xy 37.154114 -370.14533)
			(xy 37.192205 -370.200963) (xy 37.223359 -370.260757) (xy 37.247125 -370.323853) (xy 37.263163 -370.389341)
			(xy 37.27124 -370.456279) (xy 37.271241 -370.523703) (xy 37.271241 -370.523704) (xy 40.548752 -370.523704)
			(xy 40.548753 -370.456278) (xy 40.556831 -370.389338) (xy 40.572869 -370.323848) (xy 40.596637 -370.26075)
			(xy 40.627792 -370.200954) (xy 40.665885 -370.14532) (xy 40.687752 -370.119656) (xy 40.693556 -370.112516)
			(xy 40.700065 -370.095321) (xy 40.700452 -370.086128) (xy 40.700452 -369.928902) (xy 40.700929 -369.918774)
			(xy 40.708658 -369.900051) (xy 40.722947 -369.885694) (xy 40.741634 -369.877877) (xy 40.75176 -369.87734)
			(xy 41.46804 -369.87734) (xy 41.478202 -369.87769) (xy 41.496963 -369.885506) (xy 41.511286 -369.899925)
			(xy 41.518977 -369.918738) (xy 41.519348 -369.928902) (xy 41.519348 -370.086128) (xy 41.519756 -370.095315)
			(xy 41.526273 -370.112499) (xy 41.532048 -370.119656) (xy 41.553902 -370.14533) (xy 41.591994 -370.200962)
			(xy 41.623149 -370.260757) (xy 41.646916 -370.323852) (xy 41.662954 -370.389341) (xy 41.671031 -370.456279)
			(xy 41.671032 -370.523644) (xy 44.949071 -370.523644) (xy 44.949073 -370.456338) (xy 44.957118 -370.389515)
			(xy 44.973092 -370.324132) (xy 44.996766 -370.261127) (xy 45.027801 -370.201403) (xy 45.065751 -370.145816)
			(xy 45.08754 -370.120164) (xy 45.093339 -370.113021) (xy 45.099851 -370.095829) (xy 45.10024 -370.086636)
			(xy 45.10024 -369.928902) (xy 45.100665 -369.91873) (xy 45.10845 -369.899935) (xy 45.122835 -369.88555)
			(xy 45.14163 -369.877765) (xy 45.151802 -369.87734) (xy 45.868082 -369.87734) (xy 45.878253 -369.877778)
			(xy 45.897047 -369.885558) (xy 45.911433 -369.899939) (xy 45.919218 -369.918731) (xy 45.919644 -369.928902)
			(xy 45.919644 -370.086636) (xy 45.92005 -370.095823) (xy 45.926568 -370.113007) (xy 45.932344 -370.120164)
			(xy 45.95412 -370.145826) (xy 45.992071 -370.20141) (xy 46.023105 -370.261132) (xy 46.046779 -370.324136)
			(xy 46.062754 -370.389517) (xy 46.070799 -370.456339) (xy 46.0708 -370.523643) (xy 46.062757 -370.590465)
			(xy 46.046785 -370.655847) (xy 46.023113 -370.718851) (xy 45.99208 -370.778574) (xy 45.954131 -370.83416)
			(xy 45.932344 -370.859812) (xy 45.926553 -370.866961) (xy 45.920036 -370.884149) (xy 45.919644 -370.89334)
			(xy 45.919644 -371.386862) (xy 45.920085 -371.396046) (xy 45.926578 -371.41323) (xy 45.932344 -371.42039)
			(xy 45.954146 -371.44603) (xy 45.992096 -371.501618) (xy 46.023129 -371.561343) (xy 46.046568 -371.623726)
			(xy 47.14919 -371.623726) (xy 47.149193 -371.556417) (xy 47.157242 -371.489591) (xy 47.17322 -371.424206)
			(xy 47.1969 -371.3612) (xy 47.22794 -371.301475) (xy 47.265897 -371.24589) (xy 47.287688 -371.220238)
			(xy 47.293492 -371.213098) (xy 47.300003 -371.195904) (xy 47.300388 -371.18671) (xy 47.300388 -371.028722)
			(xy 47.300783 -371.018546) (xy 47.30857 -370.999742) (xy 47.322966 -370.985355) (xy 47.341773 -370.977578)
			(xy 47.35195 -370.97716) (xy 48.06823 -370.97716) (xy 48.078392 -370.977609) (xy 48.097167 -370.985398)
			(xy 48.111532 -370.999777) (xy 48.119301 -371.018559) (xy 48.119792 -371.028722) (xy 48.119792 -371.18671)
			(xy 48.120199 -371.195898) (xy 48.126715 -371.213082) (xy 48.132492 -371.220238) (xy 48.154241 -371.245921)
			(xy 48.192189 -371.301504) (xy 48.196948 -371.310662) (xy 53.966364 -371.310662) (xy 53.966364 -370.447062)
			(xy 53.96685 -370.419793) (xy 53.974612 -370.365809) (xy 53.989977 -370.313479) (xy 54.012634 -370.263869)
			(xy 54.04212 -370.217988) (xy 54.077835 -370.176771) (xy 54.119052 -370.141056) (xy 54.164933 -370.11157)
			(xy 54.214543 -370.088913) (xy 54.266873 -370.073548) (xy 54.320857 -370.065786) (xy 54.375395 -370.065786)
			(xy 54.429379 -370.073548) (xy 54.481709 -370.088913) (xy 54.531319 -370.11157) (xy 54.5772 -370.141056)
			(xy 54.618417 -370.176771) (xy 54.654132 -370.217988) (xy 54.683618 -370.263869) (xy 54.706275 -370.313479)
			(xy 54.72164 -370.365809) (xy 54.729402 -370.419793) (xy 54.729888 -370.447062) (xy 54.729888 -371.310662)
			(xy 57.339484 -371.310662) (xy 57.339484 -370.447062) (xy 57.33997 -370.419793) (xy 57.347732 -370.365809)
			(xy 57.363097 -370.313479) (xy 57.385754 -370.263869) (xy 57.41524 -370.217988) (xy 57.450955 -370.176771)
			(xy 57.492172 -370.141056) (xy 57.538053 -370.11157) (xy 57.587663 -370.088913) (xy 57.639993 -370.073548)
			(xy 57.693977 -370.065786) (xy 57.748515 -370.065786) (xy 57.802499 -370.073548) (xy 57.854829 -370.088913)
			(xy 57.904439 -370.11157) (xy 57.95032 -370.141056) (xy 57.991537 -370.176771) (xy 58.027252 -370.217988)
			(xy 58.056738 -370.263869) (xy 58.079395 -370.313479) (xy 58.09476 -370.365809) (xy 58.102522 -370.419793)
			(xy 58.103008 -370.447062) (xy 58.103008 -370.523703) (xy 71.348807 -370.523703) (xy 71.348808 -370.456279)
			(xy 71.356885 -370.38934) (xy 71.372921 -370.32385) (xy 71.396686 -370.260753) (xy 71.427838 -370.200956)
			(xy 71.465928 -370.145321) (xy 71.487792 -370.119656) (xy 71.493589 -370.112511) (xy 71.500104 -370.09532)
			(xy 71.500492 -370.086128) (xy 71.500492 -369.928902) (xy 71.501027 -369.918781) (xy 71.508745 -369.900069)
			(xy 71.523016 -369.885715) (xy 71.541682 -369.877887) (xy 71.5518 -369.87734) (xy 72.26808 -369.87734)
			(xy 72.278238 -369.877739) (xy 72.296998 -369.885535) (xy 72.311323 -369.89994) (xy 72.319016 -369.918742)
			(xy 72.319388 -369.928902) (xy 72.319388 -370.086128) (xy 72.319787 -370.095316) (xy 72.326309 -370.1125)
			(xy 72.332088 -370.119656) (xy 72.353941 -370.145331) (xy 72.39203 -370.200964) (xy 72.423182 -370.260758)
			(xy 72.446948 -370.323854) (xy 72.462984 -370.389342) (xy 72.471061 -370.45628) (xy 72.471063 -370.523644)
			(xy 75.749102 -370.523644) (xy 75.749103 -370.456338) (xy 75.757149 -370.389513) (xy 75.773125 -370.32413)
			(xy 75.796801 -370.261125) (xy 75.827837 -370.201401) (xy 75.86579 -370.145816) (xy 75.88758 -370.120164)
			(xy 75.893372 -370.113015) (xy 75.89989 -370.095828) (xy 75.90028 -370.086636) (xy 75.90028 -369.928902)
			(xy 75.900666 -369.918725) (xy 75.908459 -369.899923) (xy 75.922856 -369.885536) (xy 75.941665 -369.877759)
			(xy 75.951842 -369.87734) (xy 76.668122 -369.87734) (xy 76.678281 -369.877815) (xy 76.697052 -369.885597)
			(xy 76.711416 -369.899969) (xy 76.71919 -369.918742) (xy 76.719684 -369.928902) (xy 76.719684 -370.086636)
			(xy 76.72008 -370.095825) (xy 76.726604 -370.113009) (xy 76.732384 -370.120164) (xy 76.754159 -370.145826)
			(xy 76.792107 -370.201412) (xy 76.82314 -370.261134) (xy 76.846812 -370.324137) (xy 76.862785 -370.389518)
			(xy 76.87083 -370.456339) (xy 76.870831 -370.523643) (xy 76.870824 -370.523703) (xy 80.148895 -370.523703)
			(xy 80.148896 -370.456279) (xy 80.156972 -370.38934) (xy 80.173008 -370.323851) (xy 80.196773 -370.260754)
			(xy 80.227924 -370.200957) (xy 80.266012 -370.145322) (xy 80.287876 -370.119656) (xy 80.293671 -370.112509)
			(xy 80.300187 -370.09532) (xy 80.300576 -370.086128) (xy 80.300576 -369.928902) (xy 80.301029 -369.918771)
			(xy 80.308763 -369.900043) (xy 80.32306 -369.885685) (xy 80.341755 -369.877873) (xy 80.351884 -369.87734)
			(xy 81.068164 -369.87734) (xy 81.078289 -369.877747) (xy 81.096999 -369.88549) (xy 81.111316 -369.899811)
			(xy 81.119056 -369.918523) (xy 81.119472 -369.928648) (xy 81.119472 -370.086128) (xy 81.119875 -370.095316)
			(xy 81.126394 -370.1125) (xy 81.132172 -370.119656) (xy 81.154025 -370.14533) (xy 81.192116 -370.200963)
			(xy 81.223269 -370.260758) (xy 81.247035 -370.323853) (xy 81.263072 -370.389342) (xy 81.271149 -370.456279)
			(xy 81.27115 -370.523703) (xy 84.548686 -370.523703) (xy 84.548687 -370.456279) (xy 84.556763 -370.389341)
			(xy 84.572799 -370.323851) (xy 84.596563 -370.260754) (xy 84.627713 -370.200957) (xy 84.665801 -370.145322)
			(xy 84.687664 -370.119656) (xy 84.69347 -370.112518) (xy 84.699977 -370.095322) (xy 84.700364 -370.086128)
			(xy 84.700364 -369.928902) (xy 84.700829 -369.918772) (xy 84.708561 -369.900047) (xy 84.722854 -369.88569)
			(xy 84.741545 -369.877875) (xy 84.751672 -369.87734) (xy 85.467952 -369.87734) (xy 85.478076 -369.877756)
			(xy 85.496787 -369.885496) (xy 85.511104 -369.899813) (xy 85.518844 -369.918524) (xy 85.51926 -369.928648)
			(xy 85.51926 -370.086128) (xy 85.519666 -370.095315) (xy 85.526183 -370.112499) (xy 85.53196 -370.119656)
			(xy 85.553814 -370.14533) (xy 85.591905 -370.200963) (xy 85.623059 -370.260757) (xy 85.646825 -370.323853)
			(xy 85.662863 -370.389341) (xy 85.67094 -370.456279) (xy 85.670941 -370.523644) (xy 115.349244 -370.523644)
			(xy 115.349245 -370.456338) (xy 115.35729 -370.389516) (xy 115.373263 -370.324133) (xy 115.396936 -370.261128)
			(xy 115.427969 -370.201404) (xy 115.465917 -370.145817) (xy 115.487704 -370.120164) (xy 115.493499 -370.113018)
			(xy 115.500014 -370.095828) (xy 115.500404 -370.086636) (xy 115.500404 -369.928902) (xy 115.500934 -369.918749)
			(xy 115.508702 -369.899986) (xy 115.523056 -369.885622) (xy 115.541813 -369.877841) (xy 115.551966 -369.87734)
			(xy 116.268246 -369.87734) (xy 116.278407 -369.877796) (xy 116.297177 -369.885586) (xy 116.311541 -369.899963)
			(xy 116.319314 -369.918741) (xy 116.319808 -369.928902) (xy 116.319808 -370.086636) (xy 116.320199 -370.095825)
			(xy 116.326726 -370.11301) (xy 116.332508 -370.120164) (xy 116.354286 -370.145825) (xy 116.392238 -370.201409)
			(xy 116.423275 -370.261131) (xy 116.446951 -370.324134) (xy 116.462926 -370.389516) (xy 116.470972 -370.456338)
			(xy 116.470973 -370.523644) (xy 116.470966 -370.523703) (xy 119.749013 -370.523703) (xy 119.749014 -370.456279)
			(xy 119.757091 -370.38934) (xy 119.773128 -370.32385) (xy 119.796893 -370.260752) (xy 119.828045 -370.200956)
			(xy 119.866135 -370.145321) (xy 119.888 -370.119656) (xy 119.893798 -370.112512) (xy 119.900312 -370.09532)
			(xy 119.9007 -370.086128) (xy 119.9007 -369.928902) (xy 119.901227 -369.91878) (xy 119.908947 -369.900067)
			(xy 119.92322 -369.885712) (xy 119.941889 -369.877886) (xy 119.952008 -369.87734) (xy 120.668288 -369.87734)
			(xy 120.678446 -369.877732) (xy 120.697206 -369.885531) (xy 120.711531 -369.899938) (xy 120.719224 -369.918741)
			(xy 120.719596 -369.928902) (xy 120.719596 -370.086128) (xy 120.719993 -370.095317) (xy 120.726516 -370.112501)
			(xy 120.732296 -370.119656) (xy 120.754148 -370.145331) (xy 120.792238 -370.200964) (xy 120.823389 -370.260759)
			(xy 120.847154 -370.323854) (xy 120.863191 -370.389342) (xy 120.871267 -370.45628) (xy 120.871269 -370.523644)
			(xy 124.149308 -370.523644) (xy 124.149309 -370.456338) (xy 124.157355 -370.389513) (xy 124.173331 -370.32413)
			(xy 124.197007 -370.261125) (xy 124.228045 -370.201401) (xy 124.265998 -370.145816) (xy 124.287788 -370.120164)
			(xy 124.293581 -370.113016) (xy 124.300098 -370.095828) (xy 124.300488 -370.086636) (xy 124.300488 -369.928902)
			(xy 124.300867 -369.918724) (xy 124.30866 -369.89992) (xy 124.32306 -369.885533) (xy 124.341872 -369.877757)
			(xy 124.35205 -369.87734) (xy 125.06833 -369.87734) (xy 125.07849 -369.877809) (xy 125.09726 -369.885593)
			(xy 125.111625 -369.899967) (xy 125.119398 -369.918742) (xy 125.119892 -369.928902) (xy 125.119892 -370.086636)
			(xy 125.120286 -370.095825) (xy 125.126811 -370.113009) (xy 125.132592 -370.120164) (xy 125.154367 -370.145826)
			(xy 125.192314 -370.201412) (xy 125.223346 -370.261134) (xy 125.247018 -370.324138) (xy 125.262991 -370.389518)
			(xy 125.271036 -370.456339) (xy 125.271037 -370.523643) (xy 125.271037 -370.523644) (xy 128.549099 -370.523644)
			(xy 128.5491 -370.456338) (xy 128.557146 -370.389514) (xy 128.573121 -370.32413) (xy 128.596797 -370.261125)
			(xy 128.627834 -370.201402) (xy 128.665787 -370.145816) (xy 128.687576 -370.120164) (xy 128.693368 -370.113015)
			(xy 128.699886 -370.095828) (xy 128.700276 -370.086636) (xy 128.700276 -369.928902) (xy 128.700666 -369.918726)
			(xy 128.708458 -369.899924) (xy 128.722854 -369.885538) (xy 128.741661 -369.877759) (xy 128.751838 -369.87734)
			(xy 129.468118 -369.87734) (xy 129.478277 -369.877818) (xy 129.497047 -369.885599) (xy 129.511412 -369.89997)
			(xy 129.519185 -369.918743) (xy 129.51968 -369.928902) (xy 129.51968 -370.086636) (xy 129.520077 -370.095824)
			(xy 129.5266 -370.113008) (xy 129.53238 -370.120164) (xy 129.554155 -370.145826) (xy 129.592103 -370.201412)
			(xy 129.623136 -370.261134) (xy 129.646809 -370.324137) (xy 129.662782 -370.389518) (xy 129.670827 -370.456339)
			(xy 129.670828 -370.523643) (xy 129.670828 -370.523644) (xy 159.349153 -370.523644) (xy 159.349154 -370.456338)
			(xy 159.357199 -370.389515) (xy 159.373173 -370.324133) (xy 159.396846 -370.261128) (xy 159.427879 -370.201404)
			(xy 159.465828 -370.145816) (xy 159.487616 -370.120164) (xy 159.493412 -370.113019) (xy 159.499927 -370.095828)
			(xy 159.500316 -370.086636) (xy 159.500316 -369.928902) (xy 159.500835 -369.918747) (xy 159.508604 -369.899982)
			(xy 159.522962 -369.885618) (xy 159.541723 -369.877839) (xy 159.551878 -369.87734) (xy 160.268158 -369.87734)
			(xy 160.278327 -369.877798) (xy 160.297121 -369.88557) (xy 160.311508 -369.899945) (xy 160.319294 -369.918733)
			(xy 160.31972 -369.928902) (xy 160.31972 -370.086636) (xy 160.320109 -370.095826) (xy 160.326637 -370.11301)
			(xy 160.33242 -370.120164) (xy 160.354197 -370.145825) (xy 160.392149 -370.20141) (xy 160.423185 -370.261131)
			(xy 160.44686 -370.324135) (xy 160.462835 -370.389516) (xy 160.470881 -370.456339) (xy 160.470882 -370.523643)
			(xy 160.470875 -370.523703) (xy 163.748922 -370.523703) (xy 163.748923 -370.456279) (xy 163.757 -370.389339)
			(xy 163.773037 -370.323849) (xy 163.796803 -370.260752) (xy 163.827956 -370.200955) (xy 163.866047 -370.145321)
			(xy 163.887912 -370.119656) (xy 163.893711 -370.112513) (xy 163.900224 -370.095321) (xy 163.900612 -370.086128)
			(xy 163.900612 -369.928902) (xy 163.901127 -369.918779) (xy 163.908849 -369.900063) (xy 163.923126 -369.885708)
			(xy 163.9418 -369.877884) (xy 163.95192 -369.87734) (xy 164.6682 -369.87734) (xy 164.678359 -369.877722)
			(xy 164.697119 -369.885526) (xy 164.711444 -369.899935) (xy 164.719136 -369.918741) (xy 164.719508 -369.928902)
			(xy 164.719508 -370.086128) (xy 164.719903 -370.095317) (xy 164.726427 -370.112501) (xy 164.732208 -370.119656)
			(xy 164.75406 -370.145331) (xy 164.792148 -370.200964) (xy 164.823299 -370.260759) (xy 164.847064 -370.323855)
			(xy 164.8631 -370.389343) (xy 164.871176 -370.45628) (xy 164.871178 -370.523644) (xy 168.149241 -370.523644)
			(xy 168.149242 -370.456338) (xy 168.157287 -370.389516) (xy 168.17326 -370.324133) (xy 168.196933 -370.261128)
			(xy 168.227965 -370.201404) (xy 168.265913 -370.145817) (xy 168.2877 -370.120164) (xy 168.293494 -370.113017)
			(xy 168.30001 -370.095828) (xy 168.3004 -370.086636) (xy 168.3004 -369.928902) (xy 168.300934 -369.918749)
			(xy 168.308701 -369.899987) (xy 168.323054 -369.885623) (xy 168.341809 -369.877842) (xy 168.351962 -369.87734)
			(xy 169.068242 -369.87734) (xy 169.078403 -369.877799) (xy 169.097173 -369.885588) (xy 169.111537 -369.899964)
			(xy 169.11931 -369.918741) (xy 169.119804 -369.928902) (xy 169.119804 -370.086636) (xy 169.120196 -370.095825)
			(xy 169.126722 -370.113009) (xy 169.132504 -370.120164) (xy 169.154279 -370.145826) (xy 169.192225 -370.201412)
			(xy 169.223256 -370.261135) (xy 169.246928 -370.324138) (xy 169.2629 -370.389519) (xy 169.270945 -370.456339)
			(xy 169.270946 -370.523643) (xy 169.270946 -370.523644) (xy 172.549008 -370.523644) (xy 172.549009 -370.456338)
			(xy 172.557055 -370.389513) (xy 172.573031 -370.32413) (xy 172.596707 -370.261125) (xy 172.627745 -370.201401)
			(xy 172.665698 -370.145816) (xy 172.687488 -370.120164) (xy 172.693281 -370.113016) (xy 172.699798 -370.095828)
			(xy 172.700188 -370.086636) (xy 172.700188 -369.928902) (xy 172.700567 -369.918724) (xy 172.70836 -369.89992)
			(xy 172.72276 -369.885533) (xy 172.741572 -369.877757) (xy 172.75175 -369.87734) (xy 173.46803 -369.87734)
			(xy 173.47819 -369.877809) (xy 173.49696 -369.885593) (xy 173.511325 -369.899967) (xy 173.519098 -369.918742)
			(xy 173.519592 -369.928902) (xy 173.519592 -370.086636) (xy 173.519986 -370.095825) (xy 173.526511 -370.113009)
			(xy 173.532292 -370.120164) (xy 173.554067 -370.145826) (xy 173.592014 -370.201412) (xy 173.623046 -370.261134)
			(xy 173.646718 -370.324138) (xy 173.662691 -370.389518) (xy 173.670736 -370.456339) (xy 173.670737 -370.523643)
			(xy 173.662694 -370.590464) (xy 173.646724 -370.655845) (xy 173.623054 -370.718849) (xy 173.592023 -370.778573)
			(xy 173.554078 -370.834159) (xy 173.532292 -370.859812) (xy 173.526507 -370.866965) (xy 173.519986 -370.88415)
			(xy 173.519592 -370.89334) (xy 173.519592 -370.901722) (xy 204.470508 -370.901722) (xy 204.470508 -367.316004)
			(xy 204.470934 -367.305935) (xy 204.478654 -367.287337) (xy 204.485494 -367.279936) (xy 204.682344 -367.083086)
			(xy 204.689733 -367.076232) (xy 204.708341 -367.068521) (xy 204.718412 -367.0681) (xy 208.051146 -367.0681)
			(xy 208.061216 -367.068527) (xy 208.079815 -367.076244) (xy 208.087214 -367.083086) (xy 208.263998 -367.25987)
			(xy 208.270817 -367.267287) (xy 208.278549 -367.285873) (xy 208.278984 -367.295938) (xy 208.278984 -370.103908)
			(xy 208.279552 -370.116248) (xy 208.288818 -370.13912) (xy 208.297018 -370.148358) (xy 208.297526 -370.148866)
			(xy 208.34985 -370.20119) (xy 208.35903 -370.209654) (xy 208.382078 -370.219214) (xy 208.394554 -370.219732)
			(xy 208.738724 -370.219732) (xy 208.748796 -370.220137) (xy 208.767394 -370.227871) (xy 208.774792 -370.234718)
			(xy 209.51444 -370.974366) (xy 209.523615 -370.982837) (xy 209.546667 -370.99239) (xy 209.559144 -370.992908)
			(xy 210.018376 -370.992908) (xy 210.028444 -370.993344) (xy 210.047042 -371.001057) (xy 210.054444 -371.007894)
			(xy 210.21421 -371.16766) (xy 210.221026 -371.175079) (xy 210.228759 -371.193664) (xy 210.229196 -371.203728)
			(xy 210.229196 -371.61724) (xy 210.229798 -371.629697) (xy 210.239356 -371.652707) (xy 210.247738 -371.661944)
			(xy 210.379056 -371.793262) (xy 210.379564 -371.79377) (xy 210.388781 -371.802003) (xy 210.411665 -371.811276)
			(xy 210.424014 -371.811804) (xy 216.605104 -371.811804) (xy 216.617445 -371.811237) (xy 216.640316 -371.801971)
			(xy 216.649554 -371.79377) (xy 216.650062 -371.793262) (xy 217.67927 -370.764054) (xy 217.679778 -370.763546)
			(xy 217.688008 -370.754327) (xy 217.697282 -370.731444) (xy 217.697812 -370.719096) (xy 217.697812 -367.36528)
			(xy 217.698224 -367.355209) (xy 217.705954 -367.336611) (xy 217.712798 -367.329212) (xy 217.96883 -367.073434)
			(xy 217.97623 -367.066593) (xy 217.994829 -367.058873) (xy 218.004898 -367.058448) (xy 221.295214 -367.058448)
			(xy 221.305259 -367.058823) (xy 221.323856 -367.066407) (xy 221.331282 -367.07318) (xy 221.508066 -367.249964)
			(xy 221.514878 -367.257386) (xy 221.522615 -367.275968) (xy 221.523052 -367.286032) (xy 221.523052 -370.745258)
			(xy 221.523577 -370.757603) (xy 221.532871 -370.780476) (xy 221.541086 -370.789708) (xy 221.541594 -370.790216)
			(xy 221.701614 -370.950236) (xy 221.708464 -370.957628) (xy 221.716177 -370.976233) (xy 221.7166 -370.986304)
			(xy 221.7166 -373.574564) (xy 221.71724 -373.587017) (xy 221.726771 -373.610028) (xy 221.735142 -373.619268)
			(xy 223.603312 -375.487438) (xy 223.6125 -375.495892) (xy 223.635542 -375.505456) (xy 223.648016 -375.50598)
			(xy 225.569526 -375.50598) (xy 225.581983 -375.505377) (xy 225.604994 -375.49582) (xy 225.61423 -375.487438)
			(xy 226.890326 -374.211342) (xy 226.890834 -374.210834) (xy 226.899064 -374.201614) (xy 226.90834 -374.178732)
			(xy 226.908868 -374.166384) (xy 226.908868 -372.704106) (xy 226.909279 -372.694035) (xy 226.917008 -372.675436)
			(xy 226.923854 -372.668038) (xy 228.193346 -371.3988) (xy 228.201796 -371.389609) (xy 228.211362 -371.366569)
			(xy 228.211888 -371.354096) (xy 228.211888 -370.983256) (xy 228.212267 -370.973181) (xy 228.220018 -370.954582)
			(xy 228.226874 -370.947188) (xy 228.380798 -370.793264) (xy 228.389257 -370.78408) (xy 228.398819 -370.761035)
			(xy 228.39934 -370.74856) (xy 228.39934 -367.292382) (xy 228.399715 -367.282337) (xy 228.4073 -367.263741)
			(xy 228.414072 -367.256314) (xy 228.600508 -367.069878) (xy 228.607909 -367.063039) (xy 228.626508 -367.055319)
			(xy 228.636576 -367.054892) (xy 231.959912 -367.054892) (xy 231.969985 -367.055287) (xy 231.988584 -367.063026)
			(xy 231.99598 -367.069878) (xy 232.182416 -367.256314) (xy 232.1891 -367.263803) (xy 232.196697 -367.282356)
			(xy 232.197148 -367.292382) (xy 232.197148 -370.755164) (xy 232.197775 -370.767618) (xy 232.207314 -370.79063)
			(xy 232.21569 -370.799868) (xy 232.35031 -370.934234) (xy 232.357159 -370.941627) (xy 232.364873 -370.960232)
			(xy 232.365296 -370.970302) (xy 232.365296 -371.212364) (xy 232.365833 -371.224708) (xy 232.37512 -371.247579)
			(xy 232.38333 -371.256814) (xy 232.383838 -371.257322) (xy 233.100118 -371.973602) (xy 233.106954 -371.981005)
			(xy 233.114675 -371.999602) (xy 233.115104 -372.00967) (xy 233.115104 -375.498868) (xy 233.115741 -375.511321)
			(xy 233.125274 -375.534332) (xy 233.133646 -375.543572) (xy 233.841798 -376.251724) (xy 235.85424 -376.251724)
			(xy 235.85424 -368.653314) (xy 235.854662 -368.643244) (xy 235.862384 -368.624646) (xy 235.869226 -368.617246)
			(xy 236.22889 -368.257582) (xy 236.236297 -368.250752) (xy 236.254891 -368.243027) (xy 236.264958 -368.242596)
			(xy 242.047014 -368.242596) (xy 242.057087 -368.242989) (xy 242.075686 -368.25073) (xy 242.083082 -368.257582)
			(xy 242.35029 -368.52479) (xy 242.357117 -368.532201) (xy 242.364845 -368.550792) (xy 242.365276 -368.560858)
			(xy 242.365276 -376.144028) (xy 242.364736 -376.155236) (xy 242.355238 -376.175537) (xy 242.346988 -376.183144)
			(xy 242.273836 -376.244104) (xy 242.269772 -376.247914) (xy 241.986816 -376.53087) (xy 241.986562 -376.531124)
			(xy 241.978942 -376.540522) (xy 241.91849 -376.631454) (xy 241.910997 -376.641545) (xy 241.888878 -376.653411)
			(xy 241.876326 -376.65406) (xy 236.25683 -376.65406) (xy 236.246761 -376.653629) (xy 236.228163 -376.645913)
			(xy 236.220762 -376.639074) (xy 235.869226 -376.287792) (xy 235.862394 -376.280386) (xy 235.854669 -376.261791)
			(xy 235.85424 -376.251724) (xy 233.841798 -376.251724) (xy 234.964478 -377.374404) (xy 242.49126 -377.374404)
			(xy 242.49126 -368.547142) (xy 242.491691 -368.537073) (xy 242.499406 -368.518474) (xy 242.506246 -368.511074)
			(xy 242.759738 -368.257582) (xy 242.767129 -368.25073) (xy 242.785735 -368.243018) (xy 242.795806 -368.242596)
			(xy 265.583924 -368.242596) (xy 265.593998 -368.242984) (xy 265.612597 -368.250728) (xy 265.619992 -368.257582)
			(xy 266.105894 -368.743484) (xy 266.112719 -368.750896) (xy 266.120448 -368.769486) (xy 266.12088 -368.779552)
			(xy 266.12088 -370.523704) (xy 286.928752 -370.523704) (xy 286.928753 -370.456278) (xy 286.936831 -370.389338)
			(xy 286.952869 -370.323848) (xy 286.976637 -370.26075) (xy 287.007792 -370.200954) (xy 287.045885 -370.14532)
			(xy 287.067752 -370.119656) (xy 287.073556 -370.112516) (xy 287.080065 -370.095321) (xy 287.080452 -370.086128)
			(xy 287.080452 -369.928902) (xy 287.080929 -369.918774) (xy 287.088658 -369.900051) (xy 287.102947 -369.885694)
			(xy 287.121634 -369.877877) (xy 287.13176 -369.87734) (xy 287.84804 -369.87734) (xy 287.85817 -369.877684)
			(xy 287.876882 -369.885453) (xy 287.891196 -369.899792) (xy 287.898933 -369.918517) (xy 287.899348 -369.928648)
			(xy 287.899348 -370.086128) (xy 287.899756 -370.095315) (xy 287.906273 -370.112499) (xy 287.912048 -370.119656)
			(xy 287.933902 -370.14533) (xy 287.971994 -370.200962) (xy 288.003149 -370.260757) (xy 288.026916 -370.323852)
			(xy 288.042954 -370.389341) (xy 288.051031 -370.456279) (xy 288.051032 -370.523644) (xy 291.329071 -370.523644)
			(xy 291.329073 -370.456338) (xy 291.337118 -370.389515) (xy 291.353092 -370.324132) (xy 291.376766 -370.261127)
			(xy 291.407801 -370.201403) (xy 291.445751 -370.145816) (xy 291.46754 -370.120164) (xy 291.473339 -370.113021)
			(xy 291.479851 -370.095829) (xy 291.48024 -370.086636) (xy 291.48024 -369.928902) (xy 291.480665 -369.91873)
			(xy 291.48845 -369.899935) (xy 291.502835 -369.88555) (xy 291.52163 -369.877765) (xy 291.531802 -369.87734)
			(xy 292.248082 -369.87734) (xy 292.258253 -369.877778) (xy 292.277047 -369.885558) (xy 292.291433 -369.899939)
			(xy 292.299218 -369.918731) (xy 292.299644 -369.928902) (xy 292.299644 -370.086636) (xy 292.30005 -370.095823)
			(xy 292.306568 -370.113007) (xy 292.312344 -370.120164) (xy 292.33412 -370.145826) (xy 292.372071 -370.20141)
			(xy 292.403105 -370.261132) (xy 292.426779 -370.324136) (xy 292.442754 -370.389517) (xy 292.450799 -370.456339)
			(xy 292.4508 -370.523643) (xy 292.450793 -370.523704) (xy 295.72884 -370.523704) (xy 295.728841 -370.456278)
			(xy 295.736918 -370.389339) (xy 295.752956 -370.323848) (xy 295.776723 -370.260751) (xy 295.807878 -370.200955)
			(xy 295.84597 -370.145321) (xy 295.867836 -370.119656) (xy 295.873638 -370.112515) (xy 295.880149 -370.095321)
			(xy 295.880536 -370.086128) (xy 295.880536 -369.928902) (xy 295.881028 -369.918776) (xy 295.888755 -369.900056)
			(xy 295.903039 -369.885699) (xy 295.92172 -369.877879) (xy 295.931844 -369.87734) (xy 296.648124 -369.87734)
			(xy 296.658285 -369.877703) (xy 296.677045 -369.885514) (xy 296.691369 -369.899929) (xy 296.699061 -369.918739)
			(xy 296.699432 -369.928902) (xy 296.699432 -370.086128) (xy 296.699844 -370.095315) (xy 296.706358 -370.112498)
			(xy 296.712132 -370.119656) (xy 296.733983 -370.145332) (xy 296.77207 -370.200965) (xy 296.803219 -370.26076)
			(xy 296.826983 -370.323856) (xy 296.843018 -370.389343) (xy 296.851095 -370.45628) (xy 296.851096 -370.523702)
			(xy 296.851096 -370.523704) (xy 300.128631 -370.523704) (xy 300.128632 -370.456278) (xy 300.136709 -370.389339)
			(xy 300.152747 -370.323849) (xy 300.176513 -370.260751) (xy 300.207667 -370.200955) (xy 300.245758 -370.145321)
			(xy 300.267624 -370.119656) (xy 300.273425 -370.112514) (xy 300.279936 -370.095321) (xy 300.280324 -370.086128)
			(xy 300.280324 -369.928902) (xy 300.280828 -369.918777) (xy 300.288552 -369.900059) (xy 300.302833 -369.885704)
			(xy 300.32151 -369.877882) (xy 300.331632 -369.87734) (xy 301.047912 -369.87734) (xy 301.058072 -369.877712)
			(xy 301.076832 -369.885519) (xy 301.091157 -369.899932) (xy 301.098849 -369.91874) (xy 301.09922 -369.928902)
			(xy 301.09922 -370.086128) (xy 301.099612 -370.095317) (xy 301.106138 -370.112502) (xy 301.11192 -370.119656)
			(xy 301.133771 -370.145331) (xy 301.171859 -370.200965) (xy 301.203009 -370.26076) (xy 301.226773 -370.323855)
			(xy 301.242809 -370.389343) (xy 301.250886 -370.45628) (xy 301.250887 -370.523644) (xy 330.92919 -370.523644)
			(xy 330.929191 -370.456338) (xy 330.937237 -370.389514) (xy 330.953212 -370.324131) (xy 330.976887 -370.261126)
			(xy 331.007923 -370.201402) (xy 331.045875 -370.145816) (xy 331.067664 -370.120164) (xy 331.073466 -370.113023)
			(xy 331.079976 -370.095829) (xy 331.080364 -370.086636) (xy 331.080364 -369.928902) (xy 331.080766 -369.918727)
			(xy 331.088555 -369.899928) (xy 331.102948 -369.885542) (xy 331.121751 -369.877761) (xy 331.131926 -369.87734)
			(xy 331.848206 -369.87734) (xy 331.858364 -369.877829) (xy 331.877134 -369.885605) (xy 331.891499 -369.899973)
			(xy 331.899273 -369.918744) (xy 331.899768 -369.928902) (xy 331.899768 -370.086636) (xy 331.900168 -370.095824)
			(xy 331.90669 -370.113008) (xy 331.912468 -370.120164) (xy 331.934244 -370.145826) (xy 331.972193 -370.201411)
			(xy 332.003226 -370.261133) (xy 332.026899 -370.324137) (xy 332.042873 -370.389518) (xy 332.050918 -370.456339)
			(xy 332.050919 -370.523643) (xy 332.050912 -370.523703) (xy 335.328983 -370.523703) (xy 335.328984 -370.456279)
			(xy 335.33706 -370.389341) (xy 335.353096 -370.323852) (xy 335.376859 -370.260754) (xy 335.408009 -370.200957)
			(xy 335.446097 -370.145322) (xy 335.46796 -370.119656) (xy 335.473765 -370.112517) (xy 335.480273 -370.095322)
			(xy 335.48066 -370.086128) (xy 335.48066 -369.928902) (xy 335.481129 -369.918773) (xy 335.48886 -369.900048)
			(xy 335.503152 -369.885691) (xy 335.521841 -369.877875) (xy 335.531968 -369.87734) (xy 336.248248 -369.87734)
			(xy 336.25841 -369.877683) (xy 336.277171 -369.885502) (xy 336.291494 -369.899923) (xy 336.299185 -369.918737)
			(xy 336.299556 -369.928902) (xy 336.299556 -370.086128) (xy 336.299963 -370.095315) (xy 336.30648 -370.112499)
			(xy 336.312256 -370.119656) (xy 336.33411 -370.14533) (xy 336.372202 -370.200962) (xy 336.403355 -370.260757)
			(xy 336.427122 -370.323853) (xy 336.44316 -370.389341) (xy 336.451237 -370.456279) (xy 336.451238 -370.523644)
			(xy 339.729277 -370.523644) (xy 339.729279 -370.456338) (xy 339.737324 -370.389514) (xy 339.753299 -370.324131)
			(xy 339.776973 -370.261126) (xy 339.808008 -370.201402) (xy 339.845959 -370.145816) (xy 339.867748 -370.120164)
			(xy 339.873548 -370.113022) (xy 339.880059 -370.095829) (xy 339.880448 -370.086636) (xy 339.880448 -369.928902)
			(xy 339.880866 -369.918729) (xy 339.888652 -369.899933) (xy 339.903039 -369.885547) (xy 339.921837 -369.877764)
			(xy 339.93201 -369.87734) (xy 340.64829 -369.87734) (xy 340.658461 -369.877772) (xy 340.677256 -369.885554)
			(xy 340.691641 -369.899937) (xy 340.699426 -369.918731) (xy 340.699852 -369.928902) (xy 340.699852 -370.086636)
			(xy 340.700256 -370.095824) (xy 340.706775 -370.113007) (xy 340.712552 -370.120164) (xy 340.734328 -370.145826)
			(xy 340.772278 -370.201411) (xy 340.803312 -370.261133) (xy 340.826986 -370.324136) (xy 340.84296 -370.389517)
			(xy 340.851005 -370.456339) (xy 340.851006 -370.523643) (xy 340.851006 -370.523644) (xy 344.129068 -370.523644)
			(xy 344.129069 -370.456338) (xy 344.137115 -370.389515) (xy 344.153089 -370.324132) (xy 344.176763 -370.261127)
			(xy 344.207797 -370.201403) (xy 344.245748 -370.145816) (xy 344.267536 -370.120164) (xy 344.273335 -370.113021)
			(xy 344.279847 -370.095829) (xy 344.280236 -370.086636) (xy 344.280236 -369.928902) (xy 344.280735 -369.918745)
			(xy 344.288508 -369.899976) (xy 344.302873 -369.885611) (xy 344.321641 -369.877836) (xy 344.331798 -369.87734)
			(xy 345.048078 -369.87734) (xy 345.058248 -369.877782) (xy 345.077043 -369.88556) (xy 345.091429 -369.89994)
			(xy 345.099214 -369.918732) (xy 345.09964 -369.928902) (xy 345.09964 -370.086636) (xy 345.100046 -370.095823)
			(xy 345.106564 -370.113007) (xy 345.11234 -370.120164) (xy 345.134116 -370.145826) (xy 345.172067 -370.20141)
			(xy 345.203102 -370.261132) (xy 345.226776 -370.324136) (xy 345.242751 -370.389517) (xy 345.250796 -370.456339)
			(xy 345.250797 -370.523643) (xy 345.250797 -370.523644) (xy 374.929099 -370.523644) (xy 374.9291 -370.456338)
			(xy 374.937146 -370.389514) (xy 374.953121 -370.32413) (xy 374.976797 -370.261125) (xy 375.007834 -370.201402)
			(xy 375.045787 -370.145816) (xy 375.067576 -370.120164) (xy 375.073368 -370.113015) (xy 375.079886 -370.095828)
			(xy 375.080276 -370.086636) (xy 375.080276 -369.928902) (xy 375.080666 -369.918726) (xy 375.088458 -369.899924)
			(xy 375.102854 -369.885538) (xy 375.121661 -369.877759) (xy 375.131838 -369.87734) (xy 375.848118 -369.87734)
			(xy 375.858277 -369.877818) (xy 375.877047 -369.885599) (xy 375.891412 -369.89997) (xy 375.899185 -369.918743)
			(xy 375.89968 -369.928902) (xy 375.89968 -370.086636) (xy 375.900077 -370.095824) (xy 375.9066 -370.113008)
			(xy 375.91238 -370.120164) (xy 375.934155 -370.145826) (xy 375.972103 -370.201412) (xy 376.003136 -370.261134)
			(xy 376.026809 -370.324137) (xy 376.042782 -370.389518) (xy 376.050827 -370.456339) (xy 376.050828 -370.523643)
			(xy 376.050821 -370.523703) (xy 379.328892 -370.523703) (xy 379.328893 -370.456279) (xy 379.336969 -370.38934)
			(xy 379.353005 -370.323851) (xy 379.376769 -370.260754) (xy 379.40792 -370.200957) (xy 379.446008 -370.145322)
			(xy 379.467872 -370.119656) (xy 379.473678 -370.112518) (xy 379.480185 -370.095322) (xy 379.480572 -370.086128)
			(xy 379.480572 -369.928902) (xy 379.481029 -369.918772) (xy 379.488762 -369.900044) (xy 379.503058 -369.885687)
			(xy 379.521752 -369.877873) (xy 379.53188 -369.87734) (xy 380.24816 -369.87734) (xy 380.258316 -369.877755)
			(xy 380.277076 -369.885545) (xy 380.291402 -369.899945) (xy 380.299096 -369.918743) (xy 380.299468 -369.928902)
			(xy 380.299468 -370.086128) (xy 380.299872 -370.095316) (xy 380.306391 -370.1125) (xy 380.312168 -370.119656)
			(xy 380.334021 -370.14533) (xy 380.372112 -370.200963) (xy 380.403265 -370.260758) (xy 380.427032 -370.323853)
			(xy 380.443069 -370.389342) (xy 380.451146 -370.456279) (xy 380.451147 -370.523644) (xy 383.729187 -370.523644)
			(xy 383.729188 -370.456338) (xy 383.737234 -370.389514) (xy 383.753209 -370.324131) (xy 383.776884 -370.261126)
			(xy 383.807919 -370.201402) (xy 383.845871 -370.145816) (xy 383.86766 -370.120164) (xy 383.873462 -370.113023)
			(xy 383.879972 -370.095829) (xy 383.88036 -370.086636) (xy 383.88036 -369.928902) (xy 383.880766 -369.918728)
			(xy 383.888554 -369.899929) (xy 383.902946 -369.885543) (xy 383.921748 -369.877762) (xy 383.931922 -369.87734)
			(xy 384.648202 -369.87734) (xy 384.65836 -369.877832) (xy 384.67713 -369.885607) (xy 384.691495 -369.899974)
			(xy 384.699269 -369.918744) (xy 384.699764 -369.928902) (xy 384.699764 -370.086636) (xy 384.700165 -370.095824)
			(xy 384.706686 -370.113008) (xy 384.712464 -370.120164) (xy 384.73424 -370.145826) (xy 384.772189 -370.201411)
			(xy 384.803222 -370.261133) (xy 384.826895 -370.324137) (xy 384.842869 -370.389518) (xy 384.850914 -370.456339)
			(xy 384.850915 -370.523643) (xy 384.850915 -370.523644) (xy 388.128977 -370.523644) (xy 388.128979 -370.456338)
			(xy 388.137024 -370.389514) (xy 388.152999 -370.324131) (xy 388.176673 -370.261126) (xy 388.207708 -370.201402)
			(xy 388.245659 -370.145816) (xy 388.267448 -370.120164) (xy 388.273248 -370.113022) (xy 388.279759 -370.095829)
			(xy 388.280148 -370.086636) (xy 388.280148 -369.928902) (xy 388.280566 -369.918729) (xy 388.288352 -369.899933)
			(xy 388.302739 -369.885547) (xy 388.321537 -369.877764) (xy 388.33171 -369.87734) (xy 389.04799 -369.87734)
			(xy 389.058161 -369.877772) (xy 389.076956 -369.885554) (xy 389.091341 -369.899937) (xy 389.099126 -369.918731)
			(xy 389.099552 -369.928902) (xy 389.099552 -370.086636) (xy 389.099956 -370.095824) (xy 389.106475 -370.113007)
			(xy 389.112252 -370.120164) (xy 389.134028 -370.145826) (xy 389.171978 -370.201411) (xy 389.203012 -370.261133)
			(xy 389.226686 -370.324136) (xy 389.24266 -370.389517) (xy 389.250705 -370.456339) (xy 389.250706 -370.523643)
			(xy 389.250706 -370.523644) (xy 418.929008 -370.523644) (xy 418.929009 -370.456338) (xy 418.937055 -370.389513)
			(xy 418.953031 -370.32413) (xy 418.976707 -370.261125) (xy 419.007745 -370.201401) (xy 419.045698 -370.145816)
			(xy 419.067488 -370.120164) (xy 419.073281 -370.113016) (xy 419.079798 -370.095828) (xy 419.080188 -370.086636)
			(xy 419.080188 -369.928902) (xy 419.080567 -369.918724) (xy 419.08836 -369.89992) (xy 419.10276 -369.885533)
			(xy 419.121572 -369.877757) (xy 419.13175 -369.87734) (xy 419.84803 -369.87734) (xy 419.85819 -369.877809)
			(xy 419.87696 -369.885593) (xy 419.891325 -369.899967) (xy 419.899098 -369.918742) (xy 419.899592 -369.928902)
			(xy 419.899592 -370.086636) (xy 419.899986 -370.095825) (xy 419.906511 -370.113009) (xy 419.912292 -370.120164)
			(xy 419.934067 -370.145826) (xy 419.972014 -370.201412) (xy 420.003046 -370.261134) (xy 420.026718 -370.324138)
			(xy 420.042691 -370.389518) (xy 420.050736 -370.456339) (xy 420.050737 -370.523643) (xy 420.05073 -370.523703)
			(xy 423.328801 -370.523703) (xy 423.328802 -370.456279) (xy 423.336878 -370.38934) (xy 423.352915 -370.323851)
			(xy 423.37668 -370.260753) (xy 423.407831 -370.200957) (xy 423.44592 -370.145322) (xy 423.467784 -370.119656)
			(xy 423.47358 -370.11251) (xy 423.480095 -370.09532) (xy 423.480484 -370.086128) (xy 423.480484 -369.928902)
			(xy 423.48093 -369.91877) (xy 423.488665 -369.900041) (xy 423.502964 -369.885683) (xy 423.521662 -369.877871)
			(xy 423.531792 -369.87734) (xy 424.248072 -369.87734) (xy 424.258198 -369.87774) (xy 424.276908 -369.885486)
			(xy 424.291225 -369.899808) (xy 424.298964 -369.918522) (xy 424.29938 -369.928648) (xy 424.29938 -370.086128)
			(xy 424.299781 -370.095316) (xy 424.306302 -370.1125) (xy 424.31208 -370.119656) (xy 424.333933 -370.145331)
			(xy 424.372023 -370.200963) (xy 424.403176 -370.260758) (xy 424.426941 -370.323854) (xy 424.442978 -370.389342)
			(xy 424.451055 -370.456279) (xy 424.451056 -370.523644) (xy 427.729096 -370.523644) (xy 427.729097 -370.456338)
			(xy 427.737143 -370.389514) (xy 427.753118 -370.32413) (xy 427.776794 -370.261125) (xy 427.80783 -370.201402)
			(xy 427.845783 -370.145816) (xy 427.867572 -370.120164) (xy 427.873375 -370.113024) (xy 427.879884 -370.095829)
			(xy 427.880272 -370.086636) (xy 427.880272 -369.928902) (xy 427.880666 -369.918726) (xy 427.888457 -369.899925)
			(xy 427.902852 -369.885539) (xy 427.921658 -369.87776) (xy 427.931834 -369.87734) (xy 428.648114 -369.87734)
			(xy 428.658273 -369.877822) (xy 428.677043 -369.885602) (xy 428.691407 -369.899971) (xy 428.699181 -369.918743)
			(xy 428.699676 -369.928902) (xy 428.699676 -370.086636) (xy 428.700074 -370.095824) (xy 428.706597 -370.113008)
			(xy 428.712376 -370.120164) (xy 428.734152 -370.145826) (xy 428.7721 -370.201411) (xy 428.803133 -370.261134)
			(xy 428.826806 -370.324137) (xy 428.842779 -370.389518) (xy 428.850824 -370.456339) (xy 428.850825 -370.523643)
			(xy 428.850825 -370.523644) (xy 432.128887 -370.523644) (xy 432.128888 -370.456338) (xy 432.136934 -370.389514)
			(xy 432.152909 -370.324131) (xy 432.176584 -370.261126) (xy 432.207619 -370.201402) (xy 432.245571 -370.145816)
			(xy 432.26736 -370.120164) (xy 432.273162 -370.113023) (xy 432.279672 -370.095829) (xy 432.28006 -370.086636)
			(xy 432.28006 -369.928902) (xy 432.280466 -369.918728) (xy 432.288254 -369.899929) (xy 432.302646 -369.885543)
			(xy 432.321448 -369.877762) (xy 432.331622 -369.87734) (xy 433.047902 -369.87734) (xy 433.05806 -369.877832)
			(xy 433.07683 -369.885607) (xy 433.091195 -369.899974) (xy 433.098969 -369.918744) (xy 433.099464 -369.928902)
			(xy 433.099464 -370.086636) (xy 433.099865 -370.095824) (xy 433.106386 -370.113008) (xy 433.112164 -370.120164)
			(xy 433.13394 -370.145826) (xy 433.171889 -370.201411) (xy 433.202922 -370.261133) (xy 433.226595 -370.324137)
			(xy 433.242569 -370.389518) (xy 433.250614 -370.456339) (xy 433.250615 -370.523643) (xy 433.242572 -370.590465)
			(xy 433.226601 -370.655846) (xy 433.20293 -370.71885) (xy 433.171898 -370.778573) (xy 433.133951 -370.83416)
			(xy 433.112164 -370.859812) (xy 433.106375 -370.866963) (xy 433.099857 -370.884149) (xy 433.099464 -370.89334)
			(xy 433.099464 -371.386862) (xy 433.099901 -371.396046) (xy 433.106397 -371.41323) (xy 433.112164 -371.42039)
			(xy 433.133966 -371.446031) (xy 433.171914 -371.501619) (xy 433.202946 -371.561344) (xy 433.226383 -371.623725)
			(xy 434.329029 -371.623725) (xy 434.329032 -371.556418) (xy 434.33708 -371.489593) (xy 434.353056 -371.424209)
			(xy 434.376732 -371.361203) (xy 434.407768 -371.301478) (xy 434.445719 -371.245891) (xy 434.467508 -371.220238)
			(xy 434.473314 -371.2131) (xy 434.479823 -371.195904) (xy 434.480208 -371.18671) (xy 434.480208 -371.028722)
			(xy 434.48075 -371.018569) (xy 434.488512 -370.999806) (xy 434.502863 -370.985441) (xy 434.521618 -370.977661)
			(xy 434.53177 -370.97716) (xy 435.24805 -370.97716) (xy 435.258221 -370.977605) (xy 435.277019 -370.985378)
			(xy 435.291406 -370.999758) (xy 435.299189 -371.018551) (xy 435.299612 -371.028722) (xy 435.299612 -371.18671)
			(xy 435.300015 -371.195898) (xy 435.306533 -371.213082) (xy 435.312312 -371.220238) (xy 435.334064 -371.24592)
			(xy 435.372017 -371.301501) (xy 435.403055 -371.36122) (xy 435.426732 -371.424221) (xy 435.442709 -371.4896)
			(xy 435.450757 -371.55642) (xy 435.45076 -371.623723) (xy 435.442719 -371.690544) (xy 435.426749 -371.755924)
			(xy 435.403078 -371.818928) (xy 435.372046 -371.87865) (xy 435.334099 -371.934235) (xy 435.312312 -371.959886)
			(xy 435.306498 -371.967019) (xy 435.299993 -371.984219) (xy 435.299612 -371.993414) (xy 435.299612 -372.486682)
			(xy 435.300028 -372.495869) (xy 435.306537 -372.513053) (xy 435.312312 -372.52021) (xy 435.334135 -372.545834)
			(xy 435.372086 -372.601423) (xy 435.40312 -372.66115) (xy 435.426793 -372.724159) (xy 435.442765 -372.789545)
			(xy 435.450807 -372.856371) (xy 435.450804 -372.92368) (xy 435.442756 -372.990506) (xy 435.426778 -373.05589)
			(xy 435.403099 -373.118896) (xy 435.372059 -373.178621) (xy 435.334103 -373.234206) (xy 435.312312 -373.259858)
			(xy 435.30651 -373.266999) (xy 435.299998 -373.284193) (xy 435.299612 -373.293386) (xy 435.299612 -373.451374)
			(xy 435.299213 -373.46155) (xy 435.291428 -373.480354) (xy 435.277034 -373.494741) (xy 435.258226 -373.502518)
			(xy 435.24805 -373.502936) (xy 434.53177 -373.502936) (xy 434.521607 -373.502491) (xy 434.502832 -373.494701)
			(xy 434.488467 -373.480321) (xy 434.480698 -373.461537) (xy 434.480208 -373.451374) (xy 434.480208 -373.293386)
			(xy 434.479803 -373.284198) (xy 434.473286 -373.267014) (xy 434.467508 -373.259858) (xy 434.445755 -373.234178)
			(xy 434.407807 -373.178595) (xy 434.376774 -373.118875) (xy 434.3531 -373.055874) (xy 434.337126 -372.990495)
			(xy 434.32908 -372.923676) (xy 434.329077 -372.856375) (xy 434.337117 -372.789555) (xy 434.353085 -372.724175)
			(xy 434.376753 -372.661172) (xy 434.40778 -372.601449) (xy 434.445723 -372.545863) (xy 434.467508 -372.52021)
			(xy 434.473326 -372.51308) (xy 434.479828 -372.495878) (xy 434.480208 -372.486682) (xy 434.480208 -371.993414)
			(xy 434.479789 -371.984228) (xy 434.473281 -371.967043) (xy 434.467508 -371.959886) (xy 434.445684 -371.934264)
			(xy 434.407738 -371.878673) (xy 434.376708 -371.818945) (xy 434.353039 -371.755936) (xy 434.33707 -371.690551)
			(xy 434.329029 -371.623725) (xy 433.226383 -371.623725) (xy 433.226618 -371.62435) (xy 433.24259 -371.689734)
			(xy 433.250633 -371.756557) (xy 433.250632 -371.823864) (xy 433.242586 -371.890687) (xy 433.226612 -371.95607)
			(xy 433.202938 -372.019075) (xy 433.171903 -372.078799) (xy 433.133953 -372.134386) (xy 433.112164 -372.160038)
			(xy 433.106364 -372.167181) (xy 433.099852 -372.184373) (xy 433.099464 -372.193566) (xy 433.099464 -372.351554)
			(xy 433.098999 -372.361722) (xy 433.091229 -372.380516) (xy 433.076856 -372.394902) (xy 433.05807 -372.402689)
			(xy 433.047902 -372.403116) (xy 432.331622 -372.403116) (xy 432.321446 -372.402717) (xy 432.302643 -372.394931)
			(xy 432.288256 -372.380537) (xy 432.280478 -372.36173) (xy 432.28006 -372.351554) (xy 432.28006 -372.193566)
			(xy 432.279653 -372.184379) (xy 432.273135 -372.167195) (xy 432.26736 -372.160038) (xy 432.245586 -372.134375)
			(xy 432.207635 -372.07879) (xy 432.1766 -372.019069) (xy 432.152925 -371.956065) (xy 432.136951 -371.890684)
			(xy 432.128905 -371.823863) (xy 432.128904 -371.756558) (xy 432.136947 -371.689736) (xy 432.152919 -371.624355)
			(xy 432.176591 -371.561351) (xy 432.207624 -371.501628) (xy 432.245573 -371.446042) (xy 432.26736 -371.42039)
			(xy 432.273151 -371.413241) (xy 432.279667 -371.396053) (xy 432.28006 -371.386862) (xy 432.28006 -370.89334)
			(xy 432.279617 -370.884157) (xy 432.273125 -370.866972) (xy 432.26736 -370.859812) (xy 432.24556 -370.83417)
			(xy 432.20761 -370.778582) (xy 432.176576 -370.718858) (xy 432.152903 -370.655852) (xy 432.136931 -370.590468)
			(xy 432.128887 -370.523644) (xy 428.850825 -370.523644) (xy 428.842782 -370.590464) (xy 428.826811 -370.655846)
			(xy 428.80314 -370.71885) (xy 428.772109 -370.778573) (xy 428.734163 -370.83416) (xy 428.712376 -370.859812)
			(xy 428.706589 -370.866964) (xy 428.700069 -370.884149) (xy 428.699676 -370.89334) (xy 428.699676 -371.386862)
			(xy 428.70011 -371.396047) (xy 428.706608 -371.413231) (xy 428.712376 -371.42039) (xy 428.734177 -371.446031)
			(xy 428.772125 -371.501619) (xy 428.803156 -371.561345) (xy 428.826615 -371.623785) (xy 429.928709 -371.623785)
			(xy 429.928713 -371.556358) (xy 429.936793 -371.489417) (xy 429.952833 -371.423925) (xy 429.976602 -371.360827)
			(xy 430.007759 -371.30103) (xy 430.045853 -371.245395) (xy 430.06772 -371.21973) (xy 430.073531 -371.212595)
			(xy 430.080036 -371.195397) (xy 430.08042 -371.186202) (xy 430.08042 -371.028722) (xy 430.080944 -371.018599)
			(xy 430.088661 -370.999882) (xy 430.102935 -370.985526) (xy 430.121608 -370.977702) (xy 430.131728 -370.97716)
			(xy 430.848008 -370.97716) (xy 430.858158 -370.977614) (xy 430.876902 -370.985405) (xy 430.891224 -370.999791)
			(xy 430.898931 -371.018571) (xy 430.899316 -371.028722) (xy 430.899316 -371.186202) (xy 430.899722 -371.19539)
			(xy 430.906238 -371.212574) (xy 430.912016 -371.21973) (xy 430.933842 -371.245426) (xy 430.971931 -371.301057)
			(xy 431.003082 -371.360849) (xy 431.026848 -371.423942) (xy 431.042886 -371.489427) (xy 431.050964 -371.556361)
			(xy 431.050968 -371.623782) (xy 431.042896 -371.690717) (xy 431.026865 -371.756204) (xy 431.003106 -371.819299)
			(xy 430.97196 -371.879094) (xy 430.933877 -371.934729) (xy 430.912016 -371.960394) (xy 430.906241 -371.967555)
			(xy 430.899713 -371.984733) (xy 430.899316 -371.993922) (xy 430.899316 -372.486174) (xy 430.899735 -372.49536)
			(xy 430.906242 -372.512545) (xy 430.912016 -372.519702) (xy 430.933913 -372.54534) (xy 430.971999 -372.600979)
			(xy 431.003148 -372.660779) (xy 431.026909 -372.723879) (xy 431.042942 -372.789371) (xy 431.051015 -372.856313)
			(xy 431.051012 -372.923739) (xy 431.042933 -372.990679) (xy 431.026894 -373.05617) (xy 431.003127 -373.119268)
			(xy 430.971973 -373.179065) (xy 430.933881 -373.2347) (xy 430.912016 -373.260366) (xy 430.906211 -373.267505)
			(xy 430.899701 -373.2847) (xy 430.899316 -373.293894) (xy 430.899316 -373.451374) (xy 430.898851 -373.461504)
			(xy 430.891124 -373.480233) (xy 430.87683 -373.494592) (xy 430.858136 -373.502405) (xy 430.848008 -373.502936)
			(xy 430.131728 -373.502936) (xy 430.12158 -373.502456) (xy 430.102835 -373.494677) (xy 430.088512 -373.480298)
			(xy 430.080805 -373.461523) (xy 430.08042 -373.451374) (xy 430.08042 -373.293894) (xy 430.080008 -373.284707)
			(xy 430.073495 -373.267523) (xy 430.06772 -373.260366) (xy 430.045889 -373.234674) (xy 430.007798 -373.179043)
			(xy 429.976644 -373.119251) (xy 429.952877 -373.056158) (xy 429.936839 -372.990672) (xy 429.92876 -372.923736)
			(xy 429.928757 -372.856315) (xy 429.93683 -372.789379) (xy 429.952862 -372.723891) (xy 429.976624 -372.660796)
			(xy 430.007771 -372.601) (xy 430.045857 -372.545367) (xy 430.06772 -372.519702) (xy 430.073501 -372.512546)
			(xy 430.080024 -372.495364) (xy 430.08042 -372.486174) (xy 430.08042 -371.993922) (xy 430.079995 -371.984737)
			(xy 430.073491 -371.967552) (xy 430.06772 -371.960394) (xy 430.045818 -371.93476) (xy 430.007729 -371.879121)
			(xy 429.976579 -371.819321) (xy 429.952816 -371.75622) (xy 429.936783 -371.690727) (xy 429.928709 -371.623785)
			(xy 428.826615 -371.623785) (xy 428.826828 -371.624351) (xy 428.842799 -371.689734) (xy 428.850842 -371.756558)
			(xy 428.850841 -371.823863) (xy 428.842795 -371.890687) (xy 428.826821 -371.95607) (xy 428.803148 -372.019075)
			(xy 428.772114 -372.078799) (xy 428.734164 -372.134386) (xy 428.712376 -372.160038) (xy 428.706578 -372.167182)
			(xy 428.700065 -372.184374) (xy 428.699676 -372.193566) (xy 428.699676 -372.351554) (xy 428.699199 -372.361721)
			(xy 428.691432 -372.380512) (xy 428.677062 -372.394898) (xy 428.65828 -372.402687) (xy 428.648114 -372.403116)
			(xy 427.931834 -372.403116) (xy 427.921659 -372.402707) (xy 427.902856 -372.394925) (xy 427.888469 -372.380534)
			(xy 427.880691 -372.361729) (xy 427.880272 -372.351554) (xy 427.880272 -372.193566) (xy 427.879884 -372.184376)
			(xy 427.873356 -372.167192) (xy 427.867572 -372.160038) (xy 427.845797 -372.134375) (xy 427.807846 -372.078791)
			(xy 427.77681 -372.019069) (xy 427.753135 -371.956066) (xy 427.73716 -371.890685) (xy 427.729114 -371.823863)
			(xy 427.729113 -371.756558) (xy 427.737156 -371.689736) (xy 427.753129 -371.624354) (xy 427.776801 -371.56135)
			(xy 427.807835 -371.501627) (xy 427.845784 -371.446042) (xy 427.867572 -371.42039) (xy 427.873364 -371.413242)
			(xy 427.879879 -371.396053) (xy 427.880272 -371.386862) (xy 427.880272 -370.89334) (xy 427.879849 -370.884154)
			(xy 427.873345 -370.866969) (xy 427.867572 -370.859812) (xy 427.845772 -370.83417) (xy 427.807821 -370.778583)
			(xy 427.776786 -370.718858) (xy 427.753113 -370.655852) (xy 427.73714 -370.590468) (xy 427.729096 -370.523644)
			(xy 424.451056 -370.523644) (xy 424.451056 -370.523703) (xy 424.442981 -370.59064) (xy 424.426947 -370.656129)
			(xy 424.403183 -370.719225) (xy 424.372033 -370.779021) (xy 424.333944 -370.834655) (xy 424.31208 -370.86032)
			(xy 424.30629 -370.86747) (xy 424.299772 -370.884657) (xy 424.29938 -370.893848) (xy 424.29938 -371.386354)
			(xy 424.299817 -371.395538) (xy 424.306312 -371.412723) (xy 424.31208 -371.419882) (xy 424.333958 -371.445536)
			(xy 424.372048 -371.501171) (xy 424.403199 -371.560969) (xy 424.426835 -371.623725) (xy 425.528941 -371.623725)
			(xy 425.528945 -371.556418) (xy 425.536992 -371.489593) (xy 425.552969 -371.424208) (xy 425.576645 -371.361202)
			(xy 425.607682 -371.301478) (xy 425.645634 -371.24589) (xy 425.667424 -371.220238) (xy 425.673232 -371.213101)
			(xy 425.679739 -371.195904) (xy 425.680124 -371.18671) (xy 425.680124 -371.028722) (xy 425.680582 -371.018554)
			(xy 425.688357 -370.999762) (xy 425.702732 -370.985377) (xy 425.721518 -370.977589) (xy 425.731686 -370.97716)
			(xy 426.447966 -370.97716) (xy 426.458138 -370.977592) (xy 426.476936 -370.98537) (xy 426.491323 -370.999754)
			(xy 426.499105 -371.01855) (xy 426.499528 -371.028722) (xy 426.499528 -371.18671) (xy 426.499927 -371.195898)
			(xy 426.506448 -371.213083) (xy 426.512228 -371.220238) (xy 426.533979 -371.24592) (xy 426.571931 -371.301502)
			(xy 426.602968 -371.361221) (xy 426.626645 -371.424221) (xy 426.642621 -371.4896) (xy 426.650669 -371.55642)
			(xy 426.650672 -371.623723) (xy 426.642631 -371.690543) (xy 426.626661 -371.755924) (xy 426.602991 -371.818927)
			(xy 426.571961 -371.878649) (xy 426.534014 -371.934234) (xy 426.512228 -371.959886) (xy 426.506404 -371.967011)
			(xy 426.499908 -371.984217) (xy 426.499528 -371.993414) (xy 426.499528 -372.486682) (xy 426.49994 -372.495869)
			(xy 426.506452 -372.513054) (xy 426.512228 -372.52021) (xy 426.53405 -372.545834) (xy 426.572 -372.601424)
			(xy 426.603034 -372.661151) (xy 426.626706 -372.724159) (xy 426.642678 -372.789545) (xy 426.65072 -372.856371)
			(xy 426.650717 -372.92368) (xy 426.642669 -372.990505) (xy 426.626691 -373.05589) (xy 426.603013 -373.118896)
			(xy 426.571974 -373.17862) (xy 426.534019 -373.234206) (xy 426.512228 -373.259858) (xy 426.506416 -373.266992)
			(xy 426.499912 -373.284191) (xy 426.499528 -373.293386) (xy 426.499528 -373.451374) (xy 426.499114 -373.461548)
			(xy 426.491331 -373.480349) (xy 426.476942 -373.494736) (xy 426.45814 -373.502515) (xy 426.447966 -373.502936)
			(xy 425.731686 -373.502936) (xy 425.72151 -373.502547) (xy 425.70271 -373.494752) (xy 425.688325 -373.480356)
			(xy 425.680545 -373.46155) (xy 425.680124 -373.451374) (xy 425.680124 -373.293386) (xy 425.679715 -373.284199)
			(xy 425.6732 -373.267015) (xy 425.667424 -373.259858) (xy 425.64567 -373.234178) (xy 425.607722 -373.178595)
			(xy 425.576688 -373.118875) (xy 425.553014 -373.055874) (xy 425.537039 -372.990496) (xy 425.528992 -372.923677)
			(xy 425.528989 -372.856375) (xy 425.53703 -372.789555) (xy 425.552999 -372.724174) (xy 425.576667 -372.661171)
			(xy 425.607695 -372.601449) (xy 425.645639 -372.545863) (xy 425.667424 -372.52021) (xy 425.673244 -372.513082)
			(xy 425.679744 -372.495878) (xy 425.680124 -372.486682) (xy 425.680124 -371.993414) (xy 425.679702 -371.984228)
			(xy 425.673196 -371.967044) (xy 425.667424 -371.959886) (xy 425.645599 -371.934264) (xy 425.607653 -371.878673)
			(xy 425.576622 -371.818945) (xy 425.552952 -371.755937) (xy 425.536982 -371.690551) (xy 425.528941 -371.623725)
			(xy 424.426835 -371.623725) (xy 424.426964 -371.624067) (xy 424.442999 -371.689558) (xy 424.451074 -371.756498)
			(xy 424.451072 -371.823923) (xy 424.442995 -371.890863) (xy 424.426957 -371.956353) (xy 424.403191 -372.01945)
			(xy 424.372037 -372.079247) (xy 424.333946 -372.134881) (xy 424.31208 -372.160546) (xy 424.306279 -372.167688)
			(xy 424.299768 -372.184881) (xy 424.29938 -372.194074) (xy 424.29938 -372.351554) (xy 424.298836 -372.361675)
			(xy 424.291127 -372.380392) (xy 424.276858 -372.394749) (xy 424.25819 -372.402573) (xy 424.248072 -372.403116)
			(xy 423.531792 -372.403116) (xy 423.521685 -372.402622) (xy 423.50301 -372.394884) (xy 423.488716 -372.38059)
			(xy 423.480978 -372.361915) (xy 423.480484 -372.351808) (xy 423.480484 -372.194074) (xy 423.48009 -372.184885)
			(xy 423.473565 -372.167701) (xy 423.467784 -372.160546) (xy 423.445934 -372.134869) (xy 423.407846 -372.079236)
			(xy 423.376696 -372.019441) (xy 423.352932 -371.956346) (xy 423.336896 -371.890858) (xy 423.328819 -371.823922)
			(xy 423.328818 -371.756499) (xy 423.336892 -371.689562) (xy 423.352925 -371.624074) (xy 423.376687 -371.560978)
			(xy 423.407835 -371.501182) (xy 423.445921 -371.445547) (xy 423.467784 -371.419882) (xy 423.473569 -371.412728)
			(xy 423.480091 -371.395544) (xy 423.480484 -371.386354) (xy 423.480484 -370.893848) (xy 423.480055 -370.884663)
			(xy 423.473555 -370.867478) (xy 423.467784 -370.86032) (xy 423.445909 -370.834664) (xy 423.407821 -370.779028)
			(xy 423.376672 -370.71923) (xy 423.352909 -370.656132) (xy 423.336875 -370.590642) (xy 423.328801 -370.523703)
			(xy 420.05073 -370.523703) (xy 420.042694 -370.590464) (xy 420.026724 -370.655845) (xy 420.003054 -370.718849)
			(xy 419.972023 -370.778573) (xy 419.934078 -370.834159) (xy 419.912292 -370.859812) (xy 419.906507 -370.866965)
			(xy 419.899986 -370.88415) (xy 419.899592 -370.89334) (xy 419.899592 -371.386862) (xy 419.900022 -371.396047)
			(xy 419.906522 -371.413231) (xy 419.912292 -371.42039) (xy 419.934093 -371.446031) (xy 419.972039 -371.50162)
			(xy 420.00307 -371.561345) (xy 420.026528 -371.623785) (xy 421.128621 -371.623785) (xy 421.128625 -371.556358)
			(xy 421.136705 -371.489416) (xy 421.152746 -371.423925) (xy 421.176516 -371.360826) (xy 421.207673 -371.301029)
			(xy 421.245769 -371.245395) (xy 421.267636 -371.21973) (xy 421.273449 -371.212597) (xy 421.279953 -371.195397)
			(xy 421.280336 -371.186202) (xy 421.280336 -371.028722) (xy 421.280844 -371.018597) (xy 421.288564 -370.999877)
			(xy 421.302844 -370.98552) (xy 421.321522 -370.9777) (xy 421.331644 -370.97716) (xy 422.047924 -370.97716)
			(xy 422.058029 -370.977664) (xy 422.076701 -370.985402) (xy 422.090993 -370.999693) (xy 422.098734 -371.018363)
			(xy 422.099232 -371.028468) (xy 422.099232 -371.186202) (xy 422.099656 -371.195387) (xy 422.106162 -371.212571)
			(xy 422.111932 -371.21973) (xy 422.133758 -371.245427) (xy 422.171845 -371.301057) (xy 422.202996 -371.36085)
			(xy 422.226761 -371.423942) (xy 422.242798 -371.489427) (xy 422.250876 -371.556361) (xy 422.25088 -371.623781)
			(xy 422.242808 -371.690717) (xy 422.226778 -371.756203) (xy 422.203019 -371.819298) (xy 422.171875 -371.879094)
			(xy 422.133793 -371.934728) (xy 422.111932 -371.960394) (xy 422.106147 -371.967547) (xy 422.099627 -371.984732)
			(xy 422.099232 -371.993922) (xy 422.099232 -372.486174) (xy 422.09967 -372.495358) (xy 422.106166 -372.512542)
			(xy 422.111932 -372.519702) (xy 422.133828 -372.54534) (xy 422.171914 -372.600979) (xy 422.203061 -372.66078)
			(xy 422.226822 -372.72388) (xy 422.242854 -372.789372) (xy 422.250927 -372.856313) (xy 422.250924 -372.923738)
			(xy 422.242845 -372.990678) (xy 422.226807 -373.056169) (xy 422.20304 -373.119267) (xy 422.171888 -373.179064)
			(xy 422.133797 -373.2347) (xy 422.111932 -373.260366) (xy 422.106117 -373.267498) (xy 422.099615 -373.284699)
			(xy 422.099232 -373.293894) (xy 422.099232 -373.451374) (xy 422.098751 -373.461503) (xy 422.091027 -373.480228)
			(xy 422.076738 -373.494587) (xy 422.05805 -373.502402) (xy 422.047924 -373.502936) (xy 421.331644 -373.502936)
			(xy 421.321529 -373.502449) (xy 421.302833 -373.494722) (xy 421.288519 -373.480427) (xy 421.280765 -373.461743)
			(xy 421.280336 -373.451628) (xy 421.280336 -373.293894) (xy 421.279921 -373.284708) (xy 421.27341 -373.267524)
			(xy 421.267636 -373.260366) (xy 421.245804 -373.234674) (xy 421.207712 -373.179044) (xy 421.176558 -373.119252)
			(xy 421.15279 -373.056158) (xy 421.136751 -372.990672) (xy 421.128672 -372.923736) (xy 421.128669 -372.856315)
			(xy 421.136742 -372.789378) (xy 421.152775 -372.72389) (xy 421.176537 -372.660795) (xy 421.207686 -372.601)
			(xy 421.245773 -372.545367) (xy 421.267636 -372.519702) (xy 421.273419 -372.512547) (xy 421.279941 -372.495364)
			(xy 421.280336 -372.486174) (xy 421.280336 -371.993922) (xy 421.279907 -371.984737) (xy 421.273406 -371.967553)
			(xy 421.267636 -371.960394) (xy 421.245733 -371.93476) (xy 421.207643 -371.879122) (xy 421.176492 -371.819322)
			(xy 421.152729 -371.756221) (xy 421.136695 -371.690727) (xy 421.128621 -371.623785) (xy 420.026528 -371.623785)
			(xy 420.026741 -371.624351) (xy 420.042712 -371.689734) (xy 420.050754 -371.756558) (xy 420.050753 -371.823863)
			(xy 420.042708 -371.890686) (xy 420.026734 -371.956069) (xy 420.003061 -372.019074) (xy 419.972028 -372.078798)
			(xy 419.93408 -372.134385) (xy 419.912292 -372.160038) (xy 419.906496 -372.167183) (xy 419.899981 -372.184374)
			(xy 419.899592 -372.193566) (xy 419.899592 -372.351554) (xy 419.899099 -372.361719) (xy 419.891335 -372.380507)
			(xy 419.876971 -372.394892) (xy 419.858194 -372.402684) (xy 419.84803 -372.403116) (xy 419.13175 -372.403116)
			(xy 419.121576 -372.402694) (xy 419.102773 -372.394917) (xy 419.088385 -372.38053) (xy 419.080607 -372.361728)
			(xy 419.080188 -372.351554) (xy 419.080188 -372.193566) (xy 419.079797 -372.184377) (xy 419.07327 -372.167192)
			(xy 419.067488 -372.160038) (xy 419.045713 -372.134375) (xy 419.00776 -372.078791) (xy 418.976724 -372.01907)
			(xy 418.953048 -371.956067) (xy 418.937072 -371.890685) (xy 418.929026 -371.823863) (xy 418.929025 -371.756558)
			(xy 418.937069 -371.689736) (xy 418.953042 -371.624354) (xy 418.976715 -371.561349) (xy 419.007749 -371.501627)
			(xy 419.0457 -371.446041) (xy 419.067488 -371.42039) (xy 419.07327 -371.413234) (xy 419.079794 -371.396052)
			(xy 419.080188 -371.386862) (xy 419.080188 -370.89334) (xy 419.079761 -370.884154) (xy 419.07326 -370.86697)
			(xy 419.067488 -370.859812) (xy 419.045687 -370.83417) (xy 419.007735 -370.778583) (xy 418.9767 -370.718859)
			(xy 418.953026 -370.655853) (xy 418.937052 -370.590469) (xy 418.929008 -370.523644) (xy 389.250706 -370.523644)
			(xy 389.242663 -370.590465) (xy 389.226691 -370.655847) (xy 389.203019 -370.718851) (xy 389.171987 -370.778574)
			(xy 389.134039 -370.83416) (xy 389.112252 -370.859812) (xy 389.106462 -370.866962) (xy 389.099945 -370.884149)
			(xy 389.099552 -370.89334) (xy 389.099552 -371.386862) (xy 389.099991 -371.396046) (xy 389.106486 -371.41323)
			(xy 389.112252 -371.42039) (xy 389.134054 -371.446031) (xy 389.172003 -371.501618) (xy 389.203036 -371.561344)
			(xy 389.226474 -371.623725) (xy 390.32912 -371.623725) (xy 390.329123 -371.556418) (xy 390.337171 -371.489593)
			(xy 390.353146 -371.42421) (xy 390.376822 -371.361204) (xy 390.407857 -371.301479) (xy 390.445807 -371.245891)
			(xy 390.467596 -371.220238) (xy 390.473401 -371.213099) (xy 390.479911 -371.195904) (xy 390.480296 -371.18671)
			(xy 390.480296 -371.028722) (xy 390.48085 -371.018571) (xy 390.48861 -370.99981) (xy 390.502956 -370.985446)
			(xy 390.521707 -370.977663) (xy 390.531858 -370.97716) (xy 391.248138 -370.97716) (xy 391.258301 -370.977603)
			(xy 391.277075 -370.985394) (xy 391.29144 -370.999775) (xy 391.299209 -371.018558) (xy 391.2997 -371.028722)
			(xy 391.2997 -371.18671) (xy 391.300106 -371.195898) (xy 391.306623 -371.213082) (xy 391.3124 -371.220238)
			(xy 391.334149 -371.245921) (xy 391.372097 -371.301504) (xy 391.403129 -371.361224) (xy 391.426803 -371.424224)
			(xy 391.442777 -371.489602) (xy 391.450824 -371.556421) (xy 391.450827 -371.623722) (xy 391.442787 -371.690541)
			(xy 391.42682 -371.755921) (xy 391.403153 -371.818924) (xy 391.372126 -371.878647) (xy 391.334184 -371.934233)
			(xy 391.3124 -371.959886) (xy 391.306584 -371.967018) (xy 391.300081 -371.984219) (xy 391.2997 -371.993414)
			(xy 391.2997 -372.486682) (xy 391.300119 -372.495868) (xy 391.306627 -372.513053) (xy 391.3124 -372.52021)
			(xy 391.33422 -372.545835) (xy 391.372165 -372.601426) (xy 391.403195 -372.661154) (xy 391.426864 -372.724162)
			(xy 391.442833 -372.789547) (xy 391.450874 -372.856372) (xy 391.450871 -372.923679) (xy 391.442824 -372.990503)
			(xy 391.426849 -373.055887) (xy 391.403174 -373.118893) (xy 391.372139 -373.178617) (xy 391.334189 -373.234205)
			(xy 391.3124 -373.259858) (xy 391.306596 -373.266998) (xy 391.300086 -373.284193) (xy 391.2997 -373.293386)
			(xy 391.2997 -373.451374) (xy 391.299146 -373.461525) (xy 391.291388 -373.480287) (xy 391.277041 -373.494652)
			(xy 391.258289 -373.502434) (xy 391.248138 -373.502936) (xy 390.531858 -373.502936) (xy 390.521694 -373.5025)
			(xy 390.502919 -373.494707) (xy 390.488555 -373.480324) (xy 390.480786 -373.461538) (xy 390.480296 -373.451374)
			(xy 390.480296 -373.293386) (xy 390.479893 -373.284198) (xy 390.473374 -373.267014) (xy 390.467596 -373.259858)
			(xy 390.445843 -373.234178) (xy 390.407896 -373.178594) (xy 390.376864 -373.118874) (xy 390.353191 -373.055874)
			(xy 390.337217 -372.990495) (xy 390.329171 -372.923676) (xy 390.329167 -372.856375) (xy 390.337208 -372.789555)
			(xy 390.353176 -372.724175) (xy 390.376843 -372.661173) (xy 390.40787 -372.60145) (xy 390.445812 -372.545863)
			(xy 390.467596 -372.52021) (xy 390.473413 -372.513079) (xy 390.479916 -372.495878) (xy 390.480296 -372.486682)
			(xy 390.480296 -371.993414) (xy 390.47988 -371.984227) (xy 390.47337 -371.967043) (xy 390.467596 -371.959886)
			(xy 390.445772 -371.934264) (xy 390.407827 -371.878672) (xy 390.376798 -371.818944) (xy 390.353129 -371.755936)
			(xy 390.33716 -371.69055) (xy 390.32912 -371.623725) (xy 389.226474 -371.623725) (xy 389.226709 -371.62435)
			(xy 389.242681 -371.689733) (xy 389.250724 -371.756557) (xy 389.250723 -371.823864) (xy 389.242677 -371.890687)
			(xy 389.226702 -371.956071) (xy 389.203028 -372.019076) (xy 389.171992 -372.0788) (xy 389.134041 -372.134386)
			(xy 389.112252 -372.160038) (xy 389.106451 -372.16718) (xy 389.09994 -372.184373) (xy 389.099552 -372.193566)
			(xy 389.099552 -372.351554) (xy 389.099098 -372.361724) (xy 389.091327 -372.380519) (xy 389.07695 -372.394906)
			(xy 389.05816 -372.402691) (xy 389.04799 -372.403116) (xy 388.33171 -372.403116) (xy 388.321533 -372.402727)
			(xy 388.30273 -372.394937) (xy 388.288343 -372.38054) (xy 388.280566 -372.361731) (xy 388.280148 -372.351554)
			(xy 388.280148 -372.193566) (xy 388.279743 -372.184378) (xy 388.273225 -372.167195) (xy 388.267448 -372.160038)
			(xy 388.245674 -372.134375) (xy 388.207724 -372.07879) (xy 388.17669 -372.019068) (xy 388.153016 -371.956065)
			(xy 388.137042 -371.890684) (xy 388.128996 -371.823863) (xy 388.128995 -371.756558) (xy 388.137038 -371.689737)
			(xy 388.15301 -371.624355) (xy 388.176681 -371.561351) (xy 388.207713 -371.501628) (xy 388.245661 -371.446042)
			(xy 388.267448 -371.42039) (xy 388.273237 -371.41324) (xy 388.279755 -371.396053) (xy 388.280148 -371.386862)
			(xy 388.280148 -370.89334) (xy 388.279708 -370.884156) (xy 388.273214 -370.866972) (xy 388.267448 -370.859812)
			(xy 388.245648 -370.83417) (xy 388.207699 -370.778582) (xy 388.176666 -370.718857) (xy 388.152993 -370.655851)
			(xy 388.137021 -370.590468) (xy 388.128977 -370.523644) (xy 384.850915 -370.523644) (xy 384.842872 -370.590465)
			(xy 384.826901 -370.655846) (xy 384.80323 -370.71885) (xy 384.772198 -370.778573) (xy 384.734251 -370.83416)
			(xy 384.712464 -370.859812) (xy 384.706675 -370.866963) (xy 384.700157 -370.884149) (xy 384.699764 -370.89334)
			(xy 384.699764 -371.386862) (xy 384.700201 -371.396046) (xy 384.706697 -371.41323) (xy 384.712464 -371.42039)
			(xy 384.734266 -371.446031) (xy 384.772214 -371.501619) (xy 384.803246 -371.561344) (xy 384.826706 -371.623785)
			(xy 385.9288 -371.623785) (xy 385.928804 -371.556358) (xy 385.936884 -371.489417) (xy 385.952923 -371.423926)
			(xy 385.976692 -371.360827) (xy 386.007848 -371.30103) (xy 386.045941 -371.245395) (xy 386.067808 -371.21973)
			(xy 386.073618 -371.212594) (xy 386.080124 -371.195396) (xy 386.080508 -371.186202) (xy 386.080508 -371.028722)
			(xy 386.081044 -371.018601) (xy 386.088758 -370.999886) (xy 386.103029 -370.98553) (xy 386.121698 -370.977704)
			(xy 386.131816 -370.97716) (xy 386.848096 -370.97716) (xy 386.858245 -370.977624) (xy 386.876989 -370.985411)
			(xy 386.891311 -370.999794) (xy 386.899019 -371.018571) (xy 386.899404 -371.028722) (xy 386.899404 -371.186202)
			(xy 386.899812 -371.195389) (xy 386.906327 -371.212574) (xy 386.912104 -371.21973) (xy 386.93393 -371.245426)
			(xy 386.97202 -371.301056) (xy 387.003172 -371.360848) (xy 387.026938 -371.423941) (xy 387.042976 -371.489426)
			(xy 387.051055 -371.556361) (xy 387.051059 -371.623782) (xy 387.042987 -371.690717) (xy 387.026955 -371.756204)
			(xy 387.003196 -371.8193) (xy 386.972049 -371.879095) (xy 386.933966 -371.934729) (xy 386.912104 -371.960394)
			(xy 386.906328 -371.967554) (xy 386.899801 -371.984733) (xy 386.899404 -371.993922) (xy 386.899404 -372.486174)
			(xy 386.899826 -372.49536) (xy 386.906331 -372.512545) (xy 386.912104 -372.519702) (xy 386.934001 -372.54534)
			(xy 386.972089 -372.600978) (xy 387.003238 -372.660778) (xy 387.027 -372.723879) (xy 387.043033 -372.789371)
			(xy 387.051106 -372.856312) (xy 387.051103 -372.923739) (xy 387.043024 -372.990679) (xy 387.026985 -373.05617)
			(xy 387.003217 -373.119268) (xy 386.972062 -373.179066) (xy 386.93397 -373.234701) (xy 386.912104 -373.260366)
			(xy 386.906297 -373.267504) (xy 386.899789 -373.2847) (xy 386.899404 -373.293894) (xy 386.899404 -373.451374)
			(xy 386.898854 -373.461494) (xy 386.891142 -373.480206) (xy 386.876876 -373.494562) (xy 386.858212 -373.50239)
			(xy 386.848096 -373.502936) (xy 386.131816 -373.502936) (xy 386.121667 -373.502466) (xy 386.102922 -373.494683)
			(xy 386.0886 -373.480301) (xy 386.080893 -373.461524) (xy 386.080508 -373.451374) (xy 386.080508 -373.293894)
			(xy 386.080099 -373.284707) (xy 386.073584 -373.267523) (xy 386.067808 -373.260366) (xy 386.045977 -373.234673)
			(xy 386.007887 -373.179043) (xy 385.976734 -373.119251) (xy 385.952968 -373.056157) (xy 385.93693 -372.990671)
			(xy 385.928851 -372.923736) (xy 385.928848 -372.856315) (xy 385.936921 -372.789379) (xy 385.952953 -372.723892)
			(xy 385.976713 -372.660796) (xy 386.007861 -372.601001) (xy 386.045946 -372.545367) (xy 386.067808 -372.519702)
			(xy 386.073587 -372.512544) (xy 386.080112 -372.495363) (xy 386.080508 -372.486174) (xy 386.080508 -371.993922)
			(xy 386.080085 -371.984736) (xy 386.07358 -371.967552) (xy 386.067808 -371.960394) (xy 386.045906 -371.93476)
			(xy 386.007818 -371.879121) (xy 385.976669 -371.819321) (xy 385.952906 -371.75622) (xy 385.936873 -371.690727)
			(xy 385.9288 -371.623785) (xy 384.826706 -371.623785) (xy 384.826918 -371.62435) (xy 384.84289 -371.689734)
			(xy 384.850933 -371.756557) (xy 384.850932 -371.823864) (xy 384.842886 -371.890687) (xy 384.826912 -371.95607)
			(xy 384.803238 -372.019075) (xy 384.772203 -372.078799) (xy 384.734253 -372.134386) (xy 384.712464 -372.160038)
			(xy 384.706664 -372.167181) (xy 384.700152 -372.184373) (xy 384.699764 -372.193566) (xy 384.699764 -372.351554)
			(xy 384.699299 -372.361722) (xy 384.691529 -372.380516) (xy 384.677156 -372.394902) (xy 384.65837 -372.402689)
			(xy 384.648202 -372.403116) (xy 383.931922 -372.403116) (xy 383.921746 -372.402717) (xy 383.902943 -372.394931)
			(xy 383.888556 -372.380537) (xy 383.880778 -372.36173) (xy 383.88036 -372.351554) (xy 383.88036 -372.193566)
			(xy 383.879953 -372.184379) (xy 383.873435 -372.167195) (xy 383.86766 -372.160038) (xy 383.845886 -372.134375)
			(xy 383.807935 -372.07879) (xy 383.7769 -372.019069) (xy 383.753225 -371.956065) (xy 383.737251 -371.890684)
			(xy 383.729205 -371.823863) (xy 383.729204 -371.756558) (xy 383.737247 -371.689736) (xy 383.753219 -371.624355)
			(xy 383.776891 -371.561351) (xy 383.807924 -371.501628) (xy 383.845873 -371.446042) (xy 383.86766 -371.42039)
			(xy 383.873451 -371.413241) (xy 383.879967 -371.396053) (xy 383.88036 -371.386862) (xy 383.88036 -370.89334)
			(xy 383.879917 -370.884157) (xy 383.873425 -370.866972) (xy 383.86766 -370.859812) (xy 383.84586 -370.83417)
			(xy 383.80791 -370.778582) (xy 383.776876 -370.718858) (xy 383.753203 -370.655852) (xy 383.737231 -370.590468)
			(xy 383.729187 -370.523644) (xy 380.451147 -370.523644) (xy 380.451147 -370.523703) (xy 380.443072 -370.590641)
			(xy 380.427037 -370.656129) (xy 380.403273 -370.719226) (xy 380.372122 -370.779022) (xy 380.334032 -370.834655)
			(xy 380.312168 -370.86032) (xy 380.306376 -370.867469) (xy 380.299859 -370.884657) (xy 380.299468 -370.893848)
			(xy 380.299468 -371.386354) (xy 380.299908 -371.395538) (xy 380.306402 -371.412722) (xy 380.312168 -371.419882)
			(xy 380.334047 -371.445535) (xy 380.372137 -371.501171) (xy 380.403289 -371.560968) (xy 380.426925 -371.623725)
			(xy 381.529032 -371.623725) (xy 381.529035 -371.556418) (xy 381.537083 -371.489593) (xy 381.553059 -371.424209)
			(xy 381.576735 -371.361203) (xy 381.607771 -371.301478) (xy 381.645723 -371.245891) (xy 381.667512 -371.220238)
			(xy 381.673319 -371.2131) (xy 381.679827 -371.195904) (xy 381.680212 -371.18671) (xy 381.680212 -371.028722)
			(xy 381.680751 -371.018569) (xy 381.688513 -370.999805) (xy 381.702865 -370.98544) (xy 381.721621 -370.97766)
			(xy 381.731774 -370.97716) (xy 382.448054 -370.97716) (xy 382.458225 -370.977602) (xy 382.477023 -370.985376)
			(xy 382.491411 -370.999757) (xy 382.499193 -371.018551) (xy 382.499616 -371.028722) (xy 382.499616 -371.18671)
			(xy 382.500018 -371.195898) (xy 382.506537 -371.213083) (xy 382.512316 -371.220238) (xy 382.534068 -371.24592)
			(xy 382.572021 -371.301501) (xy 382.603058 -371.36122) (xy 382.626735 -371.424221) (xy 382.642712 -371.4896)
			(xy 382.65076 -371.55642) (xy 382.650763 -371.623723) (xy 382.642722 -371.690544) (xy 382.626752 -371.755924)
			(xy 382.603081 -371.818927) (xy 382.57205 -371.87865) (xy 382.534103 -371.934234) (xy 382.512316 -371.959886)
			(xy 382.506502 -371.967019) (xy 382.499997 -371.984219) (xy 382.499616 -371.993414) (xy 382.499616 -372.486682)
			(xy 382.500031 -372.495869) (xy 382.506541 -372.513053) (xy 382.512316 -372.52021) (xy 382.534138 -372.545834)
			(xy 382.572089 -372.601424) (xy 382.603123 -372.661151) (xy 382.626796 -372.724159) (xy 382.642768 -372.789545)
			(xy 382.65081 -372.856371) (xy 382.650807 -372.92368) (xy 382.642759 -372.990506) (xy 382.626781 -373.05589)
			(xy 382.603103 -373.118896) (xy 382.572063 -373.17862) (xy 382.534107 -373.234206) (xy 382.512316 -373.259858)
			(xy 382.506514 -373.267) (xy 382.500002 -373.284193) (xy 382.499616 -373.293386) (xy 382.499616 -373.451374)
			(xy 382.499214 -373.46155) (xy 382.491429 -373.480352) (xy 382.477036 -373.49474) (xy 382.45823 -373.502517)
			(xy 382.448054 -373.502936) (xy 381.731774 -373.502936) (xy 381.721611 -373.502487) (xy 381.702837 -373.4947)
			(xy 381.688471 -373.48032) (xy 381.680702 -373.461537) (xy 381.680212 -373.451374) (xy 381.680212 -373.293386)
			(xy 381.679806 -373.284198) (xy 381.673289 -373.267014) (xy 381.667512 -373.259858) (xy 381.645758 -373.234178)
			(xy 381.60781 -373.178595) (xy 381.576777 -373.118875) (xy 381.553104 -373.055874) (xy 381.537129 -372.990496)
			(xy 381.529083 -372.923676) (xy 381.52908 -372.856375) (xy 381.53712 -372.789555) (xy 381.553088 -372.724175)
			(xy 381.576756 -372.661172) (xy 381.607784 -372.601449) (xy 381.645727 -372.545862) (xy 381.667512 -372.52021)
			(xy 381.673331 -372.51308) (xy 381.679832 -372.495878) (xy 381.680212 -372.486682) (xy 381.680212 -371.993414)
			(xy 381.679792 -371.984228) (xy 381.673285 -371.967044) (xy 381.667512 -371.959886) (xy 381.645688 -371.934264)
			(xy 381.607742 -371.878673) (xy 381.576712 -371.818945) (xy 381.553042 -371.755936) (xy 381.537073 -371.690551)
			(xy 381.529032 -371.623725) (xy 380.426925 -371.623725) (xy 380.427054 -371.624067) (xy 380.443089 -371.689558)
			(xy 380.451165 -371.756498) (xy 380.451163 -371.823923) (xy 380.443086 -371.890863) (xy 380.427048 -371.956353)
			(xy 380.403281 -372.019451) (xy 380.372126 -372.079247) (xy 380.334034 -372.134881) (xy 380.312168 -372.160546)
			(xy 380.306365 -372.167687) (xy 380.299855 -372.184881) (xy 380.299468 -372.194074) (xy 380.299468 -372.351554)
			(xy 380.298936 -372.361677) (xy 380.291225 -372.380395) (xy 380.276952 -372.394753) (xy 380.25828 -372.402575)
			(xy 380.24816 -372.403116) (xy 379.53188 -372.403116) (xy 379.521727 -372.402695) (xy 379.502977 -372.394896)
			(xy 379.488655 -372.3805) (xy 379.480953 -372.36171) (xy 379.480572 -372.351554) (xy 379.480572 -372.194074)
			(xy 379.480181 -372.184885) (xy 379.473655 -372.1677) (xy 379.467872 -372.160546) (xy 379.446023 -372.134869)
			(xy 379.407935 -372.079235) (xy 379.376786 -372.019441) (xy 379.353022 -371.956345) (xy 379.336986 -371.890858)
			(xy 379.32891 -371.823922) (xy 379.328909 -371.7565) (xy 379.336983 -371.689563) (xy 379.353016 -371.624075)
			(xy 379.376777 -371.560979) (xy 379.407925 -371.501183) (xy 379.44601 -371.445548) (xy 379.467872 -371.419882)
			(xy 379.473667 -371.412736) (xy 379.480181 -371.395546) (xy 379.480572 -371.386354) (xy 379.480572 -370.893848)
			(xy 379.480145 -370.884663) (xy 379.473644 -370.867478) (xy 379.467872 -370.86032) (xy 379.445997 -370.834664)
			(xy 379.407911 -370.779027) (xy 379.376762 -370.71923) (xy 379.353 -370.656132) (xy 379.336966 -370.590642)
			(xy 379.328892 -370.523703) (xy 376.050821 -370.523703) (xy 376.042785 -370.590464) (xy 376.026814 -370.655846)
			(xy 376.003143 -370.71885) (xy 375.972113 -370.778573) (xy 375.934166 -370.83416) (xy 375.91238 -370.859812)
			(xy 375.906594 -370.866964) (xy 375.900073 -370.884149) (xy 375.89968 -370.89334) (xy 375.89968 -371.386862)
			(xy 375.900113 -371.396047) (xy 375.906611 -371.413231) (xy 375.91238 -371.42039) (xy 375.934181 -371.446031)
			(xy 375.972128 -371.50162) (xy 376.00316 -371.561345) (xy 376.026618 -371.623785) (xy 377.128712 -371.623785)
			(xy 377.128716 -371.556358) (xy 377.136796 -371.489417) (xy 377.152836 -371.423925) (xy 377.176606 -371.360827)
			(xy 377.207762 -371.301029) (xy 377.245857 -371.245395) (xy 377.267724 -371.21973) (xy 377.273536 -371.212596)
			(xy 377.28004 -371.195397) (xy 377.280424 -371.186202) (xy 377.280424 -371.028722) (xy 377.280944 -371.018599)
			(xy 377.288662 -370.999881) (xy 377.302938 -370.985524) (xy 377.321612 -370.977702) (xy 377.331732 -370.97716)
			(xy 378.048012 -370.97716) (xy 378.058162 -370.977611) (xy 378.076907 -370.985403) (xy 378.091229 -370.99979)
			(xy 378.098935 -371.01857) (xy 378.09932 -371.028722) (xy 378.09932 -371.186202) (xy 378.099725 -371.19539)
			(xy 378.106242 -371.212574) (xy 378.11202 -371.21973) (xy 378.133846 -371.245426) (xy 378.171934 -371.301057)
			(xy 378.203086 -371.360849) (xy 378.226851 -371.423942) (xy 378.242889 -371.489427) (xy 378.250967 -371.556361)
			(xy 378.250971 -371.623782) (xy 378.242899 -371.690717) (xy 378.226868 -371.756204) (xy 378.203109 -371.819299)
			(xy 378.171964 -371.879094) (xy 378.133881 -371.934728) (xy 378.11202 -371.960394) (xy 378.106246 -371.967555)
			(xy 378.099717 -371.984733) (xy 378.09932 -371.993922) (xy 378.09932 -372.486174) (xy 378.099738 -372.49536)
			(xy 378.106246 -372.512545) (xy 378.11202 -372.519702) (xy 378.133917 -372.54534) (xy 378.172003 -372.600979)
			(xy 378.203151 -372.660779) (xy 378.226913 -372.723879) (xy 378.242945 -372.789372) (xy 378.251018 -372.856313)
			(xy 378.251015 -372.923739) (xy 378.242936 -372.990679) (xy 378.226897 -373.056169) (xy 378.20313 -373.119268)
			(xy 378.171977 -373.179065) (xy 378.133885 -373.2347) (xy 378.11202 -373.260366) (xy 378.106215 -373.267506)
			(xy 378.099705 -373.2847) (xy 378.09932 -373.293894) (xy 378.09932 -373.451374) (xy 378.098851 -373.461504)
			(xy 378.091125 -373.480232) (xy 378.076832 -373.494591) (xy 378.05814 -373.502404) (xy 378.048012 -373.502936)
			(xy 377.331732 -373.502936) (xy 377.321584 -373.502453) (xy 377.30284 -373.494675) (xy 377.288516 -373.480297)
			(xy 377.280809 -373.461523) (xy 377.280424 -373.451374) (xy 377.280424 -373.293894) (xy 377.280012 -373.284707)
			(xy 377.273499 -373.267523) (xy 377.267724 -373.260366) (xy 377.245893 -373.234674) (xy 377.207801 -373.179044)
			(xy 377.176648 -373.119251) (xy 377.152881 -373.056158) (xy 377.136842 -372.990672) (xy 377.128763 -372.923736)
			(xy 377.12876 -372.856315) (xy 377.136833 -372.789378) (xy 377.152865 -372.723891) (xy 377.176627 -372.660795)
			(xy 377.207775 -372.601) (xy 377.245861 -372.545367) (xy 377.267724 -372.519702) (xy 377.273505 -372.512546)
			(xy 377.280028 -372.495364) (xy 377.280424 -372.486174) (xy 377.280424 -371.993922) (xy 377.279998 -371.984737)
			(xy 377.273495 -371.967552) (xy 377.267724 -371.960394) (xy 377.245822 -371.93476) (xy 377.207733 -371.879122)
			(xy 377.176582 -371.819321) (xy 377.152819 -371.75622) (xy 377.136786 -371.690727) (xy 377.128712 -371.623785)
			(xy 376.026618 -371.623785) (xy 376.026831 -371.624351) (xy 376.042802 -371.689734) (xy 376.050845 -371.756558)
			(xy 376.050844 -371.823863) (xy 376.042799 -371.890687) (xy 376.026825 -371.956069) (xy 376.003151 -372.019074)
			(xy 375.972117 -372.078799) (xy 375.934168 -372.134386) (xy 375.91238 -372.160038) (xy 375.906582 -372.167182)
			(xy 375.900069 -372.184374) (xy 375.89968 -372.193566) (xy 375.89968 -372.351554) (xy 375.899199 -372.36172)
			(xy 375.891432 -372.380511) (xy 375.877064 -372.394896) (xy 375.858284 -372.402686) (xy 375.848118 -372.403116)
			(xy 375.131838 -372.403116) (xy 375.121663 -372.402704) (xy 375.102861 -372.394923) (xy 375.088473 -372.380533)
			(xy 375.080695 -372.361729) (xy 375.080276 -372.351554) (xy 375.080276 -372.193566) (xy 375.079887 -372.184376)
			(xy 375.073359 -372.167192) (xy 375.067576 -372.160038) (xy 375.045801 -372.134375) (xy 375.007849 -372.078791)
			(xy 374.976813 -372.019069) (xy 374.953138 -371.956066) (xy 374.937163 -371.890685) (xy 374.929117 -371.823863)
			(xy 374.929116 -371.756558) (xy 374.937159 -371.689736) (xy 374.953132 -371.624354) (xy 374.976805 -371.56135)
			(xy 375.007838 -371.501627) (xy 375.045788 -371.446042) (xy 375.067576 -371.42039) (xy 375.073357 -371.413233)
			(xy 375.079882 -371.396052) (xy 375.080276 -371.386862) (xy 375.080276 -370.89334) (xy 375.079852 -370.884154)
			(xy 375.073349 -370.866969) (xy 375.067576 -370.859812) (xy 375.045775 -370.83417) (xy 375.007825 -370.778583)
			(xy 374.97679 -370.718858) (xy 374.953116 -370.655852) (xy 374.937143 -370.590469) (xy 374.929099 -370.523644)
			(xy 345.250797 -370.523644) (xy 345.242754 -370.590465) (xy 345.226782 -370.655847) (xy 345.203109 -370.718851)
			(xy 345.172076 -370.778574) (xy 345.134128 -370.83416) (xy 345.11234 -370.859812) (xy 345.106548 -370.86696)
			(xy 345.100032 -370.884149) (xy 345.09964 -370.89334) (xy 345.09964 -371.386862) (xy 345.100082 -371.396046)
			(xy 345.106575 -371.41323) (xy 345.11234 -371.42039) (xy 345.134142 -371.446031) (xy 345.172092 -371.501618)
			(xy 345.203126 -371.561343) (xy 345.226564 -371.623726) (xy 346.329187 -371.623726) (xy 346.32919 -371.556417)
			(xy 346.337239 -371.489591) (xy 346.353217 -371.424206) (xy 346.376896 -371.3612) (xy 346.407936 -371.301476)
			(xy 346.445893 -371.24589) (xy 346.467684 -371.220238) (xy 346.473488 -371.213098) (xy 346.479999 -371.195904)
			(xy 346.480384 -371.18671) (xy 346.480384 -371.028722) (xy 346.480783 -371.018546) (xy 346.488569 -370.999743)
			(xy 346.502963 -370.985356) (xy 346.52177 -370.977578) (xy 346.531946 -370.97716) (xy 347.248226 -370.97716)
			(xy 347.258388 -370.977612) (xy 347.277162 -370.9854) (xy 347.291527 -370.999778) (xy 347.299297 -371.018559)
			(xy 347.299788 -371.028722) (xy 347.299788 -371.18671) (xy 347.300196 -371.195897) (xy 347.306711 -371.213082)
			(xy 347.312488 -371.220238) (xy 347.334237 -371.245921) (xy 347.372185 -371.301504) (xy 347.403219 -371.361224)
			(xy 347.426893 -371.424224) (xy 347.442867 -371.489602) (xy 347.450914 -371.556421) (xy 347.450918 -371.623722)
			(xy 347.442878 -371.690542) (xy 347.426909 -371.755921) (xy 347.403242 -371.818924) (xy 347.372215 -371.878647)
			(xy 347.334272 -371.934233) (xy 347.312488 -371.959886) (xy 347.306671 -371.967017) (xy 347.300169 -371.984218)
			(xy 347.299788 -371.993414) (xy 347.299788 -372.486682) (xy 347.30021 -372.495868) (xy 347.306716 -372.513052)
			(xy 347.312488 -372.52021) (xy 347.334308 -372.545835) (xy 347.372254 -372.601426) (xy 347.403285 -372.661154)
			(xy 347.426954 -372.724162) (xy 347.442924 -372.789547) (xy 347.450965 -372.856372) (xy 347.450962 -372.923679)
			(xy 347.442915 -372.990504) (xy 347.426939 -373.055887) (xy 347.403264 -373.118893) (xy 347.372228 -373.178618)
			(xy 347.334277 -373.234205) (xy 347.312488 -373.259858) (xy 347.306683 -373.266997) (xy 347.300174 -373.284192)
			(xy 347.299788 -373.293386) (xy 347.299788 -373.451374) (xy 347.299246 -373.461527) (xy 347.291485 -373.480291)
			(xy 347.277134 -373.494656) (xy 347.258378 -373.502436) (xy 347.248226 -373.502936) (xy 346.531946 -373.502936)
			(xy 346.521774 -373.502498) (xy 346.502975 -373.494723) (xy 346.488588 -373.480341) (xy 346.480806 -373.461546)
			(xy 346.480384 -373.451374) (xy 346.480384 -373.293386) (xy 346.479984 -373.284198) (xy 346.473464 -373.267013)
			(xy 346.467684 -373.259858) (xy 346.445928 -373.234179) (xy 346.407976 -373.178597) (xy 346.376938 -373.118878)
			(xy 346.353262 -373.055877) (xy 346.337285 -372.990498) (xy 346.329237 -372.923677) (xy 346.329234 -372.856374)
			(xy 346.337276 -372.789553) (xy 346.353247 -372.724172) (xy 346.376917 -372.661169) (xy 346.407949 -372.601447)
			(xy 346.445897 -372.545862) (xy 346.467684 -372.52021) (xy 346.473499 -372.513078) (xy 346.480003 -372.495877)
			(xy 346.480384 -372.486682) (xy 346.480384 -371.993414) (xy 346.479971 -371.984227) (xy 346.47346 -371.967042)
			(xy 346.467684 -371.959886) (xy 346.445858 -371.934265) (xy 346.407907 -371.878675) (xy 346.376873 -371.818948)
			(xy 346.3532 -371.755939) (xy 346.337229 -371.690553) (xy 346.329187 -371.623726) (xy 345.226564 -371.623726)
			(xy 345.226798 -371.624349) (xy 345.242771 -371.689733) (xy 345.250814 -371.756557) (xy 345.250813 -371.823864)
			(xy 345.242767 -371.890688) (xy 345.226792 -371.956071) (xy 345.203117 -372.019076) (xy 345.172081 -372.0788)
			(xy 345.134129 -372.134386) (xy 345.11234 -372.160038) (xy 345.106537 -372.167179) (xy 345.100028 -372.184373)
			(xy 345.09964 -372.193566) (xy 345.09964 -372.351554) (xy 345.099198 -372.361725) (xy 345.091424 -372.380523)
			(xy 345.077043 -372.394911) (xy 345.058249 -372.402693) (xy 345.048078 -372.403116) (xy 344.331798 -372.403116)
			(xy 344.321621 -372.402737) (xy 344.302817 -372.394942) (xy 344.288431 -372.380543) (xy 344.280654 -372.361732)
			(xy 344.280236 -372.351554) (xy 344.280236 -372.193566) (xy 344.279834 -372.184378) (xy 344.273314 -372.167194)
			(xy 344.267536 -372.160038) (xy 344.245762 -372.134374) (xy 344.207813 -372.078789) (xy 344.17678 -372.019067)
			(xy 344.153106 -371.956064) (xy 344.137132 -371.890684) (xy 344.129087 -371.823862) (xy 344.129086 -371.756559)
			(xy 344.137129 -371.689737) (xy 344.1531 -371.624356) (xy 344.176771 -371.561352) (xy 344.207803 -371.501629)
			(xy 344.245749 -371.446042) (xy 344.267536 -371.42039) (xy 344.273324 -371.413239) (xy 344.279843 -371.396053)
			(xy 344.280236 -371.386862) (xy 344.280236 -370.89334) (xy 344.279798 -370.884156) (xy 344.273303 -370.866972)
			(xy 344.267536 -370.859812) (xy 344.245736 -370.83417) (xy 344.207788 -370.778582) (xy 344.176756 -370.718857)
			(xy 344.153084 -370.655851) (xy 344.137112 -370.590468) (xy 344.129068 -370.523644) (xy 340.851006 -370.523644)
			(xy 340.842963 -370.590465) (xy 340.826991 -370.655847) (xy 340.803319 -370.718851) (xy 340.772287 -370.778574)
			(xy 340.734339 -370.83416) (xy 340.712552 -370.859812) (xy 340.706762 -370.866962) (xy 340.700245 -370.884149)
			(xy 340.699852 -370.89334) (xy 340.699852 -371.386862) (xy 340.700291 -371.396046) (xy 340.706786 -371.41323)
			(xy 340.712552 -371.42039) (xy 340.734354 -371.446031) (xy 340.772303 -371.501618) (xy 340.803336 -371.561344)
			(xy 340.826797 -371.623785) (xy 341.928891 -371.623785) (xy 341.928895 -371.556358) (xy 341.936974 -371.489417)
			(xy 341.953014 -371.423926) (xy 341.976782 -371.360828) (xy 342.007937 -371.301031) (xy 342.04603 -371.245395)
			(xy 342.067896 -371.21973) (xy 342.073704 -371.212593) (xy 342.080212 -371.195396) (xy 342.080596 -371.186202)
			(xy 342.080596 -371.028722) (xy 342.081143 -371.018602) (xy 342.088856 -370.99989) (xy 342.103123 -370.985534)
			(xy 342.121787 -370.977706) (xy 342.131904 -370.97716) (xy 342.848184 -370.97716) (xy 342.858332 -370.977634)
			(xy 342.877076 -370.985417) (xy 342.891399 -370.999797) (xy 342.899106 -371.018572) (xy 342.899492 -371.028722)
			(xy 342.899492 -371.186202) (xy 342.899903 -371.195389) (xy 342.906416 -371.212573) (xy 342.912192 -371.21973)
			(xy 342.934019 -371.245426) (xy 342.972109 -371.301056) (xy 343.003262 -371.360848) (xy 343.027029 -371.423941)
			(xy 343.043067 -371.489426) (xy 343.051146 -371.556361) (xy 343.05115 -371.623782) (xy 343.043077 -371.690718)
			(xy 343.027046 -371.756205) (xy 343.003285 -371.8193) (xy 342.972139 -371.879095) (xy 342.934054 -371.934729)
			(xy 342.912192 -371.960394) (xy 342.906415 -371.967553) (xy 342.899889 -371.984733) (xy 342.899492 -371.993922)
			(xy 342.899492 -372.486174) (xy 342.899917 -372.49536) (xy 342.90642 -372.512544) (xy 342.912192 -372.519702)
			(xy 342.93409 -372.54534) (xy 342.972178 -372.600978) (xy 343.003328 -372.660778) (xy 343.02709 -372.723878)
			(xy 343.043124 -372.789371) (xy 343.051197 -372.856312) (xy 343.051194 -372.923739) (xy 343.043114 -372.99068)
			(xy 343.027075 -373.056171) (xy 343.003307 -373.119269) (xy 342.972152 -373.179066) (xy 342.934058 -373.234701)
			(xy 342.912192 -373.260366) (xy 342.906384 -373.267503) (xy 342.899876 -373.2847) (xy 342.899492 -373.293894)
			(xy 342.899492 -373.451374) (xy 342.898953 -373.461495) (xy 342.89124 -373.48021) (xy 342.87697 -373.494566)
			(xy 342.858302 -373.502392) (xy 342.848184 -373.502936) (xy 342.131904 -373.502936) (xy 342.121755 -373.502476)
			(xy 342.103009 -373.494688) (xy 342.088687 -373.480304) (xy 342.080981 -373.461525) (xy 342.080596 -373.451374)
			(xy 342.080596 -373.293894) (xy 342.080189 -373.284706) (xy 342.073673 -373.267522) (xy 342.067896 -373.260366)
			(xy 342.046066 -373.234673) (xy 342.007976 -373.179042) (xy 341.976824 -373.11925) (xy 341.953058 -373.056157)
			(xy 341.937021 -372.990671) (xy 341.928942 -372.923736) (xy 341.928939 -372.856315) (xy 341.937011 -372.789379)
			(xy 341.953043 -372.723892) (xy 341.976803 -372.660797) (xy 342.00795 -372.601001) (xy 342.046034 -372.545367)
			(xy 342.067896 -372.519702) (xy 342.073674 -372.512543) (xy 342.0802 -372.495363) (xy 342.080596 -372.486174)
			(xy 342.080596 -371.993922) (xy 342.080176 -371.984736) (xy 342.073669 -371.967551) (xy 342.067896 -371.960394)
			(xy 342.045995 -371.934759) (xy 342.007908 -371.87912) (xy 341.976759 -371.81932) (xy 341.952997 -371.756219)
			(xy 341.936964 -371.690726) (xy 341.928891 -371.623785) (xy 340.826797 -371.623785) (xy 340.827009 -371.62435)
			(xy 340.842981 -371.689733) (xy 340.851024 -371.756557) (xy 340.851023 -371.823864) (xy 340.842977 -371.890687)
			(xy 340.827002 -371.956071) (xy 340.803328 -372.019076) (xy 340.772292 -372.0788) (xy 340.734341 -372.134386)
			(xy 340.712552 -372.160038) (xy 340.706751 -372.16718) (xy 340.70024 -372.184373) (xy 340.699852 -372.193566)
			(xy 340.699852 -372.351554) (xy 340.699398 -372.361724) (xy 340.691627 -372.380519) (xy 340.67725 -372.394906)
			(xy 340.65846 -372.402691) (xy 340.64829 -372.403116) (xy 339.93201 -372.403116) (xy 339.921833 -372.402727)
			(xy 339.90303 -372.394937) (xy 339.888643 -372.38054) (xy 339.880866 -372.361731) (xy 339.880448 -372.351554)
			(xy 339.880448 -372.193566) (xy 339.880043 -372.184378) (xy 339.873525 -372.167195) (xy 339.867748 -372.160038)
			(xy 339.845974 -372.134375) (xy 339.808024 -372.07879) (xy 339.77699 -372.019068) (xy 339.753316 -371.956065)
			(xy 339.737342 -371.890684) (xy 339.729296 -371.823863) (xy 339.729295 -371.756558) (xy 339.737338 -371.689737)
			(xy 339.75331 -371.624355) (xy 339.776981 -371.561351) (xy 339.808013 -371.501628) (xy 339.845961 -371.446042)
			(xy 339.867748 -371.42039) (xy 339.873537 -371.41324) (xy 339.880055 -371.396053) (xy 339.880448 -371.386862)
			(xy 339.880448 -370.89334) (xy 339.880008 -370.884156) (xy 339.873514 -370.866972) (xy 339.867748 -370.859812)
			(xy 339.845948 -370.83417) (xy 339.807999 -370.778582) (xy 339.776966 -370.718857) (xy 339.753293 -370.655851)
			(xy 339.737321 -370.590468) (xy 339.729277 -370.523644) (xy 336.451238 -370.523644) (xy 336.451238 -370.523703)
			(xy 336.443163 -370.590641) (xy 336.427128 -370.65613) (xy 336.403363 -370.719227) (xy 336.372211 -370.779022)
			(xy 336.334121 -370.834656) (xy 336.312256 -370.86032) (xy 336.306463 -370.867467) (xy 336.299947 -370.884656)
			(xy 336.299556 -370.893848) (xy 336.299556 -371.386354) (xy 336.299998 -371.395538) (xy 336.306491 -371.412722)
			(xy 336.312256 -371.419882) (xy 336.334135 -371.445535) (xy 336.372226 -371.50117) (xy 336.403379 -371.560968)
			(xy 336.427016 -371.623725) (xy 337.529123 -371.623725) (xy 337.529126 -371.556418) (xy 337.537174 -371.489593)
			(xy 337.55315 -371.424209) (xy 337.576825 -371.361204) (xy 337.60786 -371.301479) (xy 337.645811 -371.245891)
			(xy 337.6676 -371.220238) (xy 337.673405 -371.213099) (xy 337.679915 -371.195904) (xy 337.6803 -371.18671)
			(xy 337.6803 -371.028722) (xy 337.68085 -371.01857) (xy 337.68861 -370.999809) (xy 337.702958 -370.985444)
			(xy 337.721711 -370.977662) (xy 337.731862 -370.97716) (xy 338.448142 -370.97716) (xy 338.458305 -370.9776)
			(xy 338.477079 -370.985392) (xy 338.491444 -370.999774) (xy 338.499213 -371.018558) (xy 338.499704 -371.028722)
			(xy 338.499704 -371.18671) (xy 338.500109 -371.195898) (xy 338.506626 -371.213082) (xy 338.512404 -371.220238)
			(xy 338.534153 -371.245921) (xy 338.5721 -371.301504) (xy 338.603133 -371.361224) (xy 338.626806 -371.424224)
			(xy 338.64278 -371.489602) (xy 338.650827 -371.556421) (xy 338.65083 -371.623722) (xy 338.64279 -371.690541)
			(xy 338.626823 -371.755921) (xy 338.603156 -371.818924) (xy 338.57213 -371.878646) (xy 338.534188 -371.934233)
			(xy 338.512404 -371.959886) (xy 338.506589 -371.967018) (xy 338.500085 -371.984219) (xy 338.499704 -371.993414)
			(xy 338.499704 -372.486682) (xy 338.500122 -372.495868) (xy 338.50663 -372.513053) (xy 338.512404 -372.52021)
			(xy 338.534224 -372.545835) (xy 338.572169 -372.601427) (xy 338.603198 -372.661154) (xy 338.626867 -372.724162)
			(xy 338.642836 -372.789547) (xy 338.650877 -372.856372) (xy 338.650874 -372.923679) (xy 338.642827 -372.990503)
			(xy 338.626852 -373.055887) (xy 338.603177 -373.118892) (xy 338.572142 -373.178617) (xy 338.534192 -373.234205)
			(xy 338.512404 -373.259858) (xy 338.506601 -373.266999) (xy 338.50009 -373.284193) (xy 338.499704 -373.293386)
			(xy 338.499704 -373.451374) (xy 338.499147 -373.461525) (xy 338.491388 -373.480286) (xy 338.477043 -373.49465)
			(xy 338.458292 -373.502433) (xy 338.448142 -373.502936) (xy 337.731862 -373.502936) (xy 337.721699 -373.502497)
			(xy 337.702924 -373.494705) (xy 337.688559 -373.480323) (xy 337.68079 -373.461538) (xy 337.6803 -373.451374)
			(xy 337.6803 -373.293386) (xy 337.679896 -373.284198) (xy 337.673378 -373.267014) (xy 337.6676 -373.259858)
			(xy 337.645847 -373.234178) (xy 337.6079 -373.178595) (xy 337.576867 -373.118874) (xy 337.553194 -373.055874)
			(xy 337.53722 -372.990495) (xy 337.529174 -372.923676) (xy 337.52917 -372.856375) (xy 337.537211 -372.789555)
			(xy 337.553179 -372.724175) (xy 337.576846 -372.661172) (xy 337.607873 -372.601449) (xy 337.645816 -372.545863)
			(xy 337.6676 -372.52021) (xy 337.673417 -372.513079) (xy 337.67992 -372.495878) (xy 337.6803 -372.486682)
			(xy 337.6803 -371.993414) (xy 337.679883 -371.984228) (xy 337.673374 -371.967043) (xy 337.6676 -371.959886)
			(xy 337.645776 -371.934264) (xy 337.607831 -371.878672) (xy 337.576802 -371.818944) (xy 337.553133 -371.755936)
			(xy 337.537163 -371.69055) (xy 337.529123 -371.623725) (xy 336.427016 -371.623725) (xy 336.427144 -371.624066)
			(xy 336.44318 -371.689557) (xy 336.451256 -371.756498) (xy 336.451254 -371.823923) (xy 336.443176 -371.890863)
			(xy 336.427138 -371.956354) (xy 336.40337 -372.019451) (xy 336.372216 -372.079248) (xy 336.334122 -372.134881)
			(xy 336.312256 -372.160546) (xy 336.306452 -372.167686) (xy 336.299943 -372.184881) (xy 336.299556 -372.194074)
			(xy 336.299556 -372.351554) (xy 336.299036 -372.361678) (xy 336.291322 -372.380399) (xy 336.277046 -372.394757)
			(xy 336.258369 -372.402577) (xy 336.248248 -372.403116) (xy 335.531968 -372.403116) (xy 335.521814 -372.402705)
			(xy 335.503064 -372.394902) (xy 335.488742 -372.380502) (xy 335.481041 -372.36171) (xy 335.48066 -372.351554)
			(xy 335.48066 -372.194074) (xy 335.480249 -372.184887) (xy 335.473734 -372.167704) (xy 335.46796 -372.160546)
			(xy 335.446111 -372.134869) (xy 335.408025 -372.079235) (xy 335.376876 -372.01944) (xy 335.353112 -371.956345)
			(xy 335.337077 -371.890858) (xy 335.329001 -371.823921) (xy 335.329 -371.7565) (xy 335.337073 -371.689563)
			(xy 335.353106 -371.624075) (xy 335.376867 -371.560979) (xy 335.408014 -371.501183) (xy 335.446098 -371.445548)
			(xy 335.46796 -371.419882) (xy 335.473754 -371.412735) (xy 335.480269 -371.395546) (xy 335.48066 -371.386354)
			(xy 335.48066 -370.893848) (xy 335.480214 -370.884665) (xy 335.473724 -370.867481) (xy 335.46796 -370.86032)
			(xy 335.446086 -370.834664) (xy 335.408 -370.779027) (xy 335.376852 -370.719229) (xy 335.35309 -370.656131)
			(xy 335.337057 -370.590642) (xy 335.328983 -370.523703) (xy 332.050912 -370.523703) (xy 332.042876 -370.590465)
			(xy 332.026905 -370.655846) (xy 332.003233 -370.71885) (xy 331.972202 -370.778573) (xy 331.934255 -370.83416)
			(xy 331.912468 -370.859812) (xy 331.90668 -370.866963) (xy 331.900161 -370.884149) (xy 331.899768 -370.89334)
			(xy 331.899768 -371.386862) (xy 331.900204 -371.396046) (xy 331.906701 -371.41323) (xy 331.912468 -371.42039)
			(xy 331.934269 -371.446031) (xy 331.972217 -371.501619) (xy 332.00325 -371.561344) (xy 332.026709 -371.623785)
			(xy 333.128803 -371.623785) (xy 333.128807 -371.556358) (xy 333.136887 -371.489417) (xy 333.152927 -371.423926)
			(xy 333.176696 -371.360827) (xy 333.207851 -371.30103) (xy 333.245945 -371.245395) (xy 333.267812 -371.21973)
			(xy 333.273622 -371.212594) (xy 333.280128 -371.195397) (xy 333.280512 -371.186202) (xy 333.280512 -371.028722)
			(xy 333.281044 -371.0186) (xy 333.288759 -370.999885) (xy 333.303031 -370.985529) (xy 333.321701 -370.977704)
			(xy 333.33182 -370.97716) (xy 334.0481 -370.97716) (xy 334.058249 -370.977621) (xy 334.076994 -370.985409)
			(xy 334.091316 -370.999793) (xy 334.099023 -371.018571) (xy 334.099408 -371.028722) (xy 334.099408 -371.186202)
			(xy 334.099815 -371.195389) (xy 334.106331 -371.212574) (xy 334.112108 -371.21973) (xy 334.133934 -371.245426)
			(xy 334.172024 -371.301056) (xy 334.203176 -371.360848) (xy 334.226942 -371.423941) (xy 334.242979 -371.489426)
			(xy 334.251058 -371.556361) (xy 334.251062 -371.623782) (xy 334.24299 -371.690717) (xy 334.226958 -371.756204)
			(xy 334.203199 -371.819299) (xy 334.172053 -371.879095) (xy 334.133969 -371.934729) (xy 334.112108 -371.960394)
			(xy 334.106332 -371.967554) (xy 334.099805 -371.984733) (xy 334.099408 -371.993922) (xy 334.099408 -372.486174)
			(xy 334.099829 -372.49536) (xy 334.106335 -372.512545) (xy 334.112108 -372.519702) (xy 334.134005 -372.54534)
			(xy 334.172092 -372.600978) (xy 334.203241 -372.660779) (xy 334.227003 -372.723879) (xy 334.243036 -372.789371)
			(xy 334.251109 -372.856312) (xy 334.251106 -372.923739) (xy 334.243027 -372.990679) (xy 334.226988 -373.05617)
			(xy 334.20322 -373.119268) (xy 334.172066 -373.179065) (xy 334.133974 -373.234701) (xy 334.112108 -373.260366)
			(xy 334.106302 -373.267504) (xy 334.099793 -373.2847) (xy 334.099408 -373.293894) (xy 334.099408 -373.451374)
			(xy 334.098854 -373.461493) (xy 334.091143 -373.480205) (xy 334.076878 -373.49456) (xy 334.058216 -373.502389)
			(xy 334.0481 -373.502936) (xy 333.33182 -373.502936) (xy 333.321672 -373.502463) (xy 333.302927 -373.494681)
			(xy 333.288604 -373.4803) (xy 333.280897 -373.461524) (xy 333.280512 -373.451374) (xy 333.280512 -373.293894)
			(xy 333.280102 -373.284707) (xy 333.273588 -373.267523) (xy 333.267812 -373.260366) (xy 333.245981 -373.234673)
			(xy 333.20789 -373.179043) (xy 333.176738 -373.119251) (xy 333.152971 -373.056157) (xy 333.136933 -372.990672)
			(xy 333.128854 -372.923736) (xy 333.128851 -372.856315) (xy 333.136924 -372.789379) (xy 333.152956 -372.723891)
			(xy 333.176717 -372.660796) (xy 333.207864 -372.601001) (xy 333.24595 -372.545367) (xy 333.267812 -372.519702)
			(xy 333.273592 -372.512545) (xy 333.280116 -372.495363) (xy 333.280512 -372.486174) (xy 333.280512 -371.993922)
			(xy 333.280088 -371.984736) (xy 333.273584 -371.967552) (xy 333.267812 -371.960394) (xy 333.24591 -371.93476)
			(xy 333.207822 -371.879121) (xy 333.176672 -371.819321) (xy 333.15291 -371.75622) (xy 333.136876 -371.690727)
			(xy 333.128803 -371.623785) (xy 332.026709 -371.623785) (xy 332.026921 -371.62435) (xy 332.042893 -371.689734)
			(xy 332.050936 -371.756558) (xy 332.050935 -371.823864) (xy 332.042889 -371.890687) (xy 332.026915 -371.95607)
			(xy 332.003241 -372.019075) (xy 331.972207 -372.078799) (xy 331.934256 -372.134386) (xy 331.912468 -372.160038)
			(xy 331.906669 -372.167181) (xy 331.900156 -372.184373) (xy 331.899768 -372.193566) (xy 331.899768 -372.351554)
			(xy 331.899299 -372.361722) (xy 331.89153 -372.380514) (xy 331.877158 -372.394901) (xy 331.858373 -372.402688)
			(xy 331.848206 -372.403116) (xy 331.131926 -372.403116) (xy 331.12175 -372.402714) (xy 331.102948 -372.394929)
			(xy 331.08856 -372.380536) (xy 331.080783 -372.36173) (xy 331.080364 -372.351554) (xy 331.080364 -372.193566)
			(xy 331.079956 -372.184379) (xy 331.073439 -372.167195) (xy 331.067664 -372.160038) (xy 331.045889 -372.134375)
			(xy 331.007939 -372.078791) (xy 330.976903 -372.019069) (xy 330.953229 -371.956066) (xy 330.937254 -371.890684)
			(xy 330.929208 -371.823863) (xy 330.929207 -371.756558) (xy 330.93725 -371.689736) (xy 330.953222 -371.624355)
			(xy 330.976895 -371.561351) (xy 331.007928 -371.501628) (xy 331.045876 -371.446042) (xy 331.067664 -371.42039)
			(xy 331.073455 -371.413241) (xy 331.079971 -371.396053) (xy 331.080364 -371.386862) (xy 331.080364 -370.89334)
			(xy 331.07992 -370.884157) (xy 331.073428 -370.866973) (xy 331.067664 -370.859812) (xy 331.045864 -370.83417)
			(xy 331.007914 -370.778582) (xy 330.97688 -370.718858) (xy 330.953206 -370.655852) (xy 330.937234 -370.590468)
			(xy 330.92919 -370.523644) (xy 301.250887 -370.523644) (xy 301.250887 -370.523702) (xy 301.242812 -370.590639)
			(xy 301.226779 -370.656127) (xy 301.203017 -370.719224) (xy 301.171869 -370.77902) (xy 301.133783 -370.834654)
			(xy 301.11192 -370.86032) (xy 301.106135 -370.867473) (xy 301.099613 -370.884658) (xy 301.09922 -370.893848)
			(xy 301.09922 -371.386354) (xy 301.099648 -371.395539) (xy 301.106149 -371.412724) (xy 301.11192 -371.419882)
			(xy 301.133797 -371.445536) (xy 301.171884 -371.501173) (xy 301.203033 -371.560971) (xy 301.226688 -371.623785)
			(xy 302.328773 -371.623785) (xy 302.328777 -371.556358) (xy 302.336856 -371.489418) (xy 302.352895 -371.423927)
			(xy 302.376662 -371.360829) (xy 302.407815 -371.301031) (xy 302.445907 -371.245396) (xy 302.467772 -371.21973)
			(xy 302.47359 -371.2126) (xy 302.48009 -371.195398) (xy 302.480472 -371.186202) (xy 302.480472 -371.028722)
			(xy 302.480945 -371.018593) (xy 302.488672 -370.999866) (xy 302.502963 -370.985508) (xy 302.521653 -370.977693)
			(xy 302.53178 -370.97716) (xy 303.24806 -370.97716) (xy 303.258207 -370.977654) (xy 303.27695 -370.985429)
			(xy 303.291274 -370.999803) (xy 303.298982 -371.018574) (xy 303.299368 -371.028722) (xy 303.299368 -371.186202)
			(xy 303.299784 -371.195388) (xy 303.306294 -371.212572) (xy 303.312068 -371.21973) (xy 303.333896 -371.245425)
			(xy 303.371988 -371.301055) (xy 303.403142 -371.360847) (xy 303.42691 -371.42394) (xy 303.442949 -371.489425)
			(xy 303.451028 -371.556361) (xy 303.451031 -371.623782) (xy 303.442959 -371.690718) (xy 303.426926 -371.756206)
			(xy 303.403165 -371.819301) (xy 303.372017 -371.879096) (xy 303.333931 -371.934729) (xy 303.312068 -371.960394)
			(xy 303.306287 -371.96755) (xy 303.299764 -371.984732) (xy 303.299368 -371.993922) (xy 303.299368 -372.486174)
			(xy 303.299798 -372.495359) (xy 303.306299 -372.512543) (xy 303.312068 -372.519702) (xy 303.333966 -372.545339)
			(xy 303.372056 -372.600977) (xy 303.403207 -372.660777) (xy 303.426971 -372.723877) (xy 303.443005 -372.78937)
			(xy 303.451079 -372.856312) (xy 303.451076 -372.923739) (xy 303.442996 -372.99068) (xy 303.426956 -373.056172)
			(xy 303.403186 -373.11927) (xy 303.37203 -373.179067) (xy 303.333935 -373.234701) (xy 303.312068 -373.260366)
			(xy 303.306257 -373.267501) (xy 303.299752 -373.284699) (xy 303.299368 -373.293894) (xy 303.299368 -373.451374)
			(xy 303.298853 -373.461498) (xy 303.291135 -373.480217) (xy 303.276857 -373.494574) (xy 303.258181 -373.502396)
			(xy 303.24806 -373.502936) (xy 302.53178 -373.502936) (xy 302.521629 -373.502496) (xy 302.502883 -373.4947)
			(xy 302.488562 -373.48031) (xy 302.480856 -373.461527) (xy 302.480472 -373.451374) (xy 302.480472 -373.293894)
			(xy 302.480071 -373.284706) (xy 302.473552 -373.267521) (xy 302.467772 -373.260366) (xy 302.445942 -373.234673)
			(xy 302.407855 -373.179042) (xy 302.376704 -373.119249) (xy 302.352939 -373.056156) (xy 302.336902 -372.99067)
			(xy 302.328824 -372.923736) (xy 302.328821 -372.856315) (xy 302.336893 -372.78938) (xy 302.352924 -372.723893)
			(xy 302.376683 -372.660798) (xy 302.407828 -372.601002) (xy 302.445911 -372.545368) (xy 302.467772 -372.519702)
			(xy 302.473559 -372.51255) (xy 302.480077 -372.495364) (xy 302.480472 -372.486174) (xy 302.480472 -371.993922)
			(xy 302.480058 -371.984735) (xy 302.473548 -371.96755) (xy 302.467772 -371.960394) (xy 302.445872 -371.934759)
			(xy 302.407786 -371.87912) (xy 302.376638 -371.819319) (xy 302.352878 -371.756218) (xy 302.336846 -371.690726)
			(xy 302.328773 -371.623785) (xy 301.226688 -371.623785) (xy 301.226795 -371.624069) (xy 301.242829 -371.689559)
			(xy 301.250904 -371.756498) (xy 301.250903 -371.823923) (xy 301.242826 -371.890862) (xy 301.226789 -371.956351)
			(xy 301.203024 -372.019449) (xy 301.171873 -372.079245) (xy 301.133784 -372.13488) (xy 301.11192 -372.160546)
			(xy 301.106124 -372.167692) (xy 301.099608 -372.184882) (xy 301.09922 -372.194074) (xy 301.09922 -372.351554)
			(xy 301.098734 -372.361683) (xy 301.091014 -372.38041) (xy 301.076727 -372.39477) (xy 301.058038 -372.402583)
			(xy 301.047912 -372.403116) (xy 300.331632 -372.403116) (xy 300.321482 -372.402653) (xy 300.302733 -372.394871)
			(xy 300.288409 -372.380487) (xy 300.280705 -372.361706) (xy 300.280324 -372.351554) (xy 300.280324 -372.194074)
			(xy 300.279921 -372.184886) (xy 300.273402 -372.167702) (xy 300.267624 -372.160546) (xy 300.245773 -372.13487)
			(xy 300.207682 -372.079237) (xy 300.17653 -372.019443) (xy 300.152764 -371.956347) (xy 300.136726 -371.890859)
			(xy 300.128649 -371.823922) (xy 300.128648 -371.756499) (xy 300.136723 -371.689561) (xy 300.152757 -371.624073)
			(xy 300.176521 -371.560976) (xy 300.207671 -371.501181) (xy 300.24576 -371.445547) (xy 300.267624 -371.419882)
			(xy 300.273413 -371.412732) (xy 300.279932 -371.395545) (xy 300.280324 -371.386354) (xy 300.280324 -370.893848)
			(xy 300.279885 -370.884664) (xy 300.273391 -370.86748) (xy 300.267624 -370.86032) (xy 300.245747 -370.834665)
			(xy 300.207657 -370.779029) (xy 300.176506 -370.719232) (xy 300.152741 -370.656134) (xy 300.136706 -370.590643)
			(xy 300.128631 -370.523704) (xy 296.851096 -370.523704) (xy 296.843021 -370.590639) (xy 296.826988 -370.656127)
			(xy 296.803227 -370.719223) (xy 296.772079 -370.779019) (xy 296.733994 -370.834654) (xy 296.712132 -370.86032)
			(xy 296.706336 -370.867465) (xy 296.699823 -370.884656) (xy 296.699432 -370.893848) (xy 296.699432 -371.386354)
			(xy 296.699879 -371.395537) (xy 296.706369 -371.412721) (xy 296.712132 -371.419882) (xy 296.734009 -371.445536)
			(xy 296.772095 -371.501173) (xy 296.803243 -371.560971) (xy 296.826876 -371.623726) (xy 297.92898 -371.623726)
			(xy 297.928984 -371.556417) (xy 297.937032 -371.489591) (xy 297.95301 -371.424206) (xy 297.976689 -371.3612)
			(xy 298.007729 -371.301476) (xy 298.045685 -371.245889) (xy 298.067476 -371.220238) (xy 298.073279 -371.213097)
			(xy 298.07979 -371.195903) (xy 298.080176 -371.18671) (xy 298.080176 -371.028722) (xy 298.080583 -371.018547)
			(xy 298.088368 -370.999746) (xy 298.102759 -370.985359) (xy 298.121563 -370.97758) (xy 298.131738 -370.97716)
			(xy 298.848018 -370.97716) (xy 298.858193 -370.97755) (xy 298.876993 -370.985345) (xy 298.891378 -370.999741)
			(xy 298.899158 -371.018546) (xy 298.89958 -371.028722) (xy 298.89958 -371.18671) (xy 298.89999 -371.195897)
			(xy 298.906504 -371.213081) (xy 298.91228 -371.220238) (xy 298.93403 -371.245921) (xy 298.971978 -371.301504)
			(xy 299.003012 -371.361223) (xy 299.026686 -371.424224) (xy 299.042661 -371.489602) (xy 299.050708 -371.556421)
			(xy 299.050711 -371.623722) (xy 299.042671 -371.690542) (xy 299.026703 -371.755922) (xy 299.003035 -371.818925)
			(xy 298.972008 -371.878647) (xy 298.934065 -371.934233) (xy 298.91228 -371.959886) (xy 298.906462 -371.967016)
			(xy 298.899961 -371.984218) (xy 298.89958 -371.993414) (xy 298.89958 -372.486682) (xy 298.900003 -372.495868)
			(xy 298.906508 -372.513052) (xy 298.91228 -372.52021) (xy 298.934101 -372.545835) (xy 298.972047 -372.601426)
			(xy 299.003078 -372.661153) (xy 299.026748 -372.724161) (xy 299.042718 -372.789547) (xy 299.050759 -372.856372)
			(xy 299.050756 -372.923679) (xy 299.042709 -372.990504) (xy 299.026733 -373.055888) (xy 299.003057 -373.118894)
			(xy 298.972021 -373.178618) (xy 298.934069 -373.234206) (xy 298.91228 -373.259858) (xy 298.906474 -373.266996)
			(xy 298.899966 -373.284192) (xy 298.89958 -373.293386) (xy 298.89958 -373.451374) (xy 298.899115 -373.461542)
			(xy 298.891342 -373.480332) (xy 298.876969 -373.494717) (xy 298.858185 -373.502506) (xy 298.848018 -373.502936)
			(xy 298.131738 -373.502936) (xy 298.121566 -373.502504) (xy 298.102767 -373.494727) (xy 298.08838 -373.480343)
			(xy 298.080598 -373.461546) (xy 298.080176 -373.451374) (xy 298.080176 -373.293386) (xy 298.079778 -373.284197)
			(xy 298.073256 -373.267013) (xy 298.067476 -373.259858) (xy 298.045721 -373.234179) (xy 298.007768 -373.178597)
			(xy 297.976732 -373.118878) (xy 297.953055 -373.055877) (xy 297.937079 -372.990497) (xy 297.929031 -372.923677)
			(xy 297.929028 -372.856374) (xy 297.93707 -372.789553) (xy 297.95304 -372.724172) (xy 297.976711 -372.661169)
			(xy 298.007742 -372.601447) (xy 298.045689 -372.545862) (xy 298.067476 -372.52021) (xy 298.073291 -372.513077)
			(xy 298.079795 -372.495877) (xy 298.080176 -372.486682) (xy 298.080176 -371.993414) (xy 298.079765 -371.984227)
			(xy 298.073252 -371.967042) (xy 298.067476 -371.959886) (xy 298.04565 -371.934265) (xy 298.007699 -371.878675)
			(xy 297.976666 -371.818948) (xy 297.952993 -371.755939) (xy 297.937022 -371.690552) (xy 297.92898 -371.623726)
			(xy 296.826876 -371.623726) (xy 296.827005 -371.624069) (xy 296.843039 -371.689559) (xy 296.851113 -371.756498)
			(xy 296.851112 -371.823923) (xy 296.843035 -371.890861) (xy 296.826999 -371.956351) (xy 296.803235 -372.019448)
			(xy 296.772084 -372.079245) (xy 296.733996 -372.13488) (xy 296.712132 -372.160546) (xy 296.706325 -372.167684)
			(xy 296.699819 -372.18488) (xy 296.699432 -372.194074) (xy 296.699432 -372.351554) (xy 296.698935 -372.361681)
			(xy 296.691217 -372.380407) (xy 296.676933 -372.394765) (xy 296.658249 -372.402581) (xy 296.648124 -372.403116)
			(xy 295.931844 -372.403116) (xy 295.921695 -372.402643) (xy 295.902946 -372.394865) (xy 295.888622 -372.380484)
			(xy 295.880918 -372.361705) (xy 295.880536 -372.351554) (xy 295.880536 -372.194074) (xy 295.88013 -372.184887)
			(xy 295.873613 -372.167703) (xy 295.867836 -372.160546) (xy 295.845985 -372.13487) (xy 295.807893 -372.079238)
			(xy 295.77674 -372.019444) (xy 295.752973 -371.956348) (xy 295.736936 -371.89086) (xy 295.728858 -371.823922)
			(xy 295.728857 -371.756499) (xy 295.736932 -371.689561) (xy 295.752967 -371.624072) (xy 295.776731 -371.560976)
			(xy 295.807882 -371.50118) (xy 295.845972 -371.445547) (xy 295.867836 -371.419882) (xy 295.873627 -371.412733)
			(xy 295.880144 -371.395545) (xy 295.880536 -371.386354) (xy 295.880536 -370.893848) (xy 295.880095 -370.884664)
			(xy 295.873602 -370.86748) (xy 295.867836 -370.86032) (xy 295.845959 -370.834665) (xy 295.807868 -370.77903)
			(xy 295.776716 -370.719233) (xy 295.752951 -370.656134) (xy 295.736915 -370.590644) (xy 295.72884 -370.523704)
			(xy 292.450793 -370.523704) (xy 292.442757 -370.590465) (xy 292.426785 -370.655847) (xy 292.403113 -370.718851)
			(xy 292.37208 -370.778574) (xy 292.334131 -370.83416) (xy 292.312344 -370.859812) (xy 292.306553 -370.866961)
			(xy 292.300036 -370.884149) (xy 292.299644 -370.89334) (xy 292.299644 -371.386862) (xy 292.300085 -371.396046)
			(xy 292.306578 -371.41323) (xy 292.312344 -371.42039) (xy 292.334146 -371.44603) (xy 292.372096 -371.501618)
			(xy 292.403129 -371.561343) (xy 292.42659 -371.623785) (xy 293.528685 -371.623785) (xy 293.528689 -371.556358)
			(xy 293.536768 -371.489418) (xy 293.552807 -371.423927) (xy 293.576575 -371.360828) (xy 293.60773 -371.301031)
			(xy 293.645822 -371.245395) (xy 293.667688 -371.21973) (xy 293.673495 -371.212592) (xy 293.680004 -371.195396)
			(xy 293.680388 -371.186202) (xy 293.680388 -371.028722) (xy 293.680943 -371.018603) (xy 293.688654 -370.999892)
			(xy 293.702919 -370.985537) (xy 293.72158 -370.977708) (xy 293.731696 -370.97716) (xy 294.447976 -370.97716)
			(xy 294.458078 -370.977704) (xy 294.476748 -370.985426) (xy 294.491043 -370.999705) (xy 294.498785 -371.018366)
			(xy 294.499284 -371.028468) (xy 294.499284 -371.186202) (xy 294.499697 -371.195389) (xy 294.506209 -371.212573)
			(xy 294.511984 -371.21973) (xy 294.533811 -371.245426) (xy 294.571902 -371.301056) (xy 294.603055 -371.360847)
			(xy 294.626822 -371.42394) (xy 294.642861 -371.489426) (xy 294.65094 -371.556361) (xy 294.650944 -371.623782)
			(xy 294.642871 -371.690718) (xy 294.626839 -371.756205) (xy 294.603079 -371.8193) (xy 294.571932 -371.879095)
			(xy 294.533846 -371.934729) (xy 294.511984 -371.960394) (xy 294.506206 -371.967552) (xy 294.499681 -371.984733)
			(xy 294.499284 -371.993922) (xy 294.499284 -372.486174) (xy 294.49971 -372.495359) (xy 294.506213 -372.512544)
			(xy 294.511984 -372.519702) (xy 294.533882 -372.545339) (xy 294.571971 -372.600978) (xy 294.603121 -372.660777)
			(xy 294.626884 -372.723878) (xy 294.642917 -372.789371) (xy 294.650991 -372.856312) (xy 294.650988 -372.923739)
			(xy 294.642908 -372.99068) (xy 294.626869 -373.056171) (xy 294.6031 -373.119269) (xy 294.571944 -373.179066)
			(xy 294.533851 -373.234701) (xy 294.511984 -373.260366) (xy 294.506175 -373.267502) (xy 294.499668 -373.2847)
			(xy 294.499284 -373.293894) (xy 294.499284 -373.451374) (xy 294.498753 -373.461496) (xy 294.491038 -373.480212)
			(xy 294.476766 -373.494569) (xy 294.458095 -373.502393) (xy 294.447976 -373.502936) (xy 293.731696 -373.502936)
			(xy 293.721591 -373.502419) (xy 293.70292 -373.494687) (xy 293.688627 -373.4804) (xy 293.680886 -373.461732)
			(xy 293.680388 -373.451628) (xy 293.680388 -373.293894) (xy 293.679983 -373.284706) (xy 293.673466 -373.267522)
			(xy 293.667688 -373.260366) (xy 293.645858 -373.234673) (xy 293.607769 -373.179042) (xy 293.576617 -373.11925)
			(xy 293.552852 -373.056156) (xy 293.536814 -372.990671) (xy 293.528736 -372.923736) (xy 293.528733 -372.856315)
			(xy 293.536805 -372.789379) (xy 293.552837 -372.723892) (xy 293.576597 -372.660797) (xy 293.607743 -372.601002)
			(xy 293.645826 -372.545367) (xy 293.667688 -372.519702) (xy 293.673465 -372.512543) (xy 293.679992 -372.495363)
			(xy 293.680388 -372.486174) (xy 293.680388 -371.993922) (xy 293.67997 -371.984736) (xy 293.673462 -371.967551)
			(xy 293.667688 -371.960394) (xy 293.645787 -371.934759) (xy 293.6077 -371.87912) (xy 293.576552 -371.81932)
			(xy 293.55279 -371.756219) (xy 293.536758 -371.690726) (xy 293.528685 -371.623785) (xy 292.42659 -371.623785)
			(xy 292.426802 -371.624349) (xy 292.442775 -371.689733) (xy 292.450818 -371.756557) (xy 292.450817 -371.823864)
			(xy 292.442771 -371.890688) (xy 292.426796 -371.956071) (xy 292.403121 -372.019076) (xy 292.372085 -372.0788)
			(xy 292.334133 -372.134386) (xy 292.312344 -372.160038) (xy 292.306542 -372.167179) (xy 292.300032 -372.184373)
			(xy 292.299644 -372.193566) (xy 292.299644 -372.351554) (xy 292.299198 -372.361725) (xy 292.291425 -372.380522)
			(xy 292.277046 -372.394909) (xy 292.258253 -372.402693) (xy 292.248082 -372.403116) (xy 291.531802 -372.403116)
			(xy 291.521625 -372.402733) (xy 291.502821 -372.394941) (xy 291.488435 -372.380542) (xy 291.480658 -372.361732)
			(xy 291.48024 -372.351554) (xy 291.48024 -372.193566) (xy 291.479837 -372.184378) (xy 291.473317 -372.167194)
			(xy 291.46754 -372.160038) (xy 291.445766 -372.134374) (xy 291.407817 -372.07879) (xy 291.376783 -372.019068)
			(xy 291.353109 -371.956065) (xy 291.337135 -371.890684) (xy 291.32909 -371.823862) (xy 291.329089 -371.756559)
			(xy 291.337132 -371.689737) (xy 291.353103 -371.624356) (xy 291.376774 -371.561352) (xy 291.407806 -371.501628)
			(xy 291.445753 -371.446042) (xy 291.46754 -371.42039) (xy 291.473328 -371.413239) (xy 291.479847 -371.396053)
			(xy 291.48024 -371.386862) (xy 291.48024 -370.89334) (xy 291.479801 -370.884156) (xy 291.473306 -370.866972)
			(xy 291.46754 -370.859812) (xy 291.44574 -370.83417) (xy 291.407792 -370.778582) (xy 291.376759 -370.718857)
			(xy 291.353087 -370.655851) (xy 291.337115 -370.590468) (xy 291.329071 -370.523644) (xy 288.051032 -370.523644)
			(xy 288.051032 -370.523703) (xy 288.042957 -370.590641) (xy 288.026921 -370.65613) (xy 288.003156 -370.719227)
			(xy 287.972004 -370.779022) (xy 287.933913 -370.834656) (xy 287.912048 -370.86032) (xy 287.906254 -370.867467)
			(xy 287.899739 -370.884656) (xy 287.899348 -370.893848) (xy 287.899348 -371.386354) (xy 287.899792 -371.395537)
			(xy 287.906284 -371.412721) (xy 287.912048 -371.419882) (xy 287.933928 -371.445535) (xy 287.972019 -371.50117)
			(xy 288.003172 -371.560967) (xy 288.02681 -371.623726) (xy 289.128893 -371.623726) (xy 289.128896 -371.556417)
			(xy 289.136945 -371.489591) (xy 289.152924 -371.424206) (xy 289.176603 -371.3612) (xy 289.207644 -371.301475)
			(xy 289.2456 -371.245889) (xy 289.267392 -371.220238) (xy 289.273196 -371.213098) (xy 289.279707 -371.195904)
			(xy 289.280092 -371.18671) (xy 289.280092 -371.028722) (xy 289.28065 -371.018571) (xy 289.288409 -370.999811)
			(xy 289.302754 -370.985447) (xy 289.321504 -370.977663) (xy 289.331654 -370.97716) (xy 290.047934 -370.97716)
			(xy 290.058097 -370.977606) (xy 290.076871 -370.985396) (xy 290.091236 -370.999776) (xy 290.099005 -371.018559)
			(xy 290.099496 -371.028722) (xy 290.099496 -371.18671) (xy 290.099902 -371.195898) (xy 290.106419 -371.213082)
			(xy 290.112196 -371.220238) (xy 290.133945 -371.245921) (xy 290.171893 -371.301504) (xy 290.202926 -371.361224)
			(xy 290.226599 -371.424224) (xy 290.242574 -371.489602) (xy 290.250621 -371.556421) (xy 290.250624 -371.623722)
			(xy 290.242584 -371.690542) (xy 290.226616 -371.755921) (xy 290.202949 -371.818924) (xy 290.171922 -371.878647)
			(xy 290.13398 -371.934233) (xy 290.112196 -371.959886) (xy 290.10638 -371.967017) (xy 290.099877 -371.984218)
			(xy 290.099496 -371.993414) (xy 290.099496 -372.486682) (xy 290.099916 -372.495868) (xy 290.106423 -372.513053)
			(xy 290.112196 -372.52021) (xy 290.134016 -372.545835) (xy 290.171962 -372.601426) (xy 290.202991 -372.661154)
			(xy 290.226661 -372.724162) (xy 290.24263 -372.789547) (xy 290.250671 -372.856372) (xy 290.250668 -372.923679)
			(xy 290.242621 -372.990503) (xy 290.226646 -373.055887) (xy 290.202971 -373.118893) (xy 290.171935 -373.178618)
			(xy 290.133985 -373.234205) (xy 290.112196 -373.259858) (xy 290.106392 -373.266998) (xy 290.099882 -373.284192)
			(xy 290.099496 -373.293386) (xy 290.099496 -373.451374) (xy 290.098946 -373.461526) (xy 290.091187 -373.480288)
			(xy 290.076838 -373.494653) (xy 290.058085 -373.502435) (xy 290.047934 -373.502936) (xy 289.331654 -373.502936)
			(xy 289.32149 -373.502504) (xy 289.302715 -373.494709) (xy 289.28835 -373.480325) (xy 289.280582 -373.461539)
			(xy 289.280092 -373.451374) (xy 289.280092 -373.293386) (xy 289.27969 -373.284198) (xy 289.273171 -373.267014)
			(xy 289.267392 -373.259858) (xy 289.245636 -373.234179) (xy 289.207683 -373.178598) (xy 289.176645 -373.118878)
			(xy 289.152968 -373.055877) (xy 289.136991 -372.990498) (xy 289.128943 -372.923677) (xy 289.12894 -372.856374)
			(xy 289.136982 -372.789553) (xy 289.152953 -372.724172) (xy 289.176624 -372.661168) (xy 289.207656 -372.601446)
			(xy 289.245605 -372.545861) (xy 289.267392 -372.52021) (xy 289.273208 -372.513079) (xy 289.279711 -372.495878)
			(xy 289.280092 -372.486682) (xy 289.280092 -371.993414) (xy 289.279677 -371.984227) (xy 289.273167 -371.967043)
			(xy 289.267392 -371.959886) (xy 289.245565 -371.934265) (xy 289.207614 -371.878676) (xy 289.17658 -371.818948)
			(xy 289.152907 -371.755939) (xy 289.136935 -371.690553) (xy 289.128893 -371.623726) (xy 288.02681 -371.623726)
			(xy 288.026938 -371.624066) (xy 288.042974 -371.689557) (xy 288.05105 -371.756498) (xy 288.051048 -371.823923)
			(xy 288.04297 -371.890864) (xy 288.026932 -371.956354) (xy 288.003164 -372.019452) (xy 287.972008 -372.079248)
			(xy 287.933915 -372.134882) (xy 287.912048 -372.160546) (xy 287.906243 -372.167685) (xy 287.899735 -372.18488)
			(xy 287.899348 -372.194074) (xy 287.899348 -372.351554) (xy 287.898835 -372.361679) (xy 287.89112 -372.380402)
			(xy 287.876842 -372.39476) (xy 287.858162 -372.402579) (xy 287.84804 -372.403116) (xy 287.13176 -372.403116)
			(xy 287.121651 -372.402648) (xy 287.102975 -372.3949) (xy 287.088682 -372.380598) (xy 287.080946 -372.361918)
			(xy 287.080452 -372.351808) (xy 287.080452 -372.194074) (xy 287.080043 -372.184887) (xy 287.073527 -372.167703)
			(xy 287.067752 -372.160546) (xy 287.0459 -372.13487) (xy 287.007807 -372.079238) (xy 286.976653 -372.019444)
			(xy 286.952886 -371.956349) (xy 286.936848 -371.89086) (xy 286.92877 -371.823922) (xy 286.928769 -371.756499)
			(xy 286.936844 -371.68956) (xy 286.95288 -371.624072) (xy 286.976645 -371.560975) (xy 287.007797 -371.50118)
			(xy 287.045887 -371.445546) (xy 287.067752 -371.419882) (xy 287.073545 -371.412735) (xy 287.08006 -371.395546)
			(xy 287.080452 -371.386354) (xy 287.080452 -370.893848) (xy 287.080007 -370.884665) (xy 287.073516 -370.867481)
			(xy 287.067752 -370.86032) (xy 287.045874 -370.834665) (xy 287.007783 -370.779031) (xy 286.97663 -370.719233)
			(xy 286.952864 -370.656135) (xy 286.936828 -370.590644) (xy 286.928752 -370.523704) (xy 266.12088 -370.523704)
			(xy 266.12088 -374.423882) (xy 286.928731 -374.423882) (xy 286.928735 -374.356454) (xy 286.936815 -374.289512)
			(xy 286.952857 -374.22402) (xy 286.976628 -374.160921) (xy 287.007787 -374.101124) (xy 287.045884 -374.04549)
			(xy 287.067752 -374.019826) (xy 287.073569 -374.012695) (xy 287.08007 -373.995494) (xy 287.080452 -373.986298)
			(xy 287.080452 -373.828818) (xy 287.080942 -373.818691) (xy 287.088666 -373.799968) (xy 287.102951 -373.785611)
			(xy 287.121636 -373.777793) (xy 287.13176 -373.777256) (xy 287.84804 -373.777256) (xy 287.858146 -373.777751)
			(xy 287.876817 -373.785494) (xy 287.891108 -373.799787) (xy 287.898849 -373.818458) (xy 287.899348 -373.828564)
			(xy 287.899348 -373.986298) (xy 287.899771 -373.995484) (xy 287.906277 -374.012667) (xy 287.912048 -374.019826)
			(xy 287.933873 -374.045524) (xy 287.971966 -374.101153) (xy 288.003121 -374.160944) (xy 288.02689 -374.224037)
			(xy 288.04293 -374.289522) (xy 288.05101 -374.356458) (xy 288.051014 -374.423823) (xy 291.32905 -374.423823)
			(xy 291.329054 -374.356514) (xy 291.337102 -374.289689) (xy 291.35308 -374.224304) (xy 291.376757 -374.161298)
			(xy 291.407796 -374.101573) (xy 291.44575 -374.045986) (xy 291.46754 -374.020334) (xy 291.473352 -374.0132)
			(xy 291.479857 -373.996001) (xy 291.48024 -373.986806) (xy 291.48024 -373.828818) (xy 291.480678 -373.818647)
			(xy 291.488458 -373.799853) (xy 291.502839 -373.785467) (xy 291.521631 -373.777682) (xy 291.531802 -373.777256)
			(xy 292.248082 -373.777256) (xy 292.258255 -373.777679) (xy 292.277053 -373.785461) (xy 292.291439 -373.799847)
			(xy 292.299221 -373.818645) (xy 292.299644 -373.828818) (xy 292.299644 -373.986806) (xy 292.300064 -373.995992)
			(xy 292.306572 -374.013176) (xy 292.312344 -374.020334) (xy 292.334091 -374.04602) (xy 292.372042 -374.101601)
			(xy 292.403078 -374.16132) (xy 292.426754 -374.22432) (xy 292.44273 -374.289698) (xy 292.450778 -374.356517)
			(xy 292.450782 -374.423819) (xy 292.450774 -374.423882) (xy 295.728819 -374.423882) (xy 295.728822 -374.356455)
			(xy 295.736903 -374.289513) (xy 295.752944 -374.224021) (xy 295.776715 -374.160922) (xy 295.807872 -374.101125)
			(xy 295.845968 -374.045491) (xy 295.867836 -374.019826) (xy 295.873651 -374.012694) (xy 295.880154 -373.995493)
			(xy 295.880536 -373.986298) (xy 295.880536 -373.828818) (xy 295.881041 -373.818693) (xy 295.888762 -373.799973)
			(xy 295.903043 -373.785616) (xy 295.921722 -373.777796) (xy 295.931844 -373.777256) (xy 296.648124 -373.777256)
			(xy 296.658274 -373.777701) (xy 296.677019 -373.785496) (xy 296.69134 -373.799885) (xy 296.699046 -373.818666)
			(xy 296.699432 -373.828818) (xy 296.699432 -373.986298) (xy 296.699858 -373.995483) (xy 296.706362 -374.012667)
			(xy 296.712132 -374.019826) (xy 296.733954 -374.045526) (xy 296.772041 -374.101156) (xy 296.803192 -374.160948)
			(xy 296.826957 -374.22404) (xy 296.842995 -374.289525) (xy 296.851073 -374.356459) (xy 296.851077 -374.423878)
			(xy 296.851077 -374.423882) (xy 300.12861 -374.423882) (xy 300.128613 -374.356455) (xy 300.136694 -374.289513)
			(xy 300.152734 -374.224021) (xy 300.176504 -374.160923) (xy 300.207661 -374.101126) (xy 300.245757 -374.045491)
			(xy 300.267624 -374.019826) (xy 300.273437 -374.012693) (xy 300.279941 -373.995493) (xy 300.280324 -373.986298)
			(xy 300.280324 -373.828818) (xy 300.280841 -373.818694) (xy 300.28856 -373.799977) (xy 300.302837 -373.78562)
			(xy 300.321511 -373.777798) (xy 300.331632 -373.777256) (xy 301.047912 -373.777256) (xy 301.058061 -373.777711)
			(xy 301.076806 -373.785502) (xy 301.091127 -373.799888) (xy 301.098834 -373.818667) (xy 301.09922 -373.828818)
			(xy 301.09922 -373.986298) (xy 301.099627 -373.995486) (xy 301.106142 -374.01267) (xy 301.11192 -374.019826)
			(xy 301.133742 -374.045526) (xy 301.171831 -374.101156) (xy 301.202982 -374.160947) (xy 301.226748 -374.22404)
			(xy 301.242785 -374.289524) (xy 301.250864 -374.356458) (xy 301.250868 -374.423823) (xy 330.929168 -374.423823)
			(xy 330.929172 -374.356514) (xy 330.937221 -374.289688) (xy 330.953199 -374.224303) (xy 330.976878 -374.161297)
			(xy 331.007917 -374.101572) (xy 331.045873 -374.045986) (xy 331.067664 -374.020334) (xy 331.073479 -374.013202)
			(xy 331.079981 -373.996001) (xy 331.080364 -373.986806) (xy 331.080364 -373.828818) (xy 331.080779 -373.818644)
			(xy 331.088563 -373.799845) (xy 331.102952 -373.785458) (xy 331.121752 -373.777677) (xy 331.131926 -373.777256)
			(xy 331.848206 -373.777256) (xy 331.85838 -373.777659) (xy 331.877178 -373.78545) (xy 331.891564 -373.799842)
			(xy 331.899345 -373.818644) (xy 331.899768 -373.828818) (xy 331.899768 -373.986806) (xy 331.900182 -373.995993)
			(xy 331.906694 -374.013177) (xy 331.912468 -374.020334) (xy 331.934214 -374.04602) (xy 331.972164 -374.101602)
			(xy 332.003198 -374.161321) (xy 332.026873 -374.224321) (xy 332.042849 -374.289699) (xy 332.050896 -374.356518)
			(xy 332.0509 -374.423819) (xy 332.050892 -374.423882) (xy 335.328961 -374.423882) (xy 335.328965 -374.356455)
			(xy 335.337045 -374.289515) (xy 335.353083 -374.224024) (xy 335.37685 -374.160926) (xy 335.408004 -374.101128)
			(xy 335.446095 -374.045492) (xy 335.46796 -374.019826) (xy 335.473778 -374.012696) (xy 335.480278 -373.995494)
			(xy 335.48066 -373.986298) (xy 335.48066 -373.828818) (xy 335.481142 -373.81869) (xy 335.488867 -373.799965)
			(xy 335.503156 -373.785608) (xy 335.521842 -373.777791) (xy 335.531968 -373.777256) (xy 336.248248 -373.777256)
			(xy 336.2584 -373.777682) (xy 336.277145 -373.785485) (xy 336.291465 -373.799879) (xy 336.299171 -373.818664)
			(xy 336.299556 -373.828818) (xy 336.299556 -373.986298) (xy 336.299977 -373.995484) (xy 336.306484 -374.012668)
			(xy 336.312256 -374.019826) (xy 336.33408 -374.045525) (xy 336.372173 -374.101153) (xy 336.403328 -374.160944)
			(xy 336.427097 -374.224037) (xy 336.443136 -374.289523) (xy 336.451216 -374.356458) (xy 336.45122 -374.423823)
			(xy 339.729256 -374.423823) (xy 339.72926 -374.356514) (xy 339.737309 -374.289689) (xy 339.753286 -374.224304)
			(xy 339.776964 -374.161298) (xy 339.808003 -374.101573) (xy 339.845957 -374.045986) (xy 339.867748 -374.020334)
			(xy 339.873561 -374.013201) (xy 339.880065 -373.996001) (xy 339.880448 -373.986806) (xy 339.880448 -373.828818)
			(xy 339.880879 -373.818646) (xy 339.88866 -373.79985) (xy 339.903043 -373.785464) (xy 339.921838 -373.77768)
			(xy 339.93201 -373.777256) (xy 340.64829 -373.777256) (xy 340.658463 -373.777672) (xy 340.677261 -373.785457)
			(xy 340.691647 -373.799846) (xy 340.699429 -373.818645) (xy 340.699852 -373.828818) (xy 340.699852 -373.986806)
			(xy 340.70027 -373.995992) (xy 340.706779 -374.013176) (xy 340.712552 -374.020334) (xy 340.734299 -374.04602)
			(xy 340.772249 -374.101601) (xy 340.803285 -374.16132) (xy 340.82696 -374.22432) (xy 340.842936 -374.289699)
			(xy 340.850984 -374.356517) (xy 340.850988 -374.423819) (xy 340.850988 -374.423823) (xy 344.129047 -374.423823)
			(xy 344.129051 -374.356514) (xy 344.137099 -374.289689) (xy 344.153077 -374.224304) (xy 344.176754 -374.161298)
			(xy 344.207792 -374.101573) (xy 344.245746 -374.045986) (xy 344.267536 -374.020334) (xy 344.273348 -374.0132)
			(xy 344.279852 -373.996001) (xy 344.280236 -373.986806) (xy 344.280236 -373.828818) (xy 344.280678 -373.818648)
			(xy 344.288457 -373.799854) (xy 344.302837 -373.785468) (xy 344.321628 -373.777682) (xy 344.331798 -373.777256)
			(xy 345.048078 -373.777256) (xy 345.05825 -373.777683) (xy 345.077048 -373.785464) (xy 345.091434 -373.799849)
			(xy 345.099217 -373.818646) (xy 345.09964 -373.828818) (xy 345.09964 -373.986806) (xy 345.100061 -373.995992)
			(xy 345.106569 -374.013175) (xy 345.11234 -374.020334) (xy 345.134087 -374.04602) (xy 345.172038 -374.101601)
			(xy 345.203075 -374.16132) (xy 345.226751 -374.22432) (xy 345.242727 -374.289698) (xy 345.250775 -374.356517)
			(xy 345.250779 -374.423819) (xy 345.250779 -374.423823) (xy 374.929078 -374.423823) (xy 374.929081 -374.356514)
			(xy 374.93713 -374.289688) (xy 374.953109 -374.224303) (xy 374.976788 -374.161296) (xy 375.007828 -374.101572)
			(xy 375.045784 -374.045985) (xy 375.067576 -374.020334) (xy 375.07338 -374.013194) (xy 375.079891 -373.996)
			(xy 375.080276 -373.986806) (xy 375.080276 -373.828818) (xy 375.080679 -373.818643) (xy 375.088465 -373.799841)
			(xy 375.102858 -373.785454) (xy 375.121663 -373.777675) (xy 375.131838 -373.777256) (xy 375.848118 -373.777256)
			(xy 375.858279 -373.777719) (xy 375.877052 -373.785503) (xy 375.891418 -373.799878) (xy 375.899188 -373.818656)
			(xy 375.89968 -373.828818) (xy 375.89968 -373.986806) (xy 375.900092 -373.995993) (xy 375.906605 -374.013177)
			(xy 375.91238 -374.020334) (xy 375.934126 -374.046021) (xy 375.972074 -374.101603) (xy 376.003108 -374.161322)
			(xy 376.026783 -374.224321) (xy 376.042758 -374.289699) (xy 376.050805 -374.356518) (xy 376.050809 -374.423819)
			(xy 376.050801 -374.423882) (xy 379.32887 -374.423882) (xy 379.328874 -374.356455) (xy 379.336954 -374.289515)
			(xy 379.352993 -374.224024) (xy 379.376761 -374.160925) (xy 379.407915 -374.101127) (xy 379.446007 -374.045492)
			(xy 379.467872 -374.019826) (xy 379.473691 -374.012697) (xy 379.48019 -373.995494) (xy 379.480572 -373.986298)
			(xy 379.480572 -373.828818) (xy 379.481042 -373.818688) (xy 379.48877 -373.799962) (xy 379.503062 -373.785604)
			(xy 379.521753 -373.777789) (xy 379.53188 -373.777256) (xy 380.24816 -373.777256) (xy 380.258306 -373.777754)
			(xy 380.277049 -373.785528) (xy 380.291372 -373.799901) (xy 380.299081 -373.818671) (xy 380.299468 -373.828818)
			(xy 380.299468 -373.986298) (xy 380.299886 -373.995484) (xy 380.306395 -374.012668) (xy 380.312168 -374.019826)
			(xy 380.333992 -374.045525) (xy 380.372084 -374.101154) (xy 380.403238 -374.160945) (xy 380.427006 -374.224038)
			(xy 380.443046 -374.289523) (xy 380.451125 -374.356458) (xy 380.451129 -374.423823) (xy 383.729165 -374.423823)
			(xy 383.729169 -374.356514) (xy 383.737218 -374.289688) (xy 383.753196 -374.224303) (xy 383.776874 -374.161297)
			(xy 383.807914 -374.101572) (xy 383.845869 -374.045986) (xy 383.86766 -374.020334) (xy 383.873474 -374.013202)
			(xy 383.879977 -373.996001) (xy 383.88036 -373.986806) (xy 383.88036 -373.828818) (xy 383.880779 -373.818645)
			(xy 383.888562 -373.799846) (xy 383.90295 -373.78546) (xy 383.921749 -373.777678) (xy 383.931922 -373.777256)
			(xy 384.648202 -373.777256) (xy 384.658376 -373.777663) (xy 384.677174 -373.785452) (xy 384.69156 -373.799843)
			(xy 384.699341 -373.818644) (xy 384.699764 -373.828818) (xy 384.699764 -373.986806) (xy 384.700179 -373.995992)
			(xy 384.70669 -374.013176) (xy 384.712464 -374.020334) (xy 384.73421 -374.04602) (xy 384.77216 -374.101602)
			(xy 384.803195 -374.161321) (xy 384.82687 -374.224321) (xy 384.842846 -374.289699) (xy 384.850893 -374.356518)
			(xy 384.850897 -374.423819) (xy 384.850897 -374.423823) (xy 388.128956 -374.423823) (xy 388.12896 -374.356514)
			(xy 388.137009 -374.289689) (xy 388.152986 -374.224304) (xy 388.176664 -374.161298) (xy 388.207703 -374.101573)
			(xy 388.245657 -374.045986) (xy 388.267448 -374.020334) (xy 388.273261 -374.013201) (xy 388.279765 -373.996001)
			(xy 388.280148 -373.986806) (xy 388.280148 -373.828818) (xy 388.280579 -373.818646) (xy 388.28836 -373.79985)
			(xy 388.302743 -373.785464) (xy 388.321538 -373.77768) (xy 388.33171 -373.777256) (xy 389.04799 -373.777256)
			(xy 389.058163 -373.777672) (xy 389.076961 -373.785457) (xy 389.091347 -373.799846) (xy 389.099129 -373.818645)
			(xy 389.099552 -373.828818) (xy 389.099552 -373.986806) (xy 389.09997 -373.995992) (xy 389.106479 -374.013176)
			(xy 389.112252 -374.020334) (xy 389.133999 -374.04602) (xy 389.171949 -374.101601) (xy 389.202985 -374.16132)
			(xy 389.22666 -374.22432) (xy 389.242636 -374.289699) (xy 389.250684 -374.356517) (xy 389.250688 -374.423819)
			(xy 389.250688 -374.423823) (xy 418.928987 -374.423823) (xy 418.928991 -374.356514) (xy 418.93704 -374.289688)
			(xy 418.953019 -374.224302) (xy 418.976698 -374.161296) (xy 419.007739 -374.101572) (xy 419.045696 -374.045986)
			(xy 419.067488 -374.020334) (xy 419.073294 -374.013195) (xy 419.079803 -373.996) (xy 419.080188 -373.986806)
			(xy 419.080188 -373.828818) (xy 419.08058 -373.818641) (xy 419.088368 -373.799837) (xy 419.102764 -373.78545)
			(xy 419.121573 -373.777673) (xy 419.13175 -373.777256) (xy 419.84803 -373.777256) (xy 419.858192 -373.777709)
			(xy 419.876965 -373.785497) (xy 419.89133 -373.799875) (xy 419.8991 -373.818656) (xy 419.899592 -373.828818)
			(xy 419.899592 -373.986806) (xy 419.900001 -373.995993) (xy 419.906516 -374.013177) (xy 419.912292 -374.020334)
			(xy 419.934038 -374.04602) (xy 419.971986 -374.101603) (xy 420.003019 -374.161322) (xy 420.026693 -374.224322)
			(xy 420.042668 -374.2897) (xy 420.050715 -374.356518) (xy 420.050719 -374.423819) (xy 420.050711 -374.423882)
			(xy 423.328779 -374.423882) (xy 423.328783 -374.356455) (xy 423.336863 -374.289514) (xy 423.352903 -374.224023)
			(xy 423.376671 -374.160925) (xy 423.407825 -374.101127) (xy 423.445918 -374.045492) (xy 423.467784 -374.019826)
			(xy 423.473593 -374.012689) (xy 423.480101 -373.995492) (xy 423.480484 -373.986298) (xy 423.480484 -373.828818)
			(xy 423.480942 -373.818687) (xy 423.488672 -373.799958) (xy 423.502968 -373.785599) (xy 423.521663 -373.777787)
			(xy 423.531792 -373.777256) (xy 424.248072 -373.777256) (xy 424.258174 -373.777807) (xy 424.276843 -373.785527)
			(xy 424.291137 -373.799803) (xy 424.298881 -373.818463) (xy 424.29938 -373.828564) (xy 424.29938 -373.986298)
			(xy 424.299795 -373.995485) (xy 424.306306 -374.012669) (xy 424.31208 -374.019826) (xy 424.333903 -374.045525)
			(xy 424.371995 -374.101154) (xy 424.403148 -374.160946) (xy 424.426916 -374.224038) (xy 424.442955 -374.289523)
			(xy 424.451034 -374.356458) (xy 424.451038 -374.423823) (xy 427.729074 -374.423823) (xy 427.729078 -374.356514)
			(xy 427.737127 -374.289688) (xy 427.753106 -374.224303) (xy 427.776784 -374.161296) (xy 427.807824 -374.101572)
			(xy 427.84578 -374.045986) (xy 427.867572 -374.020334) (xy 427.873388 -374.013203) (xy 427.879889 -373.996001)
			(xy 427.880272 -373.986806) (xy 427.880272 -373.828818) (xy 427.880679 -373.818643) (xy 427.888465 -373.799842)
			(xy 427.902856 -373.785456) (xy 427.921659 -373.777676) (xy 427.931834 -373.777256) (xy 428.648114 -373.777256)
			(xy 428.658289 -373.777653) (xy 428.677087 -373.785446) (xy 428.691472 -373.79984) (xy 428.699253 -373.818643)
			(xy 428.699676 -373.828818) (xy 428.699676 -373.986806) (xy 428.700088 -373.995993) (xy 428.706601 -374.013177)
			(xy 428.712376 -374.020334) (xy 428.734122 -374.04602) (xy 428.772071 -374.101602) (xy 428.803105 -374.161321)
			(xy 428.82678 -374.224321) (xy 428.842755 -374.289699) (xy 428.850802 -374.356518) (xy 428.850806 -374.423819)
			(xy 428.850806 -374.423823) (xy 432.128865 -374.423823) (xy 432.128869 -374.356514) (xy 432.136918 -374.289688)
			(xy 432.152896 -374.224303) (xy 432.176574 -374.161297) (xy 432.207614 -374.101572) (xy 432.245569 -374.045986)
			(xy 432.26736 -374.020334) (xy 432.273174 -374.013202) (xy 432.279677 -373.996001) (xy 432.28006 -373.986806)
			(xy 432.28006 -373.828818) (xy 432.280479 -373.818645) (xy 432.288262 -373.799846) (xy 432.30265 -373.78546)
			(xy 432.321449 -373.777678) (xy 432.331622 -373.777256) (xy 433.047902 -373.777256) (xy 433.058076 -373.777663)
			(xy 433.076874 -373.785452) (xy 433.09126 -373.799843) (xy 433.099041 -373.818644) (xy 433.099464 -373.828818)
			(xy 433.099464 -373.986806) (xy 433.099879 -373.995992) (xy 433.10639 -374.013176) (xy 433.112164 -374.020334)
			(xy 433.13391 -374.04602) (xy 433.17186 -374.101602) (xy 433.202895 -374.161321) (xy 433.22657 -374.224321)
			(xy 433.242546 -374.289699) (xy 433.250593 -374.356518) (xy 433.250597 -374.423819) (xy 433.242557 -374.490639)
			(xy 433.226589 -374.556019) (xy 433.202921 -374.619021) (xy 433.171892 -374.678744) (xy 433.133949 -374.73433)
			(xy 433.112164 -374.759982) (xy 433.106346 -374.767112) (xy 433.099845 -374.784314) (xy 433.099464 -374.79351)
			(xy 433.099464 -375.286778) (xy 433.099893 -375.295963) (xy 433.106394 -375.313147) (xy 433.112164 -375.320306)
			(xy 433.133981 -375.345934) (xy 433.171929 -375.401524) (xy 433.202961 -375.461251) (xy 433.226632 -375.524259)
			(xy 433.242603 -375.589644) (xy 433.250644 -375.656469) (xy 433.250642 -375.723776) (xy 433.242594 -375.790601)
			(xy 433.226618 -375.855985) (xy 433.202942 -375.91899) (xy 433.171906 -375.978715) (xy 433.133954 -376.034302)
			(xy 433.112164 -376.059954) (xy 433.106357 -376.067092) (xy 433.09985 -376.084288) (xy 433.099464 -376.093482)
			(xy 433.099464 -376.25147) (xy 433.099011 -376.261639) (xy 433.091237 -376.280433) (xy 433.07686 -376.294819)
			(xy 433.058071 -376.302605) (xy 433.047902 -376.303032) (xy 432.331622 -376.303032) (xy 432.321448 -376.302617)
			(xy 432.302648 -376.294834) (xy 432.288262 -376.280445) (xy 432.280481 -376.261644) (xy 432.28006 -376.25147)
			(xy 432.28006 -376.093482) (xy 432.279645 -376.084296) (xy 432.273133 -376.067112) (xy 432.26736 -376.059954)
			(xy 432.245601 -376.034278) (xy 432.20765 -375.978695) (xy 432.176614 -375.918975) (xy 432.152939 -375.855974)
			(xy 432.136963 -375.790594) (xy 432.128917 -375.723774) (xy 432.128914 -375.656471) (xy 432.136955 -375.58965)
			(xy 432.152926 -375.524269) (xy 432.176596 -375.461266) (xy 432.207627 -375.401543) (xy 432.245574 -375.345958)
			(xy 432.26736 -375.320306) (xy 432.273144 -375.313152) (xy 432.279664 -375.295968) (xy 432.28006 -375.286778)
			(xy 432.28006 -374.79351) (xy 432.279632 -374.784325) (xy 432.273129 -374.767141) (xy 432.26736 -374.759982)
			(xy 432.24553 -374.734364) (xy 432.207581 -374.678773) (xy 432.176549 -374.619045) (xy 432.152877 -374.556036)
			(xy 432.136907 -374.49065) (xy 432.128865 -374.423823) (xy 428.850806 -374.423823) (xy 428.842766 -374.490639)
			(xy 428.826798 -374.556018) (xy 428.803131 -374.619021) (xy 428.772103 -374.678743) (xy 428.73416 -374.734329)
			(xy 428.712376 -374.759982) (xy 428.706559 -374.767113) (xy 428.700057 -374.784314) (xy 428.699676 -374.79351)
			(xy 428.699676 -375.286778) (xy 428.700102 -375.295963) (xy 428.706605 -375.313148) (xy 428.712376 -375.320306)
			(xy 428.734193 -375.345934) (xy 428.77214 -375.401524) (xy 428.803171 -375.461251) (xy 428.826841 -375.524259)
			(xy 428.842812 -375.589644) (xy 428.850853 -375.656469) (xy 428.850851 -375.723776) (xy 428.842804 -375.790601)
			(xy 428.826828 -375.855984) (xy 428.803152 -375.91899) (xy 428.772117 -375.978714) (xy 428.734165 -376.034302)
			(xy 428.712376 -376.059954) (xy 428.706571 -376.067093) (xy 428.700062 -376.084288) (xy 428.699676 -376.093482)
			(xy 428.699676 -376.25147) (xy 428.699212 -376.261638) (xy 428.691439 -376.280429) (xy 428.677066 -376.294815)
			(xy 428.658282 -376.302603) (xy 428.648114 -376.303032) (xy 427.931834 -376.303032) (xy 427.921661 -376.302607)
			(xy 427.902861 -376.294828) (xy 427.888474 -376.280442) (xy 427.880693 -376.261643) (xy 427.880272 -376.25147)
			(xy 427.880272 -376.093482) (xy 427.879877 -376.084293) (xy 427.873353 -376.067109) (xy 427.867572 -376.059954)
			(xy 427.845813 -376.034278) (xy 427.807861 -375.978696) (xy 427.776825 -375.918976) (xy 427.753149 -375.855974)
			(xy 427.737173 -375.790595) (xy 427.729126 -375.723774) (xy 427.729123 -375.656471) (xy 427.737165 -375.58965)
			(xy 427.753135 -375.524269) (xy 427.776806 -375.461266) (xy 427.807838 -375.401543) (xy 427.845785 -375.345958)
			(xy 427.867572 -375.320306) (xy 427.873357 -375.313153) (xy 427.879877 -375.295968) (xy 427.880272 -375.286778)
			(xy 427.880272 -374.79351) (xy 427.879863 -374.784323) (xy 427.873349 -374.767138) (xy 427.867572 -374.759982)
			(xy 427.845742 -374.734364) (xy 427.807792 -374.678774) (xy 427.776759 -374.619046) (xy 427.753087 -374.556037)
			(xy 427.737116 -374.49065) (xy 427.729074 -374.423823) (xy 424.451038 -374.423823) (xy 424.451038 -374.423879)
			(xy 424.442966 -374.490815) (xy 424.426934 -374.556302) (xy 424.403174 -374.619397) (xy 424.372027 -374.679192)
			(xy 424.333942 -374.734825) (xy 424.31208 -374.76049) (xy 424.30626 -374.767619) (xy 424.29976 -374.784822)
			(xy 424.29938 -374.794018) (xy 424.29938 -375.28627) (xy 424.299809 -375.295455) (xy 424.30631 -375.312639)
			(xy 424.31208 -375.319798) (xy 424.333974 -375.345439) (xy 424.372063 -375.401076) (xy 424.403214 -375.460876)
			(xy 424.426977 -375.523976) (xy 424.443011 -375.589468) (xy 424.451085 -375.656409) (xy 424.451082 -375.723836)
			(xy 424.443003 -375.790776) (xy 424.426964 -375.856267) (xy 424.403195 -375.919366) (xy 424.37204 -375.979163)
			(xy 424.333946 -376.034797) (xy 424.31208 -376.060462) (xy 424.306272 -376.067599) (xy 424.299765 -376.084796)
			(xy 424.29938 -376.09399) (xy 424.29938 -376.25147) (xy 424.29885 -376.261592) (xy 424.291135 -376.280309)
			(xy 424.276863 -376.294666) (xy 424.258191 -376.30249) (xy 424.248072 -376.303032) (xy 423.531792 -376.303032)
			(xy 423.521687 -376.302522) (xy 423.503015 -376.294788) (xy 423.488721 -376.280499) (xy 423.480981 -376.261829)
			(xy 423.480484 -376.251724) (xy 423.480484 -376.09399) (xy 423.480082 -376.084802) (xy 423.473563 -376.067617)
			(xy 423.467784 -376.060462) (xy 423.44595 -376.034772) (xy 423.407862 -375.979141) (xy 423.37671 -375.919348)
			(xy 423.352945 -375.856254) (xy 423.336908 -375.790768) (xy 423.32883 -375.723833) (xy 423.328827 -375.656412)
			(xy 423.3369 -375.589476) (xy 423.352932 -375.523989) (xy 423.376692 -375.460893) (xy 423.407838 -375.401098)
			(xy 423.445922 -375.345463) (xy 423.467784 -375.319798) (xy 423.473562 -375.31264) (xy 423.480088 -375.295459)
			(xy 423.480484 -375.28627) (xy 423.480484 -374.794018) (xy 423.480069 -374.784831) (xy 423.473559 -374.767647)
			(xy 423.467784 -374.76049) (xy 423.445879 -374.734859) (xy 423.407793 -374.679219) (xy 423.376645 -374.619418)
			(xy 423.352884 -374.556317) (xy 423.336852 -374.490824) (xy 423.328779 -374.423882) (xy 420.050711 -374.423882)
			(xy 420.042679 -374.490638) (xy 420.026712 -374.556018) (xy 420.003045 -374.61902) (xy 419.972018 -374.678743)
			(xy 419.934076 -374.73433) (xy 419.912292 -374.759982) (xy 419.906477 -374.767114) (xy 419.899974 -374.784315)
			(xy 419.899592 -374.79351) (xy 419.899592 -375.286778) (xy 419.900015 -375.295964) (xy 419.90652 -375.313148)
			(xy 419.912292 -375.320306) (xy 419.934108 -375.345934) (xy 419.972054 -375.401525) (xy 420.003084 -375.461252)
			(xy 420.026754 -375.52426) (xy 420.042724 -375.589644) (xy 420.050765 -375.656469) (xy 420.050763 -375.723776)
			(xy 420.042716 -375.7906) (xy 420.026741 -375.855984) (xy 420.003066 -375.918989) (xy 419.972031 -375.978714)
			(xy 419.934081 -376.034301) (xy 419.912292 -376.059954) (xy 419.906489 -376.067095) (xy 419.899978 -376.084289)
			(xy 419.899592 -376.093482) (xy 419.899592 -376.25147) (xy 419.899043 -376.261622) (xy 419.891284 -376.280385)
			(xy 419.876935 -376.29475) (xy 419.858182 -376.302531) (xy 419.84803 -376.303032) (xy 419.13175 -376.303032)
			(xy 419.121578 -376.302595) (xy 419.102779 -376.29482) (xy 419.088391 -376.280438) (xy 419.080609 -376.261642)
			(xy 419.080188 -376.25147) (xy 419.080188 -376.093482) (xy 419.079789 -376.084294) (xy 419.073268 -376.067109)
			(xy 419.067488 -376.059954) (xy 419.045728 -376.034278) (xy 419.007775 -375.978696) (xy 418.976738 -375.918976)
			(xy 418.953061 -375.855975) (xy 418.937085 -375.790595) (xy 418.929038 -375.723774) (xy 418.929035 -375.656471)
			(xy 418.937077 -375.589649) (xy 418.953048 -375.524268) (xy 418.97672 -375.461265) (xy 419.007752 -375.401542)
			(xy 419.045701 -375.345957) (xy 419.067488 -375.320306) (xy 419.073263 -375.313145) (xy 419.079791 -375.295967)
			(xy 419.080188 -375.286778) (xy 419.080188 -374.79351) (xy 419.079776 -374.784323) (xy 419.073264 -374.767138)
			(xy 419.067488 -374.759982) (xy 419.045658 -374.734364) (xy 419.007707 -374.678774) (xy 418.976673 -374.619046)
			(xy 418.953 -374.556037) (xy 418.937029 -374.49065) (xy 418.928987 -374.423823) (xy 389.250688 -374.423823)
			(xy 389.242648 -374.490639) (xy 389.226679 -374.556019) (xy 389.203011 -374.619022) (xy 389.171982 -374.678744)
			(xy 389.134037 -374.73433) (xy 389.112252 -374.759982) (xy 389.106432 -374.76711) (xy 389.099933 -374.784314)
			(xy 389.099552 -374.79351) (xy 389.099552 -375.286778) (xy 389.099983 -375.295963) (xy 389.106483 -375.313147)
			(xy 389.112252 -375.320306) (xy 389.13407 -375.345934) (xy 389.172018 -375.401523) (xy 389.203051 -375.46125)
			(xy 389.226722 -375.524258) (xy 389.242693 -375.589643) (xy 389.250735 -375.656469) (xy 389.250732 -375.723776)
			(xy 389.242685 -375.790601) (xy 389.226709 -375.855985) (xy 389.203032 -375.918991) (xy 389.171995 -375.978715)
			(xy 389.134042 -376.034302) (xy 389.112252 -376.059954) (xy 389.106444 -376.067091) (xy 389.099937 -376.084288)
			(xy 389.099552 -376.093482) (xy 389.099552 -376.25147) (xy 389.099111 -376.261641) (xy 389.091334 -376.280437)
			(xy 389.076954 -376.294823) (xy 389.058161 -376.302607) (xy 389.04799 -376.303032) (xy 388.33171 -376.303032)
			(xy 388.321535 -376.302627) (xy 388.302735 -376.29484) (xy 388.288349 -376.280448) (xy 388.280569 -376.261645)
			(xy 388.280148 -376.25147) (xy 388.280148 -376.093482) (xy 388.279736 -376.084295) (xy 388.273222 -376.067111)
			(xy 388.267448 -376.059954) (xy 388.24569 -376.034278) (xy 388.207739 -375.978695) (xy 388.176704 -375.918975)
			(xy 388.153029 -375.855973) (xy 388.137054 -375.790594) (xy 388.129007 -375.723774) (xy 388.129005 -375.656471)
			(xy 388.137046 -375.58965) (xy 388.153016 -375.52427) (xy 388.176686 -375.461267) (xy 388.207716 -375.401544)
			(xy 388.245662 -375.345958) (xy 388.267448 -375.320306) (xy 388.273231 -375.313151) (xy 388.279752 -375.295968)
			(xy 388.280148 -375.286778) (xy 388.280148 -374.79351) (xy 388.279722 -374.784325) (xy 388.273218 -374.767141)
			(xy 388.267448 -374.759982) (xy 388.245619 -374.734364) (xy 388.20767 -374.678773) (xy 388.176638 -374.619045)
			(xy 388.152968 -374.556036) (xy 388.136997 -374.490649) (xy 388.128956 -374.423823) (xy 384.850897 -374.423823)
			(xy 384.842857 -374.490639) (xy 384.826889 -374.556019) (xy 384.803221 -374.619021) (xy 384.772192 -374.678744)
			(xy 384.734249 -374.73433) (xy 384.712464 -374.759982) (xy 384.706646 -374.767112) (xy 384.700145 -374.784314)
			(xy 384.699764 -374.79351) (xy 384.699764 -375.286778) (xy 384.700193 -375.295963) (xy 384.706694 -375.313147)
			(xy 384.712464 -375.320306) (xy 384.734281 -375.345934) (xy 384.772229 -375.401524) (xy 384.803261 -375.461251)
			(xy 384.826932 -375.524259) (xy 384.842903 -375.589644) (xy 384.850944 -375.656469) (xy 384.850942 -375.723776)
			(xy 384.842894 -375.790601) (xy 384.826918 -375.855985) (xy 384.803242 -375.91899) (xy 384.772206 -375.978715)
			(xy 384.734254 -376.034302) (xy 384.712464 -376.059954) (xy 384.706657 -376.067092) (xy 384.70015 -376.084288)
			(xy 384.699764 -376.093482) (xy 384.699764 -376.25147) (xy 384.699311 -376.261639) (xy 384.691537 -376.280433)
			(xy 384.67716 -376.294819) (xy 384.658371 -376.302605) (xy 384.648202 -376.303032) (xy 383.931922 -376.303032)
			(xy 383.921748 -376.302617) (xy 383.902948 -376.294834) (xy 383.888562 -376.280445) (xy 383.880781 -376.261644)
			(xy 383.88036 -376.25147) (xy 383.88036 -376.093482) (xy 383.879945 -376.084296) (xy 383.873433 -376.067112)
			(xy 383.86766 -376.059954) (xy 383.845901 -376.034278) (xy 383.80795 -375.978695) (xy 383.776914 -375.918975)
			(xy 383.753239 -375.855974) (xy 383.737263 -375.790594) (xy 383.729217 -375.723774) (xy 383.729214 -375.656471)
			(xy 383.737255 -375.58965) (xy 383.753226 -375.524269) (xy 383.776896 -375.461266) (xy 383.807927 -375.401543)
			(xy 383.845874 -375.345958) (xy 383.86766 -375.320306) (xy 383.873444 -375.313152) (xy 383.879964 -375.295968)
			(xy 383.88036 -375.286778) (xy 383.88036 -374.79351) (xy 383.879932 -374.784325) (xy 383.873429 -374.767141)
			(xy 383.86766 -374.759982) (xy 383.84583 -374.734364) (xy 383.807881 -374.678773) (xy 383.776849 -374.619045)
			(xy 383.753177 -374.556036) (xy 383.737207 -374.49065) (xy 383.729165 -374.423823) (xy 380.451129 -374.423823)
			(xy 380.451129 -374.423879) (xy 380.443057 -374.490815) (xy 380.427025 -374.556302) (xy 380.403264 -374.619397)
			(xy 380.372116 -374.679192) (xy 380.334031 -374.734825) (xy 380.312168 -374.76049) (xy 380.306347 -374.767617)
			(xy 380.299847 -374.784822) (xy 380.299468 -374.794018) (xy 380.299468 -375.28627) (xy 380.2999 -375.295455)
			(xy 380.306399 -375.312639) (xy 380.312168 -375.319798) (xy 380.334063 -375.345438) (xy 380.372152 -375.401076)
			(xy 380.403304 -375.460875) (xy 380.427068 -375.523975) (xy 380.443102 -375.589468) (xy 380.451176 -375.656409)
			(xy 380.451173 -375.723836) (xy 380.443094 -375.790777) (xy 380.427054 -375.856268) (xy 380.403285 -375.919366)
			(xy 380.372129 -375.979163) (xy 380.334035 -376.034797) (xy 380.312168 -376.060462) (xy 380.306358 -376.067598)
			(xy 380.299852 -376.084796) (xy 380.299468 -376.09399) (xy 380.299468 -376.25147) (xy 380.298949 -376.261594)
			(xy 380.291233 -376.280313) (xy 380.276956 -376.29467) (xy 380.258281 -376.302492) (xy 380.24816 -376.303032)
			(xy 379.53188 -376.303032) (xy 379.521729 -376.302596) (xy 379.502982 -376.294799) (xy 379.48866 -376.280408)
			(xy 379.480955 -376.261623) (xy 379.480572 -376.25147) (xy 379.480572 -376.09399) (xy 379.480173 -376.084802)
			(xy 379.473652 -376.067617) (xy 379.467872 -376.060462) (xy 379.446038 -376.034772) (xy 379.407951 -375.97914)
			(xy 379.3768 -375.919347) (xy 379.353036 -375.856254) (xy 379.336999 -375.790768) (xy 379.328921 -375.723833)
			(xy 379.328918 -375.656412) (xy 379.336991 -375.589476) (xy 379.353022 -375.523989) (xy 379.376782 -375.460894)
			(xy 379.407928 -375.401098) (xy 379.446011 -375.345464) (xy 379.467872 -375.319798) (xy 379.473661 -375.312648)
			(xy 379.480178 -375.295461) (xy 379.480572 -375.28627) (xy 379.480572 -374.794018) (xy 379.48016 -374.784831)
			(xy 379.473648 -374.767646) (xy 379.467872 -374.76049) (xy 379.445968 -374.734858) (xy 379.407882 -374.679218)
			(xy 379.376735 -374.619417) (xy 379.352974 -374.556316) (xy 379.336943 -374.490823) (xy 379.32887 -374.423882)
			(xy 376.050801 -374.423882) (xy 376.042769 -374.490638) (xy 376.026801 -374.556018) (xy 376.003134 -374.619021)
			(xy 375.972107 -374.678743) (xy 375.934164 -374.734329) (xy 375.91238 -374.759982) (xy 375.906564 -374.767113)
			(xy 375.900062 -374.784315) (xy 375.89968 -374.79351) (xy 375.89968 -375.286778) (xy 375.900105 -375.295963)
			(xy 375.906609 -375.313148) (xy 375.91238 -375.320306) (xy 375.934197 -375.345934) (xy 375.972143 -375.401524)
			(xy 376.003174 -375.461252) (xy 376.026845 -375.524259) (xy 376.042815 -375.589644) (xy 376.050856 -375.656469)
			(xy 376.050854 -375.723776) (xy 376.042807 -375.7906) (xy 376.026831 -375.855984) (xy 376.003156 -375.91899)
			(xy 375.97212 -375.978714) (xy 375.934169 -376.034302) (xy 375.91238 -376.059954) (xy 375.906576 -376.067094)
			(xy 375.900066 -376.084288) (xy 375.89968 -376.093482) (xy 375.89968 -376.25147) (xy 375.899212 -376.261637)
			(xy 375.89144 -376.280428) (xy 375.877068 -376.294813) (xy 375.858285 -376.302602) (xy 375.848118 -376.303032)
			(xy 375.131838 -376.303032) (xy 375.121665 -376.302604) (xy 375.102866 -376.294826) (xy 375.088478 -376.280441)
			(xy 375.080697 -376.261643) (xy 375.080276 -376.25147) (xy 375.080276 -376.093482) (xy 375.07988 -376.084293)
			(xy 375.073357 -376.067109) (xy 375.067576 -376.059954) (xy 375.045817 -376.034278) (xy 375.007865 -375.978696)
			(xy 374.976828 -375.918976) (xy 374.953152 -375.855974) (xy 374.937176 -375.790595) (xy 374.929129 -375.723774)
			(xy 374.929126 -375.656471) (xy 374.937168 -375.58965) (xy 374.953138 -375.524269) (xy 374.97681 -375.461265)
			(xy 375.007841 -375.401543) (xy 375.045789 -375.345958) (xy 375.067576 -375.320306) (xy 375.07335 -375.313144)
			(xy 375.079879 -375.295967) (xy 375.080276 -375.286778) (xy 375.080276 -374.79351) (xy 375.079866 -374.784323)
			(xy 375.073353 -374.767138) (xy 375.067576 -374.759982) (xy 375.045746 -374.734365) (xy 375.007796 -374.678774)
			(xy 374.976762 -374.619046) (xy 374.95309 -374.556037) (xy 374.937119 -374.49065) (xy 374.929078 -374.423823)
			(xy 345.250779 -374.423823) (xy 345.242739 -374.49064) (xy 345.226769 -374.55602) (xy 345.2031 -374.619022)
			(xy 345.172071 -374.678745) (xy 345.134126 -374.73433) (xy 345.11234 -374.759982) (xy 345.106519 -374.767109)
			(xy 345.10002 -374.784314) (xy 345.09964 -374.79351) (xy 345.09964 -375.286778) (xy 345.100074 -375.295962)
			(xy 345.106573 -375.313146) (xy 345.11234 -375.320306) (xy 345.134158 -375.345933) (xy 345.172107 -375.401523)
			(xy 345.203141 -375.46125) (xy 345.226813 -375.524258) (xy 345.242784 -375.589643) (xy 345.250826 -375.656469)
			(xy 345.250823 -375.723776) (xy 345.242776 -375.790602) (xy 345.226799 -375.855986) (xy 345.203122 -375.918992)
			(xy 345.172084 -375.978716) (xy 345.13413 -376.034302) (xy 345.11234 -376.059954) (xy 345.106531 -376.06709)
			(xy 345.100025 -376.084288) (xy 345.09964 -376.093482) (xy 345.09964 -376.25147) (xy 345.099211 -376.261642)
			(xy 345.091432 -376.280441) (xy 345.077047 -376.294827) (xy 345.05825 -376.302609) (xy 345.048078 -376.303032)
			(xy 344.331798 -376.303032) (xy 344.321623 -376.302637) (xy 344.302822 -376.294846) (xy 344.288436 -376.280451)
			(xy 344.280657 -376.261646) (xy 344.280236 -376.25147) (xy 344.280236 -376.093482) (xy 344.279826 -376.084295)
			(xy 344.273311 -376.067111) (xy 344.267536 -376.059954) (xy 344.245778 -376.034277) (xy 344.207829 -375.978694)
			(xy 344.176794 -375.918974) (xy 344.15312 -375.855973) (xy 344.137145 -375.790594) (xy 344.129098 -375.723774)
			(xy 344.129096 -375.656471) (xy 344.137137 -375.589651) (xy 344.153106 -375.52427) (xy 344.176776 -375.461267)
			(xy 344.207805 -375.401544) (xy 344.24575 -375.345958) (xy 344.267536 -375.320306) (xy 344.273317 -375.31315)
			(xy 344.27984 -375.295968) (xy 344.280236 -375.286778) (xy 344.280236 -374.79351) (xy 344.279813 -374.784324)
			(xy 344.273308 -374.76714) (xy 344.267536 -374.759982) (xy 344.245707 -374.734364) (xy 344.20776 -374.678772)
			(xy 344.176728 -374.619044) (xy 344.153058 -374.556035) (xy 344.137088 -374.490649) (xy 344.129047 -374.423823)
			(xy 340.850988 -374.423823) (xy 340.842948 -374.490639) (xy 340.826979 -374.556019) (xy 340.803311 -374.619022)
			(xy 340.772282 -374.678744) (xy 340.734337 -374.73433) (xy 340.712552 -374.759982) (xy 340.706732 -374.76711)
			(xy 340.700233 -374.784314) (xy 340.699852 -374.79351) (xy 340.699852 -375.286778) (xy 340.700283 -375.295963)
			(xy 340.706783 -375.313147) (xy 340.712552 -375.320306) (xy 340.73437 -375.345934) (xy 340.772318 -375.401523)
			(xy 340.803351 -375.46125) (xy 340.827022 -375.524258) (xy 340.842993 -375.589643) (xy 340.851035 -375.656469)
			(xy 340.851032 -375.723776) (xy 340.842985 -375.790601) (xy 340.827009 -375.855985) (xy 340.803332 -375.918991)
			(xy 340.772295 -375.978715) (xy 340.734342 -376.034302) (xy 340.712552 -376.059954) (xy 340.706744 -376.067091)
			(xy 340.700237 -376.084288) (xy 340.699852 -376.093482) (xy 340.699852 -376.25147) (xy 340.699411 -376.261641)
			(xy 340.691634 -376.280437) (xy 340.677254 -376.294823) (xy 340.658461 -376.302607) (xy 340.64829 -376.303032)
			(xy 339.93201 -376.303032) (xy 339.921835 -376.302627) (xy 339.903035 -376.29484) (xy 339.888649 -376.280448)
			(xy 339.880869 -376.261645) (xy 339.880448 -376.25147) (xy 339.880448 -376.093482) (xy 339.880036 -376.084295)
			(xy 339.873522 -376.067111) (xy 339.867748 -376.059954) (xy 339.84599 -376.034278) (xy 339.808039 -375.978695)
			(xy 339.777004 -375.918975) (xy 339.753329 -375.855973) (xy 339.737354 -375.790594) (xy 339.729307 -375.723774)
			(xy 339.729305 -375.656471) (xy 339.737346 -375.58965) (xy 339.753316 -375.52427) (xy 339.776986 -375.461267)
			(xy 339.808016 -375.401544) (xy 339.845962 -375.345958) (xy 339.867748 -375.320306) (xy 339.873531 -375.313151)
			(xy 339.880052 -375.295968) (xy 339.880448 -375.286778) (xy 339.880448 -374.79351) (xy 339.880022 -374.784325)
			(xy 339.873518 -374.767141) (xy 339.867748 -374.759982) (xy 339.845919 -374.734364) (xy 339.80797 -374.678773)
			(xy 339.776938 -374.619045) (xy 339.753268 -374.556036) (xy 339.737297 -374.490649) (xy 339.729256 -374.423823)
			(xy 336.45122 -374.423823) (xy 336.45122 -374.423879) (xy 336.443148 -374.490815) (xy 336.427115 -374.556303)
			(xy 336.403354 -374.619398) (xy 336.372206 -374.679193) (xy 336.334119 -374.734826) (xy 336.312256 -374.76049)
			(xy 336.306433 -374.767616) (xy 336.299935 -374.784821) (xy 336.299556 -374.794018) (xy 336.299556 -375.28627)
			(xy 336.29999 -375.295454) (xy 336.306488 -375.312639) (xy 336.312256 -375.319798) (xy 336.334151 -375.345438)
			(xy 336.372242 -375.401075) (xy 336.403394 -375.460875) (xy 336.427158 -375.523975) (xy 336.443193 -375.589467)
			(xy 336.451267 -375.656409) (xy 336.451264 -375.723836) (xy 336.443185 -375.790777) (xy 336.427145 -375.856268)
			(xy 336.403375 -375.919367) (xy 336.372218 -375.979163) (xy 336.334123 -376.034797) (xy 336.312256 -376.060462)
			(xy 336.306445 -376.067597) (xy 336.29994 -376.084795) (xy 336.299556 -376.09399) (xy 336.299556 -376.25147)
			(xy 336.299049 -376.261595) (xy 336.29133 -376.280317) (xy 336.27705 -376.294674) (xy 336.258371 -376.302494)
			(xy 336.248248 -376.303032) (xy 335.531968 -376.303032) (xy 335.521816 -376.302605) (xy 335.503069 -376.294805)
			(xy 335.488748 -376.280411) (xy 335.481043 -376.261624) (xy 335.48066 -376.25147) (xy 335.48066 -376.09399)
			(xy 335.480241 -376.084804) (xy 335.473732 -376.06762) (xy 335.46796 -376.060462) (xy 335.446127 -376.034772)
			(xy 335.40804 -375.97914) (xy 335.37689 -375.919347) (xy 335.353126 -375.856253) (xy 335.33709 -375.790768)
			(xy 335.329012 -375.723833) (xy 335.329009 -375.656412) (xy 335.337082 -375.589477) (xy 335.353113 -375.52399)
			(xy 335.376872 -375.460894) (xy 335.408017 -375.401099) (xy 335.446099 -375.345464) (xy 335.46796 -375.319798)
			(xy 335.473747 -375.312647) (xy 335.480266 -375.295461) (xy 335.48066 -375.28627) (xy 335.48066 -374.794018)
			(xy 335.480228 -374.784833) (xy 335.473728 -374.76765) (xy 335.46796 -374.76049) (xy 335.446056 -374.734858)
			(xy 335.407971 -374.679218) (xy 335.376825 -374.619417) (xy 335.353065 -374.556316) (xy 335.337033 -374.490823)
			(xy 335.328961 -374.423882) (xy 332.050892 -374.423882) (xy 332.04286 -374.490639) (xy 332.026892 -374.556019)
			(xy 332.003224 -374.619021) (xy 331.972196 -374.678744) (xy 331.934253 -374.73433) (xy 331.912468 -374.759982)
			(xy 331.90665 -374.767112) (xy 331.900149 -374.784314) (xy 331.899768 -374.79351) (xy 331.899768 -375.286778)
			(xy 331.900196 -375.295963) (xy 331.906698 -375.313147) (xy 331.912468 -375.320306) (xy 331.934285 -375.345934)
			(xy 331.972233 -375.401524) (xy 332.003264 -375.461251) (xy 332.026935 -375.524259) (xy 332.042906 -375.589644)
			(xy 332.050947 -375.656469) (xy 332.050945 -375.723776) (xy 332.042898 -375.790601) (xy 332.026922 -375.855985)
			(xy 332.003246 -375.91899) (xy 331.972209 -375.978715) (xy 331.934257 -376.034302) (xy 331.912468 -376.059954)
			(xy 331.906662 -376.067092) (xy 331.900154 -376.084288) (xy 331.899768 -376.093482) (xy 331.899768 -376.25147)
			(xy 331.899312 -376.261639) (xy 331.891538 -376.280432) (xy 331.877162 -376.294817) (xy 331.858375 -376.302604)
			(xy 331.848206 -376.303032) (xy 331.131926 -376.303032) (xy 331.121752 -376.302614) (xy 331.102953 -376.294832)
			(xy 331.088566 -376.280444) (xy 331.080785 -376.261644) (xy 331.080364 -376.25147) (xy 331.080364 -376.093482)
			(xy 331.079948 -376.084296) (xy 331.073437 -376.067112) (xy 331.067664 -376.059954) (xy 331.045905 -376.034278)
			(xy 331.007954 -375.978695) (xy 330.976918 -375.918975) (xy 330.953242 -375.855974) (xy 330.937266 -375.790594)
			(xy 330.92922 -375.723774) (xy 330.929217 -375.656471) (xy 330.937258 -375.58965) (xy 330.953229 -375.524269)
			(xy 330.976899 -375.461266) (xy 331.007931 -375.401543) (xy 331.045877 -375.345958) (xy 331.067664 -375.320306)
			(xy 331.073448 -375.313152) (xy 331.079969 -375.295968) (xy 331.080364 -375.286778) (xy 331.080364 -374.79351)
			(xy 331.079935 -374.784325) (xy 331.073433 -374.767141) (xy 331.067664 -374.759982) (xy 331.045834 -374.734364)
			(xy 331.007885 -374.678773) (xy 330.976852 -374.619045) (xy 330.95318 -374.556036) (xy 330.93721 -374.49065)
			(xy 330.929168 -374.423823) (xy 301.250868 -374.423823) (xy 301.250868 -374.423878) (xy 301.242797 -374.490814)
			(xy 301.226766 -374.5563) (xy 301.203008 -374.619395) (xy 301.171863 -374.67919) (xy 301.133781 -374.734824)
			(xy 301.11192 -374.76049) (xy 301.106105 -374.767622) (xy 301.099601 -374.784823) (xy 301.09922 -374.794018)
			(xy 301.09922 -375.28627) (xy 301.09964 -375.295456) (xy 301.106146 -375.312641) (xy 301.11192 -375.319798)
			(xy 301.133813 -375.345439) (xy 301.171899 -375.401078) (xy 301.203048 -375.460877) (xy 301.226809 -375.523977)
			(xy 301.242842 -375.589469) (xy 301.250915 -375.65641) (xy 301.250912 -375.723835) (xy 301.242834 -375.790775)
			(xy 301.226796 -375.856266) (xy 301.203029 -375.919364) (xy 301.171876 -375.979161) (xy 301.133785 -376.034796)
			(xy 301.11192 -376.060462) (xy 301.106117 -376.067603) (xy 301.099605 -376.084797) (xy 301.09922 -376.09399)
			(xy 301.09922 -376.25147) (xy 301.098748 -376.2616) (xy 301.091023 -376.280328) (xy 301.076731 -376.294687)
			(xy 301.058039 -376.3025) (xy 301.047912 -376.303032) (xy 300.331632 -376.303032) (xy 300.321484 -376.302553)
			(xy 300.302738 -376.294774) (xy 300.288415 -376.280395) (xy 300.280708 -376.26162) (xy 300.280324 -376.25147)
			(xy 300.280324 -376.09399) (xy 300.279913 -376.084803) (xy 300.2734 -376.067619) (xy 300.267624 -376.060462)
			(xy 300.245789 -376.034773) (xy 300.207697 -375.979142) (xy 300.176544 -375.91935) (xy 300.152777 -375.856256)
			(xy 300.136739 -375.790769) (xy 300.12866 -375.723833) (xy 300.128658 -375.656412) (xy 300.136731 -375.589475)
			(xy 300.152764 -375.523987) (xy 300.176526 -375.460892) (xy 300.207674 -375.401096) (xy 300.245761 -375.345463)
			(xy 300.267624 -375.319798) (xy 300.273407 -375.312643) (xy 300.279929 -375.29546) (xy 300.280324 -375.28627)
			(xy 300.280324 -374.794018) (xy 300.2799 -374.784832) (xy 300.273395 -374.767648) (xy 300.267624 -374.76049)
			(xy 300.245718 -374.734859) (xy 300.207629 -374.67922) (xy 300.176479 -374.61942) (xy 300.152716 -374.556318)
			(xy 300.136683 -374.490825) (xy 300.12861 -374.423882) (xy 296.851077 -374.423882) (xy 296.843006 -374.490813)
			(xy 296.826976 -374.556299) (xy 296.803218 -374.619394) (xy 296.772074 -374.67919) (xy 296.733992 -374.734824)
			(xy 296.712132 -374.76049) (xy 296.706306 -374.767614) (xy 296.699811 -374.784821) (xy 296.699432 -374.794018)
			(xy 296.699432 -375.28627) (xy 296.699872 -375.295454) (xy 296.706366 -375.312638) (xy 296.712132 -375.319798)
			(xy 296.734024 -375.345439) (xy 296.77211 -375.401078) (xy 296.803258 -375.460878) (xy 296.827019 -375.523978)
			(xy 296.843051 -375.589469) (xy 296.851124 -375.65641) (xy 296.851121 -375.723835) (xy 296.843043 -375.790775)
			(xy 296.827005 -375.856265) (xy 296.803239 -375.919363) (xy 296.772087 -375.979161) (xy 296.733997 -376.034796)
			(xy 296.712132 -376.060462) (xy 296.706318 -376.067595) (xy 296.699816 -376.084795) (xy 296.699432 -376.09399)
			(xy 296.699432 -376.25147) (xy 296.698948 -376.261598) (xy 296.691225 -376.280324) (xy 296.676937 -376.294683)
			(xy 296.65825 -376.302498) (xy 296.648124 -376.303032) (xy 295.931844 -376.303032) (xy 295.921697 -376.302543)
			(xy 295.902951 -376.294768) (xy 295.888628 -376.280392) (xy 295.880921 -376.261619) (xy 295.880536 -376.25147)
			(xy 295.880536 -376.09399) (xy 295.880123 -376.084803) (xy 295.87361 -376.067619) (xy 295.867836 -376.060462)
			(xy 295.846 -376.034773) (xy 295.807908 -375.979143) (xy 295.776754 -375.91935) (xy 295.752987 -375.856256)
			(xy 295.736948 -375.79077) (xy 295.728869 -375.723834) (xy 295.728867 -375.656412) (xy 295.73694 -375.589475)
			(xy 295.752973 -375.523987) (xy 295.776736 -375.460891) (xy 295.807885 -375.401096) (xy 295.845973 -375.345463)
			(xy 295.867836 -375.319798) (xy 295.873621 -375.312644) (xy 295.880142 -375.29546) (xy 295.880536 -375.28627)
			(xy 295.880536 -374.794018) (xy 295.880109 -374.784833) (xy 295.873606 -374.767649) (xy 295.867836 -374.76049)
			(xy 295.84593 -374.734859) (xy 295.80784 -374.679221) (xy 295.776689 -374.61942) (xy 295.752925 -374.556319)
			(xy 295.736892 -374.490825) (xy 295.728819 -374.423882) (xy 292.450774 -374.423882) (xy 292.442742 -374.490639)
			(xy 292.426773 -374.55602) (xy 292.403104 -374.619022) (xy 292.372075 -374.678745) (xy 292.33413 -374.73433)
			(xy 292.312344 -374.759982) (xy 292.306523 -374.76711) (xy 292.300025 -374.784314) (xy 292.299644 -374.79351)
			(xy 292.299644 -375.286778) (xy 292.300077 -375.295962) (xy 292.306576 -375.313146) (xy 292.312344 -375.320306)
			(xy 292.334162 -375.345934) (xy 292.372111 -375.401523) (xy 292.403144 -375.46125) (xy 292.426816 -375.524258)
			(xy 292.442787 -375.589643) (xy 292.450829 -375.656469) (xy 292.450826 -375.723776) (xy 292.442779 -375.790601)
			(xy 292.426802 -375.855985) (xy 292.403125 -375.918991) (xy 292.372088 -375.978716) (xy 292.334134 -376.034302)
			(xy 292.312344 -376.059954) (xy 292.306535 -376.06709) (xy 292.300029 -376.084288) (xy 292.299644 -376.093482)
			(xy 292.299644 -376.25147) (xy 292.299211 -376.261642) (xy 292.291433 -376.280439) (xy 292.277049 -376.294826)
			(xy 292.258254 -376.302609) (xy 292.248082 -376.303032) (xy 291.531802 -376.303032) (xy 291.521627 -376.302634)
			(xy 291.502826 -376.294844) (xy 291.48844 -376.28045) (xy 291.480661 -376.261645) (xy 291.48024 -376.25147)
			(xy 291.48024 -376.093482) (xy 291.47983 -376.084295) (xy 291.473315 -376.067111) (xy 291.46754 -376.059954)
			(xy 291.445782 -376.034277) (xy 291.407832 -375.978695) (xy 291.376798 -375.918974) (xy 291.353123 -375.855973)
			(xy 291.337148 -375.790594) (xy 291.329101 -375.723774) (xy 291.329099 -375.656471) (xy 291.33714 -375.589651)
			(xy 291.35311 -375.52427) (xy 291.376779 -375.461267) (xy 291.407809 -375.401544) (xy 291.445754 -375.345958)
			(xy 291.46754 -375.320306) (xy 291.473322 -375.31315) (xy 291.479844 -375.295968) (xy 291.48024 -375.286778)
			(xy 291.48024 -374.79351) (xy 291.479816 -374.784324) (xy 291.473311 -374.76714) (xy 291.46754 -374.759982)
			(xy 291.445711 -374.734364) (xy 291.407763 -374.678773) (xy 291.376732 -374.619044) (xy 291.353061 -374.556035)
			(xy 291.337091 -374.490649) (xy 291.32905 -374.423823) (xy 288.051014 -374.423823) (xy 288.051014 -374.423879)
			(xy 288.042941 -374.490816) (xy 288.026909 -374.556303) (xy 288.003147 -374.619398) (xy 287.971998 -374.679193)
			(xy 287.933911 -374.734826) (xy 287.912048 -374.76049) (xy 287.906224 -374.767616) (xy 287.899727 -374.784821)
			(xy 287.899348 -374.794018) (xy 287.899348 -375.28627) (xy 287.899784 -375.295454) (xy 287.906281 -375.312638)
			(xy 287.912048 -375.319798) (xy 287.933943 -375.345438) (xy 287.972035 -375.401075) (xy 288.003187 -375.460874)
			(xy 288.026952 -375.523974) (xy 288.042987 -375.589467) (xy 288.051061 -375.656409) (xy 288.051058 -375.723836)
			(xy 288.042978 -375.790777) (xy 288.026938 -375.856269) (xy 288.003168 -375.919367) (xy 287.972011 -375.979164)
			(xy 287.933916 -376.034798) (xy 287.912048 -376.060462) (xy 287.906236 -376.067596) (xy 287.899732 -376.084795)
			(xy 287.899348 -376.09399) (xy 287.899348 -376.25147) (xy 287.898849 -376.261596) (xy 287.891129 -376.280319)
			(xy 287.876846 -376.294677) (xy 287.858164 -376.302495) (xy 287.84804 -376.303032) (xy 287.13176 -376.303032)
			(xy 287.121653 -376.302548) (xy 287.10298 -376.294804) (xy 287.088687 -376.280507) (xy 287.080948 -376.261831)
			(xy 287.080452 -376.251724) (xy 287.080452 -376.09399) (xy 287.080035 -376.084804) (xy 287.073525 -376.06762)
			(xy 287.067752 -376.060462) (xy 287.045916 -376.034773) (xy 287.007823 -375.979143) (xy 286.976668 -375.919351)
			(xy 286.9529 -375.856257) (xy 286.93686 -375.79077) (xy 286.928781 -375.723834) (xy 286.928779 -375.656411)
			(xy 286.936852 -375.589474) (xy 286.952886 -375.523986) (xy 286.976649 -375.46089) (xy 287.007799 -375.401095)
			(xy 287.045888 -375.345462) (xy 287.067752 -375.319798) (xy 287.073538 -375.312646) (xy 287.080058 -375.29546)
			(xy 287.080452 -375.28627) (xy 287.080452 -374.794018) (xy 287.080022 -374.784833) (xy 287.073521 -374.767649)
			(xy 287.067752 -374.76049) (xy 287.045845 -374.73486) (xy 287.007754 -374.679221) (xy 286.976602 -374.619421)
			(xy 286.952838 -374.556319) (xy 286.936804 -374.490825) (xy 286.928731 -374.423882) (xy 266.12088 -374.423882)
			(xy 266.12088 -377.534932) (xy 266.120477 -377.545004) (xy 266.112741 -377.563602) (xy 266.105894 -377.571)
			(xy 265.757406 -377.919234) (xy 265.750002 -377.926069) (xy 265.731406 -377.933791) (xy 265.721338 -377.93422)
			(xy 243.05133 -377.93422) (xy 243.04126 -377.9338) (xy 243.022661 -377.926078) (xy 243.015262 -377.919234)
			(xy 242.506246 -377.410472) (xy 242.499408 -377.40307) (xy 242.491685 -377.384473) (xy 242.49126 -377.374404)
			(xy 234.964478 -377.374404) (xy 236.356885 -378.766811) (xy 269.68983 -378.766811) (xy 269.68983 -378.633249)
			(xy 269.697894 -378.499931) (xy 269.713994 -378.367343) (xy 269.738069 -378.235969) (xy 269.770032 -378.106288)
			(xy 269.809767 -377.978774) (xy 269.857129 -377.853891) (xy 269.911944 -377.732096) (xy 269.974014 -377.613833)
			(xy 270.04311 -377.499534) (xy 270.118982 -377.389614) (xy 270.201352 -377.284477) (xy 270.28992 -377.184504)
			(xy 270.384362 -377.090062) (xy 270.484335 -377.001494) (xy 270.589472 -376.919124) (xy 270.699392 -376.843252)
			(xy 270.813691 -376.774156) (xy 270.931954 -376.712086) (xy 271.053749 -376.657271) (xy 271.178632 -376.609909)
			(xy 271.306146 -376.570174) (xy 271.435827 -376.538211) (xy 271.567201 -376.514136) (xy 271.699789 -376.498036)
			(xy 271.833107 -376.489972) (xy 271.966669 -376.489972) (xy 272.099987 -376.498036) (xy 272.232575 -376.514136)
			(xy 272.363949 -376.538211) (xy 272.49363 -376.570174) (xy 272.621144 -376.609909) (xy 272.746027 -376.657271)
			(xy 272.867822 -376.712086) (xy 272.986085 -376.774156) (xy 273.068299 -376.823856) (xy 289.128922 -376.823856)
			(xy 289.128922 -376.75655) (xy 289.136967 -376.689727) (xy 289.152941 -376.624344) (xy 289.176615 -376.56134)
			(xy 289.207651 -376.501617) (xy 289.245603 -376.446031) (xy 289.267392 -376.42038) (xy 289.273179 -376.413228)
			(xy 289.2797 -376.396043) (xy 289.280092 -376.386852) (xy 289.280092 -375.893584) (xy 289.279691 -375.884396)
			(xy 289.273171 -375.867212) (xy 289.267392 -375.860056) (xy 289.245634 -375.834379) (xy 289.207681 -375.778797)
			(xy 289.176643 -375.719078) (xy 289.152966 -375.656076) (xy 289.13699 -375.590696) (xy 289.128942 -375.523876)
			(xy 289.128939 -375.456572) (xy 289.136981 -375.389751) (xy 289.152952 -375.32437) (xy 289.176624 -375.261367)
			(xy 289.207656 -375.201644) (xy 289.245605 -375.146059) (xy 289.267392 -375.120408) (xy 289.273167 -375.113247)
			(xy 289.279695 -375.096069) (xy 289.280092 -375.08688) (xy 289.280092 -374.928638) (xy 289.280664 -374.918488)
			(xy 289.288417 -374.899729) (xy 289.302758 -374.885364) (xy 289.321505 -374.87758) (xy 289.331654 -374.877076)
			(xy 290.047934 -374.877076) (xy 290.058113 -374.877437) (xy 290.076915 -374.88524) (xy 290.0913 -374.899645)
			(xy 290.099077 -374.918459) (xy 290.099496 -374.928638) (xy 290.099496 -375.08688) (xy 290.099917 -375.096066)
			(xy 290.106423 -375.11325) (xy 290.112196 -375.120408) (xy 290.134014 -375.146035) (xy 290.17196 -375.201626)
			(xy 290.20299 -375.261353) (xy 290.226659 -375.324361) (xy 290.242629 -375.389746) (xy 290.25067 -375.456571)
			(xy 290.250667 -375.523878) (xy 290.24262 -375.590702) (xy 290.226645 -375.656085) (xy 290.20297 -375.719091)
			(xy 290.171935 -375.778816) (xy 290.133985 -375.834403) (xy 290.112196 -375.860056) (xy 290.106393 -375.867196)
			(xy 290.099882 -375.884391) (xy 290.099496 -375.893584) (xy 290.099496 -376.386852) (xy 290.09993 -376.396037)
			(xy 290.106427 -376.413221) (xy 290.112196 -376.42038) (xy 290.133987 -376.446029) (xy 290.171933 -376.501617)
			(xy 290.202964 -376.561341) (xy 290.226635 -376.624346) (xy 290.242607 -376.689728) (xy 290.25065 -376.756551)
			(xy 290.25065 -376.823855) (xy 290.250643 -376.823915) (xy 293.528715 -376.823915) (xy 293.528715 -376.756491)
			(xy 293.53679 -376.689554) (xy 293.552824 -376.624065) (xy 293.576588 -376.560968) (xy 293.607737 -376.501172)
			(xy 293.645825 -376.445537) (xy 293.667688 -376.419872) (xy 293.673478 -376.412722) (xy 293.679997 -376.395535)
			(xy 293.680388 -376.386344) (xy 293.680388 -375.894092) (xy 293.679984 -375.884904) (xy 293.673466 -375.86772)
			(xy 293.667688 -375.860564) (xy 293.645856 -375.834873) (xy 293.607767 -375.779242) (xy 293.576616 -375.719449)
			(xy 293.55285 -375.656355) (xy 293.536813 -375.59087) (xy 293.528735 -375.523934) (xy 293.528732 -375.456514)
			(xy 293.536804 -375.389578) (xy 293.552836 -375.324091) (xy 293.576596 -375.260995) (xy 293.607742 -375.2012)
			(xy 293.645826 -375.145565) (xy 293.667688 -375.1199) (xy 293.673466 -375.112741) (xy 293.679992 -375.095561)
			(xy 293.680388 -375.086372) (xy 293.680388 -374.928638) (xy 293.680956 -374.91852) (xy 293.688662 -374.89981)
			(xy 293.702923 -374.885454) (xy 293.721582 -374.877624) (xy 293.731696 -374.877076) (xy 294.447976 -374.877076)
			(xy 294.458094 -374.877535) (xy 294.476793 -374.885271) (xy 294.491107 -374.899574) (xy 294.498857 -374.918266)
			(xy 294.499284 -374.928384) (xy 294.499284 -375.086372) (xy 294.499711 -375.095557) (xy 294.506214 -375.112742)
			(xy 294.511984 -375.1199) (xy 294.53388 -375.145539) (xy 294.571969 -375.201177) (xy 294.603119 -375.260977)
			(xy 294.626882 -375.324077) (xy 294.642916 -375.389569) (xy 294.650989 -375.456511) (xy 294.650986 -375.523937)
			(xy 294.642907 -375.590878) (xy 294.626868 -375.656369) (xy 294.603099 -375.719467) (xy 294.571944 -375.779264)
			(xy 294.53385 -375.834899) (xy 294.511984 -375.860564) (xy 294.506176 -375.867701) (xy 294.499669 -375.884898)
			(xy 294.499284 -375.894092) (xy 294.499284 -376.386344) (xy 294.499677 -376.395533) (xy 294.506203 -376.412717)
			(xy 294.511984 -376.419872) (xy 294.533852 -376.445534) (xy 294.571942 -376.501168) (xy 294.603094 -376.560965)
			(xy 294.626858 -376.624062) (xy 294.642894 -376.689552) (xy 294.65097 -376.756491) (xy 294.650969 -376.823856)
			(xy 297.92901 -376.823856) (xy 297.92901 -376.75655) (xy 297.937054 -376.689727) (xy 297.953028 -376.624345)
			(xy 297.976702 -376.56134) (xy 298.007737 -376.501617) (xy 298.045687 -376.446032) (xy 298.067476 -376.42038)
			(xy 298.073261 -376.413226) (xy 298.079783 -376.396042) (xy 298.080176 -376.386852) (xy 298.080176 -375.893584)
			(xy 298.079779 -375.884395) (xy 298.073257 -375.867211) (xy 298.067476 -375.860056) (xy 298.045719 -375.834378)
			(xy 298.007766 -375.778797) (xy 297.97673 -375.719077) (xy 297.953054 -375.656076) (xy 297.937077 -375.590696)
			(xy 297.92903 -375.523876) (xy 297.929027 -375.456572) (xy 297.937069 -375.389751) (xy 297.953039 -375.324371)
			(xy 297.97671 -375.261367) (xy 298.007742 -375.201645) (xy 298.045689 -375.14606) (xy 298.067476 -375.120408)
			(xy 298.073249 -375.113246) (xy 298.079778 -375.096068) (xy 298.080176 -375.08688) (xy 298.080176 -374.928638)
			(xy 298.080596 -374.918464) (xy 298.088376 -374.899663) (xy 298.102763 -374.885276) (xy 298.121564 -374.877496)
			(xy 298.131738 -374.877076) (xy 298.848018 -374.877076) (xy 298.858195 -374.87745) (xy 298.876998 -374.885248)
			(xy 298.891383 -374.899649) (xy 298.899161 -374.91846) (xy 298.89958 -374.928638) (xy 298.89958 -375.08688)
			(xy 298.900004 -375.096066) (xy 298.906509 -375.11325) (xy 298.91228 -375.120408) (xy 298.934099 -375.146035)
			(xy 298.972045 -375.201625) (xy 299.003076 -375.261352) (xy 299.026746 -375.32436) (xy 299.042716 -375.389745)
			(xy 299.050758 -375.45657) (xy 299.050755 -375.523878) (xy 299.042708 -375.590702) (xy 299.026732 -375.656086)
			(xy 299.003056 -375.719092) (xy 298.972021 -375.778816) (xy 298.934069 -375.834404) (xy 298.91228 -375.860056)
			(xy 298.906475 -375.867195) (xy 298.899966 -375.88439) (xy 298.89958 -375.893584) (xy 298.89958 -376.386852)
			(xy 298.900018 -376.396036) (xy 298.906513 -376.413221) (xy 298.91228 -376.42038) (xy 298.934071 -376.446029)
			(xy 298.972019 -376.501616) (xy 299.003051 -376.561341) (xy 299.026722 -376.624345) (xy 299.042695 -376.689728)
			(xy 299.050731 -376.756492) (xy 302.328802 -376.756492) (xy 302.336877 -376.689554) (xy 302.352912 -376.624066)
			(xy 302.376674 -376.560969) (xy 302.407823 -376.501173) (xy 302.445909 -376.445538) (xy 302.467772 -376.419872)
			(xy 302.473572 -376.412729) (xy 302.480082 -376.395537) (xy 302.480472 -376.386344) (xy 302.480472 -375.894092)
			(xy 302.480072 -375.884904) (xy 302.473552 -375.867719) (xy 302.467772 -375.860564) (xy 302.44594 -375.834872)
			(xy 302.407853 -375.779241) (xy 302.376702 -375.719448) (xy 302.352937 -375.656355) (xy 302.336901 -375.590869)
			(xy 302.328823 -375.523934) (xy 302.32882 -375.456514) (xy 302.336892 -375.389578) (xy 302.352923 -375.324091)
			(xy 302.376682 -375.260996) (xy 302.407828 -375.2012) (xy 302.445911 -375.145566) (xy 302.467772 -375.1199)
			(xy 302.47356 -375.112749) (xy 302.480078 -375.095563) (xy 302.480472 -375.086372) (xy 302.480472 -374.928638)
			(xy 302.480959 -374.91851) (xy 302.48868 -374.899784) (xy 302.502967 -374.885425) (xy 302.521654 -374.87761)
			(xy 302.53178 -374.877076) (xy 303.24806 -374.877076) (xy 303.258209 -374.877554) (xy 303.276955 -374.885332)
			(xy 303.291279 -374.899711) (xy 303.298985 -374.918488) (xy 303.299368 -374.928638) (xy 303.299368 -375.086372)
			(xy 303.299799 -375.095557) (xy 303.306299 -375.112741) (xy 303.312068 -375.1199) (xy 303.333965 -375.145539)
			(xy 303.372054 -375.201176) (xy 303.403205 -375.260976) (xy 303.426969 -375.324076) (xy 303.443004 -375.389569)
			(xy 303.451077 -375.456511) (xy 303.451074 -375.523937) (xy 303.442995 -375.590878) (xy 303.426955 -375.65637)
			(xy 303.403186 -375.719468) (xy 303.37203 -375.779265) (xy 303.333935 -375.834899) (xy 303.312068 -375.860564)
			(xy 303.306258 -375.867699) (xy 303.299752 -375.884898) (xy 303.299368 -375.894092) (xy 303.299368 -376.386344)
			(xy 303.299764 -376.395533) (xy 303.306288 -376.412716) (xy 303.312068 -376.419872) (xy 303.333937 -376.445533)
			(xy 303.372028 -376.501168) (xy 303.40318 -376.560964) (xy 303.426945 -376.624062) (xy 303.442982 -376.689551)
			(xy 303.451058 -376.756491) (xy 303.451057 -376.823915) (xy 333.128833 -376.823915) (xy 333.128833 -376.756491)
			(xy 333.136908 -376.689553) (xy 333.152944 -376.624064) (xy 333.176708 -376.560967) (xy 333.207859 -376.501171)
			(xy 333.245948 -376.445537) (xy 333.267812 -376.419872) (xy 333.273604 -376.412724) (xy 333.280121 -376.395536)
			(xy 333.280512 -376.386344) (xy 333.280512 -375.894092) (xy 333.280103 -375.884905) (xy 333.273588 -375.86772)
			(xy 333.267812 -375.860564) (xy 333.245979 -375.834873) (xy 333.207889 -375.779242) (xy 333.176736 -375.71945)
			(xy 333.152969 -375.656356) (xy 333.136931 -375.59087) (xy 333.128853 -375.523935) (xy 333.12885 -375.456513)
			(xy 333.136923 -375.389577) (xy 333.152955 -375.32409) (xy 333.176716 -375.260994) (xy 333.207864 -375.201199)
			(xy 333.24595 -375.145565) (xy 333.267812 -375.1199) (xy 333.273592 -375.112743) (xy 333.280116 -375.095562)
			(xy 333.280512 -375.086372) (xy 333.280512 -374.928638) (xy 333.281057 -374.918517) (xy 333.288767 -374.899802)
			(xy 333.303035 -374.885446) (xy 333.321702 -374.87762) (xy 333.33182 -374.877076) (xy 334.0481 -374.877076)
			(xy 334.058251 -374.877521) (xy 334.076999 -374.885312) (xy 334.091321 -374.899701) (xy 334.099025 -374.918485)
			(xy 334.099408 -374.928638) (xy 334.099408 -375.086372) (xy 334.09983 -375.095558) (xy 334.106335 -375.112743)
			(xy 334.112108 -375.1199) (xy 334.134003 -375.145539) (xy 334.17209 -375.201178) (xy 334.203239 -375.260978)
			(xy 334.227001 -375.324078) (xy 334.243034 -375.38957) (xy 334.251107 -375.456511) (xy 334.251105 -375.523937)
			(xy 334.243026 -375.590877) (xy 334.226987 -375.656368) (xy 334.20322 -375.719466) (xy 334.172066 -375.779263)
			(xy 334.133974 -375.834899) (xy 334.112108 -375.860564) (xy 334.106303 -375.867703) (xy 334.099793 -375.884898)
			(xy 334.099408 -375.894092) (xy 334.099408 -376.386344) (xy 334.099795 -376.395534) (xy 334.106324 -376.412718)
			(xy 334.112108 -376.419872) (xy 334.133976 -376.445534) (xy 334.172064 -376.501169) (xy 334.203214 -376.560966)
			(xy 334.226977 -376.624063) (xy 334.243012 -376.689553) (xy 334.251088 -376.756491) (xy 334.251087 -376.823855)
			(xy 337.529152 -376.823855) (xy 337.529152 -376.756551) (xy 337.537195 -376.689729) (xy 337.553167 -376.624348)
			(xy 337.576837 -376.561344) (xy 337.607868 -376.50162) (xy 337.645814 -376.446033) (xy 337.6676 -376.42038)
			(xy 337.673388 -376.413228) (xy 337.679908 -376.396043) (xy 337.6803 -376.386852) (xy 337.6803 -375.893584)
			(xy 337.679897 -375.884396) (xy 337.673378 -375.867212) (xy 337.6676 -375.860056) (xy 337.645845 -375.834377)
			(xy 337.607898 -375.778794) (xy 337.576865 -375.719074) (xy 337.553192 -375.656073) (xy 337.537218 -375.590694)
			(xy 337.529172 -375.523875) (xy 337.529169 -375.456573) (xy 337.53721 -375.389753) (xy 337.553178 -375.324373)
			(xy 337.576846 -375.26137) (xy 337.607873 -375.201647) (xy 337.645815 -375.146061) (xy 337.6676 -375.120408)
			(xy 337.673376 -375.113248) (xy 337.679903 -375.096069) (xy 337.6803 -375.08688) (xy 337.6803 -374.928638)
			(xy 337.680864 -374.918487) (xy 337.688619 -374.899726) (xy 337.702963 -374.885361) (xy 337.721712 -374.877579)
			(xy 337.731862 -374.877076) (xy 338.448142 -374.877076) (xy 338.458307 -374.8775) (xy 338.477085 -374.885295)
			(xy 338.49145 -374.899683) (xy 338.499216 -374.918472) (xy 338.499704 -374.928638) (xy 338.499704 -375.08688)
			(xy 338.500123 -375.096066) (xy 338.50663 -375.113251) (xy 338.512404 -375.120408) (xy 338.534222 -375.146035)
			(xy 338.572167 -375.201626) (xy 338.603196 -375.261353) (xy 338.626865 -375.324361) (xy 338.642835 -375.389746)
			(xy 338.650876 -375.456571) (xy 338.650873 -375.523877) (xy 338.642826 -375.590701) (xy 338.626851 -375.656085)
			(xy 338.603177 -375.719091) (xy 338.572142 -375.778815) (xy 338.534192 -375.834403) (xy 338.512404 -375.860056)
			(xy 338.506602 -375.867197) (xy 338.50009 -375.884391) (xy 338.499704 -375.893584) (xy 338.499704 -376.386852)
			(xy 338.500136 -376.396037) (xy 338.506634 -376.413222) (xy 338.512404 -376.42038) (xy 338.534194 -376.44603)
			(xy 338.57214 -376.501617) (xy 338.603171 -376.561342) (xy 338.626842 -376.624346) (xy 338.642813 -376.689729)
			(xy 338.650856 -376.756551) (xy 338.650856 -376.823855) (xy 338.650849 -376.823915) (xy 341.928921 -376.823915)
			(xy 341.928921 -376.756491) (xy 341.936996 -376.689553) (xy 341.953031 -376.624065) (xy 341.976794 -376.560968)
			(xy 342.007944 -376.501172) (xy 342.046032 -376.445537) (xy 342.067896 -376.419872) (xy 342.073686 -376.412722)
			(xy 342.080205 -376.395535) (xy 342.080596 -376.386344) (xy 342.080596 -375.894092) (xy 342.08019 -375.884904)
			(xy 342.073674 -375.86772) (xy 342.067896 -375.860564) (xy 342.046064 -375.834873) (xy 342.007974 -375.779242)
			(xy 341.976822 -375.719449) (xy 341.953057 -375.656356) (xy 341.937019 -375.59087) (xy 341.928941 -375.523935)
			(xy 341.928938 -375.456513) (xy 341.93701 -375.389577) (xy 341.953042 -375.32409) (xy 341.976803 -375.260995)
			(xy 342.007949 -375.201199) (xy 342.046034 -375.145565) (xy 342.067896 -375.1199) (xy 342.073675 -375.112742)
			(xy 342.0802 -375.095561) (xy 342.080596 -375.086372) (xy 342.080596 -374.928638) (xy 342.081157 -374.918519)
			(xy 342.088864 -374.899807) (xy 342.103127 -374.885451) (xy 342.121789 -374.877623) (xy 342.131904 -374.877076)
			(xy 342.848184 -374.877076) (xy 342.858334 -374.877534) (xy 342.877082 -374.88532) (xy 342.891405 -374.899705)
			(xy 342.899109 -374.918486) (xy 342.899492 -374.928638) (xy 342.899492 -375.086372) (xy 342.899917 -375.095558)
			(xy 342.906421 -375.112742) (xy 342.912192 -375.1199) (xy 342.934088 -375.145539) (xy 342.972176 -375.201177)
			(xy 343.003326 -375.260977) (xy 343.027088 -375.324077) (xy 343.043122 -375.38957) (xy 343.051195 -375.456511)
			(xy 343.051193 -375.523937) (xy 343.043113 -375.590878) (xy 343.027074 -375.656369) (xy 343.003306 -375.719467)
			(xy 342.972151 -375.779264) (xy 342.934058 -375.834899) (xy 342.912192 -375.860564) (xy 342.906385 -375.867702)
			(xy 342.899877 -375.884898) (xy 342.899492 -375.894092) (xy 342.899492 -376.386344) (xy 342.899883 -376.395533)
			(xy 342.90641 -376.412717) (xy 342.912192 -376.419872) (xy 342.93406 -376.445534) (xy 342.972149 -376.501169)
			(xy 343.0033 -376.560965) (xy 343.027065 -376.624063) (xy 343.0431 -376.689552) (xy 343.051176 -376.756491)
			(xy 343.051175 -376.823856) (xy 346.329216 -376.823856) (xy 346.329216 -376.75655) (xy 346.33726 -376.689727)
			(xy 346.353234 -376.624345) (xy 346.376909 -376.56134) (xy 346.407944 -376.501617) (xy 346.445895 -376.446032)
			(xy 346.467684 -376.42038) (xy 346.47347 -376.413227) (xy 346.479991 -376.396043) (xy 346.480384 -376.386852)
			(xy 346.480384 -375.893584) (xy 346.479985 -375.884396) (xy 346.473464 -375.867211) (xy 346.467684 -375.860056)
			(xy 346.445926 -375.834379) (xy 346.407974 -375.778797) (xy 346.376937 -375.719077) (xy 346.35326 -375.656076)
			(xy 346.337283 -375.590696) (xy 346.329236 -375.523876) (xy 346.329233 -375.456572) (xy 346.337275 -375.389751)
			(xy 346.353246 -375.32437) (xy 346.376917 -375.261367) (xy 346.407949 -375.201645) (xy 346.445897 -375.14606)
			(xy 346.467684 -375.120408) (xy 346.473458 -375.113247) (xy 346.479987 -375.096069) (xy 346.480384 -375.08688)
			(xy 346.480384 -374.928638) (xy 346.480796 -374.918463) (xy 346.488577 -374.899661) (xy 346.502967 -374.885273)
			(xy 346.521771 -374.877495) (xy 346.531946 -374.877076) (xy 347.248226 -374.877076) (xy 347.258404 -374.877443)
			(xy 347.277207 -374.885244) (xy 347.291592 -374.899647) (xy 347.299369 -374.918459) (xy 347.299788 -374.928638)
			(xy 347.299788 -375.08688) (xy 347.300211 -375.096066) (xy 347.306716 -375.11325) (xy 347.312488 -375.120408)
			(xy 347.334306 -375.146035) (xy 347.372252 -375.201625) (xy 347.403283 -375.261353) (xy 347.426953 -375.324361)
			(xy 347.442923 -375.389746) (xy 347.450964 -375.456571) (xy 347.450961 -375.523878) (xy 347.442914 -375.590702)
			(xy 347.426938 -375.656086) (xy 347.403263 -375.719091) (xy 347.372228 -375.778816) (xy 347.334277 -375.834403)
			(xy 347.312488 -375.860056) (xy 347.306684 -375.867196) (xy 347.300174 -375.88439) (xy 347.299788 -375.893584)
			(xy 347.299788 -376.386852) (xy 347.300224 -376.396036) (xy 347.30672 -376.413221) (xy 347.312488 -376.42038)
			(xy 347.334279 -376.446029) (xy 347.372226 -376.501617) (xy 347.403257 -376.561341) (xy 347.426929 -376.624346)
			(xy 347.442901 -376.689728) (xy 347.450944 -376.756551) (xy 347.450944 -376.823855) (xy 347.450937 -376.823915)
			(xy 377.128742 -376.823915) (xy 377.128742 -376.756491) (xy 377.136817 -376.689553) (xy 377.152853 -376.624064)
			(xy 377.176618 -376.560967) (xy 377.20777 -376.501171) (xy 377.245859 -376.445537) (xy 377.267724 -376.419872)
			(xy 377.273518 -376.412725) (xy 377.280033 -376.395536) (xy 377.280424 -376.386344) (xy 377.280424 -375.894092)
			(xy 377.280012 -375.884905) (xy 377.273499 -375.867721) (xy 377.267724 -375.860564) (xy 377.245891 -375.834873)
			(xy 377.207799 -375.779243) (xy 377.176646 -375.71945) (xy 377.152879 -375.656357) (xy 377.136841 -375.590871)
			(xy 377.128762 -375.523935) (xy 377.128759 -375.456513) (xy 377.136832 -375.389577) (xy 377.152865 -375.324089)
			(xy 377.176626 -375.260993) (xy 377.207775 -375.201198) (xy 377.245861 -375.145565) (xy 377.267724 -375.1199)
			(xy 377.273506 -375.112744) (xy 377.280029 -375.095562) (xy 377.280424 -375.086372) (xy 377.280424 -374.928638)
			(xy 377.280957 -374.918516) (xy 377.28867 -374.899799) (xy 377.302942 -374.885442) (xy 377.321613 -374.877618)
			(xy 377.331732 -374.877076) (xy 378.048012 -374.877076) (xy 378.058164 -374.877511) (xy 378.076912 -374.885306)
			(xy 378.091234 -374.899698) (xy 378.098938 -374.918484) (xy 378.09932 -374.928638) (xy 378.09932 -375.086372)
			(xy 378.099739 -375.095558) (xy 378.106246 -375.112743) (xy 378.11202 -375.1199) (xy 378.133915 -375.14554)
			(xy 378.172001 -375.201178) (xy 378.203149 -375.260978) (xy 378.226911 -375.324078) (xy 378.242943 -375.38957)
			(xy 378.251016 -375.456511) (xy 378.251014 -375.523937) (xy 378.242935 -375.590877) (xy 378.226897 -375.656368)
			(xy 378.20313 -375.719466) (xy 378.171976 -375.779263) (xy 378.133885 -375.834898) (xy 378.11202 -375.860564)
			(xy 378.106216 -375.867704) (xy 378.099705 -375.884898) (xy 378.09932 -375.894092) (xy 378.09932 -376.386344)
			(xy 378.099704 -376.395534) (xy 378.106235 -376.412718) (xy 378.11202 -376.419872) (xy 378.133887 -376.445534)
			(xy 378.171974 -376.50117) (xy 378.203124 -376.560967) (xy 378.226887 -376.624064) (xy 378.242922 -376.689553)
			(xy 378.250997 -376.756491) (xy 378.250997 -376.756551) (xy 381.529061 -376.756551) (xy 381.537105 -376.689729)
			(xy 381.553076 -376.624347) (xy 381.576747 -376.561343) (xy 381.607779 -376.501619) (xy 381.645725 -376.446032)
			(xy 381.667512 -376.42038) (xy 381.673301 -376.413229) (xy 381.67982 -376.396043) (xy 381.680212 -376.386852)
			(xy 381.680212 -375.893584) (xy 381.679807 -375.884396) (xy 381.67329 -375.867212) (xy 381.667512 -375.860056)
			(xy 381.645756 -375.834378) (xy 381.607808 -375.778794) (xy 381.576775 -375.719074) (xy 381.553102 -375.656073)
			(xy 381.537127 -375.590694) (xy 381.529081 -375.523875) (xy 381.529078 -375.456573) (xy 381.537119 -375.389753)
			(xy 381.553088 -375.324373) (xy 381.576756 -375.26137) (xy 381.607784 -375.201647) (xy 381.645727 -375.14606)
			(xy 381.667512 -375.120408) (xy 381.673289 -375.113249) (xy 381.679815 -375.096069) (xy 381.680212 -375.08688)
			(xy 381.680212 -374.928638) (xy 381.680694 -374.918472) (xy 381.688462 -374.899683) (xy 381.702829 -374.885298)
			(xy 381.721609 -374.877507) (xy 381.731774 -374.877076) (xy 382.448054 -374.877076) (xy 382.458227 -374.877502)
			(xy 382.477028 -374.885279) (xy 382.491416 -374.899665) (xy 382.499196 -374.918465) (xy 382.499616 -374.928638)
			(xy 382.499616 -375.08688) (xy 382.500032 -375.096067) (xy 382.506541 -375.113251) (xy 382.512316 -375.120408)
			(xy 382.534136 -375.146034) (xy 382.572087 -375.201623) (xy 382.603122 -375.26135) (xy 382.626795 -375.324358)
			(xy 382.642767 -375.389744) (xy 382.650809 -375.45657) (xy 382.650806 -375.523878) (xy 382.642758 -375.590704)
			(xy 382.62678 -375.656088) (xy 382.603102 -375.719094) (xy 382.572063 -375.778818) (xy 382.534107 -375.834404)
			(xy 382.512316 -375.860056) (xy 382.506515 -375.867198) (xy 382.500002 -375.884391) (xy 382.499616 -375.893584)
			(xy 382.499616 -376.386852) (xy 382.500045 -376.396037) (xy 382.506545 -376.413222) (xy 382.512316 -376.42038)
			(xy 382.534109 -376.446028) (xy 382.572061 -376.501614) (xy 382.603096 -376.561338) (xy 382.626771 -376.624343)
			(xy 382.642745 -376.689726) (xy 382.650789 -376.75655) (xy 382.650789 -376.823856) (xy 382.650782 -376.823915)
			(xy 385.92883 -376.823915) (xy 385.92883 -376.756491) (xy 385.936905 -376.689553) (xy 385.95294 -376.624064)
			(xy 385.976705 -376.560967) (xy 386.007855 -376.501171) (xy 386.045944 -376.445537) (xy 386.067808 -376.419872)
			(xy 386.0736 -376.412724) (xy 386.080117 -376.395535) (xy 386.080508 -376.386344) (xy 386.080508 -375.894092)
			(xy 386.0801 -375.884905) (xy 386.073584 -375.867721) (xy 386.067808 -375.860564) (xy 386.045975 -375.834873)
			(xy 386.007885 -375.779242) (xy 385.976732 -375.71945) (xy 385.952966 -375.656356) (xy 385.936928 -375.59087)
			(xy 385.92885 -375.523935) (xy 385.928847 -375.456513) (xy 385.93692 -375.389577) (xy 385.952952 -375.32409)
			(xy 385.976713 -375.260994) (xy 386.00786 -375.201199) (xy 386.045946 -375.145565) (xy 386.067808 -375.1199)
			(xy 386.073588 -375.112743) (xy 386.080112 -375.095562) (xy 386.080508 -375.086372) (xy 386.080508 -374.928638)
			(xy 386.081057 -374.918518) (xy 386.088766 -374.899804) (xy 386.103033 -374.885447) (xy 386.121699 -374.877621)
			(xy 386.131816 -374.877076) (xy 386.848096 -374.877076) (xy 386.858247 -374.877524) (xy 386.876995 -374.885314)
			(xy 386.891317 -374.899702) (xy 386.899021 -374.918485) (xy 386.899404 -374.928638) (xy 386.899404 -375.086372)
			(xy 386.899827 -375.095558) (xy 386.906332 -375.112742) (xy 386.912104 -375.1199) (xy 386.933999 -375.145539)
			(xy 386.972087 -375.201178) (xy 387.003236 -375.260978) (xy 387.026998 -375.324078) (xy 387.043031 -375.38957)
			(xy 387.051104 -375.456511) (xy 387.051102 -375.523937) (xy 387.043023 -375.590877) (xy 387.026984 -375.656368)
			(xy 387.003216 -375.719466) (xy 386.972062 -375.779264) (xy 386.93397 -375.834899) (xy 386.912104 -375.860564)
			(xy 386.906298 -375.867703) (xy 386.899789 -375.884898) (xy 386.899404 -375.894092) (xy 386.899404 -376.386344)
			(xy 386.899792 -376.395534) (xy 386.906321 -376.412718) (xy 386.912104 -376.419872) (xy 386.933972 -376.445534)
			(xy 386.97206 -376.501169) (xy 387.00321 -376.560966) (xy 387.026974 -376.624063) (xy 387.043009 -376.689552)
			(xy 387.051085 -376.756491) (xy 387.051084 -376.823855) (xy 390.329149 -376.823855) (xy 390.329149 -376.756551)
			(xy 390.337192 -376.689729) (xy 390.353163 -376.624348) (xy 390.376834 -376.561344) (xy 390.407864 -376.50162)
			(xy 390.44581 -376.446033) (xy 390.467596 -376.42038) (xy 390.473383 -376.413228) (xy 390.479904 -376.396043)
			(xy 390.480296 -376.386852) (xy 390.480296 -375.893584) (xy 390.479894 -375.884396) (xy 390.473375 -375.867212)
			(xy 390.467596 -375.860056) (xy 390.445841 -375.834377) (xy 390.407894 -375.778794) (xy 390.376862 -375.719073)
			(xy 390.353189 -375.656072) (xy 390.337215 -375.590694) (xy 390.329169 -375.523875) (xy 390.329166 -375.456573)
			(xy 390.337207 -375.389754) (xy 390.353175 -375.324374) (xy 390.376842 -375.261371) (xy 390.407869 -375.201648)
			(xy 390.445812 -375.146061) (xy 390.467596 -375.120408) (xy 390.473371 -375.113248) (xy 390.479899 -375.096069)
			(xy 390.480296 -375.08688) (xy 390.480296 -374.928638) (xy 390.480864 -374.918488) (xy 390.488618 -374.899728)
			(xy 390.502961 -374.885363) (xy 390.521709 -374.877579) (xy 390.531858 -374.877076) (xy 391.248138 -374.877076)
			(xy 391.258303 -374.877503) (xy 391.27708 -374.885297) (xy 391.291445 -374.899684) (xy 391.299212 -374.918472)
			(xy 391.2997 -374.928638) (xy 391.2997 -375.08688) (xy 391.30012 -375.096066) (xy 391.306627 -375.113251)
			(xy 391.3124 -375.120408) (xy 391.334218 -375.146035) (xy 391.372163 -375.201626) (xy 391.403193 -375.261353)
			(xy 391.426862 -375.324361) (xy 391.442832 -375.389746) (xy 391.450873 -375.456571) (xy 391.45087 -375.523877)
			(xy 391.442823 -375.590702) (xy 391.426848 -375.656085) (xy 391.403173 -375.719091) (xy 391.372139 -375.778816)
			(xy 391.334188 -375.834403) (xy 391.3124 -375.860056) (xy 391.306597 -375.867197) (xy 391.300086 -375.884391)
			(xy 391.2997 -375.893584) (xy 391.2997 -376.386852) (xy 391.300133 -376.396037) (xy 391.306631 -376.413221)
			(xy 391.3124 -376.42038) (xy 391.33419 -376.446029) (xy 391.372137 -376.501617) (xy 391.403168 -376.561342)
			(xy 391.426838 -376.624346) (xy 391.44281 -376.689728) (xy 391.450853 -376.756551) (xy 391.450853 -376.823855)
			(xy 391.450846 -376.823915) (xy 421.128651 -376.823915) (xy 421.128651 -376.756491) (xy 421.136727 -376.689552)
			(xy 421.152763 -376.624063) (xy 421.176528 -376.560966) (xy 421.20768 -376.50117) (xy 421.245771 -376.445537)
			(xy 421.267636 -376.419872) (xy 421.273432 -376.412726) (xy 421.279946 -376.395536) (xy 421.280336 -376.386344)
			(xy 421.280336 -375.894092) (xy 421.279922 -375.884905) (xy 421.27341 -375.867721) (xy 421.267636 -375.860564)
			(xy 421.245802 -375.834873) (xy 421.20771 -375.779243) (xy 421.176556 -375.719451) (xy 421.152788 -375.656357)
			(xy 421.13675 -375.590871) (xy 421.128671 -375.523935) (xy 421.128668 -375.456513) (xy 421.136741 -375.389576)
			(xy 421.152774 -375.324089) (xy 421.176536 -375.260993) (xy 421.207685 -375.201198) (xy 421.245773 -375.145565)
			(xy 421.267636 -375.1199) (xy 421.27342 -375.112746) (xy 421.279941 -375.095562) (xy 421.280336 -375.086372)
			(xy 421.280336 -374.928638) (xy 421.280858 -374.918514) (xy 421.288572 -374.899795) (xy 421.302848 -374.885437)
			(xy 421.321523 -374.877616) (xy 421.331644 -374.877076) (xy 422.047924 -374.877076) (xy 422.058031 -374.877565)
			(xy 422.076706 -374.885306) (xy 422.090999 -374.899601) (xy 422.098737 -374.918277) (xy 422.099232 -374.928384)
			(xy 422.099232 -375.086372) (xy 422.099671 -375.095556) (xy 422.106166 -375.11274) (xy 422.111932 -375.1199)
			(xy 422.133826 -375.14554) (xy 422.171912 -375.201179) (xy 422.203059 -375.260979) (xy 422.22682 -375.324079)
			(xy 422.242853 -375.389571) (xy 422.250926 -375.456511) (xy 422.250923 -375.523937) (xy 422.242844 -375.590877)
			(xy 422.226806 -375.656367) (xy 422.20304 -375.719465) (xy 422.171887 -375.779263) (xy 422.133797 -375.834898)
			(xy 422.111932 -375.860564) (xy 422.106117 -375.867696) (xy 422.099615 -375.884897) (xy 422.099232 -375.894092)
			(xy 422.099232 -376.386344) (xy 422.099636 -376.395532) (xy 422.106156 -376.412715) (xy 422.111932 -376.419872)
			(xy 422.133799 -376.445535) (xy 422.171885 -376.50117) (xy 422.203034 -376.560967) (xy 422.226797 -376.624064)
			(xy 422.242831 -376.689553) (xy 422.250906 -376.756491) (xy 422.250906 -376.756551) (xy 425.52897 -376.756551)
			(xy 425.537014 -376.689729) (xy 425.552986 -376.624347) (xy 425.576658 -376.561343) (xy 425.607689 -376.501619)
			(xy 425.645637 -376.446032) (xy 425.667424 -376.42038) (xy 425.673214 -376.413231) (xy 425.679732 -376.396043)
			(xy 425.680124 -376.386852) (xy 425.680124 -375.893584) (xy 425.679716 -375.884397) (xy 425.6732 -375.867213)
			(xy 425.667424 -375.860056) (xy 425.645668 -375.834378) (xy 425.60772 -375.778795) (xy 425.576686 -375.719074)
			(xy 425.553012 -375.656073) (xy 425.537037 -375.590695) (xy 425.528991 -375.523875) (xy 425.528988 -375.456573)
			(xy 425.537029 -375.389753) (xy 425.552998 -375.324373) (xy 425.576666 -375.26137) (xy 425.607695 -375.201647)
			(xy 425.645639 -375.146061) (xy 425.667424 -375.120408) (xy 425.673202 -375.11325) (xy 425.679727 -375.096069)
			(xy 425.680124 -375.08688) (xy 425.680124 -374.928638) (xy 425.680595 -374.918471) (xy 425.688365 -374.899679)
			(xy 425.702736 -374.885294) (xy 425.721519 -374.877505) (xy 425.731686 -374.877076) (xy 426.447966 -374.877076)
			(xy 426.45814 -374.877493) (xy 426.476941 -374.885274) (xy 426.491329 -374.899662) (xy 426.499108 -374.918464)
			(xy 426.499528 -374.928638) (xy 426.499528 -375.08688) (xy 426.499941 -375.096067) (xy 426.506452 -375.113252)
			(xy 426.512228 -375.120408) (xy 426.534048 -375.146034) (xy 426.571998 -375.201623) (xy 426.603032 -375.26135)
			(xy 426.626705 -375.324358) (xy 426.642676 -375.389744) (xy 426.650718 -375.45657) (xy 426.650716 -375.523878)
			(xy 426.642668 -375.590704) (xy 426.62669 -375.656088) (xy 426.603013 -375.719094) (xy 426.571974 -375.778818)
			(xy 426.534019 -375.834404) (xy 426.512228 -375.860056) (xy 426.506416 -375.86719) (xy 426.499913 -375.884389)
			(xy 426.499528 -375.893584) (xy 426.499528 -376.386852) (xy 426.499955 -376.396037) (xy 426.506456 -376.413222)
			(xy 426.512228 -376.42038) (xy 426.534021 -376.446029) (xy 426.571971 -376.501615) (xy 426.603006 -376.561338)
			(xy 426.62668 -376.624344) (xy 426.642654 -376.689727) (xy 426.650698 -376.75655) (xy 426.650698 -376.823856)
			(xy 426.650691 -376.823915) (xy 429.928739 -376.823915) (xy 429.928739 -376.756491) (xy 429.936814 -376.689553)
			(xy 429.95285 -376.624064) (xy 429.976615 -376.560967) (xy 430.007766 -376.501171) (xy 430.045856 -376.445537)
			(xy 430.06772 -376.419872) (xy 430.073513 -376.412725) (xy 430.080029 -376.395536) (xy 430.08042 -376.386344)
			(xy 430.08042 -375.894092) (xy 430.080009 -375.884905) (xy 430.073496 -375.867721) (xy 430.06772 -375.860564)
			(xy 430.045887 -375.834873) (xy 430.007796 -375.779243) (xy 429.976643 -375.71945) (xy 429.952876 -375.656357)
			(xy 429.936837 -375.590871) (xy 429.928759 -375.523935) (xy 429.928756 -375.456513) (xy 429.936829 -375.389577)
			(xy 429.952861 -375.324089) (xy 429.976623 -375.260994) (xy 430.007771 -375.201199) (xy 430.045857 -375.145565)
			(xy 430.06772 -375.1199) (xy 430.073501 -375.112744) (xy 430.080024 -375.095562) (xy 430.08042 -375.086372)
			(xy 430.08042 -374.928638) (xy 430.080957 -374.918516) (xy 430.088669 -374.8998) (xy 430.10294 -374.885443)
			(xy 430.121609 -374.877619) (xy 430.131728 -374.877076) (xy 430.848008 -374.877076) (xy 430.85816 -374.877515)
			(xy 430.876907 -374.885308) (xy 430.89123 -374.899699) (xy 430.898933 -374.918484) (xy 430.899316 -374.928638)
			(xy 430.899316 -375.086372) (xy 430.899736 -375.095558) (xy 430.906242 -375.112743) (xy 430.912016 -375.1199)
			(xy 430.933911 -375.14554) (xy 430.971998 -375.201178) (xy 431.003146 -375.260978) (xy 431.026908 -375.324078)
			(xy 431.04294 -375.38957) (xy 431.051013 -375.456511) (xy 431.051011 -375.523937) (xy 431.042932 -375.590877)
			(xy 431.026893 -375.656368) (xy 431.003126 -375.719466) (xy 430.971973 -375.779263) (xy 430.933881 -375.834898)
			(xy 430.912016 -375.860564) (xy 430.906212 -375.867704) (xy 430.899701 -375.884898) (xy 430.899316 -375.894092)
			(xy 430.899316 -376.386344) (xy 430.899701 -376.395534) (xy 430.906232 -376.412718) (xy 430.912016 -376.419872)
			(xy 430.933883 -376.445534) (xy 430.971971 -376.50117) (xy 431.003121 -376.560966) (xy 431.026884 -376.624064)
			(xy 431.042918 -376.689553) (xy 431.050994 -376.756491) (xy 431.050994 -376.756551) (xy 434.329058 -376.756551)
			(xy 434.337101 -376.689729) (xy 434.353073 -376.624348) (xy 434.376744 -376.561343) (xy 434.407775 -376.50162)
			(xy 434.445721 -376.446033) (xy 434.467508 -376.42038) (xy 434.473296 -376.413229) (xy 434.479816 -376.396043)
			(xy 434.480208 -376.386852) (xy 434.480208 -375.893584) (xy 434.479804 -375.884396) (xy 434.473286 -375.867212)
			(xy 434.467508 -375.860056) (xy 434.445753 -375.834378) (xy 434.407805 -375.778794) (xy 434.376772 -375.719074)
			(xy 434.353099 -375.656073) (xy 434.337124 -375.590694) (xy 434.329078 -375.523875) (xy 434.329075 -375.456573)
			(xy 434.337116 -375.389753) (xy 434.353084 -375.324373) (xy 434.376752 -375.26137) (xy 434.40778 -375.201647)
			(xy 434.445723 -375.146061) (xy 434.467508 -375.120408) (xy 434.473285 -375.113249) (xy 434.479811 -375.096069)
			(xy 434.480208 -375.08688) (xy 434.480208 -374.928638) (xy 434.480694 -374.918473) (xy 434.488461 -374.899684)
			(xy 434.502827 -374.885299) (xy 434.521605 -374.877508) (xy 434.53177 -374.877076) (xy 435.24805 -374.877076)
			(xy 435.258223 -374.877506) (xy 435.277024 -374.885281) (xy 435.291412 -374.899666) (xy 435.299192 -374.918465)
			(xy 435.299612 -374.928638) (xy 435.299612 -375.08688) (xy 435.300029 -375.096067) (xy 435.306538 -375.113251)
			(xy 435.312312 -375.120408) (xy 435.334133 -375.146034) (xy 435.372084 -375.201623) (xy 435.403118 -375.26135)
			(xy 435.426791 -375.324358) (xy 435.442764 -375.389744) (xy 435.450806 -375.45657) (xy 435.450803 -375.523878)
			(xy 435.442755 -375.590704) (xy 435.426777 -375.656088) (xy 435.403099 -375.719094) (xy 435.372059 -375.778819)
			(xy 435.334103 -375.834404) (xy 435.312312 -375.860056) (xy 435.306511 -375.867198) (xy 435.299998 -375.884391)
			(xy 435.299612 -375.893584) (xy 435.299612 -376.386852) (xy 435.300042 -376.396037) (xy 435.306542 -376.413222)
			(xy 435.312312 -376.42038) (xy 435.334105 -376.446028) (xy 435.372057 -376.501614) (xy 435.403093 -376.561338)
			(xy 435.426768 -376.624343) (xy 435.442742 -376.689726) (xy 435.450786 -376.75655) (xy 435.450786 -376.823856)
			(xy 435.442741 -376.89068) (xy 435.426766 -376.956063) (xy 435.40309 -377.019068) (xy 435.372054 -377.078791)
			(xy 435.334101 -377.134376) (xy 435.312312 -377.160028) (xy 435.306522 -377.167178) (xy 435.300003 -377.184365)
			(xy 435.299612 -377.193556) (xy 435.299612 -377.35129) (xy 435.299227 -377.361467) (xy 435.291436 -377.380271)
			(xy 435.277038 -377.394658) (xy 435.258228 -377.402435) (xy 435.24805 -377.402852) (xy 434.53177 -377.402852)
			(xy 434.521609 -377.402391) (xy 434.502837 -377.394605) (xy 434.488473 -377.380229) (xy 434.480701 -377.361451)
			(xy 434.480208 -377.35129) (xy 434.480208 -377.193556) (xy 434.479817 -377.184367) (xy 434.47329 -377.167183)
			(xy 434.467508 -377.160028) (xy 434.445725 -377.134372) (xy 434.407778 -377.078786) (xy 434.376746 -377.019062)
			(xy 434.353075 -376.956058) (xy 434.337103 -376.890677) (xy 434.329059 -376.823855) (xy 434.329058 -376.756551)
			(xy 431.050994 -376.756551) (xy 431.050993 -376.823915) (xy 431.042917 -376.890853) (xy 431.026882 -376.956342)
			(xy 431.003118 -377.019439) (xy 430.971968 -377.079236) (xy 430.93388 -377.13487) (xy 430.912016 -377.160536)
			(xy 430.906223 -377.167684) (xy 430.899706 -377.184872) (xy 430.899316 -377.194064) (xy 430.899316 -377.35129)
			(xy 430.898864 -377.361421) (xy 430.891131 -377.380151) (xy 430.876834 -377.394509) (xy 430.858137 -377.402321)
			(xy 430.848008 -377.402852) (xy 430.131728 -377.402852) (xy 430.121582 -377.402357) (xy 430.10284 -377.39458)
			(xy 430.088518 -377.380207) (xy 430.080808 -377.361437) (xy 430.08042 -377.35129) (xy 430.08042 -377.194064)
			(xy 430.080023 -377.184876) (xy 430.0735 -377.167692) (xy 430.06772 -377.160536) (xy 430.045859 -377.134868)
			(xy 430.007769 -377.079234) (xy 429.976617 -377.019439) (xy 429.952852 -376.956342) (xy 429.936815 -376.890853)
			(xy 429.928739 -376.823915) (xy 426.650691 -376.823915) (xy 426.642653 -376.890679) (xy 426.626679 -376.956062)
			(xy 426.603004 -377.019067) (xy 426.571968 -377.07879) (xy 426.534017 -377.134376) (xy 426.512228 -377.160028)
			(xy 426.506428 -377.167171) (xy 426.499918 -377.184363) (xy 426.499528 -377.193556) (xy 426.499528 -377.35129)
			(xy 426.499127 -377.361465) (xy 426.491339 -377.380266) (xy 426.476946 -377.394653) (xy 426.458141 -377.402432)
			(xy 426.447966 -377.402852) (xy 425.731686 -377.402852) (xy 425.721526 -377.402378) (xy 425.702755 -377.394597)
			(xy 425.68839 -377.380225) (xy 425.680618 -377.36145) (xy 425.680124 -377.35129) (xy 425.680124 -377.193556)
			(xy 425.67973 -377.184367) (xy 425.673204 -377.167183) (xy 425.667424 -377.160028) (xy 425.645641 -377.134372)
			(xy 425.607693 -377.078786) (xy 425.57666 -377.019063) (xy 425.552988 -376.956059) (xy 425.537015 -376.890677)
			(xy 425.528971 -376.823855) (xy 425.52897 -376.756551) (xy 422.250906 -376.756551) (xy 422.250905 -376.823915)
			(xy 422.24283 -376.890853) (xy 422.226795 -376.956342) (xy 422.203032 -377.019438) (xy 422.171882 -377.079235)
			(xy 422.133795 -377.13487) (xy 422.111932 -377.160536) (xy 422.106129 -377.167677) (xy 422.09962 -377.184871)
			(xy 422.099232 -377.194064) (xy 422.099232 -377.35129) (xy 422.098764 -377.36142) (xy 422.091035 -377.380146)
			(xy 422.076742 -377.394503) (xy 422.058051 -377.402318) (xy 422.047924 -377.402852) (xy 421.331644 -377.402852)
			(xy 421.321544 -377.40228) (xy 421.302877 -377.394567) (xy 421.288583 -377.380297) (xy 421.280837 -377.361643)
			(xy 421.280336 -377.351544) (xy 421.280336 -377.194064) (xy 421.279935 -377.184876) (xy 421.273414 -377.167692)
			(xy 421.267636 -377.160536) (xy 421.245775 -377.134868) (xy 421.207684 -377.079235) (xy 421.176531 -377.019439)
			(xy 421.152765 -376.956343) (xy 421.136728 -376.890854) (xy 421.128651 -376.823915) (xy 391.450846 -376.823915)
			(xy 391.442809 -376.890678) (xy 391.426837 -376.956059) (xy 391.403165 -377.019064) (xy 391.372134 -377.078788)
			(xy 391.334187 -377.134375) (xy 391.3124 -377.160028) (xy 391.306609 -377.167177) (xy 391.300091 -377.184365)
			(xy 391.2997 -377.193556) (xy 391.2997 -377.35129) (xy 391.299159 -377.361442) (xy 391.291395 -377.380204)
			(xy 391.277044 -377.394568) (xy 391.25829 -377.40235) (xy 391.248138 -377.402852) (xy 390.531858 -377.402852)
			(xy 390.521696 -377.402401) (xy 390.502924 -377.394611) (xy 390.48856 -377.380232) (xy 390.480789 -377.361452)
			(xy 390.480296 -377.35129) (xy 390.480296 -377.193556) (xy 390.479908 -377.184366) (xy 390.473379 -377.167182)
			(xy 390.467596 -377.160028) (xy 390.445814 -377.134372) (xy 390.407867 -377.078785) (xy 390.376836 -377.019062)
			(xy 390.353165 -376.956058) (xy 390.337193 -376.890676) (xy 390.329149 -376.823855) (xy 387.051084 -376.823855)
			(xy 387.051084 -376.823915) (xy 387.043008 -376.890853) (xy 387.026972 -376.956343) (xy 387.003208 -377.01944)
			(xy 386.972057 -377.079236) (xy 386.933968 -377.134871) (xy 386.912104 -377.160536) (xy 386.90631 -377.167683)
			(xy 386.899794 -377.184872) (xy 386.899404 -377.194064) (xy 386.899404 -377.35129) (xy 386.898867 -377.361411)
			(xy 386.89115 -377.380123) (xy 386.87688 -377.394478) (xy 386.858214 -377.402306) (xy 386.848096 -377.402852)
			(xy 386.131816 -377.402852) (xy 386.121669 -377.402366) (xy 386.102927 -377.394586) (xy 386.088605 -377.380209)
			(xy 386.080896 -377.361438) (xy 386.080508 -377.35129) (xy 386.080508 -377.194064) (xy 386.080114 -377.184875)
			(xy 386.073589 -377.167691) (xy 386.067808 -377.160536) (xy 386.045948 -377.134868) (xy 386.007858 -377.079234)
			(xy 385.976707 -377.019438) (xy 385.952942 -376.956342) (xy 385.936906 -376.890853) (xy 385.92883 -376.823915)
			(xy 382.650782 -376.823915) (xy 382.642744 -376.89068) (xy 382.626769 -376.956063) (xy 382.603094 -377.019068)
			(xy 382.572058 -377.078791) (xy 382.534105 -377.134376) (xy 382.512316 -377.160028) (xy 382.506527 -377.167179)
			(xy 382.500007 -377.184365) (xy 382.499616 -377.193556) (xy 382.499616 -377.35129) (xy 382.499227 -377.361467)
			(xy 382.491437 -377.38027) (xy 382.47704 -377.394657) (xy 382.458231 -377.402434) (xy 382.448054 -377.402852)
			(xy 381.731774 -377.402852) (xy 381.721613 -377.402388) (xy 381.702842 -377.394603) (xy 381.688477 -377.380228)
			(xy 381.680705 -377.361451) (xy 381.680212 -377.35129) (xy 381.680212 -377.193556) (xy 381.67982 -377.184367)
			(xy 381.673294 -377.167183) (xy 381.667512 -377.160028) (xy 381.645729 -377.134372) (xy 381.607782 -377.078786)
			(xy 381.57675 -377.019062) (xy 381.553078 -376.956058) (xy 381.537106 -376.890677) (xy 381.529062 -376.823855)
			(xy 381.529061 -376.756551) (xy 378.250997 -376.756551) (xy 378.250996 -376.823915) (xy 378.24292 -376.890853)
			(xy 378.226885 -376.956342) (xy 378.203121 -377.019439) (xy 378.171971 -377.079235) (xy 378.133884 -377.13487)
			(xy 378.11202 -377.160536) (xy 378.106228 -377.167685) (xy 378.09971 -377.184872) (xy 378.09932 -377.194064)
			(xy 378.09932 -377.35129) (xy 378.098864 -377.361421) (xy 378.091132 -377.38015) (xy 378.076836 -377.394508)
			(xy 378.058141 -377.40232) (xy 378.048012 -377.402852) (xy 377.331732 -377.402852) (xy 377.321586 -377.402353)
			(xy 377.302845 -377.394578) (xy 377.288522 -377.380206) (xy 377.280812 -377.361437) (xy 377.280424 -377.35129)
			(xy 377.280424 -377.194064) (xy 377.280026 -377.184876) (xy 377.273503 -377.167692) (xy 377.267724 -377.160536)
			(xy 377.245863 -377.134868) (xy 377.207773 -377.079234) (xy 377.17662 -377.019439) (xy 377.152855 -376.956342)
			(xy 377.136819 -376.890853) (xy 377.128742 -376.823915) (xy 347.450937 -376.823915) (xy 347.4429 -376.890678)
			(xy 347.426927 -376.95606) (xy 347.403255 -377.019065) (xy 347.372223 -377.078788) (xy 347.334275 -377.134376)
			(xy 347.312488 -377.160028) (xy 347.306696 -377.167176) (xy 347.300179 -377.184364) (xy 347.299788 -377.193556)
			(xy 347.299788 -377.35129) (xy 347.299259 -377.361444) (xy 347.291493 -377.380208) (xy 347.277138 -377.394573)
			(xy 347.25838 -377.402352) (xy 347.248226 -377.402852) (xy 346.531946 -377.402852) (xy 346.521776 -377.402398)
			(xy 346.502981 -377.394627) (xy 346.488594 -377.38025) (xy 346.480809 -377.36146) (xy 346.480384 -377.35129)
			(xy 346.480384 -377.193556) (xy 346.479999 -377.184366) (xy 346.473468 -377.167182) (xy 346.467684 -377.160028)
			(xy 346.445899 -377.134373) (xy 346.407947 -377.078788) (xy 346.376911 -377.019065) (xy 346.353236 -376.956061)
			(xy 346.337262 -376.890679) (xy 346.329216 -376.823856) (xy 343.051175 -376.823856) (xy 343.051175 -376.823915)
			(xy 343.043099 -376.890854) (xy 343.027063 -376.956343) (xy 343.003298 -377.01944) (xy 342.972146 -377.079236)
			(xy 342.934056 -377.134871) (xy 342.912192 -377.160536) (xy 342.906397 -377.167682) (xy 342.899882 -377.184872)
			(xy 342.899492 -377.194064) (xy 342.899492 -377.35129) (xy 342.898966 -377.361412) (xy 342.891248 -377.380127)
			(xy 342.876974 -377.394483) (xy 342.858303 -377.402308) (xy 342.848184 -377.402852) (xy 342.131904 -377.402852)
			(xy 342.121757 -377.402376) (xy 342.103014 -377.394592) (xy 342.088693 -377.380212) (xy 342.080984 -377.361439)
			(xy 342.080596 -377.35129) (xy 342.080596 -377.194064) (xy 342.080204 -377.184875) (xy 342.073678 -377.167691)
			(xy 342.067896 -377.160536) (xy 342.046036 -377.134867) (xy 342.007948 -377.079233) (xy 341.976797 -377.019438)
			(xy 341.953033 -376.956341) (xy 341.936997 -376.890852) (xy 341.928921 -376.823915) (xy 338.650849 -376.823915)
			(xy 338.642812 -376.890677) (xy 338.62684 -376.956059) (xy 338.603168 -377.019064) (xy 338.572137 -377.078788)
			(xy 338.534191 -377.134375) (xy 338.512404 -377.160028) (xy 338.506614 -377.167178) (xy 338.500095 -377.184365)
			(xy 338.499704 -377.193556) (xy 338.499704 -377.35129) (xy 338.49916 -377.361442) (xy 338.491396 -377.380203)
			(xy 338.477047 -377.394567) (xy 338.458293 -377.402349) (xy 338.448142 -377.402852) (xy 337.731862 -377.402852)
			(xy 337.721701 -377.402397) (xy 337.702929 -377.394609) (xy 337.688564 -377.380231) (xy 337.680793 -377.361452)
			(xy 337.6803 -377.35129) (xy 337.6803 -377.193556) (xy 337.679911 -377.184367) (xy 337.673383 -377.167182)
			(xy 337.6676 -377.160028) (xy 337.645817 -377.134372) (xy 337.607871 -377.078785) (xy 337.57684 -377.019062)
			(xy 337.553168 -376.956058) (xy 337.537196 -376.890677) (xy 337.529152 -376.823855) (xy 334.251087 -376.823855)
			(xy 334.251087 -376.823915) (xy 334.243011 -376.890853) (xy 334.226976 -376.956342) (xy 334.203211 -377.019439)
			(xy 334.172061 -377.079236) (xy 334.133972 -377.134871) (xy 334.112108 -377.160536) (xy 334.106315 -377.167684)
			(xy 334.099798 -377.184872) (xy 334.099408 -377.194064) (xy 334.099408 -377.35129) (xy 334.098867 -377.36141)
			(xy 334.091151 -377.380122) (xy 334.076882 -377.394477) (xy 334.058217 -377.402305) (xy 334.0481 -377.402852)
			(xy 333.33182 -377.402852) (xy 333.321674 -377.402363) (xy 333.302932 -377.394584) (xy 333.288609 -377.380209)
			(xy 333.2809 -377.361438) (xy 333.280512 -377.35129) (xy 333.280512 -377.194064) (xy 333.280117 -377.184875)
			(xy 333.273592 -377.167691) (xy 333.267812 -377.160536) (xy 333.245952 -377.134868) (xy 333.207862 -377.079234)
			(xy 333.17671 -377.019438) (xy 333.152945 -376.956342) (xy 333.136909 -376.890853) (xy 333.128833 -376.823915)
			(xy 303.451057 -376.823915) (xy 303.44298 -376.890854) (xy 303.426944 -376.956344) (xy 303.403178 -377.019441)
			(xy 303.372025 -377.079237) (xy 303.333933 -377.134871) (xy 303.312068 -377.160536) (xy 303.30627 -377.16768)
			(xy 303.299757 -377.184871) (xy 303.299368 -377.194064) (xy 303.299368 -377.35129) (xy 303.298865 -377.361415)
			(xy 303.291142 -377.380135) (xy 303.276861 -377.394491) (xy 303.258182 -377.402312) (xy 303.24806 -377.402852)
			(xy 302.53178 -377.402852) (xy 302.521631 -377.402396) (xy 302.502888 -377.394604) (xy 302.488567 -377.380218)
			(xy 302.480859 -377.361441) (xy 302.480472 -377.35129) (xy 302.480472 -377.194064) (xy 302.480085 -377.184874)
			(xy 302.473556 -377.16769) (xy 302.467772 -377.160536) (xy 302.445913 -377.134867) (xy 302.407826 -377.079232)
			(xy 302.376677 -377.019436) (xy 302.352913 -376.95634) (xy 302.336879 -376.890852) (xy 302.328803 -376.823914)
			(xy 302.328802 -376.756492) (xy 299.050731 -376.756492) (xy 299.050738 -376.756551) (xy 299.050738 -376.823856)
			(xy 299.042693 -376.890678) (xy 299.026721 -376.95606) (xy 299.003048 -377.019065) (xy 298.972016 -377.078789)
			(xy 298.934067 -377.134376) (xy 298.91228 -377.160028) (xy 298.906487 -377.167175) (xy 298.899971 -377.184364)
			(xy 298.89958 -377.193556) (xy 298.89958 -377.35129) (xy 298.899059 -377.361445) (xy 298.891291 -377.38021)
			(xy 298.876934 -377.394575) (xy 298.858173 -377.402353) (xy 298.848018 -377.402852) (xy 298.131738 -377.402852)
			(xy 298.121568 -377.402405) (xy 298.102772 -377.39463) (xy 298.088385 -377.380252) (xy 298.080601 -377.36146)
			(xy 298.080176 -377.35129) (xy 298.080176 -377.193556) (xy 298.079792 -377.184366) (xy 298.073261 -377.167182)
			(xy 298.067476 -377.160028) (xy 298.045691 -377.134373) (xy 298.00774 -377.078788) (xy 297.976704 -377.019065)
			(xy 297.95303 -376.956061) (xy 297.937055 -376.890679) (xy 297.92901 -376.823856) (xy 294.650969 -376.823856)
			(xy 294.650969 -376.823915) (xy 294.642893 -376.890854) (xy 294.626856 -376.956343) (xy 294.603091 -377.019441)
			(xy 294.571939 -377.079237) (xy 294.533849 -377.134871) (xy 294.511984 -377.160536) (xy 294.506188 -377.167681)
			(xy 294.499673 -377.184872) (xy 294.499284 -377.194064) (xy 294.499284 -377.35129) (xy 294.498766 -377.361413)
			(xy 294.491046 -377.38013) (xy 294.47677 -377.394485) (xy 294.458096 -377.402309) (xy 294.447976 -377.402852)
			(xy 293.731696 -377.402852) (xy 293.721593 -377.402319) (xy 293.702925 -377.39459) (xy 293.688632 -377.380308)
			(xy 293.680889 -377.361646) (xy 293.680388 -377.351544) (xy 293.680388 -377.194064) (xy 293.679998 -377.184875)
			(xy 293.673471 -377.16769) (xy 293.667688 -377.160536) (xy 293.645828 -377.134867) (xy 293.60774 -377.079233)
			(xy 293.57659 -377.019437) (xy 293.552826 -376.956341) (xy 293.536791 -376.890852) (xy 293.528715 -376.823915)
			(xy 290.250643 -376.823915) (xy 290.242606 -376.890678) (xy 290.226633 -376.95606) (xy 290.202962 -377.019064)
			(xy 290.17193 -377.078788) (xy 290.133983 -377.134375) (xy 290.112196 -377.160028) (xy 290.106405 -377.167177)
			(xy 290.099887 -377.184365) (xy 290.099496 -377.193556) (xy 290.099496 -377.35129) (xy 290.098959 -377.361443)
			(xy 290.091194 -377.380205) (xy 290.076842 -377.39457) (xy 290.058087 -377.402351) (xy 290.047934 -377.402852)
			(xy 289.331654 -377.402852) (xy 289.321492 -377.402404) (xy 289.30272 -377.394613) (xy 289.288356 -377.380233)
			(xy 289.280585 -377.361452) (xy 289.280092 -377.35129) (xy 289.280092 -377.193556) (xy 289.279705 -377.184366)
			(xy 289.273176 -377.167182) (xy 289.267392 -377.160028) (xy 289.245607 -377.134373) (xy 289.207654 -377.078788)
			(xy 289.176618 -377.019066) (xy 289.152942 -376.956061) (xy 289.136968 -376.890679) (xy 289.128922 -376.823856)
			(xy 273.068299 -376.823856) (xy 273.100384 -376.843252) (xy 273.210304 -376.919124) (xy 273.315441 -377.001494)
			(xy 273.415414 -377.090062) (xy 273.509856 -377.184504) (xy 273.598424 -377.284477) (xy 273.680794 -377.389614)
			(xy 273.756666 -377.499534) (xy 273.825762 -377.613833) (xy 273.887832 -377.732096) (xy 273.942647 -377.853891)
			(xy 273.990009 -377.978774) (xy 274.029744 -378.106288) (xy 274.061707 -378.235969) (xy 274.077801 -378.323794)
			(xy 286.928742 -378.323794) (xy 286.928744 -378.256367) (xy 286.936824 -378.189426) (xy 286.952863 -378.123935)
			(xy 286.976633 -378.060837) (xy 287.007789 -378.00104) (xy 287.045885 -377.945406) (xy 287.067752 -377.919742)
			(xy 287.073562 -377.912607) (xy 287.080067 -377.895408) (xy 287.080452 -377.886214) (xy 287.080452 -377.728734)
			(xy 287.080955 -377.718608) (xy 287.088674 -377.699885) (xy 287.102955 -377.685528) (xy 287.121637 -377.677709)
			(xy 287.13176 -377.677172) (xy 287.84804 -377.677172) (xy 287.858148 -377.677652) (xy 287.876822 -377.685397)
			(xy 287.891114 -377.699695) (xy 287.898852 -377.718372) (xy 287.899348 -377.72848) (xy 287.899348 -377.886214)
			(xy 287.899763 -377.8954) (xy 287.906275 -377.912584) (xy 287.912048 -377.919742) (xy 287.933888 -377.945427)
			(xy 287.971981 -378.001058) (xy 288.003136 -378.060851) (xy 288.026904 -378.123945) (xy 288.042943 -378.189432)
			(xy 288.051021 -378.256369) (xy 288.051024 -378.323734) (xy 291.329062 -378.323734) (xy 291.329064 -378.256427)
			(xy 291.337111 -378.189602) (xy 291.353086 -378.124219) (xy 291.376762 -378.061213) (xy 291.407799 -378.001489)
			(xy 291.445751 -377.945902) (xy 291.46754 -377.92025) (xy 291.473345 -377.913111) (xy 291.479854 -377.895916)
			(xy 291.48024 -377.886722) (xy 291.48024 -377.728734) (xy 291.480692 -377.718564) (xy 291.488466 -377.69977)
			(xy 291.502843 -377.685384) (xy 291.521633 -377.677598) (xy 291.531802 -377.677172) (xy 292.248082 -377.677172)
			(xy 292.258257 -377.677579) (xy 292.277058 -377.685365) (xy 292.291444 -377.699756) (xy 292.299224 -377.718559)
			(xy 292.299644 -377.728734) (xy 292.299644 -377.886722) (xy 292.300056 -377.895909) (xy 292.30657 -377.913092)
			(xy 292.312344 -377.92025) (xy 292.334107 -377.945923) (xy 292.372057 -378.001506) (xy 292.403093 -378.061227)
			(xy 292.426768 -378.124228) (xy 292.442743 -378.189608) (xy 292.450789 -378.256429) (xy 292.450792 -378.323732)
			(xy 292.450785 -378.323794) (xy 295.72883 -378.323794) (xy 295.728832 -378.256367) (xy 295.736911 -378.189427)
			(xy 295.752951 -378.123936) (xy 295.776719 -378.060837) (xy 295.807875 -378.001041) (xy 295.845969 -377.945407)
			(xy 295.867836 -377.919742) (xy 295.873644 -377.912605) (xy 295.880151 -377.895408) (xy 295.880536 -377.886214)
			(xy 295.880536 -377.728734) (xy 295.881055 -377.71861) (xy 295.88877 -377.69989) (xy 295.903047 -377.685533)
			(xy 295.921723 -377.677712) (xy 295.931844 -377.677172) (xy 296.648124 -377.677172) (xy 296.658276 -377.677601)
			(xy 296.677024 -377.6854) (xy 296.691345 -377.699793) (xy 296.699049 -377.71858) (xy 296.699432 -377.728734)
			(xy 296.699432 -377.886214) (xy 296.699851 -377.8954) (xy 296.70636 -377.912584) (xy 296.712132 -377.919742)
			(xy 296.733969 -377.945429) (xy 296.772057 -378.001061) (xy 296.803207 -378.060855) (xy 296.826971 -378.123949)
			(xy 296.843007 -378.189435) (xy 296.851085 -378.25637) (xy 296.851087 -378.323791) (xy 296.851087 -378.323794)
			(xy 300.128621 -378.323794) (xy 300.128623 -378.256367) (xy 300.136702 -378.189427) (xy 300.152741 -378.123936)
			(xy 300.176509 -378.060838) (xy 300.207664 -378.001041) (xy 300.245758 -377.945407) (xy 300.267624 -377.919742)
			(xy 300.27343 -377.912604) (xy 300.279938 -377.895408) (xy 300.280324 -377.886214) (xy 300.280324 -377.728734)
			(xy 300.280854 -377.718611) (xy 300.288568 -377.699894) (xy 300.302841 -377.685537) (xy 300.321512 -377.677714)
			(xy 300.331632 -377.677172) (xy 301.047912 -377.677172) (xy 301.058063 -377.677611) (xy 301.076811 -377.685405)
			(xy 301.091133 -377.699796) (xy 301.098837 -377.718581) (xy 301.09922 -377.728734) (xy 301.09922 -377.886214)
			(xy 301.099619 -377.895402) (xy 301.10614 -377.912587) (xy 301.11192 -377.919742) (xy 301.133758 -377.945429)
			(xy 301.171846 -378.001061) (xy 301.202997 -378.060854) (xy 301.226761 -378.123948) (xy 301.242798 -378.189434)
			(xy 301.250876 -378.25637) (xy 301.250878 -378.323734) (xy 330.92918 -378.323734) (xy 330.929182 -378.256427)
			(xy 330.937229 -378.189602) (xy 330.953206 -378.124218) (xy 330.976882 -378.061212) (xy 331.00792 -378.001488)
			(xy 331.045874 -377.945902) (xy 331.067664 -377.92025) (xy 331.073472 -377.913113) (xy 331.079978 -377.895916)
			(xy 331.080364 -377.886722) (xy 331.080364 -377.728734) (xy 331.080792 -377.718561) (xy 331.088571 -377.699763)
			(xy 331.102956 -377.685376) (xy 331.121753 -377.677594) (xy 331.131926 -377.677172) (xy 331.848206 -377.677172)
			(xy 331.858382 -377.67756) (xy 331.877184 -377.685353) (xy 331.891569 -377.69975) (xy 331.899348 -377.718557)
			(xy 331.899768 -377.728734) (xy 331.899768 -377.886722) (xy 331.900175 -377.895909) (xy 331.906692 -377.913093)
			(xy 331.912468 -377.92025) (xy 331.93423 -377.945923) (xy 331.972179 -378.001507) (xy 332.003213 -378.061228)
			(xy 332.026887 -378.124229) (xy 332.042861 -378.189609) (xy 332.050907 -378.256429) (xy 332.05091 -378.323732)
			(xy 332.050903 -378.323793) (xy 335.328973 -378.323793) (xy 335.328975 -378.256368) (xy 335.337053 -378.189429)
			(xy 335.35309 -378.123939) (xy 335.376855 -378.060841) (xy 335.408007 -378.001044) (xy 335.446096 -377.945408)
			(xy 335.46796 -377.919742) (xy 335.473771 -377.912607) (xy 335.480275 -377.895409) (xy 335.48066 -377.886214)
			(xy 335.48066 -377.728734) (xy 335.481155 -377.718607) (xy 335.488875 -377.699883) (xy 335.50316 -377.685525)
			(xy 335.521844 -377.677708) (xy 335.531968 -377.677172) (xy 336.248248 -377.677172) (xy 336.258402 -377.677582)
			(xy 336.27715 -377.685388) (xy 336.29147 -377.699787) (xy 336.299173 -377.718578) (xy 336.299556 -377.728734)
			(xy 336.299556 -377.886214) (xy 336.299969 -377.895401) (xy 336.306482 -377.912585) (xy 336.312256 -377.919742)
			(xy 336.334096 -377.945428) (xy 336.372188 -378.001058) (xy 336.403343 -378.060851) (xy 336.42711 -378.123945)
			(xy 336.443149 -378.189433) (xy 336.451227 -378.256369) (xy 336.45123 -378.323734) (xy 339.729268 -378.323734)
			(xy 339.72927 -378.256427) (xy 339.737317 -378.189602) (xy 339.753293 -378.124218) (xy 339.776969 -378.061213)
			(xy 339.808006 -378.001489) (xy 339.845958 -377.945902) (xy 339.867748 -377.92025) (xy 339.873554 -377.913112)
			(xy 339.880062 -377.895916) (xy 339.880448 -377.886722) (xy 339.880448 -377.728734) (xy 339.880892 -377.718563)
			(xy 339.888668 -377.699768) (xy 339.903047 -377.685381) (xy 339.92184 -377.677597) (xy 339.93201 -377.677172)
			(xy 340.64829 -377.677172) (xy 340.658465 -377.677573) (xy 340.677266 -377.685361) (xy 340.691653 -377.699754)
			(xy 340.699432 -377.718559) (xy 340.699852 -377.728734) (xy 340.699852 -377.886722) (xy 340.700262 -377.895909)
			(xy 340.706777 -377.913093) (xy 340.712552 -377.92025) (xy 340.734314 -377.945923) (xy 340.772264 -378.001506)
			(xy 340.803299 -378.061227) (xy 340.826974 -378.124229) (xy 340.842949 -378.189608) (xy 340.850995 -378.256429)
			(xy 340.850998 -378.323732) (xy 340.850998 -378.323734) (xy 344.129059 -378.323734) (xy 344.129061 -378.256427)
			(xy 344.137108 -378.189603) (xy 344.153083 -378.124219) (xy 344.176759 -378.061213) (xy 344.207795 -378.001489)
			(xy 344.245747 -377.945902) (xy 344.267536 -377.92025) (xy 344.273341 -377.913111) (xy 344.27985 -377.895916)
			(xy 344.280236 -377.886722) (xy 344.280236 -377.728734) (xy 344.280692 -377.718565) (xy 344.288465 -377.699771)
			(xy 344.302841 -377.685385) (xy 344.321629 -377.677599) (xy 344.331798 -377.677172) (xy 345.048078 -377.677172)
			(xy 345.058252 -377.677583) (xy 345.077053 -377.685367) (xy 345.09144 -377.699757) (xy 345.099219 -377.71856)
			(xy 345.09964 -377.728734) (xy 345.09964 -377.886722) (xy 345.100053 -377.895909) (xy 345.106566 -377.913092)
			(xy 345.11234 -377.92025) (xy 345.134103 -377.945923) (xy 345.172054 -378.001506) (xy 345.203089 -378.061226)
			(xy 345.226764 -378.124228) (xy 345.24274 -378.189608) (xy 345.250786 -378.256429) (xy 345.250789 -378.323732)
			(xy 345.250789 -378.323734) (xy 374.929089 -378.323734) (xy 374.929092 -378.256427) (xy 374.937139 -378.189602)
			(xy 374.953116 -378.124218) (xy 374.976793 -378.061212) (xy 375.007831 -378.001488) (xy 375.045786 -377.945902)
			(xy 375.067576 -377.92025) (xy 375.073374 -377.913105) (xy 375.079888 -377.895915) (xy 375.080276 -377.886722)
			(xy 375.080276 -377.728734) (xy 375.080693 -377.71856) (xy 375.088474 -377.699759) (xy 375.102862 -377.685371)
			(xy 375.121664 -377.677592) (xy 375.131838 -377.677172) (xy 375.848118 -377.677172) (xy 375.858295 -377.67755)
			(xy 375.877097 -377.685347) (xy 375.891482 -377.699747) (xy 375.89926 -377.718557) (xy 375.89968 -377.728734)
			(xy 375.89968 -377.886722) (xy 375.900084 -377.89591) (xy 375.906602 -377.913094) (xy 375.91238 -377.92025)
			(xy 375.934142 -377.945923) (xy 375.97209 -378.001507) (xy 376.003123 -378.061228) (xy 376.026797 -378.12423)
			(xy 376.042771 -378.189609) (xy 376.050817 -378.256429) (xy 376.050819 -378.323732) (xy 376.050812 -378.323793)
			(xy 379.328882 -378.323793) (xy 379.328884 -378.256368) (xy 379.336962 -378.189428) (xy 379.352999 -378.123938)
			(xy 379.376765 -378.06084) (xy 379.407917 -378.001043) (xy 379.446007 -377.945408) (xy 379.467872 -377.919742)
			(xy 379.473684 -377.912608) (xy 379.480188 -377.895409) (xy 379.480572 -377.886214) (xy 379.480572 -377.728734)
			(xy 379.481056 -377.718606) (xy 379.488778 -377.699879) (xy 379.503066 -377.685521) (xy 379.521754 -377.677706)
			(xy 379.53188 -377.677172) (xy 380.24816 -377.677172) (xy 380.258308 -377.677654) (xy 380.277054 -377.685431)
			(xy 380.291378 -377.699809) (xy 380.299084 -377.718584) (xy 380.299468 -377.728734) (xy 380.299468 -377.886214)
			(xy 380.299878 -377.895401) (xy 380.306393 -377.912585) (xy 380.312168 -377.919742) (xy 380.334008 -377.945428)
			(xy 380.372099 -378.001059) (xy 380.403253 -378.060852) (xy 380.42702 -378.123946) (xy 380.443058 -378.189433)
			(xy 380.451137 -378.256369) (xy 380.451139 -378.323734) (xy 383.729177 -378.323734) (xy 383.729179 -378.256427)
			(xy 383.737226 -378.189602) (xy 383.753202 -378.124218) (xy 383.776879 -378.061212) (xy 383.807917 -378.001488)
			(xy 383.84587 -377.945902) (xy 383.86766 -377.92025) (xy 383.873468 -377.913113) (xy 383.879974 -377.895916)
			(xy 383.88036 -377.886722) (xy 383.88036 -377.728734) (xy 383.880792 -377.718562) (xy 383.88857 -377.699764)
			(xy 383.902954 -377.685377) (xy 383.92175 -377.677595) (xy 383.931922 -377.677172) (xy 384.648202 -377.677172)
			(xy 384.658378 -377.677563) (xy 384.677179 -377.685355) (xy 384.691565 -377.699751) (xy 384.699344 -377.718558)
			(xy 384.699764 -377.728734) (xy 384.699764 -377.886722) (xy 384.700172 -377.895909) (xy 384.706688 -377.913093)
			(xy 384.712464 -377.92025) (xy 384.734226 -377.945923) (xy 384.772175 -378.001507) (xy 384.803209 -378.061228)
			(xy 384.826884 -378.124229) (xy 384.842858 -378.189609) (xy 384.850904 -378.256429) (xy 384.850907 -378.323732)
			(xy 384.850907 -378.323734) (xy 388.128968 -378.323734) (xy 388.12897 -378.256427) (xy 388.137017 -378.189602)
			(xy 388.152993 -378.124218) (xy 388.176669 -378.061213) (xy 388.207706 -378.001489) (xy 388.245658 -377.945902)
			(xy 388.267448 -377.92025) (xy 388.273254 -377.913112) (xy 388.279762 -377.895916) (xy 388.280148 -377.886722)
			(xy 388.280148 -377.728734) (xy 388.280592 -377.718563) (xy 388.288368 -377.699768) (xy 388.302747 -377.685381)
			(xy 388.32154 -377.677597) (xy 388.33171 -377.677172) (xy 389.04799 -377.677172) (xy 389.058165 -377.677573)
			(xy 389.076966 -377.685361) (xy 389.091353 -377.699754) (xy 389.099132 -377.718559) (xy 389.099552 -377.728734)
			(xy 389.099552 -377.886722) (xy 389.099962 -377.895909) (xy 389.106477 -377.913093) (xy 389.112252 -377.92025)
			(xy 389.134014 -377.945923) (xy 389.171964 -378.001506) (xy 389.202999 -378.061227) (xy 389.226674 -378.124229)
			(xy 389.242649 -378.189608) (xy 389.250695 -378.256429) (xy 389.250698 -378.323732) (xy 389.250698 -378.323734)
			(xy 418.928998 -378.323734) (xy 418.929001 -378.256426) (xy 418.937048 -378.189601) (xy 418.953025 -378.124217)
			(xy 418.976703 -378.061211) (xy 419.007742 -378.001487) (xy 419.045697 -377.945902) (xy 419.067488 -377.92025)
			(xy 419.073287 -377.913106) (xy 419.079801 -377.895915) (xy 419.080188 -377.886722) (xy 419.080188 -377.728734)
			(xy 419.080593 -377.718558) (xy 419.088376 -377.699755) (xy 419.102768 -377.685367) (xy 419.121574 -377.67759)
			(xy 419.13175 -377.677172) (xy 419.84803 -377.677172) (xy 419.858208 -377.67754) (xy 419.87701 -377.685341)
			(xy 419.891395 -377.699744) (xy 419.899173 -377.718556) (xy 419.899592 -377.728734) (xy 419.899592 -377.886722)
			(xy 419.899993 -377.89591) (xy 419.906513 -377.913094) (xy 419.912292 -377.92025) (xy 419.934053 -377.945924)
			(xy 419.972001 -378.001508) (xy 420.003034 -378.061229) (xy 420.026706 -378.12423) (xy 420.04268 -378.189609)
			(xy 420.050726 -378.256429) (xy 420.050728 -378.323732) (xy 420.050721 -378.323793) (xy 423.328791 -378.323793)
			(xy 423.328793 -378.256368) (xy 423.336871 -378.189428) (xy 423.352909 -378.123938) (xy 423.376675 -378.06084)
			(xy 423.407828 -378.001043) (xy 423.445919 -377.945408) (xy 423.467784 -377.919742) (xy 423.473586 -377.9126)
			(xy 423.480098 -377.895407) (xy 423.480484 -377.886214) (xy 423.480484 -377.728734) (xy 423.480956 -377.718604)
			(xy 423.488681 -377.699875) (xy 423.502972 -377.685516) (xy 423.521664 -377.677704) (xy 423.531792 -377.677172)
			(xy 424.248072 -377.677172) (xy 424.258189 -377.677638) (xy 424.276887 -377.685372) (xy 424.291201 -377.699673)
			(xy 424.298953 -377.718363) (xy 424.29938 -377.72848) (xy 424.29938 -377.886214) (xy 424.299788 -377.895401)
			(xy 424.306303 -377.912585) (xy 424.31208 -377.919742) (xy 424.333919 -377.945428) (xy 424.37201 -378.001059)
			(xy 424.403163 -378.060852) (xy 424.426929 -378.123946) (xy 424.442967 -378.189433) (xy 424.451046 -378.256369)
			(xy 424.451048 -378.323734) (xy 427.729086 -378.323734) (xy 427.729089 -378.256427) (xy 427.737136 -378.189602)
			(xy 427.753113 -378.124218) (xy 427.77679 -378.061212) (xy 427.807828 -378.001488) (xy 427.845782 -377.945902)
			(xy 427.867572 -377.92025) (xy 427.873381 -377.913114) (xy 427.879886 -377.895916) (xy 427.880272 -377.886722)
			(xy 427.880272 -377.728734) (xy 427.880693 -377.71856) (xy 427.888473 -377.69976) (xy 427.90286 -377.685373)
			(xy 427.92166 -377.677593) (xy 427.931834 -377.677172) (xy 428.648114 -377.677172) (xy 428.658291 -377.677553)
			(xy 428.677092 -377.685349) (xy 428.691478 -377.699748) (xy 428.699256 -377.718557) (xy 428.699676 -377.728734)
			(xy 428.699676 -377.886722) (xy 428.700081 -377.89591) (xy 428.706599 -377.913094) (xy 428.712376 -377.92025)
			(xy 428.734137 -377.945924) (xy 428.772086 -378.001507) (xy 428.80312 -378.061228) (xy 428.826793 -378.12423)
			(xy 428.842767 -378.189609) (xy 428.850813 -378.256429) (xy 428.850816 -378.323732) (xy 428.850816 -378.323734)
			(xy 432.128877 -378.323734) (xy 432.128879 -378.256427) (xy 432.136926 -378.189602) (xy 432.152902 -378.124218)
			(xy 432.176579 -378.061212) (xy 432.207617 -378.001488) (xy 432.24557 -377.945902) (xy 432.26736 -377.92025)
			(xy 432.273168 -377.913113) (xy 432.279674 -377.895916) (xy 432.28006 -377.886722) (xy 432.28006 -377.728734)
			(xy 432.280492 -377.718562) (xy 432.28827 -377.699764) (xy 432.302654 -377.685377) (xy 432.32145 -377.677595)
			(xy 432.331622 -377.677172) (xy 433.047902 -377.677172) (xy 433.058078 -377.677563) (xy 433.076879 -377.685355)
			(xy 433.091265 -377.699751) (xy 433.099044 -377.718558) (xy 433.099464 -377.728734) (xy 433.099464 -377.886722)
			(xy 433.099872 -377.895909) (xy 433.106388 -377.913093) (xy 433.112164 -377.92025) (xy 433.133926 -377.945923)
			(xy 433.171875 -378.001507) (xy 433.202909 -378.061228) (xy 433.226584 -378.124229) (xy 433.242558 -378.189609)
			(xy 433.250604 -378.256429) (xy 433.250607 -378.323732) (xy 433.242565 -378.390553) (xy 433.226595 -378.455933)
			(xy 433.202925 -378.518937) (xy 433.171895 -378.57866) (xy 433.13395 -378.634246) (xy 433.112164 -378.659898)
			(xy 433.106381 -378.667053) (xy 433.099859 -378.684236) (xy 433.099464 -378.693426) (xy 433.099464 -379.186694)
			(xy 433.099885 -379.19588) (xy 433.106392 -379.213064) (xy 433.112164 -379.220222) (xy 433.133997 -379.245837)
			(xy 433.171944 -379.301429) (xy 433.202975 -379.361158) (xy 433.226645 -379.424167) (xy 433.242615 -379.489554)
			(xy 433.250655 -379.55638) (xy 433.250651 -379.623689) (xy 433.242603 -379.690515) (xy 433.226625 -379.755899)
			(xy 433.202947 -379.818906) (xy 433.171909 -379.878631) (xy 433.133955 -379.934218) (xy 433.112164 -379.95987)
			(xy 433.106351 -379.967003) (xy 433.099847 -379.984203) (xy 433.099464 -379.993398) (xy 433.099464 -380.151386)
			(xy 433.099025 -380.161556) (xy 433.091245 -380.180351) (xy 433.076864 -380.194736) (xy 433.058072 -380.202522)
			(xy 433.047902 -380.202948) (xy 432.331622 -380.202948) (xy 432.32145 -380.202518) (xy 432.302653 -380.194737)
			(xy 432.288267 -380.180353) (xy 432.280484 -380.161558) (xy 432.28006 -380.151386) (xy 432.28006 -379.993398)
			(xy 432.279637 -379.984212) (xy 432.273131 -379.967029) (xy 432.26736 -379.95987) (xy 432.245617 -379.934181)
			(xy 432.207665 -379.8786) (xy 432.176629 -379.818882) (xy 432.152953 -379.755882) (xy 432.136976 -379.690504)
			(xy 432.128928 -379.623685) (xy 432.128924 -379.556384) (xy 432.136964 -379.489564) (xy 432.152932 -379.424184)
			(xy 432.176601 -379.361181) (xy 432.20763 -379.301459) (xy 432.245575 -379.245874) (xy 432.26736 -379.220222)
			(xy 432.27318 -379.213093) (xy 432.279679 -379.19589) (xy 432.28006 -379.186694) (xy 432.28006 -378.693426)
			(xy 432.279624 -378.684242) (xy 432.273127 -378.667058) (xy 432.26736 -378.659898) (xy 432.245546 -378.634267)
			(xy 432.207596 -378.578678) (xy 432.176563 -378.518952) (xy 432.152891 -378.455945) (xy 432.136919 -378.39056)
			(xy 432.128877 -378.323734) (xy 428.850816 -378.323734) (xy 428.842774 -378.390552) (xy 428.826805 -378.455933)
			(xy 428.803136 -378.518936) (xy 428.772106 -378.578659) (xy 428.734161 -378.634245) (xy 428.712376 -378.659898)
			(xy 428.706595 -378.667054) (xy 428.700072 -378.684236) (xy 428.699676 -378.693426) (xy 428.699676 -379.186694)
			(xy 428.700094 -379.19588) (xy 428.706603 -379.213064) (xy 428.712376 -379.220222) (xy 428.734209 -379.245837)
			(xy 428.772155 -379.301429) (xy 428.803185 -379.361158) (xy 428.826855 -379.424167) (xy 428.842824 -379.489554)
			(xy 428.850865 -379.55638) (xy 428.85086 -379.623689) (xy 428.842812 -379.690514) (xy 428.826835 -379.755899)
			(xy 428.803157 -379.818905) (xy 428.772119 -379.87863) (xy 428.734166 -379.934218) (xy 428.712376 -379.95987)
			(xy 428.706564 -379.967004) (xy 428.70006 -379.984203) (xy 428.699676 -379.993398) (xy 428.699676 -380.151386)
			(xy 428.699156 -380.161541) (xy 428.691388 -380.180307) (xy 428.677031 -380.194673) (xy 428.658269 -380.20245)
			(xy 428.648114 -380.202948) (xy 427.931834 -380.202948) (xy 427.921663 -380.202508) (xy 427.902866 -380.194731)
			(xy 427.88848 -380.180351) (xy 427.880696 -380.161557) (xy 427.880272 -380.151386) (xy 427.880272 -379.993398)
			(xy 427.879869 -379.98421) (xy 427.873351 -379.967025) (xy 427.867572 -379.95987) (xy 427.845829 -379.934181)
			(xy 427.807876 -379.878601) (xy 427.776839 -379.818882) (xy 427.753162 -379.755883) (xy 427.737185 -379.690505)
			(xy 427.729137 -379.623686) (xy 427.729133 -379.556384) (xy 427.737173 -379.489564) (xy 427.753142 -379.424183)
			(xy 427.776811 -379.361181) (xy 427.807841 -379.301459) (xy 427.845786 -379.245874) (xy 427.867572 -379.220222)
			(xy 427.873393 -379.213094) (xy 427.879891 -379.19589) (xy 427.880272 -379.186694) (xy 427.880272 -378.693426)
			(xy 427.879856 -378.684239) (xy 427.873347 -378.667055) (xy 427.867572 -378.659898) (xy 427.845758 -378.634267)
			(xy 427.807808 -378.578678) (xy 427.776774 -378.518952) (xy 427.753101 -378.455945) (xy 427.737129 -378.39056)
			(xy 427.729086 -378.323734) (xy 424.451048 -378.323734) (xy 424.451048 -378.323791) (xy 424.442974 -378.390728)
			(xy 424.426941 -378.456216) (xy 424.403179 -378.519312) (xy 424.37203 -378.579107) (xy 424.333943 -378.634741)
			(xy 424.31208 -378.660406) (xy 424.306296 -378.66756) (xy 424.299775 -378.684744) (xy 424.29938 -378.693934)
			(xy 424.29938 -379.186186) (xy 424.299802 -379.195372) (xy 424.306308 -379.212556) (xy 424.31208 -379.219714)
			(xy 424.33399 -379.245342) (xy 424.372079 -379.300981) (xy 424.403228 -379.360782) (xy 424.426991 -379.423884)
			(xy 424.443024 -379.489378) (xy 424.451096 -379.556321) (xy 424.451092 -379.623748) (xy 424.443011 -379.69069)
			(xy 424.42697 -379.756182) (xy 424.4032 -379.819281) (xy 424.372043 -379.879078) (xy 424.333947 -379.934713)
			(xy 424.31208 -379.960378) (xy 424.306266 -379.96751) (xy 424.299762 -379.984711) (xy 424.29938 -379.993906)
			(xy 424.29938 -380.151386) (xy 424.298863 -380.161509) (xy 424.291143 -380.180226) (xy 424.276866 -380.194583)
			(xy 424.258193 -380.202406) (xy 424.248072 -380.202948) (xy 423.531792 -380.202948) (xy 423.521689 -380.202422)
			(xy 423.50302 -380.194691) (xy 423.488727 -380.180407) (xy 423.480984 -380.161743) (xy 423.480484 -380.15164)
			(xy 423.480484 -379.993906) (xy 423.480075 -379.984719) (xy 423.473561 -379.967534) (xy 423.467784 -379.960378)
			(xy 423.445966 -379.934675) (xy 423.407877 -379.879046) (xy 423.376725 -379.819255) (xy 423.352959 -379.756163)
			(xy 423.336921 -379.690678) (xy 423.328841 -379.623744) (xy 423.328837 -379.556325) (xy 423.336908 -379.48939)
			(xy 423.352938 -379.423904) (xy 423.376697 -379.360809) (xy 423.407841 -379.301014) (xy 423.445923 -379.245379)
			(xy 423.467784 -379.219714) (xy 423.473598 -379.212581) (xy 423.480103 -379.195381) (xy 423.480484 -379.186186)
			(xy 423.480484 -378.693934) (xy 423.480061 -378.684748) (xy 423.473557 -378.667563) (xy 423.467784 -378.660406)
			(xy 423.445895 -378.634762) (xy 423.407808 -378.579124) (xy 423.376659 -378.519324) (xy 423.352897 -378.456225)
			(xy 423.336864 -378.390733) (xy 423.328791 -378.323793) (xy 420.050721 -378.323793) (xy 420.042687 -378.390552)
			(xy 420.026718 -378.455932) (xy 420.003049 -378.518936) (xy 419.972021 -378.578659) (xy 419.934077 -378.634245)
			(xy 419.912292 -378.659898) (xy 419.906513 -378.667056) (xy 419.899988 -378.684237) (xy 419.899592 -378.693426)
			(xy 419.899592 -379.186694) (xy 419.900007 -379.195881) (xy 419.906518 -379.213065) (xy 419.912292 -379.220222)
			(xy 419.934124 -379.245837) (xy 419.972069 -379.30143) (xy 420.003099 -379.361159) (xy 420.026768 -379.424168)
			(xy 420.042737 -379.489554) (xy 420.050777 -379.556381) (xy 420.050772 -379.623689) (xy 420.042724 -379.690514)
			(xy 420.026747 -379.755898) (xy 420.003071 -379.818905) (xy 419.972034 -379.87863) (xy 419.934082 -379.934217)
			(xy 419.912292 -379.95987) (xy 419.906482 -379.967006) (xy 419.899976 -379.984204) (xy 419.899592 -379.993398)
			(xy 419.899592 -380.151386) (xy 419.899056 -380.161539) (xy 419.891292 -380.180302) (xy 419.876939 -380.194667)
			(xy 419.858183 -380.202447) (xy 419.84803 -380.202948) (xy 419.13175 -380.202948) (xy 419.12158 -380.202495)
			(xy 419.102784 -380.194724) (xy 419.088396 -380.180347) (xy 419.080612 -380.161556) (xy 419.080188 -380.151386)
			(xy 419.080188 -379.993398) (xy 419.079781 -379.98421) (xy 419.073266 -379.967026) (xy 419.067488 -379.95987)
			(xy 419.045744 -379.934181) (xy 419.007791 -379.878601) (xy 418.976753 -379.818883) (xy 418.953075 -379.755883)
			(xy 418.937097 -379.690505) (xy 418.929049 -379.623686) (xy 418.929045 -379.556383) (xy 418.937085 -379.489563)
			(xy 418.953055 -379.424183) (xy 418.976724 -379.36118) (xy 419.007755 -379.301458) (xy 419.045702 -379.245873)
			(xy 419.067488 -379.220222) (xy 419.073299 -379.213087) (xy 419.079805 -379.195889) (xy 419.080188 -379.186694)
			(xy 419.080188 -378.693426) (xy 419.079768 -378.68424) (xy 419.073262 -378.667055) (xy 419.067488 -378.659898)
			(xy 419.045673 -378.634268) (xy 419.007722 -378.578679) (xy 418.976687 -378.518953) (xy 418.953014 -378.455946)
			(xy 418.937041 -378.39056) (xy 418.928998 -378.323734) (xy 389.250698 -378.323734) (xy 389.242656 -378.390553)
			(xy 389.226686 -378.455934) (xy 389.203015 -378.518937) (xy 389.171985 -378.57866) (xy 389.134038 -378.634246)
			(xy 389.112252 -378.659898) (xy 389.106468 -378.667052) (xy 389.099947 -378.684236) (xy 389.099552 -378.693426)
			(xy 389.099552 -379.186694) (xy 389.099976 -379.19588) (xy 389.106481 -379.213063) (xy 389.112252 -379.220222)
			(xy 389.134085 -379.245837) (xy 389.172033 -379.301428) (xy 389.203065 -379.361157) (xy 389.226736 -379.424166)
			(xy 389.242706 -379.489553) (xy 389.250746 -379.55638) (xy 389.250742 -379.623689) (xy 389.242693 -379.690515)
			(xy 389.226715 -379.7559) (xy 389.203037 -379.818906) (xy 389.171998 -379.878631) (xy 389.134043 -379.934218)
			(xy 389.112252 -379.95987) (xy 389.106437 -379.967002) (xy 389.099935 -379.984203) (xy 389.099552 -379.993398)
			(xy 389.099552 -380.151386) (xy 389.099125 -380.161558) (xy 389.091342 -380.180354) (xy 389.076958 -380.19474)
			(xy 389.058162 -380.202524) (xy 389.04799 -380.202948) (xy 388.33171 -380.202948) (xy 388.321537 -380.202528)
			(xy 388.30274 -380.194743) (xy 388.288354 -380.180357) (xy 388.280571 -380.161559) (xy 388.280148 -380.151386)
			(xy 388.280148 -379.993398) (xy 388.279728 -379.984212) (xy 388.27322 -379.967028) (xy 388.267448 -379.95987)
			(xy 388.245705 -379.934181) (xy 388.207755 -379.8786) (xy 388.176719 -379.818881) (xy 388.153043 -379.755882)
			(xy 388.137067 -379.690504) (xy 388.129019 -379.623685) (xy 388.129015 -379.556384) (xy 388.137054 -379.489564)
			(xy 388.153023 -379.424184) (xy 388.176691 -379.361182) (xy 388.207719 -379.30146) (xy 388.245663 -379.245874)
			(xy 388.267448 -379.220222) (xy 388.273266 -379.213092) (xy 388.279767 -379.19589) (xy 388.280148 -379.186694)
			(xy 388.280148 -378.693426) (xy 388.279715 -378.684241) (xy 388.273216 -378.667057) (xy 388.267448 -378.659898)
			(xy 388.245634 -378.634267) (xy 388.207686 -378.578678) (xy 388.176653 -378.518951) (xy 388.152981 -378.455944)
			(xy 388.13701 -378.390559) (xy 388.128968 -378.323734) (xy 384.850907 -378.323734) (xy 384.842865 -378.390553)
			(xy 384.826895 -378.455933) (xy 384.803225 -378.518937) (xy 384.772195 -378.57866) (xy 384.73425 -378.634246)
			(xy 384.712464 -378.659898) (xy 384.706681 -378.667053) (xy 384.700159 -378.684236) (xy 384.699764 -378.693426)
			(xy 384.699764 -379.186694) (xy 384.700185 -379.19588) (xy 384.706692 -379.213064) (xy 384.712464 -379.220222)
			(xy 384.734297 -379.245837) (xy 384.772244 -379.301429) (xy 384.803275 -379.361158) (xy 384.826945 -379.424167)
			(xy 384.842915 -379.489554) (xy 384.850955 -379.55638) (xy 384.850951 -379.623689) (xy 384.842903 -379.690515)
			(xy 384.826925 -379.755899) (xy 384.803247 -379.818906) (xy 384.772209 -379.878631) (xy 384.734255 -379.934218)
			(xy 384.712464 -379.95987) (xy 384.706651 -379.967003) (xy 384.700147 -379.984203) (xy 384.699764 -379.993398)
			(xy 384.699764 -380.151386) (xy 384.699325 -380.161556) (xy 384.691545 -380.180351) (xy 384.677164 -380.194736)
			(xy 384.658372 -380.202522) (xy 384.648202 -380.202948) (xy 383.931922 -380.202948) (xy 383.92175 -380.202518)
			(xy 383.902953 -380.194737) (xy 383.888567 -380.180353) (xy 383.880784 -380.161558) (xy 383.88036 -380.151386)
			(xy 383.88036 -379.993398) (xy 383.879937 -379.984212) (xy 383.873431 -379.967029) (xy 383.86766 -379.95987)
			(xy 383.845917 -379.934181) (xy 383.807965 -379.8786) (xy 383.776929 -379.818882) (xy 383.753253 -379.755882)
			(xy 383.737276 -379.690504) (xy 383.729228 -379.623685) (xy 383.729224 -379.556384) (xy 383.737264 -379.489564)
			(xy 383.753232 -379.424184) (xy 383.776901 -379.361181) (xy 383.80793 -379.301459) (xy 383.845875 -379.245874)
			(xy 383.86766 -379.220222) (xy 383.87348 -379.213093) (xy 383.879979 -379.19589) (xy 383.88036 -379.186694)
			(xy 383.88036 -378.693426) (xy 383.879924 -378.684242) (xy 383.873427 -378.667058) (xy 383.86766 -378.659898)
			(xy 383.845846 -378.634267) (xy 383.807896 -378.578678) (xy 383.776863 -378.518952) (xy 383.753191 -378.455945)
			(xy 383.737219 -378.39056) (xy 383.729177 -378.323734) (xy 380.451139 -378.323734) (xy 380.451139 -378.323792)
			(xy 380.443065 -378.390729) (xy 380.427031 -378.456217) (xy 380.403269 -378.519313) (xy 380.372119 -378.579108)
			(xy 380.334032 -378.634741) (xy 380.312168 -378.660406) (xy 380.306382 -378.667559) (xy 380.299862 -378.684744)
			(xy 380.299468 -378.693934) (xy 380.299468 -379.186186) (xy 380.299892 -379.195372) (xy 380.306397 -379.212556)
			(xy 380.312168 -379.219714) (xy 380.334078 -379.245341) (xy 380.372168 -379.300981) (xy 380.403318 -379.360782)
			(xy 380.427081 -379.423884) (xy 380.443114 -379.489378) (xy 380.451187 -379.556321) (xy 380.451183 -379.623749)
			(xy 380.443102 -379.69069) (xy 380.427061 -379.756182) (xy 380.40329 -379.819281) (xy 380.372132 -379.879079)
			(xy 380.334036 -379.934713) (xy 380.312168 -379.960378) (xy 380.306352 -379.967509) (xy 380.29985 -379.984711)
			(xy 380.299468 -379.993906) (xy 380.299468 -380.151386) (xy 380.298962 -380.161511) (xy 380.291241 -380.18023)
			(xy 380.27696 -380.194587) (xy 380.258282 -380.202408) (xy 380.24816 -380.202948) (xy 379.53188 -380.202948)
			(xy 379.521731 -380.202496) (xy 379.502987 -380.194703) (xy 379.488666 -380.180316) (xy 379.480958 -380.161537)
			(xy 379.480572 -380.151386) (xy 379.480572 -379.993906) (xy 379.480165 -379.984718) (xy 379.47365 -379.967534)
			(xy 379.467872 -379.960378) (xy 379.446054 -379.934675) (xy 379.407966 -379.879045) (xy 379.376815 -379.819254)
			(xy 379.353049 -379.756162) (xy 379.337011 -379.690678) (xy 379.328932 -379.623744) (xy 379.328928 -379.556325)
			(xy 379.336999 -379.48939) (xy 379.353029 -379.423904) (xy 379.376787 -379.360809) (xy 379.40793 -379.301014)
			(xy 379.446012 -379.24538) (xy 379.467872 -379.219714) (xy 379.473696 -379.212589) (xy 379.480192 -379.195383)
			(xy 379.480572 -379.186186) (xy 379.480572 -378.693934) (xy 379.480152 -378.684748) (xy 379.473646 -378.667563)
			(xy 379.467872 -378.660406) (xy 379.445983 -378.634761) (xy 379.407897 -378.579123) (xy 379.376749 -378.519324)
			(xy 379.352988 -378.456224) (xy 379.336955 -378.390733) (xy 379.328882 -378.323793) (xy 376.050812 -378.323793)
			(xy 376.042778 -378.390552) (xy 376.026808 -378.455933) (xy 376.003139 -378.518936) (xy 375.97211 -378.578659)
			(xy 375.934166 -378.634246) (xy 375.91238 -378.659898) (xy 375.906599 -378.667054) (xy 375.900076 -378.684236)
			(xy 375.89968 -378.693426) (xy 375.89968 -379.186694) (xy 375.900098 -379.19588) (xy 375.906607 -379.213064)
			(xy 375.91238 -379.220222) (xy 375.934212 -379.245837) (xy 375.972159 -379.301429) (xy 376.003189 -379.361158)
			(xy 376.026858 -379.424168) (xy 376.042827 -379.489554) (xy 376.050868 -379.55638) (xy 376.050863 -379.623689)
			(xy 376.042815 -379.690514) (xy 376.026838 -379.755899) (xy 376.003161 -379.818905) (xy 375.972123 -379.87863)
			(xy 375.93417 -379.934218) (xy 375.91238 -379.95987) (xy 375.906569 -379.967005) (xy 375.900064 -379.984203)
			(xy 375.89968 -379.993398) (xy 375.89968 -380.151386) (xy 375.899156 -380.161541) (xy 375.891389 -380.180306)
			(xy 375.877033 -380.194671) (xy 375.858272 -380.202449) (xy 375.848118 -380.202948) (xy 375.131838 -380.202948)
			(xy 375.121667 -380.202505) (xy 375.102871 -380.19473) (xy 375.088484 -380.18035) (xy 375.0807 -380.161557)
			(xy 375.080276 -380.151386) (xy 375.080276 -379.993398) (xy 375.079872 -379.98421) (xy 375.073355 -379.967025)
			(xy 375.067576 -379.95987) (xy 375.045832 -379.934181) (xy 375.00788 -379.878601) (xy 374.976842 -379.818883)
			(xy 374.953165 -379.755883) (xy 374.937188 -379.690505) (xy 374.92914 -379.623686) (xy 374.929136 -379.556384)
			(xy 374.937176 -379.489563) (xy 374.953145 -379.424183) (xy 374.976814 -379.361181) (xy 375.007844 -379.301459)
			(xy 375.04579 -379.245874) (xy 375.067576 -379.220222) (xy 375.073385 -379.213086) (xy 375.079893 -379.195889)
			(xy 375.080276 -379.186694) (xy 375.080276 -378.693426) (xy 375.079859 -378.684239) (xy 375.073351 -378.667055)
			(xy 375.067576 -378.659898) (xy 375.045762 -378.634267) (xy 375.007811 -378.578679) (xy 374.976777 -378.518952)
			(xy 374.953104 -378.455945) (xy 374.937132 -378.39056) (xy 374.929089 -378.323734) (xy 345.250789 -378.323734)
			(xy 345.242747 -378.390553) (xy 345.226776 -378.455934) (xy 345.203105 -378.518938) (xy 345.172074 -378.57866)
			(xy 345.134127 -378.634246) (xy 345.11234 -378.659898) (xy 345.106554 -378.667051) (xy 345.100035 -378.684236)
			(xy 345.09964 -378.693426) (xy 345.09964 -379.186694) (xy 345.100066 -379.195879) (xy 345.10657 -379.213063)
			(xy 345.11234 -379.220222) (xy 345.134174 -379.245837) (xy 345.172123 -379.301428) (xy 345.203155 -379.361156)
			(xy 345.226826 -379.424166) (xy 345.242797 -379.489553) (xy 345.250837 -379.55638) (xy 345.250833 -379.623689)
			(xy 345.242784 -379.690515) (xy 345.226806 -379.7559) (xy 345.203127 -379.818907) (xy 345.172087 -379.878632)
			(xy 345.134131 -379.934218) (xy 345.11234 -379.95987) (xy 345.106524 -379.967001) (xy 345.100023 -379.984203)
			(xy 345.09964 -379.993398) (xy 345.09964 -380.151386) (xy 345.099224 -380.161559) (xy 345.09144 -380.180358)
			(xy 345.077051 -380.194744) (xy 345.058252 -380.202526) (xy 345.048078 -380.202948) (xy 344.331798 -380.202948)
			(xy 344.321625 -380.202537) (xy 344.302827 -380.194749) (xy 344.288442 -380.180359) (xy 344.280659 -380.16156)
			(xy 344.280236 -380.151386) (xy 344.280236 -379.993398) (xy 344.279819 -379.984212) (xy 344.273309 -379.967028)
			(xy 344.267536 -379.95987) (xy 344.245794 -379.93418) (xy 344.207844 -379.878599) (xy 344.176809 -379.818881)
			(xy 344.153133 -379.755881) (xy 344.137157 -379.690504) (xy 344.12911 -379.623685) (xy 344.129106 -379.556384)
			(xy 344.137145 -379.489565) (xy 344.153113 -379.424185) (xy 344.17678 -379.361182) (xy 344.207808 -379.30146)
			(xy 344.245751 -379.245874) (xy 344.267536 -379.220222) (xy 344.273353 -379.213091) (xy 344.279855 -379.19589)
			(xy 344.280236 -379.186694) (xy 344.280236 -378.693426) (xy 344.279805 -378.684241) (xy 344.273305 -378.667057)
			(xy 344.267536 -378.659898) (xy 344.245723 -378.634267) (xy 344.207775 -378.578677) (xy 344.176743 -378.518951)
			(xy 344.153072 -378.455944) (xy 344.137101 -378.390559) (xy 344.129059 -378.323734) (xy 340.850998 -378.323734)
			(xy 340.842956 -378.390553) (xy 340.826986 -378.455934) (xy 340.803315 -378.518937) (xy 340.772285 -378.57866)
			(xy 340.734338 -378.634246) (xy 340.712552 -378.659898) (xy 340.706768 -378.667052) (xy 340.700247 -378.684236)
			(xy 340.699852 -378.693426) (xy 340.699852 -379.186694) (xy 340.700276 -379.19588) (xy 340.706781 -379.213063)
			(xy 340.712552 -379.220222) (xy 340.734385 -379.245837) (xy 340.772333 -379.301428) (xy 340.803365 -379.361157)
			(xy 340.827036 -379.424166) (xy 340.843006 -379.489553) (xy 340.851046 -379.55638) (xy 340.851042 -379.623689)
			(xy 340.842993 -379.690515) (xy 340.827015 -379.7559) (xy 340.803337 -379.818906) (xy 340.772298 -379.878631)
			(xy 340.734343 -379.934218) (xy 340.712552 -379.95987) (xy 340.706737 -379.967002) (xy 340.700235 -379.984203)
			(xy 340.699852 -379.993398) (xy 340.699852 -380.151386) (xy 340.699425 -380.161558) (xy 340.691642 -380.180354)
			(xy 340.677258 -380.19474) (xy 340.658462 -380.202524) (xy 340.64829 -380.202948) (xy 339.93201 -380.202948)
			(xy 339.921837 -380.202528) (xy 339.90304 -380.194743) (xy 339.888654 -380.180357) (xy 339.880871 -380.161559)
			(xy 339.880448 -380.151386) (xy 339.880448 -379.993398) (xy 339.880028 -379.984212) (xy 339.87352 -379.967028)
			(xy 339.867748 -379.95987) (xy 339.846005 -379.934181) (xy 339.808055 -379.8786) (xy 339.777019 -379.818881)
			(xy 339.753343 -379.755882) (xy 339.737367 -379.690504) (xy 339.729319 -379.623685) (xy 339.729315 -379.556384)
			(xy 339.737354 -379.489564) (xy 339.753323 -379.424184) (xy 339.776991 -379.361182) (xy 339.808019 -379.30146)
			(xy 339.845963 -379.245874) (xy 339.867748 -379.220222) (xy 339.873566 -379.213092) (xy 339.880067 -379.19589)
			(xy 339.880448 -379.186694) (xy 339.880448 -378.693426) (xy 339.880015 -378.684241) (xy 339.873516 -378.667057)
			(xy 339.867748 -378.659898) (xy 339.845934 -378.634267) (xy 339.807986 -378.578678) (xy 339.776953 -378.518951)
			(xy 339.753281 -378.455944) (xy 339.73731 -378.390559) (xy 339.729268 -378.323734) (xy 336.45123 -378.323734)
			(xy 336.45123 -378.323792) (xy 336.443156 -378.390729) (xy 336.427122 -378.456217) (xy 336.403359 -378.519313)
			(xy 336.372208 -378.579108) (xy 336.33412 -378.634742) (xy 336.312256 -378.660406) (xy 336.306469 -378.667558)
			(xy 336.29995 -378.684743) (xy 336.299556 -378.693934) (xy 336.299556 -379.186186) (xy 336.299983 -379.195371)
			(xy 336.306486 -379.212555) (xy 336.312256 -379.219714) (xy 336.334167 -379.245341) (xy 336.372257 -379.30098)
			(xy 336.403408 -379.360781) (xy 336.427172 -379.423883) (xy 336.443205 -379.489377) (xy 336.451278 -379.55632)
			(xy 336.451274 -379.623749) (xy 336.443193 -379.690691) (xy 336.427151 -379.756183) (xy 336.40338 -379.819282)
			(xy 336.372221 -379.879079) (xy 336.334124 -379.934713) (xy 336.312256 -379.960378) (xy 336.306438 -379.967508)
			(xy 336.299937 -379.98471) (xy 336.299556 -379.993906) (xy 336.299556 -380.151386) (xy 336.299062 -380.161512)
			(xy 336.291338 -380.180234) (xy 336.277054 -380.194591) (xy 336.258372 -380.20241) (xy 336.248248 -380.202948)
			(xy 335.531968 -380.202948) (xy 335.521818 -380.202506) (xy 335.503074 -380.194708) (xy 335.488753 -380.180319)
			(xy 335.481046 -380.161538) (xy 335.48066 -380.151386) (xy 335.48066 -379.993906) (xy 335.480234 -379.984721)
			(xy 335.47373 -379.967537) (xy 335.46796 -379.960378) (xy 335.446143 -379.934675) (xy 335.408055 -379.879045)
			(xy 335.376905 -379.819253) (xy 335.35314 -379.756162) (xy 335.337102 -379.690678) (xy 335.329023 -379.623744)
			(xy 335.329019 -379.556325) (xy 335.33709 -379.48939) (xy 335.353119 -379.423904) (xy 335.376876 -379.36081)
			(xy 335.40802 -379.301015) (xy 335.4461 -379.24538) (xy 335.46796 -379.219714) (xy 335.473783 -379.212588)
			(xy 335.48028 -379.195382) (xy 335.48066 -379.186186) (xy 335.48066 -378.693934) (xy 335.48022 -378.68475)
			(xy 335.473726 -378.667566) (xy 335.46796 -378.660406) (xy 335.446072 -378.634761) (xy 335.407987 -378.579123)
			(xy 335.376839 -378.519323) (xy 335.353078 -378.456224) (xy 335.337046 -378.390733) (xy 335.328973 -378.323793)
			(xy 332.050903 -378.323793) (xy 332.042868 -378.390553) (xy 332.026898 -378.455933) (xy 332.003229 -378.518937)
			(xy 331.972199 -378.578659) (xy 331.934254 -378.634246) (xy 331.912468 -378.659898) (xy 331.906686 -378.667053)
			(xy 331.900163 -378.684236) (xy 331.899768 -378.693426) (xy 331.899768 -379.186694) (xy 331.900188 -379.19588)
			(xy 331.906696 -379.213064) (xy 331.912468 -379.220222) (xy 331.934301 -379.245837) (xy 331.972248 -379.301429)
			(xy 332.003279 -379.361158) (xy 332.026949 -379.424167) (xy 332.042918 -379.489554) (xy 332.050958 -379.55638)
			(xy 332.050954 -379.623689) (xy 332.042906 -379.690514) (xy 332.026928 -379.755899) (xy 332.00325 -379.818906)
			(xy 331.972212 -379.878631) (xy 331.934258 -379.934218) (xy 331.912468 -379.95987) (xy 331.906655 -379.967003)
			(xy 331.900151 -379.984203) (xy 331.899768 -379.993398) (xy 331.899768 -380.151386) (xy 331.899325 -380.161556)
			(xy 331.891546 -380.180349) (xy 331.877166 -380.194734) (xy 331.858376 -380.202521) (xy 331.848206 -380.202948)
			(xy 331.131926 -380.202948) (xy 331.121754 -380.202514) (xy 331.102958 -380.194735) (xy 331.088571 -380.180352)
			(xy 331.080788 -380.161558) (xy 331.080364 -380.151386) (xy 331.080364 -379.993398) (xy 331.07994 -379.984213)
			(xy 331.073434 -379.967029) (xy 331.067664 -379.95987) (xy 331.045921 -379.934181) (xy 331.007969 -379.8786)
			(xy 330.976932 -379.818882) (xy 330.953256 -379.755882) (xy 330.937279 -379.690504) (xy 330.929231 -379.623686)
			(xy 330.929227 -379.556384) (xy 330.937267 -379.489564) (xy 330.953235 -379.424184) (xy 330.976904 -379.361181)
			(xy 331.007933 -379.301459) (xy 331.045878 -379.245874) (xy 331.067664 -379.220222) (xy 331.073484 -379.213094)
			(xy 331.079983 -379.19589) (xy 331.080364 -379.186694) (xy 331.080364 -378.693426) (xy 331.079927 -378.684242)
			(xy 331.07343 -378.667058) (xy 331.067664 -378.659898) (xy 331.04585 -378.634267) (xy 331.0079 -378.578678)
			(xy 330.976866 -378.518952) (xy 330.953194 -378.455945) (xy 330.937222 -378.39056) (xy 330.92918 -378.323734)
			(xy 301.250878 -378.323734) (xy 301.250878 -378.323791) (xy 301.242805 -378.390727) (xy 301.226773 -378.456215)
			(xy 301.203013 -378.51931) (xy 301.171866 -378.579106) (xy 301.133782 -378.63474) (xy 301.11192 -378.660406)
			(xy 301.106141 -378.667564) (xy 301.099615 -378.684745) (xy 301.09922 -378.693934) (xy 301.09922 -379.186186)
			(xy 301.099632 -379.195373) (xy 301.106144 -379.212558) (xy 301.11192 -379.219714) (xy 301.133828 -379.245342)
			(xy 301.171914 -379.300983) (xy 301.203062 -379.360784) (xy 301.226823 -379.423886) (xy 301.242854 -379.489379)
			(xy 301.250926 -379.556321) (xy 301.250922 -379.623748) (xy 301.242842 -379.690689) (xy 301.226802 -379.75618)
			(xy 301.203034 -379.819279) (xy 301.171879 -379.879077) (xy 301.133786 -379.934712) (xy 301.11192 -379.960378)
			(xy 301.10611 -379.967514) (xy 301.099603 -379.984711) (xy 301.09922 -379.993906) (xy 301.09922 -380.151386)
			(xy 301.098761 -380.161517) (xy 301.09103 -380.180245) (xy 301.076735 -380.194603) (xy 301.058041 -380.202416)
			(xy 301.047912 -380.202948) (xy 300.331632 -380.202948) (xy 300.321486 -380.202453) (xy 300.302743 -380.194677)
			(xy 300.28842 -380.180304) (xy 300.280711 -380.161534) (xy 300.280324 -380.151386) (xy 300.280324 -379.993906)
			(xy 300.279906 -379.98472) (xy 300.273397 -379.967536) (xy 300.267624 -379.960378) (xy 300.245804 -379.934676)
			(xy 300.207713 -379.879047) (xy 300.176559 -379.819256) (xy 300.152791 -379.756164) (xy 300.136751 -379.690679)
			(xy 300.128672 -379.623745) (xy 300.128667 -379.556324) (xy 300.136739 -379.489389) (xy 300.15277 -379.423902)
			(xy 300.17653 -379.360807) (xy 300.207677 -379.301012) (xy 300.245762 -379.245379) (xy 300.267624 -379.219714)
			(xy 300.273442 -379.212584) (xy 300.279943 -379.195382) (xy 300.280324 -379.186186) (xy 300.280324 -378.693934)
			(xy 300.279892 -378.684749) (xy 300.273393 -378.667565) (xy 300.267624 -378.660406) (xy 300.245734 -378.634762)
			(xy 300.207644 -378.579125) (xy 300.176493 -378.519326) (xy 300.152729 -378.456227) (xy 300.136695 -378.390735)
			(xy 300.128621 -378.323794) (xy 296.851087 -378.323794) (xy 296.843014 -378.390727) (xy 296.826983 -378.456214)
			(xy 296.803223 -378.51931) (xy 296.772077 -378.579105) (xy 296.733993 -378.63474) (xy 296.712132 -378.660406)
			(xy 296.706342 -378.667556) (xy 296.699825 -378.684743) (xy 296.699432 -378.693934) (xy 296.699432 -379.186186)
			(xy 296.699864 -379.195371) (xy 296.706364 -379.212554) (xy 296.712132 -379.219714) (xy 296.73404 -379.245342)
			(xy 296.772125 -379.300983) (xy 296.803272 -379.360785) (xy 296.827032 -379.423886) (xy 296.843064 -379.489379)
			(xy 296.851135 -379.556321) (xy 296.851131 -379.623748) (xy 296.843051 -379.690689) (xy 296.827012 -379.75618)
			(xy 296.803244 -379.819279) (xy 296.77209 -379.879076) (xy 296.733998 -379.934712) (xy 296.712132 -379.960378)
			(xy 296.706312 -379.967506) (xy 296.699813 -379.98471) (xy 296.699432 -379.993906) (xy 296.699432 -380.151386)
			(xy 296.698961 -380.161515) (xy 296.691233 -380.180241) (xy 296.676941 -380.194599) (xy 296.658251 -380.202414)
			(xy 296.648124 -380.202948) (xy 295.931844 -380.202948) (xy 295.921699 -380.202443) (xy 295.902957 -380.194671)
			(xy 295.888633 -380.1803) (xy 295.880924 -380.161533) (xy 295.880536 -380.151386) (xy 295.880536 -379.993906)
			(xy 295.880115 -379.98472) (xy 295.873608 -379.967536) (xy 295.867836 -379.960378) (xy 295.846016 -379.934676)
			(xy 295.807924 -379.879048) (xy 295.776769 -379.819257) (xy 295.753 -379.756165) (xy 295.736961 -379.69068)
			(xy 295.728881 -379.623745) (xy 295.728876 -379.556324) (xy 295.736948 -379.489388) (xy 295.75298 -379.423901)
			(xy 295.776741 -379.360806) (xy 295.807888 -379.301012) (xy 295.845974 -379.245379) (xy 295.867836 -379.219714)
			(xy 295.873656 -379.212586) (xy 295.880156 -379.195382) (xy 295.880536 -379.186186) (xy 295.880536 -378.693934)
			(xy 295.880101 -378.68475) (xy 295.873604 -378.667565) (xy 295.867836 -378.660406) (xy 295.845945 -378.634762)
			(xy 295.807855 -378.579126) (xy 295.776703 -378.519327) (xy 295.752939 -378.456227) (xy 295.736904 -378.390735)
			(xy 295.72883 -378.323794) (xy 292.450785 -378.323794) (xy 292.44275 -378.390553) (xy 292.426779 -378.455934)
			(xy 292.403109 -378.518938) (xy 292.372077 -378.57866) (xy 292.334131 -378.634246) (xy 292.312344 -378.659898)
			(xy 292.306559 -378.667051) (xy 292.300039 -378.684236) (xy 292.299644 -378.693426) (xy 292.299644 -379.186694)
			(xy 292.30007 -379.195879) (xy 292.306574 -379.213063) (xy 292.312344 -379.220222) (xy 292.334178 -379.245837)
			(xy 292.372126 -379.301428) (xy 292.403158 -379.361157) (xy 292.426829 -379.424166) (xy 292.4428 -379.489553)
			(xy 292.45084 -379.55638) (xy 292.450836 -379.623689) (xy 292.442787 -379.690515) (xy 292.426809 -379.7559)
			(xy 292.40313 -379.818907) (xy 292.372091 -379.878631) (xy 292.334135 -379.934218) (xy 292.312344 -379.95987)
			(xy 292.306528 -379.967001) (xy 292.300027 -379.984203) (xy 292.299644 -379.993398) (xy 292.299644 -380.151386)
			(xy 292.299224 -380.161559) (xy 292.291441 -380.180357) (xy 292.277054 -380.194743) (xy 292.258255 -380.202525)
			(xy 292.248082 -380.202948) (xy 291.531802 -380.202948) (xy 291.521629 -380.202534) (xy 291.502831 -380.194747)
			(xy 291.488446 -380.180358) (xy 291.480663 -380.161559) (xy 291.48024 -380.151386) (xy 291.48024 -379.993398)
			(xy 291.479822 -379.984212) (xy 291.473313 -379.967028) (xy 291.46754 -379.95987) (xy 291.445798 -379.934181)
			(xy 291.407847 -379.878599) (xy 291.376812 -379.818881) (xy 291.353137 -379.755881) (xy 291.337161 -379.690504)
			(xy 291.329113 -379.623685) (xy 291.329109 -379.556384) (xy 291.337148 -379.489564) (xy 291.353116 -379.424185)
			(xy 291.376784 -379.361182) (xy 291.407812 -379.30146) (xy 291.445755 -379.245874) (xy 291.46754 -379.220222)
			(xy 291.473357 -379.213092) (xy 291.479859 -379.19589) (xy 291.48024 -379.186694) (xy 291.48024 -378.693426)
			(xy 291.479809 -378.684241) (xy 291.473309 -378.667057) (xy 291.46754 -378.659898) (xy 291.445727 -378.634267)
			(xy 291.407778 -378.578678) (xy 291.376746 -378.518951) (xy 291.353075 -378.455944) (xy 291.337104 -378.390559)
			(xy 291.329062 -378.323734) (xy 288.051024 -378.323734) (xy 288.051024 -378.323792) (xy 288.04295 -378.390729)
			(xy 288.026915 -378.456218) (xy 288.003152 -378.519314) (xy 287.972001 -378.579109) (xy 287.933912 -378.634742)
			(xy 287.912048 -378.660406) (xy 287.90626 -378.667557) (xy 287.899742 -378.684743) (xy 287.899348 -378.693934)
			(xy 287.899348 -379.186186) (xy 287.899776 -379.195371) (xy 287.906279 -379.212555) (xy 287.912048 -379.219714)
			(xy 287.933959 -379.245341) (xy 287.97205 -379.30098) (xy 288.003201 -379.360781) (xy 288.026965 -379.423883)
			(xy 288.042999 -379.489377) (xy 288.051072 -379.55632) (xy 288.051068 -379.623749) (xy 288.042987 -379.690691)
			(xy 288.026945 -379.756183) (xy 288.003173 -379.819282) (xy 287.972014 -379.879079) (xy 287.933917 -379.934714)
			(xy 287.912048 -379.960378) (xy 287.906229 -379.967507) (xy 287.899729 -379.98471) (xy 287.899348 -379.993906)
			(xy 287.899348 -380.151386) (xy 287.898862 -380.161513) (xy 287.891136 -380.180236) (xy 287.87685 -380.194594)
			(xy 287.858165 -380.202411) (xy 287.84804 -380.202948) (xy 287.13176 -380.202948) (xy 287.121655 -380.202449)
			(xy 287.102985 -380.194707) (xy 287.088693 -380.180415) (xy 287.080951 -380.161745) (xy 287.080452 -380.15164)
			(xy 287.080452 -379.993906) (xy 287.080027 -379.984721) (xy 287.073523 -379.967537) (xy 287.067752 -379.960378)
			(xy 287.045931 -379.934676) (xy 287.007838 -379.879048) (xy 286.976682 -379.819258) (xy 286.952913 -379.756165)
			(xy 286.936873 -379.69068) (xy 286.928793 -379.623745) (xy 286.928788 -379.556324) (xy 286.936861 -379.489388)
			(xy 286.952893 -379.423901) (xy 286.976654 -379.360806) (xy 287.007802 -379.301011) (xy 287.045889 -379.245378)
			(xy 287.067752 -379.219714) (xy 287.073574 -379.212587) (xy 287.080072 -379.195382) (xy 287.080452 -379.186186)
			(xy 287.080452 -378.693934) (xy 287.080014 -378.68475) (xy 287.073519 -378.667566) (xy 287.067752 -378.660406)
			(xy 287.045861 -378.634763) (xy 287.007769 -378.579126) (xy 286.976617 -378.519328) (xy 286.952852 -378.456228)
			(xy 286.936817 -378.390735) (xy 286.928742 -378.323794) (xy 274.077801 -378.323794) (xy 274.085782 -378.367343)
			(xy 274.101882 -378.499931) (xy 274.109946 -378.633249) (xy 274.11045 -378.70003) (xy 274.109946 -378.766811)
			(xy 274.101882 -378.900129) (xy 274.085782 -379.032717) (xy 274.061707 -379.164091) (xy 274.029744 -379.293772)
			(xy 273.990009 -379.421286) (xy 273.942647 -379.546169) (xy 273.887832 -379.667964) (xy 273.825762 -379.786227)
			(xy 273.756666 -379.900526) (xy 273.680794 -380.010446) (xy 273.598424 -380.115583) (xy 273.509856 -380.215556)
			(xy 273.415414 -380.309998) (xy 273.315441 -380.398566) (xy 273.210304 -380.480936) (xy 273.100384 -380.556808)
			(xy 272.986085 -380.625904) (xy 272.92786 -380.656463) (xy 289.128932 -380.656463) (xy 289.136975 -380.589641)
			(xy 289.152947 -380.524259) (xy 289.17662 -380.461255) (xy 289.207654 -380.401532) (xy 289.245604 -380.345947)
			(xy 289.267392 -380.320296) (xy 289.273172 -380.313139) (xy 289.279697 -380.295958) (xy 289.280092 -380.286768)
			(xy 289.280092 -379.7935) (xy 289.279684 -379.784313) (xy 289.273169 -379.767128) (xy 289.267392 -379.759972)
			(xy 289.24565 -379.734282) (xy 289.207696 -379.678702) (xy 289.176658 -379.618984) (xy 289.15298 -379.555985)
			(xy 289.137002 -379.490606) (xy 289.128953 -379.423787) (xy 289.128949 -379.356485) (xy 289.136989 -379.289665)
			(xy 289.152959 -379.224284) (xy 289.176628 -379.161282) (xy 289.207659 -379.10156) (xy 289.245606 -379.045975)
			(xy 289.267392 -379.020324) (xy 289.273202 -379.013189) (xy 289.279709 -378.995991) (xy 289.280092 -378.986796)
			(xy 289.280092 -378.828554) (xy 289.280595 -378.818399) (xy 289.288376 -378.799638) (xy 289.302738 -378.785276)
			(xy 289.321499 -378.777495) (xy 289.331654 -378.776992) (xy 290.047934 -378.776992) (xy 290.058088 -378.777504)
			(xy 290.076849 -378.785281) (xy 290.091212 -378.799641) (xy 290.098993 -378.8184) (xy 290.099496 -378.828554)
			(xy 290.099496 -378.986796) (xy 290.099909 -378.995983) (xy 290.106421 -379.013167) (xy 290.112196 -379.020324)
			(xy 290.13403 -379.045938) (xy 290.171975 -379.101531) (xy 290.203004 -379.16126) (xy 290.226673 -379.224269)
			(xy 290.242641 -379.289656) (xy 290.250681 -379.356482) (xy 290.250677 -379.42379) (xy 290.242628 -379.490615)
			(xy 290.226651 -379.556) (xy 290.202975 -379.619006) (xy 290.171938 -379.678731) (xy 290.133986 -379.734319)
			(xy 290.112196 -379.759972) (xy 290.106386 -379.767108) (xy 290.099879 -379.784305) (xy 290.099496 -379.7935)
			(xy 290.099496 -380.286768) (xy 290.099922 -380.295953) (xy 290.106425 -380.313138) (xy 290.112196 -380.320296)
			(xy 290.134002 -380.345932) (xy 290.171948 -380.401522) (xy 290.202979 -380.461248) (xy 290.226649 -380.524255)
			(xy 290.242619 -380.589638) (xy 290.250654 -380.656404) (xy 293.528724 -380.656404) (xy 293.536798 -380.589467)
			(xy 293.552831 -380.52398) (xy 293.576592 -380.460884) (xy 293.60774 -380.401088) (xy 293.645826 -380.345453)
			(xy 293.667688 -380.319788) (xy 293.673471 -380.312633) (xy 293.679994 -380.29545) (xy 293.680388 -380.28626)
			(xy 293.680388 -379.794008) (xy 293.679977 -379.784821) (xy 293.673464 -379.767636) (xy 293.667688 -379.76048)
			(xy 293.645872 -379.734776) (xy 293.607782 -379.679146) (xy 293.57663 -379.619356) (xy 293.552864 -379.556264)
			(xy 293.536825 -379.49078) (xy 293.528746 -379.423846) (xy 293.528741 -379.356426) (xy 293.536812 -379.289491)
			(xy 293.552842 -379.224005) (xy 293.576601 -379.16091) (xy 293.607745 -379.101115) (xy 293.645827 -379.045481)
			(xy 293.667688 -379.019816) (xy 293.673501 -379.012683) (xy 293.680006 -378.995483) (xy 293.680388 -378.986288)
			(xy 293.680388 -378.828554) (xy 293.680887 -378.818431) (xy 293.688621 -378.799718) (xy 293.702902 -378.785366)
			(xy 293.721575 -378.777539) (xy 293.731696 -378.776992) (xy 294.447976 -378.776992) (xy 294.458096 -378.777435)
			(xy 294.476798 -378.785174) (xy 294.491112 -378.799482) (xy 294.49886 -378.81818) (xy 294.499284 -378.8283)
			(xy 294.499284 -378.986288) (xy 294.499704 -378.995474) (xy 294.506211 -379.012658) (xy 294.511984 -379.019816)
			(xy 294.533896 -379.045442) (xy 294.571984 -379.101082) (xy 294.603134 -379.160883) (xy 294.626896 -379.223985)
			(xy 294.642928 -379.289479) (xy 294.651001 -379.356422) (xy 294.650996 -379.42385) (xy 294.642915 -379.490792)
			(xy 294.626874 -379.556284) (xy 294.603104 -379.619383) (xy 294.571947 -379.67918) (xy 294.533851 -379.734815)
			(xy 294.511984 -379.76048) (xy 294.506169 -379.767612) (xy 294.499666 -379.784813) (xy 294.499284 -379.794008)
			(xy 294.499284 -380.28626) (xy 294.499717 -380.295445) (xy 294.506215 -380.312629) (xy 294.511984 -380.319788)
			(xy 294.533868 -380.345437) (xy 294.571957 -380.401073) (xy 294.603108 -380.460872) (xy 294.626872 -380.523971)
			(xy 294.642906 -380.589462) (xy 294.650981 -380.656402) (xy 294.650981 -380.656463) (xy 297.92902 -380.656463)
			(xy 297.937062 -380.589641) (xy 297.953034 -380.52426) (xy 297.976707 -380.461256) (xy 298.00774 -380.401533)
			(xy 298.045688 -380.345948) (xy 298.067476 -380.320296) (xy 298.073254 -380.313137) (xy 298.079781 -380.295957)
			(xy 298.080176 -380.286768) (xy 298.080176 -379.7935) (xy 298.079771 -379.784312) (xy 298.073254 -379.767128)
			(xy 298.067476 -379.759972) (xy 298.045734 -379.734282) (xy 298.007782 -379.678701) (xy 297.976744 -379.618984)
			(xy 297.953067 -379.555984) (xy 297.93709 -379.490606) (xy 297.929041 -379.423787) (xy 297.929037 -379.356485)
			(xy 297.937077 -379.289665) (xy 297.953046 -379.224285) (xy 297.976715 -379.161283) (xy 298.007745 -379.101561)
			(xy 298.04569 -379.045976) (xy 298.067476 -379.020324) (xy 298.073285 -379.013187) (xy 298.079793 -378.99599)
			(xy 298.080176 -378.986796) (xy 298.080176 -378.828554) (xy 298.080597 -378.818389) (xy 298.088393 -378.799611)
			(xy 298.102782 -378.785246) (xy 298.121572 -378.77748) (xy 298.131738 -378.776992) (xy 298.848018 -378.776992)
			(xy 298.858171 -378.777517) (xy 298.876932 -378.785289) (xy 298.891295 -378.799644) (xy 298.899077 -378.818401)
			(xy 298.89958 -378.828554) (xy 298.89958 -378.986796) (xy 298.899996 -378.995982) (xy 298.906506 -379.013167)
			(xy 298.91228 -379.020324) (xy 298.934114 -379.045938) (xy 298.972061 -379.10153) (xy 299.003091 -379.161259)
			(xy 299.02676 -379.224269) (xy 299.042729 -379.289655) (xy 299.050769 -379.356482) (xy 299.050765 -379.42379)
			(xy 299.042716 -379.490616) (xy 299.026739 -379.556) (xy 299.003061 -379.619007) (xy 298.972023 -379.678732)
			(xy 298.93407 -379.73432) (xy 298.91228 -379.759972) (xy 298.906468 -379.767106) (xy 298.899963 -379.784305)
			(xy 298.89958 -379.7935) (xy 298.89958 -380.286768) (xy 298.90001 -380.295953) (xy 298.90651 -380.313137)
			(xy 298.91228 -380.320296) (xy 298.934087 -380.345932) (xy 298.972034 -380.401521) (xy 299.003065 -380.461247)
			(xy 299.026736 -380.524254) (xy 299.042707 -380.589638) (xy 299.050742 -380.656404) (xy 302.328812 -380.656404)
			(xy 302.336886 -380.589468) (xy 302.352918 -380.52398) (xy 302.376679 -380.460884) (xy 302.407826 -380.401089)
			(xy 302.44591 -380.345454) (xy 302.467772 -380.319788) (xy 302.473565 -380.312641) (xy 302.48008 -380.295451)
			(xy 302.480472 -380.28626) (xy 302.480472 -379.794008) (xy 302.480064 -379.78482) (xy 302.47355 -379.767636)
			(xy 302.467772 -379.76048) (xy 302.445956 -379.734775) (xy 302.407868 -379.679146) (xy 302.376717 -379.619355)
			(xy 302.352951 -379.556263) (xy 302.336913 -379.490779) (xy 302.328834 -379.423846) (xy 302.328829 -379.356426)
			(xy 302.3369 -379.289492) (xy 302.35293 -379.224006) (xy 302.376687 -379.160911) (xy 302.407831 -379.101116)
			(xy 302.445912 -379.045482) (xy 302.467772 -379.019816) (xy 302.473595 -379.01269) (xy 302.480092 -378.995485)
			(xy 302.480472 -378.986288) (xy 302.480472 -378.828554) (xy 302.48089 -378.81842) (xy 302.488639 -378.799692)
			(xy 302.502946 -378.785336) (xy 302.521648 -378.777525) (xy 302.53178 -378.776992) (xy 303.24806 -378.776992)
			(xy 303.258211 -378.777454) (xy 303.27696 -378.785235) (xy 303.291285 -378.79962) (xy 303.298987 -378.818402)
			(xy 303.299368 -378.828554) (xy 303.299368 -378.986288) (xy 303.299791 -378.995474) (xy 303.306296 -379.012658)
			(xy 303.312068 -379.019816) (xy 303.33398 -379.045442) (xy 303.37207 -379.101081) (xy 303.40322 -379.160883)
			(xy 303.426983 -379.223985) (xy 303.443016 -379.289479) (xy 303.451089 -379.356422) (xy 303.451084 -379.42385)
			(xy 303.443003 -379.490792) (xy 303.426962 -379.556284) (xy 303.403191 -379.619383) (xy 303.372032 -379.679181)
			(xy 303.333936 -379.734815) (xy 303.312068 -379.76048) (xy 303.306251 -379.76761) (xy 303.299749 -379.784812)
			(xy 303.299368 -379.794008) (xy 303.299368 -380.28626) (xy 303.299805 -380.295444) (xy 303.306301 -380.312628)
			(xy 303.312068 -380.319788) (xy 303.333953 -380.345436) (xy 303.372043 -380.401073) (xy 303.403195 -380.460871)
			(xy 303.426959 -380.52397) (xy 303.442994 -380.589461) (xy 303.451069 -380.656402) (xy 303.451069 -380.656404)
			(xy 333.128842 -380.656404) (xy 333.136916 -380.589467) (xy 333.15295 -380.523979) (xy 333.176713 -380.460883)
			(xy 333.207862 -380.401087) (xy 333.245949 -380.345453) (xy 333.267812 -380.319788) (xy 333.273598 -380.312635)
			(xy 333.280118 -380.29545) (xy 333.280512 -380.28626) (xy 333.280512 -379.794008) (xy 333.280095 -379.784822)
			(xy 333.273586 -379.767637) (xy 333.267812 -379.76048) (xy 333.245995 -379.734776) (xy 333.207904 -379.679147)
			(xy 333.17675 -379.619357) (xy 333.152983 -379.556265) (xy 333.136944 -379.49078) (xy 333.128864 -379.423846)
			(xy 333.12886 -379.356426) (xy 333.136931 -379.289491) (xy 333.152962 -379.224004) (xy 333.176721 -379.160909)
			(xy 333.207867 -379.101115) (xy 333.24595 -379.045481) (xy 333.267812 -379.019816) (xy 333.273628 -379.012685)
			(xy 333.280131 -378.995483) (xy 333.280512 -378.986288) (xy 333.280512 -378.828554) (xy 333.280988 -378.818428)
			(xy 333.288726 -378.799711) (xy 333.303015 -378.785357) (xy 333.321696 -378.777535) (xy 333.33182 -378.776992)
			(xy 334.0481 -378.776992) (xy 334.058253 -378.777422) (xy 334.077004 -378.785216) (xy 334.091327 -378.79961)
			(xy 334.099028 -378.818399) (xy 334.099408 -378.828554) (xy 334.099408 -378.986288) (xy 334.099822 -378.995475)
			(xy 334.106333 -379.012659) (xy 334.112108 -379.019816) (xy 334.134019 -379.045442) (xy 334.172106 -379.101083)
			(xy 334.203254 -379.160884) (xy 334.227015 -379.223986) (xy 334.243047 -379.28948) (xy 334.251119 -379.356422)
			(xy 334.251114 -379.42385) (xy 334.243034 -379.490791) (xy 334.226994 -379.556283) (xy 334.203224 -379.619382)
			(xy 334.172068 -379.679179) (xy 334.133975 -379.734815) (xy 334.112108 -379.76048) (xy 334.106296 -379.767614)
			(xy 334.09979 -379.784813) (xy 334.099408 -379.794008) (xy 334.099408 -380.28626) (xy 334.099836 -380.295445)
			(xy 334.106337 -380.31263) (xy 334.112108 -380.319788) (xy 334.133991 -380.345437) (xy 334.172079 -380.401074)
			(xy 334.203228 -380.460873) (xy 334.226991 -380.523972) (xy 334.243025 -380.589463) (xy 334.251099 -380.656402)
			(xy 334.251099 -380.656464) (xy 337.529162 -380.656464) (xy 337.537203 -380.589643) (xy 337.553173 -380.524262)
			(xy 337.576842 -380.461259) (xy 337.607871 -380.401536) (xy 337.645815 -380.345949) (xy 337.6676 -380.320296)
			(xy 337.673381 -380.31314) (xy 337.679905 -380.295958) (xy 337.6803 -380.286768) (xy 337.6803 -379.7935)
			(xy 337.67989 -379.784313) (xy 337.673376 -379.767129) (xy 337.6676 -379.759972) (xy 337.645861 -379.734281)
			(xy 337.607913 -379.678699) (xy 337.57688 -379.61898) (xy 337.553206 -379.555981) (xy 337.537231 -379.490604)
			(xy 337.529183 -379.423786) (xy 337.529179 -379.356486) (xy 337.537218 -379.289667) (xy 337.553185 -379.224288)
			(xy 337.57685 -379.161286) (xy 337.607876 -379.101563) (xy 337.645816 -379.045977) (xy 337.6676 -379.020324)
			(xy 337.673411 -379.013189) (xy 337.679917 -378.995991) (xy 337.6803 -378.986796) (xy 337.6803 -378.828554)
			(xy 337.680795 -378.818398) (xy 337.688577 -378.799635) (xy 337.702942 -378.785273) (xy 337.721706 -378.777493)
			(xy 337.731862 -378.776992) (xy 338.448142 -378.776992) (xy 338.458297 -378.777498) (xy 338.477058 -378.785278)
			(xy 338.49142 -378.799639) (xy 338.499201 -378.818399) (xy 338.499704 -378.828554) (xy 338.499704 -378.986796)
			(xy 338.500115 -378.995983) (xy 338.506628 -379.013167) (xy 338.512404 -379.020324) (xy 338.534237 -379.045938)
			(xy 338.572182 -379.101531) (xy 338.603211 -379.16126) (xy 338.626879 -379.22427) (xy 338.642847 -379.289656)
			(xy 338.650887 -379.356482) (xy 338.650883 -379.42379) (xy 338.642834 -379.490615) (xy 338.626858 -379.556)
			(xy 338.603181 -379.619006) (xy 338.572145 -379.678731) (xy 338.534193 -379.734319) (xy 338.512404 -379.759972)
			(xy 338.506595 -379.767108) (xy 338.500088 -379.784306) (xy 338.499704 -379.7935) (xy 338.499704 -380.286768)
			(xy 338.500129 -380.295954) (xy 338.506632 -380.313138) (xy 338.512404 -380.320296) (xy 338.53421 -380.345933)
			(xy 338.572155 -380.401522) (xy 338.603185 -380.461248) (xy 338.626855 -380.524255) (xy 338.642826 -380.589639)
			(xy 338.65086 -380.656404) (xy 341.92893 -380.656404) (xy 341.937004 -380.589467) (xy 341.953037 -380.523979)
			(xy 341.976799 -380.460883) (xy 342.007947 -380.401088) (xy 342.046033 -380.345453) (xy 342.067896 -380.319788)
			(xy 342.07368 -380.312634) (xy 342.080202 -380.29545) (xy 342.080596 -380.28626) (xy 342.080596 -379.794008)
			(xy 342.080183 -379.784821) (xy 342.073671 -379.767637) (xy 342.067896 -379.76048) (xy 342.046079 -379.734776)
			(xy 342.007989 -379.679147) (xy 341.976837 -379.619356) (xy 341.95307 -379.556264) (xy 341.937032 -379.49078)
			(xy 341.928952 -379.423846) (xy 341.928948 -379.356426) (xy 341.937019 -379.289491) (xy 341.953049 -379.224005)
			(xy 341.976807 -379.16091) (xy 342.007952 -379.101115) (xy 342.046035 -379.045481) (xy 342.067896 -379.019816)
			(xy 342.07371 -379.012683) (xy 342.080215 -378.995483) (xy 342.080596 -378.986288) (xy 342.080596 -378.828554)
			(xy 342.081088 -378.81843) (xy 342.088822 -378.799716) (xy 342.103106 -378.785363) (xy 342.121782 -378.777538)
			(xy 342.131904 -378.776992) (xy 342.848184 -378.776992) (xy 342.858336 -378.777434) (xy 342.877087 -378.785223)
			(xy 342.89141 -378.799614) (xy 342.899112 -378.8184) (xy 342.899492 -378.828554) (xy 342.899492 -378.986288)
			(xy 342.89991 -378.995474) (xy 342.906418 -379.012659) (xy 342.912192 -379.019816) (xy 342.934103 -379.045442)
			(xy 342.972191 -379.101082) (xy 343.00334 -379.160884) (xy 343.027102 -379.223986) (xy 343.043135 -379.28948)
			(xy 343.051207 -379.356422) (xy 343.051202 -379.42385) (xy 343.043122 -379.490792) (xy 343.027081 -379.556283)
			(xy 343.003311 -379.619382) (xy 342.972154 -379.67918) (xy 342.934059 -379.734815) (xy 342.912192 -379.76048)
			(xy 342.906378 -379.767613) (xy 342.899874 -379.784813) (xy 342.899492 -379.794008) (xy 342.899492 -380.28626)
			(xy 342.899923 -380.295445) (xy 342.906422 -380.312629) (xy 342.912192 -380.319788) (xy 342.934076 -380.345437)
			(xy 342.972165 -380.401074) (xy 343.003315 -380.460872) (xy 343.027078 -380.523971) (xy 343.043113 -380.589462)
			(xy 343.051187 -380.656402) (xy 343.051187 -380.656463) (xy 346.329226 -380.656463) (xy 346.337269 -380.589641)
			(xy 346.353241 -380.524259) (xy 346.376913 -380.461255) (xy 346.407947 -380.401533) (xy 346.445896 -380.345948)
			(xy 346.467684 -380.320296) (xy 346.473463 -380.313138) (xy 346.479989 -380.295957) (xy 346.480384 -380.286768)
			(xy 346.480384 -379.7935) (xy 346.479977 -379.784312) (xy 346.473462 -379.767128) (xy 346.467684 -379.759972)
			(xy 346.445942 -379.734282) (xy 346.407989 -379.678702) (xy 346.376951 -379.618984) (xy 346.353274 -379.555984)
			(xy 346.337296 -379.490606) (xy 346.329247 -379.423787) (xy 346.329243 -379.356485) (xy 346.337283 -379.289665)
			(xy 346.353252 -379.224285) (xy 346.376922 -379.161282) (xy 346.407952 -379.10156) (xy 346.445898 -379.045976)
			(xy 346.467684 -379.020324) (xy 346.473493 -379.013188) (xy 346.480001 -378.99599) (xy 346.480384 -378.986796)
			(xy 346.480384 -378.828554) (xy 346.480797 -378.818388) (xy 346.488595 -378.799609) (xy 346.502986 -378.785243)
			(xy 346.521779 -378.777479) (xy 346.531946 -378.776992) (xy 347.248226 -378.776992) (xy 347.25838 -378.777511)
			(xy 347.277141 -378.785285) (xy 347.291504 -378.799642) (xy 347.299285 -378.8184) (xy 347.299788 -378.828554)
			(xy 347.299788 -378.986796) (xy 347.300203 -378.995983) (xy 347.306714 -379.013167) (xy 347.312488 -379.020324)
			(xy 347.334322 -379.045938) (xy 347.372268 -379.10153) (xy 347.403297 -379.161259) (xy 347.426966 -379.224269)
			(xy 347.442935 -379.289656) (xy 347.450975 -379.356482) (xy 347.450971 -379.42379) (xy 347.442922 -379.490616)
			(xy 347.426945 -379.556) (xy 347.403268 -379.619007) (xy 347.372231 -379.678732) (xy 347.334278 -379.734319)
			(xy 347.312488 -379.759972) (xy 347.306677 -379.767107) (xy 347.300171 -379.784305) (xy 347.299788 -379.7935)
			(xy 347.299788 -380.286768) (xy 347.300216 -380.295953) (xy 347.306718 -380.313138) (xy 347.312488 -380.320296)
			(xy 347.334295 -380.345932) (xy 347.372241 -380.401522) (xy 347.403272 -380.461248) (xy 347.426942 -380.524254)
			(xy 347.442913 -380.589638) (xy 347.450948 -380.656404) (xy 377.128751 -380.656404) (xy 377.136826 -380.589466)
			(xy 377.15286 -380.523978) (xy 377.176623 -380.460882) (xy 377.207772 -380.401087) (xy 377.24586 -380.345453)
			(xy 377.267724 -380.319788) (xy 377.273511 -380.312636) (xy 377.280031 -380.295451) (xy 377.280424 -380.28626)
			(xy 377.280424 -379.794008) (xy 377.280005 -379.784822) (xy 377.273497 -379.767638) (xy 377.267724 -379.76048)
			(xy 377.245906 -379.734776) (xy 377.207815 -379.679148) (xy 377.17666 -379.619357) (xy 377.152893 -379.556265)
			(xy 377.136853 -379.490781) (xy 377.128773 -379.423846) (xy 377.128769 -379.356426) (xy 377.13684 -379.28949)
			(xy 377.152871 -379.224004) (xy 377.176631 -379.160909) (xy 377.207777 -379.101114) (xy 377.245862 -379.045481)
			(xy 377.267724 -379.019816) (xy 377.273542 -379.012686) (xy 377.280043 -378.995484) (xy 377.280424 -378.986288)
			(xy 377.280424 -378.828554) (xy 377.280888 -378.818426) (xy 377.288628 -378.799707) (xy 377.302921 -378.785353)
			(xy 377.321607 -378.777533) (xy 377.331732 -378.776992) (xy 378.048012 -378.776992) (xy 378.058166 -378.777411)
			(xy 378.076917 -378.785209) (xy 378.09124 -378.799607) (xy 378.098941 -378.818398) (xy 378.09932 -378.828554)
			(xy 378.09932 -378.986288) (xy 378.099731 -378.995475) (xy 378.106244 -379.01266) (xy 378.11202 -379.019816)
			(xy 378.13393 -379.045443) (xy 378.172016 -379.101083) (xy 378.203164 -379.160885) (xy 378.226924 -379.223987)
			(xy 378.242956 -379.28948) (xy 378.251028 -379.356423) (xy 378.251023 -379.42385) (xy 378.242943 -379.490791)
			(xy 378.226903 -379.556282) (xy 378.203134 -379.619381) (xy 378.171979 -379.679179) (xy 378.133886 -379.734814)
			(xy 378.11202 -379.76048) (xy 378.106209 -379.767615) (xy 378.099702 -379.784813) (xy 378.09932 -379.794008)
			(xy 378.09932 -380.28626) (xy 378.099745 -380.295446) (xy 378.106248 -380.312631) (xy 378.11202 -380.319788)
			(xy 378.133903 -380.345437) (xy 378.17199 -380.401075) (xy 378.203138 -380.460873) (xy 378.226901 -380.523972)
			(xy 378.242934 -380.589463) (xy 378.251008 -380.656403) (xy 378.251008 -380.656464) (xy 381.529071 -380.656464)
			(xy 381.537113 -380.589643) (xy 381.553083 -380.524262) (xy 381.576752 -380.461258) (xy 381.607782 -380.401535)
			(xy 381.645726 -380.345948) (xy 381.667512 -380.320296) (xy 381.673294 -380.313141) (xy 381.679817 -380.295958)
			(xy 381.680212 -380.286768) (xy 381.680212 -379.7935) (xy 381.679799 -379.784313) (xy 381.673287 -379.767129)
			(xy 381.667512 -379.759972) (xy 381.645773 -379.73428) (xy 381.607824 -379.678699) (xy 381.57679 -379.618981)
			(xy 381.553116 -379.555981) (xy 381.537141 -379.490604) (xy 381.529093 -379.423786) (xy 381.529089 -379.356486)
			(xy 381.537128 -379.289667) (xy 381.553095 -379.224288) (xy 381.576761 -379.161285) (xy 381.607787 -379.101563)
			(xy 381.645728 -379.045977) (xy 381.667512 -379.020324) (xy 381.673325 -379.01319) (xy 381.679829 -378.995991)
			(xy 381.680212 -378.986796) (xy 381.680212 -378.828554) (xy 381.680695 -378.818397) (xy 381.68848 -378.799631)
			(xy 381.702848 -378.785269) (xy 381.721616 -378.777491) (xy 381.731774 -378.776992) (xy 382.448054 -378.776992)
			(xy 382.458203 -378.77757) (xy 382.476962 -378.785321) (xy 382.491328 -378.79966) (xy 382.499112 -378.818406)
			(xy 382.499616 -378.828554) (xy 382.499616 -378.986796) (xy 382.500025 -378.995983) (xy 382.506539 -379.013168)
			(xy 382.512316 -379.020324) (xy 382.534153 -379.045936) (xy 382.572103 -379.101528) (xy 382.603137 -379.161256)
			(xy 382.626809 -379.224266) (xy 382.64278 -379.289654) (xy 382.650821 -379.356481) (xy 382.650816 -379.423791)
			(xy 382.642767 -379.490618) (xy 382.626787 -379.556003) (xy 382.603107 -379.61901) (xy 382.572066 -379.678734)
			(xy 382.534108 -379.734321) (xy 382.512316 -379.759972) (xy 382.506508 -379.767109) (xy 382.5 -379.784306)
			(xy 382.499616 -379.7935) (xy 382.499616 -380.286768) (xy 382.500038 -380.295954) (xy 382.506543 -380.313139)
			(xy 382.512316 -380.320296) (xy 382.534125 -380.345931) (xy 382.572076 -380.401519) (xy 382.603111 -380.461245)
			(xy 382.626784 -380.524251) (xy 382.642757 -380.589636) (xy 382.650793 -380.656404) (xy 385.928839 -380.656404)
			(xy 385.936913 -380.589467) (xy 385.952947 -380.523979) (xy 385.976709 -380.460883) (xy 386.007858 -380.401087)
			(xy 386.045945 -380.345453) (xy 386.067808 -380.319788) (xy 386.073593 -380.312635) (xy 386.080114 -380.29545)
			(xy 386.080508 -380.28626) (xy 386.080508 -379.794008) (xy 386.080092 -379.784821) (xy 386.073582 -379.767637)
			(xy 386.067808 -379.76048) (xy 386.045991 -379.734776) (xy 386.0079 -379.679147) (xy 385.976747 -379.619356)
			(xy 385.95298 -379.556265) (xy 385.936941 -379.49078) (xy 385.928861 -379.423846) (xy 385.928857 -379.356426)
			(xy 385.936928 -379.289491) (xy 385.952958 -379.224004) (xy 385.976718 -379.160909) (xy 386.007863 -379.101115)
			(xy 386.045947 -379.045481) (xy 386.067808 -379.019816) (xy 386.073624 -379.012684) (xy 386.080127 -378.995483)
			(xy 386.080508 -378.986288) (xy 386.080508 -378.828554) (xy 386.080988 -378.818428) (xy 386.088725 -378.799712)
			(xy 386.103012 -378.785359) (xy 386.121693 -378.777535) (xy 386.131816 -378.776992) (xy 386.848096 -378.776992)
			(xy 386.858249 -378.777425) (xy 386.877 -378.785218) (xy 386.891323 -378.799611) (xy 386.899024 -378.818399)
			(xy 386.899404 -378.828554) (xy 386.899404 -378.986288) (xy 386.899819 -378.995475) (xy 386.906329 -379.012659)
			(xy 386.912104 -379.019816) (xy 386.934015 -379.045442) (xy 386.972102 -379.101083) (xy 387.00325 -379.160884)
			(xy 387.027012 -379.223986) (xy 387.043044 -379.28948) (xy 387.051116 -379.356422) (xy 387.051111 -379.42385)
			(xy 387.043031 -379.490791) (xy 387.02699 -379.556283) (xy 387.003221 -379.619382) (xy 386.972065 -379.679179)
			(xy 386.933971 -379.734815) (xy 386.912104 -379.76048) (xy 386.906291 -379.767614) (xy 386.899786 -379.784813)
			(xy 386.899404 -379.794008) (xy 386.899404 -380.28626) (xy 386.899832 -380.295445) (xy 386.906333 -380.31263)
			(xy 386.912104 -380.319788) (xy 386.933987 -380.345437) (xy 386.972075 -380.401074) (xy 387.003225 -380.460872)
			(xy 387.026988 -380.523971) (xy 387.043022 -380.589462) (xy 387.051096 -380.656402) (xy 387.051096 -380.656464)
			(xy 390.329159 -380.656464) (xy 390.3372 -380.589643) (xy 390.35317 -380.524263) (xy 390.376839 -380.461259)
			(xy 390.407867 -380.401536) (xy 390.445811 -380.345949) (xy 390.467596 -380.320296) (xy 390.473376 -380.313139)
			(xy 390.479901 -380.295958) (xy 390.480296 -380.286768) (xy 390.480296 -379.7935) (xy 390.479887 -379.784313)
			(xy 390.473372 -379.767128) (xy 390.467596 -379.759972) (xy 390.445857 -379.73428) (xy 390.407909 -379.678699)
			(xy 390.376876 -379.61898) (xy 390.353203 -379.555981) (xy 390.337228 -379.490604) (xy 390.32918 -379.423786)
			(xy 390.329176 -379.356486) (xy 390.337215 -379.289667) (xy 390.353181 -379.224288) (xy 390.376847 -379.161286)
			(xy 390.407872 -379.101563) (xy 390.445812 -379.045977) (xy 390.467596 -379.020324) (xy 390.473407 -379.013189)
			(xy 390.479913 -378.995991) (xy 390.480296 -378.986796) (xy 390.480296 -378.828554) (xy 390.480795 -378.818398)
			(xy 390.488576 -378.799636) (xy 390.50294 -378.785274) (xy 390.521702 -378.777494) (xy 390.531858 -378.776992)
			(xy 391.248138 -378.776992) (xy 391.258293 -378.777501) (xy 391.277054 -378.785279) (xy 391.291416 -378.79964)
			(xy 391.299197 -378.8184) (xy 391.2997 -378.828554) (xy 391.2997 -378.986796) (xy 391.300112 -378.995983)
			(xy 391.306625 -379.013167) (xy 391.3124 -379.020324) (xy 391.334234 -379.045938) (xy 391.372178 -379.101531)
			(xy 391.403207 -379.16126) (xy 391.426876 -379.224269) (xy 391.442844 -379.289656) (xy 391.450884 -379.356482)
			(xy 391.45088 -379.42379) (xy 391.442831 -379.490615) (xy 391.426855 -379.556) (xy 391.403178 -379.619006)
			(xy 391.372141 -379.678731) (xy 391.334189 -379.734319) (xy 391.3124 -379.759972) (xy 391.30659 -379.767108)
			(xy 391.300083 -379.784306) (xy 391.2997 -379.7935) (xy 391.2997 -380.286768) (xy 391.300126 -380.295954)
			(xy 391.306629 -380.313138) (xy 391.3124 -380.320296) (xy 391.334206 -380.345933) (xy 391.372152 -380.401522)
			(xy 391.403182 -380.461248) (xy 391.426852 -380.524255) (xy 391.442822 -380.589638) (xy 391.450857 -380.656404)
			(xy 421.12866 -380.656404) (xy 421.136735 -380.589466) (xy 421.152769 -380.523978) (xy 421.176533 -380.460881)
			(xy 421.207683 -380.401086) (xy 421.245772 -380.345453) (xy 421.267636 -380.319788) (xy 421.273425 -380.312637)
			(xy 421.279943 -380.295451) (xy 421.280336 -380.28626) (xy 421.280336 -379.794008) (xy 421.279914 -379.784822)
			(xy 421.273408 -379.767638) (xy 421.267636 -379.76048) (xy 421.245818 -379.734776) (xy 421.207725 -379.679148)
			(xy 421.176571 -379.619358) (xy 421.152802 -379.556266) (xy 421.136762 -379.490781) (xy 421.128682 -379.423846)
			(xy 421.128678 -379.356426) (xy 421.136749 -379.28949) (xy 421.152781 -379.224003) (xy 421.176541 -379.160908)
			(xy 421.207688 -379.101114) (xy 421.245774 -379.045481) (xy 421.267636 -379.019816) (xy 421.273455 -379.012687)
			(xy 421.279956 -378.995484) (xy 421.280336 -378.986288) (xy 421.280336 -378.828554) (xy 421.280789 -378.818425)
			(xy 421.288531 -378.799703) (xy 421.302827 -378.785349) (xy 421.321517 -378.777531) (xy 421.331644 -378.776992)
			(xy 422.047924 -378.776992) (xy 422.058033 -378.777465) (xy 422.076711 -378.785209) (xy 422.091004 -378.79951)
			(xy 422.09874 -378.81819) (xy 422.099232 -378.8283) (xy 422.099232 -378.986288) (xy 422.099663 -378.995473)
			(xy 422.106164 -379.012656) (xy 422.111932 -379.019816) (xy 422.133842 -379.045443) (xy 422.171927 -379.101084)
			(xy 422.203074 -379.160885) (xy 422.226834 -379.223987) (xy 422.242865 -379.289481) (xy 422.250937 -379.356423)
			(xy 422.250932 -379.423849) (xy 422.242852 -379.49079) (xy 422.226813 -379.556282) (xy 422.203045 -379.61938)
			(xy 422.17189 -379.679178) (xy 422.133798 -379.734814) (xy 422.111932 -379.76048) (xy 422.106111 -379.767607)
			(xy 422.099613 -379.784812) (xy 422.099232 -379.794008) (xy 422.099232 -380.28626) (xy 422.099677 -380.295443)
			(xy 422.106168 -380.312627) (xy 422.111932 -380.319788) (xy 422.133814 -380.345438) (xy 422.171901 -380.401075)
			(xy 422.203049 -380.460874) (xy 422.22681 -380.523973) (xy 422.242843 -380.589463) (xy 422.250917 -380.656403)
			(xy 422.250917 -380.656463) (xy 425.52898 -380.656463) (xy 425.537022 -380.589642) (xy 425.552992 -380.524262)
			(xy 425.576662 -380.461258) (xy 425.607692 -380.401535) (xy 425.645638 -380.345948) (xy 425.667424 -380.320296)
			(xy 425.673208 -380.313142) (xy 425.679729 -380.295958) (xy 425.680124 -380.286768) (xy 425.680124 -379.7935)
			(xy 425.679709 -379.784313) (xy 425.673198 -379.767129) (xy 425.667424 -379.759972) (xy 425.645684 -379.734281)
			(xy 425.607735 -379.678699) (xy 425.5767 -379.618981) (xy 425.553026 -379.555982) (xy 425.53705 -379.490605)
			(xy 425.529002 -379.423787) (xy 425.528998 -379.356486) (xy 425.537037 -379.289667) (xy 425.553004 -379.224287)
			(xy 425.576671 -379.161285) (xy 425.607698 -379.101563) (xy 425.64564 -379.045977) (xy 425.667424 -379.020324)
			(xy 425.673238 -379.013191) (xy 425.679742 -378.995991) (xy 425.680124 -378.986796) (xy 425.680124 -378.828554)
			(xy 425.680595 -378.818395) (xy 425.688382 -378.799628) (xy 425.702754 -378.785264) (xy 425.721527 -378.777489)
			(xy 425.731686 -378.776992) (xy 426.447966 -378.776992) (xy 426.458116 -378.77756) (xy 426.476875 -378.785315)
			(xy 426.49124 -378.799657) (xy 426.499024 -378.818405) (xy 426.499528 -378.828554) (xy 426.499528 -378.986796)
			(xy 426.499934 -378.995984) (xy 426.50645 -379.013168) (xy 426.512228 -379.020324) (xy 426.534064 -379.045937)
			(xy 426.572014 -379.101528) (xy 426.603047 -379.161257) (xy 426.626718 -379.224267) (xy 426.642689 -379.289654)
			(xy 426.65073 -379.356481) (xy 426.650725 -379.423791) (xy 426.642676 -379.490617) (xy 426.626697 -379.556003)
			(xy 426.603017 -379.619009) (xy 426.571977 -379.678734) (xy 426.53402 -379.73432) (xy 426.512228 -379.759972)
			(xy 426.50641 -379.767101) (xy 426.49991 -379.784304) (xy 426.499528 -379.7935) (xy 426.499528 -380.286768)
			(xy 426.499947 -380.295954) (xy 426.506454 -380.313139) (xy 426.512228 -380.320296) (xy 426.534036 -380.345932)
			(xy 426.571987 -380.40152) (xy 426.603021 -380.461245) (xy 426.626694 -380.524252) (xy 426.642667 -380.589636)
			(xy 426.650703 -380.656404) (xy 429.928748 -380.656404) (xy 429.936823 -380.589467) (xy 429.952857 -380.523978)
			(xy 429.976619 -380.460882) (xy 430.007769 -380.401087) (xy 430.045857 -380.345453) (xy 430.06772 -380.319788)
			(xy 430.073506 -380.312636) (xy 430.080027 -380.295451) (xy 430.08042 -380.28626) (xy 430.08042 -379.794008)
			(xy 430.080001 -379.784822) (xy 430.073493 -379.767638) (xy 430.06772 -379.76048) (xy 430.045902 -379.734776)
			(xy 430.007811 -379.679148) (xy 429.976657 -379.619357) (xy 429.952889 -379.556265) (xy 429.93685 -379.490781)
			(xy 429.92877 -379.423846) (xy 429.928766 -379.356426) (xy 429.936837 -379.289491) (xy 429.952868 -379.224004)
			(xy 429.976628 -379.160909) (xy 430.007774 -379.101114) (xy 430.045858 -379.045481) (xy 430.06772 -379.019816)
			(xy 430.073537 -379.012685) (xy 430.080039 -378.995484) (xy 430.08042 -378.986288) (xy 430.08042 -378.828554)
			(xy 430.080888 -378.818427) (xy 430.088628 -378.799708) (xy 430.102919 -378.785354) (xy 430.121603 -378.777533)
			(xy 430.131728 -378.776992) (xy 430.848008 -378.776992) (xy 430.858162 -378.777415) (xy 430.876913 -378.785212)
			(xy 430.891235 -378.799608) (xy 430.898936 -378.818398) (xy 430.899316 -378.828554) (xy 430.899316 -378.986288)
			(xy 430.899728 -378.995475) (xy 430.90624 -379.01266) (xy 430.912016 -379.019816) (xy 430.933927 -379.045443)
			(xy 430.972013 -379.101083) (xy 431.003161 -379.160885) (xy 431.026921 -379.223987) (xy 431.042953 -379.28948)
			(xy 431.051025 -379.356422) (xy 431.05102 -379.42385) (xy 431.04294 -379.490791) (xy 431.0269 -379.556282)
			(xy 431.003131 -379.619381) (xy 430.971976 -379.679179) (xy 430.933882 -379.734814) (xy 430.912016 -379.76048)
			(xy 430.906205 -379.767615) (xy 430.899698 -379.784813) (xy 430.899316 -379.794008) (xy 430.899316 -380.28626)
			(xy 430.899742 -380.295446) (xy 430.906244 -380.31263) (xy 430.912016 -380.319788) (xy 430.933899 -380.345437)
			(xy 430.971986 -380.401074) (xy 431.003135 -380.460873) (xy 431.026897 -380.523972) (xy 431.042931 -380.589463)
			(xy 431.051005 -380.656403) (xy 431.051005 -380.656464) (xy 434.329068 -380.656464) (xy 434.33711 -380.589643)
			(xy 434.35308 -380.524262) (xy 434.376749 -380.461259) (xy 434.407778 -380.401535) (xy 434.445722 -380.345949)
			(xy 434.467508 -380.320296) (xy 434.47329 -380.31314) (xy 434.479813 -380.295958) (xy 434.480208 -380.286768)
			(xy 434.480208 -379.7935) (xy 434.479796 -379.784313) (xy 434.473283 -379.767129) (xy 434.467508 -379.759972)
			(xy 434.445769 -379.73428) (xy 434.407821 -379.678699) (xy 434.376787 -379.61898) (xy 434.353113 -379.555981)
			(xy 434.337137 -379.490604) (xy 434.32909 -379.423786) (xy 434.329086 -379.356486) (xy 434.337125 -379.289667)
			(xy 434.353091 -379.224288) (xy 434.376757 -379.161286) (xy 434.407783 -379.101563) (xy 434.445724 -379.045977)
			(xy 434.467508 -379.020324) (xy 434.47332 -379.01319) (xy 434.479825 -378.995991) (xy 434.480208 -378.986796)
			(xy 434.480208 -378.828554) (xy 434.480695 -378.818397) (xy 434.488479 -378.799633) (xy 434.502846 -378.78527)
			(xy 434.521613 -378.777492) (xy 434.53177 -378.776992) (xy 435.24805 -378.776992) (xy 435.258213 -378.777504)
			(xy 435.276998 -378.785264) (xy 435.291383 -378.799622) (xy 435.299177 -378.818392) (xy 435.299612 -378.828554)
			(xy 435.299612 -378.986796) (xy 435.300021 -378.995983) (xy 435.306535 -379.013168) (xy 435.312312 -379.020324)
			(xy 435.334148 -379.045937) (xy 435.372099 -379.101528) (xy 435.403133 -379.161256) (xy 435.426805 -379.224266)
			(xy 435.442776 -379.289654) (xy 435.450817 -379.356481) (xy 435.450813 -379.423791) (xy 435.442763 -379.490618)
			(xy 435.426784 -379.556003) (xy 435.403103 -379.61901) (xy 435.372062 -379.678734) (xy 435.334104 -379.73432)
			(xy 435.312312 -379.759972) (xy 435.306504 -379.767109) (xy 435.299996 -379.784306) (xy 435.299612 -379.7935)
			(xy 435.299612 -380.286768) (xy 435.300035 -380.295954) (xy 435.306539 -380.313139) (xy 435.312312 -380.320296)
			(xy 435.334121 -380.345931) (xy 435.372072 -380.401519) (xy 435.403107 -380.461244) (xy 435.426781 -380.524251)
			(xy 435.442754 -380.589636) (xy 435.450797 -380.656461) (xy 435.450796 -380.723769) (xy 435.442749 -380.790594)
			(xy 435.426772 -380.855977) (xy 435.403095 -380.918983) (xy 435.372057 -380.978707) (xy 435.334102 -381.034292)
			(xy 435.312312 -381.059944) (xy 435.306516 -381.067089) (xy 435.3 -381.08428) (xy 435.299612 -381.093472)
			(xy 435.299612 -381.251206) (xy 435.29924 -381.261384) (xy 435.291444 -381.280189) (xy 435.277041 -381.294575)
			(xy 435.258229 -381.302351) (xy 435.24805 -381.302768) (xy 434.53177 -381.302768) (xy 434.521611 -381.302291)
			(xy 434.502842 -381.294508) (xy 434.488478 -381.280138) (xy 434.480704 -381.261365) (xy 434.480208 -381.251206)
			(xy 434.480208 -381.093472) (xy 434.47981 -381.084284) (xy 434.473288 -381.067099) (xy 434.467508 -381.059944)
			(xy 434.445741 -381.034275) (xy 434.407793 -380.97869) (xy 434.376761 -380.918969) (xy 434.353088 -380.855967)
			(xy 434.337115 -380.790587) (xy 434.32907 -380.723766) (xy 434.329068 -380.656464) (xy 431.051005 -380.656464)
			(xy 431.051003 -380.723827) (xy 431.042926 -380.790767) (xy 431.026889 -380.856257) (xy 431.003123 -380.919354)
			(xy 430.971971 -380.979151) (xy 430.933881 -381.034786) (xy 430.912016 -381.060452) (xy 430.906217 -381.067595)
			(xy 430.899703 -381.084787) (xy 430.899316 -381.09398) (xy 430.899316 -381.251206) (xy 430.898877 -381.261338)
			(xy 430.891139 -381.280068) (xy 430.876838 -381.294426) (xy 430.858138 -381.302237) (xy 430.848008 -381.302768)
			(xy 430.131728 -381.302768) (xy 430.121572 -381.302355) (xy 430.102814 -381.294563) (xy 430.088488 -381.280163)
			(xy 430.080793 -381.261364) (xy 430.08042 -381.251206) (xy 430.08042 -381.09398) (xy 430.080015 -381.084792)
			(xy 430.073497 -381.067608) (xy 430.06772 -381.060452) (xy 430.045875 -381.034771) (xy 430.007784 -380.979139)
			(xy 429.976632 -380.919345) (xy 429.952865 -380.85625) (xy 429.936828 -380.790763) (xy 429.92875 -380.723826)
			(xy 429.928748 -380.656404) (xy 426.650703 -380.656404) (xy 426.65071 -380.656461) (xy 426.650708 -380.723769)
			(xy 426.642661 -380.790593) (xy 426.626685 -380.855977) (xy 426.603009 -380.918982) (xy 426.571971 -380.978706)
			(xy 426.534018 -381.034292) (xy 426.512228 -381.059944) (xy 426.506422 -381.067082) (xy 426.499915 -381.084278)
			(xy 426.499528 -381.093472) (xy 426.499528 -381.251206) (xy 426.49914 -381.261382) (xy 426.491347 -381.280184)
			(xy 426.47695 -381.294569) (xy 426.458143 -381.302348) (xy 426.447966 -381.302768) (xy 425.731686 -381.302768)
			(xy 425.721528 -381.302278) (xy 425.70276 -381.2945) (xy 425.688395 -381.280133) (xy 425.68062 -381.261364)
			(xy 425.680124 -381.251206) (xy 425.680124 -381.093472) (xy 425.679722 -381.084284) (xy 425.673202 -381.0671)
			(xy 425.667424 -381.059944) (xy 425.645656 -381.034276) (xy 425.607708 -380.978691) (xy 425.576675 -380.91897)
			(xy 425.553001 -380.855967) (xy 425.537027 -380.790587) (xy 425.528982 -380.723767) (xy 425.52898 -380.656463)
			(xy 422.250917 -380.656463) (xy 422.250915 -380.723827) (xy 422.242838 -380.790766) (xy 422.226801 -380.856256)
			(xy 422.203036 -380.919354) (xy 422.171885 -380.979151) (xy 422.133796 -381.034786) (xy 422.111932 -381.060452)
			(xy 422.106123 -381.067588) (xy 422.099618 -381.084786) (xy 422.099232 -381.09398) (xy 422.099232 -381.251206)
			(xy 422.098777 -381.261337) (xy 422.091042 -381.280063) (xy 422.076746 -381.29442) (xy 422.058052 -381.302234)
			(xy 422.047924 -381.302768) (xy 421.331644 -381.302768) (xy 421.32152 -381.302347) (xy 421.302812 -381.294608)
			(xy 421.288495 -381.280292) (xy 421.280754 -381.261584) (xy 421.280336 -381.25146) (xy 421.280336 -381.09398)
			(xy 421.279927 -381.084793) (xy 421.273412 -381.067609) (xy 421.267636 -381.060452) (xy 421.24579 -381.034771)
			(xy 421.207699 -380.97914) (xy 421.176545 -380.919346) (xy 421.152778 -380.856251) (xy 421.13674 -380.790764)
			(xy 421.128662 -380.723826) (xy 421.12866 -380.656404) (xy 391.450857 -380.656404) (xy 391.450864 -380.656462)
			(xy 391.450863 -380.723768) (xy 391.442817 -380.790591) (xy 391.426843 -380.855974) (xy 391.40317 -380.918979)
			(xy 391.372136 -380.978704) (xy 391.334188 -381.034291) (xy 391.3124 -381.059944) (xy 391.306602 -381.067088)
			(xy 391.300088 -381.08428) (xy 391.2997 -381.093472) (xy 391.2997 -381.251206) (xy 391.299172 -381.261359)
			(xy 391.291403 -381.280121) (xy 391.277048 -381.294485) (xy 391.258291 -381.302266) (xy 391.248138 -381.302768)
			(xy 390.531858 -381.302768) (xy 390.521698 -381.302301) (xy 390.502929 -381.294514) (xy 390.488566 -381.28014)
			(xy 390.480792 -381.261366) (xy 390.480296 -381.251206) (xy 390.480296 -381.093472) (xy 390.4799 -381.084283)
			(xy 390.473377 -381.067099) (xy 390.467596 -381.059944) (xy 390.445829 -381.034275) (xy 390.407883 -380.97869)
			(xy 390.376851 -380.918968) (xy 390.353179 -380.855966) (xy 390.337206 -380.790586) (xy 390.329161 -380.723766)
			(xy 390.329159 -380.656464) (xy 387.051096 -380.656464) (xy 387.051094 -380.723828) (xy 387.043016 -380.790767)
			(xy 387.026979 -380.856257) (xy 387.003213 -380.919355) (xy 386.97206 -380.979152) (xy 386.933969 -381.034787)
			(xy 386.912104 -381.060452) (xy 386.906303 -381.067594) (xy 386.899791 -381.084787) (xy 386.899404 -381.09398)
			(xy 386.899404 -381.251206) (xy 386.89888 -381.261328) (xy 386.891158 -381.280041) (xy 386.876884 -381.294395)
			(xy 386.858215 -381.302222) (xy 386.848096 -381.302768) (xy 386.131816 -381.302768) (xy 386.121659 -381.302365)
			(xy 386.102901 -381.294568) (xy 386.088576 -381.280166) (xy 386.080881 -381.261365) (xy 386.080508 -381.251206)
			(xy 386.080508 -381.09398) (xy 386.080106 -381.084792) (xy 386.073587 -381.067608) (xy 386.067808 -381.060452)
			(xy 386.045963 -381.034771) (xy 386.007874 -380.979139) (xy 385.976722 -380.919345) (xy 385.952956 -380.85625)
			(xy 385.936919 -380.790763) (xy 385.928841 -380.723826) (xy 385.928839 -380.656404) (xy 382.650793 -380.656404)
			(xy 382.6508 -380.656461) (xy 382.650799 -380.723769) (xy 382.642752 -380.790593) (xy 382.626775 -380.855977)
			(xy 382.603098 -380.918983) (xy 382.57206 -380.978707) (xy 382.534106 -381.034292) (xy 382.512316 -381.059944)
			(xy 382.50652 -381.06709) (xy 382.500005 -381.08428) (xy 382.499616 -381.093472) (xy 382.499616 -381.251206)
			(xy 382.49924 -381.261384) (xy 382.491444 -381.280187) (xy 382.477044 -381.294574) (xy 382.458232 -381.30235)
			(xy 382.448054 -381.302768) (xy 381.731774 -381.302768) (xy 381.721615 -381.302288) (xy 381.702847 -381.294506)
			(xy 381.688482 -381.280137) (xy 381.680708 -381.261365) (xy 381.680212 -381.251206) (xy 381.680212 -381.093472)
			(xy 381.679813 -381.084284) (xy 381.673291 -381.0671) (xy 381.667512 -381.059944) (xy 381.645745 -381.034275)
			(xy 381.607797 -380.978691) (xy 381.576764 -380.918969) (xy 381.553092 -380.855967) (xy 381.537118 -380.790587)
			(xy 381.529073 -380.723767) (xy 381.529071 -380.656464) (xy 378.251008 -380.656464) (xy 378.251006 -380.723827)
			(xy 378.242929 -380.790767) (xy 378.226892 -380.856257) (xy 378.203126 -380.919354) (xy 378.171974 -380.979151)
			(xy 378.133884 -381.034786) (xy 378.11202 -381.060452) (xy 378.106221 -381.067596) (xy 378.099707 -381.084787)
			(xy 378.09932 -381.09398) (xy 378.09932 -381.251206) (xy 378.098877 -381.261338) (xy 378.09114 -381.280067)
			(xy 378.07684 -381.294424) (xy 378.058142 -381.302236) (xy 378.048012 -381.302768) (xy 377.331732 -381.302768)
			(xy 377.321576 -381.302352) (xy 377.302818 -381.294561) (xy 377.288492 -381.280162) (xy 377.280797 -381.261364)
			(xy 377.280424 -381.251206) (xy 377.280424 -381.09398) (xy 377.280018 -381.084792) (xy 377.273501 -381.067608)
			(xy 377.267724 -381.060452) (xy 377.245879 -381.034771) (xy 377.207788 -380.979139) (xy 377.176635 -380.919345)
			(xy 377.152869 -380.856251) (xy 377.136831 -380.790763) (xy 377.128753 -380.723826) (xy 377.128751 -380.656404)
			(xy 347.450948 -380.656404) (xy 347.450955 -380.656462) (xy 347.450954 -380.723768) (xy 347.442908 -380.790592)
			(xy 347.426934 -380.855975) (xy 347.40326 -380.91898) (xy 347.372226 -380.978704) (xy 347.334276 -381.034291)
			(xy 347.312488 -381.059944) (xy 347.306689 -381.067087) (xy 347.300176 -381.084279) (xy 347.299788 -381.093472)
			(xy 347.299788 -381.251206) (xy 347.299272 -381.261361) (xy 347.2915 -381.280125) (xy 347.277142 -381.294489)
			(xy 347.258381 -381.302268) (xy 347.248226 -381.302768) (xy 346.531946 -381.302768) (xy 346.521778 -381.302299)
			(xy 346.502986 -381.29453) (xy 346.488599 -381.280158) (xy 346.480812 -381.261373) (xy 346.480384 -381.251206)
			(xy 346.480384 -381.093472) (xy 346.479991 -381.084283) (xy 346.473466 -381.067099) (xy 346.467684 -381.059944)
			(xy 346.445915 -381.034276) (xy 346.407962 -380.978693) (xy 346.376926 -380.918972) (xy 346.35325 -380.85597)
			(xy 346.337274 -380.790589) (xy 346.329228 -380.723767) (xy 346.329226 -380.656463) (xy 343.051187 -380.656463)
			(xy 343.051185 -380.723828) (xy 343.043107 -380.790767) (xy 343.027069 -380.856258) (xy 343.003303 -380.919356)
			(xy 342.972149 -380.979152) (xy 342.934057 -381.034787) (xy 342.912192 -381.060452) (xy 342.90639 -381.067593)
			(xy 342.899879 -381.084787) (xy 342.899492 -381.09398) (xy 342.899492 -381.251206) (xy 342.898979 -381.261329)
			(xy 342.891255 -381.280044) (xy 342.876978 -381.294399) (xy 342.858304 -381.302224) (xy 342.848184 -381.302768)
			(xy 342.131904 -381.302768) (xy 342.121746 -381.302374) (xy 342.102988 -381.294574) (xy 342.088663 -381.280168)
			(xy 342.080969 -381.261366) (xy 342.080596 -381.251206) (xy 342.080596 -381.09398) (xy 342.080196 -381.084792)
			(xy 342.073675 -381.067608) (xy 342.067896 -381.060452) (xy 342.046052 -381.03477) (xy 342.007963 -380.979138)
			(xy 341.976811 -380.919344) (xy 341.953046 -380.856249) (xy 341.93701 -380.790762) (xy 341.928932 -380.723826)
			(xy 341.92893 -380.656404) (xy 338.65086 -380.656404) (xy 338.650867 -380.656462) (xy 338.650866 -380.723768)
			(xy 338.64282 -380.790591) (xy 338.626846 -380.855974) (xy 338.603173 -380.918979) (xy 338.57214 -380.978704)
			(xy 338.534192 -381.034291) (xy 338.512404 -381.059944) (xy 338.506607 -381.067089) (xy 338.500092 -381.08428)
			(xy 338.499704 -381.093472) (xy 338.499704 -381.251206) (xy 338.499172 -381.261359) (xy 338.491404 -381.28012)
			(xy 338.47705 -381.294484) (xy 338.458295 -381.302265) (xy 338.448142 -381.302768) (xy 337.731862 -381.302768)
			(xy 337.721703 -381.302298) (xy 337.702934 -381.294512) (xy 337.68857 -381.280139) (xy 337.680796 -381.261366)
			(xy 337.6803 -381.251206) (xy 337.6803 -381.093472) (xy 337.679904 -381.084283) (xy 337.67338 -381.067099)
			(xy 337.6676 -381.059944) (xy 337.645833 -381.034275) (xy 337.607886 -380.97869) (xy 337.576854 -380.918969)
			(xy 337.553182 -380.855966) (xy 337.537209 -380.790587) (xy 337.529164 -380.723766) (xy 337.529162 -380.656464)
			(xy 334.251099 -380.656464) (xy 334.251097 -380.723828) (xy 334.243019 -380.790767) (xy 334.226982 -380.856257)
			(xy 334.203216 -380.919355) (xy 334.172063 -380.979152) (xy 334.133973 -381.034787) (xy 334.112108 -381.060452)
			(xy 334.106308 -381.067595) (xy 334.099795 -381.084787) (xy 334.099408 -381.09398) (xy 334.099408 -381.251206)
			(xy 334.09888 -381.261327) (xy 334.091159 -381.280039) (xy 334.076886 -381.294394) (xy 334.058218 -381.302221)
			(xy 334.0481 -381.302768) (xy 333.33182 -381.302768) (xy 333.321663 -381.302362) (xy 333.302905 -381.294567)
			(xy 333.28858 -381.280165) (xy 333.280885 -381.261365) (xy 333.280512 -381.251206) (xy 333.280512 -381.09398)
			(xy 333.280109 -381.084792) (xy 333.27359 -381.067608) (xy 333.267812 -381.060452) (xy 333.245967 -381.034771)
			(xy 333.207877 -380.979139) (xy 333.176725 -380.919345) (xy 333.152959 -380.85625) (xy 333.136922 -380.790763)
			(xy 333.128844 -380.723826) (xy 333.128842 -380.656404) (xy 303.451069 -380.656404) (xy 303.451067 -380.723828)
			(xy 303.442989 -380.790768) (xy 303.42695 -380.856259) (xy 303.403182 -380.919357) (xy 303.372027 -380.979153)
			(xy 303.333934 -381.034787) (xy 303.312068 -381.060452) (xy 303.306263 -381.067591) (xy 303.299754 -381.084786)
			(xy 303.299368 -381.09398) (xy 303.299368 -381.251206) (xy 303.298878 -381.261332) (xy 303.29115 -381.280052)
			(xy 303.276865 -381.294408) (xy 303.258184 -381.302228) (xy 303.24806 -381.302768) (xy 302.53178 -381.302768)
			(xy 302.521621 -381.302394) (xy 302.502861 -381.294586) (xy 302.488538 -381.280174) (xy 302.480844 -381.261368)
			(xy 302.480472 -381.251206) (xy 302.480472 -381.09398) (xy 302.480078 -381.084791) (xy 302.473554 -381.067607)
			(xy 302.467772 -381.060452) (xy 302.445929 -381.03477) (xy 302.407841 -380.979137) (xy 302.376691 -380.919343)
			(xy 302.352927 -380.856248) (xy 302.336891 -380.790762) (xy 302.328814 -380.723826) (xy 302.328812 -380.656404)
			(xy 299.050742 -380.656404) (xy 299.050749 -380.656462) (xy 299.050747 -380.723768) (xy 299.042702 -380.790592)
			(xy 299.026727 -380.855975) (xy 299.003053 -380.91898) (xy 298.972018 -380.978704) (xy 298.934068 -381.034292)
			(xy 298.91228 -381.059944) (xy 298.90648 -381.067087) (xy 298.899968 -381.084279) (xy 298.89958 -381.093472)
			(xy 298.89958 -381.251206) (xy 298.899072 -381.261362) (xy 298.891299 -381.280128) (xy 298.876938 -381.294492)
			(xy 298.858174 -381.302269) (xy 298.848018 -381.302768) (xy 298.131738 -381.302768) (xy 298.12157 -381.302305)
			(xy 298.102777 -381.294534) (xy 298.088391 -381.28016) (xy 298.080604 -381.261374) (xy 298.080176 -381.251206)
			(xy 298.080176 -381.093472) (xy 298.079785 -381.084283) (xy 298.073258 -381.067098) (xy 298.067476 -381.059944)
			(xy 298.045707 -381.034276) (xy 298.007755 -380.978693) (xy 297.976719 -380.918972) (xy 297.953043 -380.855969)
			(xy 297.937068 -380.790589) (xy 297.929022 -380.723767) (xy 297.92902 -380.656463) (xy 294.650981 -380.656463)
			(xy 294.650979 -380.723828) (xy 294.642901 -380.790768) (xy 294.626863 -380.856258) (xy 294.603096 -380.919356)
			(xy 294.571942 -380.979153) (xy 294.53385 -381.034787) (xy 294.511984 -381.060452) (xy 294.506181 -381.067593)
			(xy 294.499671 -381.084787) (xy 294.499284 -381.09398) (xy 294.499284 -381.251206) (xy 294.498779 -381.26133)
			(xy 294.491054 -381.280047) (xy 294.476773 -381.294402) (xy 294.458097 -381.302225) (xy 294.447976 -381.302768)
			(xy 293.731696 -381.302768) (xy 293.721569 -381.302386) (xy 293.70286 -381.294631) (xy 293.688544 -381.280303)
			(xy 293.680805 -381.261587) (xy 293.680388 -381.25146) (xy 293.680388 -381.09398) (xy 293.67999 -381.084791)
			(xy 293.673468 -381.067607) (xy 293.667688 -381.060452) (xy 293.645844 -381.03477) (xy 293.607756 -380.979138)
			(xy 293.576605 -380.919344) (xy 293.55284 -380.856249) (xy 293.536803 -380.790762) (xy 293.528726 -380.723826)
			(xy 293.528724 -380.656404) (xy 290.250654 -380.656404) (xy 290.250661 -380.656462) (xy 290.25066 -380.723768)
			(xy 290.242614 -380.790591) (xy 290.22664 -380.855974) (xy 290.202966 -380.918979) (xy 290.171933 -380.978704)
			(xy 290.133984 -381.034291) (xy 290.112196 -381.059944) (xy 290.106398 -381.067088) (xy 290.099884 -381.084279)
			(xy 290.099496 -381.093472) (xy 290.099496 -381.251206) (xy 290.098972 -381.26136) (xy 290.091202 -381.280123)
			(xy 290.076846 -381.294486) (xy 290.058088 -381.302267) (xy 290.047934 -381.302768) (xy 289.331654 -381.302768)
			(xy 289.321494 -381.302304) (xy 289.302725 -381.294516) (xy 289.288362 -381.280141) (xy 289.280588 -381.261366)
			(xy 289.280092 -381.251206) (xy 289.280092 -381.093472) (xy 289.279697 -381.084283) (xy 289.273173 -381.067099)
			(xy 289.267392 -381.059944) (xy 289.245622 -381.034276) (xy 289.207669 -380.978693) (xy 289.176632 -380.918972)
			(xy 289.152956 -380.85597) (xy 289.13698 -380.790589) (xy 289.128934 -380.723767) (xy 289.128932 -380.656463)
			(xy 272.92786 -380.656463) (xy 272.867822 -380.687974) (xy 272.746027 -380.742789) (xy 272.621144 -380.790151)
			(xy 272.49363 -380.829886) (xy 272.363949 -380.861849) (xy 272.232575 -380.885924) (xy 272.099987 -380.902024)
			(xy 271.966669 -380.910088) (xy 271.833107 -380.910088) (xy 271.699789 -380.902024) (xy 271.567201 -380.885924)
			(xy 271.435827 -380.861849) (xy 271.306146 -380.829886) (xy 271.178632 -380.790151) (xy 271.053749 -380.742789)
			(xy 270.931954 -380.687974) (xy 270.813691 -380.625904) (xy 270.699392 -380.556808) (xy 270.589472 -380.480936)
			(xy 270.484335 -380.398566) (xy 270.384362 -380.309998) (xy 270.28992 -380.215556) (xy 270.201352 -380.115583)
			(xy 270.118982 -380.010446) (xy 270.04311 -379.900526) (xy 269.974014 -379.786227) (xy 269.911944 -379.667964)
			(xy 269.857129 -379.546169) (xy 269.809767 -379.421286) (xy 269.770032 -379.293772) (xy 269.738069 -379.164091)
			(xy 269.713994 -379.032717) (xy 269.697894 -378.900129) (xy 269.68983 -378.766811) (xy 236.356885 -378.766811)
			(xy 237.084108 -379.494034) (xy 237.084616 -379.494542) (xy 237.093852 -379.502751) (xy 237.116722 -379.512039)
			(xy 237.129066 -379.512576) (xy 239.773968 -379.512576) (xy 239.786313 -379.512049) (xy 239.809185 -379.502755)
			(xy 239.818418 -379.494542) (xy 239.818926 -379.494034) (xy 240.443004 -378.869702) (xy 240.450409 -378.862868)
			(xy 240.469004 -378.855145) (xy 240.479072 -378.854716) (xy 262.036814 -378.854716) (xy 262.046885 -378.85513)
			(xy 262.065482 -378.862858) (xy 262.072882 -378.869702) (xy 262.259318 -379.056138) (xy 262.26617 -379.063529)
			(xy 262.273882 -379.082135) (xy 262.274304 -379.092206) (xy 262.274304 -382.223705) (xy 286.928753 -382.223705)
			(xy 286.928754 -382.15628) (xy 286.936832 -382.08934) (xy 286.95287 -382.02385) (xy 286.976638 -381.960752)
			(xy 287.007792 -381.900956) (xy 287.045886 -381.845322) (xy 287.067752 -381.819658) (xy 287.073555 -381.812518)
			(xy 287.080065 -381.795323) (xy 287.080452 -381.78613) (xy 287.080452 -381.628904) (xy 287.080987 -381.618801)
			(xy 287.088715 -381.600133) (xy 287.102996 -381.585839) (xy 287.121658 -381.578096) (xy 287.13176 -381.577596)
			(xy 287.84804 -381.577596) (xy 287.858151 -381.578052) (xy 287.876829 -381.585802) (xy 287.891122 -381.600108)
			(xy 287.898856 -381.618793) (xy 287.899348 -381.628904) (xy 287.899348 -381.78613) (xy 287.899755 -381.795317)
			(xy 287.906272 -381.812501) (xy 287.912048 -381.819658) (xy 287.933904 -381.84533) (xy 287.971996 -381.900963)
			(xy 288.00315 -381.960757) (xy 288.026917 -382.023853) (xy 288.042955 -382.089342) (xy 288.051033 -382.156281)
			(xy 288.051034 -382.223645) (xy 291.329073 -382.223645) (xy 291.329074 -382.15634) (xy 291.337119 -382.089516)
			(xy 291.353093 -382.024133) (xy 291.376767 -381.961128) (xy 291.407801 -381.901405) (xy 291.445751 -381.845818)
			(xy 291.46754 -381.820166) (xy 291.473339 -381.813022) (xy 291.479851 -381.795831) (xy 291.48024 -381.786638)
			(xy 291.48024 -381.628904) (xy 291.48062 -381.618777) (xy 291.488375 -381.600066) (xy 291.502703 -381.58575)
			(xy 291.52142 -381.578012) (xy 291.531548 -381.577596) (xy 292.248082 -381.577596) (xy 292.258202 -381.57814)
			(xy 292.276915 -381.585854) (xy 292.29127 -381.600122) (xy 292.299098 -381.618787) (xy 292.299644 -381.628904)
			(xy 292.299644 -381.786638) (xy 292.300049 -381.795826) (xy 292.306568 -381.813009) (xy 292.312344 -381.820166)
			(xy 292.334122 -381.845826) (xy 292.372072 -381.901411) (xy 292.403107 -381.961133) (xy 292.426781 -382.024137)
			(xy 292.442755 -382.089518) (xy 292.450801 -382.15634) (xy 292.450801 -382.223645) (xy 292.450794 -382.223705)
			(xy 295.728841 -382.223705) (xy 295.728842 -382.15628) (xy 295.73692 -382.08934) (xy 295.752957 -382.02385)
			(xy 295.776724 -381.960753) (xy 295.807878 -381.900957) (xy 295.84597 -381.845323) (xy 295.867836 -381.819658)
			(xy 295.873637 -381.812516) (xy 295.880148 -381.795323) (xy 295.880536 -381.78613) (xy 295.880536 -381.628904)
			(xy 295.88092 -381.618777) (xy 295.888674 -381.600067) (xy 295.903001 -381.585751) (xy 295.921717 -381.578012)
			(xy 295.931844 -381.577596) (xy 296.648124 -381.577596) (xy 296.658234 -381.578065) (xy 296.676912 -381.58581)
			(xy 296.691206 -381.600112) (xy 296.69894 -381.618794) (xy 296.699432 -381.628904) (xy 296.699432 -381.78613)
			(xy 296.699843 -381.795317) (xy 296.706358 -381.8125) (xy 296.712132 -381.819658) (xy 296.733985 -381.845332)
			(xy 296.772072 -381.900966) (xy 296.803221 -381.960761) (xy 296.826985 -382.023857) (xy 296.84302 -382.089345)
			(xy 296.851096 -382.156281) (xy 296.851097 -382.223704) (xy 296.851097 -382.223705) (xy 300.128632 -382.223705)
			(xy 300.128633 -382.15628) (xy 300.13671 -382.089341) (xy 300.152748 -382.023851) (xy 300.176514 -381.960753)
			(xy 300.207667 -381.900957) (xy 300.245759 -381.845323) (xy 300.267624 -381.819658) (xy 300.273424 -381.812515)
			(xy 300.279936 -381.795323) (xy 300.280324 -381.78613) (xy 300.280324 -381.628904) (xy 300.28072 -381.618779)
			(xy 300.288471 -381.600071) (xy 300.302794 -381.585755) (xy 300.321507 -381.578014) (xy 300.331632 -381.577596)
			(xy 301.047912 -381.577596) (xy 301.058021 -381.578075) (xy 301.076699 -381.585816) (xy 301.090993 -381.600115)
			(xy 301.098728 -381.618795) (xy 301.09922 -381.628904) (xy 301.09922 -381.78613) (xy 301.099611 -381.795319)
			(xy 301.106138 -381.812504) (xy 301.11192 -381.819658) (xy 301.133773 -381.845332) (xy 301.171861 -381.900965)
			(xy 301.203011 -381.960761) (xy 301.226775 -382.023856) (xy 301.242811 -382.089344) (xy 301.250887 -382.156281)
			(xy 301.250888 -382.223646) (xy 330.929191 -382.223646) (xy 330.929192 -382.156339) (xy 330.937238 -382.089516)
			(xy 330.953213 -382.024133) (xy 330.976888 -381.961128) (xy 331.007923 -381.901404) (xy 331.045875 -381.845818)
			(xy 331.067664 -381.820166) (xy 331.073465 -381.813025) (xy 331.079975 -381.795831) (xy 331.080364 -381.786638)
			(xy 331.080364 -381.628904) (xy 331.080824 -381.618755) (xy 331.088612 -381.600009) (xy 331.102996 -381.585687)
			(xy 331.121775 -381.577981) (xy 331.131926 -381.577596) (xy 331.848206 -381.577596) (xy 331.858328 -381.57812)
			(xy 331.877041 -381.585842) (xy 331.891395 -381.600116) (xy 331.899222 -381.618785) (xy 331.899768 -381.628904)
			(xy 331.899768 -381.786638) (xy 331.900167 -381.795826) (xy 331.906689 -381.81301) (xy 331.912468 -381.820166)
			(xy 331.934246 -381.845826) (xy 331.972195 -381.901412) (xy 332.003228 -381.961134) (xy 332.026901 -382.024138)
			(xy 332.042874 -382.089519) (xy 332.050919 -382.15634) (xy 332.05092 -382.223645) (xy 332.050913 -382.223704)
			(xy 335.328984 -382.223704) (xy 335.328985 -382.156281) (xy 335.337061 -382.089342) (xy 335.353096 -382.023853)
			(xy 335.37686 -381.960756) (xy 335.40801 -381.900959) (xy 335.446097 -381.845324) (xy 335.46796 -381.819658)
			(xy 335.473764 -381.812519) (xy 335.480273 -381.795323) (xy 335.48066 -381.78613) (xy 335.48066 -381.628904)
			(xy 335.481187 -381.6188) (xy 335.488916 -381.60013) (xy 335.5032 -381.585837) (xy 335.521865 -381.578095)
			(xy 335.531968 -381.577596) (xy 336.248248 -381.577596) (xy 336.258359 -381.578046) (xy 336.277038 -381.585799)
			(xy 336.291331 -381.600106) (xy 336.299064 -381.618792) (xy 336.299556 -381.628904) (xy 336.299556 -381.78613)
			(xy 336.299962 -381.795317) (xy 336.30648 -381.812501) (xy 336.312256 -381.819658) (xy 336.334112 -381.845331)
			(xy 336.372204 -381.900963) (xy 336.403357 -381.960758) (xy 336.427124 -382.023854) (xy 336.443161 -382.089342)
			(xy 336.451239 -382.156281) (xy 336.45124 -382.223645) (xy 339.729279 -382.223645) (xy 339.72928 -382.156339)
			(xy 339.737325 -382.089516) (xy 339.753299 -382.024133) (xy 339.776974 -381.961128) (xy 339.808009 -381.901404)
			(xy 339.845959 -381.845818) (xy 339.867748 -381.820166) (xy 339.873547 -381.813023) (xy 339.880059 -381.795831)
			(xy 339.880448 -381.786638) (xy 339.880448 -381.628904) (xy 339.880924 -381.618757) (xy 339.888708 -381.600014)
			(xy 339.903088 -381.585693) (xy 339.921861 -381.577984) (xy 339.93201 -381.577596) (xy 340.64829 -381.577596)
			(xy 340.658411 -381.578133) (xy 340.677123 -381.58585) (xy 340.691478 -381.60012) (xy 340.699306 -381.618786)
			(xy 340.699852 -381.628904) (xy 340.699852 -381.786638) (xy 340.700255 -381.795826) (xy 340.706775 -381.813009)
			(xy 340.712552 -381.820166) (xy 340.73433 -381.845826) (xy 340.77228 -381.901411) (xy 340.803314 -381.961134)
			(xy 340.826988 -382.024137) (xy 340.842962 -382.089518) (xy 340.851007 -382.15634) (xy 340.851007 -382.223645)
			(xy 344.12907 -382.223645) (xy 344.129071 -382.15634) (xy 344.137116 -382.089516) (xy 344.15309 -382.024134)
			(xy 344.176764 -381.961129) (xy 344.207798 -381.901405) (xy 344.245748 -381.845818) (xy 344.267536 -381.820166)
			(xy 344.273334 -381.813022) (xy 344.279847 -381.79583) (xy 344.280236 -381.786638) (xy 344.280236 -381.628904)
			(xy 344.280626 -381.618746) (xy 344.288427 -381.599986) (xy 344.302834 -381.585662) (xy 344.321637 -381.577968)
			(xy 344.331798 -381.577596) (xy 345.048078 -381.577596) (xy 345.058198 -381.578143) (xy 345.07691 -381.585856)
			(xy 345.091266 -381.600123) (xy 345.099094 -381.618787) (xy 345.09964 -381.628904) (xy 345.09964 -381.786638)
			(xy 345.100045 -381.795825) (xy 345.106564 -381.813009) (xy 345.11234 -381.820166) (xy 345.134118 -381.845826)
			(xy 345.172069 -381.901411) (xy 345.203104 -381.961133) (xy 345.226778 -382.024137) (xy 345.242752 -382.089518)
			(xy 345.250798 -382.15634) (xy 345.250798 -382.223645) (xy 345.250798 -382.223646) (xy 374.9291 -382.223646)
			(xy 374.929101 -382.156339) (xy 374.937147 -382.089515) (xy 374.953122 -382.024132) (xy 374.976798 -381.961127)
			(xy 375.007834 -381.901404) (xy 375.045787 -381.845818) (xy 375.067576 -381.820166) (xy 375.073367 -381.813016)
			(xy 375.079886 -381.795829) (xy 375.080276 -381.786638) (xy 375.080276 -381.628904) (xy 375.080724 -381.618753)
			(xy 375.088514 -381.600005) (xy 375.102902 -381.585683) (xy 375.121685 -381.577979) (xy 375.131838 -381.577596)
			(xy 375.848118 -381.577596) (xy 375.85824 -381.57811) (xy 375.876954 -381.585836) (xy 375.891308 -381.600113)
			(xy 375.899134 -381.618784) (xy 375.89968 -381.628904) (xy 375.89968 -381.786638) (xy 375.900076 -381.795827)
			(xy 375.9066 -381.813011) (xy 375.91238 -381.820166) (xy 375.934157 -381.845826) (xy 375.972105 -381.901412)
			(xy 376.003138 -381.961135) (xy 376.02681 -382.024138) (xy 376.042784 -382.089519) (xy 376.050828 -382.156341)
			(xy 376.050829 -382.223644) (xy 376.050822 -382.223704) (xy 379.328893 -382.223704) (xy 379.328894 -382.156281)
			(xy 379.33697 -382.089342) (xy 379.353006 -382.023853) (xy 379.37677 -381.960756) (xy 379.40792 -381.900959)
			(xy 379.446008 -381.845324) (xy 379.467872 -381.819658) (xy 379.473678 -381.81252) (xy 379.480185 -381.795324)
			(xy 379.480572 -381.78613) (xy 379.480572 -381.628904) (xy 379.481088 -381.618799) (xy 379.488819 -381.600126)
			(xy 379.503106 -381.585832) (xy 379.521775 -381.578092) (xy 379.53188 -381.577596) (xy 380.24816 -381.577596)
			(xy 380.258279 -381.578049) (xy 380.276981 -381.585783) (xy 380.291297 -381.600088) (xy 380.299044 -381.618785)
			(xy 380.299468 -381.628904) (xy 380.299468 -381.78613) (xy 380.299871 -381.795318) (xy 380.30639 -381.812502)
			(xy 380.312168 -381.819658) (xy 380.334023 -381.845331) (xy 380.372114 -381.900963) (xy 380.403267 -381.960758)
			(xy 380.427033 -382.023854) (xy 380.443071 -382.089343) (xy 380.451148 -382.156281) (xy 380.451149 -382.223646)
			(xy 383.729188 -382.223646) (xy 383.729189 -382.156339) (xy 383.737235 -382.089516) (xy 383.753209 -382.024133)
			(xy 383.776884 -381.961128) (xy 383.80792 -381.901404) (xy 383.845871 -381.845818) (xy 383.86766 -381.820166)
			(xy 383.873461 -381.813024) (xy 383.879971 -381.795831) (xy 383.88036 -381.786638) (xy 383.88036 -381.628904)
			(xy 383.880824 -381.618755) (xy 383.888611 -381.600011) (xy 383.902994 -381.585689) (xy 383.921771 -381.577981)
			(xy 383.931922 -381.577596) (xy 384.648202 -381.577596) (xy 384.658323 -381.578124) (xy 384.677036 -381.585844)
			(xy 384.691391 -381.600117) (xy 384.699218 -381.618786) (xy 384.699764 -381.628904) (xy 384.699764 -381.786638)
			(xy 384.700164 -381.795826) (xy 384.706686 -381.81301) (xy 384.712464 -381.820166) (xy 384.734242 -381.845826)
			(xy 384.772191 -381.901412) (xy 384.803224 -381.961134) (xy 384.826898 -382.024137) (xy 384.842871 -382.089519)
			(xy 384.850916 -382.15634) (xy 384.850917 -382.223645) (xy 388.128979 -382.223645) (xy 388.12898 -382.156339)
			(xy 388.137025 -382.089516) (xy 388.152999 -382.024133) (xy 388.176674 -381.961128) (xy 388.207709 -381.901404)
			(xy 388.245659 -381.845818) (xy 388.267448 -381.820166) (xy 388.273247 -381.813023) (xy 388.279759 -381.795831)
			(xy 388.280148 -381.786638) (xy 388.280148 -381.628904) (xy 388.280624 -381.618757) (xy 388.288408 -381.600014)
			(xy 388.302788 -381.585693) (xy 388.321561 -381.577984) (xy 388.33171 -381.577596) (xy 389.04799 -381.577596)
			(xy 389.058111 -381.578133) (xy 389.076823 -381.58585) (xy 389.091178 -381.60012) (xy 389.099006 -381.618786)
			(xy 389.099552 -381.628904) (xy 389.099552 -381.786638) (xy 389.099955 -381.795826) (xy 389.106475 -381.813009)
			(xy 389.112252 -381.820166) (xy 389.13403 -381.845826) (xy 389.17198 -381.901411) (xy 389.203014 -381.961134)
			(xy 389.226688 -382.024137) (xy 389.242662 -382.089518) (xy 389.250707 -382.15634) (xy 389.250707 -382.223645)
			(xy 389.250707 -382.223646) (xy 418.92901 -382.223646) (xy 418.92901 -382.156339) (xy 418.937056 -382.089515)
			(xy 418.953032 -382.024132) (xy 418.976708 -381.961127) (xy 419.007745 -381.901403) (xy 419.045698 -381.845818)
			(xy 419.067488 -381.820166) (xy 419.07328 -381.813018) (xy 419.079798 -381.79583) (xy 419.080188 -381.786638)
			(xy 419.080188 -381.628904) (xy 419.080688 -381.618797) (xy 419.088422 -381.600121) (xy 419.102714 -381.585827)
			(xy 419.121389 -381.57809) (xy 419.131496 -381.577596) (xy 419.84803 -381.577596) (xy 419.858153 -381.578101)
			(xy 419.876867 -381.58583) (xy 419.89122 -381.60011) (xy 419.899046 -381.618783) (xy 419.899592 -381.628904)
			(xy 419.899592 -381.786638) (xy 419.899986 -381.795827) (xy 419.906511 -381.813011) (xy 419.912292 -381.820166)
			(xy 419.934069 -381.845827) (xy 419.972016 -381.901413) (xy 420.003048 -381.961135) (xy 420.02672 -382.024139)
			(xy 420.042693 -382.089519) (xy 420.050737 -382.156341) (xy 420.050738 -382.223644) (xy 420.050731 -382.223705)
			(xy 423.328802 -382.223705) (xy 423.328803 -382.15628) (xy 423.33688 -382.089342) (xy 423.352916 -382.023852)
			(xy 423.37668 -381.960755) (xy 423.407831 -381.900959) (xy 423.44592 -381.845324) (xy 423.467784 -381.819658)
			(xy 423.473579 -381.812512) (xy 423.480095 -381.795322) (xy 423.480484 -381.78613) (xy 423.480484 -381.628904)
			(xy 423.480988 -381.618798) (xy 423.488721 -381.600122) (xy 423.503012 -381.585828) (xy 423.521686 -381.57809)
			(xy 423.531792 -381.577596) (xy 424.248072 -381.577596) (xy 424.258192 -381.578039) (xy 424.276895 -381.585777)
			(xy 424.29121 -381.600085) (xy 424.298957 -381.618784) (xy 424.29938 -381.628904) (xy 424.29938 -381.78613)
			(xy 424.29978 -381.795318) (xy 424.306301 -381.812502) (xy 424.31208 -381.819658) (xy 424.333935 -381.845331)
			(xy 424.372025 -381.900964) (xy 424.403177 -381.960759) (xy 424.426943 -382.023855) (xy 424.44298 -382.089343)
			(xy 424.451057 -382.156281) (xy 424.451058 -382.223646) (xy 427.729097 -382.223646) (xy 427.729098 -382.156339)
			(xy 427.737144 -382.089515) (xy 427.753119 -382.024132) (xy 427.776794 -381.961127) (xy 427.807831 -381.901404)
			(xy 427.845783 -381.845818) (xy 427.867572 -381.820166) (xy 427.873374 -381.813025) (xy 427.879883 -381.795831)
			(xy 427.880272 -381.786638) (xy 427.880272 -381.628904) (xy 427.880724 -381.618754) (xy 427.888513 -381.600007)
			(xy 427.9029 -381.585684) (xy 427.921682 -381.577979) (xy 427.931834 -381.577596) (xy 428.648114 -381.577596)
			(xy 428.658236 -381.578114) (xy 428.676949 -381.585838) (xy 428.691303 -381.600114) (xy 428.69913 -381.618785)
			(xy 428.699676 -381.628904) (xy 428.699676 -381.786638) (xy 428.700073 -381.795826) (xy 428.706596 -381.81301)
			(xy 428.712376 -381.820166) (xy 428.734154 -381.845826) (xy 428.772102 -381.901412) (xy 428.803135 -381.961135)
			(xy 428.826807 -382.024138) (xy 428.84278 -382.089519) (xy 428.850825 -382.15634) (xy 428.850826 -382.223644)
			(xy 428.850826 -382.223646) (xy 432.128888 -382.223646) (xy 432.128889 -382.156339) (xy 432.136935 -382.089516)
			(xy 432.152909 -382.024133) (xy 432.176584 -381.961128) (xy 432.20762 -381.901404) (xy 432.245571 -381.845818)
			(xy 432.26736 -381.820166) (xy 432.273161 -381.813024) (xy 432.279671 -381.795831) (xy 432.28006 -381.786638)
			(xy 432.28006 -381.628904) (xy 432.280524 -381.618755) (xy 432.288311 -381.600011) (xy 432.302694 -381.585689)
			(xy 432.321471 -381.577981) (xy 432.331622 -381.577596) (xy 433.047902 -381.577596) (xy 433.058023 -381.578124)
			(xy 433.076736 -381.585844) (xy 433.091091 -381.600117) (xy 433.098918 -381.618786) (xy 433.099464 -381.628904)
			(xy 433.099464 -381.786638) (xy 433.099864 -381.795826) (xy 433.106386 -381.81301) (xy 433.112164 -381.820166)
			(xy 433.133942 -381.845826) (xy 433.171891 -381.901412) (xy 433.202924 -381.961134) (xy 433.226598 -382.024137)
			(xy 433.242571 -382.089519) (xy 433.250616 -382.15634) (xy 433.250617 -382.223645) (xy 433.242574 -382.290466)
			(xy 433.226602 -382.355848) (xy 433.202931 -382.418852) (xy 433.171899 -382.478576) (xy 433.133951 -382.534162)
			(xy 433.112164 -382.559814) (xy 433.106374 -382.566964) (xy 433.099856 -382.584151) (xy 433.099464 -382.593342)
			(xy 433.099464 -383.086864) (xy 433.0999 -383.096048) (xy 433.106397 -383.113232) (xy 433.112164 -383.120392)
			(xy 433.133967 -383.146031) (xy 433.171916 -383.20162) (xy 433.202948 -383.261345) (xy 433.226386 -383.323727)
			(xy 434.32903 -383.323727) (xy 434.329034 -383.256419) (xy 434.337081 -383.189595) (xy 434.353057 -383.124211)
			(xy 434.376732 -383.061205) (xy 434.407768 -383.00148) (xy 434.445719 -382.945893) (xy 434.467508 -382.92024)
			(xy 434.473313 -382.913101) (xy 434.479823 -382.895906) (xy 434.480208 -382.886712) (xy 434.480208 -382.728724)
			(xy 434.480641 -382.71857) (xy 434.48843 -382.699817) (xy 434.502824 -382.685492) (xy 434.521614 -382.677793)
			(xy 434.53177 -382.677416) (xy 435.24805 -382.677416) (xy 435.258171 -382.677967) (xy 435.276886 -382.685674)
			(xy 435.291243 -382.69994) (xy 435.299068 -382.718607) (xy 435.299612 -382.728724) (xy 435.299612 -382.886712)
			(xy 435.300014 -382.8959) (xy 435.306533 -382.913084) (xy 435.312312 -382.92024) (xy 435.334066 -382.945921)
			(xy 435.372019 -383.001502) (xy 435.403056 -383.061221) (xy 435.426733 -383.124222) (xy 435.44271 -383.189601)
			(xy 435.450758 -383.256421) (xy 435.450761 -383.323724) (xy 435.44272 -383.390546) (xy 435.426749 -383.455926)
			(xy 435.403079 -383.518929) (xy 435.372047 -383.578652) (xy 435.334099 -383.634237) (xy 435.312312 -383.659888)
			(xy 435.306497 -383.66702) (xy 435.299993 -383.684221) (xy 435.299612 -383.693416) (xy 435.299612 -384.186684)
			(xy 435.300027 -384.195871) (xy 435.306537 -384.213055) (xy 435.312312 -384.220212) (xy 435.334137 -384.245834)
			(xy 435.372087 -384.301424) (xy 435.403122 -384.361151) (xy 435.426795 -384.42416) (xy 435.442767 -384.489546)
			(xy 435.450809 -384.556373) (xy 435.450805 -384.623681) (xy 435.442757 -384.690507) (xy 435.426779 -384.755892)
			(xy 435.4031 -384.818898) (xy 435.37206 -384.878623) (xy 435.334103 -384.934208) (xy 435.312312 -384.95986)
			(xy 435.306509 -384.967001) (xy 435.299998 -384.984195) (xy 435.299612 -384.993388) (xy 435.299612 -385.151376)
			(xy 435.299159 -385.161527) (xy 435.291374 -385.180277) (xy 435.276987 -385.194601) (xy 435.258203 -385.202303)
			(xy 435.24805 -385.202684) (xy 434.53177 -385.202684) (xy 434.521644 -385.202199) (xy 434.502927 -385.194466)
			(xy 434.488573 -385.180179) (xy 434.48075 -385.161499) (xy 434.480208 -385.151376) (xy 434.480208 -384.993388)
			(xy 434.479802 -384.9842) (xy 434.473285 -384.967016) (xy 434.467508 -384.95986) (xy 434.445757 -384.934178)
			(xy 434.407809 -384.878595) (xy 434.376776 -384.818876) (xy 434.353102 -384.755875) (xy 434.337128 -384.690497)
			(xy 434.329081 -384.623678) (xy 434.329078 -384.556376) (xy 434.337118 -384.489557) (xy 434.353086 -384.424177)
			(xy 434.376753 -384.361174) (xy 434.407781 -384.301451) (xy 434.445723 -384.245864) (xy 434.467508 -384.220212)
			(xy 434.473325 -384.213082) (xy 434.479827 -384.19588) (xy 434.480208 -384.186684) (xy 434.480208 -383.693416)
			(xy 434.479788 -383.68423) (xy 434.473281 -383.667046) (xy 434.467508 -383.659888) (xy 434.445686 -383.634265)
			(xy 434.40774 -383.578673) (xy 434.37671 -383.518945) (xy 434.353041 -383.455937) (xy 434.337071 -383.390552)
			(xy 434.32903 -383.323727) (xy 433.226386 -383.323727) (xy 433.22662 -383.324351) (xy 433.242592 -383.389735)
			(xy 433.250634 -383.456559) (xy 433.250633 -383.523865) (xy 433.242587 -383.590689) (xy 433.226613 -383.656072)
			(xy 433.202938 -383.719077) (xy 433.171903 -383.778801) (xy 433.133953 -383.834388) (xy 433.112164 -383.86004)
			(xy 433.106363 -383.867182) (xy 433.099852 -383.884375) (xy 433.099464 -383.893568) (xy 433.099464 -384.051556)
			(xy 433.099042 -384.061712) (xy 433.091254 -384.08047) (xy 433.076856 -384.094796) (xy 433.05806 -384.102491)
			(xy 433.047902 -384.102864) (xy 432.331622 -384.102864) (xy 432.321497 -384.102356) (xy 432.302777 -384.094636)
			(xy 432.28842 -384.080356) (xy 432.2806 -384.061678) (xy 432.28006 -384.051556) (xy 432.28006 -383.893568)
			(xy 432.279652 -383.884381) (xy 432.273135 -383.867197) (xy 432.26736 -383.86004) (xy 432.245587 -383.834375)
			(xy 432.207637 -383.778791) (xy 432.176602 -383.719069) (xy 432.152927 -383.656066) (xy 432.136952 -383.590686)
			(xy 432.128907 -383.523864) (xy 432.128905 -383.45656) (xy 432.136948 -383.389738) (xy 432.15292 -383.324357)
			(xy 432.176592 -383.261353) (xy 432.207624 -383.20163) (xy 432.245573 -383.146044) (xy 432.26736 -383.120392)
			(xy 432.27315 -383.113242) (xy 432.279667 -383.096055) (xy 432.28006 -383.086864) (xy 432.28006 -382.593342)
			(xy 432.279616 -382.584159) (xy 432.273125 -382.566975) (xy 432.26736 -382.559814) (xy 432.245562 -382.53417)
			(xy 432.207612 -382.478583) (xy 432.176578 -382.418858) (xy 432.152905 -382.355853) (xy 432.136932 -382.290469)
			(xy 432.128888 -382.223646) (xy 428.850826 -382.223646) (xy 428.842783 -382.290466) (xy 428.826812 -382.355848)
			(xy 428.803141 -382.418852) (xy 428.772109 -382.478575) (xy 428.734163 -382.534162) (xy 428.712376 -382.559814)
			(xy 428.706588 -382.566965) (xy 428.700069 -382.584151) (xy 428.699676 -382.593342) (xy 428.699676 -383.086864)
			(xy 428.700109 -383.096049) (xy 428.706607 -383.113233) (xy 428.712376 -383.120392) (xy 428.734179 -383.146031)
			(xy 428.772126 -383.20162) (xy 428.803158 -383.261345) (xy 428.826616 -383.323786) (xy 429.928711 -383.323786)
			(xy 429.928714 -383.25636) (xy 429.936794 -383.189418) (xy 429.952834 -383.123927) (xy 429.976603 -383.060829)
			(xy 430.007759 -383.001032) (xy 430.045853 -382.945397) (xy 430.06772 -382.919732) (xy 430.07353 -382.912597)
			(xy 430.080036 -382.895398) (xy 430.08042 -382.886204) (xy 430.08042 -382.728724) (xy 430.080836 -382.718601)
			(xy 430.08858 -382.699894) (xy 430.102897 -382.685578) (xy 430.121605 -382.677835) (xy 430.131728 -382.677416)
			(xy 430.848008 -382.677416) (xy 430.858133 -382.67781) (xy 430.87684 -382.685564) (xy 430.891154 -382.699887)
			(xy 430.898896 -382.718599) (xy 430.899316 -382.728724) (xy 430.899316 -382.886204) (xy 430.899721 -382.895392)
			(xy 430.906238 -382.912576) (xy 430.912016 -382.919732) (xy 430.933844 -382.945427) (xy 430.971933 -383.001057)
			(xy 431.003084 -383.06085) (xy 431.02685 -383.123943) (xy 431.042887 -383.189428) (xy 431.050966 -383.256363)
			(xy 431.050969 -383.323783) (xy 431.042897 -383.390719) (xy 431.026866 -383.456206) (xy 431.003106 -383.519301)
			(xy 430.971961 -383.579096) (xy 430.933877 -383.634731) (xy 430.912016 -383.660396) (xy 430.90624 -383.667556)
			(xy 430.899713 -383.684735) (xy 430.899316 -383.693924) (xy 430.899316 -384.186176) (xy 430.899734 -384.195362)
			(xy 430.906242 -384.212547) (xy 430.912016 -384.219704) (xy 430.933915 -384.24534) (xy 430.972001 -384.300979)
			(xy 431.00315 -384.36078) (xy 431.026911 -384.42388) (xy 431.042944 -384.489373) (xy 431.051016 -384.556314)
			(xy 431.051013 -384.62374) (xy 431.042934 -384.690681) (xy 431.026895 -384.756171) (xy 431.003128 -384.81927)
			(xy 430.971974 -384.879067) (xy 430.933882 -384.934702) (xy 430.912016 -384.960368) (xy 430.90621 -384.967507)
			(xy 430.8997 -384.984702) (xy 430.899316 -384.993896) (xy 430.899316 -385.151376) (xy 430.898865 -385.161495)
			(xy 430.891128 -385.180195) (xy 430.876822 -385.19451) (xy 430.858127 -385.202259) (xy 430.848008 -385.202684)
			(xy 430.131728 -385.202684) (xy 430.121605 -385.202261) (xy 430.102899 -385.194519) (xy 430.088583 -385.180204)
			(xy 430.08084 -385.161499) (xy 430.08042 -385.151376) (xy 430.08042 -384.993896) (xy 430.080008 -384.984709)
			(xy 430.073495 -384.967525) (xy 430.06772 -384.960368) (xy 430.045891 -384.934674) (xy 430.0078 -384.879044)
			(xy 429.976646 -384.819252) (xy 429.952879 -384.756159) (xy 429.936841 -384.690673) (xy 429.928761 -384.623738)
			(xy 429.928758 -384.556316) (xy 429.936831 -384.48938) (xy 429.952863 -384.423893) (xy 429.976624 -384.360797)
			(xy 430.007772 -384.301002) (xy 430.045857 -384.245369) (xy 430.06772 -384.219704) (xy 430.0735 -384.212547)
			(xy 430.080024 -384.195365) (xy 430.08042 -384.186176) (xy 430.08042 -383.693924) (xy 430.079994 -383.684739)
			(xy 430.073491 -383.667554) (xy 430.06772 -383.660396) (xy 430.04582 -383.63476) (xy 430.007731 -383.579122)
			(xy 429.976581 -383.519322) (xy 429.952818 -383.456221) (xy 429.936784 -383.390728) (xy 429.928711 -383.323786)
			(xy 428.826616 -383.323786) (xy 428.826829 -383.324352) (xy 428.842801 -383.389735) (xy 428.850843 -383.456559)
			(xy 428.850842 -383.523865) (xy 428.842797 -383.590688) (xy 428.826822 -383.656071) (xy 428.803148 -383.719077)
			(xy 428.772114 -383.778801) (xy 428.734164 -383.834388) (xy 428.712376 -383.86004) (xy 428.706577 -383.867183)
			(xy 428.700065 -383.884375) (xy 428.699676 -383.893568) (xy 428.699676 -384.051556) (xy 428.699242 -384.06171)
			(xy 428.691456 -384.080466) (xy 428.677063 -384.094792) (xy 428.65827 -384.102489) (xy 428.648114 -384.102864)
			(xy 427.931834 -384.102864) (xy 427.92171 -384.102345) (xy 427.90299 -384.09463) (xy 427.888633 -384.080353)
			(xy 427.880812 -384.061677) (xy 427.880272 -384.051556) (xy 427.880272 -383.893568) (xy 427.879883 -383.884378)
			(xy 427.873355 -383.867194) (xy 427.867572 -383.86004) (xy 427.845799 -383.834375) (xy 427.807848 -383.778791)
			(xy 427.776812 -383.71907) (xy 427.753137 -383.656067) (xy 427.737162 -383.590686) (xy 427.729116 -383.523864)
			(xy 427.729114 -383.45656) (xy 427.737157 -383.389738) (xy 427.75313 -383.324356) (xy 427.776802 -383.261352)
			(xy 427.807835 -383.201629) (xy 427.845784 -383.146044) (xy 427.867572 -383.120392) (xy 427.873363 -383.113243)
			(xy 427.879879 -383.096055) (xy 427.880272 -383.086864) (xy 427.880272 -382.593342) (xy 427.879848 -382.584156)
			(xy 427.873344 -382.566971) (xy 427.867572 -382.559814) (xy 427.845774 -382.53417) (xy 427.807823 -382.478583)
			(xy 427.776788 -382.418859) (xy 427.753115 -382.355853) (xy 427.737141 -382.29047) (xy 427.729097 -382.223646)
			(xy 424.451058 -382.223646) (xy 424.451058 -382.223704) (xy 424.442983 -382.290642) (xy 424.426948 -382.356131)
			(xy 424.403184 -382.419227) (xy 424.372033 -382.479023) (xy 424.333944 -382.534657) (xy 424.31208 -382.560322)
			(xy 424.306289 -382.567471) (xy 424.299772 -382.584659) (xy 424.29938 -382.59385) (xy 424.29938 -383.086356)
			(xy 424.299816 -383.09554) (xy 424.306312 -383.112725) (xy 424.31208 -383.119884) (xy 424.33396 -383.145536)
			(xy 424.37205 -383.201172) (xy 424.403201 -383.26097) (xy 424.426837 -383.323727) (xy 425.528942 -383.323727)
			(xy 425.528946 -383.256419) (xy 425.536993 -383.189594) (xy 425.55297 -383.12421) (xy 425.576646 -383.061204)
			(xy 425.607682 -383.00148) (xy 425.645635 -382.945892) (xy 425.667424 -382.92024) (xy 425.673231 -382.913103)
			(xy 425.679739 -382.895906) (xy 425.680124 -382.886712) (xy 425.680124 -382.728724) (xy 425.680536 -382.7186)
			(xy 425.688281 -382.699892) (xy 425.702599 -382.685576) (xy 425.721308 -382.677834) (xy 425.731432 -382.677416)
			(xy 426.447966 -382.677416) (xy 426.458088 -382.677954) (xy 426.476803 -382.685666) (xy 426.49116 -382.699937)
			(xy 426.498984 -382.718606) (xy 426.499528 -382.728724) (xy 426.499528 -382.886712) (xy 426.499926 -382.895901)
			(xy 426.506447 -382.913085) (xy 426.512228 -382.92024) (xy 426.533981 -382.945921) (xy 426.571933 -383.001502)
			(xy 426.60297 -383.061222) (xy 426.626646 -383.124223) (xy 426.642623 -383.189602) (xy 426.65067 -383.256422)
			(xy 426.650673 -383.323724) (xy 426.642632 -383.390545) (xy 426.626662 -383.455926) (xy 426.602992 -383.518929)
			(xy 426.571961 -383.578651) (xy 426.534014 -383.634236) (xy 426.512228 -383.659888) (xy 426.506403 -383.667013)
			(xy 426.499907 -383.684219) (xy 426.499528 -383.693416) (xy 426.499528 -384.186684) (xy 426.499939 -384.195871)
			(xy 426.506451 -384.213056) (xy 426.512228 -384.220212) (xy 426.534052 -384.245834) (xy 426.572002 -384.301424)
			(xy 426.603036 -384.361152) (xy 426.626708 -384.42416) (xy 426.64268 -384.489546) (xy 426.650721 -384.556373)
			(xy 426.650718 -384.623681) (xy 426.64267 -384.690507) (xy 426.626692 -384.755892) (xy 426.603014 -384.818898)
			(xy 426.571974 -384.878622) (xy 426.534019 -384.934208) (xy 426.512228 -384.95986) (xy 426.506415 -384.966993)
			(xy 426.499912 -384.984193) (xy 426.499528 -384.993388) (xy 426.499528 -385.151376) (xy 426.499065 -385.161494)
			(xy 426.49133 -385.180191) (xy 426.477028 -385.194505) (xy 426.458337 -385.202257) (xy 426.44822 -385.202684)
			(xy 425.731686 -385.202684) (xy 425.721561 -385.202185) (xy 425.702845 -385.194457) (xy 425.68849 -385.180175)
			(xy 425.680667 -385.161498) (xy 425.680124 -385.151376) (xy 425.680124 -384.993388) (xy 425.679714 -384.984201)
			(xy 425.6732 -384.967017) (xy 425.667424 -384.95986) (xy 425.645672 -384.934178) (xy 425.607723 -384.878596)
			(xy 425.576689 -384.818876) (xy 425.553015 -384.755876) (xy 425.53704 -384.690497) (xy 425.528994 -384.623678)
			(xy 425.52899 -384.556376) (xy 425.537031 -384.489556) (xy 425.552999 -384.424176) (xy 425.576667 -384.361173)
			(xy 425.607696 -384.301451) (xy 425.645639 -384.245865) (xy 425.667424 -384.220212) (xy 425.673243 -384.213083)
			(xy 425.679744 -384.19588) (xy 425.680124 -384.186684) (xy 425.680124 -383.693416) (xy 425.679701 -383.68423)
			(xy 425.673195 -383.667046) (xy 425.667424 -383.659888) (xy 425.645601 -383.634265) (xy 425.607655 -383.578674)
			(xy 425.576624 -383.518946) (xy 425.552954 -383.455938) (xy 425.536984 -383.390552) (xy 425.528942 -383.323727)
			(xy 424.426837 -383.323727) (xy 424.426965 -383.324068) (xy 424.443 -383.389559) (xy 424.451075 -383.456499)
			(xy 424.451074 -383.523925) (xy 424.442996 -383.590864) (xy 424.426958 -383.656355) (xy 424.403191 -383.719452)
			(xy 424.372038 -383.779249) (xy 424.333946 -383.834883) (xy 424.31208 -383.860548) (xy 424.306278 -383.867689)
			(xy 424.299767 -383.884883) (xy 424.29938 -383.894076) (xy 424.29938 -384.051556) (xy 424.298947 -384.061678)
			(xy 424.29121 -384.080385) (xy 424.276898 -384.094701) (xy 424.258194 -384.102444) (xy 424.248072 -384.102864)
			(xy 423.531792 -384.102864) (xy 423.521665 -384.10249) (xy 423.502954 -384.094732) (xy 423.488639 -384.080402)
			(xy 423.4809 -384.061684) (xy 423.480484 -384.051556) (xy 423.480484 -383.894076) (xy 423.480089 -383.884887)
			(xy 423.473565 -383.867703) (xy 423.467784 -383.860548) (xy 423.445936 -383.83487) (xy 423.407848 -383.779237)
			(xy 423.376698 -383.719442) (xy 423.352933 -383.656347) (xy 423.336897 -383.59086) (xy 423.32882 -383.523923)
			(xy 423.328819 -383.456501) (xy 423.336893 -383.389564) (xy 423.352926 -383.324076) (xy 423.376688 -383.26098)
			(xy 423.407836 -383.201184) (xy 423.445922 -383.145549) (xy 423.467784 -383.119884) (xy 423.473568 -383.11273)
			(xy 423.480091 -383.095546) (xy 423.480484 -383.086356) (xy 423.480484 -382.59385) (xy 423.480054 -382.584665)
			(xy 423.473554 -382.56748) (xy 423.467784 -382.560322) (xy 423.445911 -382.534665) (xy 423.407823 -382.479029)
			(xy 423.376674 -382.419231) (xy 423.352911 -382.356133) (xy 423.336877 -382.290643) (xy 423.328802 -382.223705)
			(xy 420.050731 -382.223705) (xy 420.042695 -382.290466) (xy 420.026725 -382.355847) (xy 420.003054 -382.418851)
			(xy 419.972024 -382.478574) (xy 419.934078 -382.534161) (xy 419.912292 -382.559814) (xy 419.906506 -382.566967)
			(xy 419.899985 -382.584151) (xy 419.899592 -382.593342) (xy 419.899592 -383.086864) (xy 419.900021 -383.096049)
			(xy 419.906522 -383.113234) (xy 419.912292 -383.120392) (xy 419.934094 -383.146032) (xy 419.972041 -383.201621)
			(xy 420.003072 -383.261346) (xy 420.02653 -383.323787) (xy 421.128623 -383.323787) (xy 421.128626 -383.256359)
			(xy 421.136706 -383.189418) (xy 421.152747 -383.123926) (xy 421.176516 -383.060828) (xy 421.207673 -383.001031)
			(xy 421.245769 -382.945397) (xy 421.267636 -382.919732) (xy 421.273449 -382.912598) (xy 421.279953 -382.895399)
			(xy 421.280336 -382.886204) (xy 421.280336 -382.728724) (xy 421.280736 -382.718599) (xy 421.288483 -382.699889)
			(xy 421.302805 -382.685572) (xy 421.321518 -382.677832) (xy 421.331644 -382.677416) (xy 422.047924 -382.677416)
			(xy 422.058036 -382.677866) (xy 422.076718 -382.685614) (xy 422.091013 -382.699922) (xy 422.098744 -382.718611)
			(xy 422.099232 -382.728724) (xy 422.099232 -382.886204) (xy 422.099656 -382.895389) (xy 422.106162 -382.912573)
			(xy 422.111932 -382.919732) (xy 422.133759 -382.945427) (xy 422.171847 -383.001058) (xy 422.202998 -383.06085)
			(xy 422.226762 -383.123943) (xy 422.242799 -383.189428) (xy 422.250878 -383.256363) (xy 422.250881 -383.323783)
			(xy 422.242809 -383.390718) (xy 422.226778 -383.456205) (xy 422.20302 -383.5193) (xy 422.171875 -383.579096)
			(xy 422.133793 -383.63473) (xy 422.111932 -383.660396) (xy 422.106146 -383.667549) (xy 422.099627 -383.684734)
			(xy 422.099232 -383.693924) (xy 422.099232 -384.186176) (xy 422.099669 -384.19536) (xy 422.106166 -384.212544)
			(xy 422.111932 -384.219704) (xy 422.13383 -384.245341) (xy 422.171916 -384.30098) (xy 422.203063 -384.36078)
			(xy 422.226824 -384.423881) (xy 422.242856 -384.489373) (xy 422.250928 -384.556314) (xy 422.250925 -384.62374)
			(xy 422.242846 -384.69068) (xy 422.226808 -384.756171) (xy 422.203041 -384.819269) (xy 422.171888 -384.879066)
			(xy 422.133797 -384.934702) (xy 422.111932 -384.960368) (xy 422.106116 -384.967499) (xy 422.099615 -384.984701)
			(xy 422.099232 -384.993896) (xy 422.099232 -385.151376) (xy 422.098696 -385.161479) (xy 422.090972 -385.180151)
			(xy 422.076691 -385.194445) (xy 422.058027 -385.202187) (xy 422.047924 -385.202684) (xy 421.331644 -385.202684)
			(xy 421.321522 -385.202247) (xy 421.302817 -385.194511) (xy 421.2885 -385.1802) (xy 421.280756 -385.161497)
			(xy 421.280336 -385.151376) (xy 421.280336 -384.993896) (xy 421.27992 -384.98471) (xy 421.27341 -384.967526)
			(xy 421.267636 -384.960368) (xy 421.245806 -384.934674) (xy 421.207714 -384.879045) (xy 421.17656 -384.819253)
			(xy 421.152792 -384.756159) (xy 421.136753 -384.690673) (xy 421.128674 -384.623738) (xy 421.12867 -384.556316)
			(xy 421.136743 -384.48938) (xy 421.152776 -384.423892) (xy 421.176538 -384.360797) (xy 421.207686 -384.301002)
			(xy 421.245773 -384.245369) (xy 421.267636 -384.219704) (xy 421.273418 -384.212549) (xy 421.27994 -384.195366)
			(xy 421.280336 -384.186176) (xy 421.280336 -383.693924) (xy 421.279906 -383.684739) (xy 421.273405 -383.667555)
			(xy 421.267636 -383.660396) (xy 421.245735 -383.634761) (xy 421.207645 -383.579123) (xy 421.176494 -383.519323)
			(xy 421.152731 -383.456222) (xy 421.136696 -383.390729) (xy 421.128623 -383.323787) (xy 420.02653 -383.323787)
			(xy 420.026742 -383.324352) (xy 420.042713 -383.389736) (xy 420.050756 -383.456559) (xy 420.050754 -383.523865)
			(xy 420.042709 -383.590688) (xy 420.026735 -383.656071) (xy 420.003062 -383.719076) (xy 419.972028 -383.7788)
			(xy 419.93408 -383.834387) (xy 419.912292 -383.86004) (xy 419.906495 -383.867185) (xy 419.899981 -383.884376)
			(xy 419.899592 -383.893568) (xy 419.899592 -384.051556) (xy 419.899148 -384.061677) (xy 419.891413 -384.080381)
			(xy 419.877104 -384.094697) (xy 419.858404 -384.102442) (xy 419.848284 -384.102864) (xy 419.13175 -384.102864)
			(xy 419.121627 -384.102333) (xy 419.102908 -384.094622) (xy 419.08855 -384.080349) (xy 419.080728 -384.061676)
			(xy 419.080188 -384.051556) (xy 419.080188 -383.893568) (xy 419.079796 -383.884379) (xy 419.07327 -383.867194)
			(xy 419.067488 -383.86004) (xy 419.045715 -383.834376) (xy 419.007762 -383.778792) (xy 418.976725 -383.719071)
			(xy 418.95305 -383.656068) (xy 418.937074 -383.590686) (xy 418.929028 -383.523864) (xy 418.929026 -383.45656)
			(xy 418.93707 -383.389737) (xy 418.953042 -383.324355) (xy 418.976716 -383.261351) (xy 419.00775 -383.201629)
			(xy 419.0457 -383.146043) (xy 419.067488 -383.120392) (xy 419.073269 -383.113236) (xy 419.079793 -383.096054)
			(xy 419.080188 -383.086864) (xy 419.080188 -382.593342) (xy 419.07976 -382.584157) (xy 419.073259 -382.566972)
			(xy 419.067488 -382.559814) (xy 419.045689 -382.534171) (xy 419.007737 -382.478584) (xy 418.976702 -382.41886)
			(xy 418.953027 -382.355854) (xy 418.937054 -382.29047) (xy 418.92901 -382.223646) (xy 389.250707 -382.223646)
			(xy 389.242664 -382.290467) (xy 389.226692 -382.355848) (xy 389.20302 -382.418853) (xy 389.171987 -382.478576)
			(xy 389.134039 -382.534162) (xy 389.112252 -382.559814) (xy 389.106461 -382.566963) (xy 389.099944 -382.584151)
			(xy 389.099552 -382.593342) (xy 389.099552 -383.086864) (xy 389.09999 -383.096048) (xy 389.106485 -383.113232)
			(xy 389.112252 -383.120392) (xy 389.134056 -383.146031) (xy 389.172005 -383.201619) (xy 389.203038 -383.261344)
			(xy 389.226475 -383.323726) (xy 390.329121 -383.323726) (xy 390.329125 -383.256419) (xy 390.337172 -383.189595)
			(xy 390.353147 -383.124211) (xy 390.376822 -383.061206) (xy 390.407857 -383.001481) (xy 390.445807 -382.945893)
			(xy 390.467596 -382.92024) (xy 390.4734 -382.9131) (xy 390.47991 -382.895906) (xy 390.480296 -382.886712)
			(xy 390.480296 -382.728724) (xy 390.480741 -382.718572) (xy 390.488528 -382.699821) (xy 390.502918 -382.685497)
			(xy 390.521704 -382.677795) (xy 390.531858 -382.677416) (xy 391.248138 -382.677416) (xy 391.258264 -382.677895)
			(xy 391.276982 -382.685631) (xy 391.291336 -382.699919) (xy 391.299158 -382.7186) (xy 391.2997 -382.728724)
			(xy 391.2997 -382.886712) (xy 391.300105 -382.8959) (xy 391.306622 -382.913084) (xy 391.3124 -382.92024)
			(xy 391.334151 -382.945922) (xy 391.372099 -383.001505) (xy 391.403131 -383.061225) (xy 391.426804 -383.124225)
			(xy 391.442779 -383.189603) (xy 391.450825 -383.256422) (xy 391.450828 -383.323724) (xy 391.442788 -383.390543)
			(xy 391.42682 -383.455923) (xy 391.403153 -383.518926) (xy 391.372126 -383.578649) (xy 391.334184 -383.634235)
			(xy 391.3124 -383.659888) (xy 391.306584 -383.667019) (xy 391.300081 -383.68422) (xy 391.2997 -383.693416)
			(xy 391.2997 -384.186684) (xy 391.300118 -384.19587) (xy 391.306626 -384.213055) (xy 391.3124 -384.220212)
			(xy 391.334222 -384.245836) (xy 391.372167 -384.301427) (xy 391.403197 -384.361155) (xy 391.426866 -384.424163)
			(xy 391.442835 -384.489548) (xy 391.450876 -384.556374) (xy 391.450872 -384.623681) (xy 391.442825 -384.690505)
			(xy 391.42685 -384.755889) (xy 391.403175 -384.818895) (xy 391.372139 -384.878619) (xy 391.334189 -384.934207)
			(xy 391.3124 -384.95986) (xy 391.306595 -384.967) (xy 391.300086 -384.984194) (xy 391.2997 -384.993388)
			(xy 391.2997 -385.151376) (xy 391.299259 -385.161529) (xy 391.291471 -385.180281) (xy 391.27708 -385.194605)
			(xy 391.258292 -385.202305) (xy 391.248138 -385.202684) (xy 390.531858 -385.202684) (xy 390.521732 -385.202209)
			(xy 390.503014 -385.194471) (xy 390.48866 -385.180182) (xy 390.480838 -385.1615) (xy 390.480296 -385.151376)
			(xy 390.480296 -384.993388) (xy 390.479892 -384.9842) (xy 390.473374 -384.967016) (xy 390.467596 -384.95986)
			(xy 390.445845 -384.934178) (xy 390.407898 -384.878595) (xy 390.376865 -384.818875) (xy 390.353192 -384.755875)
			(xy 390.337218 -384.690496) (xy 390.329172 -384.623678) (xy 390.329169 -384.556376) (xy 390.337209 -384.489557)
			(xy 390.353176 -384.424177) (xy 390.376843 -384.361174) (xy 390.40787 -384.301452) (xy 390.445812 -384.245865)
			(xy 390.467596 -384.220212) (xy 390.473412 -384.21308) (xy 390.479915 -384.19588) (xy 390.480296 -384.186684)
			(xy 390.480296 -383.693416) (xy 390.479879 -383.68423) (xy 390.47337 -383.667045) (xy 390.467596 -383.659888)
			(xy 390.445774 -383.634264) (xy 390.407829 -383.578673) (xy 390.3768 -383.518945) (xy 390.353131 -383.455937)
			(xy 390.337162 -383.390552) (xy 390.329121 -383.323726) (xy 389.226475 -383.323726) (xy 389.22671 -383.324351)
			(xy 389.242682 -383.389735) (xy 389.250725 -383.456559) (xy 389.250724 -383.523865) (xy 389.242678 -383.590689)
			(xy 389.226703 -383.656072) (xy 389.203028 -383.719078) (xy 389.171992 -383.778802) (xy 389.134041 -383.834388)
			(xy 389.112252 -383.86004) (xy 389.10645 -383.867181) (xy 389.09994 -383.884375) (xy 389.099552 -383.893568)
			(xy 389.099552 -384.051556) (xy 389.099043 -384.061701) (xy 389.091272 -384.080442) (xy 389.076902 -384.094765)
			(xy 389.058136 -384.102476) (xy 389.04799 -384.102864) (xy 388.33171 -384.102864) (xy 388.321584 -384.102365)
			(xy 388.302864 -384.094642) (xy 388.288508 -384.080359) (xy 388.280687 -384.061679) (xy 388.280148 -384.051556)
			(xy 388.280148 -383.893568) (xy 388.279742 -383.884381) (xy 388.273224 -383.867197) (xy 388.267448 -383.86004)
			(xy 388.245676 -383.834375) (xy 388.207726 -383.778791) (xy 388.176692 -383.719069) (xy 388.153018 -383.656066)
			(xy 388.137043 -383.590685) (xy 388.128998 -383.523864) (xy 388.128996 -383.45656) (xy 388.137039 -383.389738)
			(xy 388.15301 -383.324357) (xy 388.176682 -383.261353) (xy 388.207714 -383.20163) (xy 388.245661 -383.146044)
			(xy 388.267448 -383.120392) (xy 388.273236 -383.113241) (xy 388.279755 -383.096055) (xy 388.280148 -383.086864)
			(xy 388.280148 -382.593342) (xy 388.279707 -382.584158) (xy 388.273213 -382.566974) (xy 388.267448 -382.559814)
			(xy 388.24565 -382.53417) (xy 388.207701 -382.478583) (xy 388.176668 -382.418858) (xy 388.152995 -382.355852)
			(xy 388.137022 -382.290469) (xy 388.128979 -382.223645) (xy 384.850917 -382.223645) (xy 384.842874 -382.290466)
			(xy 384.826902 -382.355848) (xy 384.803231 -382.418852) (xy 384.772199 -382.478576) (xy 384.734251 -382.534162)
			(xy 384.712464 -382.559814) (xy 384.706674 -382.566964) (xy 384.700156 -382.584151) (xy 384.699764 -382.593342)
			(xy 384.699764 -383.086864) (xy 384.7002 -383.096048) (xy 384.706697 -383.113232) (xy 384.712464 -383.120392)
			(xy 384.734267 -383.146031) (xy 384.772216 -383.20162) (xy 384.803248 -383.261345) (xy 384.826708 -383.323786)
			(xy 385.928802 -383.323786) (xy 385.928805 -383.25636) (xy 385.936885 -383.189419) (xy 385.952924 -383.123928)
			(xy 385.976693 -383.060829) (xy 386.007848 -383.001032) (xy 386.045942 -382.945397) (xy 386.067808 -382.919732)
			(xy 386.073617 -382.912596) (xy 386.080124 -382.895398) (xy 386.080508 -382.886204) (xy 386.080508 -382.728724)
			(xy 386.080936 -382.718602) (xy 386.088677 -382.699897) (xy 386.102991 -382.685582) (xy 386.121694 -382.677837)
			(xy 386.131816 -382.677416) (xy 386.848096 -382.677416) (xy 386.85822 -382.67782) (xy 386.876927 -382.685569)
			(xy 386.891242 -382.69989) (xy 386.898984 -382.7186) (xy 386.899404 -382.728724) (xy 386.899404 -382.886204)
			(xy 386.899811 -382.895391) (xy 386.906327 -382.912576) (xy 386.912104 -382.919732) (xy 386.933932 -382.945426)
			(xy 386.972022 -383.001057) (xy 387.003174 -383.060849) (xy 387.02694 -383.123942) (xy 387.042978 -383.189428)
			(xy 387.051057 -383.256363) (xy 387.05106 -383.323783) (xy 387.042988 -383.390719) (xy 387.026956 -383.456206)
			(xy 387.003196 -383.519301) (xy 386.97205 -383.579097) (xy 386.933966 -383.634731) (xy 386.912104 -383.660396)
			(xy 386.906327 -383.667555) (xy 386.899801 -383.684735) (xy 386.899404 -383.693924) (xy 386.899404 -384.186176)
			(xy 386.899825 -384.195362) (xy 386.906331 -384.212547) (xy 386.912104 -384.219704) (xy 386.934003 -384.24534)
			(xy 386.972091 -384.300979) (xy 387.003239 -384.360779) (xy 387.027001 -384.42388) (xy 387.043034 -384.489372)
			(xy 387.051107 -384.556314) (xy 387.051104 -384.62374) (xy 387.043025 -384.690681) (xy 387.026985 -384.756172)
			(xy 387.003217 -384.81927) (xy 386.972063 -384.879068) (xy 386.93397 -384.934703) (xy 386.912104 -384.960368)
			(xy 386.906297 -384.967506) (xy 386.899788 -384.984702) (xy 386.899404 -384.993896) (xy 386.899404 -385.151376)
			(xy 386.898965 -385.161496) (xy 386.891225 -385.180199) (xy 386.876916 -385.194514) (xy 386.858216 -385.202261)
			(xy 386.848096 -385.202684) (xy 386.131816 -385.202684) (xy 386.121693 -385.202271) (xy 386.102986 -385.194525)
			(xy 386.088671 -385.180207) (xy 386.080928 -385.1615) (xy 386.080508 -385.151376) (xy 386.080508 -384.993896)
			(xy 386.080098 -384.984709) (xy 386.073584 -384.967525) (xy 386.067808 -384.960368) (xy 386.045979 -384.934674)
			(xy 386.007889 -384.879044) (xy 385.976736 -384.819251) (xy 385.95297 -384.756158) (xy 385.936931 -384.690673)
			(xy 385.928852 -384.623738) (xy 385.928849 -384.556317) (xy 385.936922 -384.489381) (xy 385.952954 -384.423893)
			(xy 385.976714 -384.360798) (xy 386.007861 -384.301003) (xy 386.045946 -384.245369) (xy 386.067808 -384.219704)
			(xy 386.073586 -384.212546) (xy 386.080112 -384.195365) (xy 386.080508 -384.186176) (xy 386.080508 -383.693924)
			(xy 386.080084 -383.684738) (xy 386.07358 -383.667554) (xy 386.067808 -383.660396) (xy 386.045908 -383.63476)
			(xy 386.00782 -383.579122) (xy 385.976671 -383.519321) (xy 385.952908 -383.456221) (xy 385.936875 -383.390728)
			(xy 385.928802 -383.323786) (xy 384.826708 -383.323786) (xy 384.82692 -383.324351) (xy 384.842892 -383.389735)
			(xy 384.850934 -383.456559) (xy 384.850933 -383.523865) (xy 384.842887 -383.590689) (xy 384.826913 -383.656072)
			(xy 384.803238 -383.719077) (xy 384.772203 -383.778801) (xy 384.734253 -383.834388) (xy 384.712464 -383.86004)
			(xy 384.706663 -383.867182) (xy 384.700152 -383.884375) (xy 384.699764 -383.893568) (xy 384.699764 -384.051556)
			(xy 384.699342 -384.061712) (xy 384.691554 -384.08047) (xy 384.677156 -384.094796) (xy 384.65836 -384.102491)
			(xy 384.648202 -384.102864) (xy 383.931922 -384.102864) (xy 383.921797 -384.102356) (xy 383.903077 -384.094636)
			(xy 383.88872 -384.080356) (xy 383.8809 -384.061678) (xy 383.88036 -384.051556) (xy 383.88036 -383.893568)
			(xy 383.879952 -383.884381) (xy 383.873435 -383.867197) (xy 383.86766 -383.86004) (xy 383.845887 -383.834375)
			(xy 383.807937 -383.778791) (xy 383.776902 -383.719069) (xy 383.753227 -383.656066) (xy 383.737252 -383.590686)
			(xy 383.729207 -383.523864) (xy 383.729205 -383.45656) (xy 383.737248 -383.389738) (xy 383.75322 -383.324357)
			(xy 383.776892 -383.261353) (xy 383.807924 -383.20163) (xy 383.845873 -383.146044) (xy 383.86766 -383.120392)
			(xy 383.87345 -383.113242) (xy 383.879967 -383.096055) (xy 383.88036 -383.086864) (xy 383.88036 -382.593342)
			(xy 383.879916 -382.584159) (xy 383.873425 -382.566975) (xy 383.86766 -382.559814) (xy 383.845862 -382.53417)
			(xy 383.807912 -382.478583) (xy 383.776878 -382.418858) (xy 383.753205 -382.355853) (xy 383.737232 -382.290469)
			(xy 383.729188 -382.223646) (xy 380.451149 -382.223646) (xy 380.451149 -382.223704) (xy 380.443073 -382.290642)
			(xy 380.427038 -382.356131) (xy 380.403273 -382.419228) (xy 380.372122 -382.479024) (xy 380.334032 -382.534657)
			(xy 380.312168 -382.560322) (xy 380.306375 -382.56747) (xy 380.299859 -382.584658) (xy 380.299468 -382.59385)
			(xy 380.299468 -383.086356) (xy 380.299907 -383.09554) (xy 380.306401 -383.112724) (xy 380.312168 -383.119884)
			(xy 380.334049 -383.145536) (xy 380.372139 -383.201171) (xy 380.403291 -383.260969) (xy 380.426928 -383.323727)
			(xy 381.529033 -383.323727) (xy 381.529037 -383.256419) (xy 381.537084 -383.189595) (xy 381.55306 -383.124211)
			(xy 381.576736 -383.061205) (xy 381.607772 -383.00148) (xy 381.645723 -382.945893) (xy 381.667512 -382.92024)
			(xy 381.673318 -382.913101) (xy 381.679827 -382.895906) (xy 381.680212 -382.886712) (xy 381.680212 -382.728724)
			(xy 381.680641 -382.71857) (xy 381.688431 -382.699816) (xy 381.702826 -382.685491) (xy 381.721618 -382.677793)
			(xy 381.731774 -382.677416) (xy 382.448054 -382.677416) (xy 382.458175 -382.677964) (xy 382.47689 -382.685672)
			(xy 382.491247 -382.699939) (xy 382.499072 -382.718606) (xy 382.499616 -382.728724) (xy 382.499616 -382.886712)
			(xy 382.500017 -382.8959) (xy 382.506537 -382.913085) (xy 382.512316 -382.92024) (xy 382.53407 -382.945921)
			(xy 382.572023 -383.001502) (xy 382.60306 -383.061221) (xy 382.626737 -383.124222) (xy 382.642713 -383.189601)
			(xy 382.650761 -383.256421) (xy 382.650764 -383.323724) (xy 382.642723 -383.390545) (xy 382.626753 -383.455926)
			(xy 382.603082 -383.518929) (xy 382.57205 -383.578652) (xy 382.534103 -383.634236) (xy 382.512316 -383.659888)
			(xy 382.506501 -383.667021) (xy 382.499997 -383.684221) (xy 382.499616 -383.693416) (xy 382.499616 -384.186684)
			(xy 382.50003 -384.195871) (xy 382.506541 -384.213055) (xy 382.512316 -384.220212) (xy 382.53414 -384.245834)
			(xy 382.572091 -384.301424) (xy 382.603125 -384.361151) (xy 382.626798 -384.42416) (xy 382.64277 -384.489546)
			(xy 382.650812 -384.556373) (xy 382.650808 -384.623681) (xy 382.64276 -384.690507) (xy 382.626782 -384.755892)
			(xy 382.603103 -384.818898) (xy 382.572063 -384.878622) (xy 382.534107 -384.934208) (xy 382.512316 -384.95986)
			(xy 382.506513 -384.967001) (xy 382.500002 -384.984195) (xy 382.499616 -384.993388) (xy 382.499616 -385.151376)
			(xy 382.499159 -385.161527) (xy 382.491375 -385.180275) (xy 382.476989 -385.194599) (xy 382.458206 -385.202303)
			(xy 382.448054 -385.202684) (xy 381.731774 -385.202684) (xy 381.721649 -385.202196) (xy 381.702931 -385.194464)
			(xy 381.688577 -385.180179) (xy 381.680754 -385.161499) (xy 381.680212 -385.151376) (xy 381.680212 -384.993388)
			(xy 381.679805 -384.984201) (xy 381.673289 -384.967016) (xy 381.667512 -384.95986) (xy 381.64576 -384.934178)
			(xy 381.607812 -384.878596) (xy 381.576779 -384.818876) (xy 381.553105 -384.755875) (xy 381.537131 -384.690497)
			(xy 381.529084 -384.623678) (xy 381.529081 -384.556376) (xy 381.537121 -384.489557) (xy 381.553089 -384.424177)
			(xy 381.576757 -384.361174) (xy 381.607784 -384.301451) (xy 381.645727 -384.245864) (xy 381.667512 -384.220212)
			(xy 381.67333 -384.213082) (xy 381.679831 -384.19588) (xy 381.680212 -384.186684) (xy 381.680212 -383.693416)
			(xy 381.679791 -383.68423) (xy 381.673285 -383.667046) (xy 381.667512 -383.659888) (xy 381.64569 -383.634265)
			(xy 381.607744 -383.578673) (xy 381.576714 -383.518946) (xy 381.553044 -383.455937) (xy 381.537074 -383.390552)
			(xy 381.529033 -383.323727) (xy 380.426928 -383.323727) (xy 380.427056 -383.324068) (xy 380.443091 -383.389559)
			(xy 380.451166 -383.456499) (xy 380.451165 -383.523925) (xy 380.443087 -383.590865) (xy 380.427049 -383.656355)
			(xy 380.403281 -383.719453) (xy 380.372127 -383.779249) (xy 380.334034 -383.834883) (xy 380.312168 -383.860548)
			(xy 380.306364 -383.867688) (xy 380.299855 -383.884883) (xy 380.299468 -383.894076) (xy 380.299468 -384.051556)
			(xy 380.299047 -384.06168) (xy 380.291308 -384.080388) (xy 380.276992 -384.094705) (xy 380.258284 -384.102446)
			(xy 380.24816 -384.102864) (xy 379.53188 -384.102864) (xy 379.521752 -384.1025) (xy 379.503041 -384.094738)
			(xy 379.488726 -384.080405) (xy 379.480988 -384.061685) (xy 379.480572 -384.051556) (xy 379.480572 -383.894076)
			(xy 379.48018 -383.884887) (xy 379.473654 -383.867702) (xy 379.467872 -383.860548) (xy 379.446025 -383.834869)
			(xy 379.407937 -383.779236) (xy 379.376788 -383.719441) (xy 379.353024 -383.656346) (xy 379.336988 -383.590859)
			(xy 379.328911 -383.523923) (xy 379.32891 -383.456501) (xy 379.336984 -383.389564) (xy 379.353017 -383.324077)
			(xy 379.376778 -383.260981) (xy 379.407925 -383.201185) (xy 379.44601 -383.14555) (xy 379.467872 -383.119884)
			(xy 379.473667 -383.112738) (xy 379.48018 -383.095548) (xy 379.480572 -383.086356) (xy 379.480572 -382.59385)
			(xy 379.480144 -382.584665) (xy 379.473643 -382.56748) (xy 379.467872 -382.560322) (xy 379.445999 -382.534664)
			(xy 379.407913 -382.479028) (xy 379.376764 -382.419231) (xy 379.353002 -382.356133) (xy 379.336968 -382.290643)
			(xy 379.328893 -382.223704) (xy 376.050822 -382.223704) (xy 376.042786 -382.290466) (xy 376.026815 -382.355847)
			(xy 376.003144 -382.418851) (xy 375.972113 -382.478575) (xy 375.934167 -382.534162) (xy 375.91238 -382.559814)
			(xy 375.906593 -382.566966) (xy 375.900073 -382.584151) (xy 375.89968 -382.593342) (xy 375.89968 -383.086864)
			(xy 375.900112 -383.096049) (xy 375.906611 -383.113233) (xy 375.91238 -383.120392) (xy 375.934183 -383.146031)
			(xy 375.97213 -383.20162) (xy 376.003162 -383.261346) (xy 376.02662 -383.323786) (xy 377.128714 -383.323786)
			(xy 377.128717 -383.256359) (xy 377.136797 -383.189418) (xy 377.152837 -383.123927) (xy 377.176606 -383.060828)
			(xy 377.207762 -383.001031) (xy 377.245857 -382.945397) (xy 377.267724 -382.919732) (xy 377.273535 -382.912597)
			(xy 377.28004 -382.895399) (xy 377.280424 -382.886204) (xy 377.280424 -382.728724) (xy 377.280836 -382.7186)
			(xy 377.288581 -382.699892) (xy 377.302899 -382.685576) (xy 377.321608 -382.677834) (xy 377.331732 -382.677416)
			(xy 378.048012 -382.677416) (xy 378.058137 -382.677806) (xy 378.076844 -382.685561) (xy 378.091159 -382.699886)
			(xy 378.098901 -382.718598) (xy 378.09932 -382.728724) (xy 378.09932 -382.886204) (xy 378.099724 -382.895392)
			(xy 378.106241 -382.912576) (xy 378.11202 -382.919732) (xy 378.133848 -382.945427) (xy 378.171936 -383.001058)
			(xy 378.203088 -383.06085) (xy 378.226853 -383.123943) (xy 378.24289 -383.189428) (xy 378.250969 -383.256363)
			(xy 378.250972 -383.323783) (xy 378.2429 -383.390719) (xy 378.226869 -383.456205) (xy 378.20311 -383.519301)
			(xy 378.171964 -383.579096) (xy 378.133881 -383.63473) (xy 378.11202 -383.660396) (xy 378.106245 -383.667557)
			(xy 378.099717 -383.684735) (xy 378.09932 -383.693924) (xy 378.09932 -384.186176) (xy 378.099737 -384.195363)
			(xy 378.106245 -384.212547) (xy 378.11202 -384.219704) (xy 378.133919 -384.24534) (xy 378.172005 -384.30098)
			(xy 378.203153 -384.36078) (xy 378.226914 -384.423881) (xy 378.242947 -384.489373) (xy 378.251019 -384.556314)
			(xy 378.251016 -384.62374) (xy 378.242937 -384.69068) (xy 378.226898 -384.756171) (xy 378.203131 -384.81927)
			(xy 378.171977 -384.879067) (xy 378.133885 -384.934702) (xy 378.11202 -384.960368) (xy 378.106214 -384.967507)
			(xy 378.099704 -384.984702) (xy 378.09932 -384.993896) (xy 378.09932 -385.151376) (xy 378.098865 -385.161494)
			(xy 378.091128 -385.180194) (xy 378.076824 -385.194508) (xy 378.05813 -385.202258) (xy 378.048012 -385.202684)
			(xy 377.331732 -385.202684) (xy 377.32161 -385.202258) (xy 377.302903 -385.194517) (xy 377.288587 -385.180203)
			(xy 377.280844 -385.161498) (xy 377.280424 -385.151376) (xy 377.280424 -384.993896) (xy 377.280011 -384.984709)
			(xy 377.273499 -384.967525) (xy 377.267724 -384.960368) (xy 377.245895 -384.934674) (xy 377.207803 -384.879044)
			(xy 377.17665 -384.819252) (xy 377.152882 -384.756159) (xy 377.136844 -384.690673) (xy 377.128765 -384.623738)
			(xy 377.128761 -384.556316) (xy 377.136834 -384.48938) (xy 377.152866 -384.423893) (xy 377.176627 -384.360797)
			(xy 377.207775 -384.301002) (xy 377.245861 -384.245369) (xy 377.267724 -384.219704) (xy 377.273504 -384.212547)
			(xy 377.280028 -384.195365) (xy 377.280424 -384.186176) (xy 377.280424 -383.693924) (xy 377.279997 -383.684739)
			(xy 377.273494 -383.667555) (xy 377.267724 -383.660396) (xy 377.245824 -383.63476) (xy 377.207735 -383.579122)
			(xy 377.176584 -383.519322) (xy 377.152821 -383.456221) (xy 377.136787 -383.390728) (xy 377.128714 -383.323786)
			(xy 376.02662 -383.323786) (xy 376.026833 -383.324352) (xy 376.042804 -383.389735) (xy 376.050846 -383.456559)
			(xy 376.050845 -383.523865) (xy 376.0428 -383.590688) (xy 376.026826 -383.656071) (xy 376.003152 -383.719076)
			(xy 375.972118 -383.778801) (xy 375.934168 -383.834388) (xy 375.91238 -383.86004) (xy 375.906582 -383.867184)
			(xy 375.900069 -383.884375) (xy 375.89968 -383.893568) (xy 375.89968 -384.051556) (xy 375.899242 -384.06171)
			(xy 375.891457 -384.080465) (xy 375.877065 -384.094791) (xy 375.858274 -384.102488) (xy 375.848118 -384.102864)
			(xy 375.131838 -384.102864) (xy 375.121714 -384.102342) (xy 375.102995 -384.094628) (xy 375.088637 -384.080352)
			(xy 375.080816 -384.061677) (xy 375.080276 -384.051556) (xy 375.080276 -383.893568) (xy 375.079886 -383.884379)
			(xy 375.073359 -383.867194) (xy 375.067576 -383.86004) (xy 375.045803 -383.834375) (xy 375.007851 -383.778792)
			(xy 374.976815 -383.71907) (xy 374.95314 -383.656067) (xy 374.937165 -383.590686) (xy 374.929119 -383.523864)
			(xy 374.929117 -383.45656) (xy 374.93716 -383.389738) (xy 374.953133 -383.324356) (xy 374.976805 -383.261352)
			(xy 375.007839 -383.201629) (xy 375.045788 -383.146044) (xy 375.067576 -383.120392) (xy 375.073356 -383.113235)
			(xy 375.079881 -383.096054) (xy 375.080276 -383.086864) (xy 375.080276 -382.593342) (xy 375.079851 -382.584156)
			(xy 375.073348 -382.566971) (xy 375.067576 -382.559814) (xy 375.045777 -382.53417) (xy 375.007826 -382.478584)
			(xy 374.976792 -382.418859) (xy 374.953118 -382.355853) (xy 374.937144 -382.29047) (xy 374.9291 -382.223646)
			(xy 345.250798 -382.223646) (xy 345.242755 -382.290467) (xy 345.226782 -382.355849) (xy 345.20311 -382.418853)
			(xy 345.172077 -382.478576) (xy 345.134128 -382.534162) (xy 345.11234 -382.559814) (xy 345.106548 -382.566962)
			(xy 345.100032 -382.584151) (xy 345.09964 -382.593342) (xy 345.09964 -383.086864) (xy 345.100081 -383.096048)
			(xy 345.106575 -383.113232) (xy 345.11234 -383.120392) (xy 345.134144 -383.146031) (xy 345.172094 -383.201619)
			(xy 345.203127 -383.261344) (xy 345.226566 -383.323727) (xy 346.329188 -383.323727) (xy 346.329192 -383.256419)
			(xy 346.33724 -383.189593) (xy 346.353218 -383.124208) (xy 346.376897 -383.061202) (xy 346.407937 -383.001478)
			(xy 346.445893 -382.945892) (xy 346.467684 -382.92024) (xy 346.473487 -382.913099) (xy 346.479998 -382.895905)
			(xy 346.480384 -382.886712) (xy 346.480384 -382.728724) (xy 346.480841 -382.718573) (xy 346.488625 -382.699825)
			(xy 346.503011 -382.685501) (xy 346.521794 -382.677797) (xy 346.531946 -382.677416) (xy 347.248226 -382.677416)
			(xy 347.258351 -382.677904) (xy 347.277069 -382.685636) (xy 347.291423 -382.699921) (xy 347.299246 -382.718601)
			(xy 347.299788 -382.728724) (xy 347.299788 -382.886712) (xy 347.300195 -382.895899) (xy 347.306711 -382.913084)
			(xy 347.312488 -382.92024) (xy 347.33424 -382.945922) (xy 347.372188 -383.001504) (xy 347.403221 -383.061224)
			(xy 347.426895 -383.124225) (xy 347.442869 -383.189603) (xy 347.450916 -383.256422) (xy 347.450919 -383.323724)
			(xy 347.442879 -383.390543) (xy 347.426911 -383.455923) (xy 347.403243 -383.518926) (xy 347.372216 -383.578649)
			(xy 347.334273 -383.634236) (xy 347.312488 -383.659888) (xy 347.30667 -383.667018) (xy 347.300169 -383.68422)
			(xy 347.299788 -383.693416) (xy 347.299788 -384.186684) (xy 347.300209 -384.19587) (xy 347.306715 -384.213054)
			(xy 347.312488 -384.220212) (xy 347.33431 -384.245835) (xy 347.372256 -384.301427) (xy 347.403286 -384.361154)
			(xy 347.426956 -384.424163) (xy 347.442926 -384.489548) (xy 347.450967 -384.556373) (xy 347.450963 -384.623681)
			(xy 347.442916 -384.690505) (xy 347.42694 -384.755889) (xy 347.403264 -384.818895) (xy 347.372228 -384.87862)
			(xy 347.334277 -384.934207) (xy 347.312488 -384.95986) (xy 347.306682 -384.966999) (xy 347.300173 -384.984194)
			(xy 347.299788 -384.993388) (xy 347.299788 -385.151376) (xy 347.299359 -385.16153) (xy 347.291569 -385.180284)
			(xy 347.277174 -385.194609) (xy 347.258382 -385.202307) (xy 347.248226 -385.202684) (xy 346.531946 -385.202684)
			(xy 346.521825 -385.202136) (xy 346.50311 -385.194428) (xy 346.488753 -385.180161) (xy 346.480928 -385.161494)
			(xy 346.480384 -385.151376) (xy 346.480384 -384.993388) (xy 346.479983 -384.9842) (xy 346.473463 -384.967015)
			(xy 346.467684 -384.95986) (xy 346.44593 -384.934179) (xy 346.407977 -384.878598) (xy 346.37694 -384.818879)
			(xy 346.353263 -384.755878) (xy 346.337287 -384.690499) (xy 346.329239 -384.623679) (xy 346.329236 -384.556376)
			(xy 346.337277 -384.489555) (xy 346.353247 -384.424174) (xy 346.376918 -384.361171) (xy 346.40795 -384.301448)
			(xy 346.445897 -384.245864) (xy 346.467684 -384.220212) (xy 346.473499 -384.213079) (xy 346.480003 -384.195879)
			(xy 346.480384 -384.186684) (xy 346.480384 -383.693416) (xy 346.47997 -383.684229) (xy 346.473459 -383.667045)
			(xy 346.467684 -383.659888) (xy 346.44586 -383.634266) (xy 346.407909 -383.578676) (xy 346.376875 -383.518949)
			(xy 346.353202 -383.45594) (xy 346.33723 -383.390554) (xy 346.329188 -383.323727) (xy 345.226566 -383.323727)
			(xy 345.2268 -383.32435) (xy 345.242773 -383.389734) (xy 345.250816 -383.456559) (xy 345.250814 -383.523865)
			(xy 345.242768 -383.590689) (xy 345.226793 -383.656073) (xy 345.203118 -383.719078) (xy 345.172081 -383.778802)
			(xy 345.134129 -383.834388) (xy 345.11234 -383.86004) (xy 345.106537 -383.86718) (xy 345.100028 -383.884375)
			(xy 345.09964 -383.893568) (xy 345.09964 -384.051556) (xy 345.099143 -384.061702) (xy 345.09137 -384.080446)
			(xy 345.076996 -384.094769) (xy 345.058226 -384.102478) (xy 345.048078 -384.102864) (xy 344.331798 -384.102864)
			(xy 344.321672 -384.102375) (xy 344.302951 -384.094647) (xy 344.288595 -384.080362) (xy 344.280775 -384.06168)
			(xy 344.280236 -384.051556) (xy 344.280236 -383.893568) (xy 344.279833 -383.88438) (xy 344.273313 -383.867196)
			(xy 344.267536 -383.86004) (xy 344.245764 -383.834375) (xy 344.207815 -383.77879) (xy 344.176781 -383.719068)
			(xy 344.153108 -383.656066) (xy 344.137134 -383.590685) (xy 344.129089 -383.523864) (xy 344.129087 -383.45656)
			(xy 344.13713 -383.389739) (xy 344.153101 -383.324358) (xy 344.176772 -383.261354) (xy 344.207803 -383.201631)
			(xy 344.24575 -383.146044) (xy 344.267536 -383.120392) (xy 344.273323 -383.11324) (xy 344.279843 -383.096055)
			(xy 344.280236 -383.086864) (xy 344.280236 -382.593342) (xy 344.279797 -382.584158) (xy 344.273303 -382.566974)
			(xy 344.267536 -382.559814) (xy 344.245738 -382.53417) (xy 344.20779 -382.478582) (xy 344.176757 -382.418858)
			(xy 344.153085 -382.355852) (xy 344.137113 -382.290469) (xy 344.12907 -382.223645) (xy 340.851007 -382.223645)
			(xy 340.842964 -382.290467) (xy 340.826992 -382.355848) (xy 340.80332 -382.418853) (xy 340.772287 -382.478576)
			(xy 340.734339 -382.534162) (xy 340.712552 -382.559814) (xy 340.706761 -382.566963) (xy 340.700244 -382.584151)
			(xy 340.699852 -382.593342) (xy 340.699852 -383.086864) (xy 340.70029 -383.096048) (xy 340.706785 -383.113232)
			(xy 340.712552 -383.120392) (xy 340.734356 -383.146031) (xy 340.772305 -383.201619) (xy 340.803338 -383.261344)
			(xy 340.826798 -383.323786) (xy 341.928893 -383.323786) (xy 341.928896 -383.25636) (xy 341.936975 -383.189419)
			(xy 341.953015 -383.123928) (xy 341.976783 -383.06083) (xy 342.007937 -383.001032) (xy 342.04603 -382.945397)
			(xy 342.067896 -382.919732) (xy 342.073703 -382.912594) (xy 342.080212 -382.895398) (xy 342.080596 -382.886204)
			(xy 342.080596 -382.728724) (xy 342.081035 -382.718604) (xy 342.088775 -382.699901) (xy 342.103084 -382.685586)
			(xy 342.121784 -382.677839) (xy 342.131904 -382.677416) (xy 342.848184 -382.677416) (xy 342.858307 -382.677829)
			(xy 342.877014 -382.685575) (xy 342.891329 -382.699893) (xy 342.899072 -382.7186) (xy 342.899492 -382.728724)
			(xy 342.899492 -382.886204) (xy 342.899902 -382.895391) (xy 342.906416 -382.912575) (xy 342.912192 -382.919732)
			(xy 342.934021 -382.945426) (xy 342.972111 -383.001056) (xy 343.003264 -383.060849) (xy 343.02703 -383.123942)
			(xy 343.043069 -383.189427) (xy 343.051148 -383.256362) (xy 343.051151 -383.323783) (xy 343.043078 -383.390719)
			(xy 343.027046 -383.456207) (xy 343.003286 -383.519302) (xy 342.972139 -383.579097) (xy 342.934054 -383.634731)
			(xy 342.912192 -383.660396) (xy 342.906414 -383.667554) (xy 342.899888 -383.684735) (xy 342.899492 -383.693924)
			(xy 342.899492 -384.186176) (xy 342.899916 -384.195362) (xy 342.90642 -384.212546) (xy 342.912192 -384.219704)
			(xy 342.934092 -384.24534) (xy 342.97218 -384.300978) (xy 343.003329 -384.360779) (xy 343.027092 -384.423879)
			(xy 343.043125 -384.489372) (xy 343.051198 -384.556314) (xy 343.051195 -384.62374) (xy 343.043115 -384.690681)
			(xy 343.027076 -384.756172) (xy 343.003307 -384.819271) (xy 342.972152 -384.879068) (xy 342.934058 -384.934703)
			(xy 342.912192 -384.960368) (xy 342.906383 -384.967504) (xy 342.899876 -384.984702) (xy 342.899492 -384.993896)
			(xy 342.899492 -385.151376) (xy 342.899064 -385.161498) (xy 342.891323 -385.180203) (xy 342.877009 -385.194518)
			(xy 342.858306 -385.202263) (xy 342.848184 -385.202684) (xy 342.131904 -385.202684) (xy 342.12178 -385.20228)
			(xy 342.103073 -385.194531) (xy 342.088758 -385.18021) (xy 342.081016 -385.1615) (xy 342.080596 -385.151376)
			(xy 342.080596 -384.993896) (xy 342.080189 -384.984709) (xy 342.073673 -384.967524) (xy 342.067896 -384.960368)
			(xy 342.046068 -384.934674) (xy 342.007978 -384.879043) (xy 341.976826 -384.819251) (xy 341.95306 -384.756158)
			(xy 341.937022 -384.690672) (xy 341.928943 -384.623737) (xy 341.92894 -384.556317) (xy 341.937012 -384.489381)
			(xy 341.953044 -384.423894) (xy 341.976804 -384.360799) (xy 342.00795 -384.301003) (xy 342.046034 -384.245369)
			(xy 342.067896 -384.219704) (xy 342.073673 -384.212545) (xy 342.080199 -384.195365) (xy 342.080596 -384.186176)
			(xy 342.080596 -383.693924) (xy 342.080175 -383.684738) (xy 342.073669 -383.667553) (xy 342.067896 -383.660396)
			(xy 342.045997 -383.63476) (xy 342.007909 -383.579121) (xy 341.976761 -383.519321) (xy 341.952999 -383.45622)
			(xy 341.936966 -383.390728) (xy 341.928893 -383.323786) (xy 340.826798 -383.323786) (xy 340.82701 -383.324351)
			(xy 340.842982 -383.389735) (xy 340.851025 -383.456559) (xy 340.851024 -383.523865) (xy 340.842978 -383.590689)
			(xy 340.827003 -383.656072) (xy 340.803328 -383.719078) (xy 340.772292 -383.778802) (xy 340.734341 -383.834388)
			(xy 340.712552 -383.86004) (xy 340.70675 -383.867181) (xy 340.70024 -383.884375) (xy 340.699852 -383.893568)
			(xy 340.699852 -384.051556) (xy 340.699343 -384.061701) (xy 340.691572 -384.080442) (xy 340.677202 -384.094765)
			(xy 340.658436 -384.102476) (xy 340.64829 -384.102864) (xy 339.93201 -384.102864) (xy 339.921884 -384.102365)
			(xy 339.903164 -384.094642) (xy 339.888808 -384.080359) (xy 339.880987 -384.061679) (xy 339.880448 -384.051556)
			(xy 339.880448 -383.893568) (xy 339.880042 -383.884381) (xy 339.873524 -383.867197) (xy 339.867748 -383.86004)
			(xy 339.845976 -383.834375) (xy 339.808026 -383.778791) (xy 339.776992 -383.719069) (xy 339.753318 -383.656066)
			(xy 339.737343 -383.590685) (xy 339.729298 -383.523864) (xy 339.729296 -383.45656) (xy 339.737339 -383.389738)
			(xy 339.75331 -383.324357) (xy 339.776982 -383.261353) (xy 339.808014 -383.20163) (xy 339.845961 -383.146044)
			(xy 339.867748 -383.120392) (xy 339.873536 -383.113241) (xy 339.880055 -383.096055) (xy 339.880448 -383.086864)
			(xy 339.880448 -382.593342) (xy 339.880007 -382.584158) (xy 339.873513 -382.566974) (xy 339.867748 -382.559814)
			(xy 339.84595 -382.53417) (xy 339.808001 -382.478583) (xy 339.776968 -382.418858) (xy 339.753295 -382.355852)
			(xy 339.737322 -382.290469) (xy 339.729279 -382.223645) (xy 336.45124 -382.223645) (xy 336.45124 -382.223704)
			(xy 336.443164 -382.290643) (xy 336.427128 -382.356132) (xy 336.403363 -382.419228) (xy 336.372211 -382.479024)
			(xy 336.334121 -382.534658) (xy 336.312256 -382.560322) (xy 336.306462 -382.567469) (xy 336.299947 -382.584658)
			(xy 336.299556 -382.59385) (xy 336.299556 -383.086356) (xy 336.299997 -383.09554) (xy 336.306491 -383.112724)
			(xy 336.312256 -383.119884) (xy 336.334137 -383.145536) (xy 336.372228 -383.201171) (xy 336.403381 -383.260969)
			(xy 336.427018 -383.323726) (xy 337.529124 -383.323726) (xy 337.529128 -383.256419) (xy 337.537175 -383.189595)
			(xy 337.55315 -383.124211) (xy 337.576825 -383.061205) (xy 337.607861 -383.001481) (xy 337.645811 -382.945893)
			(xy 337.6676 -382.92024) (xy 337.673405 -382.9131) (xy 337.679914 -382.895906) (xy 337.6803 -382.886712)
			(xy 337.6803 -382.728724) (xy 337.680741 -382.718571) (xy 337.688529 -382.699819) (xy 337.70292 -382.685495)
			(xy 337.721708 -382.677795) (xy 337.731862 -382.677416) (xy 338.448142 -382.677416) (xy 338.458268 -382.677891)
			(xy 338.476986 -382.685629) (xy 338.49134 -382.699918) (xy 338.499162 -382.7186) (xy 338.499704 -382.728724)
			(xy 338.499704 -382.886712) (xy 338.500108 -382.8959) (xy 338.506626 -382.913084) (xy 338.512404 -382.92024)
			(xy 338.534155 -382.945922) (xy 338.572102 -383.001505) (xy 338.603135 -383.061225) (xy 338.626808 -383.124225)
			(xy 338.642782 -383.189604) (xy 338.650828 -383.256422) (xy 338.650831 -383.323724) (xy 338.642791 -383.390543)
			(xy 338.626824 -383.455923) (xy 338.603157 -383.518926) (xy 338.57213 -383.578648) (xy 338.534188 -383.634235)
			(xy 338.512404 -383.659888) (xy 338.506588 -383.66702) (xy 338.500085 -383.68422) (xy 338.499704 -383.693416)
			(xy 338.499704 -384.186684) (xy 338.500121 -384.19587) (xy 338.50663 -384.213055) (xy 338.512404 -384.220212)
			(xy 338.534226 -384.245836) (xy 338.572171 -384.301427) (xy 338.6032 -384.361155) (xy 338.626869 -384.424163)
			(xy 338.642838 -384.489548) (xy 338.650879 -384.556374) (xy 338.650875 -384.623681) (xy 338.642828 -384.690505)
			(xy 338.626853 -384.755889) (xy 338.603178 -384.818894) (xy 338.572143 -384.878619) (xy 338.534193 -384.934207)
			(xy 338.512404 -384.95986) (xy 338.5066 -384.967) (xy 338.50009 -384.984194) (xy 338.499704 -384.993388)
			(xy 338.499704 -385.151376) (xy 338.499259 -385.161528) (xy 338.491472 -385.180279) (xy 338.477082 -385.194603)
			(xy 338.458296 -385.202305) (xy 338.448142 -385.202684) (xy 337.731862 -385.202684) (xy 337.721736 -385.202205)
			(xy 337.703018 -385.194469) (xy 337.688664 -385.180181) (xy 337.680842 -385.1615) (xy 337.6803 -385.151376)
			(xy 337.6803 -384.993388) (xy 337.679895 -384.9842) (xy 337.673378 -384.967016) (xy 337.6676 -384.95986)
			(xy 337.645849 -384.934178) (xy 337.607901 -384.878595) (xy 337.576869 -384.818875) (xy 337.553196 -384.755875)
			(xy 337.537221 -384.690497) (xy 337.529175 -384.623678) (xy 337.529172 -384.556376) (xy 337.537212 -384.489557)
			(xy 337.55318 -384.424177) (xy 337.576847 -384.361174) (xy 337.607874 -384.301451) (xy 337.645816 -384.245865)
			(xy 337.6676 -384.220212) (xy 337.673416 -384.213081) (xy 337.679919 -384.19588) (xy 337.6803 -384.186684)
			(xy 337.6803 -383.693416) (xy 337.679882 -383.68423) (xy 337.673374 -383.667045) (xy 337.6676 -383.659888)
			(xy 337.645778 -383.634264) (xy 337.607833 -383.578673) (xy 337.576803 -383.518945) (xy 337.553134 -383.455937)
			(xy 337.537165 -383.390552) (xy 337.529124 -383.323726) (xy 336.427018 -383.323726) (xy 336.427146 -383.324067)
			(xy 336.443182 -383.389559) (xy 336.451257 -383.456499) (xy 336.451256 -383.523925) (xy 336.443177 -383.590865)
			(xy 336.427139 -383.656356) (xy 336.403371 -383.719453) (xy 336.372216 -383.77925) (xy 336.334122 -383.834883)
			(xy 336.312256 -383.860548) (xy 336.306451 -383.867687) (xy 336.299943 -383.884882) (xy 336.299556 -383.894076)
			(xy 336.299556 -384.051556) (xy 336.29898 -384.061655) (xy 336.291267 -384.080321) (xy 336.276999 -384.094616)
			(xy 336.258346 -384.102362) (xy 336.248248 -384.102864) (xy 335.531968 -384.102864) (xy 335.521839 -384.102509)
			(xy 335.503128 -384.094744) (xy 335.488813 -384.080408) (xy 335.481076 -384.061686) (xy 335.48066 -384.051556)
			(xy 335.48066 -383.894076) (xy 335.480248 -383.884889) (xy 335.473734 -383.867706) (xy 335.46796 -383.860548)
			(xy 335.446113 -383.834869) (xy 335.408027 -383.779236) (xy 335.376877 -383.719441) (xy 335.353114 -383.656346)
			(xy 335.337079 -383.590859) (xy 335.329002 -383.523923) (xy 335.329001 -383.456501) (xy 335.337074 -383.389565)
			(xy 335.353107 -383.324077) (xy 335.376868 -383.260981) (xy 335.408014 -383.201185) (xy 335.446098 -383.14555)
			(xy 335.46796 -383.119884) (xy 335.473753 -383.112737) (xy 335.480268 -383.095548) (xy 335.48066 -383.086356)
			(xy 335.48066 -382.59385) (xy 335.480213 -382.584667) (xy 335.473723 -382.567483) (xy 335.46796 -382.560322)
			(xy 335.446088 -382.534664) (xy 335.408002 -382.479028) (xy 335.376854 -382.41923) (xy 335.353092 -382.356132)
			(xy 335.337058 -382.290643) (xy 335.328984 -382.223704) (xy 332.050913 -382.223704) (xy 332.042877 -382.290466)
			(xy 332.026905 -382.355848) (xy 332.003234 -382.418852) (xy 331.972202 -382.478575) (xy 331.934255 -382.534162)
			(xy 331.912468 -382.559814) (xy 331.906679 -382.566964) (xy 331.90016 -382.584151) (xy 331.899768 -382.593342)
			(xy 331.899768 -383.086864) (xy 331.900203 -383.096048) (xy 331.9067 -383.113233) (xy 331.912468 -383.120392)
			(xy 331.934271 -383.146031) (xy 331.972219 -383.20162) (xy 332.003251 -383.261345) (xy 332.026711 -383.323786)
			(xy 333.128805 -383.323786) (xy 333.128808 -383.25636) (xy 333.136888 -383.189419) (xy 333.152927 -383.123927)
			(xy 333.176696 -383.060829) (xy 333.207852 -383.001032) (xy 333.245945 -382.945397) (xy 333.267812 -382.919732)
			(xy 333.273621 -382.912596) (xy 333.280128 -382.895398) (xy 333.280512 -382.886204) (xy 333.280512 -382.728724)
			(xy 333.280936 -382.718602) (xy 333.288678 -382.699896) (xy 333.302993 -382.685581) (xy 333.321698 -382.677837)
			(xy 333.33182 -382.677416) (xy 334.0481 -382.677416) (xy 334.058224 -382.677816) (xy 334.076931 -382.685568)
			(xy 334.091246 -382.699889) (xy 334.098988 -382.718599) (xy 334.099408 -382.728724) (xy 334.099408 -382.886204)
			(xy 334.099815 -382.895392) (xy 334.106331 -382.912576) (xy 334.112108 -382.919732) (xy 334.133936 -382.945427)
			(xy 334.172026 -383.001057) (xy 334.203177 -383.060849) (xy 334.226943 -383.123942) (xy 334.242981 -383.189428)
			(xy 334.25106 -383.256363) (xy 334.251063 -383.323783) (xy 334.242991 -383.390719) (xy 334.226959 -383.456206)
			(xy 334.2032 -383.519301) (xy 334.172053 -383.579096) (xy 334.13397 -383.634731) (xy 334.112108 -383.660396)
			(xy 334.106332 -383.667556) (xy 334.099805 -383.684735) (xy 334.099408 -383.693924) (xy 334.099408 -384.186176)
			(xy 334.099828 -384.195362) (xy 334.106335 -384.212547) (xy 334.112108 -384.219704) (xy 334.134007 -384.24534)
			(xy 334.172094 -384.300979) (xy 334.203243 -384.360779) (xy 334.227005 -384.42388) (xy 334.243037 -384.489373)
			(xy 334.25111 -384.556314) (xy 334.251107 -384.62374) (xy 334.243028 -384.690681) (xy 334.226989 -384.756172)
			(xy 334.203221 -384.81927) (xy 334.172066 -384.879067) (xy 334.133974 -384.934703) (xy 334.112108 -384.960368)
			(xy 334.106301 -384.967506) (xy 334.099792 -384.984702) (xy 334.099408 -384.993896) (xy 334.099408 -385.151376)
			(xy 334.098965 -385.161496) (xy 334.091226 -385.180198) (xy 334.076918 -385.194512) (xy 334.05822 -385.20226)
			(xy 334.0481 -385.202684) (xy 333.33182 -385.202684) (xy 333.321697 -385.202267) (xy 333.302991 -385.194523)
			(xy 333.288675 -385.180206) (xy 333.280932 -385.161499) (xy 333.280512 -385.151376) (xy 333.280512 -384.993896)
			(xy 333.280101 -384.984709) (xy 333.273587 -384.967525) (xy 333.267812 -384.960368) (xy 333.245983 -384.934674)
			(xy 333.207892 -384.879044) (xy 333.176739 -384.819252) (xy 333.152973 -384.756158) (xy 333.136934 -384.690673)
			(xy 333.128855 -384.623738) (xy 333.128852 -384.556316) (xy 333.136925 -384.48938) (xy 333.152957 -384.423893)
			(xy 333.176717 -384.360798) (xy 333.207865 -384.301003) (xy 333.24595 -384.245369) (xy 333.267812 -384.219704)
			(xy 333.273591 -384.212546) (xy 333.280116 -384.195365) (xy 333.280512 -384.186176) (xy 333.280512 -383.693924)
			(xy 333.280088 -383.684738) (xy 333.273583 -383.667554) (xy 333.267812 -383.660396) (xy 333.245912 -383.63476)
			(xy 333.207824 -383.579122) (xy 333.176674 -383.519322) (xy 333.152911 -383.456221) (xy 333.136878 -383.390728)
			(xy 333.128805 -383.323786) (xy 332.026711 -383.323786) (xy 332.026923 -383.324351) (xy 332.042895 -383.389735)
			(xy 332.050937 -383.456559) (xy 332.050936 -383.523865) (xy 332.04289 -383.590689) (xy 332.026916 -383.656072)
			(xy 332.003242 -383.719077) (xy 331.972207 -383.778801) (xy 331.934257 -383.834388) (xy 331.912468 -383.86004)
			(xy 331.906668 -383.867183) (xy 331.900156 -383.884375) (xy 331.899768 -383.893568) (xy 331.899768 -384.051556)
			(xy 331.899342 -384.061711) (xy 331.891555 -384.080469) (xy 331.877159 -384.094795) (xy 331.858363 -384.10249)
			(xy 331.848206 -384.102864) (xy 331.131926 -384.102864) (xy 331.121801 -384.102352) (xy 331.103082 -384.094634)
			(xy 331.088724 -384.080355) (xy 331.080904 -384.061678) (xy 331.080364 -384.051556) (xy 331.080364 -383.893568)
			(xy 331.079955 -383.884381) (xy 331.073439 -383.867198) (xy 331.067664 -383.86004) (xy 331.045891 -383.834375)
			(xy 331.00794 -383.778791) (xy 330.976905 -383.71907) (xy 330.95323 -383.656067) (xy 330.937256 -383.590686)
			(xy 330.92921 -383.523864) (xy 330.929208 -383.45656) (xy 330.937251 -383.389738) (xy 330.953223 -383.324356)
			(xy 330.976895 -383.261352) (xy 331.007928 -383.20163) (xy 331.045877 -383.146044) (xy 331.067664 -383.120392)
			(xy 331.073454 -383.113243) (xy 331.079971 -383.096055) (xy 331.080364 -383.086864) (xy 331.080364 -382.593342)
			(xy 331.079919 -382.584159) (xy 331.073428 -382.566975) (xy 331.067664 -382.559814) (xy 331.045866 -382.53417)
			(xy 331.007916 -382.478583) (xy 330.976881 -382.418859) (xy 330.953208 -382.355853) (xy 330.937235 -382.29047)
			(xy 330.929191 -382.223646) (xy 301.250888 -382.223646) (xy 301.250888 -382.223704) (xy 301.242813 -382.290641)
			(xy 301.226779 -382.356129) (xy 301.203017 -382.419226) (xy 301.171869 -382.479022) (xy 301.133783 -382.534656)
			(xy 301.11192 -382.560322) (xy 301.106134 -382.567475) (xy 301.099612 -382.584659) (xy 301.09922 -382.59385)
			(xy 301.09922 -383.086356) (xy 301.099647 -383.095542) (xy 301.106148 -383.112726) (xy 301.11192 -383.119884)
			(xy 301.133799 -383.145537) (xy 301.171886 -383.201173) (xy 301.203035 -383.260972) (xy 301.22669 -383.323786)
			(xy 302.328775 -383.323786) (xy 302.328778 -383.25636) (xy 302.336857 -383.18942) (xy 302.352895 -383.123929)
			(xy 302.376662 -383.060831) (xy 302.407816 -383.001033) (xy 302.445907 -382.945398) (xy 302.467772 -382.919732)
			(xy 302.473589 -382.912601) (xy 302.480089 -382.895399) (xy 302.480472 -382.886204) (xy 302.480472 -382.728724)
			(xy 302.480935 -382.718606) (xy 302.48867 -382.699909) (xy 302.502972 -382.685595) (xy 302.521663 -382.677843)
			(xy 302.53178 -382.677416) (xy 303.24806 -382.677416) (xy 303.258182 -382.677849) (xy 303.276888 -382.685587)
			(xy 303.291204 -382.699899) (xy 303.298948 -382.718602) (xy 303.299368 -382.728724) (xy 303.299368 -382.886204)
			(xy 303.299783 -382.89539) (xy 303.306294 -382.912575) (xy 303.312068 -382.919732) (xy 303.333898 -382.945426)
			(xy 303.37199 -383.001056) (xy 303.403144 -383.060847) (xy 303.426911 -383.123941) (xy 303.44295 -383.189427)
			(xy 303.451029 -383.256362) (xy 303.451033 -383.323784) (xy 303.44296 -383.39072) (xy 303.426927 -383.456208)
			(xy 303.403166 -383.519303) (xy 303.372017 -383.579098) (xy 303.333931 -383.634731) (xy 303.312068 -383.660396)
			(xy 303.306286 -383.667552) (xy 303.299764 -383.684734) (xy 303.299368 -383.693924) (xy 303.299368 -384.186176)
			(xy 303.299797 -384.195361) (xy 303.306299 -384.212545) (xy 303.312068 -384.219704) (xy 303.333968 -384.24534)
			(xy 303.372058 -384.300978) (xy 303.403209 -384.360778) (xy 303.426973 -384.423878) (xy 303.443007 -384.489371)
			(xy 303.45108 -384.556313) (xy 303.451077 -384.623741) (xy 303.442997 -384.690682) (xy 303.426957 -384.756173)
			(xy 303.403187 -384.819272) (xy 303.37203 -384.879069) (xy 303.333935 -384.934703) (xy 303.312068 -384.960368)
			(xy 303.306256 -384.967502) (xy 303.299751 -384.984701) (xy 303.299368 -384.993896) (xy 303.299368 -385.151376)
			(xy 303.298964 -385.161501) (xy 303.291218 -385.18021) (xy 303.276897 -385.194527) (xy 303.258185 -385.202267)
			(xy 303.24806 -385.202684) (xy 302.53178 -385.202684) (xy 302.521654 -385.2023) (xy 302.502947 -385.194542)
			(xy 302.488633 -385.180216) (xy 302.480891 -385.161502) (xy 302.480472 -385.151376) (xy 302.480472 -384.993896)
			(xy 302.48007 -384.984708) (xy 302.473551 -384.967523) (xy 302.467772 -384.960368) (xy 302.445944 -384.934673)
			(xy 302.407856 -384.879042) (xy 302.376706 -384.81925) (xy 302.352941 -384.756157) (xy 302.336904 -384.690672)
			(xy 302.328825 -384.623737) (xy 302.328822 -384.556317) (xy 302.336894 -384.489382) (xy 302.352925 -384.423895)
			(xy 302.376684 -384.3608) (xy 302.407829 -384.301004) (xy 302.445911 -384.24537) (xy 302.467772 -384.219704)
			(xy 302.473558 -384.212552) (xy 302.480077 -384.195366) (xy 302.480472 -384.186176) (xy 302.480472 -383.693924)
			(xy 302.480057 -383.684737) (xy 302.473547 -383.667552) (xy 302.467772 -383.660396) (xy 302.445874 -383.634759)
			(xy 302.407788 -383.57912) (xy 302.37664 -383.51932) (xy 302.352879 -383.456219) (xy 302.336847 -383.390727)
			(xy 302.328775 -383.323786) (xy 301.22669 -383.323786) (xy 301.226797 -383.32407) (xy 301.242831 -383.38956)
			(xy 301.250905 -383.4565) (xy 301.250904 -383.523924) (xy 301.242827 -383.590863) (xy 301.22679 -383.656353)
			(xy 301.203025 -383.71945) (xy 301.171874 -383.779247) (xy 301.133784 -383.834882) (xy 301.11192 -383.860548)
			(xy 301.106123 -383.867693) (xy 301.099608 -383.884884) (xy 301.09922 -383.894076) (xy 301.09922 -384.051556)
			(xy 301.098748 -384.061673) (xy 301.091018 -384.080372) (xy 301.076719 -384.094687) (xy 301.058029 -384.102437)
			(xy 301.047912 -384.102864) (xy 300.331632 -384.102864) (xy 300.321507 -384.102457) (xy 300.302797 -384.094713)
			(xy 300.28848 -384.080393) (xy 300.28074 -384.061681) (xy 300.280324 -384.051556) (xy 300.280324 -383.894076)
			(xy 300.27992 -383.884888) (xy 300.273402 -383.867704) (xy 300.267624 -383.860548) (xy 300.245775 -383.83487)
			(xy 300.207684 -383.779238) (xy 300.176531 -383.719444) (xy 300.152765 -383.656349) (xy 300.136728 -383.590861)
			(xy 300.12865 -383.523923) (xy 300.128649 -383.456501) (xy 300.136724 -383.389563) (xy 300.152758 -383.324074)
			(xy 300.176522 -383.260978) (xy 300.207672 -383.201183) (xy 300.24576 -383.145549) (xy 300.267624 -383.119884)
			(xy 300.273413 -383.112733) (xy 300.279931 -383.095547) (xy 300.280324 -383.086356) (xy 300.280324 -382.59385)
			(xy 300.279884 -382.584666) (xy 300.273391 -382.567482) (xy 300.267624 -382.560322) (xy 300.245749 -382.534665)
			(xy 300.207659 -382.47903) (xy 300.176508 -382.419233) (xy 300.152743 -382.356135) (xy 300.136708 -382.290645)
			(xy 300.128632 -382.223705) (xy 296.851097 -382.223705) (xy 296.843022 -382.290641) (xy 296.826989 -382.356129)
			(xy 296.803227 -382.419225) (xy 296.77208 -382.479021) (xy 296.733994 -382.534656) (xy 296.712132 -382.560322)
			(xy 296.706335 -382.567467) (xy 296.699823 -382.584658) (xy 296.699432 -382.59385) (xy 296.699432 -383.086356)
			(xy 296.699878 -383.095539) (xy 296.706368 -383.112723) (xy 296.712132 -383.119884) (xy 296.734011 -383.145537)
			(xy 296.772097 -383.201174) (xy 296.803245 -383.260972) (xy 296.826877 -383.323727) (xy 297.928982 -383.323727)
			(xy 297.928985 -383.256419) (xy 297.937033 -383.189593) (xy 297.953011 -383.124208) (xy 297.97669 -383.061202)
			(xy 298.007729 -383.001478) (xy 298.045685 -382.945891) (xy 298.067476 -382.92024) (xy 298.073278 -382.913098)
			(xy 298.07979 -382.895905) (xy 298.080176 -382.886712) (xy 298.080176 -382.728724) (xy 298.080641 -382.718574)
			(xy 298.088424 -382.699827) (xy 298.102807 -382.685504) (xy 298.121587 -382.677799) (xy 298.131738 -382.677416)
			(xy 298.848018 -382.677416) (xy 298.858143 -382.677911) (xy 298.87686 -382.68564) (xy 298.891215 -382.699923)
			(xy 298.899038 -382.718602) (xy 298.89958 -382.728724) (xy 298.89958 -382.886712) (xy 298.899989 -382.895899)
			(xy 298.906504 -382.913083) (xy 298.91228 -382.92024) (xy 298.934031 -382.945922) (xy 298.97198 -383.001504)
			(xy 299.003014 -383.061224) (xy 299.026688 -383.124225) (xy 299.042663 -383.189603) (xy 299.050709 -383.256422)
			(xy 299.050713 -383.323724) (xy 299.042672 -383.390544) (xy 299.026704 -383.455924) (xy 299.003036 -383.518926)
			(xy 298.972008 -383.578649) (xy 298.934065 -383.634235) (xy 298.91228 -383.659888) (xy 298.906461 -383.667017)
			(xy 298.89996 -383.68422) (xy 298.89958 -383.693416) (xy 298.89958 -384.186684) (xy 298.900003 -384.19587)
			(xy 298.906508 -384.213054) (xy 298.91228 -384.220212) (xy 298.934103 -384.245835) (xy 298.972049 -384.301426)
			(xy 299.00308 -384.361154) (xy 299.02675 -384.424162) (xy 299.04272 -384.489548) (xy 299.050761 -384.556373)
			(xy 299.050757 -384.623681) (xy 299.04271 -384.690506) (xy 299.026734 -384.75589) (xy 299.003058 -384.818895)
			(xy 298.972021 -384.87862) (xy 298.934069 -384.934208) (xy 298.91228 -384.95986) (xy 298.906473 -384.966998)
			(xy 298.899965 -384.984194) (xy 298.89958 -384.993388) (xy 298.89958 -385.151376) (xy 298.899159 -385.161531)
			(xy 298.891367 -385.180287) (xy 298.87697 -385.194612) (xy 298.858175 -385.202309) (xy 298.848018 -385.202684)
			(xy 298.131738 -385.202684) (xy 298.121617 -385.202143) (xy 298.102901 -385.194432) (xy 298.088544 -385.180162)
			(xy 298.08072 -385.161494) (xy 298.080176 -385.151376) (xy 298.080176 -384.993388) (xy 298.079777 -384.9842)
			(xy 298.073256 -384.967015) (xy 298.067476 -384.95986) (xy 298.045723 -384.934179) (xy 298.00777 -384.878598)
			(xy 297.976733 -384.818878) (xy 297.953057 -384.755878) (xy 297.93708 -384.690499) (xy 297.929033 -384.623679)
			(xy 297.92903 -384.556376) (xy 297.937071 -384.489555) (xy 297.953041 -384.424174) (xy 297.976711 -384.361171)
			(xy 298.007742 -384.301449) (xy 298.045689 -384.245864) (xy 298.067476 -384.220212) (xy 298.07329 -384.213079)
			(xy 298.079795 -384.195879) (xy 298.080176 -384.186684) (xy 298.080176 -383.693416) (xy 298.079764 -383.684229)
			(xy 298.073252 -383.667044) (xy 298.067476 -383.659888) (xy 298.045651 -383.634266) (xy 298.007701 -383.578676)
			(xy 297.976668 -383.518948) (xy 297.952995 -383.45594) (xy 297.937024 -383.390554) (xy 297.928982 -383.323727)
			(xy 296.826877 -383.323727) (xy 296.827007 -383.324071) (xy 296.84304 -383.389561) (xy 296.851114 -383.4565)
			(xy 296.851113 -383.523924) (xy 296.843036 -383.590863) (xy 296.827 -383.656352) (xy 296.803235 -383.71945)
			(xy 296.772084 -383.779247) (xy 296.733996 -383.834882) (xy 296.712132 -383.860548) (xy 296.706324 -383.867685)
			(xy 296.699818 -383.884882) (xy 296.699432 -383.894076) (xy 296.699432 -384.051556) (xy 296.698949 -384.061672)
			(xy 296.691221 -384.080368) (xy 296.676925 -384.094683) (xy 296.658239 -384.102435) (xy 296.648124 -384.102864)
			(xy 295.931844 -384.102864) (xy 295.92172 -384.102447) (xy 295.90301 -384.094707) (xy 295.888693 -384.08039)
			(xy 295.880953 -384.06168) (xy 295.880536 -384.051556) (xy 295.880536 -383.894076) (xy 295.880129 -383.884889)
			(xy 295.873612 -383.867705) (xy 295.867836 -383.860548) (xy 295.845986 -383.83487) (xy 295.807895 -383.779238)
			(xy 295.776742 -383.719444) (xy 295.752975 -383.656349) (xy 295.736937 -383.590861) (xy 295.728859 -383.523924)
			(xy 295.728858 -383.4565) (xy 295.736933 -383.389563) (xy 295.752968 -383.324074) (xy 295.776732 -383.260978)
			(xy 295.807883 -383.201182) (xy 295.845972 -383.145549) (xy 295.867836 -383.119884) (xy 295.873626 -383.112735)
			(xy 295.880144 -383.095547) (xy 295.880536 -383.086356) (xy 295.880536 -382.59385) (xy 295.880094 -382.584666)
			(xy 295.873601 -382.567482) (xy 295.867836 -382.560322) (xy 295.845961 -382.534665) (xy 295.80787 -382.479031)
			(xy 295.776718 -382.419233) (xy 295.752953 -382.356135) (xy 295.736917 -382.290645) (xy 295.728841 -382.223705)
			(xy 292.450794 -382.223705) (xy 292.442758 -382.290467) (xy 292.426786 -382.355849) (xy 292.403113 -382.418853)
			(xy 292.37208 -382.478576) (xy 292.334131 -382.534162) (xy 292.312344 -382.559814) (xy 292.306552 -382.566962)
			(xy 292.300036 -382.584151) (xy 292.299644 -382.593342) (xy 292.299644 -383.086864) (xy 292.300084 -383.096048)
			(xy 292.306578 -383.113232) (xy 292.312344 -383.120392) (xy 292.334148 -383.146031) (xy 292.372098 -383.201619)
			(xy 292.403131 -383.261344) (xy 292.426592 -383.323786) (xy 293.528687 -383.323786) (xy 293.52869 -383.25636)
			(xy 293.536769 -383.189419) (xy 293.552808 -383.123928) (xy 293.576576 -383.06083) (xy 293.60773 -383.001033)
			(xy 293.645822 -382.945397) (xy 293.667688 -382.919732) (xy 293.673495 -382.912594) (xy 293.680004 -382.895398)
			(xy 293.680388 -382.886204) (xy 293.680388 -382.728724) (xy 293.680835 -382.718605) (xy 293.688573 -382.699904)
			(xy 293.70288 -382.685589) (xy 293.721577 -382.677841) (xy 293.731696 -382.677416) (xy 294.447976 -382.677416)
			(xy 294.458099 -382.677836) (xy 294.476805 -382.685579) (xy 294.491121 -382.699895) (xy 294.498864 -382.718601)
			(xy 294.499284 -382.728724) (xy 294.499284 -382.886204) (xy 294.499696 -382.895391) (xy 294.506209 -382.912575)
			(xy 294.511984 -382.919732) (xy 294.533813 -382.945426) (xy 294.571904 -383.001056) (xy 294.603057 -383.060848)
			(xy 294.626824 -383.123941) (xy 294.642863 -383.189427) (xy 294.650942 -383.256362) (xy 294.650945 -383.323784)
			(xy 294.642872 -383.39072) (xy 294.62684 -383.456207) (xy 294.603079 -383.519302) (xy 294.571932 -383.579097)
			(xy 294.533846 -383.634731) (xy 294.511984 -383.660396) (xy 294.506205 -383.667553) (xy 294.49968 -383.684735)
			(xy 294.499284 -383.693924) (xy 294.499284 -384.186176) (xy 294.499709 -384.195361) (xy 294.506213 -384.212546)
			(xy 294.511984 -384.219704) (xy 294.533884 -384.24534) (xy 294.571973 -384.300978) (xy 294.603123 -384.360778)
			(xy 294.626885 -384.423879) (xy 294.642919 -384.489372) (xy 294.650992 -384.556314) (xy 294.650989 -384.62374)
			(xy 294.642909 -384.690681) (xy 294.626869 -384.756173) (xy 294.603101 -384.819271) (xy 294.571945 -384.879068)
			(xy 294.533851 -384.934703) (xy 294.511984 -384.960368) (xy 294.506174 -384.967504) (xy 294.499668 -384.984702)
			(xy 294.499284 -384.993896) (xy 294.499284 -385.151376) (xy 294.498864 -385.161499) (xy 294.491121 -385.180205)
			(xy 294.476805 -385.194521) (xy 294.458099 -385.202264) (xy 294.447976 -385.202684) (xy 293.731696 -385.202684)
			(xy 293.721571 -385.202287) (xy 293.702865 -385.194534) (xy 293.68855 -385.180212) (xy 293.680808 -385.161501)
			(xy 293.680388 -385.151376) (xy 293.680388 -384.993896) (xy 293.679982 -384.984708) (xy 293.673466 -384.967524)
			(xy 293.667688 -384.960368) (xy 293.64586 -384.934673) (xy 293.607771 -384.879043) (xy 293.576619 -384.819251)
			(xy 293.552854 -384.756158) (xy 293.536816 -384.690672) (xy 293.528737 -384.623737) (xy 293.528734 -384.556317)
			(xy 293.536806 -384.489381) (xy 293.552838 -384.423894) (xy 293.576597 -384.360799) (xy 293.607743 -384.301004)
			(xy 293.645827 -384.245369) (xy 293.667688 -384.219704) (xy 293.673464 -384.212544) (xy 293.679991 -384.195365)
			(xy 293.680388 -384.186176) (xy 293.680388 -383.693924) (xy 293.679969 -383.684738) (xy 293.673462 -383.667553)
			(xy 293.667688 -383.660396) (xy 293.645789 -383.63476) (xy 293.607702 -383.579121) (xy 293.576554 -383.51932)
			(xy 293.552792 -383.45622) (xy 293.53676 -383.390727) (xy 293.528687 -383.323786) (xy 292.426592 -383.323786)
			(xy 292.426804 -383.32435) (xy 292.442776 -383.389734) (xy 292.450819 -383.456559) (xy 292.450818 -383.523865)
			(xy 292.442772 -383.590689) (xy 292.426797 -383.656073) (xy 292.403121 -383.719078) (xy 292.372085 -383.778802)
			(xy 292.334133 -383.834388) (xy 292.312344 -383.86004) (xy 292.306541 -383.86718) (xy 292.300032 -383.884375)
			(xy 292.299644 -383.893568) (xy 292.299644 -384.051556) (xy 292.299149 -384.06167) (xy 292.291423 -384.080364)
			(xy 292.277132 -384.094679) (xy 292.258449 -384.102433) (xy 292.248336 -384.102864) (xy 291.531802 -384.102864)
			(xy 291.521676 -384.102372) (xy 291.502956 -384.094645) (xy 291.488599 -384.080361) (xy 291.480779 -384.06168)
			(xy 291.48024 -384.051556) (xy 291.48024 -383.893568) (xy 291.479836 -383.88438) (xy 291.473317 -383.867197)
			(xy 291.46754 -383.86004) (xy 291.445768 -383.834375) (xy 291.407819 -383.77879) (xy 291.376785 -383.719068)
			(xy 291.353111 -383.656066) (xy 291.337137 -383.590685) (xy 291.329092 -383.523864) (xy 291.32909 -383.45656)
			(xy 291.337133 -383.389739) (xy 291.353104 -383.324357) (xy 291.376775 -383.261354) (xy 291.407806 -383.20163)
			(xy 291.445753 -383.146044) (xy 291.46754 -383.120392) (xy 291.473328 -383.113241) (xy 291.479847 -383.096055)
			(xy 291.48024 -383.086864) (xy 291.48024 -382.593342) (xy 291.4798 -382.584158) (xy 291.473306 -382.566974)
			(xy 291.46754 -382.559814) (xy 291.445742 -382.53417) (xy 291.407794 -382.478582) (xy 291.376761 -382.418858)
			(xy 291.353088 -382.355852) (xy 291.337116 -382.290469) (xy 291.329073 -382.223645) (xy 288.051034 -382.223645)
			(xy 288.051034 -382.223704) (xy 288.042958 -382.290643) (xy 288.026922 -382.356132) (xy 288.003157 -382.419229)
			(xy 287.972004 -382.479024) (xy 287.933913 -382.534658) (xy 287.912048 -382.560322) (xy 287.906253 -382.567468)
			(xy 287.899739 -382.584658) (xy 287.899348 -382.59385) (xy 287.899348 -383.086356) (xy 287.899791 -383.095539)
			(xy 287.906283 -383.112723) (xy 287.912048 -383.119884) (xy 287.93393 -383.145535) (xy 287.972021 -383.201171)
			(xy 288.003174 -383.260968) (xy 288.026812 -383.323727) (xy 289.128894 -383.323727) (xy 289.128898 -383.256418)
			(xy 289.136946 -383.189593) (xy 289.152924 -383.124208) (xy 289.176604 -383.061202) (xy 289.207644 -383.001477)
			(xy 289.245601 -382.945891) (xy 289.267392 -382.92024) (xy 289.273196 -382.9131) (xy 289.279706 -382.895905)
			(xy 289.280092 -382.886712) (xy 289.280092 -382.728724) (xy 289.280535 -382.718604) (xy 289.288274 -382.699902)
			(xy 289.302582 -382.685588) (xy 289.32128 -382.67784) (xy 289.3314 -382.677416) (xy 290.047934 -382.677416)
			(xy 290.05806 -382.677898) (xy 290.076777 -382.685632) (xy 290.091132 -382.69992) (xy 290.098954 -382.7186)
			(xy 290.099496 -382.728724) (xy 290.099496 -382.886712) (xy 290.099901 -382.8959) (xy 290.106419 -382.913084)
			(xy 290.112196 -382.92024) (xy 290.133947 -382.945922) (xy 290.171895 -383.001505) (xy 290.202928 -383.061225)
			(xy 290.226601 -383.124225) (xy 290.242576 -383.189603) (xy 290.250622 -383.256422) (xy 290.250625 -383.323724)
			(xy 290.242585 -383.390543) (xy 290.226617 -383.455923) (xy 290.20295 -383.518926) (xy 290.171923 -383.578649)
			(xy 290.133981 -383.634235) (xy 290.112196 -383.659888) (xy 290.106379 -383.667019) (xy 290.099877 -383.68422)
			(xy 290.099496 -383.693416) (xy 290.099496 -384.186684) (xy 290.099915 -384.19587) (xy 290.106423 -384.213055)
			(xy 290.112196 -384.220212) (xy 290.134018 -384.245836) (xy 290.171963 -384.301427) (xy 290.202993 -384.361155)
			(xy 290.226662 -384.424163) (xy 290.242632 -384.489548) (xy 290.250673 -384.556373) (xy 290.250669 -384.623681)
			(xy 290.242622 -384.690505) (xy 290.226646 -384.755889) (xy 290.202971 -384.818895) (xy 290.171936 -384.87862)
			(xy 290.133985 -384.934207) (xy 290.112196 -384.95986) (xy 290.106391 -384.966999) (xy 290.099881 -384.984194)
			(xy 290.099496 -384.993388) (xy 290.099496 -385.151376) (xy 290.099064 -385.161497) (xy 290.091323 -385.180201)
			(xy 290.077011 -385.194517) (xy 290.058309 -385.202262) (xy 290.048188 -385.202684) (xy 289.331654 -385.202684)
			(xy 289.321527 -385.202212) (xy 289.30281 -385.194473) (xy 289.288456 -385.180183) (xy 289.280634 -385.1615)
			(xy 289.280092 -385.151376) (xy 289.280092 -384.993388) (xy 289.279689 -384.9842) (xy 289.273171 -384.967016)
			(xy 289.267392 -384.95986) (xy 289.245638 -384.934179) (xy 289.207685 -384.878598) (xy 289.176647 -384.818879)
			(xy 289.15297 -384.755878) (xy 289.136993 -384.690499) (xy 289.128945 -384.623679) (xy 289.128942 -384.556375)
			(xy 289.136983 -384.489554) (xy 289.152954 -384.424174) (xy 289.176625 -384.36117) (xy 289.207657 -384.301448)
			(xy 289.245605 -384.245863) (xy 289.267392 -384.220212) (xy 289.273208 -384.21308) (xy 289.279711 -384.195879)
			(xy 289.280092 -384.186684) (xy 289.280092 -383.693416) (xy 289.279676 -383.684229) (xy 289.273167 -383.667045)
			(xy 289.267392 -383.659888) (xy 289.245567 -383.634266) (xy 289.207616 -383.578676) (xy 289.176581 -383.518949)
			(xy 289.152908 -383.45594) (xy 289.136936 -383.390554) (xy 289.128894 -383.323727) (xy 288.026812 -383.323727)
			(xy 288.02694 -383.324067) (xy 288.042976 -383.389558) (xy 288.051051 -383.456499) (xy 288.05105 -383.523925)
			(xy 288.042971 -383.590865) (xy 288.026933 -383.656356) (xy 288.003164 -383.719454) (xy 287.972009 -383.77925)
			(xy 287.933915 -383.834884) (xy 287.912048 -383.860548) (xy 287.906242 -383.867686) (xy 287.899734 -383.884882)
			(xy 287.899348 -383.894076) (xy 287.899348 -384.051556) (xy 287.898849 -384.06167) (xy 287.891124 -384.080363)
			(xy 287.876834 -384.094677) (xy 287.858153 -384.102432) (xy 287.84804 -384.102864) (xy 287.13176 -384.102864)
			(xy 287.12163 -384.102516) (xy 287.102919 -384.094748) (xy 287.088605 -384.08041) (xy 287.080868 -384.061686)
			(xy 287.080452 -384.051556) (xy 287.080452 -383.894076) (xy 287.080042 -383.884889) (xy 287.073527 -383.867705)
			(xy 287.067752 -383.860548) (xy 287.045902 -383.834871) (xy 287.007809 -383.779239) (xy 286.976655 -383.719445)
			(xy 286.952888 -383.65635) (xy 286.936849 -383.590862) (xy 286.928772 -383.523924) (xy 286.92877 -383.4565)
			(xy 286.936845 -383.389562) (xy 286.952881 -383.324073) (xy 286.976645 -383.260977) (xy 287.007797 -383.201182)
			(xy 287.045887 -383.145548) (xy 287.067752 -383.119884) (xy 287.073544 -383.112736) (xy 287.08006 -383.095547)
			(xy 287.080452 -383.086356) (xy 287.080452 -382.59385) (xy 287.080006 -382.584667) (xy 287.073516 -382.567483)
			(xy 287.067752 -382.560322) (xy 287.045876 -382.534666) (xy 287.007785 -382.479031) (xy 286.976631 -382.419234)
			(xy 286.952865 -382.356136) (xy 286.936829 -382.290645) (xy 286.928753 -382.223705) (xy 262.274304 -382.223705)
			(xy 262.274304 -385.608376) (xy 454.303373 -385.608376) (xy 454.303373 -385.479236) (xy 454.311323 -385.350341)
			(xy 454.327193 -385.222181) (xy 454.350922 -385.09524) (xy 454.382421 -384.970001) (xy 454.42157 -384.846938)
			(xy 454.468221 -384.726519) (xy 454.522196 -384.6092) (xy 454.583291 -384.495426) (xy 454.651274 -384.385629)
			(xy 454.725888 -384.280226) (xy 454.806849 -384.179616) (xy 454.893849 -384.084181) (xy 454.98656 -383.994282)
			(xy 455.08463 -383.910261) (xy 455.187685 -383.832437) (xy 455.295336 -383.761105) (xy 455.407175 -383.696535)
			(xy 455.522776 -383.638973) (xy 455.641701 -383.588636) (xy 455.7635 -383.545716) (xy 455.88771 -383.510375)
			(xy 456.013859 -383.482748) (xy 456.141471 -383.462939) (xy 456.27006 -383.451023) (xy 456.399138 -383.447047)
			(xy 456.528216 -383.451023) (xy 456.656805 -383.462939) (xy 456.784417 -383.482748) (xy 456.910566 -383.510375)
			(xy 457.034776 -383.545716) (xy 457.156575 -383.588636) (xy 457.2755 -383.638973) (xy 457.391101 -383.696535)
			(xy 457.50294 -383.761105) (xy 457.610591 -383.832437) (xy 457.713646 -383.910261) (xy 457.811716 -383.994282)
			(xy 457.904427 -384.084181) (xy 457.991427 -384.179616) (xy 458.072388 -384.280226) (xy 458.147002 -384.385629)
			(xy 458.214985 -384.495426) (xy 458.27608 -384.6092) (xy 458.330055 -384.726519) (xy 458.376706 -384.846938)
			(xy 458.415855 -384.970001) (xy 458.447354 -385.09524) (xy 458.471083 -385.222181) (xy 458.486953 -385.350341)
			(xy 458.494903 -385.479236) (xy 458.4954 -385.543806) (xy 458.494903 -385.608376) (xy 458.486953 -385.737271)
			(xy 458.471083 -385.865431) (xy 458.447354 -385.992372) (xy 458.415855 -386.117611) (xy 458.376706 -386.240674)
			(xy 458.330055 -386.361093) (xy 458.27608 -386.478412) (xy 458.214985 -386.592186) (xy 458.147002 -386.701983)
			(xy 458.072388 -386.807386) (xy 457.991427 -386.907996) (xy 457.904427 -387.003431) (xy 457.811716 -387.09333)
			(xy 457.713646 -387.177351) (xy 457.610591 -387.255175) (xy 457.50294 -387.326507) (xy 457.391101 -387.391077)
			(xy 457.2755 -387.448639) (xy 457.156575 -387.498976) (xy 457.034776 -387.541896) (xy 456.910566 -387.577237)
			(xy 456.784417 -387.604864) (xy 456.656805 -387.624673) (xy 456.528216 -387.636589) (xy 456.399138 -387.640566)
			(xy 456.27006 -387.636589) (xy 456.141471 -387.624673) (xy 456.013859 -387.604864) (xy 455.88771 -387.577237)
			(xy 455.7635 -387.541896) (xy 455.641701 -387.498976) (xy 455.522776 -387.448639) (xy 455.407175 -387.391077)
			(xy 455.295336 -387.326507) (xy 455.187685 -387.255175) (xy 455.08463 -387.177351) (xy 454.98656 -387.09333)
			(xy 454.893849 -387.003431) (xy 454.806849 -386.907996) (xy 454.725888 -386.807386) (xy 454.651274 -386.701983)
			(xy 454.583291 -386.592186) (xy 454.522196 -386.478412) (xy 454.468221 -386.361093) (xy 454.42157 -386.240674)
			(xy 454.382421 -386.117611) (xy 454.350922 -385.992372) (xy 454.327193 -385.865431) (xy 454.311323 -385.737271)
			(xy 454.303373 -385.608376) (xy 262.274304 -385.608376) (xy 262.274304 -387.892798) (xy 262.273903 -387.902871)
			(xy 262.266168 -387.92147) (xy 262.259318 -387.928866) (xy 259.197602 -390.990582) (xy 259.190193 -390.997411)
			(xy 259.171601 -391.005138) (xy 259.161534 -391.005568) (xy 245.155466 -391.005568) (xy 245.143121 -391.006101)
			(xy 245.120249 -391.015389) (xy 245.111016 -391.023602) (xy 245.110508 -391.02411) (xy 244.084602 -392.050016)
			(xy 244.076151 -392.059207) (xy 244.066584 -392.082246) (xy 244.06606 -392.09472) (xy 244.06606 -397.823885)
			(xy 286.928734 -397.823885) (xy 286.928737 -397.756458) (xy 286.936817 -397.689516) (xy 286.952859 -397.624024)
			(xy 286.976629 -397.560925) (xy 287.007787 -397.501128) (xy 287.045884 -397.445494) (xy 287.067752 -397.41983)
			(xy 287.073567 -397.412698) (xy 287.080069 -397.395497) (xy 287.080452 -397.386302) (xy 287.080452 -396.89405)
			(xy 287.080006 -396.884867) (xy 287.073516 -396.867683) (xy 287.067752 -396.860522) (xy 287.045876 -396.834866)
			(xy 287.007785 -396.779231) (xy 286.976631 -396.719434) (xy 286.952865 -396.656336) (xy 286.936829 -396.590845)
			(xy 286.928753 -396.523905) (xy 286.928754 -396.45648) (xy 286.936832 -396.38954) (xy 286.95287 -396.32405)
			(xy 286.976638 -396.260952) (xy 287.007792 -396.201156) (xy 287.045886 -396.145522) (xy 287.067752 -396.119858)
			(xy 287.073555 -396.112718) (xy 287.080065 -396.095523) (xy 287.080452 -396.08633) (xy 287.080452 -395.92885)
			(xy 287.080968 -395.918725) (xy 287.088682 -395.900003) (xy 287.102959 -395.885644) (xy 287.121638 -395.877825)
			(xy 287.13176 -395.877288) (xy 287.84804 -395.877288) (xy 287.858195 -395.877689) (xy 287.876946 -395.885495)
			(xy 287.891268 -395.899898) (xy 287.898968 -395.918693) (xy 287.899348 -395.92885) (xy 287.899348 -396.08633)
			(xy 287.899755 -396.095517) (xy 287.906272 -396.112701) (xy 287.912048 -396.119858) (xy 287.933904 -396.14553)
			(xy 287.971996 -396.201163) (xy 288.00315 -396.260957) (xy 288.026917 -396.324053) (xy 288.042955 -396.389542)
			(xy 288.051033 -396.456481) (xy 288.051034 -396.523904) (xy 288.042958 -396.590843) (xy 288.026922 -396.656332)
			(xy 288.003157 -396.719429) (xy 287.972004 -396.779224) (xy 287.933913 -396.834858) (xy 287.912048 -396.860522)
			(xy 287.906253 -396.867668) (xy 287.899739 -396.884858) (xy 287.899348 -396.89405) (xy 287.899348 -397.386302)
			(xy 287.899769 -397.395488) (xy 287.906276 -397.412672) (xy 287.912048 -397.41983) (xy 287.933876 -397.445525)
			(xy 287.97197 -397.501154) (xy 288.000733 -397.556355) (xy 289.128926 -397.556355) (xy 289.13697 -397.489532)
			(xy 289.152943 -397.42415) (xy 289.176617 -397.361145) (xy 289.207652 -397.301423) (xy 289.245603 -397.245837)
			(xy 289.267392 -397.220186) (xy 289.273176 -397.213032) (xy 289.279698 -397.195848) (xy 289.280092 -397.186658)
			(xy 289.280092 -397.028924) (xy 289.280541 -397.018772) (xy 289.288327 -397.000022) (xy 289.302715 -396.985698)
			(xy 289.321501 -396.977996) (xy 289.331654 -396.977616) (xy 290.047934 -396.977616) (xy 290.05806 -396.978098)
			(xy 290.076777 -396.985832) (xy 290.091132 -397.00012) (xy 290.098954 -397.0188) (xy 290.099496 -397.028924)
			(xy 290.099496 -397.186658) (xy 290.099927 -397.195843) (xy 290.106426 -397.213027) (xy 290.112196 -397.220186)
			(xy 290.133992 -397.245831) (xy 290.171939 -397.301419) (xy 290.20297 -397.361144) (xy 290.22664 -397.424149)
			(xy 290.242612 -397.489532) (xy 290.250654 -397.556355) (xy 290.250653 -397.62366) (xy 290.242609 -397.690483)
			(xy 290.226636 -397.755865) (xy 290.202963 -397.81887) (xy 290.200388 -397.823825) (xy 291.329053 -397.823825)
			(xy 291.329057 -397.756517) (xy 291.337105 -397.689692) (xy 291.353082 -397.624308) (xy 291.376759 -397.561302)
			(xy 291.407796 -397.501577) (xy 291.44575 -397.44599) (xy 291.46754 -397.420338) (xy 291.47335 -397.413203)
			(xy 291.479856 -397.396004) (xy 291.48024 -397.38681) (xy 291.48024 -396.893542) (xy 291.4798 -396.884358)
			(xy 291.473306 -396.867174) (xy 291.46754 -396.860014) (xy 291.445742 -396.83437) (xy 291.407794 -396.778782)
			(xy 291.376761 -396.719058) (xy 291.353088 -396.656052) (xy 291.337116 -396.590669) (xy 291.329073 -396.523845)
			(xy 291.329074 -396.45654) (xy 291.337119 -396.389716) (xy 291.353093 -396.324333) (xy 291.376767 -396.261328)
			(xy 291.407801 -396.201605) (xy 291.445751 -396.146018) (xy 291.46754 -396.120366) (xy 291.473339 -396.113222)
			(xy 291.479851 -396.096031) (xy 291.48024 -396.086838) (xy 291.48024 -395.92885) (xy 291.480705 -395.918681)
			(xy 291.488474 -395.899887) (xy 291.502847 -395.885501) (xy 291.521634 -395.877714) (xy 291.531802 -395.877288)
			(xy 292.248082 -395.877288) (xy 292.258259 -395.87768) (xy 292.277063 -395.885468) (xy 292.29145 -395.899864)
			(xy 292.299227 -395.918673) (xy 292.299644 -395.92885) (xy 292.299644 -396.086838) (xy 292.300049 -396.096026)
			(xy 292.306568 -396.113209) (xy 292.312344 -396.120366) (xy 292.334122 -396.146026) (xy 292.372072 -396.201611)
			(xy 292.403107 -396.261333) (xy 292.426781 -396.324337) (xy 292.442755 -396.389718) (xy 292.450801 -396.45654)
			(xy 292.450801 -396.523845) (xy 292.442758 -396.590667) (xy 292.426786 -396.656049) (xy 292.403113 -396.719053)
			(xy 292.37208 -396.778776) (xy 292.334131 -396.834362) (xy 292.312344 -396.860014) (xy 292.306552 -396.867162)
			(xy 292.300036 -396.884351) (xy 292.299644 -396.893542) (xy 292.299644 -397.38681) (xy 292.300062 -397.395996)
			(xy 292.306572 -397.41318) (xy 292.312344 -397.420338) (xy 292.334095 -397.446021) (xy 292.372046 -397.501602)
			(xy 292.40047 -397.556296) (xy 293.528718 -397.556296) (xy 293.536793 -397.489359) (xy 293.552827 -397.42387)
			(xy 293.576589 -397.360774) (xy 293.607738 -397.300978) (xy 293.645825 -397.245343) (xy 293.667688 -397.219678)
			(xy 293.673475 -397.212526) (xy 293.679996 -397.195341) (xy 293.680388 -397.18615) (xy 293.680388 -397.028924)
			(xy 293.680835 -397.018805) (xy 293.688573 -397.000104) (xy 293.70288 -396.985789) (xy 293.721577 -396.978041)
			(xy 293.731696 -396.977616) (xy 294.447976 -396.977616) (xy 294.458099 -396.978036) (xy 294.476805 -396.985779)
			(xy 294.491121 -397.000095) (xy 294.498864 -397.018801) (xy 294.499284 -397.028924) (xy 294.499284 -397.18615)
			(xy 294.499722 -397.195334) (xy 294.506217 -397.212519) (xy 294.511984 -397.219678) (xy 294.533858 -397.245335)
			(xy 294.571948 -397.30097) (xy 294.603099 -397.360767) (xy 294.626863 -397.423865) (xy 294.642899 -397.489356)
			(xy 294.650974 -397.556295) (xy 294.650973 -397.62372) (xy 294.642896 -397.690659) (xy 294.626859 -397.756149)
			(xy 294.603093 -397.819246) (xy 294.600676 -397.823885) (xy 295.728821 -397.823885) (xy 295.728825 -397.756458)
			(xy 295.736905 -397.689516) (xy 295.752946 -397.624025) (xy 295.776716 -397.560926) (xy 295.807873 -397.501129)
			(xy 295.845969 -397.445495) (xy 295.867836 -397.41983) (xy 295.873649 -397.412697) (xy 295.880153 -397.395497)
			(xy 295.880536 -397.386302) (xy 295.880536 -396.89405) (xy 295.880094 -396.884866) (xy 295.873601 -396.867682)
			(xy 295.867836 -396.860522) (xy 295.845961 -396.834865) (xy 295.80787 -396.779231) (xy 295.776718 -396.719433)
			(xy 295.752953 -396.656335) (xy 295.736917 -396.590845) (xy 295.728841 -396.523905) (xy 295.728842 -396.45648)
			(xy 295.73692 -396.38954) (xy 295.752957 -396.32405) (xy 295.776724 -396.260953) (xy 295.807878 -396.201157)
			(xy 295.84597 -396.145523) (xy 295.867836 -396.119858) (xy 295.873637 -396.112716) (xy 295.880148 -396.095523)
			(xy 295.880536 -396.08633) (xy 295.880536 -395.92885) (xy 295.881067 -395.918727) (xy 295.888778 -395.900008)
			(xy 295.903051 -395.88565) (xy 295.921724 -395.877828) (xy 295.931844 -395.877288) (xy 296.648124 -395.877288)
			(xy 296.658278 -395.877702) (xy 296.677029 -395.885503) (xy 296.691351 -395.899902) (xy 296.699052 -395.918694)
			(xy 296.699432 -395.92885) (xy 296.699432 -396.08633) (xy 296.699843 -396.095517) (xy 296.706358 -396.1127)
			(xy 296.712132 -396.119858) (xy 296.733985 -396.145532) (xy 296.772072 -396.201166) (xy 296.803221 -396.260961)
			(xy 296.826985 -396.324057) (xy 296.84302 -396.389545) (xy 296.851096 -396.456481) (xy 296.851097 -396.523904)
			(xy 296.843022 -396.590841) (xy 296.826989 -396.656329) (xy 296.803227 -396.719425) (xy 296.77208 -396.779221)
			(xy 296.733994 -396.834856) (xy 296.712132 -396.860522) (xy 296.706335 -396.867667) (xy 296.699823 -396.884858)
			(xy 296.699432 -396.89405) (xy 296.699432 -397.386302) (xy 296.699856 -397.395487) (xy 296.706362 -397.412671)
			(xy 296.712132 -397.41983) (xy 296.733958 -397.445527) (xy 296.772045 -397.501157) (xy 296.800802 -397.556355)
			(xy 297.929014 -397.556355) (xy 297.937057 -397.489532) (xy 297.95303 -397.42415) (xy 297.976704 -397.361146)
			(xy 298.007738 -397.301423) (xy 298.045688 -397.245838) (xy 298.067476 -397.220186) (xy 298.073258 -397.21303)
			(xy 298.079782 -397.195848) (xy 298.080176 -397.186658) (xy 298.080176 -397.028924) (xy 298.080641 -397.018774)
			(xy 298.088424 -397.000027) (xy 298.102807 -396.985704) (xy 298.121587 -396.977999) (xy 298.131738 -396.977616)
			(xy 298.848018 -396.977616) (xy 298.858143 -396.978111) (xy 298.87686 -396.98584) (xy 298.891215 -397.000123)
			(xy 298.899038 -397.018802) (xy 298.89958 -397.028924) (xy 298.89958 -397.186658) (xy 298.900015 -397.195842)
			(xy 298.906512 -397.213027) (xy 298.91228 -397.220186) (xy 298.934077 -397.24583) (xy 298.972024 -397.301418)
			(xy 299.003056 -397.361143) (xy 299.026728 -397.424149) (xy 299.042699 -397.489532) (xy 299.050742 -397.556355)
			(xy 299.050741 -397.62366) (xy 299.042697 -397.690483) (xy 299.026723 -397.755866) (xy 299.00305 -397.818871)
			(xy 299.000445 -397.823885) (xy 300.128612 -397.823885) (xy 300.128616 -397.756458) (xy 300.136696 -397.689517)
			(xy 300.152736 -397.624025) (xy 300.176506 -397.560927) (xy 300.207662 -397.501129) (xy 300.245757 -397.445495)
			(xy 300.267624 -397.41983) (xy 300.273436 -397.412696) (xy 300.27994 -397.395497) (xy 300.280324 -397.386302)
			(xy 300.280324 -396.89405) (xy 300.279884 -396.884866) (xy 300.273391 -396.867682) (xy 300.267624 -396.860522)
			(xy 300.245749 -396.834865) (xy 300.207659 -396.77923) (xy 300.176508 -396.719433) (xy 300.152743 -396.656335)
			(xy 300.136708 -396.590845) (xy 300.128632 -396.523905) (xy 300.128633 -396.45648) (xy 300.13671 -396.389541)
			(xy 300.152748 -396.324051) (xy 300.176514 -396.260953) (xy 300.207667 -396.201157) (xy 300.245759 -396.145523)
			(xy 300.267624 -396.119858) (xy 300.273424 -396.112715) (xy 300.279936 -396.095523) (xy 300.280324 -396.08633)
			(xy 300.280324 -395.92885) (xy 300.280867 -395.918728) (xy 300.288576 -395.900011) (xy 300.302845 -395.885654)
			(xy 300.321514 -395.87783) (xy 300.331632 -395.877288) (xy 301.047912 -395.877288) (xy 301.058065 -395.877711)
			(xy 301.076816 -395.885509) (xy 301.091138 -395.899904) (xy 301.09884 -395.918694) (xy 301.09922 -395.92885)
			(xy 301.09922 -396.08633) (xy 301.099611 -396.095519) (xy 301.106138 -396.112704) (xy 301.11192 -396.119858)
			(xy 301.133773 -396.145532) (xy 301.171861 -396.201165) (xy 301.203011 -396.260961) (xy 301.226775 -396.324056)
			(xy 301.242811 -396.389544) (xy 301.250887 -396.456481) (xy 301.250888 -396.523904) (xy 301.242813 -396.590841)
			(xy 301.226779 -396.656329) (xy 301.203017 -396.719426) (xy 301.171869 -396.779222) (xy 301.133783 -396.834856)
			(xy 301.11192 -396.860522) (xy 301.106134 -396.867675) (xy 301.099612 -396.884859) (xy 301.09922 -396.89405)
			(xy 301.09922 -397.386302) (xy 301.099625 -397.39549) (xy 301.106142 -397.412674) (xy 301.11192 -397.41983)
			(xy 301.133746 -397.445526) (xy 301.171834 -397.501157) (xy 301.200562 -397.556296) (xy 302.328806 -397.556296)
			(xy 302.336881 -397.489359) (xy 302.352914 -397.423871) (xy 302.376676 -397.360775) (xy 302.407824 -397.300979)
			(xy 302.44591 -397.245344) (xy 302.467772 -397.219678) (xy 302.473569 -397.212534) (xy 302.480081 -397.195342)
			(xy 302.480472 -397.18615) (xy 302.480472 -397.028924) (xy 302.480935 -397.018806) (xy 302.48867 -397.000109)
			(xy 302.502972 -396.985795) (xy 302.521663 -396.978043) (xy 302.53178 -396.977616) (xy 303.24806 -396.977616)
			(xy 303.258182 -396.978049) (xy 303.276888 -396.985787) (xy 303.291204 -397.000099) (xy 303.298948 -397.018802)
			(xy 303.299368 -397.028924) (xy 303.299368 -397.18615) (xy 303.299809 -397.195334) (xy 303.306302 -397.212518)
			(xy 303.312068 -397.219678) (xy 303.333943 -397.245335) (xy 303.372033 -397.30097) (xy 303.403185 -397.360767)
			(xy 303.426951 -397.423865) (xy 303.442986 -397.489355) (xy 303.451062 -397.556295) (xy 303.451061 -397.62372)
			(xy 303.442984 -397.69066) (xy 303.426946 -397.75615) (xy 303.403179 -397.819247) (xy 303.372026 -397.879043)
			(xy 303.333934 -397.934677) (xy 303.312068 -397.960342) (xy 303.306267 -397.967484) (xy 303.299756 -397.984677)
			(xy 303.299368 -397.99387) (xy 303.299368 -398.486376) (xy 303.299797 -398.495561) (xy 303.306299 -398.512745)
			(xy 303.312068 -398.519904) (xy 303.333968 -398.54554) (xy 303.372058 -398.601178) (xy 303.403209 -398.660978)
			(xy 303.426973 -398.724078) (xy 303.443007 -398.789571) (xy 303.45108 -398.856513) (xy 303.451077 -398.923941)
			(xy 303.442997 -398.990882) (xy 303.426957 -399.056373) (xy 303.403187 -399.119472) (xy 303.37203 -399.179269)
			(xy 303.333935 -399.234903) (xy 303.312068 -399.260568) (xy 303.306256 -399.267702) (xy 303.299751 -399.284901)
			(xy 303.299368 -399.294096) (xy 303.299368 -399.451576) (xy 303.298964 -399.461701) (xy 303.291218 -399.48041)
			(xy 303.276897 -399.494727) (xy 303.258185 -399.502467) (xy 303.24806 -399.502884) (xy 302.53178 -399.502884)
			(xy 302.521654 -399.5025) (xy 302.502947 -399.494742) (xy 302.488633 -399.480416) (xy 302.480891 -399.461702)
			(xy 302.480472 -399.451576) (xy 302.480472 -399.294096) (xy 302.48007 -399.284908) (xy 302.473551 -399.267723)
			(xy 302.467772 -399.260568) (xy 302.445944 -399.234873) (xy 302.407856 -399.179242) (xy 302.376706 -399.11945)
			(xy 302.352941 -399.056357) (xy 302.336904 -398.990872) (xy 302.328825 -398.923937) (xy 302.328822 -398.856517)
			(xy 302.336894 -398.789582) (xy 302.352925 -398.724095) (xy 302.376684 -398.661) (xy 302.407829 -398.601204)
			(xy 302.445911 -398.54557) (xy 302.467772 -398.519904) (xy 302.473558 -398.512752) (xy 302.480077 -398.495566)
			(xy 302.480472 -398.486376) (xy 302.480472 -397.99387) (xy 302.480082 -397.98468) (xy 302.473555 -397.967496)
			(xy 302.467772 -397.960342) (xy 302.445919 -397.934668) (xy 302.407832 -397.879034) (xy 302.376682 -397.819239)
			(xy 302.352919 -397.756143) (xy 302.336883 -397.690656) (xy 302.328807 -397.623719) (xy 302.328806 -397.556296)
			(xy 301.200562 -397.556296) (xy 301.202986 -397.560949) (xy 301.226751 -397.624042) (xy 301.242789 -397.689527)
			(xy 301.250867 -397.756461) (xy 301.250871 -397.823882) (xy 301.242799 -397.890817) (xy 301.226768 -397.956304)
			(xy 301.203009 -398.019399) (xy 301.171864 -398.079194) (xy 301.133781 -398.134828) (xy 301.11192 -398.160494)
			(xy 301.106146 -398.167655) (xy 301.099617 -398.184833) (xy 301.09922 -398.194022) (xy 301.09922 -398.351502)
			(xy 301.098774 -398.361634) (xy 301.091038 -398.380362) (xy 301.076739 -398.39472) (xy 301.058042 -398.402532)
			(xy 301.047912 -398.403064) (xy 300.331632 -398.403064) (xy 300.321475 -398.402652) (xy 300.302717 -398.39486)
			(xy 300.288391 -398.38046) (xy 300.280696 -398.361661) (xy 300.280324 -398.351502) (xy 300.280324 -398.194022)
			(xy 300.279898 -398.184837) (xy 300.273395 -398.167652) (xy 300.267624 -398.160494) (xy 300.245722 -398.13486)
			(xy 300.207633 -398.079222) (xy 300.176482 -398.019421) (xy 300.152719 -397.95632) (xy 300.136686 -397.890827)
			(xy 300.128612 -397.823885) (xy 299.000445 -397.823885) (xy 298.972017 -397.878595) (xy 298.934068 -397.934182)
			(xy 298.91228 -397.959834) (xy 298.906484 -397.96698) (xy 298.89997 -397.98417) (xy 298.89958 -397.993362)
			(xy 298.89958 -398.486884) (xy 298.900003 -398.49607) (xy 298.906508 -398.513254) (xy 298.91228 -398.520412)
			(xy 298.934103 -398.546035) (xy 298.972049 -398.601626) (xy 299.00308 -398.661354) (xy 299.02675 -398.724362)
			(xy 299.04272 -398.789748) (xy 299.050761 -398.856573) (xy 299.050757 -398.923881) (xy 299.04271 -398.990706)
			(xy 299.026734 -399.05609) (xy 299.003058 -399.119095) (xy 298.972021 -399.17882) (xy 298.934069 -399.234408)
			(xy 298.91228 -399.26006) (xy 298.906473 -399.267198) (xy 298.899965 -399.284394) (xy 298.89958 -399.293588)
			(xy 298.89958 -399.451576) (xy 298.899159 -399.461731) (xy 298.891367 -399.480487) (xy 298.87697 -399.494812)
			(xy 298.858175 -399.502509) (xy 298.848018 -399.502884) (xy 298.131738 -399.502884) (xy 298.121617 -399.502343)
			(xy 298.102901 -399.494632) (xy 298.088544 -399.480362) (xy 298.08072 -399.461694) (xy 298.080176 -399.451576)
			(xy 298.080176 -399.293588) (xy 298.079777 -399.2844) (xy 298.073256 -399.267215) (xy 298.067476 -399.26006)
			(xy 298.045723 -399.234379) (xy 298.00777 -399.178798) (xy 297.976733 -399.119078) (xy 297.953057 -399.056078)
			(xy 297.93708 -398.990699) (xy 297.929033 -398.923879) (xy 297.92903 -398.856576) (xy 297.937071 -398.789755)
			(xy 297.953041 -398.724374) (xy 297.976711 -398.661371) (xy 298.007742 -398.601649) (xy 298.045689 -398.546064)
			(xy 298.067476 -398.520412) (xy 298.07329 -398.513279) (xy 298.079795 -398.496079) (xy 298.080176 -398.486884)
			(xy 298.080176 -397.993362) (xy 298.079789 -397.984172) (xy 298.07326 -397.966988) (xy 298.067476 -397.959834)
			(xy 298.045697 -397.934174) (xy 298.007746 -397.87859) (xy 297.97671 -397.818868) (xy 297.953035 -397.755864)
			(xy 297.93706 -397.690482) (xy 297.929015 -397.62366) (xy 297.929014 -397.556355) (xy 296.800802 -397.556355)
			(xy 296.803196 -397.56095) (xy 296.826961 -397.624042) (xy 296.842998 -397.689527) (xy 296.851076 -397.756461)
			(xy 296.85108 -397.823881) (xy 296.843008 -397.890817) (xy 296.826978 -397.956303) (xy 296.803219 -398.019398)
			(xy 296.772075 -398.079194) (xy 296.733993 -398.134828) (xy 296.712132 -398.160494) (xy 296.706347 -398.167647)
			(xy 296.699827 -398.184832) (xy 296.699432 -398.194022) (xy 296.699432 -398.351502) (xy 296.698974 -398.361632)
			(xy 296.691241 -398.380359) (xy 296.676945 -398.394716) (xy 296.658252 -398.40253) (xy 296.648124 -398.403064)
			(xy 295.931844 -398.403064) (xy 295.921688 -398.402642) (xy 295.90293 -398.394854) (xy 295.888604 -398.380456)
			(xy 295.880909 -398.36166) (xy 295.880536 -398.351502) (xy 295.880536 -398.194022) (xy 295.880107 -398.184837)
			(xy 295.873606 -398.167653) (xy 295.867836 -398.160494) (xy 295.845933 -398.13486) (xy 295.807843 -398.079222)
			(xy 295.776692 -398.019422) (xy 295.752929 -397.956321) (xy 295.736895 -397.890827) (xy 295.728821 -397.823885)
			(xy 294.600676 -397.823885) (xy 294.57194 -397.879043) (xy 294.533849 -397.934677) (xy 294.511984 -397.960342)
			(xy 294.506185 -397.967486) (xy 294.499672 -397.984677) (xy 294.499284 -397.99387) (xy 294.499284 -398.486376)
			(xy 294.499709 -398.495561) (xy 294.506213 -398.512746) (xy 294.511984 -398.519904) (xy 294.533884 -398.54554)
			(xy 294.571973 -398.601178) (xy 294.603123 -398.660978) (xy 294.626885 -398.724079) (xy 294.642919 -398.789572)
			(xy 294.650992 -398.856514) (xy 294.650989 -398.92394) (xy 294.642909 -398.990881) (xy 294.626869 -399.056373)
			(xy 294.603101 -399.119471) (xy 294.571945 -399.179268) (xy 294.533851 -399.234903) (xy 294.511984 -399.260568)
			(xy 294.506174 -399.267704) (xy 294.499668 -399.284902) (xy 294.499284 -399.294096) (xy 294.499284 -399.451576)
			(xy 294.498864 -399.461699) (xy 294.491121 -399.480405) (xy 294.476805 -399.494721) (xy 294.458099 -399.502464)
			(xy 294.447976 -399.502884) (xy 293.731696 -399.502884) (xy 293.721571 -399.502487) (xy 293.702865 -399.494734)
			(xy 293.68855 -399.480412) (xy 293.680808 -399.461701) (xy 293.680388 -399.451576) (xy 293.680388 -399.294096)
			(xy 293.679982 -399.284908) (xy 293.673466 -399.267724) (xy 293.667688 -399.260568) (xy 293.64586 -399.234873)
			(xy 293.607771 -399.179243) (xy 293.576619 -399.119451) (xy 293.552854 -399.056358) (xy 293.536816 -398.990872)
			(xy 293.528737 -398.923937) (xy 293.528734 -398.856517) (xy 293.536806 -398.789581) (xy 293.552838 -398.724094)
			(xy 293.576597 -398.660999) (xy 293.607743 -398.601204) (xy 293.645827 -398.545569) (xy 293.667688 -398.519904)
			(xy 293.673464 -398.512744) (xy 293.679991 -398.495565) (xy 293.680388 -398.486376) (xy 293.680388 -397.99387)
			(xy 293.679995 -397.984681) (xy 293.673469 -397.967497) (xy 293.667688 -397.960342) (xy 293.645834 -397.934668)
			(xy 293.607746 -397.879035) (xy 293.576596 -397.81924) (xy 293.552831 -397.756144) (xy 293.536796 -397.690656)
			(xy 293.528719 -397.623719) (xy 293.528718 -397.556296) (xy 292.40047 -397.556296) (xy 292.403082 -397.561322)
			(xy 292.426757 -397.624322) (xy 292.442733 -397.689701) (xy 292.450781 -397.75652) (xy 292.450784 -397.823823)
			(xy 292.442744 -397.890643) (xy 292.426774 -397.956023) (xy 292.403105 -398.019026) (xy 292.372075 -398.078748)
			(xy 292.33413 -398.134334) (xy 292.312344 -398.159986) (xy 292.306522 -398.167113) (xy 292.300024 -398.184318)
			(xy 292.299644 -398.193514) (xy 292.299644 -398.351502) (xy 292.299237 -398.361676) (xy 292.291448 -398.380474)
			(xy 292.277057 -398.39486) (xy 292.258256 -398.402641) (xy 292.248082 -398.403064) (xy 291.531802 -398.403064)
			(xy 291.521645 -398.402565) (xy 291.502876 -398.394792) (xy 291.488511 -398.380427) (xy 291.480736 -398.361659)
			(xy 291.48024 -398.351502) (xy 291.48024 -398.193514) (xy 291.479814 -398.184329) (xy 291.473311 -398.167145)
			(xy 291.46754 -398.159986) (xy 291.445715 -398.134365) (xy 291.407767 -398.078774) (xy 291.376735 -398.019046)
			(xy 291.353065 -397.956037) (xy 291.337094 -397.890651) (xy 291.329053 -397.823825) (xy 290.200388 -397.823825)
			(xy 290.171931 -397.878594) (xy 290.133983 -397.934181) (xy 290.112196 -397.959834) (xy 290.106402 -397.966981)
			(xy 290.099886 -397.98417) (xy 290.099496 -397.993362) (xy 290.099496 -398.486884) (xy 290.099915 -398.49607)
			(xy 290.106423 -398.513255) (xy 290.112196 -398.520412) (xy 290.134018 -398.546036) (xy 290.171963 -398.601627)
			(xy 290.202993 -398.661355) (xy 290.226662 -398.724363) (xy 290.242632 -398.789748) (xy 290.250673 -398.856573)
			(xy 290.250669 -398.923881) (xy 290.242622 -398.990705) (xy 290.226646 -399.056089) (xy 290.202971 -399.119095)
			(xy 290.171936 -399.17882) (xy 290.133985 -399.234407) (xy 290.112196 -399.26006) (xy 290.106391 -399.267199)
			(xy 290.099881 -399.284394) (xy 290.099496 -399.293588) (xy 290.099496 -399.451576) (xy 290.099059 -399.461729)
			(xy 290.09127 -399.480482) (xy 290.076878 -399.494806) (xy 290.058089 -399.502506) (xy 290.047934 -399.502884)
			(xy 289.331654 -399.502884) (xy 289.321527 -399.502412) (xy 289.30281 -399.494673) (xy 289.288456 -399.480383)
			(xy 289.280634 -399.4617) (xy 289.280092 -399.451576) (xy 289.280092 -399.293588) (xy 289.279689 -399.2844)
			(xy 289.273171 -399.267216) (xy 289.267392 -399.26006) (xy 289.245638 -399.234379) (xy 289.207685 -399.178798)
			(xy 289.176647 -399.119079) (xy 289.15297 -399.056078) (xy 289.136993 -398.990699) (xy 289.128945 -398.923879)
			(xy 289.128942 -398.856575) (xy 289.136983 -398.789754) (xy 289.152954 -398.724374) (xy 289.176625 -398.66137)
			(xy 289.207657 -398.601648) (xy 289.245605 -398.546063) (xy 289.267392 -398.520412) (xy 289.273208 -398.51328)
			(xy 289.279711 -398.496079) (xy 289.280092 -398.486884) (xy 289.280092 -397.993362) (xy 289.279702 -397.984173)
			(xy 289.273175 -397.966988) (xy 289.267392 -397.959834) (xy 289.245612 -397.934174) (xy 289.20766 -397.87859)
			(xy 289.176623 -397.818868) (xy 289.152948 -397.755865) (xy 289.136972 -397.690483) (xy 289.128927 -397.62366)
			(xy 289.128926 -397.556355) (xy 288.000733 -397.556355) (xy 288.003125 -397.560946) (xy 288.026894 -397.624039)
			(xy 288.042933 -397.689525) (xy 288.051013 -397.756461) (xy 288.051016 -397.823882) (xy 288.042944 -397.890819)
			(xy 288.026911 -397.956307) (xy 288.003148 -398.019402) (xy 287.971999 -398.079197) (xy 287.933912 -398.13483)
			(xy 287.912048 -398.160494) (xy 287.906265 -398.167649) (xy 287.899744 -398.184832) (xy 287.899348 -398.194022)
			(xy 287.899348 -398.351502) (xy 287.898875 -398.36163) (xy 287.891144 -398.380354) (xy 287.876853 -398.39471)
			(xy 287.858166 -398.402527) (xy 287.84804 -398.403064) (xy 287.13176 -398.403064) (xy 287.121599 -398.40271)
			(xy 287.102839 -398.394895) (xy 287.088515 -398.380477) (xy 287.080824 -398.361666) (xy 287.080452 -398.351502)
			(xy 287.080452 -398.194022) (xy 287.08002 -398.184837) (xy 287.07352 -398.167653) (xy 287.067752 -398.160494)
			(xy 287.045849 -398.13486) (xy 287.007758 -398.079223) (xy 286.976606 -398.019423) (xy 286.952842 -397.956321)
			(xy 286.936807 -397.890828) (xy 286.928734 -397.823885) (xy 244.06606 -397.823885) (xy 244.06606 -399.830544)
			(xy 244.065668 -399.840617) (xy 244.057925 -399.859215) (xy 244.051074 -399.866612) (xy 243.052346 -400.865594)
			(xy 243.044923 -400.872406) (xy 243.026341 -400.880142) (xy 243.016278 -400.88058) (xy 238.99114 -400.88058)
			(xy 238.978794 -400.881097) (xy 238.955921 -400.890396) (xy 238.94669 -400.898614) (xy 238.946182 -400.899122)
			(xy 238.121507 -401.723797) (xy 286.928745 -401.723797) (xy 286.928747 -401.65637) (xy 286.936826 -401.58943)
			(xy 286.952865 -401.523939) (xy 286.976634 -401.460841) (xy 287.00779 -401.401044) (xy 287.045885 -401.34541)
			(xy 287.067752 -401.319746) (xy 287.07356 -401.312609) (xy 287.080067 -401.295412) (xy 287.080452 -401.286218)
			(xy 287.080452 -400.793966) (xy 287.080046 -400.784779) (xy 287.073528 -400.767595) (xy 287.067752 -400.760438)
			(xy 287.045892 -400.734769) (xy 287.0078 -400.679136) (xy 286.976646 -400.619341) (xy 286.952879 -400.556244)
			(xy 286.936842 -400.490755) (xy 286.928764 -400.423817) (xy 286.928764 -400.356392) (xy 286.93684 -400.289454)
			(xy 286.952876 -400.223964) (xy 286.976642 -400.160867) (xy 287.007795 -400.101072) (xy 287.045887 -400.045438)
			(xy 287.067752 -400.019774) (xy 287.073549 -400.012629) (xy 287.080062 -399.995438) (xy 287.080452 -399.986246)
			(xy 287.080452 -399.828766) (xy 287.080899 -399.818636) (xy 287.08864 -399.799911) (xy 287.102939 -399.785556)
			(xy 287.121632 -399.77774) (xy 287.13176 -399.777204) (xy 287.84804 -399.777204) (xy 287.858197 -399.777589)
			(xy 287.876951 -399.785399) (xy 287.891273 -399.799806) (xy 287.898971 -399.818606) (xy 287.899348 -399.828766)
			(xy 287.899348 -399.986246) (xy 287.899796 -399.995429) (xy 287.906285 -400.012613) (xy 287.912048 -400.019774)
			(xy 287.93392 -400.045433) (xy 287.972012 -400.101068) (xy 288.003165 -400.160864) (xy 288.026931 -400.223962)
			(xy 288.042968 -400.289452) (xy 288.051044 -400.356392) (xy 288.051043 -400.423817) (xy 288.042966 -400.490757)
			(xy 288.026928 -400.556247) (xy 288.003161 -400.619344) (xy 287.972007 -400.67914) (xy 287.933914 -400.734774)
			(xy 287.912048 -400.760438) (xy 287.906246 -400.767579) (xy 287.899736 -400.784773) (xy 287.899348 -400.793966)
			(xy 287.899348 -401.286218) (xy 287.899761 -401.295405) (xy 287.906274 -401.312588) (xy 287.912048 -401.319746)
			(xy 287.933892 -401.345428) (xy 287.971985 -401.401059) (xy 288.00314 -401.460852) (xy 288.026907 -401.523947)
			(xy 288.042946 -401.589435) (xy 288.051024 -401.656372) (xy 288.051026 -401.723795) (xy 288.042952 -401.790733)
			(xy 288.026917 -401.856221) (xy 288.003153 -401.919317) (xy 287.972002 -401.979113) (xy 287.933912 -402.034746)
			(xy 287.912048 -402.06041) (xy 287.906258 -402.06756) (xy 287.899741 -402.084747) (xy 287.899348 -402.093938)
			(xy 287.899348 -402.251418) (xy 287.898888 -402.261547) (xy 287.891152 -402.280271) (xy 287.876858 -402.294627)
			(xy 287.858167 -402.302444) (xy 287.84804 -402.30298) (xy 287.13176 -402.30298) (xy 287.121601 -402.302611)
			(xy 287.102844 -402.294798) (xy 287.088521 -402.280385) (xy 287.080826 -402.26158) (xy 287.080452 -402.251418)
			(xy 287.080452 -402.093938) (xy 287.080012 -402.084754) (xy 287.073518 -402.06757) (xy 287.067752 -402.06041)
			(xy 287.045865 -402.034763) (xy 287.007773 -401.979127) (xy 286.97662 -401.919329) (xy 286.952855 -401.85623)
			(xy 286.93682 -401.790738) (xy 286.928745 -401.723797) (xy 238.121507 -401.723797) (xy 237.044738 -402.800566)
			(xy 237.036256 -402.809732) (xy 237.030424 -402.823819) (xy 289.128886 -402.823819) (xy 289.12889 -402.756509)
			(xy 289.13694 -402.689682) (xy 289.15292 -402.624297) (xy 289.1766 -402.56129) (xy 289.207642 -402.501565)
			(xy 289.2456 -402.445979) (xy 289.267392 -402.420328) (xy 289.273201 -402.413191) (xy 289.279708 -402.395994)
			(xy 289.280092 -402.3868) (xy 289.280092 -401.893532) (xy 289.279668 -401.884346) (xy 289.273164 -401.867162)
			(xy 289.267392 -401.860004) (xy 289.245583 -401.834369) (xy 289.207631 -401.778781) (xy 289.176596 -401.719056)
			(xy 289.152922 -401.656049) (xy 289.136949 -401.590664) (xy 289.128906 -401.523839) (xy 289.128907 -401.456531)
			(xy 289.136954 -401.389706) (xy 289.152931 -401.324322) (xy 289.176608 -401.261317) (xy 289.207647 -401.201593)
			(xy 289.245601 -401.146007) (xy 289.267392 -401.120356) (xy 289.273189 -401.113211) (xy 289.279704 -401.09602)
			(xy 289.280092 -401.086828) (xy 289.280092 -400.92884) (xy 289.280554 -400.918689) (xy 289.288335 -400.89994)
			(xy 289.30272 -400.885615) (xy 289.321502 -400.877913) (xy 289.331654 -400.877532) (xy 290.047934 -400.877532)
			(xy 290.058062 -400.877998) (xy 290.076782 -400.885736) (xy 290.091137 -400.900028) (xy 290.098957 -400.918714)
			(xy 290.099496 -400.92884) (xy 290.099496 -401.086828) (xy 290.099893 -401.096017) (xy 290.106416 -401.113201)
			(xy 290.112196 -401.120356) (xy 290.133963 -401.146025) (xy 290.17191 -401.20161) (xy 290.202942 -401.261331)
			(xy 290.226615 -401.324334) (xy 290.242588 -401.389713) (xy 290.250633 -401.456534) (xy 290.250635 -401.523836)
			(xy 290.242593 -401.590657) (xy 290.226624 -401.656038) (xy 290.202955 -401.719041) (xy 290.200515 -401.723737)
			(xy 291.329064 -401.723737) (xy 291.329066 -401.65643) (xy 291.337113 -401.589606) (xy 291.353088 -401.524222)
			(xy 291.376763 -401.461217) (xy 291.407799 -401.401493) (xy 291.445751 -401.345906) (xy 291.46754 -401.320254)
			(xy 291.473344 -401.313114) (xy 291.479853 -401.295919) (xy 291.48024 -401.286726) (xy 291.48024 -400.793458)
			(xy 291.479841 -400.78427) (xy 291.473319 -400.767086) (xy 291.46754 -400.75993) (xy 291.445758 -400.734273)
			(xy 291.407809 -400.678687) (xy 291.376776 -400.618964) (xy 291.353103 -400.55596) (xy 291.337129 -400.490579)
			(xy 291.329085 -400.423757) (xy 291.329084 -400.356452) (xy 291.337128 -400.28963) (xy 291.3531 -400.224248)
			(xy 291.376772 -400.161244) (xy 291.407805 -400.101521) (xy 291.445753 -400.045934) (xy 291.46754 -400.020282)
			(xy 291.473332 -400.013134) (xy 291.479848 -399.995945) (xy 291.48024 -399.986754) (xy 291.48024 -399.828766)
			(xy 291.480706 -399.818606) (xy 291.488492 -399.799835) (xy 291.502866 -399.785471) (xy 291.521641 -399.777698)
			(xy 291.531802 -399.777204) (xy 292.248082 -399.777204) (xy 292.258234 -399.777747) (xy 292.276997 -399.785509)
			(xy 292.291361 -399.79986) (xy 292.299143 -399.818614) (xy 292.299644 -399.828766) (xy 292.299644 -399.986754)
			(xy 292.300089 -399.995937) (xy 292.30658 -400.013121) (xy 292.312344 -400.020282) (xy 292.334138 -400.045929)
			(xy 292.372088 -400.101516) (xy 292.403122 -400.16124) (xy 292.426795 -400.224245) (xy 292.442768 -400.289628)
			(xy 292.450812 -400.356452) (xy 292.450811 -400.423757) (xy 292.442766 -400.490581) (xy 292.426792 -400.555963)
			(xy 292.403118 -400.618968) (xy 292.372083 -400.678692) (xy 292.334132 -400.734278) (xy 292.312344 -400.75993)
			(xy 292.306545 -400.767073) (xy 292.300033 -400.784266) (xy 292.299644 -400.793458) (xy 292.299644 -401.286726)
			(xy 292.300054 -401.295913) (xy 292.306569 -401.313097) (xy 292.312344 -401.320254) (xy 292.33411 -401.345924)
			(xy 292.372061 -401.401507) (xy 292.403096 -401.461228) (xy 292.426771 -401.524231) (xy 292.442746 -401.589611)
			(xy 292.450792 -401.656432) (xy 292.450794 -401.723735) (xy 292.442752 -401.790557) (xy 292.426781 -401.855938)
			(xy 292.40311 -401.918941) (xy 292.372078 -401.978664) (xy 292.334131 -402.03425) (xy 292.312344 -402.059902)
			(xy 292.306557 -402.067054) (xy 292.300038 -402.084239) (xy 292.299644 -402.09343) (xy 292.299644 -402.251418)
			(xy 292.299181 -402.261579) (xy 292.291397 -402.280352) (xy 292.277022 -402.294718) (xy 292.258244 -402.302488)
			(xy 292.248082 -402.30298) (xy 291.531802 -402.30298) (xy 291.521647 -402.302465) (xy 291.502881 -402.294695)
			(xy 291.488516 -402.280336) (xy 291.480739 -402.261573) (xy 291.48024 -402.251418) (xy 291.48024 -402.09343)
			(xy 291.479806 -402.084246) (xy 291.473308 -402.067061) (xy 291.46754 -402.059902) (xy 291.44573 -402.034268)
			(xy 291.407782 -401.978679) (xy 291.37675 -401.918953) (xy 291.353078 -401.855946) (xy 291.337107 -401.790561)
			(xy 291.329064 -401.723737) (xy 290.200515 -401.723737) (xy 290.171926 -401.778764) (xy 290.133981 -401.834351)
			(xy 290.112196 -401.860004) (xy 290.106415 -401.86716) (xy 290.099891 -401.884342) (xy 290.099496 -401.893532)
			(xy 290.099496 -402.3868) (xy 290.099907 -402.395987) (xy 290.10642 -402.413171) (xy 290.112196 -402.420328)
			(xy 290.133935 -402.44602) (xy 290.171883 -402.501601) (xy 290.202916 -402.56132) (xy 290.22659 -402.624319)
			(xy 290.242566 -402.689696) (xy 290.250613 -402.756514) (xy 290.250617 -402.823814) (xy 290.250609 -402.823878)
			(xy 293.528678 -402.823878) (xy 293.528683 -402.75645) (xy 293.536763 -402.689509) (xy 293.552803 -402.624017)
			(xy 293.576572 -402.560919) (xy 293.607728 -402.501121) (xy 293.645822 -402.445485) (xy 293.667688 -402.41982)
			(xy 293.6735 -402.412685) (xy 293.680006 -402.395487) (xy 293.680388 -402.386292) (xy 293.680388 -401.89404)
			(xy 293.679961 -401.884854) (xy 293.67346 -401.86767) (xy 293.667688 -401.860512) (xy 293.645805 -401.834863)
			(xy 293.607717 -401.779226) (xy 293.576568 -401.719427) (xy 293.552806 -401.656328) (xy 293.536772 -401.590837)
			(xy 293.528698 -401.523897) (xy 293.5287 -401.456472) (xy 293.536777 -401.389533) (xy 293.552815 -401.324043)
			(xy 293.576581 -401.260945) (xy 293.607733 -401.201149) (xy 293.645823 -401.145513) (xy 293.667688 -401.119848)
			(xy 293.673488 -401.112705) (xy 293.680001 -401.095513) (xy 293.680388 -401.08632) (xy 293.680388 -400.92884)
			(xy 293.680849 -400.918722) (xy 293.688581 -400.900021) (xy 293.702884 -400.885706) (xy 293.721578 -400.877957)
			(xy 293.731696 -400.877532) (xy 294.447976 -400.877532) (xy 294.458101 -400.877936) (xy 294.47681 -400.885682)
			(xy 294.491127 -400.900003) (xy 294.498867 -400.918715) (xy 294.499284 -400.92884) (xy 294.499284 -401.08632)
			(xy 294.499688 -401.095508) (xy 294.506206 -401.112692) (xy 294.511984 -401.119848) (xy 294.533829 -401.145529)
			(xy 294.571919 -401.201161) (xy 294.603072 -401.260955) (xy 294.626838 -401.32405) (xy 294.642875 -401.389537)
			(xy 294.650953 -401.456474) (xy 294.650955 -401.523896) (xy 294.64288 -401.590833) (xy 294.626847 -401.656322)
			(xy 294.603084 -401.719418) (xy 294.600803 -401.723797) (xy 295.728833 -401.723797) (xy 295.728835 -401.65637)
			(xy 295.736913 -401.58943) (xy 295.752952 -401.523939) (xy 295.77672 -401.460841) (xy 295.807876 -401.401045)
			(xy 295.845969 -401.345411) (xy 295.867836 -401.319746) (xy 295.873643 -401.312608) (xy 295.88015 -401.295412)
			(xy 295.880536 -401.286218) (xy 295.880536 -400.793966) (xy 295.880134 -400.784778) (xy 295.873614 -400.767594)
			(xy 295.867836 -400.760438) (xy 295.845977 -400.734769) (xy 295.807885 -400.679135) (xy 295.776732 -400.61934)
			(xy 295.752966 -400.556244) (xy 295.736929 -400.490755) (xy 295.728852 -400.423816) (xy 295.728852 -400.356393)
			(xy 295.736928 -400.289454) (xy 295.752964 -400.223965) (xy 295.776729 -400.160868) (xy 295.807881 -400.101072)
			(xy 295.845971 -400.045439) (xy 295.867836 -400.019774) (xy 295.873631 -400.012628) (xy 295.880146 -399.995438)
			(xy 295.880536 -399.986246) (xy 295.880536 -399.828766) (xy 295.880999 -399.818638) (xy 295.888737 -399.799916)
			(xy 295.90303 -399.785561) (xy 295.921718 -399.777743) (xy 295.931844 -399.777204) (xy 296.648124 -399.777204)
			(xy 296.65828 -399.777602) (xy 296.677034 -399.785406) (xy 296.691357 -399.79981) (xy 296.699055 -399.818608)
			(xy 296.699432 -399.828766) (xy 296.699432 -399.986246) (xy 296.699883 -399.995429) (xy 296.70637 -400.012613)
			(xy 296.712132 -400.019774) (xy 296.734001 -400.045435) (xy 296.772087 -400.101071) (xy 296.803236 -400.160868)
			(xy 296.826998 -400.223965) (xy 296.843032 -400.289455) (xy 296.851107 -400.356393) (xy 296.851107 -400.423816)
			(xy 296.843031 -400.490754) (xy 296.826996 -400.556243) (xy 296.803232 -400.61934) (xy 296.772083 -400.679137)
			(xy 296.733995 -400.734772) (xy 296.712132 -400.760438) (xy 296.706329 -400.767578) (xy 296.69982 -400.784773)
			(xy 296.699432 -400.793966) (xy 296.699432 -401.286218) (xy 296.699849 -401.295404) (xy 296.70636 -401.312588)
			(xy 296.712132 -401.319746) (xy 296.733973 -401.34543) (xy 296.77206 -401.401062) (xy 296.80321 -401.460856)
			(xy 296.826974 -401.523951) (xy 296.84301 -401.589437) (xy 296.851088 -401.656373) (xy 296.85109 -401.723794)
			(xy 296.843016 -401.79073) (xy 296.826984 -401.856218) (xy 296.803224 -401.919314) (xy 296.772078 -401.979109)
			(xy 296.733994 -402.034744) (xy 296.712132 -402.06041) (xy 296.70634 -402.067558) (xy 296.699825 -402.084747)
			(xy 296.699432 -402.093938) (xy 296.699432 -402.251418) (xy 296.698988 -402.261549) (xy 296.691249 -402.280276)
			(xy 296.676949 -402.294633) (xy 296.658253 -402.302447) (xy 296.648124 -402.30298) (xy 295.931844 -402.30298)
			(xy 295.92169 -402.302542) (xy 295.902935 -402.294757) (xy 295.888609 -402.280365) (xy 295.880912 -402.261574)
			(xy 295.880536 -402.251418) (xy 295.880536 -402.093938) (xy 295.880099 -402.084754) (xy 295.873603 -402.06757)
			(xy 295.867836 -402.06041) (xy 295.845949 -402.034763) (xy 295.807859 -401.979127) (xy 295.776707 -401.919328)
			(xy 295.752942 -401.856229) (xy 295.736907 -401.790737) (xy 295.728833 -401.723797) (xy 294.600803 -401.723797)
			(xy 294.571935 -401.779213) (xy 294.533847 -401.834847) (xy 294.511984 -401.860512) (xy 294.506198 -401.867665)
			(xy 294.499678 -401.88485) (xy 294.499284 -401.89404) (xy 294.499284 -402.386292) (xy 294.499702 -402.395478)
			(xy 294.506211 -402.412662) (xy 294.511984 -402.41982) (xy 294.533801 -402.445524) (xy 294.571893 -402.501152)
			(xy 294.603046 -402.560943) (xy 294.626814 -402.624035) (xy 294.642853 -402.68952) (xy 294.650933 -402.756454)
			(xy 294.650937 -402.823819) (xy 297.928973 -402.823819) (xy 297.928978 -402.756509) (xy 297.937027 -402.689683)
			(xy 297.953006 -402.624297) (xy 297.976686 -402.561291) (xy 298.007727 -402.501566) (xy 298.045684 -402.445979)
			(xy 298.067476 -402.420328) (xy 298.073283 -402.41319) (xy 298.079792 -402.395994) (xy 298.080176 -402.3868)
			(xy 298.080176 -401.893532) (xy 298.079756 -401.884346) (xy 298.07325 -401.867161) (xy 298.067476 -401.860004)
			(xy 298.045668 -401.834368) (xy 298.007717 -401.77878) (xy 297.976683 -401.719055) (xy 297.953009 -401.656048)
			(xy 297.937037 -401.590664) (xy 297.928993 -401.523839) (xy 297.928995 -401.456531) (xy 297.937042 -401.389707)
			(xy 297.953018 -401.324323) (xy 297.976695 -401.261318) (xy 298.007732 -401.201594) (xy 298.045686 -401.146008)
			(xy 298.067476 -401.120356) (xy 298.073271 -401.113209) (xy 298.079787 -401.09602) (xy 298.080176 -401.086828)
			(xy 298.080176 -400.92884) (xy 298.080654 -400.918691) (xy 298.088432 -400.899945) (xy 298.102811 -400.885621)
			(xy 298.121588 -400.877915) (xy 298.131738 -400.877532) (xy 298.848018 -400.877532) (xy 298.858145 -400.878011)
			(xy 298.876865 -400.885744) (xy 298.89122 -400.900032) (xy 298.89904 -400.918716) (xy 298.89958 -400.92884)
			(xy 298.89958 -401.086828) (xy 298.899981 -401.096016) (xy 298.906502 -401.1132) (xy 298.91228 -401.120356)
			(xy 298.934048 -401.146024) (xy 298.971996 -401.201609) (xy 299.003029 -401.261331) (xy 299.026702 -401.324333)
			(xy 299.042676 -401.389713) (xy 299.050721 -401.456533) (xy 299.050723 -401.523837) (xy 299.042681 -401.590657)
			(xy 299.026711 -401.656038) (xy 299.003041 -401.719042) (xy 299.000571 -401.723796) (xy 300.128624 -401.723796)
			(xy 300.128626 -401.656371) (xy 300.136704 -401.58943) (xy 300.152743 -401.52394) (xy 300.17651 -401.460842)
			(xy 300.207665 -401.401045) (xy 300.245758 -401.345411) (xy 300.267624 -401.319746) (xy 300.273429 -401.312607)
			(xy 300.279938 -401.295412) (xy 300.280324 -401.286218) (xy 300.280324 -400.793966) (xy 300.279925 -400.784778)
			(xy 300.273403 -400.767594) (xy 300.267624 -400.760438) (xy 300.245765 -400.734768) (xy 300.207675 -400.679135)
			(xy 300.176522 -400.61934) (xy 300.152757 -400.556243) (xy 300.13672 -400.490755) (xy 300.128643 -400.423816)
			(xy 300.128643 -400.356393) (xy 300.136719 -400.289454) (xy 300.152754 -400.223965) (xy 300.176519 -400.160869)
			(xy 300.20767 -400.101073) (xy 300.24576 -400.045439) (xy 300.267624 -400.019774) (xy 300.273417 -400.012626)
			(xy 300.279933 -399.995438) (xy 300.280324 -399.986246) (xy 300.280324 -399.828766) (xy 300.280798 -399.818639)
			(xy 300.288534 -399.79992) (xy 300.302824 -399.785566) (xy 300.321507 -399.777745) (xy 300.331632 -399.777204)
			(xy 301.047912 -399.777204) (xy 301.058067 -399.777612) (xy 301.076821 -399.785412) (xy 301.091144 -399.799813)
			(xy 301.098843 -399.818608) (xy 301.09922 -399.828766) (xy 301.09922 -399.986246) (xy 301.099652 -399.995431)
			(xy 301.10615 -400.012616) (xy 301.11192 -400.019774) (xy 301.133789 -400.045435) (xy 301.171876 -400.10107)
			(xy 301.203026 -400.160867) (xy 301.226789 -400.223965) (xy 301.242823 -400.289454) (xy 301.250898 -400.356393)
			(xy 301.250898 -400.423816) (xy 301.242821 -400.490755) (xy 301.226786 -400.556244) (xy 301.203022 -400.619341)
			(xy 301.171872 -400.679137) (xy 301.133784 -400.734772) (xy 301.11192 -400.760438) (xy 301.106127 -400.767586)
			(xy 301.09961 -400.784774) (xy 301.09922 -400.793966) (xy 301.09922 -401.286218) (xy 301.099617 -401.295407)
			(xy 301.106139 -401.312591) (xy 301.11192 -401.319746) (xy 301.133762 -401.345429) (xy 301.17185 -401.401062)
			(xy 301.203 -401.460856) (xy 301.226765 -401.52395) (xy 301.242801 -401.589437) (xy 301.250878 -401.656373)
			(xy 301.25088 -401.723794) (xy 301.242807 -401.790731) (xy 301.226775 -401.856218) (xy 301.203014 -401.919314)
			(xy 301.171867 -401.97911) (xy 301.133782 -402.034744) (xy 301.11192 -402.06041) (xy 301.106139 -402.067566)
			(xy 301.099614 -402.084748) (xy 301.09922 -402.093938) (xy 301.09922 -402.251418) (xy 301.098787 -402.261551)
			(xy 301.091046 -402.28028) (xy 301.076743 -402.294637) (xy 301.058043 -402.302449) (xy 301.047912 -402.30298)
			(xy 300.331632 -402.30298) (xy 300.321477 -402.302552) (xy 300.302722 -402.294763) (xy 300.288396 -402.280368)
			(xy 300.280699 -402.261575) (xy 300.280324 -402.251418) (xy 300.280324 -402.093938) (xy 300.27989 -402.084753)
			(xy 300.273392 -402.067569) (xy 300.267624 -402.06041) (xy 300.245738 -402.034763) (xy 300.207648 -401.979126)
			(xy 300.176497 -401.919328) (xy 300.152733 -401.856229) (xy 300.136698 -401.790737) (xy 300.128624 -401.723796)
			(xy 299.000571 -401.723796) (xy 298.972011 -401.778765) (xy 298.934066 -401.834352) (xy 298.91228 -401.860004)
			(xy 298.906497 -401.867159) (xy 298.899975 -401.884342) (xy 298.89958 -401.893532) (xy 298.89958 -402.3868)
			(xy 298.899994 -402.395987) (xy 298.906505 -402.413171) (xy 298.91228 -402.420328) (xy 298.93402 -402.446019)
			(xy 298.971969 -402.501601) (xy 299.003003 -402.561319) (xy 299.026678 -402.624318) (xy 299.042653 -402.689696)
			(xy 299.050701 -402.756513) (xy 299.050705 -402.823814) (xy 299.050697 -402.823877) (xy 302.328766 -402.823877)
			(xy 302.328771 -402.75645) (xy 302.336851 -402.689509) (xy 302.35289 -402.624018) (xy 302.376659 -402.560919)
			(xy 302.407814 -402.501122) (xy 302.445906 -402.445486) (xy 302.467772 -402.41982) (xy 302.473594 -402.412693)
			(xy 302.480091 -402.395488) (xy 302.480472 -402.386292) (xy 302.480472 -401.89404) (xy 302.480049 -401.884854)
			(xy 302.473545 -401.867669) (xy 302.467772 -401.860512) (xy 302.445889 -401.834863) (xy 302.407803 -401.779225)
			(xy 302.376655 -401.719426) (xy 302.352893 -401.656328) (xy 302.33686 -401.590837) (xy 302.328786 -401.523897)
			(xy 302.328788 -401.456473) (xy 302.336865 -401.389534) (xy 302.352902 -401.324044) (xy 302.376667 -401.260946)
			(xy 302.407819 -401.201149) (xy 302.445908 -401.145514) (xy 302.467772 -401.119848) (xy 302.473582 -401.112713)
			(xy 302.480087 -401.095514) (xy 302.480472 -401.08632) (xy 302.480472 -400.92884) (xy 302.480948 -400.918724)
			(xy 302.488678 -400.900026) (xy 302.502976 -400.885712) (xy 302.521664 -400.87796) (xy 302.53178 -400.877532)
			(xy 303.24806 -400.877532) (xy 303.258184 -400.87795) (xy 303.276893 -400.885691) (xy 303.291209 -400.900007)
			(xy 303.29895 -400.918716) (xy 303.299368 -400.92884) (xy 303.299368 -401.08632) (xy 303.299776 -401.095507)
			(xy 303.306292 -401.112691) (xy 303.312068 -401.119848) (xy 303.333913 -401.145529) (xy 303.372005 -401.20116)
			(xy 303.403158 -401.260954) (xy 303.426925 -401.324049) (xy 303.442963 -401.389537) (xy 303.451041 -401.456474)
			(xy 303.451043 -401.523896) (xy 303.442968 -401.590834) (xy 303.426934 -401.656322) (xy 303.40317 -401.719418)
			(xy 303.37202 -401.779214) (xy 303.333932 -401.834847) (xy 303.312068 -401.860512) (xy 303.30628 -401.867663)
			(xy 303.299761 -401.884849) (xy 303.299368 -401.89404) (xy 303.299368 -402.386292) (xy 303.299789 -402.395478)
			(xy 303.306296 -402.412662) (xy 303.312068 -402.41982) (xy 303.333886 -402.445524) (xy 303.371978 -402.501152)
			(xy 303.403133 -402.560942) (xy 303.426901 -402.624034) (xy 303.442941 -402.689519) (xy 303.451021 -402.756454)
			(xy 303.451025 -402.823874) (xy 303.442954 -402.89081) (xy 303.426922 -402.956297) (xy 303.403162 -403.019392)
			(xy 303.372015 -403.079186) (xy 303.33393 -403.134819) (xy 303.312068 -403.160484) (xy 303.306249 -403.167613)
			(xy 303.299749 -403.184816) (xy 303.299368 -403.194012) (xy 303.299368 -403.351492) (xy 303.298977 -403.361618)
			(xy 303.291225 -403.380328) (xy 303.276901 -403.394643) (xy 303.258186 -403.402383) (xy 303.24806 -403.4028)
			(xy 302.53178 -403.4028) (xy 302.52167 -403.402331) (xy 302.502991 -403.394587) (xy 302.488697 -403.380285)
			(xy 302.480963 -403.361602) (xy 302.480472 -403.351492) (xy 302.480472 -403.194012) (xy 302.480062 -403.184825)
			(xy 302.473549 -403.16764) (xy 302.467772 -403.160484) (xy 302.445862 -403.134857) (xy 302.407776 -403.079216)
			(xy 302.376629 -403.019415) (xy 302.352869 -402.956313) (xy 302.336838 -402.890819) (xy 302.328766 -402.823877)
			(xy 299.050697 -402.823877) (xy 299.042666 -402.890633) (xy 299.026699 -402.956013) (xy 299.003032 -403.019015)
			(xy 298.972006 -403.078737) (xy 298.934064 -403.134323) (xy 298.91228 -403.159976) (xy 298.906466 -403.167109)
			(xy 298.899963 -403.184309) (xy 298.89958 -403.193504) (xy 298.89958 -403.351492) (xy 298.899171 -403.361648)
			(xy 298.891375 -403.380404) (xy 298.876974 -403.394729) (xy 298.858176 -403.402425) (xy 298.848018 -403.4028)
			(xy 298.131738 -403.4028) (xy 298.121619 -403.402243) (xy 298.102906 -403.394535) (xy 298.08855 -403.380271)
			(xy 298.080722 -403.361608) (xy 298.080176 -403.351492) (xy 298.080176 -403.193504) (xy 298.079769 -403.184316)
			(xy 298.073254 -403.167132) (xy 298.067476 -403.159976) (xy 298.04564 -403.134363) (xy 298.00769 -403.078772)
			(xy 297.976657 -403.019043) (xy 297.952985 -402.956034) (xy 297.937014 -402.890646) (xy 297.928973 -402.823819)
			(xy 294.650937 -402.823819) (xy 294.650937 -402.823874) (xy 294.642866 -402.890809) (xy 294.626835 -402.956296)
			(xy 294.603076 -403.019391) (xy 294.57193 -403.079186) (xy 294.533846 -403.134819) (xy 294.511984 -403.160484)
			(xy 294.506167 -403.167615) (xy 294.499665 -403.184816) (xy 294.499284 -403.194012) (xy 294.499284 -403.351492)
			(xy 294.498877 -403.361616) (xy 294.491129 -403.380322) (xy 294.476809 -403.394638) (xy 294.4581 -403.40238)
			(xy 294.447976 -403.4028) (xy 293.731696 -403.4028) (xy 293.721573 -403.402387) (xy 293.70287 -403.394638)
			(xy 293.688556 -403.38032) (xy 293.68081 -403.361615) (xy 293.680388 -403.351492) (xy 293.680388 -403.194012)
			(xy 293.679975 -403.184825) (xy 293.673464 -403.167641) (xy 293.667688 -403.160484) (xy 293.645777 -403.134857)
			(xy 293.607691 -403.079217) (xy 293.576543 -403.019415) (xy 293.552782 -402.956314) (xy 293.53675 -402.89082)
			(xy 293.528678 -402.823878) (xy 290.250609 -402.823878) (xy 290.242579 -402.890633) (xy 290.226612 -402.956012)
			(xy 290.202946 -403.019014) (xy 290.17192 -403.078737) (xy 290.133979 -403.134323) (xy 290.112196 -403.159976)
			(xy 290.106384 -403.16711) (xy 290.099879 -403.184309) (xy 290.099496 -403.193504) (xy 290.099496 -403.351492)
			(xy 290.099072 -403.361646) (xy 290.091278 -403.380399) (xy 290.076882 -403.394723) (xy 290.05809 -403.402422)
			(xy 290.047934 -403.4028) (xy 289.331654 -403.4028) (xy 289.321529 -403.402312) (xy 289.302815 -403.394577)
			(xy 289.288461 -403.380292) (xy 289.280637 -403.361614) (xy 289.280092 -403.351492) (xy 289.280092 -403.193504)
			(xy 289.279682 -403.184317) (xy 289.273168 -403.167132) (xy 289.267392 -403.159976) (xy 289.245556 -403.134363)
			(xy 289.207605 -403.078772) (xy 289.176571 -403.019044) (xy 289.152898 -402.956034) (xy 289.136927 -402.890647)
			(xy 289.128886 -402.823819) (xy 237.030424 -402.823819) (xy 237.026709 -402.832791) (xy 237.026196 -402.84527)
			(xy 237.026196 -405.623708) (xy 286.928756 -405.623708) (xy 286.928757 -405.556283) (xy 286.936834 -405.489343)
			(xy 286.952872 -405.423853) (xy 286.976639 -405.360756) (xy 287.007793 -405.30096) (xy 287.045886 -405.245326)
			(xy 287.067752 -405.219662) (xy 287.073554 -405.212521) (xy 287.080064 -405.195327) (xy 287.080452 -405.186134)
			(xy 287.080452 -404.693882) (xy 287.080039 -404.684695) (xy 287.073526 -404.667512) (xy 287.067752 -404.660354)
			(xy 287.045908 -404.634672) (xy 287.007815 -404.579041) (xy 286.97666 -404.519248) (xy 286.952893 -404.456153)
			(xy 286.936854 -404.390665) (xy 286.928776 -404.323728) (xy 286.928774 -404.256305) (xy 286.936848 -404.189367)
			(xy 286.952883 -404.123879) (xy 286.976647 -404.060783) (xy 287.007798 -404.000987) (xy 287.045888 -403.945354)
			(xy 287.067752 -403.91969) (xy 287.073542 -403.91254) (xy 287.080059 -403.895353) (xy 287.080452 -403.886162)
			(xy 287.080452 -403.728682) (xy 287.080912 -403.718553) (xy 287.088648 -403.699829) (xy 287.102942 -403.685473)
			(xy 287.121633 -403.677656) (xy 287.13176 -403.67712) (xy 287.84804 -403.67712) (xy 287.858199 -403.677489)
			(xy 287.876956 -403.685302) (xy 287.891279 -403.699715) (xy 287.898974 -403.71852) (xy 287.899348 -403.728682)
			(xy 287.899348 -403.886162) (xy 287.899788 -403.895346) (xy 287.906282 -403.91253) (xy 287.912048 -403.91969)
			(xy 287.933935 -403.945337) (xy 287.972027 -404.000973) (xy 288.00318 -404.060771) (xy 288.026945 -404.12387)
			(xy 288.04298 -404.189362) (xy 288.051055 -404.256303) (xy 288.051053 -404.32373) (xy 288.042974 -404.39067)
			(xy 288.026935 -404.456161) (xy 288.003166 -404.519259) (xy 287.97201 -404.579056) (xy 287.933915 -404.63469)
			(xy 287.912048 -404.660354) (xy 287.90624 -404.667491) (xy 287.899733 -404.684688) (xy 287.899348 -404.693882)
			(xy 287.899348 -405.186134) (xy 287.899754 -405.195321) (xy 287.906272 -405.212505) (xy 287.912048 -405.219662)
			(xy 287.933908 -405.245331) (xy 287.972 -405.300964) (xy 288.003154 -405.360759) (xy 288.026921 -405.423856)
			(xy 288.042958 -405.489345) (xy 288.051036 -405.556283) (xy 288.051036 -405.623708) (xy 288.04296 -405.690646)
			(xy 288.026924 -405.756136) (xy 288.003158 -405.819233) (xy 287.972005 -405.879028) (xy 287.933913 -405.934662)
			(xy 287.912048 -405.960326) (xy 287.906251 -405.967471) (xy 287.899738 -405.984662) (xy 287.899348 -405.993854)
			(xy 287.899348 -406.151334) (xy 287.898901 -406.161464) (xy 287.89116 -406.180189) (xy 287.876861 -406.194544)
			(xy 287.858168 -406.20236) (xy 287.84804 -406.202896) (xy 287.13176 -406.202896) (xy 287.121603 -406.202511)
			(xy 287.102849 -406.194701) (xy 287.088527 -406.180294) (xy 287.080829 -406.161494) (xy 287.080452 -406.151334)
			(xy 287.080452 -405.993854) (xy 287.080004 -405.984671) (xy 287.073515 -405.967487) (xy 287.067752 -405.960326)
			(xy 287.04588 -405.934667) (xy 287.007788 -405.879032) (xy 286.976635 -405.819236) (xy 286.952869 -405.756138)
			(xy 286.936832 -405.690648) (xy 286.928756 -405.623708) (xy 237.026196 -405.623708) (xy 237.026196 -406.72373)
			(xy 289.128897 -406.72373) (xy 289.1289 -406.656422) (xy 289.136948 -406.589596) (xy 289.152926 -406.524211)
			(xy 289.176605 -406.461205) (xy 289.207645 -406.401481) (xy 289.245601 -406.345895) (xy 289.267392 -406.320244)
			(xy 289.273194 -406.313103) (xy 289.279706 -406.295909) (xy 289.280092 -406.286716) (xy 289.280092 -405.793448)
			(xy 289.279661 -405.784263) (xy 289.273162 -405.767078) (xy 289.267392 -405.75992) (xy 289.245599 -405.734272)
			(xy 289.207647 -405.678686) (xy 289.176611 -405.618962) (xy 289.152936 -405.555957) (xy 289.136961 -405.490574)
			(xy 289.128917 -405.42375) (xy 289.128917 -405.356444) (xy 289.136962 -405.28962) (xy 289.152937 -405.224237)
			(xy 289.176613 -405.161232) (xy 289.20765 -405.101509) (xy 289.245602 -405.045923) (xy 289.267392 -405.020272)
			(xy 289.273182 -405.013122) (xy 289.279701 -404.995935) (xy 289.280092 -404.986744) (xy 289.280092 -404.828756)
			(xy 289.280486 -404.8186) (xy 289.288294 -404.799848) (xy 289.302699 -404.785527) (xy 289.321496 -404.777827)
			(xy 289.331654 -404.777448) (xy 290.047934 -404.777448) (xy 290.058064 -404.777899) (xy 290.076787 -404.785639)
			(xy 290.091143 -404.799936) (xy 290.098959 -404.818628) (xy 290.099496 -404.828756) (xy 290.099496 -404.986744)
			(xy 290.099886 -404.995933) (xy 290.106414 -405.013117) (xy 290.112196 -405.020272) (xy 290.133979 -405.045928)
			(xy 290.171925 -405.101515) (xy 290.202957 -405.161238) (xy 290.226628 -405.224242) (xy 290.242601 -405.289623)
			(xy 290.250644 -405.356445) (xy 290.250645 -405.423749) (xy 290.242602 -405.490571) (xy 290.22663 -405.555952)
			(xy 290.202959 -405.618957) (xy 290.200522 -405.623648) (xy 291.329076 -405.623648) (xy 291.329076 -405.556343)
			(xy 291.337121 -405.48952) (xy 291.353095 -405.424137) (xy 291.376768 -405.361132) (xy 291.407802 -405.301409)
			(xy 291.445752 -405.245822) (xy 291.46754 -405.22017) (xy 291.473337 -405.213025) (xy 291.47985 -405.195834)
			(xy 291.48024 -405.186642) (xy 291.48024 -404.693374) (xy 291.479833 -404.684187) (xy 291.473316 -404.667003)
			(xy 291.46754 -404.659846) (xy 291.445774 -404.634176) (xy 291.407825 -404.578592) (xy 291.37679 -404.518871)
			(xy 291.353116 -404.455869) (xy 291.337142 -404.390489) (xy 291.329096 -404.323668) (xy 291.329094 -404.256365)
			(xy 291.337136 -404.189544) (xy 291.353106 -404.124163) (xy 291.376777 -404.061159) (xy 291.407808 -404.001436)
			(xy 291.445754 -403.94585) (xy 291.46754 -403.920198) (xy 291.473325 -403.913045) (xy 291.479846 -403.89586)
			(xy 291.48024 -403.88667) (xy 291.48024 -403.728682) (xy 291.480718 -403.718523) (xy 291.488499 -403.699753)
			(xy 291.50287 -403.685388) (xy 291.521643 -403.677615) (xy 291.531802 -403.67712) (xy 292.248082 -403.67712)
			(xy 292.258236 -403.677648) (xy 292.277002 -403.685413) (xy 292.291367 -403.699768) (xy 292.299145 -403.718528)
			(xy 292.299644 -403.728682) (xy 292.299644 -403.88667) (xy 292.300081 -403.895854) (xy 292.306577 -403.913038)
			(xy 292.312344 -403.920198) (xy 292.334154 -403.945832) (xy 292.372103 -404.001421) (xy 292.403137 -404.061147)
			(xy 292.426809 -404.124153) (xy 292.442781 -404.189538) (xy 292.450824 -404.256363) (xy 292.450822 -404.32367)
			(xy 292.442775 -404.390495) (xy 292.426799 -404.455878) (xy 292.403123 -404.518884) (xy 292.372086 -404.578608)
			(xy 292.334134 -404.634194) (xy 292.312344 -404.659846) (xy 292.306539 -404.666985) (xy 292.300031 -404.68418)
			(xy 292.299644 -404.693374) (xy 292.299644 -405.186642) (xy 292.300047 -405.19583) (xy 292.306567 -405.213013)
			(xy 292.312344 -405.22017) (xy 292.334126 -405.245827) (xy 292.372076 -405.301412) (xy 292.403111 -405.361135)
			(xy 292.426785 -405.424139) (xy 292.442758 -405.489521) (xy 292.450803 -405.556343) (xy 292.450804 -405.623648)
			(xy 292.44276 -405.69047) (xy 292.426787 -405.755852) (xy 292.403114 -405.818857) (xy 292.372081 -405.87858)
			(xy 292.334132 -405.934166) (xy 292.312344 -405.959818) (xy 292.30655 -405.966965) (xy 292.300035 -405.984154)
			(xy 292.299644 -405.993346) (xy 292.299644 -406.151334) (xy 292.299194 -406.161496) (xy 292.291405 -406.18027)
			(xy 292.277026 -406.194634) (xy 292.258245 -406.202404) (xy 292.248082 -406.202896) (xy 291.531802 -406.202896)
			(xy 291.521649 -406.202366) (xy 291.502886 -406.194598) (xy 291.488522 -406.180244) (xy 291.480741 -406.161487)
			(xy 291.48024 -406.151334) (xy 291.48024 -405.993346) (xy 291.479799 -405.984162) (xy 291.473306 -405.966978)
			(xy 291.46754 -405.959818) (xy 291.445746 -405.934171) (xy 291.407797 -405.878584) (xy 291.376764 -405.818859)
			(xy 291.353092 -405.755854) (xy 291.337119 -405.690471) (xy 291.329076 -405.623648) (xy 290.200522 -405.623648)
			(xy 290.171928 -405.67868) (xy 290.133982 -405.734267) (xy 290.112196 -405.75992) (xy 290.106408 -405.767071)
			(xy 290.099888 -405.784257) (xy 290.099496 -405.793448) (xy 290.099496 -406.286716) (xy 290.099899 -406.295904)
			(xy 290.106418 -406.313088) (xy 290.112196 -406.320244) (xy 290.133951 -406.345922) (xy 290.171899 -406.401506)
			(xy 290.202931 -406.461226) (xy 290.226605 -406.524227) (xy 290.242579 -406.589606) (xy 290.250625 -406.656425)
			(xy 290.250628 -406.723727) (xy 290.250621 -406.723789) (xy 293.52869 -406.723789) (xy 293.528692 -406.656363)
			(xy 293.536771 -406.589423) (xy 293.55281 -406.523932) (xy 293.576577 -406.460834) (xy 293.607731 -406.401037)
			(xy 293.645823 -406.345401) (xy 293.667688 -406.319736) (xy 293.673493 -406.312597) (xy 293.680003 -406.295402)
			(xy 293.680388 -406.286208) (xy 293.680388 -405.793956) (xy 293.680002 -405.784766) (xy 293.673472 -405.767582)
			(xy 293.667688 -405.760428) (xy 293.645821 -405.734766) (xy 293.607733 -405.679131) (xy 293.576583 -405.619334)
			(xy 293.552819 -405.556237) (xy 293.536785 -405.490747) (xy 293.528709 -405.423809) (xy 293.52871 -405.356385)
			(xy 293.536786 -405.289447) (xy 293.552821 -405.223958) (xy 293.576585 -405.160861) (xy 293.607736 -405.101064)
			(xy 293.645824 -405.045429) (xy 293.667688 -405.019764) (xy 293.673481 -405.012616) (xy 293.679998 -404.995428)
			(xy 293.680388 -404.986236) (xy 293.680388 -404.828756) (xy 293.680849 -404.818646) (xy 293.688599 -404.799969)
			(xy 293.702903 -404.785676) (xy 293.721586 -404.777941) (xy 293.731696 -404.777448) (xy 294.447976 -404.777448)
			(xy 294.458077 -404.778003) (xy 294.476745 -404.785723) (xy 294.491038 -404.799998) (xy 294.498783 -404.818656)
			(xy 294.499284 -404.828756) (xy 294.499284 -404.986236) (xy 294.49968 -404.995425) (xy 294.506204 -405.012609)
			(xy 294.511984 -405.019764) (xy 294.533845 -405.045432) (xy 294.571934 -405.101066) (xy 294.603086 -405.160862)
			(xy 294.626851 -405.223958) (xy 294.642888 -405.289447) (xy 294.650964 -405.356385) (xy 294.650964 -405.423809)
			(xy 294.642889 -405.490747) (xy 294.626853 -405.556236) (xy 294.603089 -405.619333) (xy 294.60081 -405.623708)
			(xy 295.728844 -405.623708) (xy 295.728845 -405.556283) (xy 295.736922 -405.489344) (xy 295.752959 -405.423854)
			(xy 295.776725 -405.360757) (xy 295.807879 -405.30096) (xy 295.84597 -405.245327) (xy 295.867836 -405.219662)
			(xy 295.873636 -405.212519) (xy 295.880148 -405.195327) (xy 295.880536 -405.186134) (xy 295.880536 -404.693882)
			(xy 295.880126 -404.684695) (xy 295.873611 -404.667511) (xy 295.867836 -404.660354) (xy 295.845992 -404.634672)
			(xy 295.807901 -404.57904) (xy 295.776747 -404.519247) (xy 295.75298 -404.456152) (xy 295.736942 -404.390665)
			(xy 295.728864 -404.323728) (xy 295.728862 -404.256305) (xy 295.736936 -404.189368) (xy 295.75297 -404.123879)
			(xy 295.776733 -404.060783) (xy 295.807884 -404.000988) (xy 295.845972 -403.945355) (xy 295.867836 -403.91969)
			(xy 295.873624 -403.912539) (xy 295.880143 -403.895353) (xy 295.880536 -403.886162) (xy 295.880536 -403.728682)
			(xy 295.881011 -403.718555) (xy 295.888744 -403.699834) (xy 295.903034 -403.685478) (xy 295.921719 -403.677659)
			(xy 295.931844 -403.67712) (xy 296.648124 -403.67712) (xy 296.658282 -403.677502) (xy 296.677039 -403.685309)
			(xy 296.691362 -403.699718) (xy 296.699058 -403.718521) (xy 296.699432 -403.728682) (xy 296.699432 -403.886162)
			(xy 296.699876 -403.895345) (xy 296.706368 -403.912529) (xy 296.712132 -403.91969) (xy 296.734016 -403.945338)
			(xy 296.772102 -404.000976) (xy 296.80325 -404.060775) (xy 296.827012 -404.123874) (xy 296.843045 -404.189364)
			(xy 296.851118 -404.256304) (xy 296.851117 -404.323729) (xy 296.843039 -404.390668) (xy 296.827002 -404.456158)
			(xy 296.803237 -404.519256) (xy 296.772085 -404.579053) (xy 296.733996 -404.634688) (xy 296.712132 -404.660354)
			(xy 296.706322 -404.667489) (xy 296.699817 -404.684688) (xy 296.699432 -404.693882) (xy 296.699432 -405.186134)
			(xy 296.699841 -405.195321) (xy 296.706357 -405.212505) (xy 296.712132 -405.219662) (xy 296.733989 -405.245333)
			(xy 296.772076 -405.300967) (xy 296.803225 -405.360763) (xy 296.826988 -405.423859) (xy 296.843023 -405.489347)
			(xy 296.851099 -405.556284) (xy 296.851099 -405.623707) (xy 296.843025 -405.690644) (xy 296.826991 -405.756132)
			(xy 296.803229 -405.819229) (xy 296.77208 -405.879025) (xy 296.733994 -405.93466) (xy 296.712132 -405.960326)
			(xy 296.706334 -405.96747) (xy 296.699822 -405.984662) (xy 296.699432 -405.993854) (xy 296.699432 -406.151334)
			(xy 296.699001 -406.161466) (xy 296.691256 -406.180194) (xy 296.676953 -406.19455) (xy 296.658254 -406.202363)
			(xy 296.648124 -406.202896) (xy 295.931844 -406.202896) (xy 295.921692 -406.202442) (xy 295.90294 -406.19466)
			(xy 295.888615 -406.180273) (xy 295.880915 -406.161487) (xy 295.880536 -406.151334) (xy 295.880536 -405.993854)
			(xy 295.880092 -405.984671) (xy 295.873601 -405.967486) (xy 295.867836 -405.960326) (xy 295.845965 -405.934666)
			(xy 295.807874 -405.879032) (xy 295.776722 -405.819235) (xy 295.752956 -405.756137) (xy 295.73692 -405.690647)
			(xy 295.728844 -405.623708) (xy 294.60081 -405.623708) (xy 294.571938 -405.679129) (xy 294.533848 -405.734763)
			(xy 294.511984 -405.760428) (xy 294.506191 -405.767576) (xy 294.499675 -405.784764) (xy 294.499284 -405.793956)
			(xy 294.499284 -406.286208) (xy 294.499694 -406.295395) (xy 294.506208 -406.312579) (xy 294.511984 -406.319736)
			(xy 294.533817 -406.345427) (xy 294.571908 -406.401057) (xy 294.603061 -406.46085) (xy 294.626827 -406.523943)
			(xy 294.642866 -406.58943) (xy 294.650944 -406.656365) (xy 294.650947 -406.72373) (xy 297.928985 -406.72373)
			(xy 297.928988 -406.656422) (xy 297.937036 -406.589596) (xy 297.953013 -406.524212) (xy 297.976691 -406.461206)
			(xy 298.00773 -406.401482) (xy 298.045685 -406.345896) (xy 298.067476 -406.320244) (xy 298.073276 -406.313101)
			(xy 298.079789 -406.295909) (xy 298.080176 -406.286716) (xy 298.080176 -405.793448) (xy 298.079748 -405.784263)
			(xy 298.073247 -405.767078) (xy 298.067476 -405.75992) (xy 298.045683 -405.734272) (xy 298.007732 -405.678685)
			(xy 297.976697 -405.618962) (xy 297.953023 -405.555957) (xy 297.937049 -405.490574) (xy 297.929005 -405.42375)
			(xy 297.929005 -405.356444) (xy 297.93705 -405.28962) (xy 297.953025 -405.224238) (xy 297.9767 -405.161233)
			(xy 298.007735 -405.101509) (xy 298.045687 -405.045924) (xy 298.067476 -405.020272) (xy 298.073264 -405.013121)
			(xy 298.079785 -404.995935) (xy 298.080176 -404.986744) (xy 298.080176 -404.828756) (xy 298.080585 -404.818602)
			(xy 298.088391 -404.799853) (xy 298.102791 -404.785532) (xy 298.121582 -404.77783) (xy 298.131738 -404.777448)
			(xy 298.848018 -404.777448) (xy 298.858147 -404.777912) (xy 298.87687 -404.785647) (xy 298.891226 -404.79994)
			(xy 298.899043 -404.818629) (xy 298.89958 -404.828756) (xy 298.89958 -404.986744) (xy 298.899973 -404.995933)
			(xy 298.906499 -405.013117) (xy 298.91228 -405.020272) (xy 298.934063 -405.045928) (xy 298.972011 -405.101514)
			(xy 299.003043 -405.161237) (xy 299.026716 -405.224241) (xy 299.042688 -405.289623) (xy 299.050732 -405.356445)
			(xy 299.050733 -405.423749) (xy 299.042689 -405.490571) (xy 299.026717 -405.555953) (xy 299.003046 -405.618957)
			(xy 299.000577 -405.623708) (xy 300.128635 -405.623708) (xy 300.128635 -405.556283) (xy 300.136712 -405.489344)
			(xy 300.152749 -405.423854) (xy 300.176515 -405.360757) (xy 300.207668 -405.300961) (xy 300.245759 -405.245327)
			(xy 300.267624 -405.219662) (xy 300.273422 -405.212518) (xy 300.279935 -405.195326) (xy 300.280324 -405.186134)
			(xy 300.280324 -404.693882) (xy 300.279917 -404.684695) (xy 300.273401 -404.66751) (xy 300.267624 -404.660354)
			(xy 300.245781 -404.634671) (xy 300.20769 -404.57904) (xy 300.176537 -404.519246) (xy 300.15277 -404.456152)
			(xy 300.136733 -404.390664) (xy 300.128655 -404.323728) (xy 300.128653 -404.256305) (xy 300.136727 -404.189368)
			(xy 300.152761 -404.12388) (xy 300.176523 -404.060784) (xy 300.207673 -404.000989) (xy 300.245761 -403.945355)
			(xy 300.267624 -403.91969) (xy 300.27341 -403.912538) (xy 300.27993 -403.895352) (xy 300.280324 -403.886162)
			(xy 300.280324 -403.728682) (xy 300.280811 -403.718556) (xy 300.288542 -403.699837) (xy 300.302828 -403.685482)
			(xy 300.321509 -403.677661) (xy 300.331632 -403.67712) (xy 301.047912 -403.67712) (xy 301.058069 -403.677512)
			(xy 301.076826 -403.685315) (xy 301.09115 -403.699721) (xy 301.098846 -403.718522) (xy 301.09922 -403.728682)
			(xy 301.09922 -403.886162) (xy 301.099644 -403.895348) (xy 301.106147 -403.912533) (xy 301.11192 -403.91969)
			(xy 301.133805 -403.945338) (xy 301.171892 -404.000975) (xy 301.20304 -404.060774) (xy 301.226802 -404.123873)
			(xy 301.242836 -404.189364) (xy 301.250909 -404.256304) (xy 301.250907 -404.323729) (xy 301.24283 -404.390668)
			(xy 301.226793 -404.456158) (xy 301.203027 -404.519256) (xy 301.171875 -404.579053) (xy 301.133785 -404.634688)
			(xy 301.11192 -404.660354) (xy 301.10612 -404.667497) (xy 301.099607 -404.684689) (xy 301.09922 -404.693882)
			(xy 301.09922 -405.186134) (xy 301.099609 -405.195323) (xy 301.106137 -405.212508) (xy 301.11192 -405.219662)
			(xy 301.133777 -405.245332) (xy 301.171865 -405.300967) (xy 301.203015 -405.360762) (xy 301.226778 -405.423859)
			(xy 301.242814 -405.489347) (xy 301.25089 -405.556284) (xy 301.25089 -405.623707) (xy 301.242815 -405.690644)
			(xy 301.226781 -405.756133) (xy 301.203018 -405.819229) (xy 301.17187 -405.879026) (xy 301.133783 -405.93466)
			(xy 301.11192 -405.960326) (xy 301.106132 -405.967478) (xy 301.099612 -405.984663) (xy 301.09922 -405.993854)
			(xy 301.09922 -406.151334) (xy 301.0988 -406.161468) (xy 301.091054 -406.180197) (xy 301.076747 -406.194554)
			(xy 301.058044 -406.202365) (xy 301.047912 -406.202896) (xy 300.331632 -406.202896) (xy 300.321479 -406.202452)
			(xy 300.302727 -406.194667) (xy 300.288402 -406.180276) (xy 300.280702 -406.161488) (xy 300.280324 -406.151334)
			(xy 300.280324 -405.993854) (xy 300.279882 -405.98467) (xy 300.27339 -405.967486) (xy 300.267624 -405.960326)
			(xy 300.245753 -405.934666) (xy 300.207663 -405.879031) (xy 300.176511 -405.819235) (xy 300.152747 -405.756137)
			(xy 300.136711 -405.690647) (xy 300.128635 -405.623708) (xy 299.000577 -405.623708) (xy 298.972014 -405.678681)
			(xy 298.934067 -405.734268) (xy 298.91228 -405.75992) (xy 298.90649 -405.76707) (xy 298.899972 -405.784257)
			(xy 298.89958 -405.793448) (xy 298.89958 -406.286716) (xy 298.899987 -406.295903) (xy 298.906503 -406.313088)
			(xy 298.91228 -406.320244) (xy 298.934035 -406.345922) (xy 298.971984 -406.401506) (xy 299.003018 -406.461226)
			(xy 299.026691 -406.524227) (xy 299.042666 -406.589606) (xy 299.050712 -406.656425) (xy 299.050715 -406.723727)
			(xy 299.050708 -406.723789) (xy 302.328777 -406.723789) (xy 302.32878 -406.656363) (xy 302.336859 -406.589423)
			(xy 302.352897 -406.523933) (xy 302.376664 -406.460835) (xy 302.407816 -406.401037) (xy 302.445907 -406.345402)
			(xy 302.467772 -406.319736) (xy 302.473587 -406.312604) (xy 302.480089 -406.295403) (xy 302.480472 -406.286208)
			(xy 302.480472 -405.793956) (xy 302.480089 -405.784766) (xy 302.473557 -405.767581) (xy 302.467772 -405.760428)
			(xy 302.445905 -405.734766) (xy 302.407818 -405.67913) (xy 302.376669 -405.619333) (xy 302.352907 -405.556236)
			(xy 302.336872 -405.490747) (xy 302.328797 -405.423809) (xy 302.328798 -405.356385) (xy 302.336873 -405.289447)
			(xy 302.352908 -405.223958) (xy 302.376672 -405.160861) (xy 302.407821 -405.101065) (xy 302.445909 -405.04543)
			(xy 302.467772 -405.019764) (xy 302.473575 -405.012624) (xy 302.480084 -404.995429) (xy 302.480472 -404.986236)
			(xy 302.480472 -404.828756) (xy 302.480948 -404.818648) (xy 302.488695 -404.799974) (xy 302.502994 -404.785682)
			(xy 302.521672 -404.777944) (xy 302.53178 -404.777448) (xy 303.24806 -404.777448) (xy 303.25816 -404.778017)
			(xy 303.276827 -404.785732) (xy 303.291121 -404.800002) (xy 303.298867 -404.818657) (xy 303.299368 -404.828756)
			(xy 303.299368 -404.986236) (xy 303.299768 -404.995424) (xy 303.30629 -405.012608) (xy 303.312068 -405.019764)
			(xy 303.333929 -405.045432) (xy 303.37202 -405.101065) (xy 303.403173 -405.160861) (xy 303.426939 -405.223957)
			(xy 303.442975 -405.289447) (xy 303.451052 -405.356385) (xy 303.451052 -405.423809) (xy 303.442976 -405.490748)
			(xy 303.42694 -405.556237) (xy 303.403175 -405.619334) (xy 303.372023 -405.67913) (xy 303.333933 -405.734763)
			(xy 303.312068 -405.760428) (xy 303.306273 -405.767574) (xy 303.299758 -405.784764) (xy 303.299368 -405.793956)
			(xy 303.299368 -406.286208) (xy 303.299781 -406.295395) (xy 303.306294 -406.312579) (xy 303.312068 -406.319736)
			(xy 303.333902 -406.345427) (xy 303.371993 -406.401057) (xy 303.403147 -406.460849) (xy 303.426915 -406.523943)
			(xy 303.442953 -406.589429) (xy 303.451032 -406.656365) (xy 303.451035 -406.723787) (xy 303.442962 -406.790724)
			(xy 303.426929 -406.856211) (xy 303.403167 -406.919307) (xy 303.372018 -406.979102) (xy 303.333931 -407.034735)
			(xy 303.312068 -407.0604) (xy 303.306285 -407.067555) (xy 303.299763 -407.084738) (xy 303.299368 -407.093928)
			(xy 303.299368 -407.251408) (xy 303.29899 -407.261535) (xy 303.291233 -407.280245) (xy 303.276904 -407.29456)
			(xy 303.258187 -407.302299) (xy 303.24806 -407.302716) (xy 302.53178 -407.302716) (xy 302.521672 -407.302232)
			(xy 302.502996 -407.294491) (xy 302.488703 -407.280194) (xy 302.480966 -407.261516) (xy 302.480472 -407.251408)
			(xy 302.480472 -407.093928) (xy 302.480055 -407.084741) (xy 302.473547 -407.067557) (xy 302.467772 -407.0604)
			(xy 302.445878 -407.03476) (xy 302.407792 -406.979121) (xy 302.376644 -406.919321) (xy 302.352883 -406.856221)
			(xy 302.33685 -406.790729) (xy 302.328777 -406.723789) (xy 299.050708 -406.723789) (xy 299.042674 -406.790547)
			(xy 299.026705 -406.855927) (xy 299.003037 -406.91893) (xy 298.972009 -406.978653) (xy 298.934065 -407.034239)
			(xy 298.91228 -407.059892) (xy 298.906502 -407.06705) (xy 298.899977 -407.084231) (xy 298.89958 -407.09342)
			(xy 298.89958 -407.251408) (xy 298.899184 -407.261565) (xy 298.891382 -407.280321) (xy 298.876978 -407.294645)
			(xy 298.858177 -407.302341) (xy 298.848018 -407.302716) (xy 298.131738 -407.302716) (xy 298.121608 -407.302241)
			(xy 298.10288 -407.294517) (xy 298.088521 -407.280227) (xy 298.080708 -407.261535) (xy 298.080176 -407.251408)
			(xy 298.080176 -407.09342) (xy 298.079762 -407.084233) (xy 298.073252 -407.067048) (xy 298.067476 -407.059892)
			(xy 298.045656 -407.034266) (xy 298.007706 -406.978677) (xy 297.976672 -406.91895) (xy 297.952999 -406.855942)
			(xy 297.937027 -406.790556) (xy 297.928985 -406.72373) (xy 294.650947 -406.72373) (xy 294.650947 -406.723787)
			(xy 294.642874 -406.790723) (xy 294.626842 -406.856211) (xy 294.60308 -406.919306) (xy 294.571933 -406.979101)
			(xy 294.533847 -407.034735) (xy 294.511984 -407.0604) (xy 294.506203 -407.067556) (xy 294.49968 -407.084738)
			(xy 294.499284 -407.093928) (xy 294.499284 -407.251408) (xy 294.49889 -407.261533) (xy 294.491136 -407.28024)
			(xy 294.476813 -407.294554) (xy 294.458101 -407.302296) (xy 294.447976 -407.302716) (xy 293.731696 -407.302716)
			(xy 293.721589 -407.302218) (xy 293.702914 -407.294482) (xy 293.68862 -407.28019) (xy 293.680882 -407.261515)
			(xy 293.680388 -407.251408) (xy 293.680388 -407.093928) (xy 293.679967 -407.084742) (xy 293.673461 -407.067557)
			(xy 293.667688 -407.0604) (xy 293.645793 -407.03476) (xy 293.607706 -406.979122) (xy 293.576557 -406.919322)
			(xy 293.552796 -406.856222) (xy 293.536763 -406.79073) (xy 293.52869 -406.723789) (xy 290.250621 -406.723789)
			(xy 290.242587 -406.790547) (xy 290.226619 -406.855927) (xy 290.202951 -406.91893) (xy 290.171924 -406.978653)
			(xy 290.133981 -407.034239) (xy 290.112196 -407.059892) (xy 290.10642 -407.067052) (xy 290.099893 -407.084231)
			(xy 290.099496 -407.09342) (xy 290.099496 -407.251408) (xy 290.099085 -407.261563) (xy 290.091286 -407.280316)
			(xy 290.076886 -407.29464) (xy 290.058091 -407.302338) (xy 290.047934 -407.302716) (xy 289.331654 -407.302716)
			(xy 289.321519 -407.30231) (xy 289.302788 -407.294559) (xy 289.288432 -407.280248) (xy 289.280622 -407.261541)
			(xy 289.280092 -407.251408) (xy 289.280092 -407.09342) (xy 289.279674 -407.084234) (xy 289.273166 -407.067049)
			(xy 289.267392 -407.059892) (xy 289.245571 -407.034266) (xy 289.20762 -406.978677) (xy 289.176585 -406.918951)
			(xy 289.152912 -406.855943) (xy 289.136939 -406.790557) (xy 289.128897 -406.72373) (xy 237.026196 -406.72373)
			(xy 237.026196 -409.523887) (xy 286.928735 -409.523887) (xy 286.928738 -409.456459) (xy 286.936818 -409.389518)
			(xy 286.952859 -409.324026) (xy 286.97663 -409.260927) (xy 287.007788 -409.20113) (xy 287.045884 -409.145496)
			(xy 287.067752 -409.119832) (xy 287.073566 -409.1127) (xy 287.080069 -409.095499) (xy 287.080452 -409.086304)
			(xy 287.080452 -408.594052) (xy 287.080005 -408.584869) (xy 287.073516 -408.567685) (xy 287.067752 -408.560524)
			(xy 287.045878 -408.534866) (xy 287.007786 -408.479232) (xy 286.976633 -408.419435) (xy 286.952867 -408.356337)
			(xy 286.936831 -408.290847) (xy 286.928755 -408.223907) (xy 286.928755 -408.156481) (xy 286.936833 -408.089542)
			(xy 286.952871 -408.024051) (xy 286.976638 -407.960954) (xy 287.007793 -407.901158) (xy 287.045886 -407.845524)
			(xy 287.067752 -407.81986) (xy 287.073554 -407.812719) (xy 287.080064 -407.795525) (xy 287.080452 -407.786332)
			(xy 287.080452 -407.628852) (xy 287.080945 -407.618746) (xy 287.088689 -407.600076) (xy 287.102983 -407.585785)
			(xy 287.121654 -407.578043) (xy 287.13176 -407.577544) (xy 287.84804 -407.577544) (xy 287.858144 -407.578051)
			(xy 287.876813 -407.585791) (xy 287.891104 -407.600081) (xy 287.898847 -407.618748) (xy 287.899348 -407.628852)
			(xy 287.899348 -407.786332) (xy 287.899755 -407.795519) (xy 287.906272 -407.812703) (xy 287.912048 -407.81986)
			(xy 287.933906 -407.845531) (xy 287.971998 -407.901163) (xy 288.003152 -407.960958) (xy 288.026919 -408.024055)
			(xy 288.042957 -408.089543) (xy 288.051034 -408.156482) (xy 288.051035 -408.223906) (xy 288.042959 -408.290845)
			(xy 288.026923 -408.356334) (xy 288.003157 -408.419431) (xy 287.972004 -408.479226) (xy 287.933913 -408.53486)
			(xy 287.912048 -408.560524) (xy 287.906252 -408.56767) (xy 287.899739 -408.58486) (xy 287.899348 -408.594052)
			(xy 287.899348 -409.086304) (xy 287.899768 -409.09549) (xy 287.906276 -409.112674) (xy 287.912048 -409.119832)
			(xy 287.933878 -409.145526) (xy 287.971972 -409.201155) (xy 288.003127 -409.260947) (xy 288.026895 -409.32404)
			(xy 288.042935 -409.389526) (xy 288.051014 -409.456462) (xy 288.051018 -409.523884) (xy 288.042945 -409.590821)
			(xy 288.026911 -409.656308) (xy 288.003149 -409.719404) (xy 287.971999 -409.779199) (xy 287.933912 -409.834832)
			(xy 287.912048 -409.860496) (xy 287.906264 -409.86765) (xy 287.899743 -409.884834) (xy 287.899348 -409.894024)
			(xy 287.899348 -410.051504) (xy 287.898819 -410.061607) (xy 287.891089 -410.080276) (xy 287.876806 -410.094569)
			(xy 287.858143 -410.102312) (xy 287.84804 -410.102812) (xy 287.13176 -410.102812) (xy 287.12165 -410.102348)
			(xy 287.102973 -410.094599) (xy 287.08868 -410.080296) (xy 287.080945 -410.061614) (xy 287.080452 -410.051504)
			(xy 287.080452 -409.894024) (xy 287.080019 -409.884839) (xy 287.07352 -409.867655) (xy 287.067752 -409.860496)
			(xy 287.045851 -409.834861) (xy 287.00776 -409.779223) (xy 286.976608 -409.719423) (xy 286.952843 -409.656322)
			(xy 286.936809 -409.590829) (xy 286.928735 -409.523887) (xy 237.026196 -409.523887) (xy 237.026196 -410.623642)
			(xy 289.128908 -410.623642) (xy 289.12891 -410.556334) (xy 289.136956 -410.48951) (xy 289.152933 -410.424126)
			(xy 289.176609 -410.361121) (xy 289.207648 -410.301397) (xy 289.245602 -410.245811) (xy 289.267392 -410.22016)
			(xy 289.273187 -410.213014) (xy 289.279703 -410.195824) (xy 289.280092 -410.186632) (xy 289.280092 -409.693364)
			(xy 289.279701 -409.684175) (xy 289.273174 -409.66699) (xy 289.267392 -409.659836) (xy 289.245614 -409.634175)
			(xy 289.207662 -409.578591) (xy 289.176625 -409.518869) (xy 289.152949 -409.455866) (xy 289.136974 -409.390484)
			(xy 289.128928 -409.323662) (xy 289.128927 -409.256356) (xy 289.136971 -409.189534) (xy 289.152944 -409.124152)
			(xy 289.176618 -409.061147) (xy 289.207653 -409.001425) (xy 289.245603 -408.945839) (xy 289.267392 -408.920188)
			(xy 289.273175 -408.913033) (xy 289.279698 -408.89585) (xy 289.280092 -408.88666) (xy 289.280092 -408.728672)
			(xy 289.280498 -408.718517) (xy 289.288302 -408.699766) (xy 289.302703 -408.685443) (xy 289.321497 -408.677743)
			(xy 289.331654 -408.677364) (xy 290.047934 -408.677364) (xy 290.058066 -408.677799) (xy 290.076792 -408.685543)
			(xy 290.091148 -408.699845) (xy 290.098962 -408.718542) (xy 290.099496 -408.728672) (xy 290.099496 -408.88666)
			(xy 290.099926 -408.895845) (xy 290.106426 -408.91303) (xy 290.112196 -408.920188) (xy 290.133994 -408.945831)
			(xy 290.171941 -409.00142) (xy 290.202971 -409.061145) (xy 290.226642 -409.12415) (xy 290.242613 -409.189533)
			(xy 290.250656 -409.256356) (xy 290.250655 -409.323662) (xy 290.24261 -409.390484) (xy 290.226637 -409.455867)
			(xy 290.202964 -409.518872) (xy 290.200389 -409.523827) (xy 291.329055 -409.523827) (xy 291.329058 -409.456519)
			(xy 291.337106 -409.389694) (xy 291.353082 -409.32431) (xy 291.376759 -409.261304) (xy 291.407797 -409.201579)
			(xy 291.44575 -409.145992) (xy 291.46754 -409.12034) (xy 291.47335 -409.113204) (xy 291.479855 -409.096006)
			(xy 291.48024 -409.086812) (xy 291.48024 -408.593544) (xy 291.4798 -408.58436) (xy 291.473306 -408.567176)
			(xy 291.46754 -408.560016) (xy 291.445744 -408.53437) (xy 291.407796 -408.478783) (xy 291.376763 -408.419059)
			(xy 291.35309 -408.356053) (xy 291.337118 -408.29067) (xy 291.329074 -408.223847) (xy 291.329075 -408.156541)
			(xy 291.33712 -408.089718) (xy 291.353094 -408.024335) (xy 291.376767 -407.96133) (xy 291.407802 -407.901607)
			(xy 291.445752 -407.84602) (xy 291.46754 -407.820368) (xy 291.473338 -407.813224) (xy 291.479851 -407.796032)
			(xy 291.48024 -407.78684) (xy 291.48024 -407.628852) (xy 291.480583 -407.61869) (xy 291.488402 -407.599929)
			(xy 291.502823 -407.585606) (xy 291.521637 -407.577915) (xy 291.531802 -407.577544) (xy 292.248082 -407.577544)
			(xy 292.258208 -407.578041) (xy 292.27693 -407.585764) (xy 292.291287 -407.600047) (xy 292.299106 -407.618729)
			(xy 292.299644 -407.628852) (xy 292.299644 -407.78684) (xy 292.300048 -407.796028) (xy 292.306567 -407.813211)
			(xy 292.312344 -407.820368) (xy 292.334124 -407.846026) (xy 292.372074 -407.901612) (xy 292.403109 -407.961334)
			(xy 292.426783 -408.024338) (xy 292.442757 -408.089719) (xy 292.450802 -408.156542) (xy 292.450803 -408.223846)
			(xy 292.442759 -408.290669) (xy 292.426786 -408.356051) (xy 292.403114 -408.419055) (xy 292.372081 -408.478778)
			(xy 292.334132 -408.534364) (xy 292.312344 -408.560016) (xy 292.306551 -408.567164) (xy 292.300036 -408.584353)
			(xy 292.299644 -408.593544) (xy 292.299644 -409.086812) (xy 292.300061 -409.095998) (xy 292.306571 -409.113182)
			(xy 292.312344 -409.12034) (xy 292.334097 -409.146021) (xy 292.372048 -409.201603) (xy 292.403083 -409.261322)
			(xy 292.426759 -409.324323) (xy 292.442735 -409.389702) (xy 292.450782 -409.456522) (xy 292.450786 -409.523824)
			(xy 292.442745 -409.590645) (xy 292.426775 -409.656025) (xy 292.403106 -409.719028) (xy 292.372076 -409.77875)
			(xy 292.33413 -409.834336) (xy 292.312344 -409.859988) (xy 292.306521 -409.867114) (xy 292.300024 -409.884319)
			(xy 292.299644 -409.893516) (xy 292.299644 -410.051504) (xy 292.299182 -410.061653) (xy 292.291394 -410.080397)
			(xy 292.27701 -410.094718) (xy 292.258233 -410.102426) (xy 292.248082 -410.102812) (xy 291.531802 -410.102812)
			(xy 291.521682 -410.102273) (xy 291.502971 -410.094556) (xy 291.488616 -410.080286) (xy 291.480788 -410.061621)
			(xy 291.48024 -410.051504) (xy 291.48024 -409.893516) (xy 291.479813 -409.884331) (xy 291.47331 -409.867147)
			(xy 291.46754 -409.859988) (xy 291.445717 -409.834365) (xy 291.407769 -409.778774) (xy 291.376737 -409.719047)
			(xy 291.353066 -409.656039) (xy 291.337096 -409.590653) (xy 291.329055 -409.523827) (xy 290.200389 -409.523827)
			(xy 290.171931 -409.578596) (xy 290.133983 -409.634183) (xy 290.112196 -409.659836) (xy 290.106401 -409.666982)
			(xy 290.099886 -409.684172) (xy 290.099496 -409.693364) (xy 290.099496 -410.186632) (xy 290.099891 -410.195821)
			(xy 290.106415 -410.213005) (xy 290.112196 -410.22016) (xy 290.133967 -410.245826) (xy 290.171914 -410.301411)
			(xy 290.202946 -410.361133) (xy 290.226618 -410.424136) (xy 290.242591 -410.489516) (xy 290.250636 -410.556336)
			(xy 290.250638 -410.62364) (xy 290.250631 -410.6237) (xy 293.528701 -410.6237) (xy 293.528702 -410.556276)
			(xy 293.53678 -410.489336) (xy 293.552816 -410.423847) (xy 293.576582 -410.360749) (xy 293.607734 -410.300952)
			(xy 293.645824 -410.245317) (xy 293.667688 -410.219652) (xy 293.673486 -410.212508) (xy 293.68 -410.195317)
			(xy 293.680388 -410.186124) (xy 293.680388 -409.693872) (xy 293.679994 -409.684683) (xy 293.673469 -409.667499)
			(xy 293.667688 -409.660344) (xy 293.645836 -409.634669) (xy 293.607748 -409.579035) (xy 293.576597 -409.519241)
			(xy 293.552833 -409.456145) (xy 293.536797 -409.390657) (xy 293.52872 -409.32372) (xy 293.528719 -409.256298)
			(xy 293.536794 -409.189361) (xy 293.552828 -409.123872) (xy 293.57659 -409.060776) (xy 293.607739 -409.00098)
			(xy 293.645825 -408.945345) (xy 293.667688 -408.91968) (xy 293.673474 -408.912527) (xy 293.679995 -408.895343)
			(xy 293.680388 -408.886152) (xy 293.680388 -408.728672) (xy 293.680862 -408.718563) (xy 293.688606 -408.699886)
			(xy 293.702907 -408.685593) (xy 293.721587 -408.677857) (xy 293.731696 -408.677364) (xy 294.447976 -408.677364)
			(xy 294.458079 -408.677904) (xy 294.47675 -408.685627) (xy 294.491044 -408.699907) (xy 294.498786 -408.71857)
			(xy 294.499284 -408.728672) (xy 294.499284 -408.886152) (xy 294.499721 -408.895336) (xy 294.506216 -408.912521)
			(xy 294.511984 -408.91968) (xy 294.53386 -408.945335) (xy 294.57195 -409.000971) (xy 294.603101 -409.060768)
			(xy 294.626865 -409.123866) (xy 294.6429 -409.189357) (xy 294.650975 -409.256297) (xy 294.650974 -409.323721)
			(xy 294.642897 -409.390661) (xy 294.62686 -409.456151) (xy 294.603093 -409.519248) (xy 294.600676 -409.523887)
			(xy 295.728823 -409.523887) (xy 295.728826 -409.456459) (xy 295.736906 -409.389518) (xy 295.752947 -409.324026)
			(xy 295.776716 -409.260928) (xy 295.807873 -409.201131) (xy 295.845969 -409.145497) (xy 295.867836 -409.119832)
			(xy 295.873649 -409.112698) (xy 295.880153 -409.095499) (xy 295.880536 -409.086304) (xy 295.880536 -408.594052)
			(xy 295.880093 -408.584869) (xy 295.873601 -408.567684) (xy 295.867836 -408.560524) (xy 295.845963 -408.534866)
			(xy 295.807872 -408.479231) (xy 295.77672 -408.419434) (xy 295.752954 -408.356336) (xy 295.736918 -408.290846)
			(xy 295.728843 -408.223907) (xy 295.728843 -408.156481) (xy 295.736921 -408.089542) (xy 295.752958 -408.024052)
			(xy 295.776725 -407.960955) (xy 295.807878 -407.901159) (xy 295.84597 -407.845525) (xy 295.867836 -407.81986)
			(xy 295.873637 -407.812718) (xy 295.880148 -407.795525) (xy 295.880536 -407.786332) (xy 295.880536 -407.628852)
			(xy 295.880947 -407.618736) (xy 295.888707 -407.60005) (xy 295.903027 -407.585755) (xy 295.921727 -407.578029)
			(xy 295.931844 -407.577544) (xy 296.648124 -407.577544) (xy 296.658227 -407.578064) (xy 296.676895 -407.585799)
			(xy 296.691187 -407.600084) (xy 296.698931 -407.618749) (xy 296.699432 -407.628852) (xy 296.699432 -407.786332)
			(xy 296.699842 -407.795519) (xy 296.706357 -407.812703) (xy 296.712132 -407.81986) (xy 296.733987 -407.845532)
			(xy 296.772074 -407.901167) (xy 296.803223 -407.960962) (xy 296.826986 -408.024058) (xy 296.843021 -408.089546)
			(xy 296.851097 -408.156483) (xy 296.851098 -408.223905) (xy 296.843024 -408.290842) (xy 296.82699 -408.356331)
			(xy 296.803228 -408.419427) (xy 296.77208 -408.479223) (xy 296.733994 -408.534858) (xy 296.712132 -408.560524)
			(xy 296.706334 -408.567668) (xy 296.699822 -408.58486) (xy 296.699432 -408.594052) (xy 296.699432 -409.086304)
			(xy 296.699856 -409.095489) (xy 296.706362 -409.112673) (xy 296.712132 -409.119832) (xy 296.733959 -409.145527)
			(xy 296.772047 -409.201158) (xy 296.803198 -409.26095) (xy 296.826962 -409.324043) (xy 296.842999 -409.389528)
			(xy 296.851078 -409.456463) (xy 296.851081 -409.523883) (xy 296.843009 -409.590818) (xy 296.826978 -409.656305)
			(xy 296.80322 -409.7194) (xy 296.772075 -409.779196) (xy 296.733993 -409.83483) (xy 296.712132 -409.860496)
			(xy 296.706346 -409.867649) (xy 296.699827 -409.884834) (xy 296.699432 -409.894024) (xy 296.699432 -410.051504)
			(xy 296.698919 -410.061609) (xy 296.691186 -410.080281) (xy 296.676898 -410.094575) (xy 296.658229 -410.102315)
			(xy 296.648124 -410.102812) (xy 295.931844 -410.102812) (xy 295.921726 -410.102348) (xy 295.903026 -410.094617)
			(xy 295.88871 -410.080315) (xy 295.880961 -410.061622) (xy 295.880536 -410.051504) (xy 295.880536 -409.894024)
			(xy 295.880106 -409.884839) (xy 295.873605 -409.867655) (xy 295.867836 -409.860496) (xy 295.845935 -409.834861)
			(xy 295.807845 -409.779223) (xy 295.776694 -409.719423) (xy 295.752931 -409.656322) (xy 295.736896 -409.590829)
			(xy 295.728823 -409.523887) (xy 294.600676 -409.523887) (xy 294.57194 -409.579045) (xy 294.533849 -409.634679)
			(xy 294.511984 -409.660344) (xy 294.506184 -409.667487) (xy 294.499672 -409.684679) (xy 294.499284 -409.693872)
			(xy 294.499284 -410.186124) (xy 294.499686 -410.195312) (xy 294.506206 -410.212496) (xy 294.511984 -410.219652)
			(xy 294.533833 -410.24533) (xy 294.571923 -410.300962) (xy 294.603075 -410.360757) (xy 294.626841 -410.423852)
			(xy 294.642878 -410.489339) (xy 294.650956 -410.556277) (xy 294.650957 -410.623641) (xy 297.928996 -410.623641)
			(xy 297.928998 -410.556334) (xy 297.937044 -410.48951) (xy 297.95302 -410.424127) (xy 297.976696 -410.361121)
			(xy 298.007733 -410.301398) (xy 298.045686 -410.245812) (xy 298.067476 -410.22016) (xy 298.073269 -410.213012)
			(xy 298.079787 -410.195824) (xy 298.080176 -410.186632) (xy 298.080176 -409.693364) (xy 298.079788 -409.684174)
			(xy 298.07326 -409.66699) (xy 298.067476 -409.659836) (xy 298.045699 -409.634175) (xy 298.007747 -409.57859)
			(xy 297.976712 -409.518868) (xy 297.953037 -409.455865) (xy 297.937062 -409.390484) (xy 297.929016 -409.323661)
			(xy 297.929015 -409.256357) (xy 297.937058 -409.189534) (xy 297.953031 -409.124152) (xy 297.976704 -409.061148)
			(xy 298.007738 -409.001425) (xy 298.045688 -408.94584) (xy 298.067476 -408.920188) (xy 298.073257 -408.913032)
			(xy 298.079782 -408.89585) (xy 298.080176 -408.88666) (xy 298.080176 -408.728672) (xy 298.080598 -408.718519)
			(xy 298.088398 -408.699771) (xy 298.102794 -408.685449) (xy 298.121583 -408.677746) (xy 298.131738 -408.677364)
			(xy 298.848018 -408.677364) (xy 298.858149 -408.677812) (xy 298.876875 -408.68555) (xy 298.891232 -408.699849)
			(xy 298.899046 -408.718543) (xy 298.89958 -408.728672) (xy 298.89958 -408.88666) (xy 298.900014 -408.895845)
			(xy 298.906512 -408.913029) (xy 298.91228 -408.920188) (xy 298.934079 -408.945831) (xy 298.972026 -409.001419)
			(xy 299.003058 -409.061144) (xy 299.026729 -409.12415) (xy 299.042701 -409.189533) (xy 299.050744 -409.256356)
			(xy 299.050743 -409.323662) (xy 299.042698 -409.390485) (xy 299.026724 -409.455868) (xy 299.003051 -409.518873)
			(xy 299.000446 -409.523886) (xy 300.128614 -409.523886) (xy 300.128617 -409.456459) (xy 300.136697 -409.389518)
			(xy 300.152737 -409.324027) (xy 300.176506 -409.260928) (xy 300.207662 -409.201131) (xy 300.245757 -409.145497)
			(xy 300.267624 -409.119832) (xy 300.273435 -409.112697) (xy 300.27994 -409.095499) (xy 300.280324 -409.086304)
			(xy 300.280324 -408.594052) (xy 300.279883 -408.584868) (xy 300.27339 -408.567684) (xy 300.267624 -408.560524)
			(xy 300.245751 -408.534866) (xy 300.207661 -408.479231) (xy 300.17651 -408.419434) (xy 300.152745 -408.356336)
			(xy 300.136709 -408.290846) (xy 300.128634 -408.223906) (xy 300.128634 -408.156482) (xy 300.136711 -408.089542)
			(xy 300.152748 -408.024053) (xy 300.176514 -407.960955) (xy 300.207667 -407.901159) (xy 300.245759 -407.845525)
			(xy 300.267624 -407.81986) (xy 300.273423 -407.812717) (xy 300.279935 -407.795525) (xy 300.280324 -407.786332)
			(xy 300.280324 -407.628852) (xy 300.280747 -407.618737) (xy 300.288504 -407.600053) (xy 300.302821 -407.585759)
			(xy 300.321516 -407.578031) (xy 300.331632 -407.577544) (xy 301.047912 -407.577544) (xy 301.058015 -407.578074)
			(xy 301.076682 -407.585805) (xy 301.090975 -407.600088) (xy 301.098719 -407.61875) (xy 301.09922 -407.628852)
			(xy 301.09922 -407.786332) (xy 301.09961 -407.795521) (xy 301.106137 -407.812706) (xy 301.11192 -407.81986)
			(xy 301.133775 -407.845532) (xy 301.171863 -407.901166) (xy 301.203013 -407.960962) (xy 301.226777 -408.024057)
			(xy 301.242812 -408.089545) (xy 301.250888 -408.156483) (xy 301.250889 -408.223905) (xy 301.242814 -408.290843)
			(xy 301.22678 -408.356331) (xy 301.203018 -408.419427) (xy 301.171869 -408.479224) (xy 301.133783 -408.534858)
			(xy 301.11192 -408.560524) (xy 301.106133 -408.567676) (xy 301.099612 -408.584861) (xy 301.09922 -408.594052)
			(xy 301.09922 -409.086304) (xy 301.099624 -409.095492) (xy 301.106141 -409.112676) (xy 301.11192 -409.119832)
			(xy 301.133748 -409.145527) (xy 301.171836 -409.201158) (xy 301.202988 -409.26095) (xy 301.226753 -409.324043)
			(xy 301.24279 -409.389528) (xy 301.250869 -409.456463) (xy 301.250872 -409.523883) (xy 301.2428 -409.590819)
			(xy 301.226769 -409.656305) (xy 301.20301 -409.719401) (xy 301.171864 -409.779196) (xy 301.133781 -409.83483)
			(xy 301.11192 -409.860496) (xy 301.106145 -409.867657) (xy 301.099617 -409.884835) (xy 301.09922 -409.894024)
			(xy 301.09922 -410.051504) (xy 301.098719 -410.06161) (xy 301.090983 -410.080285) (xy 301.076692 -410.094579)
			(xy 301.058018 -410.102317) (xy 301.047912 -410.102812) (xy 300.331632 -410.102812) (xy 300.321513 -410.102358)
			(xy 300.302812 -410.094623) (xy 300.288497 -410.080318) (xy 300.280749 -410.061623) (xy 300.280324 -410.051504)
			(xy 300.280324 -409.894024) (xy 300.279897 -409.884839) (xy 300.273394 -409.867655) (xy 300.267624 -409.860496)
			(xy 300.245724 -409.83486) (xy 300.207635 -409.779222) (xy 300.176484 -409.719422) (xy 300.152721 -409.656321)
			(xy 300.136687 -409.590828) (xy 300.128614 -409.523886) (xy 299.000446 -409.523886) (xy 298.972017 -409.578597)
			(xy 298.934068 -409.634184) (xy 298.91228 -409.659836) (xy 298.906483 -409.666981) (xy 298.899969 -409.684172)
			(xy 298.89958 -409.693364) (xy 298.89958 -410.186632) (xy 298.899979 -410.19582) (xy 298.906501 -410.213004)
			(xy 298.91228 -410.22016) (xy 298.934052 -410.245825) (xy 298.972 -410.30141) (xy 299.003032 -410.361132)
			(xy 299.026705 -410.424135) (xy 299.042679 -410.489515) (xy 299.050724 -410.556336) (xy 299.050725 -410.62364)
			(xy 299.050718 -410.6237) (xy 302.328789 -410.6237) (xy 302.32879 -410.556276) (xy 302.336867 -410.489337)
			(xy 302.352904 -410.423847) (xy 302.376668 -410.36075) (xy 302.407819 -410.300953) (xy 302.445908 -410.245318)
			(xy 302.467772 -410.219652) (xy 302.47358 -410.212515) (xy 302.480086 -410.195318) (xy 302.480472 -410.186124)
			(xy 302.480472 -409.693872) (xy 302.480082 -409.684683) (xy 302.473555 -409.667498) (xy 302.467772 -409.660344)
			(xy 302.445921 -409.634669) (xy 302.407834 -409.579035) (xy 302.376684 -409.51924) (xy 302.35292 -409.456144)
			(xy 302.336885 -409.390657) (xy 302.328808 -409.32372) (xy 302.328807 -409.256298) (xy 302.336882 -409.189361)
			(xy 302.352915 -409.123873) (xy 302.376677 -409.060777) (xy 302.407824 -409.000981) (xy 302.44591 -408.945346)
			(xy 302.467772 -408.91968) (xy 302.473568 -408.912535) (xy 302.480081 -408.895344) (xy 302.480472 -408.886152)
			(xy 302.480472 -408.728672) (xy 302.480961 -408.718565) (xy 302.488703 -408.699891) (xy 302.502998 -408.685599)
			(xy 302.521673 -408.67786) (xy 302.53178 -408.677364) (xy 303.24806 -408.677364) (xy 303.258175 -408.677848)
			(xy 303.276871 -408.685576) (xy 303.291186 -408.699872) (xy 303.298939 -408.718557) (xy 303.299368 -408.728672)
			(xy 303.299368 -408.886152) (xy 303.299809 -408.895336) (xy 303.306302 -408.91252) (xy 303.312068 -408.91968)
			(xy 303.333945 -408.945335) (xy 303.372035 -409.00097) (xy 303.403187 -409.060768) (xy 303.426952 -409.123866)
			(xy 303.442988 -409.189356) (xy 303.451063 -409.256296) (xy 303.451062 -409.323722) (xy 303.442985 -409.390661)
			(xy 303.426947 -409.456151) (xy 303.40318 -409.519249) (xy 303.372026 -409.579045) (xy 303.333934 -409.634679)
			(xy 303.312068 -409.660344) (xy 303.306266 -409.667485) (xy 303.299755 -409.684679) (xy 303.299368 -409.693872)
			(xy 303.299368 -410.186124) (xy 303.299774 -410.195312) (xy 303.306291 -410.212495) (xy 303.312068 -410.219652)
			(xy 303.333917 -410.24533) (xy 303.372009 -410.300962) (xy 303.403162 -410.360756) (xy 303.426928 -410.423851)
			(xy 303.442966 -410.489339) (xy 303.451044 -410.556276) (xy 303.451045 -410.6237) (xy 303.44297 -410.690637)
			(xy 303.426935 -410.756126) (xy 303.403172 -410.819222) (xy 303.372021 -410.879018) (xy 303.333932 -410.934651)
			(xy 303.312068 -410.960316) (xy 303.306278 -410.967466) (xy 303.29976 -410.984653) (xy 303.299368 -410.993844)
			(xy 303.299368 -411.151324) (xy 303.299003 -411.161452) (xy 303.291241 -411.180162) (xy 303.276909 -411.194477)
			(xy 303.258189 -411.202216) (xy 303.24806 -411.202632) (xy 302.53178 -411.202632) (xy 302.521674 -411.202132)
			(xy 302.503001 -411.194394) (xy 302.488708 -411.180102) (xy 302.480969 -411.16143) (xy 302.480472 -411.151324)
			(xy 302.480472 -410.993844) (xy 302.480047 -410.984658) (xy 302.473544 -410.967474) (xy 302.467772 -410.960316)
			(xy 302.445893 -410.934663) (xy 302.407807 -410.879026) (xy 302.376658 -410.819228) (xy 302.352896 -410.75613)
			(xy 302.336863 -410.690639) (xy 302.328789 -410.6237) (xy 299.050718 -410.6237) (xy 299.042683 -410.690461)
			(xy 299.026712 -410.755842) (xy 299.003042 -410.818846) (xy 298.972012 -410.878569) (xy 298.934066 -410.934156)
			(xy 298.91228 -410.959808) (xy 298.906495 -410.966961) (xy 298.899974 -410.984146) (xy 298.89958 -410.993336)
			(xy 298.89958 -411.151324) (xy 298.899198 -411.161482) (xy 298.891391 -411.180239) (xy 298.876982 -411.194562)
			(xy 298.858179 -411.202258) (xy 298.848018 -411.202632) (xy 298.131738 -411.202632) (xy 298.12161 -411.202141)
			(xy 298.102885 -411.194421) (xy 298.088526 -411.180135) (xy 298.080711 -411.161449) (xy 298.080176 -411.151324)
			(xy 298.080176 -410.993336) (xy 298.079754 -410.98415) (xy 298.073249 -410.966965) (xy 298.067476 -410.959808)
			(xy 298.045672 -410.934169) (xy 298.007721 -410.878582) (xy 297.976686 -410.818857) (xy 297.953013 -410.75585)
			(xy 297.93704 -410.690466) (xy 297.928996 -410.623641) (xy 294.650957 -410.623641) (xy 294.650957 -410.623699)
			(xy 294.642883 -410.690637) (xy 294.626848 -410.756125) (xy 294.603085 -410.819221) (xy 294.571935 -410.879017)
			(xy 294.533848 -410.934651) (xy 294.511984 -410.960316) (xy 294.506196 -410.967467) (xy 294.499677 -410.984653)
			(xy 294.499284 -410.993844) (xy 294.499284 -411.151324) (xy 294.498834 -411.161436) (xy 294.491086 -411.180118)
			(xy 294.476778 -411.194413) (xy 294.458089 -411.202144) (xy 294.447976 -411.202632) (xy 293.731696 -411.202632)
			(xy 293.721591 -411.202119) (xy 293.702919 -411.194386) (xy 293.688625 -411.180098) (xy 293.680885 -411.161429)
			(xy 293.680388 -411.151324) (xy 293.680388 -410.993844) (xy 293.679959 -410.984659) (xy 293.673459 -410.967474)
			(xy 293.667688 -410.960316) (xy 293.645809 -410.934664) (xy 293.607721 -410.879027) (xy 293.576572 -410.819229)
			(xy 293.552809 -410.75613) (xy 293.536775 -410.69064) (xy 293.528701 -410.6237) (xy 290.250631 -410.6237)
			(xy 290.242595 -410.69046) (xy 290.226625 -410.755841) (xy 290.202956 -410.818845) (xy 290.171926 -410.878568)
			(xy 290.133982 -410.934155) (xy 290.112196 -410.959808) (xy 290.106413 -410.966963) (xy 290.09989 -410.984146)
			(xy 290.099496 -410.993336) (xy 290.099496 -411.151324) (xy 290.099098 -411.16148) (xy 290.091294 -411.180234)
			(xy 290.07689 -411.194557) (xy 290.058092 -411.202255) (xy 290.047934 -411.202632) (xy 289.331654 -411.202632)
			(xy 289.321521 -411.20221) (xy 289.302793 -411.194462) (xy 289.288438 -411.180156) (xy 289.280625 -411.161455)
			(xy 289.280092 -411.151324) (xy 289.280092 -410.993336) (xy 289.279666 -410.98415) (xy 289.273164 -410.966966)
			(xy 289.267392 -410.959808) (xy 289.245587 -410.934169) (xy 289.207635 -410.878582) (xy 289.1766 -410.818857)
			(xy 289.152925 -410.755851) (xy 289.136952 -410.690467) (xy 289.128908 -410.623642) (xy 237.026196 -410.623642)
			(xy 237.026196 -412.022036) (xy 237.025817 -412.032111) (xy 237.018067 -412.05071) (xy 237.01121 -412.058104)
			(xy 235.742988 -413.326326) (xy 235.735589 -413.333168) (xy 235.716989 -413.340886) (xy 235.70692 -413.341312)
			(xy 208.85277 -413.341312) (xy 208.842696 -413.340925) (xy 208.824097 -413.33318) (xy 208.816702 -413.326326)
			(xy 207.328262 -411.83814) (xy 207.321442 -411.830725) (xy 207.313712 -411.812137) (xy 207.313276 -411.802072)
			(xy 207.313276 -389.778748) (xy 207.312741 -389.766404) (xy 207.303453 -389.743532) (xy 207.295242 -389.734298)
			(xy 207.294734 -389.73379) (xy 204.725778 -387.165088) (xy 204.718937 -387.157689) (xy 204.711218 -387.139089)
			(xy 204.710792 -387.12902) (xy 204.710792 -374.725946) (xy 204.710253 -374.713602) (xy 204.700967 -374.690731)
			(xy 204.692758 -374.681496) (xy 204.69225 -374.680988) (xy 204.627226 -374.615964) (xy 204.620381 -374.608567)
			(xy 204.612664 -374.589966) (xy 204.61224 -374.579896) (xy 204.61224 -371.090444) (xy 204.611612 -371.07799)
			(xy 204.602074 -371.054978) (xy 204.593698 -371.04574) (xy 204.485494 -370.93779) (xy 204.478656 -370.930388)
			(xy 204.470935 -370.91179) (xy 204.470508 -370.901722) (xy 173.519592 -370.901722) (xy 173.519592 -371.386862)
			(xy 173.520022 -371.396047) (xy 173.526522 -371.413231) (xy 173.532292 -371.42039) (xy 173.554093 -371.446031)
			(xy 173.592039 -371.50162) (xy 173.62307 -371.561345) (xy 173.646506 -371.623725) (xy 174.74915 -371.623725)
			(xy 174.749154 -371.556417) (xy 174.757201 -371.489592) (xy 174.773178 -371.424208) (xy 174.796855 -371.361202)
			(xy 174.827893 -371.301477) (xy 174.865846 -371.24589) (xy 174.887636 -371.220238) (xy 174.893446 -371.213102)
			(xy 174.899952 -371.195904) (xy 174.900336 -371.18671) (xy 174.900336 -371.028722) (xy 174.900782 -371.018552)
			(xy 174.908559 -370.999758) (xy 174.922938 -370.985373) (xy 174.941728 -370.977587) (xy 174.951898 -370.97716)
			(xy 175.668178 -370.97716) (xy 175.678351 -370.977583) (xy 175.697149 -370.985364) (xy 175.711536 -370.999751)
			(xy 175.719317 -371.018549) (xy 175.71974 -371.028722) (xy 175.71974 -371.18671) (xy 175.720159 -371.195896)
			(xy 175.726668 -371.21308) (xy 175.73244 -371.220238) (xy 175.754191 -371.245921) (xy 175.792142 -371.301502)
			(xy 175.823178 -371.361221) (xy 175.846854 -371.424222) (xy 175.86283 -371.489601) (xy 175.870878 -371.55642)
			(xy 175.870881 -371.623723) (xy 175.862841 -371.690543) (xy 175.846871 -371.755923) (xy 175.823202 -371.818926)
			(xy 175.792172 -371.878649) (xy 175.754226 -371.934234) (xy 175.73244 -371.959886) (xy 175.726617 -371.967012)
			(xy 175.72012 -371.984218) (xy 175.71974 -371.993414) (xy 175.71974 -372.486682) (xy 175.720172 -372.495867)
			(xy 175.726672 -372.51305) (xy 175.73244 -372.52021) (xy 175.754262 -372.545834) (xy 175.792211 -372.601424)
			(xy 175.823244 -372.661151) (xy 175.846916 -372.72416) (xy 175.862887 -372.789545) (xy 175.870929 -372.856371)
			(xy 175.870926 -372.92368) (xy 175.862878 -372.990505) (xy 175.846901 -373.055889) (xy 175.823223 -373.118895)
			(xy 175.792185 -373.17862) (xy 175.754231 -373.234206) (xy 175.73244 -373.259858) (xy 175.726629 -373.266993)
			(xy 175.720125 -373.284191) (xy 175.71974 -373.293386) (xy 175.71974 -373.451374) (xy 175.719314 -373.461547)
			(xy 175.711534 -373.480345) (xy 175.697148 -373.494731) (xy 175.678351 -373.502513) (xy 175.668178 -373.502936)
			(xy 174.951898 -373.502936) (xy 174.941723 -373.502537) (xy 174.922923 -373.494747) (xy 174.908538 -373.480353)
			(xy 174.900757 -373.461549) (xy 174.900336 -373.451374) (xy 174.900336 -373.293386) (xy 174.899925 -373.284199)
			(xy 174.893411 -373.267015) (xy 174.887636 -373.259858) (xy 174.865882 -373.234178) (xy 174.827932 -373.178596)
			(xy 174.796898 -373.118876) (xy 174.773223 -373.055875) (xy 174.757248 -372.990496) (xy 174.749201 -372.923677)
			(xy 174.749198 -372.856374) (xy 174.757239 -372.789554) (xy 174.773208 -372.724174) (xy 174.796877 -372.661171)
			(xy 174.827906 -372.601448) (xy 174.865851 -372.545862) (xy 174.887636 -372.52021) (xy 174.893458 -372.513083)
			(xy 174.899957 -372.495878) (xy 174.900336 -372.486682) (xy 174.900336 -371.993414) (xy 174.899911 -371.984229)
			(xy 174.893407 -371.967044) (xy 174.887636 -371.959886) (xy 174.865811 -371.934265) (xy 174.827863 -371.878674)
			(xy 174.796832 -371.818946) (xy 174.773161 -371.755937) (xy 174.757191 -371.690551) (xy 174.74915 -371.623725)
			(xy 173.646506 -371.623725) (xy 173.646741 -371.624351) (xy 173.662712 -371.689734) (xy 173.670754 -371.756558)
			(xy 173.670753 -371.823863) (xy 173.662708 -371.890686) (xy 173.646734 -371.956069) (xy 173.623061 -372.019074)
			(xy 173.592028 -372.078798) (xy 173.55408 -372.134385) (xy 173.532292 -372.160038) (xy 173.526496 -372.167183)
			(xy 173.519981 -372.184374) (xy 173.519592 -372.193566) (xy 173.519592 -372.351554) (xy 173.519099 -372.361719)
			(xy 173.511335 -372.380507) (xy 173.496971 -372.394892) (xy 173.478194 -372.402684) (xy 173.46803 -372.403116)
			(xy 172.75175 -372.403116) (xy 172.741576 -372.402694) (xy 172.722773 -372.394917) (xy 172.708385 -372.38053)
			(xy 172.700607 -372.361728) (xy 172.700188 -372.351554) (xy 172.700188 -372.193566) (xy 172.699797 -372.184377)
			(xy 172.69327 -372.167192) (xy 172.687488 -372.160038) (xy 172.665713 -372.134375) (xy 172.62776 -372.078791)
			(xy 172.596724 -372.01907) (xy 172.573048 -371.956067) (xy 172.557072 -371.890685) (xy 172.549026 -371.823863)
			(xy 172.549025 -371.756558) (xy 172.557069 -371.689736) (xy 172.573042 -371.624354) (xy 172.596715 -371.561349)
			(xy 172.627749 -371.501627) (xy 172.6657 -371.446041) (xy 172.687488 -371.42039) (xy 172.69327 -371.413234)
			(xy 172.699794 -371.396052) (xy 172.700188 -371.386862) (xy 172.700188 -370.89334) (xy 172.699761 -370.884154)
			(xy 172.69326 -370.86697) (xy 172.687488 -370.859812) (xy 172.665687 -370.83417) (xy 172.627735 -370.778583)
			(xy 172.5967 -370.718859) (xy 172.573026 -370.655853) (xy 172.557052 -370.590469) (xy 172.549008 -370.523644)
			(xy 169.270946 -370.523644) (xy 169.262904 -370.590464) (xy 169.246933 -370.655845) (xy 169.223264 -370.718849)
			(xy 169.192234 -370.778572) (xy 169.15429 -370.834159) (xy 169.132504 -370.859812) (xy 169.12672 -370.866966)
			(xy 169.120198 -370.88415) (xy 169.119804 -370.89334) (xy 169.119804 -371.386862) (xy 169.120231 -371.396047)
			(xy 169.126733 -371.413232) (xy 169.132504 -371.42039) (xy 169.154304 -371.446031) (xy 169.19225 -371.50162)
			(xy 169.22328 -371.561346) (xy 169.246737 -371.623785) (xy 170.348831 -371.623785) (xy 170.348834 -371.556358)
			(xy 170.356914 -371.489416) (xy 170.372955 -371.423924) (xy 170.396726 -371.360825) (xy 170.427884 -371.301029)
			(xy 170.46598 -371.245394) (xy 170.487848 -371.21973) (xy 170.493663 -371.212598) (xy 170.500165 -371.195397)
			(xy 170.500548 -371.186202) (xy 170.500548 -371.028722) (xy 170.501045 -371.018596) (xy 170.508767 -370.999873)
			(xy 170.52305 -370.985516) (xy 170.541732 -370.977698) (xy 170.551856 -370.97716) (xy 171.268136 -370.97716)
			(xy 171.278287 -370.977591) (xy 171.297033 -370.985391) (xy 171.311354 -370.999784) (xy 171.319059 -371.018568)
			(xy 171.319444 -371.028722) (xy 171.319444 -371.186202) (xy 171.319866 -371.195388) (xy 171.326373 -371.212571)
			(xy 171.332144 -371.21973) (xy 171.353973 -371.245425) (xy 171.392066 -371.301054) (xy 171.423222 -371.360846)
			(xy 171.44699 -371.423939) (xy 171.46303 -371.489425) (xy 171.47111 -371.556361) (xy 171.471113 -371.623782)
			(xy 171.46304 -371.690719) (xy 171.447007 -371.756207) (xy 171.423245 -371.819302) (xy 171.392096 -371.879097)
			(xy 171.354008 -371.93473) (xy 171.332144 -371.960394) (xy 171.326361 -371.967548) (xy 171.31984 -371.984732)
			(xy 171.319444 -371.993922) (xy 171.319444 -372.486174) (xy 171.319879 -372.495358) (xy 171.326377 -372.512542)
			(xy 171.332144 -372.519702) (xy 171.354043 -372.545339) (xy 171.392135 -372.600976) (xy 171.423287 -372.660776)
			(xy 171.447052 -372.723876) (xy 171.463087 -372.789369) (xy 171.471161 -372.856312) (xy 171.471158 -372.923739)
			(xy 171.463077 -372.990681) (xy 171.447037 -373.056172) (xy 171.423266 -373.119271) (xy 171.392108 -373.179068)
			(xy 171.354012 -373.234702) (xy 171.332144 -373.260366) (xy 171.32633 -373.267499) (xy 171.319827 -373.284699)
			(xy 171.319444 -373.293894) (xy 171.319444 -373.451374) (xy 171.318952 -373.461501) (xy 171.31123 -373.480225)
			(xy 171.296945 -373.494583) (xy 171.27826 -373.5024) (xy 171.268136 -373.502936) (xy 170.551856 -373.502936)
			(xy 170.541704 -373.502515) (xy 170.522957 -373.494712) (xy 170.508637 -373.480316) (xy 170.500932 -373.461529)
			(xy 170.500548 -373.451374) (xy 170.500548 -373.293894) (xy 170.50013 -373.284708) (xy 170.493621 -373.267524)
			(xy 170.487848 -373.260366) (xy 170.466016 -373.234674) (xy 170.427923 -373.179044) (xy 170.396768 -373.119252)
			(xy 170.373 -373.056159) (xy 170.356961 -372.990673) (xy 170.348881 -372.923736) (xy 170.348878 -372.856315)
			(xy 170.356951 -372.789378) (xy 170.372985 -372.72389) (xy 170.396747 -372.660794) (xy 170.427897 -372.600999)
			(xy 170.465984 -372.545366) (xy 170.487848 -372.519702) (xy 170.493632 -372.512548) (xy 170.500153 -372.495364)
			(xy 170.500548 -372.486174) (xy 170.500548 -371.993922) (xy 170.500117 -371.984737) (xy 170.493617 -371.967553)
			(xy 170.487848 -371.960394) (xy 170.465945 -371.93476) (xy 170.427854 -371.879122) (xy 170.396703 -371.819322)
			(xy 170.372938 -371.756221) (xy 170.356904 -371.690728) (xy 170.348831 -371.623785) (xy 169.246737 -371.623785)
			(xy 169.24695 -371.624352) (xy 169.262921 -371.689735) (xy 169.270963 -371.756558) (xy 169.270962 -371.823863)
			(xy 169.262917 -371.890686) (xy 169.246944 -371.956068) (xy 169.223271 -372.019073) (xy 169.192239 -372.078798)
			(xy 169.154291 -372.134385) (xy 169.132504 -372.160038) (xy 169.126709 -372.167185) (xy 169.120193 -372.184374)
			(xy 169.119804 -372.193566) (xy 169.119804 -372.351554) (xy 169.1193 -372.361717) (xy 169.111537 -372.380503)
			(xy 169.097177 -372.394888) (xy 169.078405 -372.402682) (xy 169.068242 -372.403116) (xy 168.351962 -372.403116)
			(xy 168.341782 -372.402766) (xy 168.322978 -372.39496) (xy 168.308593 -372.380552) (xy 168.300817 -372.361734)
			(xy 168.3004 -372.351554) (xy 168.3004 -372.193566) (xy 168.300006 -372.184377) (xy 168.293481 -372.167193)
			(xy 168.2877 -372.160038) (xy 168.265927 -372.134374) (xy 168.227981 -372.078788) (xy 168.196949 -372.019066)
			(xy 168.173277 -371.956063) (xy 168.157304 -371.890683) (xy 168.14926 -371.823862) (xy 168.149258 -371.756559)
			(xy 168.1573 -371.689738) (xy 168.173271 -371.624357) (xy 168.19694 -371.561353) (xy 168.22797 -371.50163)
			(xy 168.265914 -371.446043) (xy 168.2877 -371.42039) (xy 168.293483 -371.413235) (xy 168.300006 -371.396052)
			(xy 168.3004 -371.386862) (xy 168.3004 -370.89334) (xy 168.299971 -370.884155) (xy 168.29347 -370.86697)
			(xy 168.2877 -370.859812) (xy 168.265902 -370.834169) (xy 168.227956 -370.77858) (xy 168.196925 -370.718855)
			(xy 168.173255 -370.65585) (xy 168.157284 -370.590467) (xy 168.149241 -370.523644) (xy 164.871178 -370.523644)
			(xy 164.871178 -370.523702) (xy 164.863103 -370.59064) (xy 164.847069 -370.656128) (xy 164.823307 -370.719224)
			(xy 164.792158 -370.77902) (xy 164.754071 -370.834655) (xy 164.732208 -370.86032) (xy 164.726421 -370.867472)
			(xy 164.7199 -370.884657) (xy 164.719508 -370.893848) (xy 164.719508 -371.386354) (xy 164.719938 -371.395539)
			(xy 164.726438 -371.412724) (xy 164.732208 -371.419882) (xy 164.754085 -371.445536) (xy 164.792173 -371.501172)
			(xy 164.823323 -371.56097) (xy 164.846957 -371.623726) (xy 165.949062 -371.623726) (xy 165.949066 -371.556417)
			(xy 165.957114 -371.489592) (xy 165.973091 -371.424207) (xy 165.996769 -371.361201) (xy 166.027807 -371.301477)
			(xy 166.065761 -371.24589) (xy 166.087552 -371.220238) (xy 166.093364 -371.213104) (xy 166.099868 -371.195905)
			(xy 166.100252 -371.18671) (xy 166.100252 -371.028722) (xy 166.100682 -371.01855) (xy 166.108463 -370.999753)
			(xy 166.122847 -370.985367) (xy 166.141642 -370.977584) (xy 166.151814 -370.97716) (xy 166.868094 -370.97716)
			(xy 166.878268 -370.977569) (xy 166.897067 -370.985356) (xy 166.911453 -370.999747) (xy 166.919234 -371.018548)
			(xy 166.919656 -371.028722) (xy 166.919656 -371.18671) (xy 166.920071 -371.195896) (xy 166.926582 -371.21308)
			(xy 166.932356 -371.220238) (xy 166.954106 -371.245921) (xy 166.992057 -371.301503) (xy 167.023092 -371.361222)
			(xy 167.046767 -371.424223) (xy 167.062743 -371.489601) (xy 167.07079 -371.55642) (xy 167.070793 -371.623722)
			(xy 167.062753 -371.690543) (xy 167.046784 -371.755923) (xy 167.023115 -371.818926) (xy 166.992086 -371.878648)
			(xy 166.954141 -371.934234) (xy 166.932356 -371.959886) (xy 166.926535 -371.967014) (xy 166.920036 -371.984218)
			(xy 166.919656 -371.993414) (xy 166.919656 -372.486682) (xy 166.920085 -372.495867) (xy 166.926586 -372.513051)
			(xy 166.932356 -372.52021) (xy 166.954177 -372.545834) (xy 166.992126 -372.601425) (xy 167.023158 -372.661152)
			(xy 167.046829 -372.72416) (xy 167.0628 -372.789546) (xy 167.070841 -372.856372) (xy 167.070838 -372.923679)
			(xy 167.06279 -372.990504) (xy 167.046814 -373.055889) (xy 167.023137 -373.118895) (xy 166.992099 -373.178619)
			(xy 166.954146 -373.234206) (xy 166.932356 -373.259858) (xy 166.926547 -373.266994) (xy 166.920041 -373.284192)
			(xy 166.919656 -373.293386) (xy 166.919656 -373.451374) (xy 166.919215 -373.461545) (xy 166.911437 -373.48034)
			(xy 166.897057 -373.494726) (xy 166.878264 -373.502511) (xy 166.868094 -373.502936) (xy 166.151814 -373.502936)
			(xy 166.14164 -373.502524) (xy 166.122841 -373.494739) (xy 166.108454 -373.480349) (xy 166.100673 -373.461548)
			(xy 166.100252 -373.451374) (xy 166.100252 -373.293386) (xy 166.099837 -373.2842) (xy 166.093325 -373.267016)
			(xy 166.087552 -373.259858) (xy 166.065797 -373.234178) (xy 166.027847 -373.178596) (xy 165.996811 -373.118877)
			(xy 165.973136 -373.055876) (xy 165.95716 -372.990497) (xy 165.949113 -372.923677) (xy 165.94911 -372.856374)
			(xy 165.957151 -372.789554) (xy 165.973121 -372.724173) (xy 165.99679 -372.66117) (xy 166.02782 -372.601448)
			(xy 166.065766 -372.545862) (xy 166.087552 -372.52021) (xy 166.093376 -372.513084) (xy 166.099873 -372.495879)
			(xy 166.100252 -372.486682) (xy 166.100252 -371.993414) (xy 166.099824 -371.984229) (xy 166.093321 -371.967045)
			(xy 166.087552 -371.959886) (xy 166.065726 -371.934265) (xy 166.027778 -371.878674) (xy 165.996745 -371.818947)
			(xy 165.973074 -371.755938) (xy 165.957104 -371.690552) (xy 165.949062 -371.623726) (xy 164.846957 -371.623726)
			(xy 164.847086 -371.624068) (xy 164.86312 -371.689559) (xy 164.871195 -371.756498) (xy 164.871194 -371.823923)
			(xy 164.863116 -371.890862) (xy 164.84708 -371.956352) (xy 164.823314 -372.019449) (xy 164.792162 -372.079246)
			(xy 164.754073 -372.134881) (xy 164.732208 -372.160546) (xy 164.72641 -372.16769) (xy 164.719896 -372.184881)
			(xy 164.719508 -372.194074) (xy 164.719508 -372.351554) (xy 164.718937 -372.361672) (xy 164.711233 -372.380383)
			(xy 164.696973 -372.394739) (xy 164.678314 -372.402568) (xy 164.6682 -372.403116) (xy 163.95192 -372.403116)
			(xy 163.941769 -372.402662) (xy 163.92302 -372.394876) (xy 163.908697 -372.38049) (xy 163.900993 -372.361707)
			(xy 163.900612 -372.351554) (xy 163.900612 -372.194074) (xy 163.900212 -372.184886) (xy 163.893691 -372.167702)
			(xy 163.887912 -372.160546) (xy 163.866061 -372.13487) (xy 163.827971 -372.079237) (xy 163.796819 -372.019442)
			(xy 163.773054 -371.956347) (xy 163.757017 -371.890859) (xy 163.74894 -371.823922) (xy 163.748939 -371.756499)
			(xy 163.757013 -371.689562) (xy 163.773048 -371.624073) (xy 163.796811 -371.560977) (xy 163.827961 -371.501181)
			(xy 163.866048 -371.445547) (xy 163.887912 -371.419882) (xy 163.8937 -371.412731) (xy 163.900219 -371.395545)
			(xy 163.900612 -371.386354) (xy 163.900612 -370.893848) (xy 163.900176 -370.884664) (xy 163.89368 -370.867479)
			(xy 163.887912 -370.86032) (xy 163.866036 -370.834665) (xy 163.827947 -370.779029) (xy 163.796796 -370.719232)
			(xy 163.773032 -370.656133) (xy 163.756997 -370.590643) (xy 163.748922 -370.523703) (xy 160.470875 -370.523703)
			(xy 160.462839 -370.590466) (xy 160.446866 -370.655848) (xy 160.423192 -370.718852) (xy 160.392158 -370.778575)
			(xy 160.354208 -370.83416) (xy 160.33242 -370.859812) (xy 160.326638 -370.866968) (xy 160.320114 -370.88415)
			(xy 160.31972 -370.89334) (xy 160.31972 -371.386862) (xy 160.320144 -371.396048) (xy 160.326647 -371.413233)
			(xy 160.33242 -371.42039) (xy 160.354223 -371.44603) (xy 160.392174 -371.501618) (xy 160.423209 -371.561342)
			(xy 160.44667 -371.623784) (xy 161.548767 -371.623784) (xy 161.548771 -371.556358) (xy 161.55685 -371.489418)
			(xy 161.572888 -371.423928) (xy 161.596655 -371.360829) (xy 161.627808 -371.301032) (xy 161.665899 -371.245396)
			(xy 161.687764 -371.21973) (xy 161.693581 -371.212599) (xy 161.700082 -371.195397) (xy 161.700464 -371.186202)
			(xy 161.700464 -371.028722) (xy 161.700945 -371.018594) (xy 161.70867 -370.999868) (xy 161.722959 -370.985511)
			(xy 161.741646 -370.977695) (xy 161.751772 -370.97716) (xy 162.468052 -370.97716) (xy 162.478166 -370.977654)
			(xy 162.496861 -370.985379) (xy 162.511176 -370.999671) (xy 162.51893 -371.018354) (xy 162.51936 -371.028468)
			(xy 162.51936 -371.186202) (xy 162.519778 -371.195388) (xy 162.526287 -371.212572) (xy 162.53206 -371.21973)
			(xy 162.553888 -371.245425) (xy 162.591981 -371.301055) (xy 162.623135 -371.360846) (xy 162.646903 -371.423939)
			(xy 162.662942 -371.489425) (xy 162.671022 -371.556361) (xy 162.671025 -371.623782) (xy 162.662953 -371.690719)
			(xy 162.64692 -371.756206) (xy 162.623158 -371.819302) (xy 162.59201 -371.879096) (xy 162.553923 -371.934729)
			(xy 162.53206 -371.960394) (xy 162.526278 -371.96755) (xy 162.519756 -371.984732) (xy 162.51936 -371.993922)
			(xy 162.51936 -372.486174) (xy 162.519791 -372.495359) (xy 162.526291 -372.512543) (xy 162.53206 -372.519702)
			(xy 162.553959 -372.545339) (xy 162.592049 -372.600977) (xy 162.623201 -372.660776) (xy 162.646965 -372.723877)
			(xy 162.662999 -372.78937) (xy 162.671073 -372.856312) (xy 162.67107 -372.923739) (xy 162.66299 -372.99068)
			(xy 162.646949 -373.056172) (xy 162.62318 -373.11927) (xy 162.592023 -373.179067) (xy 162.553927 -373.234701)
			(xy 162.53206 -373.260366) (xy 162.526248 -373.2675) (xy 162.519743 -373.284699) (xy 162.51936 -373.293894)
			(xy 162.51936 -373.451374) (xy 162.518852 -373.461499) (xy 162.511133 -373.48022) (xy 162.496853 -373.494577)
			(xy 162.478174 -373.502397) (xy 162.468052 -373.502936) (xy 161.751772 -373.502936) (xy 161.741666 -373.502439)
			(xy 161.722994 -373.494699) (xy 161.708701 -373.480406) (xy 161.700961 -373.461734) (xy 161.700464 -373.451628)
			(xy 161.700464 -373.293894) (xy 161.700042 -373.284708) (xy 161.693535 -373.267525) (xy 161.687764 -373.260366)
			(xy 161.665935 -373.234673) (xy 161.627847 -373.179041) (xy 161.596697 -373.119249) (xy 161.572933 -373.056155)
			(xy 161.556896 -372.99067) (xy 161.548818 -372.923736) (xy 161.548815 -372.856315) (xy 161.556887 -372.78938)
			(xy 161.572918 -372.723893) (xy 161.596676 -372.660798) (xy 161.627821 -372.601003) (xy 161.665903 -372.545368)
			(xy 161.687764 -372.519702) (xy 161.69355 -372.51255) (xy 161.700069 -372.495364) (xy 161.700464 -372.486174)
			(xy 161.700464 -371.993922) (xy 161.700029 -371.984738) (xy 161.693531 -371.967554) (xy 161.687764 -371.960394)
			(xy 161.665864 -371.934759) (xy 161.627779 -371.879119) (xy 161.596632 -371.819319) (xy 161.572871 -371.756218)
			(xy 161.55684 -371.690725) (xy 161.548767 -371.623784) (xy 160.44667 -371.623784) (xy 160.446882 -371.624348)
			(xy 160.462856 -371.689733) (xy 160.470899 -371.756557) (xy 160.470898 -371.823864) (xy 160.462852 -371.890688)
			(xy 160.446876 -371.956072) (xy 160.4232 -372.019077) (xy 160.392163 -372.078801) (xy 160.35421 -372.134386)
			(xy 160.33242 -372.160038) (xy 160.326627 -372.167186) (xy 160.32011 -372.184374) (xy 160.31972 -372.193566)
			(xy 160.31972 -372.351554) (xy 160.319297 -372.361728) (xy 160.31152 -372.38053) (xy 160.297133 -372.394918)
			(xy 160.278332 -372.402697) (xy 160.268158 -372.403116) (xy 159.551878 -372.403116) (xy 159.541699 -372.402753)
			(xy 159.522895 -372.394952) (xy 159.50851 -372.380547) (xy 159.500734 -372.361733) (xy 159.500316 -372.351554)
			(xy 159.500316 -372.193566) (xy 159.499919 -372.184378) (xy 159.493396 -372.167193) (xy 159.487616 -372.160038)
			(xy 159.465843 -372.134374) (xy 159.427895 -372.078789) (xy 159.396862 -372.019067) (xy 159.37319 -371.956064)
			(xy 159.357216 -371.890683) (xy 159.349172 -371.823862) (xy 159.34917 -371.756559) (xy 159.357213 -371.689738)
			(xy 159.373184 -371.624356) (xy 159.396854 -371.561353) (xy 159.427884 -371.501629) (xy 159.46583 -371.446042)
			(xy 159.487616 -371.42039) (xy 159.493401 -371.413237) (xy 159.499922 -371.396052) (xy 159.500316 -371.386862)
			(xy 159.500316 -370.89334) (xy 159.499883 -370.884155) (xy 159.493385 -370.866971) (xy 159.487616 -370.859812)
			(xy 159.465817 -370.834169) (xy 159.42787 -370.778581) (xy 159.396839 -370.718856) (xy 159.373168 -370.65585)
			(xy 159.357196 -370.590467) (xy 159.349153 -370.523644) (xy 129.670828 -370.523644) (xy 129.662785 -370.590464)
			(xy 129.646814 -370.655846) (xy 129.623143 -370.71885) (xy 129.592113 -370.778573) (xy 129.554166 -370.83416)
			(xy 129.53238 -370.859812) (xy 129.526594 -370.866964) (xy 129.520073 -370.884149) (xy 129.51968 -370.89334)
			(xy 129.51968 -371.386862) (xy 129.520113 -371.396047) (xy 129.526611 -371.413231) (xy 129.53238 -371.42039)
			(xy 129.554181 -371.446031) (xy 129.592128 -371.50162) (xy 129.62316 -371.561345) (xy 129.646596 -371.623725)
			(xy 130.749241 -371.623725) (xy 130.749245 -371.556418) (xy 130.757292 -371.489593) (xy 130.773269 -371.424208)
			(xy 130.796945 -371.361202) (xy 130.827982 -371.301478) (xy 130.865934 -371.24589) (xy 130.887724 -371.220238)
			(xy 130.893532 -371.213101) (xy 130.900039 -371.195904) (xy 130.900424 -371.18671) (xy 130.900424 -371.028722)
			(xy 130.900882 -371.018554) (xy 130.908657 -370.999762) (xy 130.923032 -370.985377) (xy 130.941818 -370.977589)
			(xy 130.951986 -370.97716) (xy 131.668266 -370.97716) (xy 131.678438 -370.977592) (xy 131.697236 -370.98537)
			(xy 131.711623 -370.999754) (xy 131.719405 -371.01855) (xy 131.719828 -371.028722) (xy 131.719828 -371.18671)
			(xy 131.720227 -371.195898) (xy 131.726748 -371.213083) (xy 131.732528 -371.220238) (xy 131.754279 -371.24592)
			(xy 131.792231 -371.301502) (xy 131.823268 -371.361221) (xy 131.846945 -371.424221) (xy 131.862921 -371.4896)
			(xy 131.870969 -371.55642) (xy 131.870972 -371.623723) (xy 131.862931 -371.690543) (xy 131.846961 -371.755924)
			(xy 131.823291 -371.818927) (xy 131.792261 -371.878649) (xy 131.754314 -371.934234) (xy 131.732528 -371.959886)
			(xy 131.726704 -371.967011) (xy 131.720208 -371.984217) (xy 131.719828 -371.993414) (xy 131.719828 -372.486682)
			(xy 131.72024 -372.495869) (xy 131.726752 -372.513054) (xy 131.732528 -372.52021) (xy 131.75435 -372.545834)
			(xy 131.7923 -372.601424) (xy 131.823334 -372.661151) (xy 131.847006 -372.724159) (xy 131.862978 -372.789545)
			(xy 131.87102 -372.856371) (xy 131.871017 -372.92368) (xy 131.862969 -372.990505) (xy 131.846991 -373.05589)
			(xy 131.823313 -373.118896) (xy 131.792274 -373.17862) (xy 131.754319 -373.234206) (xy 131.732528 -373.259858)
			(xy 131.726716 -373.266992) (xy 131.720212 -373.284191) (xy 131.719828 -373.293386) (xy 131.719828 -373.451374)
			(xy 131.719414 -373.461548) (xy 131.711631 -373.480349) (xy 131.697242 -373.494736) (xy 131.67844 -373.502515)
			(xy 131.668266 -373.502936) (xy 130.951986 -373.502936) (xy 130.94181 -373.502547) (xy 130.92301 -373.494752)
			(xy 130.908625 -373.480356) (xy 130.900845 -373.46155) (xy 130.900424 -373.451374) (xy 130.900424 -373.293386)
			(xy 130.900015 -373.284199) (xy 130.8935 -373.267015) (xy 130.887724 -373.259858) (xy 130.86597 -373.234178)
			(xy 130.828022 -373.178595) (xy 130.796988 -373.118875) (xy 130.773314 -373.055874) (xy 130.757339 -372.990496)
			(xy 130.749292 -372.923677) (xy 130.749289 -372.856375) (xy 130.75733 -372.789555) (xy 130.773299 -372.724174)
			(xy 130.796967 -372.661171) (xy 130.827995 -372.601449) (xy 130.865939 -372.545863) (xy 130.887724 -372.52021)
			(xy 130.893544 -372.513082) (xy 130.900044 -372.495878) (xy 130.900424 -372.486682) (xy 130.900424 -371.993414)
			(xy 130.900002 -371.984228) (xy 130.893496 -371.967044) (xy 130.887724 -371.959886) (xy 130.865899 -371.934264)
			(xy 130.827953 -371.878673) (xy 130.796922 -371.818945) (xy 130.773252 -371.755937) (xy 130.757282 -371.690551)
			(xy 130.749241 -371.623725) (xy 129.646596 -371.623725) (xy 129.646831 -371.624351) (xy 129.662802 -371.689734)
			(xy 129.670845 -371.756558) (xy 129.670844 -371.823863) (xy 129.662799 -371.890687) (xy 129.646825 -371.956069)
			(xy 129.623151 -372.019074) (xy 129.592117 -372.078799) (xy 129.554168 -372.134386) (xy 129.53238 -372.160038)
			(xy 129.526582 -372.167182) (xy 129.520069 -372.184374) (xy 129.51968 -372.193566) (xy 129.51968 -372.351554)
			(xy 129.519199 -372.36172) (xy 129.511432 -372.380511) (xy 129.497064 -372.394896) (xy 129.478284 -372.402686)
			(xy 129.468118 -372.403116) (xy 128.751838 -372.403116) (xy 128.741663 -372.402704) (xy 128.722861 -372.394923)
			(xy 128.708473 -372.380533) (xy 128.700695 -372.361729) (xy 128.700276 -372.351554) (xy 128.700276 -372.193566)
			(xy 128.699887 -372.184376) (xy 128.693359 -372.167192) (xy 128.687576 -372.160038) (xy 128.665801 -372.134375)
			(xy 128.627849 -372.078791) (xy 128.596813 -372.019069) (xy 128.573138 -371.956066) (xy 128.557163 -371.890685)
			(xy 128.549117 -371.823863) (xy 128.549116 -371.756558) (xy 128.557159 -371.689736) (xy 128.573132 -371.624354)
			(xy 128.596805 -371.56135) (xy 128.627838 -371.501627) (xy 128.665788 -371.446042) (xy 128.687576 -371.42039)
			(xy 128.693357 -371.413233) (xy 128.699882 -371.396052) (xy 128.700276 -371.386862) (xy 128.700276 -370.89334)
			(xy 128.699852 -370.884154) (xy 128.693349 -370.866969) (xy 128.687576 -370.859812) (xy 128.665775 -370.83417)
			(xy 128.627825 -370.778583) (xy 128.59679 -370.718858) (xy 128.573116 -370.655852) (xy 128.557143 -370.590469)
			(xy 128.549099 -370.523644) (xy 125.271037 -370.523644) (xy 125.262994 -370.590464) (xy 125.247024 -370.655845)
			(xy 125.223354 -370.718849) (xy 125.192323 -370.778573) (xy 125.154378 -370.834159) (xy 125.132592 -370.859812)
			(xy 125.126807 -370.866965) (xy 125.120286 -370.88415) (xy 125.119892 -370.89334) (xy 125.119892 -371.386862)
			(xy 125.120322 -371.396047) (xy 125.126822 -371.413231) (xy 125.132592 -371.42039) (xy 125.154393 -371.446031)
			(xy 125.192339 -371.50162) (xy 125.22337 -371.561345) (xy 125.246828 -371.623785) (xy 126.348921 -371.623785)
			(xy 126.348925 -371.556358) (xy 126.357005 -371.489416) (xy 126.373046 -371.423925) (xy 126.396816 -371.360826)
			(xy 126.427973 -371.301029) (xy 126.466069 -371.245395) (xy 126.487936 -371.21973) (xy 126.493749 -371.212597)
			(xy 126.500253 -371.195397) (xy 126.500636 -371.186202) (xy 126.500636 -371.028722) (xy 126.501144 -371.018597)
			(xy 126.508864 -370.999877) (xy 126.523144 -370.98552) (xy 126.541822 -370.9777) (xy 126.551944 -370.97716)
			(xy 127.268224 -370.97716) (xy 127.278375 -370.977601) (xy 127.29712 -370.985397) (xy 127.311441 -370.999787)
			(xy 127.319147 -371.018569) (xy 127.319532 -371.028722) (xy 127.319532 -371.186202) (xy 127.319956 -371.195387)
			(xy 127.326462 -371.212571) (xy 127.332232 -371.21973) (xy 127.354058 -371.245427) (xy 127.392145 -371.301057)
			(xy 127.423296 -371.36085) (xy 127.447061 -371.423942) (xy 127.463098 -371.489427) (xy 127.471176 -371.556361)
			(xy 127.47118 -371.623781) (xy 127.463108 -371.690717) (xy 127.447078 -371.756203) (xy 127.423319 -371.819298)
			(xy 127.392175 -371.879094) (xy 127.354093 -371.934728) (xy 127.332232 -371.960394) (xy 127.326447 -371.967547)
			(xy 127.319927 -371.984732) (xy 127.319532 -371.993922) (xy 127.319532 -372.486174) (xy 127.31997 -372.495358)
			(xy 127.326466 -372.512542) (xy 127.332232 -372.519702) (xy 127.354128 -372.54534) (xy 127.392214 -372.600979)
			(xy 127.423361 -372.66078) (xy 127.447122 -372.72388) (xy 127.463154 -372.789372) (xy 127.471227 -372.856313)
			(xy 127.471224 -372.923738) (xy 127.463145 -372.990678) (xy 127.447107 -373.056169) (xy 127.42334 -373.119267)
			(xy 127.392188 -373.179064) (xy 127.354097 -373.2347) (xy 127.332232 -373.260366) (xy 127.326417 -373.267498)
			(xy 127.319915 -373.284699) (xy 127.319532 -373.293894) (xy 127.319532 -373.451374) (xy 127.319051 -373.461503)
			(xy 127.311327 -373.480228) (xy 127.297038 -373.494587) (xy 127.27835 -373.502402) (xy 127.268224 -373.502936)
			(xy 126.551944 -373.502936) (xy 126.541797 -373.502443) (xy 126.523053 -373.494669) (xy 126.508729 -373.480294)
			(xy 126.501021 -373.461522) (xy 126.500636 -373.451374) (xy 126.500636 -373.293894) (xy 126.500221 -373.284708)
			(xy 126.49371 -373.267524) (xy 126.487936 -373.260366) (xy 126.466104 -373.234674) (xy 126.428012 -373.179044)
			(xy 126.396858 -373.119252) (xy 126.37309 -373.056158) (xy 126.357051 -372.990672) (xy 126.348972 -372.923736)
			(xy 126.348969 -372.856315) (xy 126.357042 -372.789378) (xy 126.373075 -372.72389) (xy 126.396837 -372.660795)
			(xy 126.427986 -372.601) (xy 126.466073 -372.545367) (xy 126.487936 -372.519702) (xy 126.493719 -372.512547)
			(xy 126.500241 -372.495364) (xy 126.500636 -372.486174) (xy 126.500636 -371.993922) (xy 126.500207 -371.984737)
			(xy 126.493706 -371.967553) (xy 126.487936 -371.960394) (xy 126.466033 -371.93476) (xy 126.427943 -371.879122)
			(xy 126.396792 -371.819322) (xy 126.373029 -371.756221) (xy 126.356995 -371.690727) (xy 126.348921 -371.623785)
			(xy 125.246828 -371.623785) (xy 125.247041 -371.624351) (xy 125.263012 -371.689734) (xy 125.271054 -371.756558)
			(xy 125.271053 -371.823863) (xy 125.263008 -371.890686) (xy 125.247034 -371.956069) (xy 125.223361 -372.019074)
			(xy 125.192328 -372.078798) (xy 125.15438 -372.134385) (xy 125.132592 -372.160038) (xy 125.126796 -372.167183)
			(xy 125.120281 -372.184374) (xy 125.119892 -372.193566) (xy 125.119892 -372.351554) (xy 125.119399 -372.361719)
			(xy 125.111635 -372.380507) (xy 125.097271 -372.394892) (xy 125.078494 -372.402684) (xy 125.06833 -372.403116)
			(xy 124.35205 -372.403116) (xy 124.341876 -372.402694) (xy 124.323073 -372.394917) (xy 124.308685 -372.38053)
			(xy 124.300907 -372.361728) (xy 124.300488 -372.351554) (xy 124.300488 -372.193566) (xy 124.300097 -372.184377)
			(xy 124.29357 -372.167192) (xy 124.287788 -372.160038) (xy 124.266013 -372.134375) (xy 124.22806 -372.078791)
			(xy 124.197024 -372.01907) (xy 124.173348 -371.956067) (xy 124.157372 -371.890685) (xy 124.149326 -371.823863)
			(xy 124.149325 -371.756558) (xy 124.157369 -371.689736) (xy 124.173342 -371.624354) (xy 124.197015 -371.561349)
			(xy 124.228049 -371.501627) (xy 124.266 -371.446041) (xy 124.287788 -371.42039) (xy 124.29357 -371.413234)
			(xy 124.300094 -371.396052) (xy 124.300488 -371.386862) (xy 124.300488 -370.89334) (xy 124.300061 -370.884154)
			(xy 124.29356 -370.86697) (xy 124.287788 -370.859812) (xy 124.265987 -370.83417) (xy 124.228035 -370.778583)
			(xy 124.197 -370.718859) (xy 124.173326 -370.655853) (xy 124.157352 -370.590469) (xy 124.149308 -370.523644)
			(xy 120.871269 -370.523644) (xy 120.871269 -370.523702) (xy 120.863194 -370.59064) (xy 120.847159 -370.656128)
			(xy 120.823396 -370.719225) (xy 120.792247 -370.779021) (xy 120.754159 -370.834655) (xy 120.732296 -370.86032)
			(xy 120.726508 -370.867471) (xy 120.719988 -370.884657) (xy 120.719596 -370.893848) (xy 120.719596 -371.386354)
			(xy 120.720029 -371.395539) (xy 120.726527 -371.412723) (xy 120.732296 -371.419882) (xy 120.754174 -371.445536)
			(xy 120.792262 -371.501172) (xy 120.823413 -371.56097) (xy 120.847047 -371.623725) (xy 121.949153 -371.623725)
			(xy 121.949157 -371.556417) (xy 121.957205 -371.489592) (xy 121.973182 -371.424208) (xy 121.996859 -371.361202)
			(xy 122.027896 -371.301477) (xy 122.06585 -371.24589) (xy 122.08764 -371.220238) (xy 122.09345 -371.213103)
			(xy 122.099956 -371.195904) (xy 122.10034 -371.18671) (xy 122.10034 -371.028722) (xy 122.100782 -371.018552)
			(xy 122.10856 -370.999757) (xy 122.12294 -370.985371) (xy 122.141732 -370.977586) (xy 122.151902 -370.97716)
			(xy 122.868182 -370.97716) (xy 122.878355 -370.977579) (xy 122.897154 -370.985362) (xy 122.91154 -370.99975)
			(xy 122.919322 -371.018549) (xy 122.919744 -371.028722) (xy 122.919744 -371.18671) (xy 122.920162 -371.195896)
			(xy 122.926672 -371.21308) (xy 122.932444 -371.220238) (xy 122.954195 -371.245921) (xy 122.992146 -371.301502)
			(xy 123.023182 -371.361222) (xy 123.046857 -371.424222) (xy 123.062833 -371.489601) (xy 123.070881 -371.55642)
			(xy 123.070884 -371.623723) (xy 123.062844 -371.690543) (xy 123.046874 -371.755923) (xy 123.023205 -371.818926)
			(xy 122.992175 -371.878648) (xy 122.95423 -371.934234) (xy 122.932444 -371.959886) (xy 122.926622 -371.967013)
			(xy 122.920124 -371.984218) (xy 122.919744 -371.993414) (xy 122.919744 -372.486682) (xy 122.920175 -372.495867)
			(xy 122.926676 -372.513051) (xy 122.932444 -372.52021) (xy 122.954266 -372.545834) (xy 122.992215 -372.601424)
			(xy 123.023248 -372.661152) (xy 123.046919 -372.72416) (xy 123.06289 -372.789546) (xy 123.070932 -372.856372)
			(xy 123.070929 -372.92368) (xy 123.062881 -372.990505) (xy 123.046904 -373.055889) (xy 123.023227 -373.118895)
			(xy 122.992188 -373.17862) (xy 122.954234 -373.234206) (xy 122.932444 -373.259858) (xy 122.926633 -373.266993)
			(xy 122.920129 -373.284192) (xy 122.919744 -373.293386) (xy 122.919744 -373.451374) (xy 122.919314 -373.461546)
			(xy 122.911534 -373.480344) (xy 122.89715 -373.49473) (xy 122.878354 -373.502513) (xy 122.868182 -373.502936)
			(xy 122.151902 -373.502936) (xy 122.141727 -373.502534) (xy 122.122928 -373.494745) (xy 122.108542 -373.480352)
			(xy 122.100761 -373.461549) (xy 122.10034 -373.451374) (xy 122.10034 -373.293386) (xy 122.099928 -373.284199)
			(xy 122.093415 -373.267015) (xy 122.08764 -373.259858) (xy 122.065886 -373.234178) (xy 122.027936 -373.178596)
			(xy 121.996901 -373.118876) (xy 121.973226 -373.055875) (xy 121.957251 -372.990496) (xy 121.949204 -372.923677)
			(xy 121.949201 -372.856374) (xy 121.957242 -372.789554) (xy 121.973211 -372.724174) (xy 121.99688 -372.661171)
			(xy 122.02791 -372.601448) (xy 122.065855 -372.545862) (xy 122.08764 -372.52021) (xy 122.093462 -372.513083)
			(xy 122.099961 -372.495878) (xy 122.10034 -372.486682) (xy 122.10034 -371.993414) (xy 122.099914 -371.984229)
			(xy 122.093411 -371.967045) (xy 122.08764 -371.959886) (xy 122.065815 -371.934265) (xy 122.027867 -371.878674)
			(xy 121.996835 -371.818946) (xy 121.973165 -371.755937) (xy 121.957194 -371.690551) (xy 121.949153 -371.623725)
			(xy 120.847047 -371.623725) (xy 120.847176 -371.624068) (xy 120.863211 -371.689558) (xy 120.871286 -371.756498)
			(xy 120.871284 -371.823923) (xy 120.863207 -371.890862) (xy 120.84717 -371.956352) (xy 120.823404 -372.01945)
			(xy 120.792252 -372.079246) (xy 120.754161 -372.134881) (xy 120.732296 -372.160546) (xy 120.726497 -372.167689)
			(xy 120.719984 -372.184881) (xy 120.719596 -372.194074) (xy 120.719596 -372.351554) (xy 120.719037 -372.361673)
			(xy 120.711331 -372.380387) (xy 120.697067 -372.394743) (xy 120.678404 -372.40257) (xy 120.668288 -372.403116)
			(xy 119.952008 -372.403116) (xy 119.941856 -372.402672) (xy 119.923107 -372.394882) (xy 119.908784 -372.380493)
			(xy 119.901081 -372.361707) (xy 119.9007 -372.351554) (xy 119.9007 -372.194074) (xy 119.900303 -372.184885)
			(xy 119.89378 -372.167701) (xy 119.888 -372.160546) (xy 119.86615 -372.134869) (xy 119.828061 -372.079237)
			(xy 119.796909 -372.019442) (xy 119.773144 -371.956346) (xy 119.757108 -371.890859) (xy 119.749031 -371.823922)
			(xy 119.74903 -371.756499) (xy 119.757104 -371.689562) (xy 119.773138 -371.624074) (xy 119.796901 -371.560977)
			(xy 119.82805 -371.501182) (xy 119.866137 -371.445547) (xy 119.888 -371.419882) (xy 119.893787 -371.41273)
			(xy 119.900307 -371.395545) (xy 119.9007 -371.386354) (xy 119.9007 -370.893848) (xy 119.900267 -370.884663)
			(xy 119.893769 -370.867479) (xy 119.888 -370.86032) (xy 119.866124 -370.834664) (xy 119.828036 -370.779029)
			(xy 119.796886 -370.719231) (xy 119.773122 -370.656133) (xy 119.757088 -370.590643) (xy 119.749013 -370.523703)
			(xy 116.470966 -370.523703) (xy 116.462929 -370.590466) (xy 116.446956 -370.655848) (xy 116.423282 -370.718853)
			(xy 116.392247 -370.778575) (xy 116.354297 -370.834161) (xy 116.332508 -370.859812) (xy 116.326725 -370.866967)
			(xy 116.320202 -370.88415) (xy 116.319808 -370.89334) (xy 116.319808 -371.386862) (xy 116.320235 -371.396047)
			(xy 116.326737 -371.413232) (xy 116.332508 -371.42039) (xy 116.354311 -371.44603) (xy 116.392263 -371.501617)
			(xy 116.423299 -371.561342) (xy 116.446761 -371.623785) (xy 117.548834 -371.623785) (xy 117.548837 -371.556358)
			(xy 117.556917 -371.489416) (xy 117.572959 -371.423924) (xy 117.596729 -371.360825) (xy 117.627887 -371.301028)
			(xy 117.665984 -371.245394) (xy 117.687852 -371.21973) (xy 117.693667 -371.212598) (xy 117.700169 -371.195397)
			(xy 117.700552 -371.186202) (xy 117.700552 -371.028722) (xy 117.701045 -371.018595) (xy 117.708768 -370.999872)
			(xy 117.723052 -370.985515) (xy 117.741736 -370.977697) (xy 117.75186 -370.97716) (xy 118.46814 -370.97716)
			(xy 118.478292 -370.977588) (xy 118.497037 -370.985389) (xy 118.511358 -370.999783) (xy 118.519063 -371.018568)
			(xy 118.519448 -371.028722) (xy 118.519448 -371.186202) (xy 118.519869 -371.195388) (xy 118.526376 -371.212572)
			(xy 118.532148 -371.21973) (xy 118.553976 -371.245425) (xy 118.59207 -371.301054) (xy 118.623225 -371.360846)
			(xy 118.646994 -371.423939) (xy 118.663033 -371.489425) (xy 118.671113 -371.556361) (xy 118.671116 -371.623782)
			(xy 118.663044 -371.690719) (xy 118.647011 -371.756207) (xy 118.623248 -371.819302) (xy 118.592099 -371.879097)
			(xy 118.554012 -371.93473) (xy 118.532148 -371.960394) (xy 118.526365 -371.967549) (xy 118.519844 -371.984732)
			(xy 118.519448 -371.993922) (xy 118.519448 -372.486174) (xy 118.519882 -372.495358) (xy 118.52638 -372.512542)
			(xy 118.532148 -372.519702) (xy 118.554047 -372.545339) (xy 118.592138 -372.600976) (xy 118.62329 -372.660776)
			(xy 118.647055 -372.723877) (xy 118.66309 -372.78937) (xy 118.671164 -372.856312) (xy 118.671161 -372.923739)
			(xy 118.663081 -372.990681) (xy 118.64704 -373.056172) (xy 118.62327 -373.119271) (xy 118.592112 -373.179068)
			(xy 118.554016 -373.234702) (xy 118.532148 -373.260366) (xy 118.526334 -373.267499) (xy 118.519831 -373.284699)
			(xy 118.519448 -373.293894) (xy 118.519448 -373.451374) (xy 118.518952 -373.461501) (xy 118.51123 -373.480223)
			(xy 118.496947 -373.494581) (xy 118.478264 -373.502399) (xy 118.46814 -373.502936) (xy 117.75186 -373.502936)
			(xy 117.741708 -373.502512) (xy 117.722961 -373.49471) (xy 117.708641 -373.480315) (xy 117.700936 -373.461528)
			(xy 117.700552 -373.451374) (xy 117.700552 -373.293894) (xy 117.700133 -373.284708) (xy 117.693624 -373.267524)
			(xy 117.687852 -373.260366) (xy 117.66602 -373.234674) (xy 117.627926 -373.179045) (xy 117.596771 -373.119253)
			(xy 117.573003 -373.056159) (xy 117.556964 -372.990673) (xy 117.548884 -372.923737) (xy 117.548881 -372.856315)
			(xy 117.556954 -372.789378) (xy 117.572988 -372.72389) (xy 117.596751 -372.660794) (xy 117.6279 -372.600999)
			(xy 117.665988 -372.545366) (xy 117.687852 -372.519702) (xy 117.693637 -372.512549) (xy 117.700157 -372.495364)
			(xy 117.700552 -372.486174) (xy 117.700552 -371.993922) (xy 117.70012 -371.984737) (xy 117.69362 -371.967553)
			(xy 117.687852 -371.960394) (xy 117.665949 -371.93476) (xy 117.627858 -371.879123) (xy 117.596706 -371.819323)
			(xy 117.572942 -371.756221) (xy 117.556907 -371.690728) (xy 117.548834 -371.623785) (xy 116.446761 -371.623785)
			(xy 116.446973 -371.624348) (xy 116.462946 -371.689732) (xy 116.47099 -371.756557) (xy 116.470989 -371.823864)
			(xy 116.462943 -371.890689) (xy 116.446967 -371.956072) (xy 116.42329 -372.019077) (xy 116.392252 -372.078801)
			(xy 116.354298 -372.134387) (xy 116.332508 -372.160038) (xy 116.326714 -372.167185) (xy 116.320197 -372.184374)
			(xy 116.319808 -372.193566) (xy 116.319808 -372.351554) (xy 116.31923 -372.361703) (xy 116.311479 -372.380462)
			(xy 116.29714 -372.394828) (xy 116.278394 -372.402612) (xy 116.268246 -372.403116) (xy 115.551966 -372.403116)
			(xy 115.541786 -372.402763) (xy 115.522982 -372.394958) (xy 115.508597 -372.380551) (xy 115.500821 -372.361734)
			(xy 115.500404 -372.351554) (xy 115.500404 -372.193566) (xy 115.500009 -372.184377) (xy 115.493485 -372.167193)
			(xy 115.487704 -372.160038) (xy 115.465931 -372.134374) (xy 115.427984 -372.078788) (xy 115.396952 -372.019066)
			(xy 115.37328 -371.956063) (xy 115.357307 -371.890683) (xy 115.349263 -371.823862) (xy 115.349261 -371.756559)
			(xy 115.357303 -371.689738) (xy 115.373274 -371.624357) (xy 115.396944 -371.561353) (xy 115.427973 -371.50163)
			(xy 115.465918 -371.446043) (xy 115.487704 -371.42039) (xy 115.493488 -371.413236) (xy 115.50001 -371.396052)
			(xy 115.500404 -371.386862) (xy 115.500404 -370.89334) (xy 115.499974 -370.884155) (xy 115.493474 -370.86697)
			(xy 115.487704 -370.859812) (xy 115.465906 -370.834169) (xy 115.427959 -370.77858) (xy 115.396929 -370.718855)
			(xy 115.373258 -370.65585) (xy 115.357287 -370.590467) (xy 115.349244 -370.523644) (xy 85.670941 -370.523644)
			(xy 85.670941 -370.523703) (xy 85.662866 -370.590641) (xy 85.646831 -370.65613) (xy 85.623066 -370.719226)
			(xy 85.591915 -370.779022) (xy 85.553825 -370.834655) (xy 85.53196 -370.86032) (xy 85.526167 -370.867468)
			(xy 85.519651 -370.884656) (xy 85.51926 -370.893848) (xy 85.51926 -371.386354) (xy 85.519701 -371.395538)
			(xy 85.526194 -371.412722) (xy 85.53196 -371.419882) (xy 85.553839 -371.445535) (xy 85.59193 -371.501171)
			(xy 85.623082 -371.560968) (xy 85.646742 -371.623785) (xy 86.748803 -371.623785) (xy 86.748807 -371.556358)
			(xy 86.756887 -371.489417) (xy 86.772927 -371.423926) (xy 86.796696 -371.360827) (xy 86.827851 -371.30103)
			(xy 86.865945 -371.245395) (xy 86.887812 -371.21973) (xy 86.893622 -371.212594) (xy 86.900128 -371.195397)
			(xy 86.900512 -371.186202) (xy 86.900512 -371.028722) (xy 86.901044 -371.0186) (xy 86.908759 -370.999885)
			(xy 86.923031 -370.985529) (xy 86.941701 -370.977704) (xy 86.95182 -370.97716) (xy 87.6681 -370.97716)
			(xy 87.678204 -370.977684) (xy 87.696874 -370.985414) (xy 87.711168 -370.999699) (xy 87.718909 -371.018365)
			(xy 87.719408 -371.028468) (xy 87.719408 -371.186202) (xy 87.719815 -371.195389) (xy 87.726331 -371.212574)
			(xy 87.732108 -371.21973) (xy 87.753934 -371.245426) (xy 87.792024 -371.301056) (xy 87.823176 -371.360848)
			(xy 87.846942 -371.423941) (xy 87.862979 -371.489426) (xy 87.871058 -371.556361) (xy 87.871062 -371.623782)
			(xy 87.86299 -371.690717) (xy 87.846958 -371.756204) (xy 87.823199 -371.819299) (xy 87.792053 -371.879095)
			(xy 87.753969 -371.934729) (xy 87.732108 -371.960394) (xy 87.726332 -371.967554) (xy 87.719805 -371.984733)
			(xy 87.719408 -371.993922) (xy 87.719408 -372.486174) (xy 87.719829 -372.49536) (xy 87.726335 -372.512545)
			(xy 87.732108 -372.519702) (xy 87.754005 -372.54534) (xy 87.792092 -372.600978) (xy 87.823241 -372.660779)
			(xy 87.847003 -372.723879) (xy 87.863036 -372.789371) (xy 87.871109 -372.856312) (xy 87.871106 -372.923739)
			(xy 87.863027 -372.990679) (xy 87.846988 -373.05617) (xy 87.82322 -373.119268) (xy 87.792066 -373.179065)
			(xy 87.753974 -373.234701) (xy 87.732108 -373.260366) (xy 87.726302 -373.267504) (xy 87.719793 -373.2847)
			(xy 87.719408 -373.293894) (xy 87.719408 -373.451374) (xy 87.718854 -373.461493) (xy 87.711143 -373.480205)
			(xy 87.696878 -373.49456) (xy 87.678216 -373.502389) (xy 87.6681 -373.502936) (xy 86.95182 -373.502936)
			(xy 86.941717 -373.502399) (xy 86.923046 -373.494675) (xy 86.908752 -373.480394) (xy 86.90101 -373.461731)
			(xy 86.900512 -373.451628) (xy 86.900512 -373.293894) (xy 86.900102 -373.284707) (xy 86.893588 -373.267523)
			(xy 86.887812 -373.260366) (xy 86.865981 -373.234673) (xy 86.82789 -373.179043) (xy 86.796738 -373.119251)
			(xy 86.772971 -373.056157) (xy 86.756933 -372.990672) (xy 86.748854 -372.923736) (xy 86.748851 -372.856315)
			(xy 86.756924 -372.789379) (xy 86.772956 -372.723891) (xy 86.796717 -372.660796) (xy 86.827864 -372.601001)
			(xy 86.86595 -372.545367) (xy 86.887812 -372.519702) (xy 86.893592 -372.512545) (xy 86.900116 -372.495363)
			(xy 86.900512 -372.486174) (xy 86.900512 -371.993922) (xy 86.900088 -371.984736) (xy 86.893584 -371.967552)
			(xy 86.887812 -371.960394) (xy 86.86591 -371.93476) (xy 86.827822 -371.879121) (xy 86.796672 -371.819321)
			(xy 86.77291 -371.75622) (xy 86.756876 -371.690727) (xy 86.748803 -371.623785) (xy 85.646742 -371.623785)
			(xy 85.646848 -371.624067) (xy 85.662883 -371.689557) (xy 85.670959 -371.756498) (xy 85.670957 -371.823923)
			(xy 85.662879 -371.890863) (xy 85.646841 -371.956354) (xy 85.623074 -372.019451) (xy 85.591919 -372.079248)
			(xy 85.553826 -372.134881) (xy 85.53196 -372.160546) (xy 85.526156 -372.167686) (xy 85.519647 -372.184881)
			(xy 85.51926 -372.194074) (xy 85.51926 -372.351554) (xy 85.518736 -372.361678) (xy 85.511023 -372.380398)
			(xy 85.496748 -372.394756) (xy 85.478073 -372.402576) (xy 85.467952 -372.403116) (xy 84.751672 -372.403116)
			(xy 84.741563 -372.402638) (xy 84.722888 -372.394894) (xy 84.708594 -372.380596) (xy 84.700858 -372.361917)
			(xy 84.700364 -372.351808) (xy 84.700364 -372.194074) (xy 84.699952 -372.184887) (xy 84.693438 -372.167704)
			(xy 84.687664 -372.160546) (xy 84.665815 -372.134869) (xy 84.627728 -372.079235) (xy 84.596579 -372.01944)
			(xy 84.572816 -371.956345) (xy 84.55678 -371.890858) (xy 84.548704 -371.823921) (xy 84.548703 -371.7565)
			(xy 84.556776 -371.689563) (xy 84.572809 -371.624075) (xy 84.59657 -371.560979) (xy 84.627717 -371.501183)
			(xy 84.665802 -371.445548) (xy 84.687664 -371.419882) (xy 84.693459 -371.412736) (xy 84.699973 -371.395546)
			(xy 84.700364 -371.386354) (xy 84.700364 -370.893848) (xy 84.699917 -370.884665) (xy 84.693427 -370.867481)
			(xy 84.687664 -370.86032) (xy 84.66579 -370.834664) (xy 84.627704 -370.779027) (xy 84.596555 -370.719229)
			(xy 84.572793 -370.656131) (xy 84.55676 -370.590642) (xy 84.548686 -370.523703) (xy 81.27115 -370.523703)
			(xy 81.263075 -370.590641) (xy 81.24704 -370.656129) (xy 81.223276 -370.719226) (xy 81.192125 -370.779021)
			(xy 81.154036 -370.834655) (xy 81.132172 -370.86032) (xy 81.126381 -370.867469) (xy 81.119864 -370.884657)
			(xy 81.119472 -370.893848) (xy 81.119472 -371.386354) (xy 81.119911 -371.395538) (xy 81.126405 -371.412722)
			(xy 81.132172 -371.419882) (xy 81.154051 -371.445535) (xy 81.192141 -371.501171) (xy 81.223293 -371.560969)
			(xy 81.246928 -371.623725) (xy 82.349035 -371.623725) (xy 82.349038 -371.556418) (xy 82.357086 -371.489593)
			(xy 82.373062 -371.424209) (xy 82.396738 -371.361203) (xy 82.427775 -371.301478) (xy 82.465727 -371.24589)
			(xy 82.487516 -371.220238) (xy 82.493323 -371.2131) (xy 82.499831 -371.195904) (xy 82.500216 -371.18671)
			(xy 82.500216 -371.028722) (xy 82.500751 -371.018568) (xy 82.508514 -370.999804) (xy 82.522867 -370.985439)
			(xy 82.541625 -370.977659) (xy 82.551778 -370.97716) (xy 83.268058 -370.97716) (xy 83.27823 -370.977599)
			(xy 83.297028 -370.985374) (xy 83.311415 -370.999756) (xy 83.319197 -371.018551) (xy 83.31962 -371.028722)
			(xy 83.31962 -371.18671) (xy 83.320021 -371.195898) (xy 83.326541 -371.213083) (xy 83.33232 -371.220238)
			(xy 83.354072 -371.24592) (xy 83.392024 -371.301501) (xy 83.423061 -371.361221) (xy 83.446738 -371.424221)
			(xy 83.462715 -371.4896) (xy 83.470763 -371.55642) (xy 83.470766 -371.623723) (xy 83.462725 -371.690544)
			(xy 83.446755 -371.755924) (xy 83.423085 -371.818927) (xy 83.392054 -371.878649) (xy 83.354107 -371.934234)
			(xy 83.33232 -371.959886) (xy 83.326507 -371.96702) (xy 83.320001 -371.984219) (xy 83.31962 -371.993414)
			(xy 83.31962 -372.486682) (xy 83.320034 -372.495869) (xy 83.326545 -372.513054) (xy 83.33232 -372.52021)
			(xy 83.354142 -372.545834) (xy 83.392093 -372.601424) (xy 83.423127 -372.661151) (xy 83.446799 -372.724159)
			(xy 83.462771 -372.789545) (xy 83.470813 -372.856371) (xy 83.47081 -372.92368) (xy 83.462762 -372.990505)
			(xy 83.446784 -373.05589) (xy 83.423106 -373.118896) (xy 83.392066 -373.17862) (xy 83.354111 -373.234206)
			(xy 83.33232 -373.259858) (xy 83.326519 -373.267) (xy 83.320006 -373.284193) (xy 83.31962 -373.293386)
			(xy 83.31962 -373.451374) (xy 83.319214 -373.461549) (xy 83.311429 -373.480351) (xy 83.297038 -373.494738)
			(xy 83.278233 -373.502517) (xy 83.268058 -373.502936) (xy 82.551778 -373.502936) (xy 82.541602 -373.502553)
			(xy 82.522802 -373.494756) (xy 82.508417 -373.480358) (xy 82.500637 -373.461551) (xy 82.500216 -373.451374)
			(xy 82.500216 -373.293386) (xy 82.499809 -373.284199) (xy 82.493293 -373.267014) (xy 82.487516 -373.259858)
			(xy 82.465763 -373.234178) (xy 82.427814 -373.178595) (xy 82.396781 -373.118875) (xy 82.373107 -373.055874)
			(xy 82.357133 -372.990496) (xy 82.349086 -372.923677) (xy 82.349083 -372.856375) (xy 82.357123 -372.789555)
			(xy 82.373092 -372.724175) (xy 82.39676 -372.661172) (xy 82.427788 -372.601449) (xy 82.465731 -372.545863)
			(xy 82.487516 -372.52021) (xy 82.493335 -372.513081) (xy 82.499836 -372.495878) (xy 82.500216 -372.486682)
			(xy 82.500216 -371.993414) (xy 82.499795 -371.984228) (xy 82.493288 -371.967044) (xy 82.487516 -371.959886)
			(xy 82.465692 -371.934264) (xy 82.427745 -371.878673) (xy 82.396715 -371.818945) (xy 82.373045 -371.755936)
			(xy 82.357076 -371.690551) (xy 82.349035 -371.623725) (xy 81.246928 -371.623725) (xy 81.247057 -371.624067)
			(xy 81.263092 -371.689558) (xy 81.271168 -371.756498) (xy 81.271166 -371.823923) (xy 81.263089 -371.890863)
			(xy 81.247051 -371.956353) (xy 81.223284 -372.019451) (xy 81.19213 -372.079247) (xy 81.154038 -372.134881)
			(xy 81.132172 -372.160546) (xy 81.12637 -372.167687) (xy 81.119859 -372.184881) (xy 81.119472 -372.194074)
			(xy 81.119472 -372.351554) (xy 81.118936 -372.361676) (xy 81.111226 -372.380394) (xy 81.096954 -372.394752)
			(xy 81.078283 -372.402574) (xy 81.068164 -372.403116) (xy 80.351884 -372.403116) (xy 80.341776 -372.402628)
			(xy 80.323101 -372.394888) (xy 80.308807 -372.380592) (xy 80.30107 -372.361916) (xy 80.300576 -372.351808)
			(xy 80.300576 -372.194074) (xy 80.300184 -372.184885) (xy 80.293658 -372.1677) (xy 80.287876 -372.160546)
			(xy 80.266027 -372.134869) (xy 80.227939 -372.079236) (xy 80.196789 -372.019441) (xy 80.173025 -371.956346)
			(xy 80.156989 -371.890858) (xy 80.148913 -371.823922) (xy 80.148912 -371.756499) (xy 80.156986 -371.689563)
			(xy 80.173019 -371.624075) (xy 80.196781 -371.560978) (xy 80.227928 -371.501182) (xy 80.266014 -371.445548)
			(xy 80.287876 -371.419882) (xy 80.29366 -371.412728) (xy 80.300183 -371.395544) (xy 80.300576 -371.386354)
			(xy 80.300576 -370.893848) (xy 80.300148 -370.884663) (xy 80.293647 -370.867478) (xy 80.287876 -370.86032)
			(xy 80.266001 -370.834664) (xy 80.227914 -370.779028) (xy 80.196765 -370.71923) (xy 80.173003 -370.656132)
			(xy 80.156969 -370.590642) (xy 80.148895 -370.523703) (xy 76.870824 -370.523703) (xy 76.862788 -370.590464)
			(xy 76.846817 -370.655845) (xy 76.823147 -370.718849) (xy 76.792116 -370.778573) (xy 76.75417 -370.83416)
			(xy 76.732384 -370.859812) (xy 76.726598 -370.866965) (xy 76.720078 -370.88415) (xy 76.719684 -370.89334)
			(xy 76.719684 -371.386862) (xy 76.720116 -371.396047) (xy 76.726615 -371.413231) (xy 76.732384 -371.42039)
			(xy 76.754185 -371.446031) (xy 76.792132 -371.50162) (xy 76.823163 -371.561345) (xy 76.846621 -371.623785)
			(xy 77.948715 -371.623785) (xy 77.948719 -371.556358) (xy 77.956799 -371.489417) (xy 77.972839 -371.423925)
			(xy 77.996609 -371.360826) (xy 78.027766 -371.301029) (xy 78.065861 -371.245395) (xy 78.087728 -371.21973)
			(xy 78.09354 -371.212596) (xy 78.100045 -371.195397) (xy 78.100428 -371.186202) (xy 78.100428 -371.028722)
			(xy 78.100944 -371.018598) (xy 78.108662 -370.99988) (xy 78.12294 -370.985523) (xy 78.141615 -370.977701)
			(xy 78.151736 -370.97716) (xy 78.868016 -370.97716) (xy 78.878121 -370.977671) (xy 78.896792 -370.985407)
			(xy 78.911084 -370.999695) (xy 78.918826 -371.018363) (xy 78.919324 -371.028468) (xy 78.919324 -371.186202)
			(xy 78.919728 -371.19539) (xy 78.926245 -371.212575) (xy 78.932024 -371.21973) (xy 78.95385 -371.245426)
			(xy 78.991938 -371.301057) (xy 79.023089 -371.360849) (xy 79.046854 -371.423942) (xy 79.062892 -371.489427)
			(xy 79.07097 -371.556361) (xy 79.070974 -371.623782) (xy 79.062902 -371.690717) (xy 79.046871 -371.756203)
			(xy 79.023112 -371.819299) (xy 78.991967 -371.879094) (xy 78.953885 -371.934728) (xy 78.932024 -371.960394)
			(xy 78.92625 -371.967556) (xy 78.919721 -371.984733) (xy 78.919324 -371.993922) (xy 78.919324 -372.486174)
			(xy 78.919741 -372.495361) (xy 78.926249 -372.512545) (xy 78.932024 -372.519702) (xy 78.953921 -372.54534)
			(xy 78.992007 -372.600979) (xy 79.023155 -372.660779) (xy 79.046916 -372.72388) (xy 79.062948 -372.789372)
			(xy 79.071021 -372.856313) (xy 79.071018 -372.923738) (xy 79.062939 -372.990679) (xy 79.046901 -373.056169)
			(xy 79.023134 -373.119267) (xy 78.99198 -373.179065) (xy 78.953889 -373.2347) (xy 78.932024 -373.260366)
			(xy 78.92622 -373.267506) (xy 78.919709 -373.2847) (xy 78.919324 -373.293894) (xy 78.919324 -373.451374)
			(xy 78.918851 -373.461504) (xy 78.911125 -373.480231) (xy 78.896834 -373.49459) (xy 78.878143 -373.502403)
			(xy 78.868016 -373.502936) (xy 78.151736 -373.502936) (xy 78.14162 -373.502455) (xy 78.122924 -373.494726)
			(xy 78.10861 -373.480429) (xy 78.100857 -373.461743) (xy 78.100428 -373.451628) (xy 78.100428 -373.293894)
			(xy 78.100015 -373.284707) (xy 78.093503 -373.267523) (xy 78.087728 -373.260366) (xy 78.065896 -373.234674)
			(xy 78.027805 -373.179044) (xy 77.996651 -373.119251) (xy 77.972884 -373.056158) (xy 77.956845 -372.990672)
			(xy 77.948766 -372.923736) (xy 77.948763 -372.856315) (xy 77.956836 -372.789378) (xy 77.972869 -372.723891)
			(xy 77.99663 -372.660795) (xy 78.027779 -372.601) (xy 78.065865 -372.545367) (xy 78.087728 -372.519702)
			(xy 78.09351 -372.512547) (xy 78.100033 -372.495364) (xy 78.100428 -372.486174) (xy 78.100428 -371.993922)
			(xy 78.100001 -371.984737) (xy 78.093498 -371.967553) (xy 78.087728 -371.960394) (xy 78.065826 -371.93476)
			(xy 78.027736 -371.879122) (xy 77.996586 -371.819321) (xy 77.972822 -371.75622) (xy 77.956789 -371.690727)
			(xy 77.948715 -371.623785) (xy 76.846621 -371.623785) (xy 76.846834 -371.624351) (xy 76.862805 -371.689734)
			(xy 76.870848 -371.756558) (xy 76.870847 -371.823863) (xy 76.862802 -371.890687) (xy 76.846828 -371.956069)
			(xy 76.823155 -372.019074) (xy 76.792121 -372.078798) (xy 76.754172 -372.134386) (xy 76.732384 -372.160038)
			(xy 76.726587 -372.167183) (xy 76.720073 -372.184374) (xy 76.719684 -372.193566) (xy 76.719684 -372.351554)
			(xy 76.719199 -372.36172) (xy 76.711433 -372.380509) (xy 76.697067 -372.394895) (xy 76.678287 -372.402686)
			(xy 76.668122 -372.403116) (xy 75.951842 -372.403116) (xy 75.941667 -372.402701) (xy 75.922865 -372.394921)
			(xy 75.908477 -372.380532) (xy 75.900699 -372.361729) (xy 75.90028 -372.351554) (xy 75.90028 -372.193566)
			(xy 75.899891 -372.184377) (xy 75.893363 -372.167192) (xy 75.88758 -372.160038) (xy 75.865805 -372.134375)
			(xy 75.827853 -372.078791) (xy 75.796817 -372.019069) (xy 75.773141 -371.956066) (xy 75.757166 -371.890685)
			(xy 75.74912 -371.823863) (xy 75.749119 -371.756558) (xy 75.757162 -371.689736) (xy 75.773135 -371.624354)
			(xy 75.796808 -371.56135) (xy 75.827842 -371.501627) (xy 75.865792 -371.446042) (xy 75.88758 -371.42039)
			(xy 75.893361 -371.413234) (xy 75.899886 -371.396052) (xy 75.90028 -371.386862) (xy 75.90028 -370.89334)
			(xy 75.899855 -370.884154) (xy 75.893352 -370.866969) (xy 75.88758 -370.859812) (xy 75.865779 -370.83417)
			(xy 75.827828 -370.778583) (xy 75.796793 -370.718859) (xy 75.773119 -370.655853) (xy 75.757146 -370.590469)
			(xy 75.749102 -370.523644) (xy 72.471063 -370.523644) (xy 72.471063 -370.523702) (xy 72.462988 -370.59064)
			(xy 72.446953 -370.656129) (xy 72.42319 -370.719225) (xy 72.39204 -370.779021) (xy 72.353952 -370.834655)
			(xy 72.332088 -370.86032) (xy 72.326299 -370.867471) (xy 72.31978 -370.884657) (xy 72.319388 -370.893848)
			(xy 72.319388 -371.386354) (xy 72.319823 -371.395539) (xy 72.32632 -371.412723) (xy 72.332088 -371.419882)
			(xy 72.353966 -371.445536) (xy 72.392055 -371.501172) (xy 72.423206 -371.560969) (xy 72.446841 -371.623725)
			(xy 73.548947 -371.623725) (xy 73.548951 -371.556417) (xy 73.556998 -371.489592) (xy 73.572975 -371.424208)
			(xy 73.596652 -371.361202) (xy 73.627689 -371.301477) (xy 73.665642 -371.24589) (xy 73.687432 -371.220238)
			(xy 73.693242 -371.213102) (xy 73.699748 -371.195904) (xy 73.700132 -371.18671) (xy 73.700132 -371.028722)
			(xy 73.700582 -371.018553) (xy 73.708359 -370.99976) (xy 73.722736 -370.985374) (xy 73.741525 -370.977587)
			(xy 73.751694 -370.97716) (xy 74.467974 -370.97716) (xy 74.478147 -370.977586) (xy 74.496945 -370.985366)
			(xy 74.511331 -370.999752) (xy 74.519113 -371.018549) (xy 74.519536 -371.028722) (xy 74.519536 -371.18671)
			(xy 74.519956 -371.195896) (xy 74.526464 -371.21308) (xy 74.532236 -371.220238) (xy 74.553987 -371.245921)
			(xy 74.591939 -371.301502) (xy 74.622975 -371.361221) (xy 74.646651 -371.424222) (xy 74.662627 -371.489601)
			(xy 74.670675 -371.55642) (xy 74.670678 -371.623723) (xy 74.662638 -371.690543) (xy 74.646668 -371.755924)
			(xy 74.622998 -371.818926) (xy 74.591968 -371.878649) (xy 74.554022 -371.934234) (xy 74.532236 -371.959886)
			(xy 74.526413 -371.967012) (xy 74.519916 -371.984217) (xy 74.519536 -371.993414) (xy 74.519536 -372.486682)
			(xy 74.519969 -372.495866) (xy 74.526468 -372.51305) (xy 74.532236 -372.52021) (xy 74.554058 -372.545834)
			(xy 74.592008 -372.601424) (xy 74.623041 -372.661151) (xy 74.646713 -372.724159) (xy 74.662684 -372.789545)
			(xy 74.670726 -372.856371) (xy 74.670723 -372.92368) (xy 74.662675 -372.990505) (xy 74.646698 -373.055889)
			(xy 74.62302 -373.118896) (xy 74.591981 -373.17862) (xy 74.554027 -373.234206) (xy 74.532236 -373.259858)
			(xy 74.526425 -373.266992) (xy 74.519921 -373.284191) (xy 74.519536 -373.293386) (xy 74.519536 -373.451374)
			(xy 74.519114 -373.461547) (xy 74.511333 -373.480346) (xy 74.496946 -373.494733) (xy 74.478147 -373.502514)
			(xy 74.467974 -373.502936) (xy 73.751694 -373.502936) (xy 73.741519 -373.50254) (xy 73.722719 -373.494749)
			(xy 73.708333 -373.480354) (xy 73.700553 -373.461549) (xy 73.700132 -373.451374) (xy 73.700132 -373.293386)
			(xy 73.699722 -373.284199) (xy 73.693207 -373.267015) (xy 73.687432 -373.259858) (xy 73.665678 -373.234178)
			(xy 73.627729 -373.178595) (xy 73.596694 -373.118876) (xy 73.57302 -373.055875) (xy 73.557045 -372.990496)
			(xy 73.548998 -372.923677) (xy 73.548995 -372.856374) (xy 73.557036 -372.789554) (xy 73.573005 -372.724174)
			(xy 73.596674 -372.661171) (xy 73.627702 -372.601448) (xy 73.665647 -372.545862) (xy 73.687432 -372.52021)
			(xy 73.693253 -372.513083) (xy 73.699753 -372.495878) (xy 73.700132 -372.486682) (xy 73.700132 -371.993414)
			(xy 73.699708 -371.984228) (xy 73.693203 -371.967044) (xy 73.687432 -371.959886) (xy 73.665607 -371.934265)
			(xy 73.62766 -371.878674) (xy 73.596629 -371.818946) (xy 73.572958 -371.755937) (xy 73.556988 -371.690551)
			(xy 73.548947 -371.623725) (xy 72.446841 -371.623725) (xy 72.44697 -371.624068) (xy 72.463005 -371.689558)
			(xy 72.47108 -371.756498) (xy 72.471078 -371.823923) (xy 72.463001 -371.890862) (xy 72.446964 -371.956352)
			(xy 72.423197 -372.01945) (xy 72.392044 -372.079246) (xy 72.353953 -372.134881) (xy 72.332088 -372.160546)
			(xy 72.326288 -372.167689) (xy 72.319776 -372.184881) (xy 72.319388 -372.194074) (xy 72.319388 -372.351554)
			(xy 72.318836 -372.361674) (xy 72.311129 -372.380389) (xy 72.296863 -372.394746) (xy 72.278197 -372.402572)
			(xy 72.26808 -372.403116) (xy 71.5518 -372.403116) (xy 71.541648 -372.402679) (xy 71.522899 -372.394886)
			(xy 71.508576 -372.380494) (xy 71.500873 -372.361708) (xy 71.500492 -372.351554) (xy 71.500492 -372.194074)
			(xy 71.500096 -372.184885) (xy 71.493573 -372.167701) (xy 71.487792 -372.160546) (xy 71.465942 -372.134869)
			(xy 71.427853 -372.079236) (xy 71.396703 -372.019442) (xy 71.372938 -371.956346) (xy 71.356902 -371.890859)
			(xy 71.348825 -371.823922) (xy 71.348824 -371.756499) (xy 71.356898 -371.689562) (xy 71.372932 -371.624074)
			(xy 71.396694 -371.560978) (xy 71.427843 -371.501182) (xy 71.465929 -371.445547) (xy 71.487792 -371.419882)
			(xy 71.493578 -371.412729) (xy 71.500099 -371.395545) (xy 71.500492 -371.386354) (xy 71.500492 -370.893848)
			(xy 71.500061 -370.884663) (xy 71.493562 -370.867478) (xy 71.487792 -370.86032) (xy 71.465917 -370.834664)
			(xy 71.427829 -370.779028) (xy 71.396679 -370.719231) (xy 71.372916 -370.656133) (xy 71.356881 -370.590642)
			(xy 71.348807 -370.523703) (xy 58.103008 -370.523703) (xy 58.103008 -371.310662) (xy 58.102522 -371.337931)
			(xy 58.09476 -371.391915) (xy 58.079395 -371.444245) (xy 58.056738 -371.493855) (xy 58.027252 -371.539736)
			(xy 57.991537 -371.580953) (xy 57.95032 -371.616668) (xy 57.904439 -371.646154) (xy 57.854829 -371.668811)
			(xy 57.802499 -371.684176) (xy 57.748515 -371.691938) (xy 57.693977 -371.691938) (xy 57.639993 -371.684176)
			(xy 57.587663 -371.668811) (xy 57.538053 -371.646154) (xy 57.492172 -371.616668) (xy 57.450955 -371.580953)
			(xy 57.41524 -371.539736) (xy 57.385754 -371.493855) (xy 57.363097 -371.444245) (xy 57.347732 -371.391915)
			(xy 57.33997 -371.337931) (xy 57.339484 -371.310662) (xy 54.729888 -371.310662) (xy 54.729402 -371.337931)
			(xy 54.72164 -371.391915) (xy 54.706275 -371.444245) (xy 54.683618 -371.493855) (xy 54.654132 -371.539736)
			(xy 54.618417 -371.580953) (xy 54.5772 -371.616668) (xy 54.531319 -371.646154) (xy 54.481709 -371.668811)
			(xy 54.429379 -371.684176) (xy 54.375395 -371.691938) (xy 54.320857 -371.691938) (xy 54.266873 -371.684176)
			(xy 54.214543 -371.668811) (xy 54.164933 -371.646154) (xy 54.119052 -371.616668) (xy 54.077835 -371.580953)
			(xy 54.04212 -371.539736) (xy 54.012634 -371.493855) (xy 53.989977 -371.444245) (xy 53.974612 -371.391915)
			(xy 53.96685 -371.337931) (xy 53.966364 -371.310662) (xy 48.196948 -371.310662) (xy 48.223223 -371.361224)
			(xy 48.246896 -371.424224) (xy 48.262871 -371.489602) (xy 48.270918 -371.556421) (xy 48.270921 -371.623722)
			(xy 48.262881 -371.690542) (xy 48.246913 -371.755921) (xy 48.223246 -371.818924) (xy 48.192219 -371.878647)
			(xy 48.154277 -371.934234) (xy 48.132492 -371.959886) (xy 48.126675 -371.967017) (xy 48.120173 -371.984218)
			(xy 48.119792 -371.993414) (xy 48.119792 -372.486682) (xy 48.120213 -372.495868) (xy 48.126719 -372.513052)
			(xy 48.132492 -372.52021) (xy 48.154312 -372.545835) (xy 48.192258 -372.601426) (xy 48.223288 -372.661154)
			(xy 48.246958 -372.724162) (xy 48.262927 -372.789547) (xy 48.270968 -372.856372) (xy 48.270965 -372.923679)
			(xy 48.262918 -372.990504) (xy 48.246942 -373.055887) (xy 48.223267 -373.118893) (xy 48.192232 -373.178618)
			(xy 48.154281 -373.234205) (xy 48.132492 -373.259858) (xy 48.126687 -373.266997) (xy 48.120178 -373.284192)
			(xy 48.119792 -373.293386) (xy 48.119792 -373.451374) (xy 48.119246 -373.461526) (xy 48.111486 -373.480289)
			(xy 48.097136 -373.494655) (xy 48.078382 -373.502435) (xy 48.06823 -373.502936) (xy 47.35195 -373.502936)
			(xy 47.341778 -373.502495) (xy 47.32298 -373.494721) (xy 47.308592 -373.48034) (xy 47.30081 -373.461545)
			(xy 47.300388 -373.451374) (xy 47.300388 -373.293386) (xy 47.299987 -373.284198) (xy 47.293467 -373.267013)
			(xy 47.287688 -373.259858) (xy 47.265932 -373.234179) (xy 47.227979 -373.178598) (xy 47.196942 -373.118878)
			(xy 47.173265 -373.055877) (xy 47.157288 -372.990498) (xy 47.14924 -372.923677) (xy 47.149237 -372.856374)
			(xy 47.157279 -372.789553) (xy 47.17325 -372.724172) (xy 47.196921 -372.661169) (xy 47.227953 -372.601446)
			(xy 47.265901 -372.545861) (xy 47.287688 -372.52021) (xy 47.293504 -372.513078) (xy 47.300007 -372.495878)
			(xy 47.300388 -372.486682) (xy 47.300388 -371.993414) (xy 47.299974 -371.984227) (xy 47.293463 -371.967043)
			(xy 47.287688 -371.959886) (xy 47.265861 -371.934265) (xy 47.227911 -371.878675) (xy 47.196876 -371.818948)
			(xy 47.173204 -371.755939) (xy 47.157232 -371.690553) (xy 47.14919 -371.623726) (xy 46.046568 -371.623726)
			(xy 46.046802 -371.624349) (xy 46.062775 -371.689733) (xy 46.070818 -371.756557) (xy 46.070817 -371.823864)
			(xy 46.062771 -371.890688) (xy 46.046796 -371.956071) (xy 46.023121 -372.019076) (xy 45.992085 -372.0788)
			(xy 45.954133 -372.134386) (xy 45.932344 -372.160038) (xy 45.926542 -372.167179) (xy 45.920032 -372.184373)
			(xy 45.919644 -372.193566) (xy 45.919644 -372.351554) (xy 45.919198 -372.361725) (xy 45.911425 -372.380522)
			(xy 45.897046 -372.394909) (xy 45.878253 -372.402693) (xy 45.868082 -372.403116) (xy 45.151802 -372.403116)
			(xy 45.141625 -372.402733) (xy 45.122821 -372.394941) (xy 45.108435 -372.380542) (xy 45.100658 -372.361732)
			(xy 45.10024 -372.351554) (xy 45.10024 -372.193566) (xy 45.099837 -372.184378) (xy 45.093317 -372.167194)
			(xy 45.08754 -372.160038) (xy 45.065766 -372.134374) (xy 45.027817 -372.07879) (xy 44.996783 -372.019068)
			(xy 44.973109 -371.956065) (xy 44.957135 -371.890684) (xy 44.94909 -371.823862) (xy 44.949089 -371.756559)
			(xy 44.957132 -371.689737) (xy 44.973103 -371.624356) (xy 44.996774 -371.561352) (xy 45.027806 -371.501628)
			(xy 45.065753 -371.446042) (xy 45.08754 -371.42039) (xy 45.093328 -371.413239) (xy 45.099847 -371.396053)
			(xy 45.10024 -371.386862) (xy 45.10024 -370.89334) (xy 45.099801 -370.884156) (xy 45.093306 -370.866972)
			(xy 45.08754 -370.859812) (xy 45.06574 -370.83417) (xy 45.027792 -370.778582) (xy 44.996759 -370.718857)
			(xy 44.973087 -370.655851) (xy 44.957115 -370.590468) (xy 44.949071 -370.523644) (xy 41.671032 -370.523644)
			(xy 41.671032 -370.523703) (xy 41.662957 -370.590641) (xy 41.646921 -370.65613) (xy 41.623156 -370.719227)
			(xy 41.592004 -370.779022) (xy 41.553913 -370.834656) (xy 41.532048 -370.86032) (xy 41.526254 -370.867467)
			(xy 41.519739 -370.884656) (xy 41.519348 -370.893848) (xy 41.519348 -371.386354) (xy 41.519792 -371.395537)
			(xy 41.526284 -371.412721) (xy 41.532048 -371.419882) (xy 41.553928 -371.445535) (xy 41.592019 -371.50117)
			(xy 41.623172 -371.560967) (xy 41.646832 -371.623785) (xy 42.748894 -371.623785) (xy 42.748898 -371.556358)
			(xy 42.756977 -371.489417) (xy 42.773017 -371.423926) (xy 42.796785 -371.360828) (xy 42.827941 -371.30103)
			(xy 42.866034 -371.245395) (xy 42.8879 -371.21973) (xy 42.893709 -371.212593) (xy 42.900216 -371.195396)
			(xy 42.9006 -371.186202) (xy 42.9006 -371.028722) (xy 42.901143 -371.018602) (xy 42.908856 -370.999888)
			(xy 42.923125 -370.985533) (xy 42.941791 -370.977706) (xy 42.951908 -370.97716) (xy 43.668188 -370.97716)
			(xy 43.678336 -370.977631) (xy 43.697081 -370.985415) (xy 43.711403 -370.999796) (xy 43.71911 -371.018572)
			(xy 43.719496 -371.028722) (xy 43.719496 -371.186202) (xy 43.719906 -371.195389) (xy 43.72642 -371.212573)
			(xy 43.732196 -371.21973) (xy 43.754023 -371.245426) (xy 43.792113 -371.301056) (xy 43.823265 -371.360848)
			(xy 43.847032 -371.423941) (xy 43.86307 -371.489426) (xy 43.871149 -371.556361) (xy 43.871153 -371.623782)
			(xy 43.86308 -371.690718) (xy 43.847049 -371.756205) (xy 43.823289 -371.8193) (xy 43.792142 -371.879095)
			(xy 43.754058 -371.934729) (xy 43.732196 -371.960394) (xy 43.726419 -371.967553) (xy 43.719893 -371.984733)
			(xy 43.719496 -371.993922) (xy 43.719496 -372.486174) (xy 43.71992 -372.49536) (xy 43.726424 -372.512544)
			(xy 43.732196 -372.519702) (xy 43.754094 -372.54534) (xy 43.792181 -372.600978) (xy 43.823331 -372.660778)
			(xy 43.847093 -372.723878) (xy 43.863127 -372.789371) (xy 43.8712 -372.856312) (xy 43.871197 -372.923739)
			(xy 43.863117 -372.990679) (xy 43.847078 -373.05617) (xy 43.82331 -373.119269) (xy 43.792155 -373.179066)
			(xy 43.754062 -373.234701) (xy 43.732196 -373.260366) (xy 43.726388 -373.267503) (xy 43.71988 -373.2847)
			(xy 43.719496 -373.293894) (xy 43.719496 -373.451374) (xy 43.718953 -373.461495) (xy 43.711241 -373.480208)
			(xy 43.696972 -373.494564) (xy 43.678306 -373.502391) (xy 43.668188 -373.502936) (xy 42.951908 -373.502936)
			(xy 42.941759 -373.502473) (xy 42.923014 -373.494686) (xy 42.908691 -373.480303) (xy 42.900985 -373.461525)
			(xy 42.9006 -373.451374) (xy 42.9006 -373.293894) (xy 42.900193 -373.284707) (xy 42.893677 -373.267522)
			(xy 42.8879 -373.260366) (xy 42.866069 -373.234673) (xy 42.82798 -373.179043) (xy 42.796828 -373.11925)
			(xy 42.773061 -373.056157) (xy 42.757024 -372.990671) (xy 42.748945 -372.923736) (xy 42.748942 -372.856315)
			(xy 42.757014 -372.789379) (xy 42.773046 -372.723892) (xy 42.796807 -372.660796) (xy 42.827953 -372.601001)
			(xy 42.866038 -372.545367) (xy 42.8879 -372.519702) (xy 42.893678 -372.512544) (xy 42.900204 -372.495363)
			(xy 42.9006 -372.486174) (xy 42.9006 -371.993922) (xy 42.900179 -371.984736) (xy 42.893673 -371.967551)
			(xy 42.8879 -371.960394) (xy 42.865999 -371.93476) (xy 42.827911 -371.879121) (xy 42.796762 -371.81932)
			(xy 42.773 -371.756219) (xy 42.756967 -371.690726) (xy 42.748894 -371.623785) (xy 41.646832 -371.623785)
			(xy 41.646938 -371.624066) (xy 41.662974 -371.689557) (xy 41.67105 -371.756498) (xy 41.671048 -371.823923)
			(xy 41.66297 -371.890864) (xy 41.646932 -371.956354) (xy 41.623164 -372.019452) (xy 41.592008 -372.079248)
			(xy 41.553915 -372.134882) (xy 41.532048 -372.160546) (xy 41.526243 -372.167685) (xy 41.519735 -372.18488)
			(xy 41.519348 -372.194074) (xy 41.519348 -372.351554) (xy 41.518835 -372.361679) (xy 41.51112 -372.380402)
			(xy 41.496842 -372.39476) (xy 41.478162 -372.402579) (xy 41.46804 -372.403116) (xy 40.75176 -372.403116)
			(xy 40.741605 -372.402711) (xy 40.722855 -372.394906) (xy 40.708534 -372.380504) (xy 40.700833 -372.361711)
			(xy 40.700452 -372.351554) (xy 40.700452 -372.194074) (xy 40.700043 -372.184887) (xy 40.693527 -372.167703)
			(xy 40.687752 -372.160546) (xy 40.6659 -372.13487) (xy 40.627807 -372.079238) (xy 40.596653 -372.019444)
			(xy 40.572886 -371.956349) (xy 40.556848 -371.89086) (xy 40.54877 -371.823922) (xy 40.548769 -371.756499)
			(xy 40.556844 -371.68956) (xy 40.57288 -371.624072) (xy 40.596645 -371.560975) (xy 40.627797 -371.50118)
			(xy 40.665887 -371.445546) (xy 40.687752 -371.419882) (xy 40.693545 -371.412735) (xy 40.70006 -371.395546)
			(xy 40.700452 -371.386354) (xy 40.700452 -370.893848) (xy 40.700007 -370.884665) (xy 40.693516 -370.867481)
			(xy 40.687752 -370.86032) (xy 40.665874 -370.834665) (xy 40.627783 -370.779031) (xy 40.59663 -370.719233)
			(xy 40.572864 -370.656135) (xy 40.556828 -370.590644) (xy 40.548752 -370.523704) (xy 37.271241 -370.523704)
			(xy 37.263166 -370.590641) (xy 37.247131 -370.65613) (xy 37.223366 -370.719226) (xy 37.192215 -370.779022)
			(xy 37.154125 -370.834655) (xy 37.13226 -370.86032) (xy 37.126467 -370.867468) (xy 37.119951 -370.884656)
			(xy 37.11956 -370.893848) (xy 37.11956 -371.386354) (xy 37.120001 -371.395538) (xy 37.126494 -371.412722)
			(xy 37.13226 -371.419882) (xy 37.154139 -371.445535) (xy 37.19223 -371.501171) (xy 37.223382 -371.560968)
			(xy 37.247019 -371.623725) (xy 38.349126 -371.623725) (xy 38.349129 -371.556418) (xy 38.357177 -371.489593)
			(xy 38.373153 -371.424209) (xy 38.396828 -371.361203) (xy 38.427864 -371.301478) (xy 38.465815 -371.245891)
			(xy 38.487604 -371.220238) (xy 38.49341 -371.213099) (xy 38.499919 -371.195904) (xy 38.500304 -371.18671)
			(xy 38.500304 -371.028722) (xy 38.50085 -371.01857) (xy 38.508611 -370.999808) (xy 38.522961 -370.985443)
			(xy 38.541714 -370.977661) (xy 38.551866 -370.97716) (xy 39.268146 -370.97716) (xy 39.278309 -370.977596)
			(xy 39.297084 -370.98539) (xy 39.311448 -370.999773) (xy 39.319217 -371.018558) (xy 39.319708 -371.028722)
			(xy 39.319708 -371.18671) (xy 39.320112 -371.195898) (xy 39.32663 -371.213082) (xy 39.332408 -371.220238)
			(xy 39.35416 -371.24592) (xy 39.392113 -371.301501) (xy 39.423151 -371.36122) (xy 39.446829 -371.424221)
			(xy 39.462806 -371.4896) (xy 39.470854 -371.55642) (xy 39.470857 -371.623723) (xy 39.462816 -371.690544)
			(xy 39.446845 -371.755925) (xy 39.423175 -371.818928) (xy 39.392143 -371.87865) (xy 39.354195 -371.934235)
			(xy 39.332408 -371.959886) (xy 39.326593 -371.967018) (xy 39.320089 -371.984219) (xy 39.319708 -371.993414)
			(xy 39.319708 -372.486682) (xy 39.320125 -372.495868) (xy 39.326634 -372.513053) (xy 39.332408 -372.52021)
			(xy 39.354231 -372.545834) (xy 39.392182 -372.601423) (xy 39.423217 -372.66115) (xy 39.44689 -372.724158)
			(xy 39.462862 -372.789545) (xy 39.470904 -372.856371) (xy 39.470901 -372.92368) (xy 39.462853 -372.990506)
			(xy 39.446875 -373.05589) (xy 39.423196 -373.118897) (xy 39.392156 -373.178621) (xy 39.354199 -373.234207)
			(xy 39.332408 -373.259858) (xy 39.326605 -373.266999) (xy 39.320094 -373.284193) (xy 39.319708 -373.293386)
			(xy 39.319708 -373.451374) (xy 39.319147 -373.461525) (xy 39.311389 -373.480284) (xy 39.297045 -373.494649)
			(xy 39.278296 -373.502432) (xy 39.268146 -373.502936) (xy 38.551866 -373.502936) (xy 38.541703 -373.502494)
			(xy 38.522928 -373.494703) (xy 38.508563 -373.480322) (xy 38.500794 -373.461538) (xy 38.500304 -373.451374)
			(xy 38.500304 -373.293386) (xy 38.4999 -373.284198) (xy 38.493382 -373.267014) (xy 38.487604 -373.259858)
			(xy 38.465851 -373.234178) (xy 38.427903 -373.178595) (xy 38.39687 -373.118875) (xy 38.373197 -373.055874)
			(xy 38.357223 -372.990495) (xy 38.349177 -372.923676) (xy 38.349174 -372.856375) (xy 38.357214 -372.789555)
			(xy 38.373182 -372.724175) (xy 38.396849 -372.661172) (xy 38.427877 -372.601449) (xy 38.465819 -372.545863)
			(xy 38.487604 -372.52021) (xy 38.493422 -372.51308) (xy 38.499924 -372.495878) (xy 38.500304 -372.486682)
			(xy 38.500304 -371.993414) (xy 38.499886 -371.984228) (xy 38.493378 -371.967043) (xy 38.487604 -371.959886)
			(xy 38.46578 -371.934264) (xy 38.427835 -371.878672) (xy 38.396805 -371.818944) (xy 38.373136 -371.755936)
			(xy 38.357167 -371.69055) (xy 38.349126 -371.623725) (xy 37.247019 -371.623725) (xy 37.247148 -371.624067)
			(xy 37.263183 -371.689557) (xy 37.271259 -371.756498) (xy 37.271257 -371.823923) (xy 37.263179 -371.890863)
			(xy 37.247141 -371.956354) (xy 37.223374 -372.019451) (xy 37.192219 -372.079248) (xy 37.154126 -372.134881)
			(xy 37.13226 -372.160546) (xy 37.126456 -372.167686) (xy 37.119947 -372.184881) (xy 37.11956 -372.194074)
			(xy 37.11956 -372.351554) (xy 37.119036 -372.361678) (xy 37.111323 -372.380398) (xy 37.097048 -372.394756)
			(xy 37.078373 -372.402576) (xy 37.068252 -372.403116) (xy 36.351972 -372.403116) (xy 36.341818 -372.402702)
			(xy 36.323068 -372.3949) (xy 36.308746 -372.380501) (xy 36.301045 -372.36171) (xy 36.300664 -372.351554)
			(xy 36.300664 -372.194074) (xy 36.300252 -372.184887) (xy 36.293738 -372.167704) (xy 36.287964 -372.160546)
			(xy 36.266115 -372.134869) (xy 36.228028 -372.079235) (xy 36.196879 -372.01944) (xy 36.173116 -371.956345)
			(xy 36.15708 -371.890858) (xy 36.149004 -371.823921) (xy 36.149003 -371.7565) (xy 36.157076 -371.689563)
			(xy 36.173109 -371.624075) (xy 36.19687 -371.560979) (xy 36.228017 -371.501183) (xy 36.266102 -371.445548)
			(xy 36.287964 -371.419882) (xy 36.293759 -371.412736) (xy 36.300273 -371.395546) (xy 36.300664 -371.386354)
			(xy 36.300664 -370.893848) (xy 36.300217 -370.884665) (xy 36.293727 -370.867481) (xy 36.287964 -370.86032)
			(xy 36.26609 -370.834664) (xy 36.228004 -370.779027) (xy 36.196855 -370.719229) (xy 36.173093 -370.656131)
			(xy 36.15706 -370.590642) (xy 36.148986 -370.523703) (xy 32.870915 -370.523703) (xy 32.862879 -370.590465)
			(xy 32.846908 -370.655846) (xy 32.823237 -370.71885) (xy 32.792205 -370.778573) (xy 32.754259 -370.83416)
			(xy 32.732472 -370.859812) (xy 32.726684 -370.866963) (xy 32.720165 -370.884149) (xy 32.719772 -370.89334)
			(xy 32.719772 -371.386862) (xy 32.720207 -371.396046) (xy 32.726704 -371.413231) (xy 32.732472 -371.42039)
			(xy 32.754273 -371.446031) (xy 32.792221 -371.501619) (xy 32.823253 -371.561344) (xy 32.846713 -371.623785)
			(xy 33.948806 -371.623785) (xy 33.94881 -371.556358) (xy 33.95689 -371.489417) (xy 33.97293 -371.423925)
			(xy 33.996699 -371.360827) (xy 34.027855 -371.30103) (xy 34.065949 -371.245395) (xy 34.087816 -371.21973)
			(xy 34.093627 -371.212595) (xy 34.100132 -371.195397) (xy 34.100516 -371.186202) (xy 34.100516 -371.028722)
			(xy 34.101044 -371.0186) (xy 34.10876 -370.999883) (xy 34.123033 -370.985527) (xy 34.141705 -370.977703)
			(xy 34.151824 -370.97716) (xy 34.868104 -370.97716) (xy 34.878253 -370.977618) (xy 34.896998 -370.985407)
			(xy 34.91132 -370.999792) (xy 34.919027 -371.018571) (xy 34.919412 -371.028722) (xy 34.919412 -371.186202)
			(xy 34.919819 -371.19539) (xy 34.926334 -371.212574) (xy 34.932112 -371.21973) (xy 34.953938 -371.245426)
			(xy 34.992027 -371.301057) (xy 35.023179 -371.360849) (xy 35.046945 -371.423941) (xy 35.062982 -371.489427)
			(xy 35.071061 -371.556361) (xy 35.071065 -371.623782) (xy 35.062993 -371.690717) (xy 35.046962 -371.756204)
			(xy 35.023202 -371.819299) (xy 34.992057 -371.879094) (xy 34.953973 -371.934729) (xy 34.932112 -371.960394)
			(xy 34.926337 -371.967555) (xy 34.919809 -371.984733) (xy 34.919412 -371.993922) (xy 34.919412 -372.486174)
			(xy 34.919832 -372.49536) (xy 34.926338 -372.512545) (xy 34.932112 -372.519702) (xy 34.954009 -372.54534)
			(xy 34.992096 -372.600979) (xy 35.023244 -372.660779) (xy 35.047006 -372.723879) (xy 35.063039 -372.789371)
			(xy 35.071112 -372.856312) (xy 35.071109 -372.923739) (xy 35.06303 -372.990679) (xy 35.046991 -373.05617)
			(xy 35.023224 -373.119268) (xy 34.99207 -373.179065) (xy 34.953978 -373.234701) (xy 34.932112 -373.260366)
			(xy 34.926306 -373.267505) (xy 34.919797 -373.2847) (xy 34.919412 -373.293894) (xy 34.919412 -373.451374)
			(xy 34.918854 -373.461493) (xy 34.911144 -373.480203) (xy 34.89688 -373.494559) (xy 34.878219 -373.502388)
			(xy 34.868104 -373.502936) (xy 34.151824 -373.502936) (xy 34.141676 -373.50246) (xy 34.122931 -373.494679)
			(xy 34.108608 -373.480299) (xy 34.100901 -373.461524) (xy 34.100516 -373.451374) (xy 34.100516 -373.293894)
			(xy 34.100105 -373.284707) (xy 34.093592 -373.267523) (xy 34.087816 -373.260366) (xy 34.065985 -373.234673)
			(xy 34.027894 -373.179043) (xy 33.996741 -373.119251) (xy 33.972974 -373.056158) (xy 33.956936 -372.990672)
			(xy 33.948857 -372.923736) (xy 33.948854 -372.856315) (xy 33.956927 -372.789379) (xy 33.972959 -372.723891)
			(xy 33.99672 -372.660796) (xy 34.027868 -372.601001) (xy 34.065953 -372.545367) (xy 34.087816 -372.519702)
			(xy 34.093596 -372.512545) (xy 34.10012 -372.495364) (xy 34.100516 -372.486174) (xy 34.100516 -371.993922)
			(xy 34.100092 -371.984736) (xy 34.093587 -371.967552) (xy 34.087816 -371.960394) (xy 34.065914 -371.93476)
			(xy 34.027826 -371.879121) (xy 33.996676 -371.819321) (xy 33.972913 -371.75622) (xy 33.956879 -371.690727)
			(xy 33.948806 -371.623785) (xy 32.846713 -371.623785) (xy 32.846925 -371.62435) (xy 32.862896 -371.689734)
			(xy 32.870939 -371.756558) (xy 32.870938 -371.823864) (xy 32.862892 -371.890687) (xy 32.846918 -371.95607)
			(xy 32.823244 -372.019075) (xy 32.79221 -372.078799) (xy 32.75426 -372.134386) (xy 32.732472 -372.160038)
			(xy 32.726673 -372.167181) (xy 32.72016 -372.184373) (xy 32.719772 -372.193566) (xy 32.719772 -372.351554)
			(xy 32.719299 -372.361721) (xy 32.711531 -372.380513) (xy 32.69716 -372.394899) (xy 32.678377 -372.402688)
			(xy 32.66821 -372.403116) (xy 31.95193 -372.403116) (xy 31.941755 -372.40271) (xy 31.922952 -372.394927)
			(xy 31.908564 -372.380535) (xy 31.900787 -372.361729) (xy 31.900368 -372.351554) (xy 31.900368 -372.193566)
			(xy 31.899959 -372.184379) (xy 31.893443 -372.167195) (xy 31.887668 -372.160038) (xy 31.865893 -372.134375)
			(xy 31.827942 -372.078791) (xy 31.796907 -372.019069) (xy 31.773232 -371.956066) (xy 31.757257 -371.890685)
			(xy 31.749211 -371.823863) (xy 31.74921 -371.756558) (xy 31.757253 -371.689736) (xy 31.773226 -371.624354)
			(xy 31.796898 -371.56135) (xy 31.827931 -371.501627) (xy 31.86588 -371.446042) (xy 31.887668 -371.42039)
			(xy 31.89346 -371.413242) (xy 31.899975 -371.396053) (xy 31.900368 -371.386862) (xy 31.900368 -370.89334)
			(xy 31.899923 -370.884157) (xy 31.893432 -370.866973) (xy 31.887668 -370.859812) (xy 31.865868 -370.83417)
			(xy 31.827917 -370.778583) (xy 31.796883 -370.718858) (xy 31.77321 -370.655852) (xy 31.757237 -370.590468)
			(xy 31.749193 -370.523644) (xy 28.471153 -370.523644) (xy 28.471153 -370.523703) (xy 28.463078 -370.59064)
			(xy 28.447043 -370.656129) (xy 28.42328 -370.719226) (xy 28.392129 -370.779021) (xy 28.35404 -370.834655)
			(xy 28.332176 -370.86032) (xy 28.326386 -370.867469) (xy 28.319868 -370.884657) (xy 28.319476 -370.893848)
			(xy 28.319476 -371.386354) (xy 28.319914 -371.395538) (xy 28.326409 -371.412722) (xy 28.332176 -371.419882)
			(xy 28.354055 -371.445535) (xy 28.392144 -371.501171) (xy 28.423296 -371.560969) (xy 28.446931 -371.623725)
			(xy 29.549038 -371.623725) (xy 29.549042 -371.556418) (xy 29.557089 -371.489593) (xy 29.573066 -371.424209)
			(xy 29.596742 -371.361203) (xy 29.627778 -371.301478) (xy 29.665731 -371.24589) (xy 29.68752 -371.220238)
			(xy 29.693328 -371.213101) (xy 29.699835 -371.195904) (xy 29.70022 -371.18671) (xy 29.70022 -371.028722)
			(xy 29.700682 -371.018554) (xy 29.708456 -370.999763) (xy 29.72283 -370.985378) (xy 29.741614 -370.97759)
			(xy 29.751782 -370.97716) (xy 30.468062 -370.97716) (xy 30.478234 -370.977596) (xy 30.497032 -370.985372)
			(xy 30.511419 -370.999755) (xy 30.519201 -371.01855) (xy 30.519624 -371.028722) (xy 30.519624 -371.18671)
			(xy 30.520024 -371.195898) (xy 30.526544 -371.213083) (xy 30.532324 -371.220238) (xy 30.554075 -371.24592)
			(xy 30.592028 -371.301502) (xy 30.623065 -371.361221) (xy 30.646741 -371.424221) (xy 30.662718 -371.4896)
			(xy 30.670766 -371.55642) (xy 30.670769 -371.623723) (xy 30.662728 -371.690543) (xy 30.646758 -371.755924)
			(xy 30.623088 -371.818927) (xy 30.592057 -371.878649) (xy 30.554111 -371.934234) (xy 30.532324 -371.959886)
			(xy 30.526511 -371.96702) (xy 30.520005 -371.984219) (xy 30.519624 -371.993414) (xy 30.519624 -372.486682)
			(xy 30.520037 -372.495869) (xy 30.526548 -372.513054) (xy 30.532324 -372.52021) (xy 30.554146 -372.545834)
			(xy 30.592096 -372.601424) (xy 30.62313 -372.661151) (xy 30.646803 -372.724159) (xy 30.662774 -372.789545)
			(xy 30.670816 -372.856371) (xy 30.670813 -372.92368) (xy 30.662765 -372.990505) (xy 30.646788 -373.05589)
			(xy 30.623109 -373.118896) (xy 30.59207 -373.17862) (xy 30.554115 -373.234206) (xy 30.532324 -373.259858)
			(xy 30.526523 -373.267) (xy 30.52001 -373.284193) (xy 30.519624 -373.293386) (xy 30.519624 -373.451374)
			(xy 30.519214 -373.461549) (xy 30.51143 -373.48035) (xy 30.49704 -373.494737) (xy 30.478237 -373.502516)
			(xy 30.468062 -373.502936) (xy 29.751782 -373.502936) (xy 29.741606 -373.50255) (xy 29.722806 -373.494754)
			(xy 29.708421 -373.480357) (xy 29.700641 -373.46155) (xy 29.70022 -373.451374) (xy 29.70022 -373.293386)
			(xy 29.699812 -373.284199) (xy 29.693297 -373.267015) (xy 29.68752 -373.259858) (xy 29.665767 -373.234178)
			(xy 29.627818 -373.178595) (xy 29.596784 -373.118875) (xy 29.57311 -373.055874) (xy 29.557136 -372.990496)
			(xy 29.549089 -372.923677) (xy 29.549086 -372.856375) (xy 29.557127 -372.789555) (xy 29.573095 -372.724175)
			(xy 29.596763 -372.661172) (xy 29.627792 -372.601449) (xy 29.665735 -372.545863) (xy 29.68752 -372.52021)
			(xy 29.69334 -372.513081) (xy 29.69984 -372.495878) (xy 29.70022 -372.486682) (xy 29.70022 -371.993414)
			(xy 29.699798 -371.984228) (xy 29.693292 -371.967044) (xy 29.68752 -371.959886) (xy 29.665695 -371.934264)
			(xy 29.627749 -371.878673) (xy 29.596718 -371.818945) (xy 29.573049 -371.755937) (xy 29.557079 -371.690551)
			(xy 29.549038 -371.623725) (xy 28.446931 -371.623725) (xy 28.44706 -371.624067) (xy 28.463096 -371.689558)
			(xy 28.471171 -371.756498) (xy 28.471169 -371.823923) (xy 28.463092 -371.890863) (xy 28.447054 -371.956353)
			(xy 28.423287 -372.01945) (xy 28.392134 -372.079247) (xy 28.354042 -372.134881) (xy 28.332176 -372.160546)
			(xy 28.326375 -372.167688) (xy 28.319864 -372.184881) (xy 28.319476 -372.194074) (xy 28.319476 -372.351554)
			(xy 28.318936 -372.361676) (xy 28.311226 -372.380393) (xy 28.296956 -372.39475) (xy 28.278287 -372.402574)
			(xy 28.268168 -372.403116) (xy 27.551888 -372.403116) (xy 27.541781 -372.402625) (xy 27.523105 -372.394886)
			(xy 27.508811 -372.380591) (xy 27.501074 -372.361916) (xy 27.50058 -372.351808) (xy 27.50058 -372.194074)
			(xy 27.500187 -372.184885) (xy 27.493662 -372.167701) (xy 27.48788 -372.160546) (xy 27.46603 -372.134869)
			(xy 27.427943 -372.079236) (xy 27.396792 -372.019441) (xy 27.373028 -371.956346) (xy 27.356993 -371.890858)
			(xy 27.348916 -371.823922) (xy 27.348915 -371.756499) (xy 27.356989 -371.689562) (xy 27.373022 -371.624074)
			(xy 27.396784 -371.560978) (xy 27.427932 -371.501182) (xy 27.466018 -371.445548) (xy 27.48788 -371.419882)
			(xy 27.493664 -371.412728) (xy 27.500187 -371.395544) (xy 27.50058 -371.386354) (xy 27.50058 -370.893848)
			(xy 27.500151 -370.884663) (xy 27.493651 -370.867478) (xy 27.48788 -370.86032) (xy 27.466005 -370.834664)
			(xy 27.427918 -370.779028) (xy 27.396769 -370.71923) (xy 27.373006 -370.656132) (xy 27.356972 -370.590642)
			(xy 27.348898 -370.523703) (xy 0.508 -370.523703) (xy 0.508 -372.100847) (xy 8.642336 -372.100847)
			(xy 8.642336 -372.040913) (xy 8.650159 -371.981491) (xy 8.665671 -371.923598) (xy 8.688607 -371.868226)
			(xy 8.718575 -371.81632) (xy 8.755061 -371.768771) (xy 8.797441 -371.726391) (xy 8.84499 -371.689905)
			(xy 8.896896 -371.659937) (xy 8.952268 -371.637001) (xy 9.010161 -371.621489) (xy 9.069583 -371.613666)
			(xy 9.09955 -371.613176) (xy 9.96315 -371.613176) (xy 9.993118 -371.613658) (xy 10.052541 -371.621481)
			(xy 10.110435 -371.636994) (xy 10.165808 -371.65993) (xy 10.217714 -371.689898) (xy 10.265264 -371.726385)
			(xy 10.307645 -371.768766) (xy 10.344132 -371.816316) (xy 10.3741 -371.868222) (xy 10.397036 -371.923595)
			(xy 10.412549 -371.981489) (xy 10.420372 -372.040912) (xy 10.420372 -372.100848) (xy 10.412549 -372.160271)
			(xy 10.397036 -372.218165) (xy 10.3741 -372.273538) (xy 10.344132 -372.325444) (xy 10.307645 -372.372994)
			(xy 10.265264 -372.415375) (xy 10.217714 -372.451862) (xy 10.165808 -372.48183) (xy 10.110435 -372.504766)
			(xy 10.052541 -372.520279) (xy 9.993118 -372.528102) (xy 9.96315 -372.528592) (xy 9.09955 -372.528592)
			(xy 9.069583 -372.528094) (xy 9.010161 -372.520271) (xy 8.952268 -372.504759) (xy 8.896896 -372.481823)
			(xy 8.84499 -372.451855) (xy 8.797441 -372.415369) (xy 8.755061 -372.372989) (xy 8.718575 -372.32544)
			(xy 8.688607 -372.273534) (xy 8.665671 -372.218162) (xy 8.650159 -372.160269) (xy 8.642336 -372.100847)
			(xy 0.508 -372.100847) (xy 0.508 -374.423871) (xy 27.348897 -374.423871) (xy 27.348897 -374.356446)
			(xy 27.356974 -374.289508) (xy 27.37301 -374.224019) (xy 27.396774 -374.160922) (xy 27.427926 -374.101125)
			(xy 27.466016 -374.045491) (xy 27.48788 -374.019826) (xy 27.493688 -374.012689) (xy 27.500197 -373.995492)
			(xy 27.50058 -373.986298) (xy 27.50058 -373.828818) (xy 27.501042 -373.818688) (xy 27.508772 -373.799959)
			(xy 27.523066 -373.785601) (xy 27.54176 -373.777788) (xy 27.551888 -373.777256) (xy 28.268168 -373.777256)
			(xy 28.278269 -373.77781) (xy 28.296938 -373.785529) (xy 28.311233 -373.799804) (xy 28.318977 -373.818463)
			(xy 28.319476 -373.828564) (xy 28.319476 -373.986298) (xy 28.319892 -373.995484) (xy 28.326402 -374.012669)
			(xy 28.332176 -374.019826) (xy 28.354038 -374.045493) (xy 28.392127 -374.101127) (xy 28.423278 -374.160923)
			(xy 28.447043 -374.22402) (xy 28.463078 -374.289509) (xy 28.471154 -374.356447) (xy 28.471155 -374.423823)
			(xy 31.749171 -374.423823) (xy 31.749175 -374.356514) (xy 31.757224 -374.289688) (xy 31.773202 -374.224303)
			(xy 31.796881 -374.161297) (xy 31.827921 -374.101572) (xy 31.865877 -374.045986) (xy 31.887668 -374.020334)
			(xy 31.893483 -374.013202) (xy 31.899985 -373.996001) (xy 31.900368 -373.986806) (xy 31.900368 -373.828818)
			(xy 31.900779 -373.818644) (xy 31.908564 -373.799844) (xy 31.922954 -373.785457) (xy 31.941756 -373.777677)
			(xy 31.95193 -373.777256) (xy 32.66821 -373.777256) (xy 32.678384 -373.777656) (xy 32.697183 -373.785448)
			(xy 32.711568 -373.799841) (xy 32.719349 -373.818643) (xy 32.719772 -373.828818) (xy 32.719772 -373.986806)
			(xy 32.720185 -373.995993) (xy 32.726697 -374.013177) (xy 32.732472 -374.020334) (xy 32.754218 -374.04602)
			(xy 32.792167 -374.101602) (xy 32.823202 -374.161321) (xy 32.846876 -374.224321) (xy 32.862852 -374.289699)
			(xy 32.870899 -374.356518) (xy 32.870903 -374.423819) (xy 32.870895 -374.423882) (xy 36.148964 -374.423882)
			(xy 36.148968 -374.356455) (xy 36.157048 -374.289515) (xy 36.173087 -374.224024) (xy 36.196854 -374.160925)
			(xy 36.228007 -374.101128) (xy 36.266099 -374.045492) (xy 36.287964 -374.019826) (xy 36.293782 -374.012697)
			(xy 36.300282 -373.995494) (xy 36.300664 -373.986298) (xy 36.300664 -373.828818) (xy 36.301142 -373.818689)
			(xy 36.308868 -373.799964) (xy 36.323158 -373.785606) (xy 36.341846 -373.777791) (xy 36.351972 -373.777256)
			(xy 37.068252 -373.777256) (xy 37.078398 -373.77776) (xy 37.09714 -373.785532) (xy 37.111464 -373.799903)
			(xy 37.119173 -373.818671) (xy 37.11956 -373.828818) (xy 37.11956 -373.986298) (xy 37.11998 -373.995484)
			(xy 37.126488 -374.012668) (xy 37.13226 -374.019826) (xy 37.154084 -374.045525) (xy 37.192177 -374.101153)
			(xy 37.223331 -374.160945) (xy 37.2471 -374.224037) (xy 37.263139 -374.289523) (xy 37.271219 -374.356458)
			(xy 37.271223 -374.423879) (xy 37.271223 -374.423882) (xy 40.548731 -374.423882) (xy 40.548735 -374.356454)
			(xy 40.556815 -374.289512) (xy 40.572857 -374.22402) (xy 40.596628 -374.160921) (xy 40.627787 -374.101124)
			(xy 40.665884 -374.04549) (xy 40.687752 -374.019826) (xy 40.693569 -374.012695) (xy 40.70007 -373.995494)
			(xy 40.700452 -373.986298) (xy 40.700452 -373.828818) (xy 40.700942 -373.818691) (xy 40.708666 -373.799968)
			(xy 40.722951 -373.785611) (xy 40.741636 -373.777793) (xy 40.75176 -373.777256) (xy 41.46804 -373.777256)
			(xy 41.478191 -373.777688) (xy 41.496936 -373.785489) (xy 41.511256 -373.799881) (xy 41.518963 -373.818665)
			(xy 41.519348 -373.828818) (xy 41.519348 -373.986298) (xy 41.519771 -373.995484) (xy 41.526277 -374.012667)
			(xy 41.532048 -374.019826) (xy 41.553873 -374.045524) (xy 41.591966 -374.101153) (xy 41.623121 -374.160944)
			(xy 41.64689 -374.224037) (xy 41.66293 -374.289522) (xy 41.67101 -374.356458) (xy 41.671014 -374.423823)
			(xy 44.94905 -374.423823) (xy 44.949054 -374.356514) (xy 44.957102 -374.289689) (xy 44.97308 -374.224304)
			(xy 44.996757 -374.161298) (xy 45.027796 -374.101573) (xy 45.06575 -374.045986) (xy 45.08754 -374.020334)
			(xy 45.093352 -374.0132) (xy 45.099857 -373.996001) (xy 45.10024 -373.986806) (xy 45.10024 -373.828818)
			(xy 45.100678 -373.818647) (xy 45.108458 -373.799853) (xy 45.122839 -373.785467) (xy 45.141631 -373.777682)
			(xy 45.151802 -373.777256) (xy 45.868082 -373.777256) (xy 45.878255 -373.777679) (xy 45.897053 -373.785461)
			(xy 45.911439 -373.799847) (xy 45.919221 -373.818645) (xy 45.919644 -373.828818) (xy 45.919644 -373.986806)
			(xy 45.920064 -373.995992) (xy 45.926572 -374.013176) (xy 45.932344 -374.020334) (xy 45.954091 -374.04602)
			(xy 45.992042 -374.101601) (xy 46.023078 -374.16132) (xy 46.046754 -374.22432) (xy 46.06273 -374.289698)
			(xy 46.070778 -374.356517) (xy 46.070782 -374.423819) (xy 46.070774 -374.423882) (xy 71.348786 -374.423882)
			(xy 71.348789 -374.356455) (xy 71.356869 -374.289514) (xy 71.372909 -374.224023) (xy 71.396677 -374.160924)
			(xy 71.427833 -374.101127) (xy 71.465926 -374.045491) (xy 71.487792 -374.019826) (xy 71.493602 -374.01269)
			(xy 71.500109 -373.995492) (xy 71.500492 -373.986298) (xy 71.500492 -373.828818) (xy 71.50104 -373.818698)
			(xy 71.508753 -373.799987) (xy 71.52302 -373.785631) (xy 71.541684 -373.777803) (xy 71.5518 -373.777256)
			(xy 72.26808 -373.777256) (xy 72.278227 -373.777737) (xy 72.296971 -373.785518) (xy 72.311293 -373.799896)
			(xy 72.319002 -373.818669) (xy 72.319388 -373.828818) (xy 72.319388 -373.986298) (xy 72.319802 -373.995485)
			(xy 72.326313 -374.012669) (xy 72.332088 -374.019826) (xy 72.353911 -374.045525) (xy 72.392002 -374.101154)
			(xy 72.423155 -374.160946) (xy 72.446922 -374.224038) (xy 72.462961 -374.289523) (xy 72.47104 -374.356458)
			(xy 72.471044 -374.423823) (xy 75.749081 -374.423823) (xy 75.749084 -374.356514) (xy 75.757133 -374.289688)
			(xy 75.773112 -374.224303) (xy 75.796791 -374.161296) (xy 75.827832 -374.101572) (xy 75.865788 -374.045985)
			(xy 75.88758 -374.020334) (xy 75.893385 -374.013194) (xy 75.899895 -373.996) (xy 75.90028 -373.986806)
			(xy 75.90028 -373.828818) (xy 75.900679 -373.818642) (xy 75.908466 -373.79984) (xy 75.92286 -373.785453)
			(xy 75.941666 -373.777675) (xy 75.951842 -373.777256) (xy 76.668122 -373.777256) (xy 76.678283 -373.777716)
			(xy 76.697057 -373.785501) (xy 76.711422 -373.799877) (xy 76.719192 -373.818656) (xy 76.719684 -373.828818)
			(xy 76.719684 -373.986806) (xy 76.720095 -373.995993) (xy 76.726608 -374.013177) (xy 76.732384 -374.020334)
			(xy 76.754129 -374.046021) (xy 76.792078 -374.101603) (xy 76.823112 -374.161322) (xy 76.846786 -374.224322)
			(xy 76.862761 -374.289699) (xy 76.870808 -374.356518) (xy 76.870812 -374.423819) (xy 76.870804 -374.423882)
			(xy 80.148873 -374.423882) (xy 80.148877 -374.356455) (xy 80.156957 -374.289515) (xy 80.172996 -374.224023)
			(xy 80.196764 -374.160925) (xy 80.227918 -374.101127) (xy 80.26601 -374.045492) (xy 80.287876 -374.019826)
			(xy 80.293684 -374.012689) (xy 80.300193 -373.995492) (xy 80.300576 -373.986298) (xy 80.300576 -373.828818)
			(xy 80.301042 -373.818688) (xy 80.308771 -373.79996) (xy 80.323064 -373.785602) (xy 80.341756 -373.777789)
			(xy 80.351884 -373.777256) (xy 81.068164 -373.777256) (xy 81.078265 -373.777814) (xy 81.096934 -373.785531)
			(xy 81.111228 -373.799806) (xy 81.118972 -373.818464) (xy 81.119472 -373.828564) (xy 81.119472 -373.986298)
			(xy 81.119889 -373.995484) (xy 81.126399 -374.012668) (xy 81.132172 -374.019826) (xy 81.153996 -374.045525)
			(xy 81.192087 -374.101154) (xy 81.223242 -374.160945) (xy 81.247009 -374.224038) (xy 81.263049 -374.289523)
			(xy 81.271128 -374.356458) (xy 81.271132 -374.423879) (xy 81.271132 -374.423882) (xy 84.548664 -374.423882)
			(xy 84.548668 -374.356455) (xy 84.556748 -374.289515) (xy 84.572787 -374.224024) (xy 84.596554 -374.160925)
			(xy 84.627707 -374.101128) (xy 84.665799 -374.045492) (xy 84.687664 -374.019826) (xy 84.693482 -374.012697)
			(xy 84.699982 -373.995494) (xy 84.700364 -373.986298) (xy 84.700364 -373.828818) (xy 84.700842 -373.818689)
			(xy 84.708568 -373.799964) (xy 84.722858 -373.785606) (xy 84.741546 -373.777791) (xy 84.751672 -373.777256)
			(xy 85.467952 -373.777256) (xy 85.478066 -373.777754) (xy 85.49676 -373.785478) (xy 85.511074 -373.799769)
			(xy 85.518829 -373.818451) (xy 85.51926 -373.828564) (xy 85.51926 -373.986298) (xy 85.51968 -373.995484)
			(xy 85.526188 -374.012668) (xy 85.53196 -374.019826) (xy 85.553784 -374.045525) (xy 85.591877 -374.101153)
			(xy 85.623031 -374.160945) (xy 85.6468 -374.224037) (xy 85.662839 -374.289523) (xy 85.670919 -374.356458)
			(xy 85.670923 -374.423822) (xy 115.349223 -374.423822) (xy 115.349227 -374.356515) (xy 115.357275 -374.28969)
			(xy 115.373251 -374.224306) (xy 115.396927 -374.1613) (xy 115.427963 -374.101574) (xy 115.465915 -374.045987)
			(xy 115.487704 -374.020334) (xy 115.493512 -374.013197) (xy 115.50002 -373.996) (xy 115.500404 -373.986806)
			(xy 115.500404 -373.828818) (xy 115.500947 -373.818666) (xy 115.508709 -373.799903) (xy 115.52306 -373.785539)
			(xy 115.541814 -373.777757) (xy 115.551966 -373.777256) (xy 116.268246 -373.777256) (xy 116.278409 -373.777696)
			(xy 116.297183 -373.785489) (xy 116.311547 -373.799871) (xy 116.319316 -373.818654) (xy 116.319808 -373.828818)
			(xy 116.319808 -373.986806) (xy 116.320214 -373.995994) (xy 116.32673 -374.013178) (xy 116.332508 -374.020334)
			(xy 116.354256 -374.046019) (xy 116.39221 -374.1016) (xy 116.423248 -374.161318) (xy 116.446925 -374.224319)
			(xy 116.462903 -374.289697) (xy 116.470951 -374.356517) (xy 116.470955 -374.42382) (xy 116.470948 -374.423882)
			(xy 119.748992 -374.423882) (xy 119.748995 -374.356455) (xy 119.757075 -374.289514) (xy 119.773115 -374.224022)
			(xy 119.796884 -374.160924) (xy 119.82804 -374.101126) (xy 119.866134 -374.045491) (xy 119.888 -374.019826)
			(xy 119.89381 -374.012691) (xy 119.900317 -373.995493) (xy 119.9007 -373.986298) (xy 119.9007 -373.828818)
			(xy 119.90124 -373.818697) (xy 119.908955 -373.799984) (xy 119.923224 -373.785629) (xy 119.94189 -373.777802)
			(xy 119.952008 -373.777256) (xy 120.668288 -373.777256) (xy 120.678436 -373.777731) (xy 120.69718 -373.785514)
			(xy 120.711502 -373.799894) (xy 120.71921 -373.818669) (xy 120.719596 -373.828818) (xy 120.719596 -373.986298)
			(xy 120.720008 -373.995485) (xy 120.726521 -374.012669) (xy 120.732296 -374.019826) (xy 120.754119 -374.045525)
			(xy 120.792209 -374.101155) (xy 120.823362 -374.160946) (xy 120.847129 -374.224039) (xy 120.863167 -374.289524)
			(xy 120.871246 -374.356458) (xy 120.87125 -374.423823) (xy 124.149287 -374.423823) (xy 124.149291 -374.356514)
			(xy 124.15734 -374.289688) (xy 124.173319 -374.224302) (xy 124.196998 -374.161296) (xy 124.228039 -374.101572)
			(xy 124.265996 -374.045986) (xy 124.287788 -374.020334) (xy 124.293594 -374.013195) (xy 124.300103 -373.996)
			(xy 124.300488 -373.986806) (xy 124.300488 -373.828818) (xy 124.30088 -373.818641) (xy 124.308668 -373.799837)
			(xy 124.323064 -373.78545) (xy 124.341873 -373.777673) (xy 124.35205 -373.777256) (xy 125.06833 -373.777256)
			(xy 125.078492 -373.777709) (xy 125.097265 -373.785497) (xy 125.11163 -373.799875) (xy 125.1194 -373.818656)
			(xy 125.119892 -373.828818) (xy 125.119892 -373.986806) (xy 125.120301 -373.995993) (xy 125.126816 -374.013177)
			(xy 125.132592 -374.020334) (xy 125.154338 -374.04602) (xy 125.192286 -374.101603) (xy 125.223319 -374.161322)
			(xy 125.246993 -374.224322) (xy 125.262968 -374.2897) (xy 125.271015 -374.356518) (xy 125.271019 -374.423819)
			(xy 125.271019 -374.423823) (xy 128.549078 -374.423823) (xy 128.549081 -374.356514) (xy 128.55713 -374.289688)
			(xy 128.573109 -374.224303) (xy 128.596788 -374.161296) (xy 128.627828 -374.101572) (xy 128.665784 -374.045985)
			(xy 128.687576 -374.020334) (xy 128.69338 -374.013194) (xy 128.699891 -373.996) (xy 128.700276 -373.986806)
			(xy 128.700276 -373.828818) (xy 128.700679 -373.818643) (xy 128.708465 -373.799841) (xy 128.722858 -373.785454)
			(xy 128.741663 -373.777675) (xy 128.751838 -373.777256) (xy 129.468118 -373.777256) (xy 129.478279 -373.777719)
			(xy 129.497052 -373.785503) (xy 129.511418 -373.799878) (xy 129.519188 -373.818656) (xy 129.51968 -373.828818)
			(xy 129.51968 -373.986806) (xy 129.520092 -373.995993) (xy 129.526605 -374.013177) (xy 129.53238 -374.020334)
			(xy 129.554126 -374.046021) (xy 129.592074 -374.101603) (xy 129.623108 -374.161322) (xy 129.646783 -374.224321)
			(xy 129.662758 -374.289699) (xy 129.670805 -374.356518) (xy 129.670809 -374.423819) (xy 129.670809 -374.423822)
			(xy 159.349132 -374.423822) (xy 159.349136 -374.356514) (xy 159.357184 -374.289689) (xy 159.373161 -374.224305)
			(xy 159.396837 -374.161299) (xy 159.427874 -374.101574) (xy 159.465826 -374.045986) (xy 159.487616 -374.020334)
			(xy 159.493425 -374.013198) (xy 159.499932 -373.996) (xy 159.500316 -373.986806) (xy 159.500316 -373.828818)
			(xy 159.500847 -373.818664) (xy 159.508612 -373.799899) (xy 159.522966 -373.785534) (xy 159.541724 -373.777755)
			(xy 159.551878 -373.777256) (xy 160.268158 -373.777256) (xy 160.278329 -373.777699) (xy 160.297126 -373.785473)
			(xy 160.311513 -373.799854) (xy 160.319297 -373.818647) (xy 160.31972 -373.828818) (xy 160.31972 -373.986806)
			(xy 160.320123 -373.995994) (xy 160.326641 -374.013179) (xy 160.33242 -374.020334) (xy 160.354168 -374.04602)
			(xy 160.39212 -374.1016) (xy 160.423158 -374.161319) (xy 160.446835 -374.224319) (xy 160.462812 -374.289698)
			(xy 160.47086 -374.356517) (xy 160.470864 -374.42382) (xy 160.470857 -374.423882) (xy 163.748901 -374.423882)
			(xy 163.748904 -374.356455) (xy 163.756985 -374.289514) (xy 163.773025 -374.224022) (xy 163.796794 -374.160923)
			(xy 163.827951 -374.101126) (xy 163.866045 -374.045491) (xy 163.887912 -374.019826) (xy 163.893724 -374.012692)
			(xy 163.900229 -373.995493) (xy 163.900612 -373.986298) (xy 163.900612 -373.828818) (xy 163.90114 -373.818696)
			(xy 163.908857 -373.79998) (xy 163.92313 -373.785624) (xy 163.941801 -373.7778) (xy 163.95192 -373.777256)
			(xy 164.6682 -373.777256) (xy 164.678349 -373.777721) (xy 164.697092 -373.785508) (xy 164.711414 -373.799891)
			(xy 164.719122 -373.818668) (xy 164.719508 -373.828818) (xy 164.719508 -373.986298) (xy 164.719917 -373.995485)
			(xy 164.726431 -374.01267) (xy 164.732208 -374.019826) (xy 164.75403 -374.045525) (xy 164.79212 -374.101155)
			(xy 164.823272 -374.160947) (xy 164.847038 -374.224039) (xy 164.863076 -374.289524) (xy 164.871155 -374.356458)
			(xy 164.871159 -374.423822) (xy 168.14922 -374.423822) (xy 168.149224 -374.356515) (xy 168.157272 -374.28969)
			(xy 168.173248 -374.224306) (xy 168.196924 -374.1613) (xy 168.22796 -374.101575) (xy 168.265911 -374.045987)
			(xy 168.2877 -374.020334) (xy 168.293507 -374.013196) (xy 168.300015 -373.996) (xy 168.3004 -373.986806)
			(xy 168.3004 -373.828818) (xy 168.300947 -373.818666) (xy 168.308709 -373.799905) (xy 168.323058 -373.78554)
			(xy 168.341811 -373.777758) (xy 168.351962 -373.777256) (xy 169.068242 -373.777256) (xy 169.078405 -373.777699)
			(xy 169.097178 -373.785491) (xy 169.111543 -373.799872) (xy 169.119312 -373.818655) (xy 169.119804 -373.828818)
			(xy 169.119804 -373.986806) (xy 169.120211 -373.995994) (xy 169.126727 -374.013178) (xy 169.132504 -374.020334)
			(xy 169.154249 -374.046021) (xy 169.192196 -374.101603) (xy 169.223229 -374.161322) (xy 169.246902 -374.224322)
			(xy 169.262877 -374.2897) (xy 169.270924 -374.356518) (xy 169.270928 -374.423819) (xy 169.270928 -374.423823)
			(xy 172.548987 -374.423823) (xy 172.548991 -374.356514) (xy 172.55704 -374.289688) (xy 172.573019 -374.224302)
			(xy 172.596698 -374.161296) (xy 172.627739 -374.101572) (xy 172.665696 -374.045986) (xy 172.687488 -374.020334)
			(xy 172.693294 -374.013195) (xy 172.699803 -373.996) (xy 172.700188 -373.986806) (xy 172.700188 -373.828818)
			(xy 172.70058 -373.818641) (xy 172.708368 -373.799837) (xy 172.722764 -373.78545) (xy 172.741573 -373.777673)
			(xy 172.75175 -373.777256) (xy 173.46803 -373.777256) (xy 173.478192 -373.777709) (xy 173.496965 -373.785497)
			(xy 173.51133 -373.799875) (xy 173.5191 -373.818656) (xy 173.519592 -373.828818) (xy 173.519592 -373.986806)
			(xy 173.520001 -373.995993) (xy 173.526516 -374.013177) (xy 173.532292 -374.020334) (xy 173.554038 -374.04602)
			(xy 173.591986 -374.101603) (xy 173.623019 -374.161322) (xy 173.646693 -374.224322) (xy 173.662668 -374.2897)
			(xy 173.670715 -374.356518) (xy 173.670719 -374.423819) (xy 173.662679 -374.490638) (xy 173.646712 -374.556018)
			(xy 173.623045 -374.61902) (xy 173.592018 -374.678743) (xy 173.554076 -374.73433) (xy 173.532292 -374.759982)
			(xy 173.526477 -374.767114) (xy 173.519974 -374.784315) (xy 173.519592 -374.79351) (xy 173.519592 -375.286778)
			(xy 173.520015 -375.295964) (xy 173.52652 -375.313148) (xy 173.532292 -375.320306) (xy 173.554108 -375.345934)
			(xy 173.592054 -375.401525) (xy 173.623084 -375.461252) (xy 173.646754 -375.52426) (xy 173.662724 -375.589644)
			(xy 173.670765 -375.656469) (xy 173.670763 -375.723776) (xy 173.662716 -375.7906) (xy 173.646741 -375.855984)
			(xy 173.623066 -375.918989) (xy 173.592031 -375.978714) (xy 173.554081 -376.034301) (xy 173.532292 -376.059954)
			(xy 173.526489 -376.067095) (xy 173.519978 -376.084289) (xy 173.519592 -376.093482) (xy 173.519592 -376.25147)
			(xy 173.519043 -376.261622) (xy 173.511284 -376.280385) (xy 173.496935 -376.29475) (xy 173.478182 -376.302531)
			(xy 173.46803 -376.303032) (xy 172.75175 -376.303032) (xy 172.741578 -376.302595) (xy 172.722779 -376.29482)
			(xy 172.708391 -376.280438) (xy 172.700609 -376.261642) (xy 172.700188 -376.25147) (xy 172.700188 -376.093482)
			(xy 172.699789 -376.084294) (xy 172.693268 -376.067109) (xy 172.687488 -376.059954) (xy 172.665728 -376.034278)
			(xy 172.627775 -375.978696) (xy 172.596738 -375.918976) (xy 172.573061 -375.855975) (xy 172.557085 -375.790595)
			(xy 172.549038 -375.723774) (xy 172.549035 -375.656471) (xy 172.557077 -375.589649) (xy 172.573048 -375.524268)
			(xy 172.59672 -375.461265) (xy 172.627752 -375.401542) (xy 172.665701 -375.345957) (xy 172.687488 -375.320306)
			(xy 172.693263 -375.313145) (xy 172.699791 -375.295967) (xy 172.700188 -375.286778) (xy 172.700188 -374.79351)
			(xy 172.699776 -374.784323) (xy 172.693264 -374.767138) (xy 172.687488 -374.759982) (xy 172.665658 -374.734364)
			(xy 172.627707 -374.678774) (xy 172.596673 -374.619046) (xy 172.573 -374.556037) (xy 172.557029 -374.49065)
			(xy 172.548987 -374.423823) (xy 169.270928 -374.423823) (xy 169.262888 -374.490638) (xy 169.246921 -374.556017)
			(xy 169.223255 -374.61902) (xy 169.192229 -374.678743) (xy 169.154288 -374.734329) (xy 169.132504 -374.759982)
			(xy 169.126691 -374.767115) (xy 169.120186 -374.784315) (xy 169.119804 -374.79351) (xy 169.119804 -375.286778)
			(xy 169.120224 -375.295964) (xy 169.126731 -375.313149) (xy 169.132504 -375.320306) (xy 169.15432 -375.345935)
			(xy 169.192265 -375.401525) (xy 169.223295 -375.461253) (xy 169.246964 -375.52426) (xy 169.262933 -375.589645)
			(xy 169.270974 -375.656469) (xy 169.270972 -375.723776) (xy 169.262925 -375.7906) (xy 169.24695 -375.855983)
			(xy 169.223276 -375.918989) (xy 169.192242 -375.978713) (xy 169.154292 -376.034301) (xy 169.132504 -376.059954)
			(xy 169.126702 -376.067096) (xy 169.120191 -376.084289) (xy 169.119804 -376.093482) (xy 169.119804 -376.25147)
			(xy 169.119243 -376.261621) (xy 169.111487 -376.280381) (xy 169.097142 -376.294746) (xy 169.078392 -376.302529)
			(xy 169.068242 -376.303032) (xy 168.351962 -376.303032) (xy 168.341798 -376.302597) (xy 168.323022 -376.294804)
			(xy 168.308657 -376.280421) (xy 168.30089 -376.261635) (xy 168.3004 -376.25147) (xy 168.3004 -376.093482)
			(xy 168.299998 -376.084294) (xy 168.293479 -376.06711) (xy 168.2877 -376.059954) (xy 168.265943 -376.034277)
			(xy 168.227996 -375.978693) (xy 168.196963 -375.918973) (xy 168.173291 -375.855972) (xy 168.157317 -375.790593)
			(xy 168.149271 -375.723774) (xy 168.149268 -375.656472) (xy 168.157309 -375.589652) (xy 168.173277 -375.524272)
			(xy 168.196945 -375.461269) (xy 168.227973 -375.401546) (xy 168.265915 -375.345959) (xy 168.2877 -375.320306)
			(xy 168.293477 -375.313147) (xy 168.300003 -375.295967) (xy 168.3004 -375.286778) (xy 168.3004 -374.79351)
			(xy 168.299985 -374.784323) (xy 168.293475 -374.767139) (xy 168.2877 -374.759982) (xy 168.265872 -374.734363)
			(xy 168.227927 -374.678771) (xy 168.196898 -374.619043) (xy 168.173229 -374.556034) (xy 168.15726 -374.490648)
			(xy 168.14922 -374.423822) (xy 164.871159 -374.423822) (xy 164.871159 -374.423879) (xy 164.863088 -374.490814)
			(xy 164.847057 -374.5563) (xy 164.823298 -374.619396) (xy 164.792152 -374.679191) (xy 164.754069 -374.734825)
			(xy 164.732208 -374.76049) (xy 164.726392 -374.767621) (xy 164.719889 -374.784822) (xy 164.719508 -374.794018)
			(xy 164.719508 -375.28627) (xy 164.719931 -375.295456) (xy 164.726435 -375.31264) (xy 164.732208 -375.319798)
			(xy 164.754101 -375.345439) (xy 164.792188 -375.401077) (xy 164.823337 -375.460877) (xy 164.8471 -375.523977)
			(xy 164.863133 -375.589469) (xy 164.871206 -375.65641) (xy 164.871203 -375.723835) (xy 164.863125 -375.790776)
			(xy 164.847086 -375.856266) (xy 164.823319 -375.919364) (xy 164.792165 -375.979161) (xy 164.754073 -376.034797)
			(xy 164.732208 -376.060462) (xy 164.726404 -376.067602) (xy 164.719893 -376.084796) (xy 164.719508 -376.09399)
			(xy 164.719508 -376.25147) (xy 164.71895 -376.261589) (xy 164.711241 -376.2803) (xy 164.696977 -376.294656)
			(xy 164.678316 -376.302485) (xy 164.6682 -376.303032) (xy 163.95192 -376.303032) (xy 163.941771 -376.302563)
			(xy 163.923025 -376.29478) (xy 163.908702 -376.280398) (xy 163.900996 -376.26162) (xy 163.900612 -376.25147)
			(xy 163.900612 -376.09399) (xy 163.900204 -376.084803) (xy 163.893689 -376.067618) (xy 163.887912 -376.060462)
			(xy 163.866077 -376.034773) (xy 163.827987 -375.979142) (xy 163.796834 -375.919349) (xy 163.773068 -375.856255)
			(xy 163.75703 -375.790769) (xy 163.748951 -375.723833) (xy 163.748949 -375.656412) (xy 163.757022 -375.589475)
			(xy 163.773054 -375.523988) (xy 163.796816 -375.460892) (xy 163.827963 -375.401097) (xy 163.866049 -375.345463)
			(xy 163.887912 -375.319798) (xy 163.893693 -375.312642) (xy 163.900217 -375.29546) (xy 163.900612 -375.28627)
			(xy 163.900612 -374.794018) (xy 163.90019 -374.784832) (xy 163.893684 -374.767648) (xy 163.887912 -374.76049)
			(xy 163.866006 -374.734859) (xy 163.827918 -374.67922) (xy 163.796769 -374.619419) (xy 163.773006 -374.556318)
			(xy 163.756973 -374.490824) (xy 163.748901 -374.423882) (xy 160.470857 -374.423882) (xy 160.462823 -374.49064)
			(xy 160.446853 -374.556021) (xy 160.423184 -374.619023) (xy 160.392153 -374.678745) (xy 160.354206 -374.73433)
			(xy 160.33242 -374.759982) (xy 160.326608 -374.767117) (xy 160.320102 -374.784315) (xy 160.31972 -374.79351)
			(xy 160.31972 -375.286778) (xy 160.320136 -375.295965) (xy 160.326645 -375.313149) (xy 160.33242 -375.320306)
			(xy 160.354238 -375.345933) (xy 160.392189 -375.401522) (xy 160.423223 -375.461249) (xy 160.446896 -375.524257)
			(xy 160.462868 -375.589643) (xy 160.470911 -375.656468) (xy 160.470908 -375.723777) (xy 160.46286 -375.790602)
			(xy 160.446883 -375.855986) (xy 160.423205 -375.918992) (xy 160.392166 -375.978716) (xy 160.354211 -376.034302)
			(xy 160.33242 -376.059954) (xy 160.32662 -376.067097) (xy 160.320107 -376.084289) (xy 160.31972 -376.093482)
			(xy 160.31972 -376.25147) (xy 160.31931 -376.261645) (xy 160.311528 -376.280447) (xy 160.297137 -376.294834)
			(xy 160.278333 -376.302613) (xy 160.268158 -376.303032) (xy 159.551878 -376.303032) (xy 159.541701 -376.302653)
			(xy 159.5229 -376.294855) (xy 159.508515 -376.280456) (xy 159.500737 -376.261647) (xy 159.500316 -376.25147)
			(xy 159.500316 -376.093482) (xy 159.499911 -376.084294) (xy 159.493393 -376.06711) (xy 159.487616 -376.059954)
			(xy 159.465858 -376.034277) (xy 159.42791 -375.978694) (xy 159.396877 -375.918973) (xy 159.373203 -375.855972)
			(xy 159.357229 -375.790593) (xy 159.349183 -375.723774) (xy 159.34918 -375.656471) (xy 159.357221 -375.589651)
			(xy 159.37319 -375.524271) (xy 159.396858 -375.461268) (xy 159.427887 -375.401545) (xy 159.465831 -375.345958)
			(xy 159.487616 -375.320306) (xy 159.493394 -375.313148) (xy 159.499919 -375.295967) (xy 159.500316 -375.286778)
			(xy 159.500316 -374.79351) (xy 159.499897 -374.784324) (xy 159.493389 -374.76714) (xy 159.487616 -374.759982)
			(xy 159.465788 -374.734364) (xy 159.427842 -374.678772) (xy 159.396811 -374.619043) (xy 159.373142 -374.556034)
			(xy 159.357173 -374.490648) (xy 159.349132 -374.423822) (xy 129.670809 -374.423822) (xy 129.662769 -374.490638)
			(xy 129.646801 -374.556018) (xy 129.623134 -374.619021) (xy 129.592107 -374.678743) (xy 129.554164 -374.734329)
			(xy 129.53238 -374.759982) (xy 129.526564 -374.767113) (xy 129.520062 -374.784315) (xy 129.51968 -374.79351)
			(xy 129.51968 -375.286778) (xy 129.520105 -375.295963) (xy 129.526609 -375.313148) (xy 129.53238 -375.320306)
			(xy 129.554197 -375.345934) (xy 129.592143 -375.401524) (xy 129.623174 -375.461252) (xy 129.646845 -375.524259)
			(xy 129.662815 -375.589644) (xy 129.670856 -375.656469) (xy 129.670854 -375.723776) (xy 129.662807 -375.7906)
			(xy 129.646831 -375.855984) (xy 129.623156 -375.91899) (xy 129.59212 -375.978714) (xy 129.554169 -376.034302)
			(xy 129.53238 -376.059954) (xy 129.526576 -376.067094) (xy 129.520066 -376.084288) (xy 129.51968 -376.093482)
			(xy 129.51968 -376.25147) (xy 129.519212 -376.261637) (xy 129.51144 -376.280428) (xy 129.497068 -376.294813)
			(xy 129.478285 -376.302602) (xy 129.468118 -376.303032) (xy 128.751838 -376.303032) (xy 128.741665 -376.302604)
			(xy 128.722866 -376.294826) (xy 128.708478 -376.280441) (xy 128.700697 -376.261643) (xy 128.700276 -376.25147)
			(xy 128.700276 -376.093482) (xy 128.69988 -376.084293) (xy 128.693357 -376.067109) (xy 128.687576 -376.059954)
			(xy 128.665817 -376.034278) (xy 128.627865 -375.978696) (xy 128.596828 -375.918976) (xy 128.573152 -375.855974)
			(xy 128.557176 -375.790595) (xy 128.549129 -375.723774) (xy 128.549126 -375.656471) (xy 128.557168 -375.58965)
			(xy 128.573138 -375.524269) (xy 128.59681 -375.461265) (xy 128.627841 -375.401543) (xy 128.665789 -375.345958)
			(xy 128.687576 -375.320306) (xy 128.69335 -375.313144) (xy 128.699879 -375.295967) (xy 128.700276 -375.286778)
			(xy 128.700276 -374.79351) (xy 128.699866 -374.784323) (xy 128.693353 -374.767138) (xy 128.687576 -374.759982)
			(xy 128.665746 -374.734365) (xy 128.627796 -374.678774) (xy 128.596762 -374.619046) (xy 128.57309 -374.556037)
			(xy 128.557119 -374.49065) (xy 128.549078 -374.423823) (xy 125.271019 -374.423823) (xy 125.262979 -374.490638)
			(xy 125.247012 -374.556018) (xy 125.223345 -374.61902) (xy 125.192318 -374.678743) (xy 125.154376 -374.73433)
			(xy 125.132592 -374.759982) (xy 125.126777 -374.767114) (xy 125.120274 -374.784315) (xy 125.119892 -374.79351)
			(xy 125.119892 -375.286778) (xy 125.120315 -375.295964) (xy 125.12682 -375.313148) (xy 125.132592 -375.320306)
			(xy 125.154408 -375.345934) (xy 125.192354 -375.401525) (xy 125.223384 -375.461252) (xy 125.247054 -375.52426)
			(xy 125.263024 -375.589644) (xy 125.271065 -375.656469) (xy 125.271063 -375.723776) (xy 125.263016 -375.7906)
			(xy 125.247041 -375.855984) (xy 125.223366 -375.918989) (xy 125.192331 -375.978714) (xy 125.154381 -376.034301)
			(xy 125.132592 -376.059954) (xy 125.126789 -376.067095) (xy 125.120278 -376.084289) (xy 125.119892 -376.093482)
			(xy 125.119892 -376.25147) (xy 125.119343 -376.261622) (xy 125.111584 -376.280385) (xy 125.097235 -376.29475)
			(xy 125.078482 -376.302531) (xy 125.06833 -376.303032) (xy 124.35205 -376.303032) (xy 124.341878 -376.302595)
			(xy 124.323079 -376.29482) (xy 124.308691 -376.280438) (xy 124.300909 -376.261642) (xy 124.300488 -376.25147)
			(xy 124.300488 -376.093482) (xy 124.300089 -376.084294) (xy 124.293568 -376.067109) (xy 124.287788 -376.059954)
			(xy 124.266028 -376.034278) (xy 124.228075 -375.978696) (xy 124.197038 -375.918976) (xy 124.173361 -375.855975)
			(xy 124.157385 -375.790595) (xy 124.149338 -375.723774) (xy 124.149335 -375.656471) (xy 124.157377 -375.589649)
			(xy 124.173348 -375.524268) (xy 124.19702 -375.461265) (xy 124.228052 -375.401542) (xy 124.266001 -375.345957)
			(xy 124.287788 -375.320306) (xy 124.293563 -375.313145) (xy 124.300091 -375.295967) (xy 124.300488 -375.286778)
			(xy 124.300488 -374.79351) (xy 124.300076 -374.784323) (xy 124.293564 -374.767138) (xy 124.287788 -374.759982)
			(xy 124.265958 -374.734364) (xy 124.228007 -374.678774) (xy 124.196973 -374.619046) (xy 124.1733 -374.556037)
			(xy 124.157329 -374.49065) (xy 124.149287 -374.423823) (xy 120.87125 -374.423823) (xy 120.87125 -374.423879)
			(xy 120.863178 -374.490814) (xy 120.847147 -374.556301) (xy 120.823388 -374.619396) (xy 120.792242 -374.679191)
			(xy 120.754158 -374.734825) (xy 120.732296 -374.76049) (xy 120.726478 -374.76762) (xy 120.719976 -374.784822)
			(xy 120.719596 -374.794018) (xy 120.719596 -375.28627) (xy 120.720022 -375.295456) (xy 120.726525 -375.31264)
			(xy 120.732296 -375.319798) (xy 120.75419 -375.345439) (xy 120.792278 -375.401077) (xy 120.823427 -375.460876)
			(xy 120.84719 -375.523976) (xy 120.863223 -375.589468) (xy 120.871297 -375.656409) (xy 120.871294 -375.723836)
			(xy 120.863215 -375.790776) (xy 120.847177 -375.856267) (xy 120.823409 -375.919365) (xy 120.792254 -375.979162)
			(xy 120.754162 -376.034797) (xy 120.732296 -376.060462) (xy 120.72649 -376.067601) (xy 120.719981 -376.084796)
			(xy 120.719596 -376.09399) (xy 120.719596 -376.25147) (xy 120.71905 -376.26159) (xy 120.711339 -376.280304)
			(xy 120.697071 -376.29466) (xy 120.678405 -376.302487) (xy 120.668288 -376.303032) (xy 119.952008 -376.303032)
			(xy 119.941858 -376.302572) (xy 119.923112 -376.294786) (xy 119.90879 -376.280401) (xy 119.901084 -376.261621)
			(xy 119.9007 -376.25147) (xy 119.9007 -376.09399) (xy 119.900294 -376.084802) (xy 119.893777 -376.067618)
			(xy 119.888 -376.060462) (xy 119.866166 -376.034772) (xy 119.828076 -375.979141) (xy 119.796924 -375.919349)
			(xy 119.773158 -375.856255) (xy 119.75712 -375.790769) (xy 119.749042 -375.723833) (xy 119.749039 -375.656412)
			(xy 119.757112 -375.589476) (xy 119.773145 -375.523988) (xy 119.796905 -375.460893) (xy 119.828053 -375.401097)
			(xy 119.866138 -375.345463) (xy 119.888 -375.319798) (xy 119.89378 -375.312641) (xy 119.900305 -375.29546)
			(xy 119.9007 -375.28627) (xy 119.9007 -374.794018) (xy 119.900281 -374.784832) (xy 119.893773 -374.767647)
			(xy 119.888 -374.76049) (xy 119.866095 -374.734859) (xy 119.828007 -374.679219) (xy 119.796858 -374.619418)
			(xy 119.773097 -374.556317) (xy 119.757064 -374.490824) (xy 119.748992 -374.423882) (xy 116.470948 -374.423882)
			(xy 116.462914 -374.49064) (xy 116.446944 -374.556021) (xy 116.423273 -374.619024) (xy 116.392242 -374.678746)
			(xy 116.354295 -374.734331) (xy 116.332508 -374.759982) (xy 116.326695 -374.767116) (xy 116.32019 -374.784315)
			(xy 116.319808 -374.79351) (xy 116.319808 -375.286778) (xy 116.320227 -375.295964) (xy 116.326734 -375.313149)
			(xy 116.332508 -375.320306) (xy 116.354327 -375.345933) (xy 116.392278 -375.401522) (xy 116.423313 -375.461249)
			(xy 116.446986 -375.524256) (xy 116.462959 -375.589642) (xy 116.471001 -375.656468) (xy 116.470999 -375.723777)
			(xy 116.462951 -375.790602) (xy 116.446973 -375.855987) (xy 116.423295 -375.918993) (xy 116.392255 -375.978717)
			(xy 116.354299 -376.034303) (xy 116.332508 -376.059954) (xy 116.326707 -376.067096) (xy 116.320195 -376.084289)
			(xy 116.319808 -376.093482) (xy 116.319808 -376.25147) (xy 116.319243 -376.26162) (xy 116.311487 -376.28038)
			(xy 116.297144 -376.294745) (xy 116.278395 -376.302528) (xy 116.268246 -376.303032) (xy 115.551966 -376.303032)
			(xy 115.541802 -376.302594) (xy 115.523027 -376.294803) (xy 115.508662 -376.28042) (xy 115.500894 -376.261634)
			(xy 115.500404 -376.25147) (xy 115.500404 -376.093482) (xy 115.500002 -376.084294) (xy 115.493483 -376.06711)
			(xy 115.487704 -376.059954) (xy 115.465947 -376.034277) (xy 115.427999 -375.978693) (xy 115.396967 -375.918973)
			(xy 115.373294 -375.855972) (xy 115.35732 -375.790593) (xy 115.349274 -375.723774) (xy 115.349271 -375.656472)
			(xy 115.357312 -375.589652) (xy 115.37328 -375.524271) (xy 115.396948 -375.461268) (xy 115.427976 -375.401545)
			(xy 115.465919 -375.345959) (xy 115.487704 -375.320306) (xy 115.493481 -375.313147) (xy 115.500007 -375.295967)
			(xy 115.500404 -375.286778) (xy 115.500404 -374.79351) (xy 115.499988 -374.784323) (xy 115.493478 -374.767139)
			(xy 115.487704 -374.759982) (xy 115.465876 -374.734363) (xy 115.427931 -374.678771) (xy 115.396901 -374.619043)
			(xy 115.373232 -374.556034) (xy 115.357263 -374.490648) (xy 115.349223 -374.423822) (xy 85.670923 -374.423822)
			(xy 85.670923 -374.423879) (xy 85.662851 -374.490815) (xy 85.646818 -374.556302) (xy 85.623057 -374.619398)
			(xy 85.591909 -374.679192) (xy 85.553823 -374.734826) (xy 85.53196 -374.76049) (xy 85.526138 -374.767617)
			(xy 85.519639 -374.784822) (xy 85.51926 -374.794018) (xy 85.51926 -375.28627) (xy 85.519694 -375.295454)
			(xy 85.526192 -375.312639) (xy 85.53196 -375.319798) (xy 85.553855 -375.345438) (xy 85.591945 -375.401075)
			(xy 85.623097 -375.460875) (xy 85.646861 -375.523975) (xy 85.662896 -375.589467) (xy 85.67097 -375.656409)
			(xy 85.670967 -375.723836) (xy 85.662888 -375.790777) (xy 85.646848 -375.856268) (xy 85.623079 -375.919367)
			(xy 85.591922 -375.979163) (xy 85.553827 -376.034797) (xy 85.53196 -376.060462) (xy 85.52615 -376.067597)
			(xy 85.519644 -376.084796) (xy 85.51926 -376.09399) (xy 85.51926 -376.25147) (xy 85.518749 -376.261595)
			(xy 85.511031 -376.280315) (xy 85.496752 -376.294673) (xy 85.478074 -376.302493) (xy 85.467952 -376.303032)
			(xy 84.751672 -376.303032) (xy 84.741565 -376.302539) (xy 84.722893 -376.294798) (xy 84.7086 -376.280504)
			(xy 84.700861 -376.261831) (xy 84.700364 -376.251724) (xy 84.700364 -376.09399) (xy 84.699944 -376.084804)
			(xy 84.693436 -376.06762) (xy 84.687664 -376.060462) (xy 84.665831 -376.034772) (xy 84.627744 -375.97914)
			(xy 84.596594 -375.919347) (xy 84.572829 -375.856253) (xy 84.556793 -375.790768) (xy 84.548715 -375.723833)
			(xy 84.548712 -375.656412) (xy 84.556785 -375.589477) (xy 84.572816 -375.52399) (xy 84.596575 -375.460894)
			(xy 84.62772 -375.401099) (xy 84.665803 -375.345464) (xy 84.687664 -375.319798) (xy 84.693452 -375.312647)
			(xy 84.69997 -375.295461) (xy 84.700364 -375.28627) (xy 84.700364 -374.794018) (xy 84.699931 -374.784834)
			(xy 84.693432 -374.76765) (xy 84.687664 -374.76049) (xy 84.66576 -374.734858) (xy 84.627675 -374.679218)
			(xy 84.596528 -374.619417) (xy 84.572768 -374.556316) (xy 84.556736 -374.490823) (xy 84.548664 -374.423882)
			(xy 81.271132 -374.423882) (xy 81.26306 -374.490815) (xy 81.247028 -374.556302) (xy 81.223267 -374.619397)
			(xy 81.19212 -374.679192) (xy 81.154034 -374.734825) (xy 81.132172 -374.76049) (xy 81.126351 -374.767618)
			(xy 81.119852 -374.784822) (xy 81.119472 -374.794018) (xy 81.119472 -375.28627) (xy 81.119903 -375.295455)
			(xy 81.126403 -375.312639) (xy 81.132172 -375.319798) (xy 81.154066 -375.345438) (xy 81.192156 -375.401076)
			(xy 81.223307 -375.460875) (xy 81.247071 -375.523975) (xy 81.263105 -375.589468) (xy 81.271179 -375.656409)
			(xy 81.271176 -375.723836) (xy 81.263097 -375.790777) (xy 81.247057 -375.856268) (xy 81.223289 -375.919366)
			(xy 81.192133 -375.979163) (xy 81.154039 -376.034797) (xy 81.132172 -376.060462) (xy 81.126363 -376.067598)
			(xy 81.119856 -376.084796) (xy 81.119472 -376.09399) (xy 81.119472 -376.25147) (xy 81.118949 -376.261593)
			(xy 81.111234 -376.280312) (xy 81.096958 -376.294669) (xy 81.078284 -376.302491) (xy 81.068164 -376.303032)
			(xy 80.351884 -376.303032) (xy 80.341778 -376.302529) (xy 80.323106 -376.294792) (xy 80.308813 -376.280501)
			(xy 80.301073 -376.26183) (xy 80.300576 -376.251724) (xy 80.300576 -376.09399) (xy 80.300176 -376.084802)
			(xy 80.293656 -376.067617) (xy 80.287876 -376.060462) (xy 80.266042 -376.034772) (xy 80.227954 -375.97914)
			(xy 80.196804 -375.919347) (xy 80.173039 -375.856254) (xy 80.157002 -375.790768) (xy 80.148924 -375.723833)
			(xy 80.148921 -375.656412) (xy 80.156994 -375.589476) (xy 80.173025 -375.523989) (xy 80.196785 -375.460894)
			(xy 80.227931 -375.401098) (xy 80.266015 -375.345464) (xy 80.287876 -375.319798) (xy 80.293653 -375.312639)
			(xy 80.30018 -375.295459) (xy 80.300576 -375.28627) (xy 80.300576 -374.794018) (xy 80.300163 -374.784831)
			(xy 80.293652 -374.767646) (xy 80.287876 -374.76049) (xy 80.265972 -374.734858) (xy 80.227886 -374.679218)
			(xy 80.196738 -374.619417) (xy 80.172977 -374.556316) (xy 80.156946 -374.490823) (xy 80.148873 -374.423882)
			(xy 76.870804 -374.423882) (xy 76.862772 -374.490638) (xy 76.846805 -374.556018) (xy 76.823138 -374.619021)
			(xy 76.79211 -374.678743) (xy 76.754168 -374.734329) (xy 76.732384 -374.759982) (xy 76.726568 -374.767114)
			(xy 76.720066 -374.784315) (xy 76.719684 -374.79351) (xy 76.719684 -375.286778) (xy 76.720108 -375.295964)
			(xy 76.726613 -375.313148) (xy 76.732384 -375.320306) (xy 76.754201 -375.345934) (xy 76.792147 -375.401525)
			(xy 76.823178 -375.461252) (xy 76.846848 -375.524259) (xy 76.862818 -375.589644) (xy 76.870859 -375.656469)
			(xy 76.870857 -375.723776) (xy 76.86281 -375.7906) (xy 76.846834 -375.855984) (xy 76.823159 -375.91899)
			(xy 76.792124 -375.978714) (xy 76.754173 -376.034302) (xy 76.732384 -376.059954) (xy 76.72658 -376.067094)
			(xy 76.72007 -376.084289) (xy 76.719684 -376.093482) (xy 76.719684 -376.25147) (xy 76.719212 -376.261637)
			(xy 76.711441 -376.280427) (xy 76.69707 -376.294812) (xy 76.678288 -376.302602) (xy 76.668122 -376.303032)
			(xy 75.951842 -376.303032) (xy 75.941669 -376.302601) (xy 75.92287 -376.294824) (xy 75.908482 -376.28044)
			(xy 75.900701 -376.261643) (xy 75.90028 -376.25147) (xy 75.90028 -376.093482) (xy 75.899883 -376.084293)
			(xy 75.893361 -376.067109) (xy 75.88758 -376.059954) (xy 75.865821 -376.034278) (xy 75.827868 -375.978696)
			(xy 75.796831 -375.918976) (xy 75.773155 -375.855975) (xy 75.757179 -375.790595) (xy 75.749132 -375.723774)
			(xy 75.749129 -375.656471) (xy 75.757171 -375.58965) (xy 75.773142 -375.524269) (xy 75.796813 -375.461265)
			(xy 75.827845 -375.401543) (xy 75.865793 -375.345958) (xy 75.88758 -375.320306) (xy 75.893354 -375.313145)
			(xy 75.899883 -375.295967) (xy 75.90028 -375.286778) (xy 75.90028 -374.79351) (xy 75.89987 -374.784323)
			(xy 75.893357 -374.767138) (xy 75.88758 -374.759982) (xy 75.865749 -374.734365) (xy 75.827799 -374.678774)
			(xy 75.796765 -374.619046) (xy 75.773093 -374.556037) (xy 75.757122 -374.49065) (xy 75.749081 -374.423823)
			(xy 72.471044 -374.423823) (xy 72.471044 -374.423879) (xy 72.462972 -374.490814) (xy 72.446941 -374.556301)
			(xy 72.423181 -374.619396) (xy 72.392034 -374.679191) (xy 72.35395 -374.734825) (xy 72.332088 -374.76049)
			(xy 72.326269 -374.76762) (xy 72.319768 -374.784822) (xy 72.319388 -374.794018) (xy 72.319388 -375.28627)
			(xy 72.319815 -375.295455) (xy 72.326317 -375.31264) (xy 72.332088 -375.319798) (xy 72.353982 -375.345439)
			(xy 72.39207 -375.401076) (xy 72.423221 -375.460876) (xy 72.446984 -375.523976) (xy 72.463017 -375.589468)
			(xy 72.471091 -375.656409) (xy 72.471088 -375.723836) (xy 72.463009 -375.790776) (xy 72.44697 -375.856267)
			(xy 72.423202 -375.919365) (xy 72.392047 -375.979162) (xy 72.353954 -376.034797) (xy 72.332088 -376.060462)
			(xy 72.326281 -376.0676) (xy 72.319773 -376.084796) (xy 72.319388 -376.09399) (xy 72.319388 -376.25147)
			(xy 72.31885 -376.261591) (xy 72.311137 -376.280307) (xy 72.296867 -376.294663) (xy 72.278198 -376.302488)
			(xy 72.26808 -376.303032) (xy 71.5518 -376.303032) (xy 71.54165 -376.302579) (xy 71.522904 -376.294789)
			(xy 71.508582 -376.280403) (xy 71.500876 -376.261622) (xy 71.500492 -376.25147) (xy 71.500492 -376.09399)
			(xy 71.500088 -376.084802) (xy 71.49357 -376.067618) (xy 71.487792 -376.060462) (xy 71.465958 -376.034772)
			(xy 71.427869 -375.979141) (xy 71.396717 -375.919348) (xy 71.372952 -375.856255) (xy 71.356914 -375.790769)
			(xy 71.348836 -375.723833) (xy 71.348833 -375.656412) (xy 71.356906 -375.589476) (xy 71.372938 -375.523989)
			(xy 71.396699 -375.460893) (xy 71.427845 -375.401098) (xy 71.46593 -375.345463) (xy 71.487792 -375.319798)
			(xy 71.493571 -375.31264) (xy 71.500096 -375.295459) (xy 71.500492 -375.28627) (xy 71.500492 -374.794018)
			(xy 71.500075 -374.784832) (xy 71.493566 -374.767647) (xy 71.487792 -374.76049) (xy 71.465887 -374.734859)
			(xy 71.4278 -374.679219) (xy 71.396652 -374.619418) (xy 71.37289 -374.556317) (xy 71.356858 -374.490824)
			(xy 71.348786 -374.423882) (xy 46.070774 -374.423882) (xy 46.062742 -374.490639) (xy 46.046773 -374.55602)
			(xy 46.023104 -374.619022) (xy 45.992075 -374.678745) (xy 45.95413 -374.73433) (xy 45.932344 -374.759982)
			(xy 45.926523 -374.76711) (xy 45.920025 -374.784314) (xy 45.919644 -374.79351) (xy 45.919644 -375.286778)
			(xy 45.920077 -375.295962) (xy 45.926576 -375.313146) (xy 45.932344 -375.320306) (xy 45.954162 -375.345934)
			(xy 45.992111 -375.401523) (xy 46.023144 -375.46125) (xy 46.046816 -375.524258) (xy 46.062787 -375.589643)
			(xy 46.070829 -375.656469) (xy 46.070826 -375.723776) (xy 46.062779 -375.790601) (xy 46.046802 -375.855985)
			(xy 46.023125 -375.918991) (xy 45.992088 -375.978716) (xy 45.954134 -376.034302) (xy 45.932344 -376.059954)
			(xy 45.926535 -376.06709) (xy 45.920029 -376.084288) (xy 45.919644 -376.093482) (xy 45.919644 -376.25147)
			(xy 45.919211 -376.261642) (xy 45.911433 -376.280439) (xy 45.897049 -376.294826) (xy 45.878254 -376.302609)
			(xy 45.868082 -376.303032) (xy 45.151802 -376.303032) (xy 45.141627 -376.302634) (xy 45.122826 -376.294844)
			(xy 45.10844 -376.28045) (xy 45.100661 -376.261645) (xy 45.10024 -376.25147) (xy 45.10024 -376.093482)
			(xy 45.09983 -376.084295) (xy 45.093315 -376.067111) (xy 45.08754 -376.059954) (xy 45.065782 -376.034277)
			(xy 45.027832 -375.978695) (xy 44.996798 -375.918974) (xy 44.973123 -375.855973) (xy 44.957148 -375.790594)
			(xy 44.949101 -375.723774) (xy 44.949099 -375.656471) (xy 44.95714 -375.589651) (xy 44.97311 -375.52427)
			(xy 44.996779 -375.461267) (xy 45.027809 -375.401544) (xy 45.065754 -375.345958) (xy 45.08754 -375.320306)
			(xy 45.093322 -375.31315) (xy 45.099844 -375.295968) (xy 45.10024 -375.286778) (xy 45.10024 -374.79351)
			(xy 45.099816 -374.784324) (xy 45.093311 -374.76714) (xy 45.08754 -374.759982) (xy 45.065711 -374.734364)
			(xy 45.027763 -374.678773) (xy 44.996732 -374.619044) (xy 44.973061 -374.556035) (xy 44.957091 -374.490649)
			(xy 44.94905 -374.423823) (xy 41.671014 -374.423823) (xy 41.671014 -374.423879) (xy 41.662941 -374.490816)
			(xy 41.646909 -374.556303) (xy 41.623147 -374.619398) (xy 41.591998 -374.679193) (xy 41.553911 -374.734826)
			(xy 41.532048 -374.76049) (xy 41.526224 -374.767616) (xy 41.519727 -374.784821) (xy 41.519348 -374.794018)
			(xy 41.519348 -375.28627) (xy 41.519784 -375.295454) (xy 41.526281 -375.312638) (xy 41.532048 -375.319798)
			(xy 41.553943 -375.345438) (xy 41.592035 -375.401075) (xy 41.623187 -375.460874) (xy 41.646952 -375.523974)
			(xy 41.662987 -375.589467) (xy 41.671061 -375.656409) (xy 41.671058 -375.723836) (xy 41.662978 -375.790777)
			(xy 41.646938 -375.856269) (xy 41.623168 -375.919367) (xy 41.592011 -375.979164) (xy 41.553916 -376.034798)
			(xy 41.532048 -376.060462) (xy 41.526236 -376.067596) (xy 41.519732 -376.084795) (xy 41.519348 -376.09399)
			(xy 41.519348 -376.25147) (xy 41.518849 -376.261596) (xy 41.511129 -376.280319) (xy 41.496846 -376.294677)
			(xy 41.478164 -376.302495) (xy 41.46804 -376.303032) (xy 40.75176 -376.303032) (xy 40.741607 -376.302612)
			(xy 40.72286 -376.294809) (xy 40.708539 -376.280413) (xy 40.700835 -376.261625) (xy 40.700452 -376.25147)
			(xy 40.700452 -376.09399) (xy 40.700035 -376.084804) (xy 40.693525 -376.06762) (xy 40.687752 -376.060462)
			(xy 40.665916 -376.034773) (xy 40.627823 -375.979143) (xy 40.596668 -375.919351) (xy 40.5729 -375.856257)
			(xy 40.55686 -375.79077) (xy 40.548781 -375.723834) (xy 40.548779 -375.656411) (xy 40.556852 -375.589474)
			(xy 40.572886 -375.523986) (xy 40.596649 -375.46089) (xy 40.627799 -375.401095) (xy 40.665888 -375.345462)
			(xy 40.687752 -375.319798) (xy 40.693538 -375.312646) (xy 40.700058 -375.29546) (xy 40.700452 -375.28627)
			(xy 40.700452 -374.794018) (xy 40.700022 -374.784833) (xy 40.693521 -374.767649) (xy 40.687752 -374.76049)
			(xy 40.665845 -374.73486) (xy 40.627754 -374.679221) (xy 40.596602 -374.619421) (xy 40.572838 -374.556319)
			(xy 40.556804 -374.490825) (xy 40.548731 -374.423882) (xy 37.271223 -374.423882) (xy 37.263151 -374.490815)
			(xy 37.247118 -374.556302) (xy 37.223357 -374.619398) (xy 37.192209 -374.679192) (xy 37.154123 -374.734826)
			(xy 37.13226 -374.76049) (xy 37.126438 -374.767617) (xy 37.119939 -374.784822) (xy 37.11956 -374.794018)
			(xy 37.11956 -375.28627) (xy 37.119994 -375.295454) (xy 37.126492 -375.312639) (xy 37.13226 -375.319798)
			(xy 37.154155 -375.345438) (xy 37.192245 -375.401075) (xy 37.223397 -375.460875) (xy 37.247161 -375.523975)
			(xy 37.263196 -375.589467) (xy 37.27127 -375.656409) (xy 37.271267 -375.723836) (xy 37.263188 -375.790777)
			(xy 37.247148 -375.856268) (xy 37.223379 -375.919367) (xy 37.192222 -375.979163) (xy 37.154127 -376.034797)
			(xy 37.13226 -376.060462) (xy 37.12645 -376.067597) (xy 37.119944 -376.084796) (xy 37.11956 -376.09399)
			(xy 37.11956 -376.25147) (xy 37.119049 -376.261595) (xy 37.111331 -376.280315) (xy 37.097052 -376.294673)
			(xy 37.078374 -376.302493) (xy 37.068252 -376.303032) (xy 36.351972 -376.303032) (xy 36.34182 -376.302602)
			(xy 36.323073 -376.294803) (xy 36.308752 -376.28041) (xy 36.301047 -376.261624) (xy 36.300664 -376.25147)
			(xy 36.300664 -376.09399) (xy 36.300244 -376.084804) (xy 36.293736 -376.06762) (xy 36.287964 -376.060462)
			(xy 36.266131 -376.034772) (xy 36.228044 -375.97914) (xy 36.196894 -375.919347) (xy 36.173129 -375.856253)
			(xy 36.157093 -375.790768) (xy 36.149015 -375.723833) (xy 36.149012 -375.656412) (xy 36.157085 -375.589477)
			(xy 36.173116 -375.52399) (xy 36.196875 -375.460894) (xy 36.22802 -375.401099) (xy 36.266103 -375.345464)
			(xy 36.287964 -375.319798) (xy 36.293752 -375.312647) (xy 36.30027 -375.295461) (xy 36.300664 -375.28627)
			(xy 36.300664 -374.794018) (xy 36.300231 -374.784834) (xy 36.293732 -374.76765) (xy 36.287964 -374.76049)
			(xy 36.26606 -374.734858) (xy 36.227975 -374.679218) (xy 36.196828 -374.619417) (xy 36.173068 -374.556316)
			(xy 36.157036 -374.490823) (xy 36.148964 -374.423882) (xy 32.870895 -374.423882) (xy 32.862863 -374.490639)
			(xy 32.846895 -374.556018) (xy 32.823227 -374.619021) (xy 32.7922 -374.678743) (xy 32.754257 -374.73433)
			(xy 32.732472 -374.759982) (xy 32.726654 -374.767112) (xy 32.720153 -374.784314) (xy 32.719772 -374.79351)
			(xy 32.719772 -375.286778) (xy 32.720199 -375.295963) (xy 32.726702 -375.313147) (xy 32.732472 -375.320306)
			(xy 32.754289 -375.345934) (xy 32.792236 -375.401524) (xy 32.823268 -375.461251) (xy 32.846938 -375.524259)
			(xy 32.862909 -375.589644) (xy 32.87095 -375.656469) (xy 32.870948 -375.723776) (xy 32.862901 -375.790601)
			(xy 32.846925 -375.855984) (xy 32.823249 -375.91899) (xy 32.792213 -375.978715) (xy 32.754261 -376.034302)
			(xy 32.732472 -376.059954) (xy 32.726666 -376.067093) (xy 32.720158 -376.084288) (xy 32.719772 -376.093482)
			(xy 32.719772 -376.25147) (xy 32.719312 -376.261638) (xy 32.711538 -376.28043) (xy 32.697164 -376.294816)
			(xy 32.678378 -376.302604) (xy 32.66821 -376.303032) (xy 31.95193 -376.303032) (xy 31.941757 -376.302611)
			(xy 31.922957 -376.29483) (xy 31.90857 -376.280443) (xy 31.900789 -376.261643) (xy 31.900368 -376.25147)
			(xy 31.900368 -376.093482) (xy 31.899951 -376.084296) (xy 31.89344 -376.067112) (xy 31.887668 -376.059954)
			(xy 31.865909 -376.034278) (xy 31.827957 -375.978696) (xy 31.796921 -375.918976) (xy 31.773245 -375.855974)
			(xy 31.75727 -375.790595) (xy 31.749223 -375.723774) (xy 31.74922 -375.656471) (xy 31.757261 -375.58965)
			(xy 31.773232 -375.524269) (xy 31.796903 -375.461266) (xy 31.827934 -375.401543) (xy 31.865881 -375.345958)
			(xy 31.887668 -375.320306) (xy 31.893453 -375.313153) (xy 31.899973 -375.295968) (xy 31.900368 -375.286778)
			(xy 31.900368 -374.79351) (xy 31.899938 -374.784325) (xy 31.893436 -374.767142) (xy 31.887668 -374.759982)
			(xy 31.865838 -374.734364) (xy 31.827888 -374.678774) (xy 31.796855 -374.619046) (xy 31.773184 -374.556036)
			(xy 31.757213 -374.49065) (xy 31.749171 -374.423823) (xy 28.471155 -374.423823) (xy 28.471155 -374.42387)
			(xy 28.463079 -374.490809) (xy 28.447044 -374.556297) (xy 28.423279 -374.619394) (xy 28.392129 -374.67919)
			(xy 28.35404 -374.734825) (xy 28.332176 -374.76049) (xy 28.326356 -374.767618) (xy 28.319856 -374.784822)
			(xy 28.319476 -374.794018) (xy 28.319476 -375.28627) (xy 28.319906 -375.295455) (xy 28.326407 -375.312639)
			(xy 28.332176 -375.319798) (xy 28.35407 -375.345439) (xy 28.39216 -375.401076) (xy 28.42331 -375.460875)
			(xy 28.447074 -375.523976) (xy 28.463108 -375.589468) (xy 28.471182 -375.656409) (xy 28.471179 -375.723836)
			(xy 28.4631 -375.790777) (xy 28.447061 -375.856268) (xy 28.423292 -375.919366) (xy 28.392136 -375.979163)
			(xy 28.354043 -376.034797) (xy 28.332176 -376.060462) (xy 28.326368 -376.067599) (xy 28.319861 -376.084796)
			(xy 28.319476 -376.09399) (xy 28.319476 -376.25147) (xy 28.31895 -376.261593) (xy 28.311235 -376.28031)
			(xy 28.29696 -376.294667) (xy 28.278288 -376.30249) (xy 28.268168 -376.303032) (xy 27.551888 -376.303032)
			(xy 27.541783 -376.302525) (xy 27.52311 -376.29479) (xy 27.508817 -376.2805) (xy 27.501077 -376.261829)
			(xy 27.50058 -376.251724) (xy 27.50058 -376.09399) (xy 27.500179 -376.084802) (xy 27.493659 -376.067617)
			(xy 27.48788 -376.060462) (xy 27.466046 -376.034772) (xy 27.427958 -375.979141) (xy 27.396807 -375.919348)
			(xy 27.373042 -375.856254) (xy 27.357005 -375.790768) (xy 27.348927 -375.723833) (xy 27.348924 -375.656412)
			(xy 27.356997 -375.589476) (xy 27.373029 -375.523989) (xy 27.396789 -375.460894) (xy 27.427935 -375.401098)
			(xy 27.466019 -375.345464) (xy 27.48788 -375.319798) (xy 27.493658 -375.312639) (xy 27.500184 -375.295459)
			(xy 27.50058 -375.28627) (xy 27.50058 -374.794018) (xy 27.500166 -374.784831) (xy 27.493655 -374.767646)
			(xy 27.48788 -374.76049) (xy 27.466014 -374.734827) (xy 27.427924 -374.679192) (xy 27.396773 -374.619396)
			(xy 27.373009 -374.556299) (xy 27.356973 -374.490809) (xy 27.348897 -374.423871) (xy 0.508 -374.423871)
			(xy 0.508 -376.756551) (xy 29.549067 -376.756551) (xy 29.557111 -376.689729) (xy 29.573083 -376.624347)
			(xy 29.596754 -376.561343) (xy 29.627786 -376.501619) (xy 29.665733 -376.446032) (xy 29.68752 -376.42038)
			(xy 29.69331 -376.41323) (xy 29.699828 -376.396043) (xy 29.70022 -376.386852) (xy 29.70022 -375.893584)
			(xy 29.699813 -375.884397) (xy 29.693297 -375.867212) (xy 29.68752 -375.860056) (xy 29.665765 -375.834378)
			(xy 29.627816 -375.778794) (xy 29.596782 -375.719074) (xy 29.573109 -375.656073) (xy 29.557134 -375.590694)
			(xy 29.549088 -375.523875) (xy 29.549085 -375.456573) (xy 29.557126 -375.389753) (xy 29.573095 -375.324373)
			(xy 29.596763 -375.26137) (xy 29.627791 -375.201647) (xy 29.665735 -375.146061) (xy 29.68752 -375.120408)
			(xy 29.693298 -375.11325) (xy 29.699823 -375.096069) (xy 29.70022 -375.08688) (xy 29.70022 -374.928638)
			(xy 29.700695 -374.918471) (xy 29.708464 -374.899681) (xy 29.722834 -374.885295) (xy 29.741616 -374.877506)
			(xy 29.751782 -374.877076) (xy 30.468062 -374.877076) (xy 30.478236 -374.877496) (xy 30.497037 -374.885276)
			(xy 30.511424 -374.899663) (xy 30.519204 -374.918464) (xy 30.519624 -374.928638) (xy 30.519624 -375.08688)
			(xy 30.520038 -375.096067) (xy 30.526548 -375.113252) (xy 30.532324 -375.120408) (xy 30.554144 -375.146034)
			(xy 30.592094 -375.201623) (xy 30.623128 -375.26135) (xy 30.646801 -375.324358) (xy 30.662773 -375.389744)
			(xy 30.670815 -375.45657) (xy 30.670812 -375.523878) (xy 30.662764 -375.590704) (xy 30.646787 -375.656088)
			(xy 30.623109 -375.719094) (xy 30.59207 -375.778818) (xy 30.554115 -375.834404) (xy 30.532324 -375.860056)
			(xy 30.526524 -375.867199) (xy 30.520011 -375.884391) (xy 30.519624 -375.893584) (xy 30.519624 -376.386852)
			(xy 30.520052 -376.396037) (xy 30.526553 -376.413222) (xy 30.532324 -376.42038) (xy 30.554117 -376.446028)
			(xy 30.592068 -376.501615) (xy 30.623103 -376.561338) (xy 30.646777 -376.624343) (xy 30.662751 -376.689726)
			(xy 30.670795 -376.75655) (xy 30.670795 -376.823856) (xy 30.670788 -376.823915) (xy 33.948836 -376.823915)
			(xy 33.948836 -376.756491) (xy 33.956911 -376.689553) (xy 33.972947 -376.624064) (xy 33.996711 -376.560967)
			(xy 34.027862 -376.501171) (xy 34.065952 -376.445537) (xy 34.087816 -376.419872) (xy 34.093609 -376.412724)
			(xy 34.100125 -376.395536) (xy 34.100516 -376.386344) (xy 34.100516 -375.894092) (xy 34.100106 -375.884905)
			(xy 34.093592 -375.867721) (xy 34.087816 -375.860564) (xy 34.065983 -375.834873) (xy 34.027892 -375.779243)
			(xy 33.996739 -375.71945) (xy 33.972973 -375.656357) (xy 33.956934 -375.59087) (xy 33.948856 -375.523935)
			(xy 33.948853 -375.456513) (xy 33.956926 -375.389577) (xy 33.972958 -375.324089) (xy 33.99672 -375.260994)
			(xy 34.027867 -375.201199) (xy 34.065953 -375.145565) (xy 34.087816 -375.1199) (xy 34.093597 -375.112744)
			(xy 34.10012 -375.095562) (xy 34.100516 -375.086372) (xy 34.100516 -374.928638) (xy 34.101057 -374.918517)
			(xy 34.108768 -374.899801) (xy 34.123038 -374.885444) (xy 34.141706 -374.87762) (xy 34.151824 -374.877076)
			(xy 34.868104 -374.877076) (xy 34.878255 -374.877518) (xy 34.897003 -374.88531) (xy 34.911325 -374.8997)
			(xy 34.919029 -374.918485) (xy 34.919412 -374.928638) (xy 34.919412 -375.086372) (xy 34.919833 -375.095558)
			(xy 34.926339 -375.112743) (xy 34.932112 -375.1199) (xy 34.954007 -375.14554) (xy 34.992094 -375.201178)
			(xy 35.023243 -375.260978) (xy 35.047004 -375.324078) (xy 35.063037 -375.38957) (xy 35.07111 -375.456511)
			(xy 35.071108 -375.523937) (xy 35.063029 -375.590877) (xy 35.04699 -375.656368) (xy 35.023223 -375.719466)
			(xy 34.992069 -375.779263) (xy 34.953977 -375.834899) (xy 34.932112 -375.860564) (xy 34.926307 -375.867703)
			(xy 34.919797 -375.884898) (xy 34.919412 -375.894092) (xy 34.919412 -376.386344) (xy 34.919798 -376.395534)
			(xy 34.926328 -376.412718) (xy 34.932112 -376.419872) (xy 34.953979 -376.445534) (xy 34.992067 -376.501169)
			(xy 35.023217 -376.560966) (xy 35.046981 -376.624063) (xy 35.063015 -376.689553) (xy 35.071091 -376.756491)
			(xy 35.071091 -376.756551) (xy 38.349155 -376.756551) (xy 38.357198 -376.689729) (xy 38.37317 -376.624348)
			(xy 38.396841 -376.561343) (xy 38.427872 -376.50162) (xy 38.465818 -376.446033) (xy 38.487604 -376.42038)
			(xy 38.493392 -376.413229) (xy 38.499912 -376.396043) (xy 38.500304 -376.386852) (xy 38.500304 -375.893584)
			(xy 38.499901 -375.884396) (xy 38.493382 -375.867212) (xy 38.487604 -375.860056) (xy 38.465849 -375.834378)
			(xy 38.427901 -375.778794) (xy 38.396869 -375.719074) (xy 38.373195 -375.656073) (xy 38.357221 -375.590694)
			(xy 38.349175 -375.523875) (xy 38.349172 -375.456573) (xy 38.357213 -375.389753) (xy 38.373181 -375.324373)
			(xy 38.396849 -375.26137) (xy 38.427876 -375.201647) (xy 38.465819 -375.146061) (xy 38.487604 -375.120408)
			(xy 38.49338 -375.113248) (xy 38.499907 -375.096069) (xy 38.500304 -375.08688) (xy 38.500304 -374.928638)
			(xy 38.500794 -374.918473) (xy 38.50856 -374.899686) (xy 38.522925 -374.885301) (xy 38.541702 -374.877508)
			(xy 38.551866 -374.877076) (xy 39.268146 -374.877076) (xy 39.278311 -374.877497) (xy 39.297089 -374.885293)
			(xy 39.311454 -374.899682) (xy 39.31922 -374.918472) (xy 39.319708 -374.928638) (xy 39.319708 -375.08688)
			(xy 39.320126 -375.096066) (xy 39.326634 -375.113251) (xy 39.332408 -375.120408) (xy 39.354229 -375.146034)
			(xy 39.39218 -375.201623) (xy 39.423215 -375.261349) (xy 39.446888 -375.324357) (xy 39.462861 -375.389743)
			(xy 39.470903 -375.45657) (xy 39.4709 -375.523878) (xy 39.462852 -375.590704) (xy 39.446874 -375.656089)
			(xy 39.423195 -375.719095) (xy 39.392155 -375.778819) (xy 39.354199 -375.834405) (xy 39.332408 -375.860056)
			(xy 39.326606 -375.867197) (xy 39.320094 -375.884391) (xy 39.319708 -375.893584) (xy 39.319708 -376.386852)
			(xy 39.320139 -376.396037) (xy 39.326638 -376.413222) (xy 39.332408 -376.42038) (xy 39.354201 -376.446028)
			(xy 39.392153 -376.501614) (xy 39.423189 -376.561338) (xy 39.446864 -376.624343) (xy 39.462839 -376.689726)
			(xy 39.470883 -376.75655) (xy 39.470883 -376.823856) (xy 39.470876 -376.823915) (xy 42.748924 -376.823915)
			(xy 42.748924 -376.756491) (xy 42.756999 -376.689553) (xy 42.773034 -376.624064) (xy 42.796798 -376.560968)
			(xy 42.827948 -376.501172) (xy 42.866036 -376.445537) (xy 42.8879 -376.419872) (xy 42.893691 -376.412723)
			(xy 42.900209 -376.395535) (xy 42.9006 -376.386344) (xy 42.9006 -375.894092) (xy 42.900194 -375.884904)
			(xy 42.893677 -375.86772) (xy 42.8879 -375.860564) (xy 42.866067 -375.834873) (xy 42.827978 -375.779242)
			(xy 42.796826 -375.719449) (xy 42.77306 -375.656356) (xy 42.757022 -375.59087) (xy 42.748944 -375.523935)
			(xy 42.748941 -375.456513) (xy 42.757013 -375.389577) (xy 42.773045 -375.32409) (xy 42.796806 -375.260995)
			(xy 42.827953 -375.201199) (xy 42.866038 -375.145565) (xy 42.8879 -375.1199) (xy 42.893679 -375.112742)
			(xy 42.900204 -375.095561) (xy 42.9006 -375.086372) (xy 42.9006 -374.928638) (xy 42.901157 -374.918519)
			(xy 42.908865 -374.899806) (xy 42.923129 -374.88545) (xy 42.941792 -374.877622) (xy 42.951908 -374.877076)
			(xy 43.668188 -374.877076) (xy 43.678338 -374.877531) (xy 43.697086 -374.885318) (xy 43.711409 -374.899704)
			(xy 43.719113 -374.918486) (xy 43.719496 -374.928638) (xy 43.719496 -375.086372) (xy 43.719921 -375.095558)
			(xy 43.726424 -375.112742) (xy 43.732196 -375.1199) (xy 43.754092 -375.145539) (xy 43.79218 -375.201177)
			(xy 43.823329 -375.260977) (xy 43.847092 -375.324077) (xy 43.863125 -375.38957) (xy 43.871198 -375.456511)
			(xy 43.871196 -375.523937) (xy 43.863116 -375.590878) (xy 43.847077 -375.656369) (xy 43.823309 -375.719467)
			(xy 43.792155 -375.779264) (xy 43.754062 -375.834899) (xy 43.732196 -375.860564) (xy 43.726389 -375.867702)
			(xy 43.719881 -375.884898) (xy 43.719496 -375.894092) (xy 43.719496 -376.386344) (xy 43.719886 -376.395533)
			(xy 43.726414 -376.412717) (xy 43.732196 -376.419872) (xy 43.754064 -376.445534) (xy 43.792153 -376.501169)
			(xy 43.823304 -376.560965) (xy 43.847068 -376.624063) (xy 43.863103 -376.689552) (xy 43.871179 -376.756491)
			(xy 43.871178 -376.823856) (xy 47.149219 -376.823856) (xy 47.149219 -376.75655) (xy 47.157264 -376.689727)
			(xy 47.173238 -376.624344) (xy 47.196912 -376.56134) (xy 47.227948 -376.501617) (xy 47.265899 -376.446031)
			(xy 47.287688 -376.42038) (xy 47.293474 -376.413227) (xy 47.299995 -376.396043) (xy 47.300388 -376.386852)
			(xy 47.300388 -375.893584) (xy 47.299988 -375.884396) (xy 47.293468 -375.867211) (xy 47.287688 -375.860056)
			(xy 47.26593 -375.834379) (xy 47.227977 -375.778797) (xy 47.19694 -375.719077) (xy 47.173263 -375.656076)
			(xy 47.157287 -375.590696) (xy 47.149239 -375.523876) (xy 47.149236 -375.456572) (xy 47.157278 -375.389751)
			(xy 47.173249 -375.32437) (xy 47.19692 -375.261367) (xy 47.227952 -375.201644) (xy 47.265901 -375.146059)
			(xy 47.287688 -375.120408) (xy 47.293462 -375.113247) (xy 47.299991 -375.096069) (xy 47.300388 -375.08688)
			(xy 47.300388 -374.928892) (xy 47.300815 -374.918739) (xy 47.308611 -374.899989) (xy 47.323006 -374.885666)
			(xy 47.341795 -374.877965) (xy 47.35195 -374.877584) (xy 48.06823 -374.877584) (xy 48.078364 -374.878003)
			(xy 48.097094 -374.885749) (xy 48.111451 -374.900056) (xy 48.119261 -374.91876) (xy 48.119792 -374.928892)
			(xy 48.119792 -375.08688) (xy 48.120214 -375.096066) (xy 48.12672 -375.11325) (xy 48.132492 -375.120408)
			(xy 48.15431 -375.146035) (xy 48.192256 -375.201626) (xy 48.223286 -375.261353) (xy 48.246956 -375.324361)
			(xy 48.262926 -375.389746) (xy 48.270967 -375.456571) (xy 48.270964 -375.523878) (xy 48.262917 -375.590702)
			(xy 48.246942 -375.656085) (xy 48.223267 -375.719091) (xy 48.192231 -375.778816) (xy 48.154281 -375.834403)
			(xy 48.132492 -375.860056) (xy 48.126688 -375.867196) (xy 48.120178 -375.884391) (xy 48.119792 -375.893584)
			(xy 48.119792 -376.386852) (xy 48.120227 -376.396037) (xy 48.126724 -376.413221) (xy 48.132492 -376.42038)
			(xy 48.154283 -376.446029) (xy 48.192229 -376.501617) (xy 48.223261 -376.561341) (xy 48.246932 -376.624346)
			(xy 48.262904 -376.689728) (xy 48.270947 -376.756551) (xy 73.548976 -376.756551) (xy 73.55702 -376.689728)
			(xy 73.572992 -376.624347) (xy 73.596664 -376.561342) (xy 73.627697 -376.501619) (xy 73.665645 -376.446032)
			(xy 73.687432 -376.42038) (xy 73.693224 -376.413231) (xy 73.699741 -376.396043) (xy 73.700132 -376.386852)
			(xy 73.700132 -375.893584) (xy 73.699722 -375.884397) (xy 73.693208 -375.867213) (xy 73.687432 -375.860056)
			(xy 73.665676 -375.834378) (xy 73.627727 -375.778795) (xy 73.596693 -375.719075) (xy 73.573018 -375.656074)
			(xy 73.557043 -375.590695) (xy 73.548997 -375.523875) (xy 73.548994 -375.456573) (xy 73.557035 -375.389753)
			(xy 73.573004 -375.324372) (xy 73.596673 -375.261369) (xy 73.627702 -375.201647) (xy 73.665647 -375.14606)
			(xy 73.687432 -375.120408) (xy 73.693212 -375.113251) (xy 73.699736 -375.096069) (xy 73.700132 -375.08688)
			(xy 73.700132 -374.928638) (xy 73.700595 -374.91847) (xy 73.708366 -374.899677) (xy 73.72274 -374.885291)
			(xy 73.741526 -374.877504) (xy 73.751694 -374.877076) (xy 74.467974 -374.877076) (xy 74.478149 -374.877486)
			(xy 74.49695 -374.88527) (xy 74.511337 -374.89966) (xy 74.519116 -374.918463) (xy 74.519536 -374.928638)
			(xy 74.519536 -375.08688) (xy 74.51997 -375.096064) (xy 74.526469 -375.113248) (xy 74.532236 -375.120408)
			(xy 74.554056 -375.146034) (xy 74.592006 -375.201623) (xy 74.623039 -375.26135) (xy 74.646711 -375.324358)
			(xy 74.662683 -375.389744) (xy 74.670725 -375.45657) (xy 74.670722 -375.523878) (xy 74.662674 -375.590703)
			(xy 74.646697 -375.656088) (xy 74.623019 -375.719094) (xy 74.591981 -375.778818) (xy 74.554027 -375.834404)
			(xy 74.532236 -375.860056) (xy 74.526425 -375.867191) (xy 74.519921 -375.88439) (xy 74.519536 -375.893584)
			(xy 74.519536 -376.386852) (xy 74.519983 -376.396035) (xy 74.526473 -376.413219) (xy 74.532236 -376.42038)
			(xy 74.554028 -376.446029) (xy 74.591979 -376.501615) (xy 74.623013 -376.561339) (xy 74.646687 -376.624344)
			(xy 74.66266 -376.689727) (xy 74.670704 -376.75655) (xy 74.670704 -376.823856) (xy 74.670697 -376.823915)
			(xy 77.948745 -376.823915) (xy 77.948745 -376.756491) (xy 77.956821 -376.689553) (xy 77.972856 -376.624063)
			(xy 77.996621 -376.560967) (xy 78.027773 -376.501171) (xy 78.065863 -376.445537) (xy 78.087728 -376.419872)
			(xy 78.093523 -376.412726) (xy 78.100038 -376.395536) (xy 78.100428 -376.386344) (xy 78.100428 -375.894092)
			(xy 78.100016 -375.884905) (xy 78.093503 -375.867721) (xy 78.087728 -375.860564) (xy 78.065894 -375.834873)
			(xy 78.027803 -375.779243) (xy 77.996649 -375.719451) (xy 77.972882 -375.656357) (xy 77.956844 -375.590871)
			(xy 77.948765 -375.523935) (xy 77.948762 -375.456513) (xy 77.956835 -375.389577) (xy 77.972868 -375.324089)
			(xy 77.99663 -375.260993) (xy 78.027778 -375.201198) (xy 78.065865 -375.145565) (xy 78.087728 -375.1199)
			(xy 78.093511 -375.112745) (xy 78.100033 -375.095562) (xy 78.100428 -375.086372) (xy 78.100428 -374.928638)
			(xy 78.100958 -374.918515) (xy 78.108671 -374.899797) (xy 78.122944 -374.88544) (xy 78.141616 -374.877618)
			(xy 78.151736 -374.877076) (xy 78.868016 -374.877076) (xy 78.878123 -374.877572) (xy 78.896797 -374.88531)
			(xy 78.91109 -374.899603) (xy 78.918828 -374.918277) (xy 78.919324 -374.928384) (xy 78.919324 -375.086372)
			(xy 78.919742 -375.095558) (xy 78.92625 -375.112743) (xy 78.932024 -375.1199) (xy 78.953919 -375.14554)
			(xy 78.992005 -375.201178) (xy 79.023153 -375.260978) (xy 79.046914 -375.324079) (xy 79.062947 -375.38957)
			(xy 79.07102 -375.456511) (xy 79.071017 -375.523937) (xy 79.062938 -375.590877) (xy 79.0469 -375.656367)
			(xy 79.023133 -375.719466) (xy 78.99198 -375.779263) (xy 78.953889 -375.834898) (xy 78.932024 -375.860564)
			(xy 78.926221 -375.867704) (xy 78.919709 -375.884898) (xy 78.919324 -375.894092) (xy 78.919324 -376.386344)
			(xy 78.919708 -376.395534) (xy 78.926239 -376.412718) (xy 78.932024 -376.419872) (xy 78.953891 -376.445534)
			(xy 78.991978 -376.50117) (xy 79.023127 -376.560967) (xy 79.04689 -376.624064) (xy 79.062925 -376.689553)
			(xy 79.071 -376.756491) (xy 79.071 -376.756551) (xy 82.349064 -376.756551) (xy 82.357108 -376.689729)
			(xy 82.373079 -376.624347) (xy 82.396751 -376.561343) (xy 82.427782 -376.501619) (xy 82.465729 -376.446032)
			(xy 82.487516 -376.42038) (xy 82.493305 -376.41323) (xy 82.499824 -376.396043) (xy 82.500216 -376.386852)
			(xy 82.500216 -375.893584) (xy 82.49981 -375.884396) (xy 82.493293 -375.867212) (xy 82.487516 -375.860056)
			(xy 82.46576 -375.834378) (xy 82.427812 -375.778795) (xy 82.396779 -375.719074) (xy 82.373105 -375.656073)
			(xy 82.357131 -375.590694) (xy 82.349084 -375.523875) (xy 82.349081 -375.456573) (xy 82.357122 -375.389753)
			(xy 82.373091 -375.324373) (xy 82.396759 -375.26137) (xy 82.427787 -375.201647) (xy 82.465731 -375.14606)
			(xy 82.487516 -375.120408) (xy 82.493294 -375.113249) (xy 82.499819 -375.096069) (xy 82.500216 -375.08688)
			(xy 82.500216 -374.928638) (xy 82.500694 -374.918472) (xy 82.508463 -374.899682) (xy 82.522832 -374.885297)
			(xy 82.541612 -374.877506) (xy 82.551778 -374.877076) (xy 83.268058 -374.877076) (xy 83.278232 -374.877499)
			(xy 83.297033 -374.885277) (xy 83.31142 -374.899664) (xy 83.3192 -374.918464) (xy 83.31962 -374.928638)
			(xy 83.31962 -375.08688) (xy 83.320035 -375.096067) (xy 83.326545 -375.113251) (xy 83.33232 -375.120408)
			(xy 83.35414 -375.146034) (xy 83.392091 -375.201623) (xy 83.423125 -375.26135) (xy 83.446798 -375.324358)
			(xy 83.46277 -375.389744) (xy 83.470812 -375.45657) (xy 83.470809 -375.523878) (xy 83.462761 -375.590704)
			(xy 83.446784 -375.656088) (xy 83.423105 -375.719094) (xy 83.392066 -375.778818) (xy 83.354111 -375.834404)
			(xy 83.33232 -375.860056) (xy 83.326519 -375.867199) (xy 83.320007 -375.884391) (xy 83.31962 -375.893584)
			(xy 83.31962 -376.386852) (xy 83.320049 -376.396037) (xy 83.326549 -376.413222) (xy 83.33232 -376.42038)
			(xy 83.354113 -376.446028) (xy 83.392064 -376.501614) (xy 83.4231 -376.561338) (xy 83.446774 -376.624343)
			(xy 83.462748 -376.689726) (xy 83.470792 -376.75655) (xy 83.470792 -376.823856) (xy 83.470785 -376.823915)
			(xy 86.748833 -376.823915) (xy 86.748833 -376.756491) (xy 86.756908 -376.689553) (xy 86.772944 -376.624064)
			(xy 86.796708 -376.560967) (xy 86.827859 -376.501171) (xy 86.865948 -376.445537) (xy 86.887812 -376.419872)
			(xy 86.893604 -376.412724) (xy 86.900121 -376.395536) (xy 86.900512 -376.386344) (xy 86.900512 -375.894092)
			(xy 86.900103 -375.884905) (xy 86.893588 -375.86772) (xy 86.887812 -375.860564) (xy 86.865979 -375.834873)
			(xy 86.827889 -375.779242) (xy 86.796736 -375.71945) (xy 86.772969 -375.656356) (xy 86.756931 -375.59087)
			(xy 86.748853 -375.523935) (xy 86.74885 -375.456513) (xy 86.756923 -375.389577) (xy 86.772955 -375.32409)
			(xy 86.796716 -375.260994) (xy 86.827864 -375.201199) (xy 86.86595 -375.145565) (xy 86.887812 -375.1199)
			(xy 86.893592 -375.112743) (xy 86.900116 -375.095562) (xy 86.900512 -375.086372) (xy 86.900512 -374.928638)
			(xy 86.901057 -374.918517) (xy 86.908767 -374.899802) (xy 86.923035 -374.885446) (xy 86.941702 -374.87762)
			(xy 86.95182 -374.877076) (xy 87.6681 -374.877076) (xy 87.678206 -374.877585) (xy 87.696879 -374.885318)
			(xy 87.711173 -374.899607) (xy 87.718912 -374.918278) (xy 87.719408 -374.928384) (xy 87.719408 -375.086372)
			(xy 87.71983 -375.095558) (xy 87.726335 -375.112743) (xy 87.732108 -375.1199) (xy 87.754003 -375.145539)
			(xy 87.79209 -375.201178) (xy 87.798441 -375.213371) (xy 104.681961 -375.213371) (xy 104.681961 -375.153429)
			(xy 104.689785 -375.094001) (xy 104.7053 -375.036103) (xy 104.72824 -374.980725) (xy 104.758212 -374.928815)
			(xy 104.794703 -374.881262) (xy 104.837089 -374.838879) (xy 104.884645 -374.802391) (xy 104.936557 -374.772424)
			(xy 104.991937 -374.749489) (xy 105.049837 -374.733978) (xy 105.109265 -374.726159) (xy 105.139236 -374.725692)
			(xy 106.002836 -374.725692) (xy 106.032802 -374.726184) (xy 106.092221 -374.734011) (xy 106.15011 -374.749527)
			(xy 106.205479 -374.772465) (xy 106.25738 -374.802434) (xy 106.304926 -374.838921) (xy 106.347303 -374.881301)
			(xy 106.383786 -374.92885) (xy 106.413751 -374.980753) (xy 106.436685 -375.036124) (xy 106.452196 -375.094014)
			(xy 106.460018 -375.153434) (xy 106.460018 -375.213366) (xy 106.452196 -375.272786) (xy 106.436685 -375.330676)
			(xy 106.413751 -375.386047) (xy 106.383786 -375.43795) (xy 106.347303 -375.485499) (xy 106.304926 -375.527879)
			(xy 106.25738 -375.564366) (xy 106.205479 -375.594335) (xy 106.15011 -375.617273) (xy 106.092221 -375.632789)
			(xy 106.032802 -375.640616) (xy 106.002836 -375.641108) (xy 105.139236 -375.641108) (xy 105.109265 -375.640641)
			(xy 105.049837 -375.632822) (xy 104.991937 -375.617311) (xy 104.936557 -375.594376) (xy 104.884645 -375.564409)
			(xy 104.837089 -375.527921) (xy 104.794703 -375.485538) (xy 104.758212 -375.437985) (xy 104.72824 -375.386075)
			(xy 104.7053 -375.330697) (xy 104.689785 -375.272799) (xy 104.681961 -375.213371) (xy 87.798441 -375.213371)
			(xy 87.823239 -375.260978) (xy 87.847001 -375.324078) (xy 87.863034 -375.38957) (xy 87.871107 -375.456511)
			(xy 87.871105 -375.523937) (xy 87.863026 -375.590877) (xy 87.846987 -375.656368) (xy 87.82322 -375.719466)
			(xy 87.792066 -375.779263) (xy 87.753974 -375.834899) (xy 87.732108 -375.860564) (xy 87.726303 -375.867703)
			(xy 87.719793 -375.884898) (xy 87.719408 -375.894092) (xy 87.719408 -376.386344) (xy 87.719795 -376.395534)
			(xy 87.726324 -376.412718) (xy 87.732108 -376.419872) (xy 87.753976 -376.445534) (xy 87.792064 -376.501169)
			(xy 87.823214 -376.560966) (xy 87.846977 -376.624063) (xy 87.863012 -376.689553) (xy 87.871088 -376.756491)
			(xy 87.871087 -376.823915) (xy 117.548863 -376.823915) (xy 117.548863 -376.756491) (xy 117.556939 -376.689552)
			(xy 117.572976 -376.624062) (xy 117.596742 -376.560965) (xy 117.627895 -376.50117) (xy 117.665986 -376.445536)
			(xy 117.687852 -376.419872) (xy 117.693649 -376.412728) (xy 117.700162 -376.395536) (xy 117.700552 -376.386344)
			(xy 117.700552 -375.894092) (xy 117.700134 -375.884906) (xy 117.693625 -375.867722) (xy 117.687852 -375.860564)
			(xy 117.666018 -375.834874) (xy 117.627925 -375.779244) (xy 117.59677 -375.719452) (xy 117.573001 -375.656358)
			(xy 117.556962 -375.590871) (xy 117.548883 -375.523935) (xy 117.54888 -375.456513) (xy 117.556953 -375.389576)
			(xy 117.572987 -375.324088) (xy 117.59675 -375.260992) (xy 117.6279 -375.201197) (xy 117.665988 -375.145564)
			(xy 117.687852 -375.1199) (xy 117.693638 -375.112747) (xy 117.700157 -375.095562) (xy 117.700552 -375.086372)
			(xy 117.700552 -374.928638) (xy 117.701058 -374.918512) (xy 117.708776 -374.89979) (xy 117.723056 -374.885432)
			(xy 117.741737 -374.877613) (xy 117.75186 -374.877076) (xy 118.46814 -374.877076) (xy 118.478294 -374.877488)
			(xy 118.497042 -374.885293) (xy 118.511363 -374.899691) (xy 118.519066 -374.918482) (xy 118.519448 -374.928638)
			(xy 118.519448 -375.086372) (xy 118.519883 -375.095556) (xy 118.526381 -375.11274) (xy 118.532148 -375.1199)
			(xy 118.554045 -375.145538) (xy 118.592136 -375.201176) (xy 118.623289 -375.260975) (xy 118.647053 -375.324075)
			(xy 118.663088 -375.389568) (xy 118.671162 -375.45651) (xy 118.671159 -375.523938) (xy 118.66308 -375.590879)
			(xy 118.647039 -375.656371) (xy 118.623269 -375.719469) (xy 118.592112 -375.779266) (xy 118.554016 -375.8349)
			(xy 118.532148 -375.860564) (xy 118.526335 -375.867698) (xy 118.519832 -375.884897) (xy 118.519448 -375.894092)
			(xy 118.519448 -376.386344) (xy 118.519849 -376.395532) (xy 118.52637 -376.412715) (xy 118.532148 -376.419872)
			(xy 118.554018 -376.445533) (xy 118.59211 -376.501167) (xy 118.623263 -376.560963) (xy 118.647029 -376.624061)
			(xy 118.663066 -376.689551) (xy 118.671143 -376.75649) (xy 118.671143 -376.756551) (xy 121.949182 -376.756551)
			(xy 121.957226 -376.689728) (xy 121.973199 -376.624346) (xy 121.996871 -376.561342) (xy 122.027904 -376.501618)
			(xy 122.065852 -376.446032) (xy 122.08764 -376.42038) (xy 122.093433 -376.413232) (xy 122.099949 -376.396044)
			(xy 122.10034 -376.386852) (xy 122.10034 -375.893584) (xy 122.099929 -375.884397) (xy 122.093415 -375.867213)
			(xy 122.08764 -375.860056) (xy 122.065884 -375.834378) (xy 122.027934 -375.778795) (xy 121.996899 -375.719075)
			(xy 121.973225 -375.656074) (xy 121.95725 -375.590695) (xy 121.949203 -375.523875) (xy 121.9492 -375.456573)
			(xy 121.957241 -375.389752) (xy 121.973211 -375.324372) (xy 121.99688 -375.261369) (xy 122.027909 -375.201646)
			(xy 122.065854 -375.14606) (xy 122.08764 -375.120408) (xy 122.093421 -375.113252) (xy 122.099944 -375.09607)
			(xy 122.10034 -375.08688) (xy 122.10034 -374.928638) (xy 122.100795 -374.918469) (xy 122.108568 -374.899674)
			(xy 122.122944 -374.885288) (xy 122.141733 -374.877502) (xy 122.151902 -374.877076) (xy 122.868182 -374.877076)
			(xy 122.878357 -374.877479) (xy 122.897159 -374.885265) (xy 122.911546 -374.899658) (xy 122.919325 -374.918463)
			(xy 122.919744 -374.928638) (xy 122.919744 -375.08688) (xy 122.920176 -375.096065) (xy 122.926676 -375.113249)
			(xy 122.932444 -375.120408) (xy 122.954264 -375.146034) (xy 122.992213 -375.201624) (xy 123.023246 -375.261351)
			(xy 123.046917 -375.324359) (xy 123.062889 -375.389744) (xy 123.070931 -375.45657) (xy 123.070928 -375.523878)
			(xy 123.06288 -375.590703) (xy 123.046903 -375.656087) (xy 123.023226 -375.719093) (xy 122.992188 -375.778818)
			(xy 122.954234 -375.834404) (xy 122.932444 -375.860056) (xy 122.926634 -375.867192) (xy 122.920129 -375.88439)
			(xy 122.919744 -375.893584) (xy 122.919744 -376.386852) (xy 122.92019 -376.396035) (xy 122.92668 -376.413219)
			(xy 122.932444 -376.42038) (xy 122.954236 -376.446029) (xy 122.992186 -376.501615) (xy 123.02322 -376.561339)
			(xy 123.046893 -376.624344) (xy 123.062866 -376.689727) (xy 123.07091 -376.75655) (xy 123.07091 -376.823856)
			(xy 123.070903 -376.823915) (xy 126.348951 -376.823915) (xy 126.348951 -376.756491) (xy 126.357027 -376.689552)
			(xy 126.373063 -376.624063) (xy 126.396828 -376.560966) (xy 126.42798 -376.50117) (xy 126.466071 -376.445537)
			(xy 126.487936 -376.419872) (xy 126.493732 -376.412726) (xy 126.500246 -376.395536) (xy 126.500636 -376.386344)
			(xy 126.500636 -375.894092) (xy 126.500222 -375.884905) (xy 126.49371 -375.867721) (xy 126.487936 -375.860564)
			(xy 126.466102 -375.834873) (xy 126.42801 -375.779243) (xy 126.396856 -375.719451) (xy 126.373088 -375.656357)
			(xy 126.35705 -375.590871) (xy 126.348971 -375.523935) (xy 126.348968 -375.456513) (xy 126.357041 -375.389576)
			(xy 126.373074 -375.324089) (xy 126.396836 -375.260993) (xy 126.427985 -375.201198) (xy 126.466073 -375.145565)
			(xy 126.487936 -375.1199) (xy 126.49372 -375.112746) (xy 126.500241 -375.095562) (xy 126.500636 -375.086372)
			(xy 126.500636 -374.928638) (xy 126.501158 -374.918514) (xy 126.508872 -374.899795) (xy 126.523148 -374.885437)
			(xy 126.541823 -374.877616) (xy 126.551944 -374.877076) (xy 127.268224 -374.877076) (xy 127.278377 -374.877501)
			(xy 127.297125 -374.8853) (xy 127.311447 -374.899695) (xy 127.31915 -374.918483) (xy 127.319532 -374.928638)
			(xy 127.319532 -375.086372) (xy 127.319971 -375.095556) (xy 127.326466 -375.11274) (xy 127.332232 -375.1199)
			(xy 127.354126 -375.14554) (xy 127.392212 -375.201179) (xy 127.423359 -375.260979) (xy 127.44712 -375.324079)
			(xy 127.463153 -375.389571) (xy 127.471226 -375.456511) (xy 127.471223 -375.523937) (xy 127.463144 -375.590877)
			(xy 127.447106 -375.656367) (xy 127.42334 -375.719465) (xy 127.392187 -375.779263) (xy 127.354097 -375.834898)
			(xy 127.332232 -375.860564) (xy 127.326417 -375.867696) (xy 127.319915 -375.884897) (xy 127.319532 -375.894092)
			(xy 127.319532 -376.386344) (xy 127.319936 -376.395532) (xy 127.326456 -376.412715) (xy 127.332232 -376.419872)
			(xy 127.354099 -376.445535) (xy 127.392185 -376.50117) (xy 127.423334 -376.560967) (xy 127.447097 -376.624064)
			(xy 127.463131 -376.689553) (xy 127.471206 -376.756491) (xy 127.471206 -376.756551) (xy 130.74927 -376.756551)
			(xy 130.757314 -376.689729) (xy 130.773286 -376.624347) (xy 130.796958 -376.561343) (xy 130.827989 -376.501619)
			(xy 130.865937 -376.446032) (xy 130.887724 -376.42038) (xy 130.893514 -376.413231) (xy 130.900032 -376.396043)
			(xy 130.900424 -376.386852) (xy 130.900424 -375.893584) (xy 130.900016 -375.884397) (xy 130.8935 -375.867213)
			(xy 130.887724 -375.860056) (xy 130.865968 -375.834378) (xy 130.82802 -375.778795) (xy 130.796986 -375.719074)
			(xy 130.773312 -375.656073) (xy 130.757337 -375.590695) (xy 130.749291 -375.523875) (xy 130.749288 -375.456573)
			(xy 130.757329 -375.389753) (xy 130.773298 -375.324373) (xy 130.796966 -375.26137) (xy 130.827995 -375.201647)
			(xy 130.865939 -375.146061) (xy 130.887724 -375.120408) (xy 130.893502 -375.11325) (xy 130.900027 -375.096069)
			(xy 130.900424 -375.08688) (xy 130.900424 -374.928638) (xy 130.900895 -374.918471) (xy 130.908665 -374.899679)
			(xy 130.923036 -374.885294) (xy 130.941819 -374.877505) (xy 130.951986 -374.877076) (xy 131.668266 -374.877076)
			(xy 131.67844 -374.877493) (xy 131.697241 -374.885274) (xy 131.711629 -374.899662) (xy 131.719408 -374.918464)
			(xy 131.719828 -374.928638) (xy 131.719828 -375.08688) (xy 131.720241 -375.096067) (xy 131.726752 -375.113252)
			(xy 131.732528 -375.120408) (xy 131.754348 -375.146034) (xy 131.792298 -375.201623) (xy 131.823332 -375.26135)
			(xy 131.847005 -375.324358) (xy 131.862976 -375.389744) (xy 131.871018 -375.45657) (xy 131.871016 -375.523878)
			(xy 131.862968 -375.590704) (xy 131.84699 -375.656088) (xy 131.823313 -375.719094) (xy 131.792274 -375.778818)
			(xy 131.754319 -375.834404) (xy 131.732528 -375.860056) (xy 131.726716 -375.86719) (xy 131.720213 -375.884389)
			(xy 131.719828 -375.893584) (xy 131.719828 -376.386852) (xy 131.720255 -376.396037) (xy 131.726756 -376.413222)
			(xy 131.732528 -376.42038) (xy 131.754321 -376.446029) (xy 131.792271 -376.501615) (xy 131.823306 -376.561338)
			(xy 131.84698 -376.624344) (xy 131.862954 -376.689727) (xy 131.870991 -376.756492) (xy 161.548796 -376.756492)
			(xy 161.556871 -376.689554) (xy 161.572905 -376.624066) (xy 161.596667 -376.560969) (xy 161.627816 -376.501173)
			(xy 161.665902 -376.445538) (xy 161.687764 -376.419872) (xy 161.693563 -376.412729) (xy 161.700074 -376.395536)
			(xy 161.700464 -376.386344) (xy 161.700464 -375.894092) (xy 161.700043 -375.884906) (xy 161.693535 -375.867723)
			(xy 161.687764 -375.860564) (xy 161.665933 -375.834872) (xy 161.627845 -375.779241) (xy 161.596695 -375.719448)
			(xy 161.572931 -375.656354) (xy 161.556894 -375.590869) (xy 161.548816 -375.523934) (xy 161.548814 -375.456514)
			(xy 161.556886 -375.389578) (xy 161.572917 -375.324092) (xy 161.596676 -375.260996) (xy 161.627821 -375.201201)
			(xy 161.665903 -375.145566) (xy 161.687764 -375.1199) (xy 161.693551 -375.112748) (xy 161.70007 -375.095562)
			(xy 161.700464 -375.086372) (xy 161.700464 -374.928638) (xy 161.700959 -374.918511) (xy 161.708678 -374.899786)
			(xy 161.722963 -374.885428) (xy 161.741647 -374.877611) (xy 161.751772 -374.877076) (xy 162.468052 -374.877076)
			(xy 162.478168 -374.877555) (xy 162.496866 -374.885283) (xy 162.511181 -374.89958) (xy 162.518933 -374.918268)
			(xy 162.51936 -374.928384) (xy 162.51936 -375.086372) (xy 162.519793 -375.095557) (xy 162.526292 -375.112741)
			(xy 162.53206 -375.1199) (xy 162.553957 -375.145539) (xy 162.592047 -375.201176) (xy 162.623199 -375.260976)
			(xy 162.646963 -375.324076) (xy 162.662997 -375.389569) (xy 162.671071 -375.456511) (xy 162.671068 -375.523938)
			(xy 162.662989 -375.590879) (xy 162.646949 -375.65637) (xy 162.623179 -375.719468) (xy 162.592022 -375.779265)
			(xy 162.553927 -375.834899) (xy 162.53206 -375.860564) (xy 162.526249 -375.867699) (xy 162.519744 -375.884897)
			(xy 162.51936 -375.894092) (xy 162.51936 -376.386344) (xy 162.519758 -376.395532) (xy 162.526281 -376.412716)
			(xy 162.53206 -376.419872) (xy 162.553929 -376.445533) (xy 162.592021 -376.501167) (xy 162.623173 -376.560964)
			(xy 162.646939 -376.624061) (xy 162.662975 -376.689551) (xy 162.671052 -376.756491) (xy 162.671051 -376.823855)
			(xy 165.949092 -376.823855) (xy 165.949092 -376.756551) (xy 165.957136 -376.689728) (xy 165.973109 -376.624346)
			(xy 165.996782 -376.561342) (xy 166.027815 -376.501618) (xy 166.065764 -376.446032) (xy 166.087552 -376.42038)
			(xy 166.093346 -376.413233) (xy 166.099861 -376.396044) (xy 166.100252 -376.386852) (xy 166.100252 -375.893584)
			(xy 166.099838 -375.884397) (xy 166.093326 -375.867214) (xy 166.087552 -375.860056) (xy 166.065795 -375.834378)
			(xy 166.027845 -375.778796) (xy 165.996809 -375.719076) (xy 165.973134 -375.656075) (xy 165.957159 -375.590695)
			(xy 165.949112 -375.523875) (xy 165.949109 -375.456573) (xy 165.95715 -375.389752) (xy 165.97312 -375.324371)
			(xy 165.99679 -375.261368) (xy 166.02782 -375.201646) (xy 166.065766 -375.14606) (xy 166.087552 -375.120408)
			(xy 166.093334 -375.113253) (xy 166.099856 -375.09607) (xy 166.100252 -375.08688) (xy 166.100252 -374.928638)
			(xy 166.100695 -374.918467) (xy 166.10847 -374.899671) (xy 166.12285 -374.885284) (xy 166.141643 -374.8775)
			(xy 166.151814 -374.877076) (xy 166.868094 -374.877076) (xy 166.87827 -374.87747) (xy 166.897072 -374.88526)
			(xy 166.911458 -374.899655) (xy 166.919237 -374.918462) (xy 166.919656 -374.928638) (xy 166.919656 -375.08688)
			(xy 166.920085 -375.096065) (xy 166.926587 -375.113249) (xy 166.932356 -375.120408) (xy 166.954175 -375.146034)
			(xy 166.992124 -375.201624) (xy 167.023156 -375.261351) (xy 167.046827 -375.324359) (xy 167.062798 -375.389745)
			(xy 167.07084 -375.45657) (xy 167.070837 -375.523878) (xy 167.062789 -375.590703) (xy 167.046813 -375.656087)
			(xy 167.023136 -375.719093) (xy 166.992099 -375.778817) (xy 166.954146 -375.834404) (xy 166.932356 -375.860056)
			(xy 166.926548 -375.867193) (xy 166.920041 -375.88439) (xy 166.919656 -375.893584) (xy 166.919656 -376.386852)
			(xy 166.920099 -376.396035) (xy 166.926591 -376.41322) (xy 166.932356 -376.42038) (xy 166.954148 -376.446029)
			(xy 166.992097 -376.501616) (xy 167.02313 -376.56134) (xy 167.046803 -376.624345) (xy 167.062776 -376.689727)
			(xy 167.07082 -376.75655) (xy 167.07082 -376.823856) (xy 167.070813 -376.823915) (xy 170.34886 -376.823915)
			(xy 170.34886 -376.756491) (xy 170.356936 -376.689552) (xy 170.372972 -376.624063) (xy 170.396738 -376.560966)
			(xy 170.427891 -376.50117) (xy 170.465983 -376.445536) (xy 170.487848 -376.419872) (xy 170.493645 -376.412727)
			(xy 170.500158 -376.395536) (xy 170.500548 -376.386344) (xy 170.500548 -375.894092) (xy 170.500131 -375.884906)
			(xy 170.493621 -375.867722) (xy 170.487848 -375.860564) (xy 170.466014 -375.834874) (xy 170.427921 -375.779244)
			(xy 170.396766 -375.719452) (xy 170.372998 -375.656358) (xy 170.356959 -375.590871) (xy 170.34888 -375.523935)
			(xy 170.348877 -375.456513) (xy 170.35695 -375.389576) (xy 170.372984 -375.324088) (xy 170.396747 -375.260992)
			(xy 170.427896 -375.201197) (xy 170.465984 -375.145564) (xy 170.487848 -375.1199) (xy 170.493633 -375.112747)
			(xy 170.500153 -375.095562) (xy 170.500548 -375.086372) (xy 170.500548 -374.928638) (xy 170.501058 -374.918513)
			(xy 170.508775 -374.899791) (xy 170.523054 -374.885433) (xy 170.541734 -374.877614) (xy 170.551856 -374.877076)
			(xy 171.268136 -374.877076) (xy 171.278289 -374.877492) (xy 171.297038 -374.885295) (xy 171.311359 -374.899692)
			(xy 171.319062 -374.918482) (xy 171.319444 -374.928638) (xy 171.319444 -375.086372) (xy 171.31988 -375.095556)
			(xy 171.326377 -375.11274) (xy 171.332144 -375.1199) (xy 171.354041 -375.145538) (xy 171.392133 -375.201175)
			(xy 171.423285 -375.260975) (xy 171.44705 -375.324075) (xy 171.463085 -375.389568) (xy 171.471159 -375.45651)
			(xy 171.471156 -375.523938) (xy 171.463076 -375.590879) (xy 171.447036 -375.656371) (xy 171.423266 -375.719469)
			(xy 171.392108 -375.779266) (xy 171.354012 -375.8349) (xy 171.332144 -375.860564) (xy 171.326331 -375.867697)
			(xy 171.319828 -375.884897) (xy 171.319444 -375.894092) (xy 171.319444 -376.386344) (xy 171.319845 -376.395532)
			(xy 171.326366 -376.412716) (xy 171.332144 -376.419872) (xy 171.354014 -376.445533) (xy 171.392106 -376.501167)
			(xy 171.42326 -376.560963) (xy 171.447026 -376.624061) (xy 171.463063 -376.689551) (xy 171.47114 -376.75649)
			(xy 171.47114 -376.756551) (xy 174.749179 -376.756551) (xy 174.757223 -376.689728) (xy 174.773195 -376.624346)
			(xy 174.796868 -376.561342) (xy 174.8279 -376.501619) (xy 174.865848 -376.446032) (xy 174.887636 -376.42038)
			(xy 174.893428 -376.413232) (xy 174.899945 -376.396043) (xy 174.900336 -376.386852) (xy 174.900336 -375.893584)
			(xy 174.899926 -375.884397) (xy 174.893411 -375.867213) (xy 174.887636 -375.860056) (xy 174.86588 -375.834378)
			(xy 174.82793 -375.778795) (xy 174.796896 -375.719075) (xy 174.773222 -375.656074) (xy 174.757246 -375.590695)
			(xy 174.7492 -375.523875) (xy 174.749197 -375.456573) (xy 174.757238 -375.389752) (xy 174.773207 -375.324372)
			(xy 174.796876 -375.261369) (xy 174.827906 -375.201646) (xy 174.865851 -375.14606) (xy 174.887636 -375.120408)
			(xy 174.893416 -375.113251) (xy 174.89994 -375.096069) (xy 174.900336 -375.08688) (xy 174.900336 -374.928638)
			(xy 174.900795 -374.918469) (xy 174.908567 -374.899676) (xy 174.922942 -374.88529) (xy 174.941729 -374.877503)
			(xy 174.951898 -374.877076) (xy 175.668178 -374.877076) (xy 175.678353 -374.877483) (xy 175.697154 -374.885268)
			(xy 175.711541 -374.899659) (xy 175.71932 -374.918463) (xy 175.71974 -374.928638) (xy 175.71974 -375.08688)
			(xy 175.720173 -375.096064) (xy 175.726672 -375.113248) (xy 175.73244 -375.120408) (xy 175.75426 -375.146034)
			(xy 175.792209 -375.201624) (xy 175.823242 -375.261351) (xy 175.846914 -375.324359) (xy 175.862886 -375.389744)
			(xy 175.870928 -375.45657) (xy 175.870925 -375.523878) (xy 175.862877 -375.590703) (xy 175.8469 -375.656087)
			(xy 175.823223 -375.719093) (xy 175.792185 -375.778818) (xy 175.754231 -375.834404) (xy 175.73244 -375.860056)
			(xy 175.72663 -375.867191) (xy 175.720125 -375.88439) (xy 175.71974 -375.893584) (xy 175.71974 -376.386852)
			(xy 175.720186 -376.396035) (xy 175.726676 -376.413219) (xy 175.73244 -376.42038) (xy 175.754232 -376.446029)
			(xy 175.792182 -376.501615) (xy 175.823216 -376.561339) (xy 175.84689 -376.624344) (xy 175.862863 -376.689727)
			(xy 175.870907 -376.75655) (xy 175.870907 -376.823856) (xy 175.862862 -376.890679) (xy 175.846888 -376.956062)
			(xy 175.823214 -377.019066) (xy 175.792179 -377.07879) (xy 175.754228 -377.134376) (xy 175.73244 -377.160028)
			(xy 175.726642 -377.167172) (xy 175.72013 -377.184364) (xy 175.71974 -377.193556) (xy 175.71974 -377.35129)
			(xy 175.719328 -377.361464) (xy 175.711542 -377.380262) (xy 175.697152 -377.394648) (xy 175.678352 -377.40243)
			(xy 175.668178 -377.402852) (xy 174.951898 -377.402852) (xy 174.941725 -377.402438) (xy 174.922928 -377.39465)
			(xy 174.908543 -377.380262) (xy 174.90076 -377.361463) (xy 174.900336 -377.35129) (xy 174.900336 -377.193556)
			(xy 174.899939 -377.184368) (xy 174.893415 -377.167184) (xy 174.887636 -377.160028) (xy 174.865852 -377.134373)
			(xy 174.827903 -377.078787) (xy 174.79687 -377.019063) (xy 174.773197 -376.956059) (xy 174.757224 -376.890678)
			(xy 174.74918 -376.823855) (xy 174.749179 -376.756551) (xy 171.47114 -376.756551) (xy 171.471139 -376.823916)
			(xy 171.463062 -376.890855) (xy 171.447024 -376.956345) (xy 171.423257 -377.019442) (xy 171.392103 -377.079238)
			(xy 171.35401 -377.134872) (xy 171.332144 -377.160536) (xy 171.326343 -377.167678) (xy 171.319832 -377.184871)
			(xy 171.319444 -377.194064) (xy 171.319444 -377.35129) (xy 171.318965 -377.361418) (xy 171.311237 -377.380142)
			(xy 171.296948 -377.394499) (xy 171.278262 -377.402316) (xy 171.268136 -377.402852) (xy 170.551856 -377.402852)
			(xy 170.541706 -377.402415) (xy 170.522962 -377.394615) (xy 170.508642 -377.380224) (xy 170.500935 -377.361442)
			(xy 170.500548 -377.35129) (xy 170.500548 -377.194064) (xy 170.500144 -377.184876) (xy 170.493625 -377.167693)
			(xy 170.487848 -377.160536) (xy 170.465986 -377.134868) (xy 170.427894 -377.079235) (xy 170.396741 -377.01944)
			(xy 170.372974 -376.956343) (xy 170.356937 -376.890854) (xy 170.34886 -376.823915) (xy 167.070813 -376.823915)
			(xy 167.062775 -376.890679) (xy 167.046801 -376.956061) (xy 167.023128 -377.019066) (xy 166.992094 -377.07879)
			(xy 166.954144 -377.134376) (xy 166.932356 -377.160028) (xy 166.92656 -377.167173) (xy 166.920046 -377.184364)
			(xy 166.919656 -377.193556) (xy 166.919656 -377.35129) (xy 166.919228 -377.361462) (xy 166.911445 -377.380257)
			(xy 166.897061 -377.394643) (xy 166.878266 -377.402427) (xy 166.868094 -377.402852) (xy 166.151814 -377.402852)
			(xy 166.141642 -377.402425) (xy 166.122846 -377.394642) (xy 166.10846 -377.380258) (xy 166.100676 -377.361462)
			(xy 166.100252 -377.35129) (xy 166.100252 -377.193556) (xy 166.099851 -377.184368) (xy 166.09333 -377.167185)
			(xy 166.087552 -377.160028) (xy 166.065768 -377.134373) (xy 166.027818 -377.078787) (xy 165.996784 -377.019064)
			(xy 165.97311 -376.95606) (xy 165.957137 -376.890678) (xy 165.949092 -376.823855) (xy 162.671051 -376.823855)
			(xy 162.671051 -376.823915) (xy 162.662974 -376.890855) (xy 162.646937 -376.956344) (xy 162.623171 -377.019442)
			(xy 162.592017 -377.079238) (xy 162.553926 -377.134871) (xy 162.53206 -377.160536) (xy 162.526261 -377.167679)
			(xy 162.519749 -377.184871) (xy 162.51936 -377.194064) (xy 162.51936 -377.35129) (xy 162.518865 -377.361416)
			(xy 162.511141 -377.380137) (xy 162.496857 -377.394494) (xy 162.478175 -377.402313) (xy 162.468052 -377.402852)
			(xy 161.751772 -377.402852) (xy 161.741668 -377.402339) (xy 161.722999 -377.394602) (xy 161.708707 -377.380314)
			(xy 161.700964 -377.361648) (xy 161.700464 -377.351544) (xy 161.700464 -377.194064) (xy 161.700057 -377.184877)
			(xy 161.69354 -377.167693) (xy 161.687764 -377.160536) (xy 161.665905 -377.134867) (xy 161.627819 -377.079232)
			(xy 161.59667 -377.019436) (xy 161.572907 -376.95634) (xy 161.556872 -376.890852) (xy 161.548797 -376.823914)
			(xy 161.548796 -376.756492) (xy 131.870991 -376.756492) (xy 131.870998 -376.75655) (xy 131.870998 -376.823856)
			(xy 131.862953 -376.890679) (xy 131.846979 -376.956062) (xy 131.823304 -377.019067) (xy 131.792268 -377.07879)
			(xy 131.754317 -377.134376) (xy 131.732528 -377.160028) (xy 131.726728 -377.167171) (xy 131.720218 -377.184363)
			(xy 131.719828 -377.193556) (xy 131.719828 -377.35129) (xy 131.719427 -377.361465) (xy 131.711639 -377.380266)
			(xy 131.697246 -377.394653) (xy 131.678441 -377.402432) (xy 131.668266 -377.402852) (xy 130.951986 -377.402852)
			(xy 130.941826 -377.402378) (xy 130.923055 -377.394597) (xy 130.90869 -377.380225) (xy 130.900918 -377.36145)
			(xy 130.900424 -377.35129) (xy 130.900424 -377.193556) (xy 130.90003 -377.184367) (xy 130.893504 -377.167183)
			(xy 130.887724 -377.160028) (xy 130.865941 -377.134372) (xy 130.827993 -377.078786) (xy 130.79696 -377.019063)
			(xy 130.773288 -376.956059) (xy 130.757315 -376.890677) (xy 130.749271 -376.823855) (xy 130.74927 -376.756551)
			(xy 127.471206 -376.756551) (xy 127.471205 -376.823915) (xy 127.46313 -376.890853) (xy 127.447095 -376.956342)
			(xy 127.423332 -377.019438) (xy 127.392182 -377.079235) (xy 127.354095 -377.13487) (xy 127.332232 -377.160536)
			(xy 127.326429 -377.167677) (xy 127.31992 -377.184871) (xy 127.319532 -377.194064) (xy 127.319532 -377.35129)
			(xy 127.319064 -377.36142) (xy 127.311335 -377.380146) (xy 127.297042 -377.394503) (xy 127.278351 -377.402318)
			(xy 127.268224 -377.402852) (xy 126.551944 -377.402852) (xy 126.541799 -377.402343) (xy 126.523058 -377.394572)
			(xy 126.508735 -377.380202) (xy 126.501024 -377.361436) (xy 126.500636 -377.35129) (xy 126.500636 -377.194064)
			(xy 126.500235 -377.184876) (xy 126.493714 -377.167692) (xy 126.487936 -377.160536) (xy 126.466075 -377.134868)
			(xy 126.427984 -377.079235) (xy 126.396831 -377.019439) (xy 126.373065 -376.956343) (xy 126.357028 -376.890854)
			(xy 126.348951 -376.823915) (xy 123.070903 -376.823915) (xy 123.062865 -376.890679) (xy 123.046891 -376.956062)
			(xy 123.023217 -377.019066) (xy 122.992183 -377.07879) (xy 122.954232 -377.134376) (xy 122.932444 -377.160028)
			(xy 122.926646 -377.167172) (xy 122.920134 -377.184364) (xy 122.919744 -377.193556) (xy 122.919744 -377.35129)
			(xy 122.919328 -377.361463) (xy 122.911543 -377.380261) (xy 122.897154 -377.394647) (xy 122.878355 -377.402429)
			(xy 122.868182 -377.402852) (xy 122.151902 -377.402852) (xy 122.141729 -377.402434) (xy 122.122933 -377.394648)
			(xy 122.108547 -377.380261) (xy 122.100764 -377.361463) (xy 122.10034 -377.35129) (xy 122.10034 -377.193556)
			(xy 122.099942 -377.184368) (xy 122.093419 -377.167184) (xy 122.08764 -377.160028) (xy 122.065856 -377.134373)
			(xy 122.027907 -377.078787) (xy 121.996873 -377.019064) (xy 121.9732 -376.95606) (xy 121.957227 -376.890678)
			(xy 121.949183 -376.823855) (xy 121.949182 -376.756551) (xy 118.671143 -376.756551) (xy 118.671142 -376.823916)
			(xy 118.663065 -376.890855) (xy 118.647028 -376.956345) (xy 118.623261 -377.019442) (xy 118.592107 -377.079238)
			(xy 118.554014 -377.134872) (xy 118.532148 -377.160536) (xy 118.526347 -377.167678) (xy 118.519836 -377.184871)
			(xy 118.519448 -377.194064) (xy 118.519448 -377.35129) (xy 118.518965 -377.361418) (xy 118.511238 -377.380141)
			(xy 118.496951 -377.394498) (xy 118.478265 -377.402315) (xy 118.46814 -377.402852) (xy 117.75186 -377.402852)
			(xy 117.74171 -377.402412) (xy 117.722967 -377.394613) (xy 117.708647 -377.380223) (xy 117.700939 -377.361442)
			(xy 117.700552 -377.35129) (xy 117.700552 -377.194064) (xy 117.700147 -377.184876) (xy 117.693628 -377.167693)
			(xy 117.687852 -377.160536) (xy 117.66599 -377.134868) (xy 117.627898 -377.079235) (xy 117.596744 -377.01944)
			(xy 117.572977 -376.956343) (xy 117.55694 -376.890854) (xy 117.548863 -376.823915) (xy 87.871087 -376.823915)
			(xy 87.863011 -376.890853) (xy 87.846976 -376.956342) (xy 87.823211 -377.019439) (xy 87.792061 -377.079236)
			(xy 87.753972 -377.134871) (xy 87.732108 -377.160536) (xy 87.726315 -377.167684) (xy 87.719798 -377.184872)
			(xy 87.719408 -377.194064) (xy 87.719408 -377.35129) (xy 87.718867 -377.36141) (xy 87.711151 -377.380122)
			(xy 87.696882 -377.394477) (xy 87.678217 -377.402305) (xy 87.6681 -377.402852) (xy 86.95182 -377.402852)
			(xy 86.941719 -377.4023) (xy 86.923051 -377.394578) (xy 86.908757 -377.380303) (xy 86.901013 -377.361644)
			(xy 86.900512 -377.351544) (xy 86.900512 -377.194064) (xy 86.900117 -377.184875) (xy 86.893592 -377.167691)
			(xy 86.887812 -377.160536) (xy 86.865952 -377.134868) (xy 86.827862 -377.079234) (xy 86.79671 -377.019438)
			(xy 86.772945 -376.956342) (xy 86.756909 -376.890853) (xy 86.748833 -376.823915) (xy 83.470785 -376.823915)
			(xy 83.462747 -376.89068) (xy 83.446772 -376.956063) (xy 83.423097 -377.019067) (xy 83.392061 -377.078791)
			(xy 83.354109 -377.134376) (xy 83.33232 -377.160028) (xy 83.326531 -377.167179) (xy 83.320011 -377.184365)
			(xy 83.31962 -377.193556) (xy 83.31962 -377.35129) (xy 83.319227 -377.361466) (xy 83.311438 -377.380269)
			(xy 83.297042 -377.394655) (xy 83.278234 -377.402433) (xy 83.268058 -377.402852) (xy 82.551778 -377.402852)
			(xy 82.541618 -377.402385) (xy 82.522846 -377.394601) (xy 82.508481 -377.380227) (xy 82.500709 -377.361451)
			(xy 82.500216 -377.35129) (xy 82.500216 -377.193556) (xy 82.499823 -377.184367) (xy 82.493297 -377.167183)
			(xy 82.487516 -377.160028) (xy 82.465733 -377.134372) (xy 82.427785 -377.078786) (xy 82.396753 -377.019063)
			(xy 82.373081 -376.956059) (xy 82.357109 -376.890677) (xy 82.349065 -376.823855) (xy 82.349064 -376.756551)
			(xy 79.071 -376.756551) (xy 79.070999 -376.823915) (xy 79.062924 -376.890853) (xy 79.046888 -376.956342)
			(xy 79.023125 -377.019439) (xy 78.991975 -377.079235) (xy 78.953887 -377.13487) (xy 78.932024 -377.160536)
			(xy 78.926232 -377.167685) (xy 78.919714 -377.184872) (xy 78.919324 -377.194064) (xy 78.919324 -377.35129)
			(xy 78.918864 -377.36142) (xy 78.911133 -377.380148) (xy 78.896838 -377.394506) (xy 78.878144 -377.402319)
			(xy 78.868016 -377.402852) (xy 78.151736 -377.402852) (xy 78.141636 -377.402286) (xy 78.122969 -377.39457)
			(xy 78.108674 -377.380299) (xy 78.100929 -377.361643) (xy 78.100428 -377.351544) (xy 78.100428 -377.194064)
			(xy 78.100029 -377.184876) (xy 78.093507 -377.167692) (xy 78.087728 -377.160536) (xy 78.065867 -377.134868)
			(xy 78.027776 -377.079235) (xy 77.996624 -377.019439) (xy 77.972858 -376.956342) (xy 77.956822 -376.890853)
			(xy 77.948745 -376.823915) (xy 74.670697 -376.823915) (xy 74.662659 -376.890679) (xy 74.646685 -376.956062)
			(xy 74.623011 -377.019067) (xy 74.591976 -377.07879) (xy 74.554025 -377.134376) (xy 74.532236 -377.160028)
			(xy 74.526437 -377.167171) (xy 74.519926 -377.184364) (xy 74.519536 -377.193556) (xy 74.519536 -377.35129)
			(xy 74.519127 -377.361464) (xy 74.511341 -377.380264) (xy 74.49695 -377.39465) (xy 74.478148 -377.402431)
			(xy 74.467974 -377.402852) (xy 73.751694 -377.402852) (xy 73.741521 -377.402441) (xy 73.722724 -377.394652)
			(xy 73.708339 -377.380263) (xy 73.700556 -377.361463) (xy 73.700132 -377.35129) (xy 73.700132 -377.193556)
			(xy 73.699736 -377.184367) (xy 73.693212 -377.167184) (xy 73.687432 -377.160028) (xy 73.665648 -377.134373)
			(xy 73.6277 -377.078786) (xy 73.596667 -377.019063) (xy 73.572994 -376.956059) (xy 73.557021 -376.890677)
			(xy 73.548977 -376.823855) (xy 73.548976 -376.756551) (xy 48.270947 -376.756551) (xy 48.270947 -376.823855)
			(xy 48.262903 -376.890678) (xy 48.24693 -376.95606) (xy 48.223258 -377.019064) (xy 48.192226 -377.078788)
			(xy 48.154279 -377.134375) (xy 48.132492 -377.160028) (xy 48.1267 -377.167176) (xy 48.120183 -377.184365)
			(xy 48.119792 -377.193556) (xy 48.119792 -377.351544) (xy 48.119414 -377.361702) (xy 48.111603 -377.380457)
			(xy 48.097193 -377.394779) (xy 48.07839 -377.402476) (xy 48.06823 -377.402852) (xy 47.35195 -377.402852)
			(xy 47.341825 -377.402332) (xy 47.323104 -377.394619) (xy 47.308746 -377.380343) (xy 47.300926 -377.361666)
			(xy 47.300388 -377.351544) (xy 47.300388 -377.193556) (xy 47.300002 -377.184366) (xy 47.293472 -377.167182)
			(xy 47.287688 -377.160028) (xy 47.265903 -377.134373) (xy 47.227951 -377.078788) (xy 47.196914 -377.019066)
			(xy 47.173239 -376.956061) (xy 47.157265 -376.890679) (xy 47.149219 -376.823856) (xy 43.871178 -376.823856)
			(xy 43.871178 -376.823915) (xy 43.863102 -376.890854) (xy 43.847066 -376.956343) (xy 43.823301 -377.01944)
			(xy 43.79215 -377.079236) (xy 43.75406 -377.134871) (xy 43.732196 -377.160536) (xy 43.726401 -377.167682)
			(xy 43.719886 -377.184872) (xy 43.719496 -377.194064) (xy 43.719496 -377.35129) (xy 43.718966 -377.361412)
			(xy 43.711248 -377.380126) (xy 43.696976 -377.394481) (xy 43.678307 -377.402307) (xy 43.668188 -377.402852)
			(xy 42.951908 -377.402852) (xy 42.941761 -377.402373) (xy 42.923019 -377.39459) (xy 42.908697 -377.380211)
			(xy 42.900988 -377.361439) (xy 42.9006 -377.35129) (xy 42.9006 -377.194064) (xy 42.900207 -377.184875)
			(xy 42.893682 -377.167691) (xy 42.8879 -377.160536) (xy 42.86604 -377.134868) (xy 42.827951 -377.079233)
			(xy 42.7968 -377.019438) (xy 42.773036 -376.956341) (xy 42.757 -376.890853) (xy 42.748924 -376.823915)
			(xy 39.470876 -376.823915) (xy 39.462838 -376.89068) (xy 39.446863 -376.956063) (xy 39.423187 -377.019068)
			(xy 39.39215 -377.078791) (xy 39.354198 -377.134377) (xy 39.332408 -377.160028) (xy 39.326618 -377.167178)
			(xy 39.320099 -377.184365) (xy 39.319708 -377.193556) (xy 39.319708 -377.35129) (xy 39.31916 -377.361441)
			(xy 39.311397 -377.380202) (xy 39.297049 -377.394566) (xy 39.278297 -377.402349) (xy 39.268146 -377.402852)
			(xy 38.551866 -377.402852) (xy 38.541705 -377.402394) (xy 38.522933 -377.394607) (xy 38.508569 -377.38023)
			(xy 38.500797 -377.361452) (xy 38.500304 -377.35129) (xy 38.500304 -377.193556) (xy 38.499914 -377.184367)
			(xy 38.493386 -377.167183) (xy 38.487604 -377.160028) (xy 38.465821 -377.134372) (xy 38.427875 -377.078785)
			(xy 38.396843 -377.019062) (xy 38.373172 -376.956058) (xy 38.357199 -376.890677) (xy 38.349156 -376.823855)
			(xy 38.349155 -376.756551) (xy 35.071091 -376.756551) (xy 35.07109 -376.823915) (xy 35.063014 -376.890853)
			(xy 35.046979 -376.956342) (xy 35.023215 -377.019439) (xy 34.992064 -377.079236) (xy 34.953976 -377.134871)
			(xy 34.932112 -377.160536) (xy 34.926319 -377.167684) (xy 34.919802 -377.184872) (xy 34.919412 -377.194064)
			(xy 34.919412 -377.35129) (xy 34.918867 -377.36141) (xy 34.911152 -377.380121) (xy 34.896884 -377.394476)
			(xy 34.878221 -377.402304) (xy 34.868104 -377.402852) (xy 34.151824 -377.402852) (xy 34.141678 -377.40236)
			(xy 34.122936 -377.394582) (xy 34.108614 -377.380208) (xy 34.100904 -377.361438) (xy 34.100516 -377.35129)
			(xy 34.100516 -377.194064) (xy 34.10012 -377.184875) (xy 34.093596 -377.167691) (xy 34.087816 -377.160536)
			(xy 34.065955 -377.134868) (xy 34.027866 -377.079234) (xy 33.996714 -377.019438) (xy 33.972949 -376.956342)
			(xy 33.956912 -376.890853) (xy 33.948836 -376.823915) (xy 30.670788 -376.823915) (xy 30.66275 -376.89068)
			(xy 30.646775 -376.956062) (xy 30.6231 -377.019067) (xy 30.592065 -377.078791) (xy 30.554113 -377.134376)
			(xy 30.532324 -377.160028) (xy 30.526536 -377.167179) (xy 30.520015 -377.184365) (xy 30.519624 -377.193556)
			(xy 30.519624 -377.35129) (xy 30.519227 -377.361466) (xy 30.511438 -377.380267) (xy 30.497044 -377.394654)
			(xy 30.478238 -377.402433) (xy 30.468062 -377.402852) (xy 29.751782 -377.402852) (xy 29.741622 -377.402381)
			(xy 29.72285 -377.394599) (xy 29.708485 -377.380226) (xy 29.700713 -377.36145) (xy 29.70022 -377.35129)
			(xy 29.70022 -377.193556) (xy 29.699827 -377.184367) (xy 29.693301 -377.167183) (xy 29.68752 -377.160028)
			(xy 29.665737 -377.134372) (xy 29.627789 -377.078786) (xy 29.596757 -377.019063) (xy 29.573084 -376.956059)
			(xy 29.557112 -376.890677) (xy 29.549068 -376.823855) (xy 29.549067 -376.756551) (xy 0.508 -376.756551)
			(xy 0.508 -378.323793) (xy 27.348888 -378.323793) (xy 27.34889 -378.256368) (xy 27.356968 -378.189428)
			(xy 27.373006 -378.123938) (xy 27.396772 -378.06084) (xy 27.427925 -378.001043) (xy 27.466015 -377.945408)
			(xy 27.48788 -377.919742) (xy 27.493681 -377.9126) (xy 27.500194 -377.895407) (xy 27.50058 -377.886214)
			(xy 27.50058 -377.728734) (xy 27.501056 -377.718605) (xy 27.50878 -377.699877) (xy 27.52307 -377.685518)
			(xy 27.541761 -377.677705) (xy 27.551888 -377.677172) (xy 28.268168 -377.677172) (xy 28.278285 -377.677641)
			(xy 28.296983 -377.685374) (xy 28.311297 -377.699674) (xy 28.319048 -377.718363) (xy 28.319476 -377.72848)
			(xy 28.319476 -377.886214) (xy 28.319885 -377.895401) (xy 28.3264 -377.912585) (xy 28.332176 -377.919742)
			(xy 28.354015 -377.945428) (xy 28.392106 -378.001059) (xy 28.42326 -378.060852) (xy 28.447026 -378.123946)
			(xy 28.463064 -378.189433) (xy 28.471143 -378.256369) (xy 28.471145 -378.323734) (xy 31.749183 -378.323734)
			(xy 31.749186 -378.256427) (xy 31.757233 -378.189602) (xy 31.773209 -378.124218) (xy 31.796886 -378.061212)
			(xy 31.827924 -378.001488) (xy 31.865878 -377.945902) (xy 31.887668 -377.92025) (xy 31.893477 -377.913114)
			(xy 31.899982 -377.895916) (xy 31.900368 -377.886722) (xy 31.900368 -377.728734) (xy 31.900793 -377.718561)
			(xy 31.908572 -377.699761) (xy 31.922958 -377.685374) (xy 31.941757 -377.677593) (xy 31.95193 -377.677172)
			(xy 32.66821 -377.677172) (xy 32.678386 -377.677557) (xy 32.697188 -377.685351) (xy 32.711574 -377.699749)
			(xy 32.719352 -377.718557) (xy 32.719772 -377.728734) (xy 32.719772 -377.886722) (xy 32.720178 -377.89591)
			(xy 32.726695 -377.913094) (xy 32.732472 -377.92025) (xy 32.754234 -377.945924) (xy 32.792182 -378.001507)
			(xy 32.823216 -378.061228) (xy 32.84689 -378.12423) (xy 32.862864 -378.189609) (xy 32.87091 -378.256429)
			(xy 32.870913 -378.323732) (xy 32.870906 -378.323793) (xy 36.148976 -378.323793) (xy 36.148978 -378.256368)
			(xy 36.157056 -378.189429) (xy 36.173093 -378.123939) (xy 36.196859 -378.060841) (xy 36.22801 -378.001044)
			(xy 36.2661 -377.945408) (xy 36.287964 -377.919742) (xy 36.293775 -377.912608) (xy 36.300279 -377.895409)
			(xy 36.300664 -377.886214) (xy 36.300664 -377.728734) (xy 36.301155 -377.718607) (xy 36.308876 -377.699882)
			(xy 36.323162 -377.685523) (xy 36.341847 -377.677707) (xy 36.351972 -377.677172) (xy 37.068252 -377.677172)
			(xy 37.0784 -377.67766) (xy 37.097145 -377.685435) (xy 37.11147 -377.699811) (xy 37.119176 -377.718585)
			(xy 37.11956 -377.728734) (xy 37.11956 -377.886214) (xy 37.119972 -377.895401) (xy 37.126485 -377.912585)
			(xy 37.13226 -377.919742) (xy 37.1541 -377.945428) (xy 37.192192 -378.001058) (xy 37.223346 -378.060851)
			(xy 37.247113 -378.123946) (xy 37.263152 -378.189433) (xy 37.27123 -378.256369) (xy 37.271233 -378.323792)
			(xy 37.271233 -378.323794) (xy 40.548742 -378.323794) (xy 40.548744 -378.256367) (xy 40.556824 -378.189426)
			(xy 40.572863 -378.123935) (xy 40.596633 -378.060837) (xy 40.627789 -378.00104) (xy 40.665885 -377.945406)
			(xy 40.687752 -377.919742) (xy 40.693562 -377.912607) (xy 40.700067 -377.895408) (xy 40.700452 -377.886214)
			(xy 40.700452 -377.728734) (xy 40.700955 -377.718608) (xy 40.708674 -377.699885) (xy 40.722955 -377.685528)
			(xy 40.741637 -377.677709) (xy 40.75176 -377.677172) (xy 41.46804 -377.677172) (xy 41.478193 -377.677588)
			(xy 41.496941 -377.685392) (xy 41.511262 -377.699789) (xy 41.518965 -377.718579) (xy 41.519348 -377.728734)
			(xy 41.519348 -377.886214) (xy 41.519763 -377.8954) (xy 41.526275 -377.912584) (xy 41.532048 -377.919742)
			(xy 41.553888 -377.945427) (xy 41.591981 -378.001058) (xy 41.623136 -378.060851) (xy 41.646904 -378.123945)
			(xy 41.662943 -378.189432) (xy 41.671021 -378.256369) (xy 41.671024 -378.323792) (xy 41.671024 -378.323793)
			(xy 71.348797 -378.323793) (xy 71.348799 -378.256368) (xy 71.356877 -378.189428) (xy 71.372915 -378.123937)
			(xy 71.396682 -378.060839) (xy 71.427835 -378.001042) (xy 71.465927 -377.945407) (xy 71.487792 -377.919742)
			(xy 71.493595 -377.912601) (xy 71.500106 -377.895407) (xy 71.500492 -377.886214) (xy 71.500492 -377.728734)
			(xy 71.501053 -377.718615) (xy 71.508761 -377.699904) (xy 71.523024 -377.685548) (xy 71.541685 -377.67772)
			(xy 71.5518 -377.677172) (xy 72.26808 -377.677172) (xy 72.278229 -377.677637) (xy 72.296976 -377.685421)
			(xy 72.311299 -377.699804) (xy 72.319005 -377.718583) (xy 72.319388 -377.728734) (xy 72.319388 -377.886214)
			(xy 72.319794 -377.895402) (xy 72.326311 -377.912586) (xy 72.332088 -377.919742) (xy 72.353927 -377.945428)
			(xy 72.392017 -378.001059) (xy 72.42317 -378.060853) (xy 72.446936 -378.123947) (xy 72.462973 -378.189433)
			(xy 72.471052 -378.25637) (xy 72.471054 -378.323734) (xy 75.749092 -378.323734) (xy 75.749095 -378.256427)
			(xy 75.757142 -378.189601) (xy 75.773119 -378.124217) (xy 75.796796 -378.061212) (xy 75.827835 -378.001488)
			(xy 75.86579 -377.945902) (xy 75.88758 -377.92025) (xy 75.893378 -377.913106) (xy 75.899892 -377.895915)
			(xy 75.90028 -377.886722) (xy 75.90028 -377.728734) (xy 75.900693 -377.718559) (xy 75.908474 -377.699757)
			(xy 75.922864 -377.68537) (xy 75.941667 -377.677591) (xy 75.951842 -377.677172) (xy 76.668122 -377.677172)
			(xy 76.678299 -377.677547) (xy 76.697101 -377.685345) (xy 76.711486 -377.699746) (xy 76.719264 -377.718556)
			(xy 76.719684 -377.728734) (xy 76.719684 -377.886722) (xy 76.720087 -377.89591) (xy 76.726606 -377.913094)
			(xy 76.732384 -377.92025) (xy 76.754146 -377.945923) (xy 76.792094 -378.001507) (xy 76.823127 -378.061228)
			(xy 76.8468 -378.12423) (xy 76.862774 -378.189609) (xy 76.87082 -378.256429) (xy 76.870822 -378.323732)
			(xy 76.870815 -378.323793) (xy 80.148885 -378.323793) (xy 80.148887 -378.256368) (xy 80.156965 -378.189428)
			(xy 80.173003 -378.123938) (xy 80.196769 -378.06084) (xy 80.227921 -378.001043) (xy 80.266011 -377.945408)
			(xy 80.287876 -377.919742) (xy 80.293677 -377.9126) (xy 80.30019 -377.895407) (xy 80.300576 -377.886214)
			(xy 80.300576 -377.728734) (xy 80.301056 -377.718605) (xy 80.308779 -377.699878) (xy 80.323068 -377.685519)
			(xy 80.341758 -377.677705) (xy 80.351884 -377.677172) (xy 81.068164 -377.677172) (xy 81.078281 -377.677645)
			(xy 81.096978 -377.685376) (xy 81.111293 -377.699675) (xy 81.119044 -377.718364) (xy 81.119472 -377.72848)
			(xy 81.119472 -377.886214) (xy 81.119882 -377.895401) (xy 81.126396 -377.912585) (xy 81.132172 -377.919742)
			(xy 81.154011 -377.945428) (xy 81.192103 -378.001059) (xy 81.223256 -378.060852) (xy 81.247023 -378.123946)
			(xy 81.263061 -378.189433) (xy 81.27114 -378.256369) (xy 81.271142 -378.323792) (xy 81.271142 -378.323793)
			(xy 84.548676 -378.323793) (xy 84.548678 -378.256368) (xy 84.556756 -378.189429) (xy 84.572793 -378.123939)
			(xy 84.596559 -378.060841) (xy 84.62771 -378.001044) (xy 84.6658 -377.945408) (xy 84.687664 -377.919742)
			(xy 84.693475 -377.912608) (xy 84.699979 -377.895409) (xy 84.700364 -377.886214) (xy 84.700364 -377.728734)
			(xy 84.700855 -377.718607) (xy 84.708576 -377.699882) (xy 84.722862 -377.685523) (xy 84.741547 -377.677707)
			(xy 84.751672 -377.677172) (xy 85.467952 -377.677172) (xy 85.478068 -377.677655) (xy 85.496765 -377.685382)
			(xy 85.51108 -377.699678) (xy 85.518832 -377.718365) (xy 85.51926 -377.72848) (xy 85.51926 -377.886214)
			(xy 85.519672 -377.895401) (xy 85.526185 -377.912585) (xy 85.53196 -377.919742) (xy 85.5538 -377.945428)
			(xy 85.591892 -378.001058) (xy 85.623046 -378.060851) (xy 85.646813 -378.123946) (xy 85.662852 -378.189433)
			(xy 85.67093 -378.256369) (xy 85.670933 -378.323734) (xy 115.349234 -378.323734) (xy 115.349237 -378.256427)
			(xy 115.357283 -378.189603) (xy 115.373258 -378.12422) (xy 115.396932 -378.061215) (xy 115.427966 -378.00149)
			(xy 115.465916 -377.945903) (xy 115.487704 -377.92025) (xy 115.493505 -377.913108) (xy 115.500017 -377.895915)
			(xy 115.500404 -377.886722) (xy 115.500404 -377.728734) (xy 115.500961 -377.718583) (xy 115.508717 -377.699821)
			(xy 115.523064 -377.685456) (xy 115.541815 -377.677674) (xy 115.551966 -377.677172) (xy 116.268246 -377.677172)
			(xy 116.278411 -377.677597) (xy 116.297188 -377.685393) (xy 116.311552 -377.69978) (xy 116.319319 -377.718568)
			(xy 116.319808 -377.728734) (xy 116.319808 -377.886722) (xy 116.320206 -377.895911) (xy 116.326728 -377.913095)
			(xy 116.332508 -377.92025) (xy 116.354272 -377.945922) (xy 116.392225 -378.001505) (xy 116.423262 -378.061225)
			(xy 116.446939 -378.124227) (xy 116.462915 -378.189607) (xy 116.470962 -378.256428) (xy 116.470964 -378.323732)
			(xy 116.470957 -378.323793) (xy 119.749003 -378.323793) (xy 119.749005 -378.256368) (xy 119.757084 -378.189428)
			(xy 119.773122 -378.123937) (xy 119.796889 -378.060839) (xy 119.828043 -378.001042) (xy 119.866134 -377.945407)
			(xy 119.888 -377.919742) (xy 119.893804 -377.912602) (xy 119.900314 -377.895407) (xy 119.9007 -377.886214)
			(xy 119.9007 -377.728734) (xy 119.901253 -377.718614) (xy 119.908963 -377.699902) (xy 119.923228 -377.685546)
			(xy 119.941892 -377.677718) (xy 119.952008 -377.677172) (xy 120.668288 -377.677172) (xy 120.678438 -377.677631)
			(xy 120.697185 -377.685417) (xy 120.711507 -377.699802) (xy 120.719213 -377.718582) (xy 120.719596 -377.728734)
			(xy 120.719596 -377.886214) (xy 120.72 -377.895402) (xy 120.726518 -377.912586) (xy 120.732296 -377.919742)
			(xy 120.754135 -377.945428) (xy 120.792224 -378.00106) (xy 120.823376 -378.060853) (xy 120.847142 -378.123947)
			(xy 120.86318 -378.189434) (xy 120.871258 -378.25637) (xy 120.87126 -378.323734) (xy 124.149298 -378.323734)
			(xy 124.149301 -378.256426) (xy 124.157348 -378.189601) (xy 124.173325 -378.124217) (xy 124.197003 -378.061211)
			(xy 124.228042 -378.001487) (xy 124.265997 -377.945902) (xy 124.287788 -377.92025) (xy 124.293587 -377.913106)
			(xy 124.300101 -377.895915) (xy 124.300488 -377.886722) (xy 124.300488 -377.728734) (xy 124.300893 -377.718558)
			(xy 124.308676 -377.699755) (xy 124.323068 -377.685367) (xy 124.341874 -377.67759) (xy 124.35205 -377.677172)
			(xy 125.06833 -377.677172) (xy 125.078508 -377.67754) (xy 125.09731 -377.685341) (xy 125.111695 -377.699744)
			(xy 125.119473 -377.718556) (xy 125.119892 -377.728734) (xy 125.119892 -377.886722) (xy 125.120293 -377.89591)
			(xy 125.126813 -377.913094) (xy 125.132592 -377.92025) (xy 125.154353 -377.945924) (xy 125.192301 -378.001508)
			(xy 125.223334 -378.061229) (xy 125.247006 -378.12423) (xy 125.26298 -378.189609) (xy 125.271026 -378.256429)
			(xy 125.271028 -378.323732) (xy 125.271028 -378.323734) (xy 128.549089 -378.323734) (xy 128.549092 -378.256427)
			(xy 128.557139 -378.189602) (xy 128.573116 -378.124218) (xy 128.596793 -378.061212) (xy 128.627831 -378.001488)
			(xy 128.665786 -377.945902) (xy 128.687576 -377.92025) (xy 128.693374 -377.913105) (xy 128.699888 -377.895915)
			(xy 128.700276 -377.886722) (xy 128.700276 -377.728734) (xy 128.700693 -377.71856) (xy 128.708474 -377.699759)
			(xy 128.722862 -377.685371) (xy 128.741664 -377.677592) (xy 128.751838 -377.677172) (xy 129.468118 -377.677172)
			(xy 129.478295 -377.67755) (xy 129.497097 -377.685347) (xy 129.511482 -377.699747) (xy 129.51926 -377.718557)
			(xy 129.51968 -377.728734) (xy 129.51968 -377.886722) (xy 129.520084 -377.89591) (xy 129.526602 -377.913094)
			(xy 129.53238 -377.92025) (xy 129.554142 -377.945923) (xy 129.59209 -378.001507) (xy 129.623123 -378.061228)
			(xy 129.646797 -378.12423) (xy 129.662771 -378.189609) (xy 129.670817 -378.256429) (xy 129.670819 -378.323732)
			(xy 129.670819 -378.323734) (xy 159.349143 -378.323734) (xy 159.349146 -378.256427) (xy 159.357192 -378.189603)
			(xy 159.373167 -378.12422) (xy 159.396842 -378.061214) (xy 159.427877 -378.00149) (xy 159.465827 -377.945902)
			(xy 159.487616 -377.92025) (xy 159.493418 -377.913109) (xy 159.499929 -377.895915) (xy 159.500316 -377.886722)
			(xy 159.500316 -377.728734) (xy 159.500791 -377.718567) (xy 159.508561 -377.699778) (xy 159.522931 -377.685392)
			(xy 159.541712 -377.677602) (xy 159.551878 -377.677172) (xy 160.268158 -377.677172) (xy 160.278331 -377.677599)
			(xy 160.297131 -377.685377) (xy 160.311519 -377.699762) (xy 160.319299 -377.718561) (xy 160.31972 -377.728734)
			(xy 160.31972 -377.886722) (xy 160.320115 -377.895911) (xy 160.326639 -377.913095) (xy 160.33242 -377.92025)
			(xy 160.354183 -377.945923) (xy 160.392136 -378.001505) (xy 160.423172 -378.061226) (xy 160.446848 -378.124227)
			(xy 160.462824 -378.189608) (xy 160.470871 -378.256429) (xy 160.470874 -378.323732) (xy 160.470867 -378.323793)
			(xy 163.748912 -378.323793) (xy 163.748914 -378.256367) (xy 163.756993 -378.189427) (xy 163.773031 -378.123937)
			(xy 163.796799 -378.060839) (xy 163.827953 -378.001042) (xy 163.866046 -377.945407) (xy 163.887912 -377.919742)
			(xy 163.893717 -377.912603) (xy 163.900226 -377.895408) (xy 163.900612 -377.886214) (xy 163.900612 -377.728734)
			(xy 163.901154 -377.718613) (xy 163.908865 -377.699898) (xy 163.923134 -377.685542) (xy 163.941802 -377.677716)
			(xy 163.95192 -377.677172) (xy 164.6682 -377.677172) (xy 164.678351 -377.677621) (xy 164.697098 -377.685411)
			(xy 164.71142 -377.699799) (xy 164.719125 -377.718582) (xy 164.719508 -377.728734) (xy 164.719508 -377.886214)
			(xy 164.71991 -377.895402) (xy 164.726429 -377.912586) (xy 164.732208 -377.919742) (xy 164.754046 -377.945428)
			(xy 164.792135 -378.00106) (xy 164.823286 -378.060853) (xy 164.847052 -378.123948) (xy 164.863089 -378.189434)
			(xy 164.871167 -378.25637) (xy 164.871169 -378.323734) (xy 168.149231 -378.323734) (xy 168.149234 -378.256427)
			(xy 168.15728 -378.189604) (xy 168.173254 -378.12422) (xy 168.196928 -378.061215) (xy 168.227963 -378.00149)
			(xy 168.265912 -377.945903) (xy 168.2877 -377.92025) (xy 168.2935 -377.913107) (xy 168.300013 -377.895915)
			(xy 168.3004 -377.886722) (xy 168.3004 -377.728734) (xy 168.30096 -377.718583) (xy 168.308717 -377.699822)
			(xy 168.323062 -377.685457) (xy 168.341812 -377.677675) (xy 168.351962 -377.677172) (xy 169.068242 -377.677172)
			(xy 169.078407 -377.6776) (xy 169.097183 -377.685394) (xy 169.111548 -377.699781) (xy 169.119315 -377.718569)
			(xy 169.119804 -377.728734) (xy 169.119804 -377.886722) (xy 169.120203 -377.89591) (xy 169.126724 -377.913095)
			(xy 169.132504 -377.92025) (xy 169.154265 -377.945924) (xy 169.192212 -378.001508) (xy 169.223244 -378.061229)
			(xy 169.246916 -378.124231) (xy 169.26289 -378.18961) (xy 169.270935 -378.256429) (xy 169.270937 -378.323732)
			(xy 169.270937 -378.323734) (xy 172.548998 -378.323734) (xy 172.549001 -378.256426) (xy 172.557048 -378.189601)
			(xy 172.573025 -378.124217) (xy 172.596703 -378.061211) (xy 172.627742 -378.001487) (xy 172.665697 -377.945902)
			(xy 172.687488 -377.92025) (xy 172.693287 -377.913106) (xy 172.699801 -377.895915) (xy 172.700188 -377.886722)
			(xy 172.700188 -377.728734) (xy 172.700593 -377.718558) (xy 172.708376 -377.699755) (xy 172.722768 -377.685367)
			(xy 172.741574 -377.67759) (xy 172.75175 -377.677172) (xy 173.46803 -377.677172) (xy 173.478208 -377.67754)
			(xy 173.49701 -377.685341) (xy 173.511395 -377.699744) (xy 173.519173 -377.718556) (xy 173.519592 -377.728734)
			(xy 173.519592 -377.886722) (xy 173.519993 -377.89591) (xy 173.526513 -377.913094) (xy 173.532292 -377.92025)
			(xy 173.554053 -377.945924) (xy 173.592001 -378.001508) (xy 173.623034 -378.061229) (xy 173.646706 -378.12423)
			(xy 173.66268 -378.189609) (xy 173.670726 -378.256429) (xy 173.670728 -378.323732) (xy 173.662687 -378.390552)
			(xy 173.646718 -378.455932) (xy 173.623049 -378.518936) (xy 173.592021 -378.578659) (xy 173.554077 -378.634245)
			(xy 173.532292 -378.659898) (xy 173.526513 -378.667056) (xy 173.519988 -378.684237) (xy 173.519592 -378.693426)
			(xy 173.519592 -378.766811) (xy 193.48983 -378.766811) (xy 193.48983 -378.633249) (xy 193.497894 -378.499931)
			(xy 193.513994 -378.367343) (xy 193.538069 -378.235969) (xy 193.570032 -378.106288) (xy 193.609767 -377.978774)
			(xy 193.657129 -377.853891) (xy 193.711944 -377.732096) (xy 193.774014 -377.613833) (xy 193.84311 -377.499534)
			(xy 193.918982 -377.389614) (xy 194.001352 -377.284477) (xy 194.08992 -377.184504) (xy 194.184362 -377.090062)
			(xy 194.284335 -377.001494) (xy 194.389472 -376.919124) (xy 194.499392 -376.843252) (xy 194.613691 -376.774156)
			(xy 194.731954 -376.712086) (xy 194.853749 -376.657271) (xy 194.978632 -376.609909) (xy 195.106146 -376.570174)
			(xy 195.235827 -376.538211) (xy 195.367201 -376.514136) (xy 195.499789 -376.498036) (xy 195.633107 -376.489972)
			(xy 195.766669 -376.489972) (xy 195.899987 -376.498036) (xy 196.032575 -376.514136) (xy 196.163949 -376.538211)
			(xy 196.29363 -376.570174) (xy 196.421144 -376.609909) (xy 196.546027 -376.657271) (xy 196.667822 -376.712086)
			(xy 196.786085 -376.774156) (xy 196.900384 -376.843252) (xy 197.010304 -376.919124) (xy 197.115441 -377.001494)
			(xy 197.215414 -377.090062) (xy 197.309856 -377.184504) (xy 197.398424 -377.284477) (xy 197.480794 -377.389614)
			(xy 197.556666 -377.499534) (xy 197.625762 -377.613833) (xy 197.687832 -377.732096) (xy 197.742647 -377.853891)
			(xy 197.790009 -377.978774) (xy 197.829744 -378.106288) (xy 197.861707 -378.235969) (xy 197.885782 -378.367343)
			(xy 197.901882 -378.499931) (xy 197.909946 -378.633249) (xy 197.91045 -378.70003) (xy 197.909946 -378.766811)
			(xy 197.901882 -378.900129) (xy 197.885782 -379.032717) (xy 197.861707 -379.164091) (xy 197.829744 -379.293772)
			(xy 197.790009 -379.421286) (xy 197.742647 -379.546169) (xy 197.687832 -379.667964) (xy 197.625762 -379.786227)
			(xy 197.556666 -379.900526) (xy 197.480794 -380.010446) (xy 197.398424 -380.115583) (xy 197.309856 -380.215556)
			(xy 197.215414 -380.309998) (xy 197.115441 -380.398566) (xy 197.010304 -380.480936) (xy 196.900384 -380.556808)
			(xy 196.786085 -380.625904) (xy 196.667822 -380.687974) (xy 196.546027 -380.742789) (xy 196.421144 -380.790151)
			(xy 196.29363 -380.829886) (xy 196.163949 -380.861849) (xy 196.032575 -380.885924) (xy 195.899987 -380.902024)
			(xy 195.766669 -380.910088) (xy 195.633107 -380.910088) (xy 195.499789 -380.902024) (xy 195.367201 -380.885924)
			(xy 195.235827 -380.861849) (xy 195.106146 -380.829886) (xy 194.978632 -380.790151) (xy 194.853749 -380.742789)
			(xy 194.731954 -380.687974) (xy 194.613691 -380.625904) (xy 194.499392 -380.556808) (xy 194.389472 -380.480936)
			(xy 194.284335 -380.398566) (xy 194.184362 -380.309998) (xy 194.08992 -380.215556) (xy 194.001352 -380.115583)
			(xy 193.918982 -380.010446) (xy 193.84311 -379.900526) (xy 193.774014 -379.786227) (xy 193.711944 -379.667964)
			(xy 193.657129 -379.546169) (xy 193.609767 -379.421286) (xy 193.570032 -379.293772) (xy 193.538069 -379.164091)
			(xy 193.513994 -379.032717) (xy 193.497894 -378.900129) (xy 193.48983 -378.766811) (xy 173.519592 -378.766811)
			(xy 173.519592 -379.186694) (xy 173.520007 -379.195881) (xy 173.526518 -379.213065) (xy 173.532292 -379.220222)
			(xy 173.554124 -379.245837) (xy 173.592069 -379.30143) (xy 173.623099 -379.361159) (xy 173.646768 -379.424168)
			(xy 173.662737 -379.489554) (xy 173.670777 -379.556381) (xy 173.670772 -379.623689) (xy 173.662724 -379.690514)
			(xy 173.646747 -379.755898) (xy 173.623071 -379.818905) (xy 173.592034 -379.87863) (xy 173.554082 -379.934217)
			(xy 173.532292 -379.95987) (xy 173.526482 -379.967006) (xy 173.519976 -379.984204) (xy 173.519592 -379.993398)
			(xy 173.519592 -380.151386) (xy 173.519056 -380.161539) (xy 173.511292 -380.180302) (xy 173.496939 -380.194667)
			(xy 173.478183 -380.202447) (xy 173.46803 -380.202948) (xy 172.75175 -380.202948) (xy 172.74158 -380.202495)
			(xy 172.722784 -380.194724) (xy 172.708396 -380.180347) (xy 172.700612 -380.161556) (xy 172.700188 -380.151386)
			(xy 172.700188 -379.993398) (xy 172.699781 -379.98421) (xy 172.693266 -379.967026) (xy 172.687488 -379.95987)
			(xy 172.665744 -379.934181) (xy 172.627791 -379.878601) (xy 172.596753 -379.818883) (xy 172.573075 -379.755883)
			(xy 172.557097 -379.690505) (xy 172.549049 -379.623686) (xy 172.549045 -379.556383) (xy 172.557085 -379.489563)
			(xy 172.573055 -379.424183) (xy 172.596724 -379.36118) (xy 172.627755 -379.301458) (xy 172.665702 -379.245873)
			(xy 172.687488 -379.220222) (xy 172.693299 -379.213087) (xy 172.699805 -379.195889) (xy 172.700188 -379.186694)
			(xy 172.700188 -378.693426) (xy 172.699768 -378.68424) (xy 172.693262 -378.667055) (xy 172.687488 -378.659898)
			(xy 172.665673 -378.634268) (xy 172.627722 -378.578679) (xy 172.596687 -378.518953) (xy 172.573014 -378.455946)
			(xy 172.557041 -378.39056) (xy 172.548998 -378.323734) (xy 169.270937 -378.323734) (xy 169.262897 -378.390552)
			(xy 169.246928 -378.455932) (xy 169.22326 -378.518935) (xy 169.192232 -378.578658) (xy 169.154289 -378.634245)
			(xy 169.132504 -378.659898) (xy 169.126726 -378.667057) (xy 169.1202 -378.684237) (xy 169.119804 -378.693426)
			(xy 169.119804 -379.186694) (xy 169.120216 -379.195881) (xy 169.126728 -379.213065) (xy 169.132504 -379.220222)
			(xy 169.154336 -379.245838) (xy 169.19228 -379.30143) (xy 169.223309 -379.361159) (xy 169.246977 -379.424169)
			(xy 169.262946 -379.489555) (xy 169.270986 -379.556381) (xy 169.270982 -379.623689) (xy 169.262933 -379.690513)
			(xy 169.246957 -379.755898) (xy 169.223281 -379.818904) (xy 169.192245 -379.878629) (xy 169.154293 -379.934217)
			(xy 169.132504 -379.95987) (xy 169.126696 -379.967007) (xy 169.120188 -379.984204) (xy 169.119804 -379.993398)
			(xy 169.119804 -380.151386) (xy 169.119256 -380.161538) (xy 169.111494 -380.180299) (xy 169.097146 -380.194663)
			(xy 169.078393 -380.202445) (xy 169.068242 -380.202948) (xy 168.351962 -380.202948) (xy 168.3418 -380.202497)
			(xy 168.323027 -380.194708) (xy 168.308663 -380.180329) (xy 168.300892 -380.161548) (xy 168.3004 -380.151386)
			(xy 168.3004 -379.993398) (xy 168.299991 -379.984211) (xy 168.293476 -379.967026) (xy 168.2877 -379.95987)
			(xy 168.265959 -379.93418) (xy 168.228011 -379.878598) (xy 168.196978 -379.818879) (xy 168.173304 -379.75588)
			(xy 168.157329 -379.690503) (xy 168.149282 -379.623685) (xy 168.149278 -379.556384) (xy 168.157317 -379.489565)
			(xy 168.173284 -379.424186) (xy 168.19695 -379.361184) (xy 168.227975 -379.301461) (xy 168.265916 -379.245875)
			(xy 168.2877 -379.220222) (xy 168.293512 -379.213088) (xy 168.300018 -379.195889) (xy 168.3004 -379.186694)
			(xy 168.3004 -378.693426) (xy 168.299977 -378.68424) (xy 168.293472 -378.667056) (xy 168.2877 -378.659898)
			(xy 168.265888 -378.634266) (xy 168.227942 -378.578676) (xy 168.196912 -378.518949) (xy 168.173243 -378.455942)
			(xy 168.157273 -378.390558) (xy 168.149231 -378.323734) (xy 164.871169 -378.323734) (xy 164.871169 -378.323791)
			(xy 164.863096 -378.390728) (xy 164.847063 -378.456215) (xy 164.823302 -378.519311) (xy 164.792155 -378.579106)
			(xy 164.75407 -378.634741) (xy 164.732208 -378.660406) (xy 164.726427 -378.667563) (xy 164.719903 -378.684744)
			(xy 164.719508 -378.693934) (xy 164.719508 -379.186186) (xy 164.719923 -379.195373) (xy 164.726433 -379.212557)
			(xy 164.732208 -379.219714) (xy 164.754117 -379.245342) (xy 164.792204 -379.300982) (xy 164.823352 -379.360784)
			(xy 164.847113 -379.423885) (xy 164.863145 -379.489379) (xy 164.871217 -379.556321) (xy 164.871213 -379.623748)
			(xy 164.863133 -379.690689) (xy 164.847093 -379.756181) (xy 164.823324 -379.81928) (xy 164.792168 -379.879077)
			(xy 164.754074 -379.934713) (xy 164.732208 -379.960378) (xy 164.726397 -379.967513) (xy 164.719891 -379.984711)
			(xy 164.719508 -379.993906) (xy 164.719508 -380.151386) (xy 164.718963 -380.161506) (xy 164.711249 -380.180218)
			(xy 164.696981 -380.194573) (xy 164.678317 -380.202401) (xy 164.6682 -380.202948) (xy 163.95192 -380.202948)
			(xy 163.941773 -380.202463) (xy 163.92303 -380.194683) (xy 163.908708 -380.180306) (xy 163.900999 -380.161534)
			(xy 163.900612 -380.151386) (xy 163.900612 -379.993906) (xy 163.900196 -379.98472) (xy 163.893686 -379.967535)
			(xy 163.887912 -379.960378) (xy 163.866093 -379.934676) (xy 163.828002 -379.879047) (xy 163.796849 -379.819256)
			(xy 163.773081 -379.756164) (xy 163.757042 -379.690679) (xy 163.748963 -379.623745) (xy 163.748958 -379.556324)
			(xy 163.75703 -379.489389) (xy 163.773061 -379.423902) (xy 163.79682 -379.360807) (xy 163.827966 -379.301013)
			(xy 163.86605 -379.245379) (xy 163.887912 -379.219714) (xy 163.893729 -379.212583) (xy 163.900231 -379.195382)
			(xy 163.900612 -379.186186) (xy 163.900612 -378.693934) (xy 163.900183 -378.684749) (xy 163.893682 -378.667565)
			(xy 163.887912 -378.660406) (xy 163.866022 -378.634762) (xy 163.827933 -378.579125) (xy 163.796783 -378.519326)
			(xy 163.77302 -378.456226) (xy 163.756986 -378.390734) (xy 163.748912 -378.323793) (xy 160.470867 -378.323793)
			(xy 160.462831 -378.390554) (xy 160.44686 -378.455935) (xy 160.423188 -378.518939) (xy 160.392156 -378.578661)
			(xy 160.354207 -378.634246) (xy 160.33242 -378.659898) (xy 160.326644 -378.667058) (xy 160.320116 -378.684237)
			(xy 160.31972 -378.693426) (xy 160.31972 -379.186694) (xy 160.320129 -379.195881) (xy 160.326643 -379.213066)
			(xy 160.33242 -379.220222) (xy 160.354254 -379.245836) (xy 160.392205 -379.301427) (xy 160.423238 -379.361156)
			(xy 160.44691 -379.424165) (xy 160.462881 -379.489552) (xy 160.470922 -379.55638) (xy 160.470918 -379.623689)
			(xy 160.462869 -379.690516) (xy 160.44689 -379.755901) (xy 160.42321 -379.818908) (xy 160.392169 -379.878632)
			(xy 160.354212 -379.934219) (xy 160.33242 -379.95987) (xy 160.326614 -379.967008) (xy 160.320104 -379.984204)
			(xy 160.31972 -379.993398) (xy 160.31972 -380.151386) (xy 160.319324 -380.161562) (xy 160.311536 -380.180364)
			(xy 160.297141 -380.194751) (xy 160.278334 -380.202529) (xy 160.268158 -380.202948) (xy 159.551878 -380.202948)
			(xy 159.541717 -380.202484) (xy 159.522945 -380.1947) (xy 159.50858 -380.180325) (xy 159.500808 -380.161547)
			(xy 159.500316 -380.151386) (xy 159.500316 -379.993398) (xy 159.499903 -379.984211) (xy 159.493391 -379.967027)
			(xy 159.487616 -379.95987) (xy 159.465874 -379.93418) (xy 159.427926 -379.878599) (xy 159.396892 -379.81888)
			(xy 159.373217 -379.75588) (xy 159.357242 -379.690503) (xy 159.349195 -379.623685) (xy 159.34919 -379.556384)
			(xy 159.35723 -379.489565) (xy 159.373197 -379.424186) (xy 159.396864 -379.361183) (xy 159.42789 -379.301461)
			(xy 159.465832 -379.245875) (xy 159.487616 -379.220222) (xy 159.49343 -379.213089) (xy 159.499934 -379.195889)
			(xy 159.500316 -379.186694) (xy 159.500316 -378.693426) (xy 159.49989 -378.684241) (xy 159.493387 -378.667056)
			(xy 159.487616 -378.659898) (xy 159.465803 -378.634267) (xy 159.427857 -378.578677) (xy 159.396826 -378.51895)
			(xy 159.373156 -378.455943) (xy 159.357185 -378.390558) (xy 159.349143 -378.323734) (xy 129.670819 -378.323734)
			(xy 129.662778 -378.390552) (xy 129.646808 -378.455933) (xy 129.623139 -378.518936) (xy 129.59211 -378.578659)
			(xy 129.554166 -378.634246) (xy 129.53238 -378.659898) (xy 129.526599 -378.667054) (xy 129.520076 -378.684236)
			(xy 129.51968 -378.693426) (xy 129.51968 -379.186694) (xy 129.520098 -379.19588) (xy 129.526607 -379.213064)
			(xy 129.53238 -379.220222) (xy 129.554212 -379.245837) (xy 129.592159 -379.301429) (xy 129.623189 -379.361158)
			(xy 129.646858 -379.424168) (xy 129.662827 -379.489554) (xy 129.670868 -379.55638) (xy 129.670863 -379.623689)
			(xy 129.662815 -379.690514) (xy 129.646838 -379.755899) (xy 129.623161 -379.818905) (xy 129.592123 -379.87863)
			(xy 129.55417 -379.934218) (xy 129.53238 -379.95987) (xy 129.526569 -379.967005) (xy 129.520064 -379.984203)
			(xy 129.51968 -379.993398) (xy 129.51968 -380.151386) (xy 129.519156 -380.161541) (xy 129.511389 -380.180306)
			(xy 129.497033 -380.194671) (xy 129.478272 -380.202449) (xy 129.468118 -380.202948) (xy 128.751838 -380.202948)
			(xy 128.741667 -380.202505) (xy 128.722871 -380.19473) (xy 128.708484 -380.18035) (xy 128.7007 -380.161557)
			(xy 128.700276 -380.151386) (xy 128.700276 -379.993398) (xy 128.699872 -379.98421) (xy 128.693355 -379.967025)
			(xy 128.687576 -379.95987) (xy 128.665832 -379.934181) (xy 128.62788 -379.878601) (xy 128.596842 -379.818883)
			(xy 128.573165 -379.755883) (xy 128.557188 -379.690505) (xy 128.54914 -379.623686) (xy 128.549136 -379.556384)
			(xy 128.557176 -379.489563) (xy 128.573145 -379.424183) (xy 128.596814 -379.361181) (xy 128.627844 -379.301459)
			(xy 128.66579 -379.245874) (xy 128.687576 -379.220222) (xy 128.693385 -379.213086) (xy 128.699893 -379.195889)
			(xy 128.700276 -379.186694) (xy 128.700276 -378.693426) (xy 128.699859 -378.684239) (xy 128.693351 -378.667055)
			(xy 128.687576 -378.659898) (xy 128.665762 -378.634267) (xy 128.627811 -378.578679) (xy 128.596777 -378.518952)
			(xy 128.573104 -378.455945) (xy 128.557132 -378.39056) (xy 128.549089 -378.323734) (xy 125.271028 -378.323734)
			(xy 125.262987 -378.390552) (xy 125.247018 -378.455932) (xy 125.223349 -378.518936) (xy 125.192321 -378.578659)
			(xy 125.154377 -378.634245) (xy 125.132592 -378.659898) (xy 125.126813 -378.667056) (xy 125.120288 -378.684237)
			(xy 125.119892 -378.693426) (xy 125.119892 -379.186694) (xy 125.120307 -379.195881) (xy 125.126818 -379.213065)
			(xy 125.132592 -379.220222) (xy 125.154424 -379.245837) (xy 125.192369 -379.30143) (xy 125.223399 -379.361159)
			(xy 125.247068 -379.424168) (xy 125.263037 -379.489554) (xy 125.271077 -379.556381) (xy 125.271072 -379.623689)
			(xy 125.263024 -379.690514) (xy 125.247047 -379.755898) (xy 125.223371 -379.818905) (xy 125.192334 -379.87863)
			(xy 125.154382 -379.934217) (xy 125.132592 -379.95987) (xy 125.126782 -379.967006) (xy 125.120276 -379.984204)
			(xy 125.119892 -379.993398) (xy 125.119892 -380.151386) (xy 125.119356 -380.161539) (xy 125.111592 -380.180302)
			(xy 125.097239 -380.194667) (xy 125.078483 -380.202447) (xy 125.06833 -380.202948) (xy 124.35205 -380.202948)
			(xy 124.34188 -380.202495) (xy 124.323084 -380.194724) (xy 124.308696 -380.180347) (xy 124.300912 -380.161556)
			(xy 124.300488 -380.151386) (xy 124.300488 -379.993398) (xy 124.300081 -379.98421) (xy 124.293566 -379.967026)
			(xy 124.287788 -379.95987) (xy 124.266044 -379.934181) (xy 124.228091 -379.878601) (xy 124.197053 -379.818883)
			(xy 124.173375 -379.755883) (xy 124.157397 -379.690505) (xy 124.149349 -379.623686) (xy 124.149345 -379.556383)
			(xy 124.157385 -379.489563) (xy 124.173355 -379.424183) (xy 124.197024 -379.36118) (xy 124.228055 -379.301458)
			(xy 124.266002 -379.245873) (xy 124.287788 -379.220222) (xy 124.293599 -379.213087) (xy 124.300105 -379.195889)
			(xy 124.300488 -379.186694) (xy 124.300488 -378.693426) (xy 124.300068 -378.68424) (xy 124.293562 -378.667055)
			(xy 124.287788 -378.659898) (xy 124.265973 -378.634268) (xy 124.228022 -378.578679) (xy 124.196987 -378.518953)
			(xy 124.173314 -378.455946) (xy 124.157341 -378.39056) (xy 124.149298 -378.323734) (xy 120.87126 -378.323734)
			(xy 120.87126 -378.323791) (xy 120.863187 -378.390728) (xy 120.847154 -378.456216) (xy 120.823392 -378.519311)
			(xy 120.792244 -378.579107) (xy 120.754159 -378.634741) (xy 120.732296 -378.660406) (xy 120.726514 -378.667561)
			(xy 120.719991 -378.684744) (xy 120.719596 -378.693934) (xy 120.719596 -379.186186) (xy 120.720014 -379.195372)
			(xy 120.726522 -379.212557) (xy 120.732296 -379.219714) (xy 120.754205 -379.245342) (xy 120.792293 -379.300982)
			(xy 120.823442 -379.360783) (xy 120.847204 -379.423885) (xy 120.863236 -379.489378) (xy 120.871308 -379.556321)
			(xy 120.871304 -379.623748) (xy 120.863224 -379.69069) (xy 120.847183 -379.756181) (xy 120.823414 -379.81928)
			(xy 120.792257 -379.879078) (xy 120.754163 -379.934713) (xy 120.732296 -379.960378) (xy 120.726483 -379.967512)
			(xy 120.719978 -379.984711) (xy 120.719596 -379.993906) (xy 120.719596 -380.151386) (xy 120.719063 -380.161507)
			(xy 120.711347 -380.180221) (xy 120.697075 -380.194577) (xy 120.678406 -380.202403) (xy 120.668288 -380.202948)
			(xy 119.952008 -380.202948) (xy 119.94186 -380.202473) (xy 119.923117 -380.194689) (xy 119.908795 -380.180309)
			(xy 119.901087 -380.161535) (xy 119.9007 -380.151386) (xy 119.9007 -379.993906) (xy 119.900287 -379.984719)
			(xy 119.893775 -379.967535) (xy 119.888 -379.960378) (xy 119.866181 -379.934675) (xy 119.828091 -379.879046)
			(xy 119.796938 -379.819255) (xy 119.773172 -379.756163) (xy 119.757133 -379.690679) (xy 119.749053 -379.623745)
			(xy 119.749049 -379.556325) (xy 119.757121 -379.489389) (xy 119.773151 -379.423903) (xy 119.79691 -379.360808)
			(xy 119.828056 -379.301013) (xy 119.866139 -379.245379) (xy 119.888 -379.219714) (xy 119.893816 -379.212582)
			(xy 119.900319 -379.195381) (xy 119.9007 -379.186186) (xy 119.9007 -378.693934) (xy 119.900273 -378.684749)
			(xy 119.893771 -378.667564) (xy 119.888 -378.660406) (xy 119.86611 -378.634762) (xy 119.828023 -378.579124)
			(xy 119.796873 -378.519325) (xy 119.77311 -378.456226) (xy 119.757077 -378.390734) (xy 119.749003 -378.323793)
			(xy 116.470957 -378.323793) (xy 116.462922 -378.390554) (xy 116.44695 -378.455936) (xy 116.423278 -378.518939)
			(xy 116.392245 -378.578662) (xy 116.354296 -378.634247) (xy 116.332508 -378.659898) (xy 116.326731 -378.667057)
			(xy 116.320204 -378.684237) (xy 116.319808 -378.693426) (xy 116.319808 -379.186694) (xy 116.320219 -379.195881)
			(xy 116.326732 -379.213066) (xy 116.332508 -379.220222) (xy 116.354343 -379.245836) (xy 116.392293 -379.301427)
			(xy 116.423328 -379.361155) (xy 116.447 -379.424165) (xy 116.462971 -379.489552) (xy 116.471013 -379.55638)
			(xy 116.471009 -379.623689) (xy 116.462959 -379.690516) (xy 116.44698 -379.755901) (xy 116.423299 -379.818908)
			(xy 116.392258 -379.878633) (xy 116.3543 -379.934219) (xy 116.332508 -379.95987) (xy 116.3267 -379.967007)
			(xy 116.320192 -379.984204) (xy 116.319808 -379.993398) (xy 116.319808 -380.151386) (xy 116.319256 -380.161537)
			(xy 116.311495 -380.180297) (xy 116.297148 -380.194661) (xy 116.278397 -380.202445) (xy 116.268246 -380.202948)
			(xy 115.551966 -380.202948) (xy 115.541804 -380.202494) (xy 115.523032 -380.194706) (xy 115.508667 -380.180328)
			(xy 115.500896 -380.161548) (xy 115.500404 -380.151386) (xy 115.500404 -379.993398) (xy 115.499994 -379.984211)
			(xy 115.49348 -379.967027) (xy 115.487704 -379.95987) (xy 115.465963 -379.93418) (xy 115.428015 -379.878598)
			(xy 115.396981 -379.81888) (xy 115.373307 -379.75588) (xy 115.357332 -379.690503) (xy 115.349285 -379.623685)
			(xy 115.349281 -379.556384) (xy 115.35732 -379.489565) (xy 115.373287 -379.424186) (xy 115.396953 -379.361184)
			(xy 115.427979 -379.301461) (xy 115.46592 -379.245875) (xy 115.487704 -379.220222) (xy 115.493517 -379.213088)
			(xy 115.500022 -379.195889) (xy 115.500404 -379.186694) (xy 115.500404 -378.693426) (xy 115.49998 -378.68424)
			(xy 115.493476 -378.667056) (xy 115.487704 -378.659898) (xy 115.465892 -378.634266) (xy 115.427946 -378.578676)
			(xy 115.396916 -378.518949) (xy 115.373246 -378.455942) (xy 115.357276 -378.390558) (xy 115.349234 -378.323734)
			(xy 85.670933 -378.323734) (xy 85.670933 -378.323792) (xy 85.662859 -378.390729) (xy 85.646825 -378.456217)
			(xy 85.623062 -378.519313) (xy 85.591912 -378.579108) (xy 85.553824 -378.634741) (xy 85.53196 -378.660406)
			(xy 85.526173 -378.667558) (xy 85.519654 -378.684743) (xy 85.51926 -378.693934) (xy 85.51926 -379.186186)
			(xy 85.519686 -379.195371) (xy 85.526189 -379.212555) (xy 85.53196 -379.219714) (xy 85.553871 -379.245341)
			(xy 85.591961 -379.30098) (xy 85.623111 -379.360781) (xy 85.646875 -379.423883) (xy 85.662908 -379.489377)
			(xy 85.670981 -379.55632) (xy 85.670977 -379.623749) (xy 85.662896 -379.690691) (xy 85.646854 -379.756183)
			(xy 85.623083 -379.819282) (xy 85.591925 -379.879079) (xy 85.553828 -379.934713) (xy 85.53196 -379.960378)
			(xy 85.526143 -379.967508) (xy 85.519641 -379.98471) (xy 85.51926 -379.993906) (xy 85.51926 -380.151386)
			(xy 85.518762 -380.161512) (xy 85.511039 -380.180233) (xy 85.496756 -380.194589) (xy 85.478075 -380.202409)
			(xy 85.467952 -380.202948) (xy 84.751672 -380.202948) (xy 84.741567 -380.202439) (xy 84.722898 -380.194701)
			(xy 84.708606 -380.180412) (xy 84.700863 -380.161744) (xy 84.700364 -380.15164) (xy 84.700364 -379.993906)
			(xy 84.699937 -379.984721) (xy 84.693433 -379.967537) (xy 84.687664 -379.960378) (xy 84.665846 -379.934675)
			(xy 84.627759 -379.879045) (xy 84.596608 -379.819254) (xy 84.572843 -379.756162) (xy 84.556805 -379.690678)
			(xy 84.548726 -379.623744) (xy 84.548722 -379.556325) (xy 84.556793 -379.48939) (xy 84.572822 -379.423904)
			(xy 84.59658 -379.36081) (xy 84.627723 -379.301014) (xy 84.665804 -379.24538) (xy 84.687664 -379.219714)
			(xy 84.693487 -379.212588) (xy 84.699984 -379.195383) (xy 84.700364 -379.186186) (xy 84.700364 -378.693934)
			(xy 84.699923 -378.68475) (xy 84.693429 -378.667566) (xy 84.687664 -378.660406) (xy 84.665776 -378.634761)
			(xy 84.62769 -378.579123) (xy 84.596543 -378.519324) (xy 84.572781 -378.456224) (xy 84.556749 -378.390733)
			(xy 84.548676 -378.323793) (xy 81.271142 -378.323793) (xy 81.263068 -378.390729) (xy 81.247035 -378.456217)
			(xy 81.223272 -378.519312) (xy 81.192123 -378.579108) (xy 81.154035 -378.634741) (xy 81.132172 -378.660406)
			(xy 81.126387 -378.667559) (xy 81.119866 -378.684744) (xy 81.119472 -378.693934) (xy 81.119472 -379.186186)
			(xy 81.119895 -379.195372) (xy 81.126401 -379.212556) (xy 81.132172 -379.219714) (xy 81.154082 -379.245341)
			(xy 81.192171 -379.300981) (xy 81.223322 -379.360782) (xy 81.247084 -379.423884) (xy 81.263118 -379.489378)
			(xy 81.27119 -379.556321) (xy 81.271186 -379.623748) (xy 81.263105 -379.69069) (xy 81.247064 -379.756182)
			(xy 81.223293 -379.819281) (xy 81.192136 -379.879079) (xy 81.15404 -379.934713) (xy 81.132172 -379.960378)
			(xy 81.126356 -379.967509) (xy 81.119854 -379.984711) (xy 81.119472 -379.993906) (xy 81.119472 -380.151386)
			(xy 81.118962 -380.16151) (xy 81.111241 -380.180229) (xy 81.096962 -380.194585) (xy 81.078286 -380.202407)
			(xy 81.068164 -380.202948) (xy 80.351884 -380.202948) (xy 80.34178 -380.202429) (xy 80.323111 -380.194695)
			(xy 80.308818 -380.180409) (xy 80.301076 -380.161744) (xy 80.300576 -380.15164) (xy 80.300576 -379.993906)
			(xy 80.300168 -379.984718) (xy 80.293654 -379.967534) (xy 80.287876 -379.960378) (xy 80.266058 -379.934675)
			(xy 80.22797 -379.879045) (xy 80.196818 -379.819254) (xy 80.173052 -379.756162) (xy 80.157015 -379.690678)
			(xy 80.148935 -379.623744) (xy 80.148931 -379.556325) (xy 80.157002 -379.48939) (xy 80.173032 -379.423904)
			(xy 80.19679 -379.360809) (xy 80.227934 -379.301014) (xy 80.266016 -379.24538) (xy 80.287876 -379.219714)
			(xy 80.293689 -379.21258) (xy 80.300195 -379.195381) (xy 80.300576 -379.186186) (xy 80.300576 -378.693934)
			(xy 80.300155 -378.684748) (xy 80.29365 -378.667563) (xy 80.287876 -378.660406) (xy 80.265987 -378.634761)
			(xy 80.227901 -378.579123) (xy 80.196753 -378.519324) (xy 80.172991 -378.456225) (xy 80.156958 -378.390733)
			(xy 80.148885 -378.323793) (xy 76.870815 -378.323793) (xy 76.862781 -378.390552) (xy 76.846812 -378.455933)
			(xy 76.823143 -378.518936) (xy 76.792114 -378.578659) (xy 76.75417 -378.634246) (xy 76.732384 -378.659898)
			(xy 76.726604 -378.667055) (xy 76.72008 -378.684236) (xy 76.719684 -378.693426) (xy 76.719684 -379.186694)
			(xy 76.720101 -379.19588) (xy 76.72661 -379.213065) (xy 76.732384 -379.220222) (xy 76.754216 -379.245837)
			(xy 76.792162 -379.30143) (xy 76.823192 -379.361158) (xy 76.846861 -379.424168) (xy 76.86283 -379.489554)
			(xy 76.870871 -379.55638) (xy 76.870866 -379.623689) (xy 76.862818 -379.690514) (xy 76.846841 -379.755899)
			(xy 76.823164 -379.818905) (xy 76.792127 -379.87863) (xy 76.754174 -379.934218) (xy 76.732384 -379.95987)
			(xy 76.726573 -379.967005) (xy 76.720068 -379.984203) (xy 76.719684 -379.993398) (xy 76.719684 -380.151386)
			(xy 76.719156 -380.16154) (xy 76.71139 -380.180305) (xy 76.697035 -380.19467) (xy 76.678276 -380.202449)
			(xy 76.668122 -380.202948) (xy 75.951842 -380.202948) (xy 75.941671 -380.202501) (xy 75.922875 -380.194728)
			(xy 75.908488 -380.180349) (xy 75.900704 -380.161556) (xy 75.90028 -380.151386) (xy 75.90028 -379.993398)
			(xy 75.899875 -379.98421) (xy 75.893358 -379.967026) (xy 75.88758 -379.95987) (xy 75.865836 -379.934181)
			(xy 75.827883 -379.878601) (xy 75.796846 -379.818883) (xy 75.773169 -379.755883) (xy 75.757191 -379.690505)
			(xy 75.749143 -379.623686) (xy 75.749139 -379.556383) (xy 75.757179 -379.489563) (xy 75.773148 -379.424183)
			(xy 75.796818 -379.36118) (xy 75.827848 -379.301458) (xy 75.865794 -379.245874) (xy 75.88758 -379.220222)
			(xy 75.89339 -379.213086) (xy 75.899897 -379.195889) (xy 75.90028 -379.186694) (xy 75.90028 -378.693426)
			(xy 75.899862 -378.68424) (xy 75.893354 -378.667055) (xy 75.88758 -378.659898) (xy 75.865766 -378.634267)
			(xy 75.827815 -378.578679) (xy 75.79678 -378.518953) (xy 75.773107 -378.455945) (xy 75.757135 -378.39056)
			(xy 75.749092 -378.323734) (xy 72.471054 -378.323734) (xy 72.471054 -378.323791) (xy 72.46298 -378.390728)
			(xy 72.446947 -378.456216) (xy 72.423186 -378.519312) (xy 72.392037 -378.579107) (xy 72.353951 -378.634741)
			(xy 72.332088 -378.660406) (xy 72.326305 -378.667561) (xy 72.319783 -378.684744) (xy 72.319388 -378.693934)
			(xy 72.319388 -379.186186) (xy 72.319808 -379.195372) (xy 72.326315 -379.212556) (xy 72.332088 -379.219714)
			(xy 72.353998 -379.245342) (xy 72.392086 -379.300981) (xy 72.423235 -379.360783) (xy 72.446997 -379.423884)
			(xy 72.46303 -379.489378) (xy 72.471102 -379.556321) (xy 72.471098 -379.623748) (xy 72.463017 -379.69069)
			(xy 72.446977 -379.756182) (xy 72.423207 -379.819281) (xy 72.39205 -379.879078) (xy 72.353955 -379.934713)
			(xy 72.332088 -379.960378) (xy 72.326274 -379.967511) (xy 72.31977 -379.984711) (xy 72.319388 -379.993906)
			(xy 72.319388 -380.151386) (xy 72.318863 -380.161508) (xy 72.311145 -380.180224) (xy 72.296871 -380.19458)
			(xy 72.278199 -380.202404) (xy 72.26808 -380.202948) (xy 71.5518 -380.202948) (xy 71.541652 -380.202479)
			(xy 71.522909 -380.194693) (xy 71.508587 -380.180311) (xy 71.500879 -380.161536) (xy 71.500492 -380.151386)
			(xy 71.500492 -379.993906) (xy 71.500081 -379.984719) (xy 71.493568 -379.967534) (xy 71.487792 -379.960378)
			(xy 71.465974 -379.934675) (xy 71.427884 -379.879046) (xy 71.396732 -379.819255) (xy 71.372965 -379.756163)
			(xy 71.356927 -379.690678) (xy 71.348847 -379.623744) (xy 71.348843 -379.556325) (xy 71.356914 -379.48939)
			(xy 71.372945 -379.423903) (xy 71.396703 -379.360808) (xy 71.427848 -379.301013) (xy 71.465931 -379.245379)
			(xy 71.487792 -379.219714) (xy 71.493607 -379.212582) (xy 71.500111 -379.195381) (xy 71.500492 -379.186186)
			(xy 71.500492 -378.693934) (xy 71.500067 -378.684748) (xy 71.493564 -378.667564) (xy 71.487792 -378.660406)
			(xy 71.465903 -378.634762) (xy 71.427815 -378.579124) (xy 71.396666 -378.519325) (xy 71.372904 -378.456225)
			(xy 71.35687 -378.390734) (xy 71.348797 -378.323793) (xy 41.671024 -378.323793) (xy 41.66295 -378.390729)
			(xy 41.646915 -378.456218) (xy 41.623152 -378.519314) (xy 41.592001 -378.579109) (xy 41.553912 -378.634742)
			(xy 41.532048 -378.660406) (xy 41.52626 -378.667557) (xy 41.519742 -378.684743) (xy 41.519348 -378.693934)
			(xy 41.519348 -379.186186) (xy 41.519776 -379.195371) (xy 41.526279 -379.212555) (xy 41.532048 -379.219714)
			(xy 41.553959 -379.245341) (xy 41.59205 -379.30098) (xy 41.623201 -379.360781) (xy 41.646965 -379.423883)
			(xy 41.662999 -379.489377) (xy 41.671072 -379.55632) (xy 41.671068 -379.623749) (xy 41.662987 -379.690691)
			(xy 41.646945 -379.756183) (xy 41.623173 -379.819282) (xy 41.592014 -379.879079) (xy 41.553917 -379.934714)
			(xy 41.532048 -379.960378) (xy 41.526229 -379.967507) (xy 41.519729 -379.98471) (xy 41.519348 -379.993906)
			(xy 41.519348 -380.151386) (xy 41.518862 -380.161513) (xy 41.511136 -380.180236) (xy 41.49685 -380.194594)
			(xy 41.478165 -380.202411) (xy 41.46804 -380.202948) (xy 40.75176 -380.202948) (xy 40.741609 -380.202512)
			(xy 40.722865 -380.194712) (xy 40.708545 -380.180321) (xy 40.700838 -380.161539) (xy 40.700452 -380.151386)
			(xy 40.700452 -379.993906) (xy 40.700027 -379.984721) (xy 40.693523 -379.967537) (xy 40.687752 -379.960378)
			(xy 40.665931 -379.934676) (xy 40.627838 -379.879048) (xy 40.596682 -379.819258) (xy 40.572913 -379.756165)
			(xy 40.556873 -379.69068) (xy 40.548793 -379.623745) (xy 40.548788 -379.556324) (xy 40.556861 -379.489388)
			(xy 40.572893 -379.423901) (xy 40.596654 -379.360806) (xy 40.627802 -379.301011) (xy 40.665889 -379.245378)
			(xy 40.687752 -379.219714) (xy 40.693574 -379.212587) (xy 40.700072 -379.195382) (xy 40.700452 -379.186186)
			(xy 40.700452 -378.693934) (xy 40.700014 -378.68475) (xy 40.693519 -378.667566) (xy 40.687752 -378.660406)
			(xy 40.665861 -378.634763) (xy 40.627769 -378.579126) (xy 40.596617 -378.519328) (xy 40.572852 -378.456228)
			(xy 40.556817 -378.390735) (xy 40.548742 -378.323794) (xy 37.271233 -378.323794) (xy 37.263159 -378.390729)
			(xy 37.247125 -378.456217) (xy 37.223362 -378.519313) (xy 37.192212 -378.579108) (xy 37.154124 -378.634741)
			(xy 37.13226 -378.660406) (xy 37.126473 -378.667558) (xy 37.119954 -378.684743) (xy 37.11956 -378.693934)
			(xy 37.11956 -379.186186) (xy 37.119986 -379.195371) (xy 37.126489 -379.212555) (xy 37.13226 -379.219714)
			(xy 37.154171 -379.245341) (xy 37.192261 -379.30098) (xy 37.223411 -379.360781) (xy 37.247175 -379.423883)
			(xy 37.263208 -379.489377) (xy 37.271281 -379.55632) (xy 37.271277 -379.623749) (xy 37.263196 -379.690691)
			(xy 37.247154 -379.756183) (xy 37.223383 -379.819282) (xy 37.192225 -379.879079) (xy 37.154128 -379.934713)
			(xy 37.13226 -379.960378) (xy 37.126443 -379.967508) (xy 37.119941 -379.98471) (xy 37.11956 -379.993906)
			(xy 37.11956 -380.151386) (xy 37.119062 -380.161512) (xy 37.111339 -380.180233) (xy 37.097056 -380.194589)
			(xy 37.078375 -380.202409) (xy 37.068252 -380.202948) (xy 36.351972 -380.202948) (xy 36.341822 -380.202502)
			(xy 36.323078 -380.194707) (xy 36.308758 -380.180318) (xy 36.30105 -380.161538) (xy 36.300664 -380.151386)
			(xy 36.300664 -379.993906) (xy 36.300237 -379.984721) (xy 36.293733 -379.967537) (xy 36.287964 -379.960378)
			(xy 36.266146 -379.934675) (xy 36.228059 -379.879045) (xy 36.196908 -379.819254) (xy 36.173143 -379.756162)
			(xy 36.157105 -379.690678) (xy 36.149026 -379.623744) (xy 36.149022 -379.556325) (xy 36.157093 -379.48939)
			(xy 36.173122 -379.423904) (xy 36.19688 -379.36081) (xy 36.228023 -379.301014) (xy 36.266104 -379.24538)
			(xy 36.287964 -379.219714) (xy 36.293787 -379.212588) (xy 36.300284 -379.195383) (xy 36.300664 -379.186186)
			(xy 36.300664 -378.693934) (xy 36.300223 -378.68475) (xy 36.293729 -378.667566) (xy 36.287964 -378.660406)
			(xy 36.266076 -378.634761) (xy 36.22799 -378.579123) (xy 36.196843 -378.519324) (xy 36.173081 -378.456224)
			(xy 36.157049 -378.390733) (xy 36.148976 -378.323793) (xy 32.870906 -378.323793) (xy 32.862871 -378.390552)
			(xy 32.846902 -378.455933) (xy 32.823232 -378.518936) (xy 32.792203 -378.578659) (xy 32.754258 -378.634246)
			(xy 32.732472 -378.659898) (xy 32.72669 -378.667053) (xy 32.720167 -378.684236) (xy 32.719772 -378.693426)
			(xy 32.719772 -379.186694) (xy 32.720191 -379.19588) (xy 32.726699 -379.213064) (xy 32.732472 -379.220222)
			(xy 32.754305 -379.245837) (xy 32.792251 -379.301429) (xy 32.823282 -379.361158) (xy 32.846952 -379.424167)
			(xy 32.862921 -379.489554) (xy 32.870962 -379.55638) (xy 32.870957 -379.623689) (xy 32.862909 -379.690514)
			(xy 32.846931 -379.755899) (xy 32.823254 -379.818905) (xy 32.792216 -379.87863) (xy 32.754262 -379.934218)
			(xy 32.732472 -379.95987) (xy 32.72666 -379.967004) (xy 32.720155 -379.984203) (xy 32.719772 -379.993398)
			(xy 32.719772 -380.151386) (xy 32.719325 -380.161556) (xy 32.711547 -380.180348) (xy 32.697168 -380.194733)
			(xy 32.678379 -380.20252) (xy 32.66821 -380.202948) (xy 31.95193 -380.202948) (xy 31.941759 -380.202511)
			(xy 31.922962 -380.194733) (xy 31.908576 -380.180351) (xy 31.900792 -380.161557) (xy 31.900368 -380.151386)
			(xy 31.900368 -379.993398) (xy 31.899944 -379.984213) (xy 31.893438 -379.967029) (xy 31.887668 -379.95987)
			(xy 31.865925 -379.934181) (xy 31.827973 -379.878601) (xy 31.796936 -379.818882) (xy 31.773259 -379.755883)
			(xy 31.757282 -379.690505) (xy 31.749234 -379.623686) (xy 31.74923 -379.556384) (xy 31.75727 -379.489564)
			(xy 31.773239 -379.424184) (xy 31.796908 -379.361181) (xy 31.827937 -379.301459) (xy 31.865882 -379.245874)
			(xy 31.887668 -379.220222) (xy 31.893488 -379.213094) (xy 31.899987 -379.19589) (xy 31.900368 -379.186694)
			(xy 31.900368 -378.693426) (xy 31.89993 -378.684242) (xy 31.893434 -378.667058) (xy 31.887668 -378.659898)
			(xy 31.865854 -378.634267) (xy 31.827904 -378.578678) (xy 31.79687 -378.518952) (xy 31.773198 -378.455945)
			(xy 31.757226 -378.39056) (xy 31.749183 -378.323734) (xy 28.471145 -378.323734) (xy 28.471145 -378.323792)
			(xy 28.463071 -378.390728) (xy 28.447038 -378.456216) (xy 28.423275 -378.519312) (xy 28.392126 -378.579108)
			(xy 28.354039 -378.634741) (xy 28.332176 -378.660406) (xy 28.326392 -378.66756) (xy 28.31987 -378.684744)
			(xy 28.319476 -378.693934) (xy 28.319476 -379.186186) (xy 28.319898 -379.195372) (xy 28.326404 -379.212556)
			(xy 28.332176 -379.219714) (xy 28.354036 -379.245382) (xy 28.392125 -379.301016) (xy 28.423276 -379.360812)
			(xy 28.447 -379.423801) (xy 29.549058 -379.423801) (xy 29.549059 -379.356496) (xy 29.557103 -379.289673)
			(xy 29.573076 -379.224291) (xy 29.596749 -379.161286) (xy 29.627783 -379.101562) (xy 29.665732 -379.045976)
			(xy 29.68752 -379.020324) (xy 29.693334 -379.013191) (xy 29.699837 -378.995991) (xy 29.70022 -378.986796)
			(xy 29.70022 -378.828554) (xy 29.700695 -378.818396) (xy 29.708482 -378.799629) (xy 29.722852 -378.785266)
			(xy 29.741623 -378.77749) (xy 29.751782 -378.776992) (xy 30.468062 -378.776992) (xy 30.478212 -378.777564)
			(xy 30.496971 -378.785317) (xy 30.511336 -378.799658) (xy 30.51912 -378.818405) (xy 30.519624 -378.828554)
			(xy 30.519624 -378.986796) (xy 30.520031 -378.995984) (xy 30.526546 -379.013168) (xy 30.532324 -379.020324)
			(xy 30.55411 -379.045978) (xy 30.592059 -379.101564) (xy 30.623093 -379.161287) (xy 30.646766 -379.224291)
			(xy 30.662739 -379.289673) (xy 30.670784 -379.356496) (xy 30.670784 -379.423801) (xy 30.66274 -379.490624)
			(xy 30.646767 -379.556006) (xy 30.623094 -379.61901) (xy 30.592061 -379.678734) (xy 30.554112 -379.73432)
			(xy 30.532324 -379.759972) (xy 30.526517 -379.76711) (xy 30.520008 -379.784306) (xy 30.519624 -379.7935)
			(xy 30.519624 -380.286768) (xy 30.520044 -380.295954) (xy 30.52655 -380.313139) (xy 30.532324 -380.320296)
			(xy 30.554132 -380.345932) (xy 30.592083 -380.40152) (xy 30.623117 -380.461245) (xy 30.646791 -380.524252)
			(xy 30.662763 -380.589636) (xy 30.6708 -380.656404) (xy 33.948845 -380.656404) (xy 33.95692 -380.589467)
			(xy 33.972953 -380.523978) (xy 33.996716 -380.460882) (xy 34.027865 -380.401087) (xy 34.065953 -380.345453)
			(xy 34.087816 -380.319788) (xy 34.093602 -380.312635) (xy 34.100122 -380.29545) (xy 34.100516 -380.28626)
			(xy 34.100516 -379.794008) (xy 34.100098 -379.784822) (xy 34.093589 -379.767638) (xy 34.087816 -379.76048)
			(xy 34.065999 -379.734776) (xy 34.027907 -379.679148) (xy 33.996754 -379.619357) (xy 33.972986 -379.556265)
			(xy 33.956947 -379.49078) (xy 33.948867 -379.423846) (xy 33.948863 -379.356426) (xy 33.956934 -379.289491)
			(xy 33.972965 -379.224004) (xy 33.996724 -379.160909) (xy 34.02787 -379.101114) (xy 34.065954 -379.045481)
			(xy 34.087816 -379.019816) (xy 34.093633 -379.012685) (xy 34.100135 -378.995484) (xy 34.100516 -378.986288)
			(xy 34.100516 -378.828554) (xy 34.100988 -378.818427) (xy 34.108727 -378.79971) (xy 34.123017 -378.785356)
			(xy 34.1417 -378.777534) (xy 34.151824 -378.776992) (xy 34.868104 -378.776992) (xy 34.878257 -378.777418)
			(xy 34.897008 -378.785214) (xy 34.911331 -378.799609) (xy 34.919032 -378.818399) (xy 34.919412 -378.828554)
			(xy 34.919412 -378.986288) (xy 34.919825 -378.995475) (xy 34.926336 -379.012659) (xy 34.932112 -379.019816)
			(xy 34.954023 -379.045443) (xy 34.992109 -379.101083) (xy 35.023257 -379.160885) (xy 35.047018 -379.223986)
			(xy 35.06305 -379.28948) (xy 35.071122 -379.356422) (xy 35.071117 -379.42385) (xy 35.063037 -379.490791)
			(xy 35.046997 -379.556283) (xy 35.023228 -379.619381) (xy 34.992072 -379.679179) (xy 34.953978 -379.734815)
			(xy 34.932112 -379.76048) (xy 34.9263 -379.767615) (xy 34.919794 -379.784813) (xy 34.919412 -379.794008)
			(xy 34.919412 -380.28626) (xy 34.919839 -380.295446) (xy 34.92634 -380.31263) (xy 34.932112 -380.319788)
			(xy 34.953995 -380.345437) (xy 34.992083 -380.401074) (xy 35.023232 -380.460873) (xy 35.046994 -380.523972)
			(xy 35.063028 -380.589463) (xy 35.071102 -380.656403) (xy 35.071102 -380.656464) (xy 38.349165 -380.656464)
			(xy 38.357207 -380.589643) (xy 38.373176 -380.524262) (xy 38.396845 -380.461259) (xy 38.427874 -380.401536)
			(xy 38.465819 -380.345949) (xy 38.487604 -380.320296) (xy 38.493385 -380.31314) (xy 38.499909 -380.295958)
			(xy 38.500304 -380.286768) (xy 38.500304 -379.7935) (xy 38.499893 -379.784313) (xy 38.49338 -379.767129)
			(xy 38.487604 -379.759972) (xy 38.465865 -379.73428) (xy 38.427917 -379.678699) (xy 38.396884 -379.61898)
			(xy 38.37321 -379.555981) (xy 38.357234 -379.490604) (xy 38.349187 -379.423786) (xy 38.349183 -379.356486)
			(xy 38.357221 -379.289667) (xy 38.373188 -379.224288) (xy 38.396854 -379.161286) (xy 38.42788 -379.101563)
			(xy 38.465821 -379.045977) (xy 38.487604 -379.020324) (xy 38.493416 -379.01319) (xy 38.499921 -378.995991)
			(xy 38.500304 -378.986796) (xy 38.500304 -378.828554) (xy 38.500795 -378.818397) (xy 38.508578 -378.799634)
			(xy 38.522944 -378.785271) (xy 38.541709 -378.777493) (xy 38.551866 -378.776992) (xy 39.268146 -378.776992)
			(xy 39.278301 -378.777495) (xy 39.297062 -378.785276) (xy 39.311424 -378.799638) (xy 39.319205 -378.818399)
			(xy 39.319708 -378.828554) (xy 39.319708 -378.986796) (xy 39.320118 -378.995983) (xy 39.326632 -379.013168)
			(xy 39.332408 -379.020324) (xy 39.354244 -379.045937) (xy 39.392195 -379.101528) (xy 39.423229 -379.161256)
			(xy 39.446902 -379.224266) (xy 39.462873 -379.289653) (xy 39.470914 -379.356481) (xy 39.47091 -379.423791)
			(xy 39.46286 -379.490618) (xy 39.44688 -379.556003) (xy 39.4232 -379.61901) (xy 39.392158 -379.678735)
			(xy 39.3542 -379.734321) (xy 39.332408 -379.759972) (xy 39.326599 -379.767109) (xy 39.320092 -379.784306)
			(xy 39.319708 -379.7935) (xy 39.319708 -380.286768) (xy 39.320132 -380.295954) (xy 39.326636 -380.313138)
			(xy 39.332408 -380.320296) (xy 39.354217 -380.345931) (xy 39.392169 -380.401519) (xy 39.423204 -380.461244)
			(xy 39.446878 -380.524251) (xy 39.462851 -380.589636) (xy 39.470887 -380.656404) (xy 42.748933 -380.656404)
			(xy 42.757007 -380.589467) (xy 42.773041 -380.523979) (xy 42.796803 -380.460883) (xy 42.827951 -380.401087)
			(xy 42.866037 -380.345453) (xy 42.8879 -380.319788) (xy 42.893684 -380.312634) (xy 42.900206 -380.29545)
			(xy 42.9006 -380.28626) (xy 42.9006 -379.794008) (xy 42.900186 -379.784821) (xy 42.893675 -379.767637)
			(xy 42.8879 -379.76048) (xy 42.866083 -379.734776) (xy 42.827993 -379.679147) (xy 42.79684 -379.619356)
			(xy 42.773073 -379.556264) (xy 42.757035 -379.49078) (xy 42.748955 -379.423846) (xy 42.748951 -379.356426)
			(xy 42.757022 -379.289491) (xy 42.773052 -379.224005) (xy 42.796811 -379.16091) (xy 42.827956 -379.101115)
			(xy 42.866039 -379.045481) (xy 42.8879 -379.019816) (xy 42.893715 -379.012684) (xy 42.900219 -378.995483)
			(xy 42.9006 -378.986288) (xy 42.9006 -378.828554) (xy 42.901088 -378.818429) (xy 42.908823 -378.799715)
			(xy 42.923108 -378.785361) (xy 42.941786 -378.777537) (xy 42.951908 -378.776992) (xy 43.668188 -378.776992)
			(xy 43.67834 -378.777431) (xy 43.697091 -378.785221) (xy 43.711414 -378.799613) (xy 43.719116 -378.8184)
			(xy 43.719496 -378.828554) (xy 43.719496 -378.986288) (xy 43.719913 -378.995474) (xy 43.726422 -379.012659)
			(xy 43.732196 -379.019816) (xy 43.754107 -379.045442) (xy 43.792195 -379.101082) (xy 43.823344 -379.160884)
			(xy 43.847105 -379.223986) (xy 43.863138 -379.28948) (xy 43.87121 -379.356422) (xy 43.871205 -379.42385)
			(xy 43.863125 -379.490791) (xy 43.847084 -379.556283) (xy 43.823314 -379.619382) (xy 43.792158 -379.67918)
			(xy 43.754063 -379.734815) (xy 43.732196 -379.76048) (xy 43.726382 -379.767613) (xy 43.719878 -379.784813)
			(xy 43.719496 -379.794008) (xy 43.719496 -380.28626) (xy 43.719926 -380.295445) (xy 43.726426 -380.31263)
			(xy 43.732196 -380.319788) (xy 43.75408 -380.345437) (xy 43.792168 -380.401074) (xy 43.823318 -380.460872)
			(xy 43.847081 -380.523971) (xy 43.863116 -380.589462) (xy 43.87119 -380.656402) (xy 43.87119 -380.656463)
			(xy 73.548987 -380.656463) (xy 73.557029 -380.589642) (xy 73.572999 -380.524261) (xy 73.596669 -380.461258)
			(xy 73.6277 -380.401535) (xy 73.665646 -380.345948) (xy 73.687432 -380.320296) (xy 73.693217 -380.313143)
			(xy 73.699738 -380.295958) (xy 73.700132 -380.286768) (xy 73.700132 -379.7935) (xy 73.699715 -379.784314)
			(xy 73.693205 -379.76713) (xy 73.687432 -379.759972) (xy 73.665692 -379.734281) (xy 73.627742 -379.6787)
			(xy 73.596707 -379.618982) (xy 73.573032 -379.555982) (xy 73.557056 -379.490605) (xy 73.549008 -379.423787)
			(xy 73.549004 -379.356486) (xy 73.557043 -379.289666) (xy 73.573011 -379.224287) (xy 73.596678 -379.161285)
			(xy 73.627705 -379.101562) (xy 73.665648 -379.045976) (xy 73.687432 -379.020324) (xy 73.693247 -379.013192)
			(xy 73.69975 -378.995991) (xy 73.700132 -378.986796) (xy 73.700132 -378.828554) (xy 73.700596 -378.818394)
			(xy 73.708384 -378.799625) (xy 73.722759 -378.785262) (xy 73.741534 -378.777488) (xy 73.751694 -378.776992)
			(xy 74.467974 -378.776992) (xy 74.478125 -378.777553) (xy 74.496884 -378.785311) (xy 74.511249 -378.799655)
			(xy 74.519032 -378.818404) (xy 74.519536 -378.828554) (xy 74.519536 -378.986796) (xy 74.519962 -378.995981)
			(xy 74.526466 -379.013165) (xy 74.532236 -379.020324) (xy 74.554072 -379.045937) (xy 74.592021 -379.101528)
			(xy 74.623053 -379.161257) (xy 74.646725 -379.224267) (xy 74.662695 -379.289654) (xy 74.670736 -379.356481)
			(xy 74.670731 -379.423791) (xy 74.662682 -379.490617) (xy 74.646703 -379.556002) (xy 74.623024 -379.619009)
			(xy 74.591984 -379.678734) (xy 74.554028 -379.73432) (xy 74.532236 -379.759972) (xy 74.526419 -379.767102)
			(xy 74.519918 -379.784304) (xy 74.519536 -379.7935) (xy 74.519536 -380.286768) (xy 74.519976 -380.295952)
			(xy 74.52647 -380.313136) (xy 74.532236 -380.320296) (xy 74.554044 -380.345932) (xy 74.591994 -380.40152)
			(xy 74.623028 -380.461246) (xy 74.6467 -380.524252) (xy 74.662673 -380.589637) (xy 74.670709 -380.656404)
			(xy 77.948754 -380.656404) (xy 77.956829 -380.589466) (xy 77.972863 -380.523978) (xy 77.996626 -380.460882)
			(xy 78.027776 -380.401086) (xy 78.065864 -380.345453) (xy 78.087728 -380.319788) (xy 78.093516 -380.312637)
			(xy 78.100035 -380.295451) (xy 78.100428 -380.28626) (xy 78.100428 -379.794008) (xy 78.100008 -379.784822)
			(xy 78.093501 -379.767638) (xy 78.087728 -379.76048) (xy 78.06591 -379.734776) (xy 78.027818 -379.679148)
			(xy 77.996664 -379.619357) (xy 77.972896 -379.556265) (xy 77.956856 -379.490781) (xy 77.948776 -379.423846)
			(xy 77.948772 -379.356426) (xy 77.956843 -379.28949) (xy 77.972874 -379.224004) (xy 77.996634 -379.160909)
			(xy 78.027781 -379.101114) (xy 78.065866 -379.045481) (xy 78.087728 -379.019816) (xy 78.093546 -379.012686)
			(xy 78.100047 -378.995484) (xy 78.100428 -378.986288) (xy 78.100428 -378.828554) (xy 78.100889 -378.818426)
			(xy 78.108629 -378.799706) (xy 78.122923 -378.785352) (xy 78.14161 -378.777532) (xy 78.151736 -378.776992)
			(xy 78.868016 -378.776992) (xy 78.878125 -378.777472) (xy 78.896802 -378.785213) (xy 78.911096 -378.799512)
			(xy 78.918831 -378.818191) (xy 78.919324 -378.8283) (xy 78.919324 -378.986288) (xy 78.919734 -378.995475)
			(xy 78.926247 -379.01266) (xy 78.932024 -379.019816) (xy 78.953934 -379.045443) (xy 78.99202 -379.101083)
			(xy 79.023167 -379.160885) (xy 79.046928 -379.223987) (xy 79.062959 -379.28948) (xy 79.071031 -379.356423)
			(xy 79.071026 -379.42385) (xy 79.062946 -379.490791) (xy 79.046906 -379.556282) (xy 79.023138 -379.619381)
			(xy 78.991983 -379.679179) (xy 78.95389 -379.734814) (xy 78.932024 -379.76048) (xy 78.926214 -379.767616)
			(xy 78.919706 -379.784813) (xy 78.919324 -379.794008) (xy 78.919324 -380.28626) (xy 78.919748 -380.295446)
			(xy 78.926251 -380.312631) (xy 78.932024 -380.319788) (xy 78.953907 -380.345437) (xy 78.991993 -380.401075)
			(xy 79.023142 -380.460873) (xy 79.046904 -380.523972) (xy 79.062937 -380.589463) (xy 79.071011 -380.656403)
			(xy 79.071011 -380.656464) (xy 82.349074 -380.656464) (xy 82.357116 -380.589643) (xy 82.373086 -380.524262)
			(xy 82.396755 -380.461258) (xy 82.427785 -380.401535) (xy 82.46573 -380.345948) (xy 82.487516 -380.320296)
			(xy 82.493299 -380.313141) (xy 82.499821 -380.295958) (xy 82.500216 -380.286768) (xy 82.500216 -379.7935)
			(xy 82.499803 -379.784313) (xy 82.493291 -379.767129) (xy 82.487516 -379.759972) (xy 82.465776 -379.734281)
			(xy 82.427828 -379.678699) (xy 82.396794 -379.618981) (xy 82.373119 -379.555982) (xy 82.357144 -379.490604)
			(xy 82.349096 -379.423786) (xy 82.349092 -379.356486) (xy 82.357131 -379.289667) (xy 82.373098 -379.224288)
			(xy 82.396764 -379.161285) (xy 82.427791 -379.101563) (xy 82.465732 -379.045977) (xy 82.487516 -379.020324)
			(xy 82.493329 -379.013191) (xy 82.499833 -378.995991) (xy 82.500216 -378.986796) (xy 82.500216 -378.828554)
			(xy 82.500695 -378.818396) (xy 82.508481 -378.79963) (xy 82.52285 -378.785267) (xy 82.54162 -378.777491)
			(xy 82.551778 -378.776992) (xy 83.268058 -378.776992) (xy 83.278207 -378.777567) (xy 83.296967 -378.785319)
			(xy 83.311332 -378.799659) (xy 83.319116 -378.818405) (xy 83.31962 -378.828554) (xy 83.31962 -378.986796)
			(xy 83.320028 -378.995984) (xy 83.326543 -379.013168) (xy 83.33232 -379.020324) (xy 83.354156 -379.045937)
			(xy 83.392107 -379.101528) (xy 83.42314 -379.161256) (xy 83.446812 -379.224266) (xy 83.462783 -379.289654)
			(xy 83.470824 -379.356481) (xy 83.470819 -379.423791) (xy 83.46277 -379.490618) (xy 83.446791 -379.556003)
			(xy 83.423111 -379.61901) (xy 83.392069 -379.678734) (xy 83.354112 -379.734321) (xy 83.33232 -379.759972)
			(xy 83.326513 -379.76711) (xy 83.320004 -379.784306) (xy 83.31962 -379.7935) (xy 83.31962 -380.286768)
			(xy 83.320041 -380.295954) (xy 83.326547 -380.313139) (xy 83.33232 -380.320296) (xy 83.354129 -380.345931)
			(xy 83.392079 -380.401519) (xy 83.423114 -380.461245) (xy 83.446788 -380.524252) (xy 83.46276 -380.589636)
			(xy 83.470797 -380.656404) (xy 86.748842 -380.656404) (xy 86.756916 -380.589467) (xy 86.77295 -380.523979)
			(xy 86.796713 -380.460883) (xy 86.827862 -380.401087) (xy 86.865949 -380.345453) (xy 86.887812 -380.319788)
			(xy 86.893598 -380.312635) (xy 86.900118 -380.29545) (xy 86.900512 -380.28626) (xy 86.900512 -379.794008)
			(xy 86.900095 -379.784822) (xy 86.893586 -379.767637) (xy 86.887812 -379.76048) (xy 86.865995 -379.734776)
			(xy 86.827904 -379.679147) (xy 86.79675 -379.619357) (xy 86.772983 -379.556265) (xy 86.756944 -379.49078)
			(xy 86.748864 -379.423846) (xy 86.74886 -379.356426) (xy 86.756931 -379.289491) (xy 86.772962 -379.224004)
			(xy 86.796721 -379.160909) (xy 86.827867 -379.101115) (xy 86.86595 -379.045481) (xy 86.887812 -379.019816)
			(xy 86.893628 -379.012685) (xy 86.900131 -378.995483) (xy 86.900512 -378.986288) (xy 86.900512 -378.828554)
			(xy 86.900988 -378.818428) (xy 86.908726 -378.799711) (xy 86.923015 -378.785357) (xy 86.941696 -378.777535)
			(xy 86.95182 -378.776992) (xy 87.6681 -378.776992) (xy 87.678208 -378.777485) (xy 87.696884 -378.785221)
			(xy 87.711179 -378.799516) (xy 87.718915 -378.818192) (xy 87.719408 -378.8283) (xy 87.719408 -378.986288)
			(xy 87.719822 -378.995475) (xy 87.726333 -379.012659) (xy 87.732108 -379.019816) (xy 87.754019 -379.045442)
			(xy 87.792106 -379.101083) (xy 87.823254 -379.160884) (xy 87.847015 -379.223986) (xy 87.863047 -379.28948)
			(xy 87.871119 -379.356422) (xy 87.871114 -379.42385) (xy 87.863034 -379.490791) (xy 87.846994 -379.556283)
			(xy 87.823224 -379.619382) (xy 87.792068 -379.679179) (xy 87.753975 -379.734815) (xy 87.732108 -379.76048)
			(xy 87.726296 -379.767614) (xy 87.71979 -379.784813) (xy 87.719408 -379.794008) (xy 87.719408 -380.28626)
			(xy 87.719836 -380.295445) (xy 87.726337 -380.31263) (xy 87.732108 -380.319788) (xy 87.753991 -380.345437)
			(xy 87.792079 -380.401074) (xy 87.823228 -380.460873) (xy 87.846991 -380.523972) (xy 87.863025 -380.589463)
			(xy 87.871099 -380.656402) (xy 87.871097 -380.723828) (xy 87.863019 -380.790767) (xy 87.846982 -380.856257)
			(xy 87.838954 -380.877572) (xy 105.0036 -380.877572) (xy 105.0036 -380.013972) (xy 105.00409 -379.983988)
			(xy 105.011918 -379.924532) (xy 105.027439 -379.866607) (xy 105.050388 -379.811203) (xy 105.080372 -379.759269)
			(xy 105.116878 -379.711693) (xy 105.159283 -379.669288) (xy 105.206859 -379.632782) (xy 105.258793 -379.602798)
			(xy 105.314197 -379.579849) (xy 105.372122 -379.564328) (xy 105.431578 -379.5565) (xy 105.491546 -379.5565)
			(xy 105.551002 -379.564328) (xy 105.608927 -379.579849) (xy 105.664331 -379.602798) (xy 105.716265 -379.632782)
			(xy 105.763841 -379.669288) (xy 105.806246 -379.711693) (xy 105.842752 -379.759269) (xy 105.872736 -379.811203)
			(xy 105.895685 -379.866607) (xy 105.911206 -379.924532) (xy 105.919034 -379.983988) (xy 105.919524 -380.013972)
			(xy 105.919524 -380.656403) (xy 117.548873 -380.656403) (xy 117.556947 -380.589466) (xy 117.572982 -380.523977)
			(xy 117.596746 -380.460881) (xy 117.627898 -380.401085) (xy 117.665987 -380.345452) (xy 117.687852 -380.319788)
			(xy 117.693643 -380.312639) (xy 117.700159 -380.295451) (xy 117.700552 -380.28626) (xy 117.700552 -379.794008)
			(xy 117.700126 -379.784823) (xy 117.693622 -379.767639) (xy 117.687852 -379.76048) (xy 117.666033 -379.734777)
			(xy 117.62794 -379.679149) (xy 117.596784 -379.619358) (xy 117.573015 -379.556266) (xy 117.556975 -379.490781)
			(xy 117.548894 -379.423846) (xy 117.54889 -379.356426) (xy 117.556962 -379.28949) (xy 117.572994 -379.224003)
			(xy 117.596755 -379.160908) (xy 117.627903 -379.101113) (xy 117.665989 -379.04548) (xy 117.687852 -379.019816)
			(xy 117.693673 -379.012688) (xy 117.700172 -378.995484) (xy 117.700552 -378.986288) (xy 117.700552 -378.828554)
			(xy 117.700989 -378.818423) (xy 117.708734 -378.799698) (xy 117.723036 -378.785343) (xy 117.741731 -378.777528)
			(xy 117.75186 -378.776992) (xy 118.46814 -378.776992) (xy 118.478296 -378.777389) (xy 118.497047 -378.785196)
			(xy 118.511369 -378.7996) (xy 118.519069 -378.818396) (xy 118.519448 -378.828554) (xy 118.519448 -378.986288)
			(xy 118.519875 -378.995473) (xy 118.526378 -379.012657) (xy 118.532148 -379.019816) (xy 118.554061 -379.045441)
			(xy 118.592152 -379.10108) (xy 118.623303 -379.160882) (xy 118.647067 -379.223984) (xy 118.663101 -379.289478)
			(xy 118.671174 -379.356422) (xy 118.671169 -379.42385) (xy 118.663088 -379.490793) (xy 118.647046 -379.556285)
			(xy 118.623274 -379.619384) (xy 118.592115 -379.679181) (xy 118.554017 -379.734816) (xy 118.532148 -379.76048)
			(xy 118.526329 -379.767609) (xy 118.519829 -379.784812) (xy 118.519448 -379.794008) (xy 118.519448 -380.28626)
			(xy 118.519889 -380.295444) (xy 118.526382 -380.312628) (xy 118.532148 -380.319788) (xy 118.554033 -380.345436)
			(xy 118.592125 -380.401072) (xy 118.623278 -380.46087) (xy 118.647043 -380.523969) (xy 118.663079 -380.589461)
			(xy 118.671154 -380.656402) (xy 118.671154 -380.656463) (xy 121.949193 -380.656463) (xy 121.957235 -380.589642)
			(xy 121.973206 -380.524261) (xy 121.996876 -380.461257) (xy 122.027907 -380.401534) (xy 122.065854 -380.345948)
			(xy 122.08764 -380.320296) (xy 122.093426 -380.313143) (xy 122.099946 -380.295958) (xy 122.10034 -380.286768)
			(xy 122.10034 -379.7935) (xy 122.099921 -379.784314) (xy 122.093413 -379.76713) (xy 122.08764 -379.759972)
			(xy 122.0659 -379.734281) (xy 122.027949 -379.6787) (xy 121.996914 -379.618982) (xy 121.973238 -379.555982)
			(xy 121.957262 -379.490605) (xy 121.949214 -379.423787) (xy 121.94921 -379.356485) (xy 121.957249 -379.289666)
			(xy 121.973217 -379.224287) (xy 121.996884 -379.161284) (xy 122.027912 -379.101562) (xy 122.065855 -379.045976)
			(xy 122.08764 -379.020324) (xy 122.093456 -379.013193) (xy 122.099958 -378.995991) (xy 122.10034 -378.986796)
			(xy 122.10034 -378.828554) (xy 122.100796 -378.818393) (xy 122.108586 -378.799623) (xy 122.122963 -378.785259)
			(xy 122.141741 -378.777486) (xy 122.151902 -378.776992) (xy 122.868182 -378.776992) (xy 122.878333 -378.777547)
			(xy 122.897093 -378.785307) (xy 122.911457 -378.799653) (xy 122.919241 -378.818404) (xy 122.919744 -378.828554)
			(xy 122.919744 -378.986796) (xy 122.920169 -378.995981) (xy 122.926674 -379.013165) (xy 122.932444 -379.020324)
			(xy 122.95428 -379.045937) (xy 122.992228 -379.101529) (xy 123.02326 -379.161257) (xy 123.046931 -379.224267)
			(xy 123.062901 -379.289654) (xy 123.070942 -379.356482) (xy 123.070937 -379.423791) (xy 123.062888 -379.490617)
			(xy 123.04691 -379.556002) (xy 123.023231 -379.619009) (xy 122.992191 -379.678733) (xy 122.954235 -379.73432)
			(xy 122.932444 -379.759972) (xy 122.926627 -379.767103) (xy 122.920126 -379.784305) (xy 122.919744 -379.7935)
			(xy 122.919744 -380.286768) (xy 122.920182 -380.295952) (xy 122.926678 -380.313136) (xy 122.932444 -380.320296)
			(xy 122.954252 -380.345932) (xy 122.992201 -380.40152) (xy 123.023235 -380.461246) (xy 123.046907 -380.524252)
			(xy 123.062879 -380.589637) (xy 123.070915 -380.656404) (xy 126.34896 -380.656404) (xy 126.357035 -380.589466)
			(xy 126.373069 -380.523978) (xy 126.396833 -380.460881) (xy 126.427983 -380.401086) (xy 126.466072 -380.345453)
			(xy 126.487936 -380.319788) (xy 126.493725 -380.312637) (xy 126.500243 -380.295451) (xy 126.500636 -380.28626)
			(xy 126.500636 -379.794008) (xy 126.500214 -379.784822) (xy 126.493708 -379.767638) (xy 126.487936 -379.76048)
			(xy 126.466118 -379.734776) (xy 126.428025 -379.679148) (xy 126.396871 -379.619358) (xy 126.373102 -379.556266)
			(xy 126.357062 -379.490781) (xy 126.348982 -379.423846) (xy 126.348978 -379.356426) (xy 126.357049 -379.28949)
			(xy 126.373081 -379.224003) (xy 126.396841 -379.160908) (xy 126.427988 -379.101114) (xy 126.466074 -379.045481)
			(xy 126.487936 -379.019816) (xy 126.493755 -379.012687) (xy 126.500256 -378.995484) (xy 126.500636 -378.986288)
			(xy 126.500636 -378.828554) (xy 126.501089 -378.818425) (xy 126.508831 -378.799703) (xy 126.523127 -378.785349)
			(xy 126.541817 -378.777531) (xy 126.551944 -378.776992) (xy 127.268224 -378.776992) (xy 127.278379 -378.777402)
			(xy 127.29713 -378.785204) (xy 127.311452 -378.799604) (xy 127.319153 -378.818397) (xy 127.319532 -378.828554)
			(xy 127.319532 -378.986288) (xy 127.319963 -378.995473) (xy 127.326464 -379.012656) (xy 127.332232 -379.019816)
			(xy 127.354142 -379.045443) (xy 127.392227 -379.101084) (xy 127.423374 -379.160885) (xy 127.447134 -379.223987)
			(xy 127.463165 -379.289481) (xy 127.471237 -379.356423) (xy 127.471232 -379.423849) (xy 127.463152 -379.49079)
			(xy 127.447113 -379.556282) (xy 127.423345 -379.61938) (xy 127.39219 -379.679178) (xy 127.354098 -379.734814)
			(xy 127.332232 -379.76048) (xy 127.326411 -379.767607) (xy 127.319913 -379.784812) (xy 127.319532 -379.794008)
			(xy 127.319532 -380.28626) (xy 127.319977 -380.295443) (xy 127.326468 -380.312627) (xy 127.332232 -380.319788)
			(xy 127.354114 -380.345438) (xy 127.392201 -380.401075) (xy 127.423349 -380.460874) (xy 127.44711 -380.523973)
			(xy 127.463143 -380.589463) (xy 127.471217 -380.656403) (xy 127.471217 -380.656463) (xy 130.74928 -380.656463)
			(xy 130.757322 -380.589642) (xy 130.773292 -380.524262) (xy 130.796962 -380.461258) (xy 130.827992 -380.401535)
			(xy 130.865938 -380.345948) (xy 130.887724 -380.320296) (xy 130.893508 -380.313142) (xy 130.900029 -380.295958)
			(xy 130.900424 -380.286768) (xy 130.900424 -379.7935) (xy 130.900009 -379.784313) (xy 130.893498 -379.767129)
			(xy 130.887724 -379.759972) (xy 130.865984 -379.734281) (xy 130.828035 -379.678699) (xy 130.797 -379.618981)
			(xy 130.773326 -379.555982) (xy 130.75735 -379.490605) (xy 130.749302 -379.423787) (xy 130.749298 -379.356486)
			(xy 130.757337 -379.289667) (xy 130.773304 -379.224287) (xy 130.796971 -379.161285) (xy 130.827998 -379.101563)
			(xy 130.86594 -379.045977) (xy 130.887724 -379.020324) (xy 130.893538 -379.013191) (xy 130.900042 -378.995991)
			(xy 130.900424 -378.986796) (xy 130.900424 -378.828554) (xy 130.900895 -378.818395) (xy 130.908682 -378.799628)
			(xy 130.923054 -378.785264) (xy 130.941827 -378.777489) (xy 130.951986 -378.776992) (xy 131.668266 -378.776992)
			(xy 131.678416 -378.77756) (xy 131.697175 -378.785315) (xy 131.71154 -378.799657) (xy 131.719324 -378.818405)
			(xy 131.719828 -378.828554) (xy 131.719828 -378.986796) (xy 131.720234 -378.995984) (xy 131.72675 -379.013168)
			(xy 131.732528 -379.020324) (xy 131.754364 -379.045937) (xy 131.792314 -379.101528) (xy 131.823347 -379.161257)
			(xy 131.847018 -379.224267) (xy 131.862989 -379.289654) (xy 131.87103 -379.356481) (xy 131.871025 -379.423791)
			(xy 131.862976 -379.490617) (xy 131.846997 -379.556003) (xy 131.823317 -379.619009) (xy 131.792277 -379.678734)
			(xy 131.75432 -379.73432) (xy 131.732528 -379.759972) (xy 131.72671 -379.767101) (xy 131.72021 -379.784304)
			(xy 131.719828 -379.7935) (xy 131.719828 -380.286768) (xy 131.720247 -380.295954) (xy 131.726754 -380.313139)
			(xy 131.732528 -380.320296) (xy 131.754336 -380.345932) (xy 131.792287 -380.40152) (xy 131.823321 -380.461245)
			(xy 131.846994 -380.524252) (xy 131.862967 -380.589636) (xy 131.871003 -380.656404) (xy 161.548806 -380.656404)
			(xy 161.55688 -380.589468) (xy 161.572912 -380.523981) (xy 161.596672 -380.460885) (xy 161.627819 -380.401089)
			(xy 161.665902 -380.345454) (xy 161.687764 -380.319788) (xy 161.693556 -380.31264) (xy 161.700072 -380.295451)
			(xy 161.700464 -380.28626) (xy 161.700464 -379.794008) (xy 161.700036 -379.784823) (xy 161.693533 -379.767639)
			(xy 161.687764 -379.76048) (xy 161.665948 -379.734775) (xy 161.627861 -379.679146) (xy 161.59671 -379.619354)
			(xy 161.572945 -379.556263) (xy 161.556907 -379.490779) (xy 161.548828 -379.423846) (xy 161.548823 -379.356426)
			(xy 161.556894 -379.289492) (xy 161.572923 -379.224006) (xy 161.59668 -379.160911) (xy 161.627824 -379.101116)
			(xy 161.665904 -379.045482) (xy 161.687764 -379.019816) (xy 161.693587 -379.01269) (xy 161.700084 -378.995484)
			(xy 161.700464 -378.986288) (xy 161.700464 -378.828554) (xy 161.70089 -378.818421) (xy 161.708637 -378.799695)
			(xy 161.722942 -378.785339) (xy 161.741641 -378.777526) (xy 161.751772 -378.776992) (xy 162.468052 -378.776992)
			(xy 162.47817 -378.777455) (xy 162.496871 -378.785186) (xy 162.511187 -378.799488) (xy 162.518935 -378.818182)
			(xy 162.51936 -378.8283) (xy 162.51936 -378.986288) (xy 162.519785 -378.995473) (xy 162.526289 -379.012658)
			(xy 162.53206 -379.019816) (xy 162.553973 -379.045442) (xy 162.592062 -379.101081) (xy 162.623213 -379.160882)
			(xy 162.646977 -379.223984) (xy 162.66301 -379.289479) (xy 162.671083 -379.356422) (xy 162.671078 -379.42385)
			(xy 162.662997 -379.490792) (xy 162.646955 -379.556285) (xy 162.623184 -379.619384) (xy 162.592025 -379.679181)
			(xy 162.553928 -379.734815) (xy 162.53206 -379.76048) (xy 162.526242 -379.76761) (xy 162.519741 -379.784812)
			(xy 162.51936 -379.794008) (xy 162.51936 -380.28626) (xy 162.519799 -380.295444) (xy 162.526294 -380.312628)
			(xy 162.53206 -380.319788) (xy 162.553945 -380.345436) (xy 162.592036 -380.401072) (xy 162.623188 -380.460871)
			(xy 162.646953 -380.52397) (xy 162.662988 -380.589461) (xy 162.671063 -380.656402) (xy 162.671063 -380.656463)
			(xy 165.949102 -380.656463) (xy 165.957144 -380.589642) (xy 165.973115 -380.524261) (xy 165.996786 -380.461257)
			(xy 166.027818 -380.401534) (xy 166.065765 -380.345948) (xy 166.087552 -380.320296) (xy 166.093339 -380.313144)
			(xy 166.099858 -380.295959) (xy 166.100252 -380.286768) (xy 166.100252 -379.7935) (xy 166.09983 -379.784314)
			(xy 166.093323 -379.76713) (xy 166.087552 -379.759972) (xy 166.065811 -379.734281) (xy 166.02786 -379.678701)
			(xy 165.996824 -379.618982) (xy 165.973148 -379.555983) (xy 165.957171 -379.490605) (xy 165.949123 -379.423787)
			(xy 165.949119 -379.356485) (xy 165.957158 -379.289666) (xy 165.973127 -379.224286) (xy 165.996795 -379.161284)
			(xy 166.027823 -379.101562) (xy 166.065767 -379.045976) (xy 166.087552 -379.020324) (xy 166.09337 -379.013194)
			(xy 166.09987 -378.995992) (xy 166.100252 -378.986796) (xy 166.100252 -378.828554) (xy 166.100696 -378.818392)
			(xy 166.108488 -378.799619) (xy 166.122869 -378.785255) (xy 166.141651 -378.777484) (xy 166.151814 -378.776992)
			(xy 166.868094 -378.776992) (xy 166.878246 -378.777537) (xy 166.897006 -378.785301) (xy 166.91137 -378.79965)
			(xy 166.919153 -378.818403) (xy 166.919656 -378.828554) (xy 166.919656 -378.986796) (xy 166.920078 -378.995982)
			(xy 166.926584 -379.013166) (xy 166.932356 -379.020324) (xy 166.954191 -379.045937) (xy 166.992139 -379.101529)
			(xy 167.02317 -379.161258) (xy 167.046841 -379.224268) (xy 167.06281 -379.289655) (xy 167.070851 -379.356482)
			(xy 167.070847 -379.423791) (xy 167.062798 -379.490617) (xy 167.046819 -379.556001) (xy 167.023141 -379.619008)
			(xy 166.992102 -379.678733) (xy 166.954147 -379.73432) (xy 166.932356 -379.759972) (xy 166.926541 -379.767104)
			(xy 166.920038 -379.784305) (xy 166.919656 -379.7935) (xy 166.919656 -380.286768) (xy 166.920091 -380.295952)
			(xy 166.926588 -380.313137) (xy 166.932356 -380.320296) (xy 166.954164 -380.345932) (xy 166.992112 -380.40152)
			(xy 167.023145 -380.461246) (xy 167.046817 -380.524253) (xy 167.062789 -380.589637) (xy 167.070824 -380.656403)
			(xy 170.34887 -380.656403) (xy 170.356944 -380.589466) (xy 170.372979 -380.523977) (xy 170.396743 -380.460881)
			(xy 170.427894 -380.401086) (xy 170.465984 -380.345452) (xy 170.487848 -380.319788) (xy 170.493638 -380.312638)
			(xy 170.500155 -380.295451) (xy 170.500548 -380.28626) (xy 170.500548 -379.794008) (xy 170.500123 -379.784823)
			(xy 170.493619 -379.767639) (xy 170.487848 -379.76048) (xy 170.46603 -379.734777) (xy 170.427936 -379.679149)
			(xy 170.396781 -379.619358) (xy 170.373012 -379.556266) (xy 170.356971 -379.490781) (xy 170.348891 -379.423846)
			(xy 170.348887 -379.356426) (xy 170.356959 -379.28949) (xy 170.37299 -379.224003) (xy 170.396751 -379.160908)
			(xy 170.427899 -379.101113) (xy 170.465985 -379.04548) (xy 170.487848 -379.019816) (xy 170.493669 -379.012688)
			(xy 170.500168 -378.995484) (xy 170.500548 -378.986288) (xy 170.500548 -378.828554) (xy 170.500989 -378.818423)
			(xy 170.508734 -378.7997) (xy 170.523034 -378.785345) (xy 170.541727 -378.777529) (xy 170.551856 -378.776992)
			(xy 171.268136 -378.776992) (xy 171.278291 -378.777392) (xy 171.297043 -378.785198) (xy 171.311365 -378.799601)
			(xy 171.319065 -378.818396) (xy 171.319444 -378.828554) (xy 171.319444 -378.986288) (xy 171.319872 -378.995473)
			(xy 171.326375 -379.012657) (xy 171.332144 -379.019816) (xy 171.354057 -379.045441) (xy 171.392148 -379.10108)
			(xy 171.4233 -379.160881) (xy 171.447064 -379.223984) (xy 171.463098 -379.289478) (xy 171.47117 -379.356422)
			(xy 171.471166 -379.42385) (xy 171.463085 -379.490793) (xy 171.447042 -379.556285) (xy 171.42327 -379.619384)
			(xy 171.392111 -379.679182) (xy 171.354013 -379.734816) (xy 171.332144 -379.76048) (xy 171.326324 -379.767608)
			(xy 171.319825 -379.784812) (xy 171.319444 -379.794008) (xy 171.319444 -380.28626) (xy 171.319886 -380.295444)
			(xy 171.326379 -380.312628) (xy 171.332144 -380.319788) (xy 171.35403 -380.345436) (xy 171.392121 -380.401072)
			(xy 171.423274 -380.46087) (xy 171.44704 -380.523969) (xy 171.463076 -380.589461) (xy 171.471151 -380.656402)
			(xy 171.471151 -380.656463) (xy 174.74919 -380.656463) (xy 174.757232 -380.589642) (xy 174.773202 -380.524261)
			(xy 174.796873 -380.461258) (xy 174.827904 -380.401535) (xy 174.86585 -380.345948) (xy 174.887636 -380.320296)
			(xy 174.893421 -380.313143) (xy 174.899942 -380.295958) (xy 174.900336 -380.286768) (xy 174.900336 -379.7935)
			(xy 174.899918 -379.784314) (xy 174.893409 -379.76713) (xy 174.887636 -379.759972) (xy 174.865896 -379.734281)
			(xy 174.827946 -379.6787) (xy 174.796911 -379.618982) (xy 174.773235 -379.555982) (xy 174.757259 -379.490605)
			(xy 174.749211 -379.423787) (xy 174.749207 -379.356486) (xy 174.757246 -379.289666) (xy 174.773214 -379.224287)
			(xy 174.796881 -379.161284) (xy 174.827909 -379.101562) (xy 174.865851 -379.045976) (xy 174.887636 -379.020324)
			(xy 174.893452 -379.013193) (xy 174.899954 -378.995991) (xy 174.900336 -378.986796) (xy 174.900336 -378.828554)
			(xy 174.900796 -378.818394) (xy 174.908585 -378.799624) (xy 174.922961 -378.78526) (xy 174.941737 -378.777487)
			(xy 174.951898 -378.776992) (xy 175.668178 -378.776992) (xy 175.678329 -378.77755) (xy 175.697089 -378.785309)
			(xy 175.711453 -378.799654) (xy 175.719237 -378.818404) (xy 175.71974 -378.828554) (xy 175.71974 -378.986796)
			(xy 175.720166 -378.995981) (xy 175.72667 -379.013165) (xy 175.73244 -379.020324) (xy 175.754276 -379.045937)
			(xy 175.792225 -379.101529) (xy 175.823257 -379.161257) (xy 175.846928 -379.224267) (xy 175.862898 -379.289654)
			(xy 175.870939 -379.356481) (xy 175.870934 -379.423791) (xy 175.862885 -379.490617) (xy 175.846907 -379.556002)
			(xy 175.823227 -379.619009) (xy 175.792187 -379.678734) (xy 175.754231 -379.73432) (xy 175.73244 -379.759972)
			(xy 175.726623 -379.767102) (xy 175.720122 -379.784305) (xy 175.71974 -379.7935) (xy 175.71974 -380.286768)
			(xy 175.720179 -380.295952) (xy 175.726674 -380.313136) (xy 175.73244 -380.320296) (xy 175.754248 -380.345932)
			(xy 175.792198 -380.40152) (xy 175.823231 -380.461246) (xy 175.846904 -380.524252) (xy 175.862876 -380.589637)
			(xy 175.870919 -380.656462) (xy 175.870917 -380.723769) (xy 175.862871 -380.790593) (xy 175.846895 -380.855977)
			(xy 175.823219 -380.918982) (xy 175.792182 -380.978706) (xy 175.75423 -381.034292) (xy 175.73244 -381.059944)
			(xy 175.726635 -381.067083) (xy 175.720127 -381.084278) (xy 175.71974 -381.093472) (xy 175.71974 -381.251206)
			(xy 175.71934 -381.261381) (xy 175.711549 -381.28018) (xy 175.697156 -381.294565) (xy 175.678353 -381.302346)
			(xy 175.668178 -381.302768) (xy 174.951898 -381.302768) (xy 174.941741 -381.302268) (xy 174.922973 -381.294494)
			(xy 174.908608 -381.280131) (xy 174.900832 -381.261363) (xy 174.900336 -381.251206) (xy 174.900336 -381.093472)
			(xy 174.899931 -381.084284) (xy 174.893413 -381.067101) (xy 174.887636 -381.059944) (xy 174.865868 -381.034275)
			(xy 174.827919 -380.978691) (xy 174.796885 -380.91897) (xy 174.773211 -380.855968) (xy 174.757237 -380.790587)
			(xy 174.749191 -380.723767) (xy 174.74919 -380.656463) (xy 171.471151 -380.656463) (xy 171.471149 -380.723828)
			(xy 171.46307 -380.790769) (xy 171.447031 -380.85626) (xy 171.423262 -380.919358) (xy 171.392106 -380.979154)
			(xy 171.354011 -381.034788) (xy 171.332144 -381.060452) (xy 171.326336 -381.067589) (xy 171.31983 -381.084786)
			(xy 171.319444 -381.09398) (xy 171.319444 -381.251206) (xy 171.318978 -381.261335) (xy 171.311245 -381.280059)
			(xy 171.296952 -381.294416) (xy 171.278263 -381.302232) (xy 171.268136 -381.302768) (xy 170.551856 -381.302768)
			(xy 170.541695 -381.302414) (xy 170.522936 -381.294598) (xy 170.508613 -381.28018) (xy 170.50092 -381.26137)
			(xy 170.500548 -381.251206) (xy 170.500548 -381.09398) (xy 170.500137 -381.084793) (xy 170.493623 -381.067609)
			(xy 170.487848 -381.060452) (xy 170.466002 -381.034771) (xy 170.42791 -380.97914) (xy 170.396755 -380.919347)
			(xy 170.372988 -380.856252) (xy 170.35695 -380.790764) (xy 170.348871 -380.723827) (xy 170.34887 -380.656403)
			(xy 167.070824 -380.656403) (xy 167.070831 -380.656462) (xy 167.070829 -380.723768) (xy 167.062783 -380.790592)
			(xy 167.046808 -380.855976) (xy 167.023133 -380.918981) (xy 166.992097 -380.978705) (xy 166.954145 -381.034292)
			(xy 166.932356 -381.059944) (xy 166.926553 -381.067084) (xy 166.920043 -381.084279) (xy 166.919656 -381.093472)
			(xy 166.919656 -381.251206) (xy 166.919171 -381.261365) (xy 166.911394 -381.280135) (xy 166.897025 -381.2945)
			(xy 166.878253 -381.302274) (xy 166.868094 -381.302768) (xy 166.151814 -381.302768) (xy 166.141644 -381.302325)
			(xy 166.122851 -381.294546) (xy 166.108466 -381.280166) (xy 166.100679 -381.261376) (xy 166.100252 -381.251206)
			(xy 166.100252 -381.093472) (xy 166.099844 -381.084285) (xy 166.093327 -381.067101) (xy 166.087552 -381.059944)
			(xy 166.065784 -381.034276) (xy 166.027833 -380.978692) (xy 165.996799 -380.918971) (xy 165.973124 -380.855968)
			(xy 165.957149 -380.790588) (xy 165.949103 -380.723767) (xy 165.949102 -380.656463) (xy 162.671063 -380.656463)
			(xy 162.671061 -380.723828) (xy 162.662983 -380.790768) (xy 162.646944 -380.856259) (xy 162.623176 -380.919357)
			(xy 162.59202 -380.979153) (xy 162.553927 -381.034787) (xy 162.53206 -381.060452) (xy 162.526254 -381.06759)
			(xy 162.519746 -381.084786) (xy 162.51936 -381.09398) (xy 162.51936 -381.251206) (xy 162.518878 -381.261333)
			(xy 162.511148 -381.280054) (xy 162.496861 -381.29441) (xy 162.478177 -381.302229) (xy 162.468052 -381.302768)
			(xy 161.751772 -381.302768) (xy 161.741644 -381.302406) (xy 161.722933 -381.294643) (xy 161.708619 -381.28031)
			(xy 161.70088 -381.261589) (xy 161.700464 -381.25146) (xy 161.700464 -381.09398) (xy 161.700049 -381.084794)
			(xy 161.693537 -381.06761) (xy 161.687764 -381.060452) (xy 161.665921 -381.03477) (xy 161.627834 -380.979137)
			(xy 161.596684 -380.919343) (xy 161.572921 -380.856248) (xy 161.556885 -380.790762) (xy 161.548808 -380.723826)
			(xy 161.548806 -380.656404) (xy 131.871003 -380.656404) (xy 131.87101 -380.656461) (xy 131.871008 -380.723769)
			(xy 131.862961 -380.790593) (xy 131.846985 -380.855977) (xy 131.823309 -380.918982) (xy 131.792271 -380.978706)
			(xy 131.754318 -381.034292) (xy 131.732528 -381.059944) (xy 131.726722 -381.067082) (xy 131.720215 -381.084278)
			(xy 131.719828 -381.093472) (xy 131.719828 -381.251206) (xy 131.71944 -381.261382) (xy 131.711647 -381.280184)
			(xy 131.69725 -381.294569) (xy 131.678443 -381.302348) (xy 131.668266 -381.302768) (xy 130.951986 -381.302768)
			(xy 130.941828 -381.302278) (xy 130.92306 -381.2945) (xy 130.908695 -381.280133) (xy 130.90092 -381.261364)
			(xy 130.900424 -381.251206) (xy 130.900424 -381.093472) (xy 130.900022 -381.084284) (xy 130.893502 -381.0671)
			(xy 130.887724 -381.059944) (xy 130.865956 -381.034276) (xy 130.828008 -380.978691) (xy 130.796975 -380.91897)
			(xy 130.773301 -380.855967) (xy 130.757327 -380.790587) (xy 130.749282 -380.723767) (xy 130.74928 -380.656463)
			(xy 127.471217 -380.656463) (xy 127.471215 -380.723827) (xy 127.463138 -380.790766) (xy 127.447101 -380.856256)
			(xy 127.423336 -380.919354) (xy 127.392185 -380.979151) (xy 127.354096 -381.034786) (xy 127.332232 -381.060452)
			(xy 127.326423 -381.067588) (xy 127.319918 -381.084786) (xy 127.319532 -381.09398) (xy 127.319532 -381.251206)
			(xy 127.319077 -381.261337) (xy 127.311342 -381.280063) (xy 127.297046 -381.29442) (xy 127.278352 -381.302234)
			(xy 127.268224 -381.302768) (xy 126.551944 -381.302768) (xy 126.541789 -381.302342) (xy 126.523031 -381.294555)
			(xy 126.508705 -381.280159) (xy 126.50101 -381.261363) (xy 126.500636 -381.251206) (xy 126.500636 -381.09398)
			(xy 126.500227 -381.084793) (xy 126.493712 -381.067609) (xy 126.487936 -381.060452) (xy 126.46609 -381.034771)
			(xy 126.427999 -380.97914) (xy 126.396845 -380.919346) (xy 126.373078 -380.856251) (xy 126.35704 -380.790764)
			(xy 126.348962 -380.723826) (xy 126.34896 -380.656404) (xy 123.070915 -380.656404) (xy 123.070922 -380.656462)
			(xy 123.07092 -380.723769) (xy 123.062874 -380.790593) (xy 123.046898 -380.855976) (xy 123.023223 -380.918982)
			(xy 122.992186 -380.978706) (xy 122.954234 -381.034292) (xy 122.932444 -381.059944) (xy 122.926639 -381.067083)
			(xy 122.920131 -381.084279) (xy 122.919744 -381.093472) (xy 122.919744 -381.251206) (xy 122.919341 -381.26138)
			(xy 122.91155 -381.280178) (xy 122.897158 -381.294564) (xy 122.878356 -381.302345) (xy 122.868182 -381.302768)
			(xy 122.151902 -381.302768) (xy 122.141745 -381.302265) (xy 122.122977 -381.294492) (xy 122.108612 -381.28013)
			(xy 122.100836 -381.261363) (xy 122.10034 -381.251206) (xy 122.10034 -381.093472) (xy 122.099934 -381.084285)
			(xy 122.093417 -381.067101) (xy 122.08764 -381.059944) (xy 122.065872 -381.034276) (xy 122.027923 -380.978691)
			(xy 121.996888 -380.91897) (xy 121.973215 -380.855968) (xy 121.95724 -380.790588) (xy 121.949194 -380.723767)
			(xy 121.949193 -380.656463) (xy 118.671154 -380.656463) (xy 118.671152 -380.723828) (xy 118.663073 -380.790769)
			(xy 118.647034 -380.85626) (xy 118.623265 -380.919357) (xy 118.592109 -380.979154) (xy 118.554015 -381.034788)
			(xy 118.532148 -381.060452) (xy 118.52634 -381.067589) (xy 118.519834 -381.084786) (xy 118.519448 -381.09398)
			(xy 118.519448 -381.251206) (xy 118.518978 -381.261335) (xy 118.511246 -381.280058) (xy 118.496954 -381.294415)
			(xy 118.478266 -381.302231) (xy 118.46814 -381.302768) (xy 117.75186 -381.302768) (xy 117.741699 -381.30241)
			(xy 117.72294 -381.294596) (xy 117.708617 -381.280179) (xy 117.700924 -381.261369) (xy 117.700552 -381.251206)
			(xy 117.700552 -381.09398) (xy 117.70014 -381.084793) (xy 117.693626 -381.06761) (xy 117.687852 -381.060452)
			(xy 117.666006 -381.034771) (xy 117.627913 -380.97914) (xy 117.596759 -380.919347) (xy 117.572991 -380.856252)
			(xy 117.556953 -380.790764) (xy 117.548874 -380.723827) (xy 117.548873 -380.656403) (xy 105.919524 -380.656403)
			(xy 105.919524 -380.877572) (xy 105.919034 -380.907556) (xy 105.911206 -380.967012) (xy 105.895685 -381.024937)
			(xy 105.872736 -381.080341) (xy 105.842752 -381.132275) (xy 105.806246 -381.179851) (xy 105.763841 -381.222256)
			(xy 105.716265 -381.258762) (xy 105.664331 -381.288746) (xy 105.608927 -381.311695) (xy 105.551002 -381.327216)
			(xy 105.491546 -381.335044) (xy 105.431578 -381.335044) (xy 105.372122 -381.327216) (xy 105.314197 -381.311695)
			(xy 105.258793 -381.288746) (xy 105.206859 -381.258762) (xy 105.159283 -381.222256) (xy 105.116878 -381.179851)
			(xy 105.080372 -381.132275) (xy 105.050388 -381.080341) (xy 105.027439 -381.024937) (xy 105.011918 -380.967012)
			(xy 105.00409 -380.907556) (xy 105.0036 -380.877572) (xy 87.838954 -380.877572) (xy 87.823216 -380.919355)
			(xy 87.792063 -380.979152) (xy 87.753973 -381.034787) (xy 87.732108 -381.060452) (xy 87.726308 -381.067595)
			(xy 87.719795 -381.084787) (xy 87.719408 -381.09398) (xy 87.719408 -381.251206) (xy 87.71888 -381.261327)
			(xy 87.711159 -381.280039) (xy 87.696886 -381.294394) (xy 87.678218 -381.302221) (xy 87.6681 -381.302768)
			(xy 86.95182 -381.302768) (xy 86.941695 -381.302367) (xy 86.922985 -381.294619) (xy 86.908669 -381.280298)
			(xy 86.900929 -381.261585) (xy 86.900512 -381.25146) (xy 86.900512 -381.09398) (xy 86.900109 -381.084792)
			(xy 86.89359 -381.067608) (xy 86.887812 -381.060452) (xy 86.865967 -381.034771) (xy 86.827877 -380.979139)
			(xy 86.796725 -380.919345) (xy 86.772959 -380.85625) (xy 86.756922 -380.790763) (xy 86.748844 -380.723826)
			(xy 86.748842 -380.656404) (xy 83.470797 -380.656404) (xy 83.470804 -380.656461) (xy 83.470802 -380.723769)
			(xy 83.462755 -380.790593) (xy 83.446779 -380.855977) (xy 83.423102 -380.918983) (xy 83.392064 -380.978706)
			(xy 83.35411 -381.034292) (xy 83.33232 -381.059944) (xy 83.326525 -381.06709) (xy 83.320009 -381.08428)
			(xy 83.31962 -381.093472) (xy 83.31962 -381.251206) (xy 83.31924 -381.261383) (xy 83.311445 -381.280186)
			(xy 83.297046 -381.294572) (xy 83.278236 -381.302349) (xy 83.268058 -381.302768) (xy 82.551778 -381.302768)
			(xy 82.54162 -381.302285) (xy 82.522851 -381.294504) (xy 82.508487 -381.280136) (xy 82.500712 -381.261365)
			(xy 82.500216 -381.251206) (xy 82.500216 -381.093472) (xy 82.499816 -381.084284) (xy 82.493295 -381.0671)
			(xy 82.487516 -381.059944) (xy 82.465749 -381.034275) (xy 82.427801 -380.978691) (xy 82.396768 -380.918969)
			(xy 82.373095 -380.855967) (xy 82.357121 -380.790587) (xy 82.349076 -380.723767) (xy 82.349074 -380.656464)
			(xy 79.071011 -380.656464) (xy 79.071009 -380.723827) (xy 79.062932 -380.790767) (xy 79.046895 -380.856256)
			(xy 79.02313 -380.919354) (xy 78.991978 -380.979151) (xy 78.953888 -381.034786) (xy 78.932024 -381.060452)
			(xy 78.926226 -381.067596) (xy 78.919711 -381.084787) (xy 78.919324 -381.09398) (xy 78.919324 -381.251206)
			(xy 78.918877 -381.261337) (xy 78.911141 -381.280066) (xy 78.896842 -381.294423) (xy 78.878145 -381.302235)
			(xy 78.868016 -381.302768) (xy 78.151736 -381.302768) (xy 78.141612 -381.302354) (xy 78.122903 -381.294611)
			(xy 78.108586 -381.280294) (xy 78.100846 -381.261584) (xy 78.100428 -381.25146) (xy 78.100428 -381.09398)
			(xy 78.100021 -381.084793) (xy 78.093505 -381.067609) (xy 78.087728 -381.060452) (xy 78.065883 -381.034771)
			(xy 78.027792 -380.979139) (xy 77.996638 -380.919346) (xy 77.972872 -380.856251) (xy 77.956834 -380.790763)
			(xy 77.948756 -380.723826) (xy 77.948754 -380.656404) (xy 74.670709 -380.656404) (xy 74.670716 -380.656462)
			(xy 74.670714 -380.723769) (xy 74.662667 -380.790593) (xy 74.646691 -380.855977) (xy 74.623015 -380.918982)
			(xy 74.591978 -380.978706) (xy 74.554026 -381.034292) (xy 74.532236 -381.059944) (xy 74.52643 -381.067082)
			(xy 74.519923 -381.084278) (xy 74.519536 -381.093472) (xy 74.519536 -381.251206) (xy 74.51914 -381.261381)
			(xy 74.511349 -381.280181) (xy 74.496954 -381.294567) (xy 74.478149 -381.302347) (xy 74.467974 -381.302768)
			(xy 73.751694 -381.302768) (xy 73.741537 -381.302272) (xy 73.722769 -381.294496) (xy 73.708404 -381.280131)
			(xy 73.700628 -381.261363) (xy 73.700132 -381.251206) (xy 73.700132 -381.093472) (xy 73.699728 -381.084284)
			(xy 73.693209 -381.0671) (xy 73.687432 -381.059944) (xy 73.665664 -381.034275) (xy 73.627715 -380.978691)
			(xy 73.596682 -380.91897) (xy 73.573008 -380.855967) (xy 73.557034 -380.790587) (xy 73.548988 -380.723767)
			(xy 73.548987 -380.656463) (xy 43.87119 -380.656463) (xy 43.871188 -380.723828) (xy 43.86311 -380.790767)
			(xy 43.847073 -380.856258) (xy 43.823306 -380.919355) (xy 43.792153 -380.979152) (xy 43.754061 -381.034787)
			(xy 43.732196 -381.060452) (xy 43.726394 -381.067594) (xy 43.719883 -381.084787) (xy 43.719496 -381.09398)
			(xy 43.719496 -381.251206) (xy 43.718979 -381.261329) (xy 43.711256 -381.280043) (xy 43.69698 -381.294398)
			(xy 43.678308 -381.302223) (xy 43.668188 -381.302768) (xy 42.951908 -381.302768) (xy 42.94175 -381.302371)
			(xy 42.922992 -381.294572) (xy 42.908667 -381.280167) (xy 42.900973 -381.261366) (xy 42.9006 -381.251206)
			(xy 42.9006 -381.09398) (xy 42.9002 -381.084792) (xy 42.893679 -381.067607) (xy 42.8879 -381.060452)
			(xy 42.866056 -381.034771) (xy 42.827966 -380.979138) (xy 42.796815 -380.919344) (xy 42.773049 -380.85625)
			(xy 42.757013 -380.790763) (xy 42.748935 -380.723826) (xy 42.748933 -380.656404) (xy 39.470887 -380.656404)
			(xy 39.470894 -380.656461) (xy 39.470893 -380.723769) (xy 39.462846 -380.790594) (xy 39.446869 -380.855978)
			(xy 39.423192 -380.918983) (xy 39.392153 -380.978707) (xy 39.354199 -381.034293) (xy 39.332408 -381.059944)
			(xy 39.326611 -381.067089) (xy 39.320096 -381.08428) (xy 39.319708 -381.093472) (xy 39.319708 -381.251206)
			(xy 39.319173 -381.261358) (xy 39.311405 -381.280119) (xy 39.297052 -381.294482) (xy 39.278298 -381.302265)
			(xy 39.268146 -381.302768) (xy 38.551866 -381.302768) (xy 38.541707 -381.302295) (xy 38.522938 -381.29451)
			(xy 38.508574 -381.280138) (xy 38.5008 -381.261365) (xy 38.500304 -381.251206) (xy 38.500304 -381.093472)
			(xy 38.499907 -381.084283) (xy 38.493384 -381.067099) (xy 38.487604 -381.059944) (xy 38.465837 -381.034275)
			(xy 38.42789 -380.97869) (xy 38.396858 -380.918969) (xy 38.373185 -380.855966) (xy 38.357212 -380.790587)
			(xy 38.349167 -380.723766) (xy 38.349165 -380.656464) (xy 35.071102 -380.656464) (xy 35.0711 -380.723828)
			(xy 35.063023 -380.790767) (xy 35.046985 -380.856257) (xy 35.023219 -380.919355) (xy 34.992067 -380.979151)
			(xy 34.953977 -381.034787) (xy 34.932112 -381.060452) (xy 34.926312 -381.067595) (xy 34.919799 -381.084787)
			(xy 34.919412 -381.09398) (xy 34.919412 -381.251206) (xy 34.91888 -381.261327) (xy 34.91116 -381.280038)
			(xy 34.896888 -381.294392) (xy 34.878222 -381.30222) (xy 34.868104 -381.302768) (xy 34.151824 -381.302768)
			(xy 34.141667 -381.302358) (xy 34.122909 -381.294565) (xy 34.108584 -381.280164) (xy 34.100889 -381.261365)
			(xy 34.100516 -381.251206) (xy 34.100516 -381.09398) (xy 34.100112 -381.084792) (xy 34.093594 -381.067608)
			(xy 34.087816 -381.060452) (xy 34.065971 -381.034771) (xy 34.027881 -380.979139) (xy 33.996728 -380.919345)
			(xy 33.972962 -380.85625) (xy 33.956925 -380.790763) (xy 33.948847 -380.723826) (xy 33.948845 -380.656404)
			(xy 30.6708 -380.656404) (xy 30.670807 -380.656461) (xy 30.670805 -380.723769) (xy 30.662758 -380.790593)
			(xy 30.646782 -380.855977) (xy 30.623105 -380.918982) (xy 30.592068 -380.978706) (xy 30.554114 -381.034292)
			(xy 30.532324 -381.059944) (xy 30.526529 -381.067091) (xy 30.520013 -381.08428) (xy 30.519624 -381.093472)
			(xy 30.519624 -381.251206) (xy 30.51924 -381.261383) (xy 30.511446 -381.280185) (xy 30.497048 -381.294571)
			(xy 30.478239 -381.302349) (xy 30.468062 -381.302768) (xy 29.751782 -381.302768) (xy 29.741624 -381.302282)
			(xy 29.722855 -381.294502) (xy 29.708491 -381.280135) (xy 29.700716 -381.261364) (xy 29.70022 -381.251206)
			(xy 29.70022 -381.093472) (xy 29.699819 -381.084284) (xy 29.693298 -381.0671) (xy 29.68752 -381.059944)
			(xy 29.665752 -381.034276) (xy 29.627804 -380.978691) (xy 29.596771 -380.918969) (xy 29.573098 -380.855967)
			(xy 29.557124 -380.790587) (xy 29.549079 -380.723767) (xy 29.549077 -380.656463) (xy 29.557119 -380.589643)
			(xy 29.573089 -380.524262) (xy 29.596759 -380.461258) (xy 29.627789 -380.401535) (xy 29.665734 -380.345948)
			(xy 29.68752 -380.320296) (xy 29.693303 -380.313141) (xy 29.699825 -380.295958) (xy 29.70022 -380.286768)
			(xy 29.70022 -379.7935) (xy 29.699806 -379.784313) (xy 29.693295 -379.767129) (xy 29.68752 -379.759972)
			(xy 29.66573 -379.734322) (xy 29.627781 -379.678735) (xy 29.596748 -379.619011) (xy 29.573075 -379.556006)
			(xy 29.557102 -379.490624) (xy 29.549058 -379.423801) (xy 28.447 -379.423801) (xy 28.447041 -379.423909)
			(xy 28.463077 -379.489397) (xy 28.471153 -379.556335) (xy 28.471153 -379.623759) (xy 28.463078 -379.690697)
			(xy 28.447043 -379.756186) (xy 28.423279 -379.819282) (xy 28.392128 -379.879078) (xy 28.35404 -379.934713)
			(xy 28.332176 -379.960378) (xy 28.326361 -379.96751) (xy 28.319858 -379.984711) (xy 28.319476 -379.993906)
			(xy 28.319476 -380.151386) (xy 28.318962 -380.16151) (xy 28.311242 -380.180228) (xy 28.296964 -380.194584)
			(xy 28.278289 -380.202406) (xy 28.268168 -380.202948) (xy 27.551888 -380.202948) (xy 27.541784 -380.202426)
			(xy 27.523115 -380.194693) (xy 27.508823 -380.180408) (xy 27.50108 -380.161743) (xy 27.50058 -380.15164)
			(xy 27.50058 -379.993906) (xy 27.500171 -379.984719) (xy 27.493657 -379.967534) (xy 27.48788 -379.960378)
			(xy 27.466012 -379.934716) (xy 27.427923 -379.879081) (xy 27.396771 -379.819285) (xy 27.373007 -379.756187)
			(xy 27.356972 -379.690698) (xy 27.348896 -379.623759) (xy 27.348896 -379.556335) (xy 27.356973 -379.489396)
			(xy 27.373009 -379.423907) (xy 27.396774 -379.36081) (xy 27.427926 -379.301013) (xy 27.466015 -379.245379)
			(xy 27.48788 -379.219714) (xy 27.493693 -379.21258) (xy 27.500199 -379.195381) (xy 27.50058 -379.186186)
			(xy 27.50058 -378.693934) (xy 27.500158 -378.684748) (xy 27.493653 -378.667563) (xy 27.48788 -378.660406)
			(xy 27.465991 -378.634761) (xy 27.427905 -378.579124) (xy 27.396756 -378.519324) (xy 27.372994 -378.456225)
			(xy 27.356961 -378.390733) (xy 27.348888 -378.323793) (xy 0.508 -378.323793) (xy 0.508 -382.223705)
			(xy 27.348899 -382.223705) (xy 27.3489 -382.15628) (xy 27.356976 -382.089342) (xy 27.373012 -382.023853)
			(xy 27.396777 -381.960755) (xy 27.427928 -381.900959) (xy 27.466016 -381.845324) (xy 27.48788 -381.819658)
			(xy 27.493675 -381.812511) (xy 27.500191 -381.795322) (xy 27.50058 -381.78613) (xy 27.50058 -381.628904)
			(xy 27.501088 -381.618798) (xy 27.508821 -381.600124) (xy 27.52311 -381.58583) (xy 27.541782 -381.578091)
			(xy 27.551888 -381.577596) (xy 28.268168 -381.577596) (xy 28.278288 -381.578042) (xy 28.29699 -381.585779)
			(xy 28.311306 -381.600086) (xy 28.319053 -381.618784) (xy 28.319476 -381.628904) (xy 28.319476 -381.78613)
			(xy 28.319877 -381.795318) (xy 28.326398 -381.812502) (xy 28.332176 -381.819658) (xy 28.354031 -381.845331)
			(xy 28.392122 -381.900964) (xy 28.423274 -381.960759) (xy 28.44704 -382.023855) (xy 28.463077 -382.089343)
			(xy 28.471154 -382.156281) (xy 28.471155 -382.223646) (xy 31.749194 -382.223646) (xy 31.749195 -382.156339)
			(xy 31.757241 -382.089516) (xy 31.773216 -382.024132) (xy 31.796891 -381.961127) (xy 31.827927 -381.901404)
			(xy 31.865879 -381.845818) (xy 31.887668 -381.820166) (xy 31.89347 -381.813025) (xy 31.899979 -381.795831)
			(xy 31.900368 -381.786638) (xy 31.900368 -381.628904) (xy 31.900824 -381.618754) (xy 31.908613 -381.600008)
			(xy 31.922998 -381.585686) (xy 31.941778 -381.57798) (xy 31.95193 -381.577596) (xy 32.66821 -381.577596)
			(xy 32.678332 -381.578117) (xy 32.697045 -381.58584) (xy 32.711399 -381.600115) (xy 32.719226 -381.618785)
			(xy 32.719772 -381.628904) (xy 32.719772 -381.786638) (xy 32.72017 -381.795826) (xy 32.726693 -381.81301)
			(xy 32.732472 -381.820166) (xy 32.75425 -381.845826) (xy 32.792198 -381.901412) (xy 32.823231 -381.961134)
			(xy 32.846904 -382.024138) (xy 32.862877 -382.089519) (xy 32.870922 -382.15634) (xy 32.870923 -382.223645)
			(xy 32.870916 -382.223704) (xy 36.148987 -382.223704) (xy 36.148988 -382.156281) (xy 36.157064 -382.089342)
			(xy 36.1731 -382.023853) (xy 36.196863 -381.960756) (xy 36.228013 -381.900959) (xy 36.266101 -381.845324)
			(xy 36.287964 -381.819658) (xy 36.293769 -381.812519) (xy 36.300277 -381.795323) (xy 36.300664 -381.78613)
			(xy 36.300664 -381.628904) (xy 36.301188 -381.6188) (xy 36.308917 -381.600129) (xy 36.323202 -381.585835)
			(xy 36.341868 -381.578094) (xy 36.351972 -381.577596) (xy 37.068252 -381.577596) (xy 37.078371 -381.578055)
			(xy 37.097073 -381.585787) (xy 37.111388 -381.60009) (xy 37.119136 -381.618786) (xy 37.11956 -381.628904)
			(xy 37.11956 -381.78613) (xy 37.119965 -381.795318) (xy 37.126483 -381.812501) (xy 37.13226 -381.819658)
			(xy 37.154116 -381.845331) (xy 37.192207 -381.900963) (xy 37.223361 -381.960758) (xy 37.247127 -382.023854)
			(xy 37.263164 -382.089343) (xy 37.271242 -382.156281) (xy 37.271243 -382.223704) (xy 37.271243 -382.223705)
			(xy 40.548753 -382.223705) (xy 40.548754 -382.15628) (xy 40.556832 -382.08934) (xy 40.57287 -382.02385)
			(xy 40.596638 -381.960752) (xy 40.627792 -381.900956) (xy 40.665886 -381.845322) (xy 40.687752 -381.819658)
			(xy 40.693555 -381.812518) (xy 40.700065 -381.795323) (xy 40.700452 -381.78613) (xy 40.700452 -381.628904)
			(xy 40.700987 -381.618801) (xy 40.708715 -381.600133) (xy 40.722996 -381.585839) (xy 40.741658 -381.578096)
			(xy 40.75176 -381.577596) (xy 41.46804 -381.577596) (xy 41.478151 -381.578052) (xy 41.496829 -381.585802)
			(xy 41.511122 -381.600108) (xy 41.518856 -381.618793) (xy 41.519348 -381.628904) (xy 41.519348 -381.78613)
			(xy 41.519755 -381.795317) (xy 41.526272 -381.812501) (xy 41.532048 -381.819658) (xy 41.553904 -381.84533)
			(xy 41.591996 -381.900963) (xy 41.62315 -381.960757) (xy 41.646917 -382.023853) (xy 41.662955 -382.089342)
			(xy 41.671033 -382.156281) (xy 41.671034 -382.223645) (xy 44.949073 -382.223645) (xy 44.949074 -382.15634)
			(xy 44.957119 -382.089516) (xy 44.973093 -382.024133) (xy 44.996767 -381.961128) (xy 45.027801 -381.901405)
			(xy 45.065751 -381.845818) (xy 45.08754 -381.820166) (xy 45.093339 -381.813022) (xy 45.099851 -381.795831)
			(xy 45.10024 -381.786638) (xy 45.10024 -381.628904) (xy 45.100626 -381.618745) (xy 45.108427 -381.599985)
			(xy 45.122836 -381.58566) (xy 45.141641 -381.577968) (xy 45.151802 -381.577596) (xy 45.868082 -381.577596)
			(xy 45.878202 -381.57814) (xy 45.896915 -381.585854) (xy 45.91127 -381.600122) (xy 45.919098 -381.618787)
			(xy 45.919644 -381.628904) (xy 45.919644 -381.786638) (xy 45.920049 -381.795826) (xy 45.926568 -381.813009)
			(xy 45.932344 -381.820166) (xy 45.954122 -381.845826) (xy 45.992072 -381.901411) (xy 46.023107 -381.961133)
			(xy 46.046781 -382.024137) (xy 46.062755 -382.089518) (xy 46.070801 -382.15634) (xy 46.070801 -382.223645)
			(xy 46.070794 -382.223705) (xy 71.348808 -382.223705) (xy 71.348809 -382.15628) (xy 71.356886 -382.089342)
			(xy 71.372922 -382.023852) (xy 71.396687 -381.960755) (xy 71.427838 -381.900958) (xy 71.465928 -381.845323)
			(xy 71.487792 -381.819658) (xy 71.493588 -381.812512) (xy 71.500103 -381.795322) (xy 71.500492 -381.78613)
			(xy 71.500492 -381.628904) (xy 71.500919 -381.618783) (xy 71.508664 -381.600081) (xy 71.522977 -381.585767)
			(xy 71.541679 -381.57802) (xy 71.5518 -381.577596) (xy 72.26808 -381.577596) (xy 72.278201 -381.578032)
			(xy 72.296903 -381.585773) (xy 72.311218 -381.600083) (xy 72.318965 -381.618783) (xy 72.319388 -381.628904)
			(xy 72.319388 -381.78613) (xy 72.319786 -381.795318) (xy 72.326308 -381.812503) (xy 72.332088 -381.819658)
			(xy 72.353943 -381.845331) (xy 72.392032 -381.900964) (xy 72.423184 -381.960759) (xy 72.446949 -382.023855)
			(xy 72.462986 -382.089343) (xy 72.471063 -382.156281) (xy 72.471064 -382.223646) (xy 75.749104 -382.223646)
			(xy 75.749104 -382.156339) (xy 75.75715 -382.089515) (xy 75.773125 -382.024132) (xy 75.796801 -381.961127)
			(xy 75.827838 -381.901403) (xy 75.86579 -381.845818) (xy 75.88758 -381.820166) (xy 75.893371 -381.813017)
			(xy 75.89989 -381.795829) (xy 75.90028 -381.786638) (xy 75.90028 -381.628904) (xy 75.900725 -381.618753)
			(xy 75.908515 -381.600004) (xy 75.922904 -381.585681) (xy 75.941689 -381.577978) (xy 75.951842 -381.577596)
			(xy 76.668122 -381.577596) (xy 76.678245 -381.578107) (xy 76.696958 -381.585834) (xy 76.711312 -381.600112)
			(xy 76.719138 -381.618784) (xy 76.719684 -381.628904) (xy 76.719684 -381.786638) (xy 76.720079 -381.795827)
			(xy 76.726604 -381.813011) (xy 76.732384 -381.820166) (xy 76.754161 -381.845826) (xy 76.792109 -381.901412)
			(xy 76.823141 -381.961135) (xy 76.846814 -382.024138) (xy 76.862787 -382.089519) (xy 76.870831 -382.156341)
			(xy 76.870832 -382.223644) (xy 76.870825 -382.223704) (xy 80.148896 -382.223704) (xy 80.148897 -382.15628)
			(xy 80.156973 -382.089342) (xy 80.173009 -382.023853) (xy 80.196773 -381.960755) (xy 80.227924 -381.900959)
			(xy 80.266012 -381.845324) (xy 80.287876 -381.819658) (xy 80.29367 -381.812511) (xy 80.300187 -381.795322)
			(xy 80.300576 -381.78613) (xy 80.300576 -381.628904) (xy 80.301088 -381.618798) (xy 80.30882 -381.600125)
			(xy 80.323108 -381.585831) (xy 80.341779 -381.578092) (xy 80.351884 -381.577596) (xy 81.068164 -381.577596)
			(xy 81.078284 -381.578046) (xy 81.096986 -381.585781) (xy 81.111301 -381.600087) (xy 81.119048 -381.618785)
			(xy 81.119472 -381.628904) (xy 81.119472 -381.78613) (xy 81.119874 -381.795318) (xy 81.126394 -381.812502)
			(xy 81.132172 -381.819658) (xy 81.154027 -381.845331) (xy 81.192118 -381.900964) (xy 81.223271 -381.960759)
			(xy 81.247037 -382.023854) (xy 81.263074 -382.089343) (xy 81.271151 -382.156281) (xy 81.271152 -382.223704)
			(xy 84.548687 -382.223704) (xy 84.548688 -382.156281) (xy 84.556764 -382.089342) (xy 84.5728 -382.023853)
			(xy 84.596563 -381.960756) (xy 84.627713 -381.900959) (xy 84.665801 -381.845324) (xy 84.687664 -381.819658)
			(xy 84.693469 -381.812519) (xy 84.699977 -381.795323) (xy 84.700364 -381.78613) (xy 84.700364 -381.628904)
			(xy 84.700888 -381.6188) (xy 84.708617 -381.600129) (xy 84.722902 -381.585835) (xy 84.741568 -381.578094)
			(xy 84.751672 -381.577596) (xy 85.467952 -381.577596) (xy 85.478071 -381.578055) (xy 85.496773 -381.585787)
			(xy 85.511088 -381.60009) (xy 85.518836 -381.618786) (xy 85.51926 -381.628904) (xy 85.51926 -381.78613)
			(xy 85.519665 -381.795318) (xy 85.526183 -381.812501) (xy 85.53196 -381.819658) (xy 85.553816 -381.845331)
			(xy 85.591907 -381.900963) (xy 85.623061 -381.960758) (xy 85.646827 -382.023854) (xy 85.662864 -382.089343)
			(xy 85.670942 -382.156281) (xy 85.670943 -382.223646) (xy 88.948982 -382.223646) (xy 88.948983 -382.156339)
			(xy 88.957028 -382.089516) (xy 88.973003 -382.024133) (xy 88.996677 -381.961128) (xy 89.027712 -381.901404)
			(xy 89.065663 -381.845818) (xy 89.087452 -381.820166) (xy 89.093252 -381.813023) (xy 89.099763 -381.795831)
			(xy 89.100152 -381.786638) (xy 89.100152 -381.628904) (xy 89.100624 -381.618756) (xy 89.108409 -381.600013)
			(xy 89.12279 -381.585691) (xy 89.141564 -381.577983) (xy 89.151714 -381.577596) (xy 89.867994 -381.577596)
			(xy 89.878115 -381.57813) (xy 89.896828 -381.585848) (xy 89.911183 -381.600119) (xy 89.91901 -381.618786)
			(xy 89.919556 -381.628904) (xy 89.919556 -381.786638) (xy 89.919958 -381.795826) (xy 89.926478 -381.81301)
			(xy 89.932256 -381.820166) (xy 89.954034 -381.845826) (xy 89.991983 -381.901411) (xy 90.023017 -381.961134)
			(xy 90.046691 -382.024137) (xy 90.062665 -382.089519) (xy 90.07071 -382.15634) (xy 90.070711 -382.223645)
			(xy 115.349246 -382.223645) (xy 115.349247 -382.15634) (xy 115.357291 -382.089517) (xy 115.373264 -382.024135)
			(xy 115.396937 -381.96113) (xy 115.427969 -381.901406) (xy 115.465917 -381.845819) (xy 115.487704 -381.820166)
			(xy 115.493498 -381.813019) (xy 115.500014 -381.79583) (xy 115.500404 -381.786638) (xy 115.500404 -381.628904)
			(xy 115.500825 -381.61875) (xy 115.50862 -381.599997) (xy 115.523017 -381.585673) (xy 115.54181 -381.577974)
			(xy 115.551966 -381.577596) (xy 116.268246 -381.577596) (xy 116.27837 -381.578088) (xy 116.297084 -381.585822)
			(xy 116.311437 -381.600106) (xy 116.319262 -381.618782) (xy 116.319808 -381.628904) (xy 116.319808 -381.786638)
			(xy 116.320198 -381.795827) (xy 116.326725 -381.813012) (xy 116.332508 -381.820166) (xy 116.354288 -381.845826)
			(xy 116.39224 -381.90141) (xy 116.423277 -381.961132) (xy 116.446952 -382.024135) (xy 116.462928 -382.089517)
			(xy 116.470973 -382.15634) (xy 116.470974 -382.223645) (xy 116.470967 -382.223705) (xy 119.749014 -382.223705)
			(xy 119.749015 -382.15628) (xy 119.757092 -382.089341) (xy 119.773128 -382.023852) (xy 119.796894 -381.960754)
			(xy 119.828046 -381.900958) (xy 119.866135 -381.845323) (xy 119.888 -381.819658) (xy 119.893797 -381.812513)
			(xy 119.900311 -381.795322) (xy 119.9007 -381.78613) (xy 119.9007 -381.628904) (xy 119.901119 -381.618782)
			(xy 119.908866 -381.600078) (xy 119.923182 -381.585764) (xy 119.941886 -381.578019) (xy 119.952008 -381.577596)
			(xy 120.668288 -381.577596) (xy 120.678409 -381.578026) (xy 120.697112 -381.585769) (xy 120.711426 -381.600081)
			(xy 120.719173 -381.618783) (xy 120.719596 -381.628904) (xy 120.719596 -381.78613) (xy 120.719992 -381.795319)
			(xy 120.726516 -381.812503) (xy 120.732296 -381.819658) (xy 120.75415 -381.845331) (xy 120.79224 -381.900965)
			(xy 120.823391 -381.96076) (xy 120.847156 -382.023855) (xy 120.863192 -382.089344) (xy 120.871269 -382.156281)
			(xy 120.87127 -382.223646) (xy 124.14931 -382.223646) (xy 124.14931 -382.156339) (xy 124.157356 -382.089515)
			(xy 124.173332 -382.024132) (xy 124.197008 -381.961127) (xy 124.228045 -381.901403) (xy 124.265998 -381.845818)
			(xy 124.287788 -381.820166) (xy 124.29358 -381.813018) (xy 124.300098 -381.79583) (xy 124.300488 -381.786638)
			(xy 124.300488 -381.628904) (xy 124.300925 -381.618752) (xy 124.308717 -381.600002) (xy 124.323109 -381.585679)
			(xy 124.341896 -381.577977) (xy 124.35205 -381.577596) (xy 125.06833 -381.577596) (xy 125.078453 -381.578101)
			(xy 125.097167 -381.58583) (xy 125.11152 -381.60011) (xy 125.119346 -381.618783) (xy 125.119892 -381.628904)
			(xy 125.119892 -381.786638) (xy 125.120286 -381.795827) (xy 125.126811 -381.813011) (xy 125.132592 -381.820166)
			(xy 125.154369 -381.845827) (xy 125.192316 -381.901413) (xy 125.223348 -381.961135) (xy 125.24702 -382.024139)
			(xy 125.262993 -382.089519) (xy 125.271037 -382.156341) (xy 125.271038 -382.223644) (xy 125.271038 -382.223646)
			(xy 128.5491 -382.223646) (xy 128.549101 -382.156339) (xy 128.557147 -382.089515) (xy 128.573122 -382.024132)
			(xy 128.596798 -381.961127) (xy 128.627834 -381.901404) (xy 128.665787 -381.845818) (xy 128.687576 -381.820166)
			(xy 128.693367 -381.813016) (xy 128.699886 -381.795829) (xy 128.700276 -381.786638) (xy 128.700276 -381.628904)
			(xy 128.700724 -381.618753) (xy 128.708514 -381.600005) (xy 128.722902 -381.585683) (xy 128.741685 -381.577979)
			(xy 128.751838 -381.577596) (xy 129.468118 -381.577596) (xy 129.47824 -381.57811) (xy 129.496954 -381.585836)
			(xy 129.511308 -381.600113) (xy 129.519134 -381.618784) (xy 129.51968 -381.628904) (xy 129.51968 -381.786638)
			(xy 129.520076 -381.795827) (xy 129.5266 -381.813011) (xy 129.53238 -381.820166) (xy 129.554157 -381.845826)
			(xy 129.592105 -381.901412) (xy 129.623138 -381.961135) (xy 129.64681 -382.024138) (xy 129.662784 -382.089519)
			(xy 129.670828 -382.156341) (xy 129.670829 -382.223644) (xy 129.670829 -382.223645) (xy 159.349155 -382.223645)
			(xy 159.349156 -382.15634) (xy 159.3572 -382.089517) (xy 159.373174 -382.024134) (xy 159.396847 -381.96113)
			(xy 159.42788 -381.901406) (xy 159.465828 -381.845818) (xy 159.487616 -381.820166) (xy 159.493411 -381.81302)
			(xy 159.499926 -381.79583) (xy 159.500316 -381.786638) (xy 159.500316 -381.628904) (xy 159.50072 -381.61878)
			(xy 159.508469 -381.600073) (xy 159.52279 -381.585758) (xy 159.5415 -381.578016) (xy 159.551624 -381.577596)
			(xy 160.268158 -381.577596) (xy 160.278277 -381.57816) (xy 160.296988 -381.585866) (xy 160.311345 -381.600128)
			(xy 160.319173 -381.618789) (xy 160.31972 -381.628904) (xy 160.31972 -381.786638) (xy 160.320108 -381.795828)
			(xy 160.326637 -381.813012) (xy 160.33242 -381.820166) (xy 160.354199 -381.845826) (xy 160.392151 -381.90141)
			(xy 160.423187 -381.961132) (xy 160.446862 -382.024136) (xy 160.462837 -382.089518) (xy 160.470882 -382.15634)
			(xy 160.470883 -382.223645) (xy 160.470876 -382.223705) (xy 163.748923 -382.223705) (xy 163.748924 -382.15628)
			(xy 163.757001 -382.089341) (xy 163.773038 -382.023851) (xy 163.796804 -381.960754) (xy 163.827956 -381.900957)
			(xy 163.866047 -381.845323) (xy 163.887912 -381.819658) (xy 163.89371 -381.812514) (xy 163.900224 -381.795323)
			(xy 163.900612 -381.78613) (xy 163.900612 -381.628904) (xy 163.90102 -381.61878) (xy 163.908769 -381.600074)
			(xy 163.923088 -381.58576) (xy 163.941796 -381.578016) (xy 163.95192 -381.577596) (xy 164.6682 -381.577596)
			(xy 164.678322 -381.578016) (xy 164.697025 -381.585763) (xy 164.711339 -381.600079) (xy 164.719085 -381.618782)
			(xy 164.719508 -381.628904) (xy 164.719508 -381.78613) (xy 164.719902 -381.795319) (xy 164.726426 -381.812503)
			(xy 164.732208 -381.819658) (xy 164.754062 -381.845331) (xy 164.79215 -381.900965) (xy 164.823301 -381.96076)
			(xy 164.847065 -382.023856) (xy 164.863101 -382.089344) (xy 164.871178 -382.156281) (xy 164.871179 -382.223645)
			(xy 168.149243 -382.223645) (xy 168.149244 -382.15634) (xy 168.157288 -382.089517) (xy 168.173261 -382.024135)
			(xy 168.196933 -381.96113) (xy 168.227965 -381.901406) (xy 168.265913 -381.845819) (xy 168.2877 -381.820166)
			(xy 168.293494 -381.813019) (xy 168.30001 -381.79583) (xy 168.3004 -381.786638) (xy 168.3004 -381.628904)
			(xy 168.300825 -381.61875) (xy 168.308619 -381.599998) (xy 168.323015 -381.585674) (xy 168.341806 -381.577975)
			(xy 168.351962 -381.577596) (xy 169.068242 -381.577596) (xy 169.078366 -381.578091) (xy 169.09708 -381.585824)
			(xy 169.111433 -381.600107) (xy 169.119258 -381.618783) (xy 169.119804 -381.628904) (xy 169.119804 -381.786638)
			(xy 169.120195 -381.795827) (xy 169.126722 -381.813012) (xy 169.132504 -381.820166) (xy 169.154281 -381.845827)
			(xy 169.192227 -381.901413) (xy 169.223258 -381.961136) (xy 169.24693 -382.024139) (xy 169.262902 -382.08952)
			(xy 169.270946 -382.156341) (xy 169.270947 -382.223644) (xy 169.270947 -382.223646) (xy 172.54901 -382.223646)
			(xy 172.54901 -382.156339) (xy 172.557056 -382.089515) (xy 172.573032 -382.024132) (xy 172.596708 -381.961127)
			(xy 172.627745 -381.901403) (xy 172.665698 -381.845818) (xy 172.687488 -381.820166) (xy 172.69328 -381.813018)
			(xy 172.699798 -381.79583) (xy 172.700188 -381.786638) (xy 172.700188 -381.628904) (xy 172.700625 -381.618752)
			(xy 172.708417 -381.600002) (xy 172.722809 -381.585679) (xy 172.741596 -381.577977) (xy 172.75175 -381.577596)
			(xy 173.46803 -381.577596) (xy 173.478153 -381.578101) (xy 173.496867 -381.58583) (xy 173.51122 -381.60011)
			(xy 173.519046 -381.618783) (xy 173.519592 -381.628904) (xy 173.519592 -381.786638) (xy 173.519986 -381.795827)
			(xy 173.526511 -381.813011) (xy 173.532292 -381.820166) (xy 173.554069 -381.845827) (xy 173.592016 -381.901413)
			(xy 173.623048 -381.961135) (xy 173.64672 -382.024139) (xy 173.662693 -382.089519) (xy 173.670737 -382.156341)
			(xy 173.670738 -382.223644) (xy 173.662695 -382.290466) (xy 173.646725 -382.355847) (xy 173.623054 -382.418851)
			(xy 173.592024 -382.478574) (xy 173.554078 -382.534161) (xy 173.532292 -382.559814) (xy 173.526506 -382.566967)
			(xy 173.519985 -382.584151) (xy 173.519592 -382.593342) (xy 173.519592 -383.086864) (xy 173.520021 -383.096049)
			(xy 173.526522 -383.113234) (xy 173.532292 -383.120392) (xy 173.554094 -383.146032) (xy 173.592041 -383.201621)
			(xy 173.623072 -383.261346) (xy 173.646507 -383.323727) (xy 174.749152 -383.323727) (xy 174.749155 -383.256419)
			(xy 174.757202 -383.189594) (xy 174.773179 -383.12421) (xy 174.796856 -383.061204) (xy 174.827893 -383.001479)
			(xy 174.865846 -382.945892) (xy 174.887636 -382.92024) (xy 174.893445 -382.913104) (xy 174.899951 -382.895906)
			(xy 174.900336 -382.886712) (xy 174.900336 -382.728724) (xy 174.900742 -382.718567) (xy 174.908536 -382.699808)
			(xy 174.922939 -382.685482) (xy 174.941739 -382.677788) (xy 174.951898 -382.677416) (xy 175.668178 -382.677416)
			(xy 175.6783 -382.677944) (xy 175.697017 -382.68566) (xy 175.711373 -382.699933) (xy 175.719197 -382.718605)
			(xy 175.71974 -382.728724) (xy 175.71974 -382.886712) (xy 175.720158 -382.895898) (xy 175.726668 -382.913082)
			(xy 175.73244 -382.92024) (xy 175.754193 -382.945921) (xy 175.792144 -383.001503) (xy 175.82318 -383.061222)
			(xy 175.846856 -383.124223) (xy 175.862832 -383.189602) (xy 175.870879 -383.256422) (xy 175.870883 -383.323724)
			(xy 175.862842 -383.390545) (xy 175.846872 -383.455925) (xy 175.823202 -383.518928) (xy 175.792172 -383.578651)
			(xy 175.754226 -383.634236) (xy 175.73244 -383.659888) (xy 175.726616 -383.667014) (xy 175.720119 -383.684219)
			(xy 175.71974 -383.693416) (xy 175.71974 -384.186684) (xy 175.720171 -384.195869) (xy 175.726672 -384.213053)
			(xy 175.73244 -384.220212) (xy 175.754264 -384.245835) (xy 175.792213 -384.301425) (xy 175.823246 -384.361152)
			(xy 175.846918 -384.424161) (xy 175.862889 -384.489547) (xy 175.87093 -384.556373) (xy 175.870927 -384.623681)
			(xy 175.862879 -384.690507) (xy 175.846902 -384.755891) (xy 175.823224 -384.818897) (xy 175.792185 -384.878622)
			(xy 175.754231 -384.934208) (xy 175.73244 -384.95986) (xy 175.726628 -384.966994) (xy 175.720124 -384.984193)
			(xy 175.71974 -384.993388) (xy 175.71974 -385.151376) (xy 175.71926 -385.161524) (xy 175.71148 -385.180268)
			(xy 175.697101 -385.194591) (xy 175.678327 -385.202298) (xy 175.668178 -385.202684) (xy 174.951898 -385.202684)
			(xy 174.941774 -385.202176) (xy 174.923058 -385.194452) (xy 174.908702 -385.180172) (xy 174.900879 -385.161497)
			(xy 174.900336 -385.151376) (xy 174.900336 -384.993388) (xy 174.899924 -384.984201) (xy 174.893411 -384.967017)
			(xy 174.887636 -384.95986) (xy 174.865884 -384.934179) (xy 174.827934 -384.878596) (xy 174.7969 -384.818877)
			(xy 174.773225 -384.755876) (xy 174.75725 -384.690497) (xy 174.749203 -384.623678) (xy 174.749199 -384.556376)
			(xy 174.75724 -384.489556) (xy 174.773209 -384.424176) (xy 174.796878 -384.361173) (xy 174.827906 -384.30145)
			(xy 174.865851 -384.245864) (xy 174.887636 -384.220212) (xy 174.893457 -384.213084) (xy 174.899956 -384.19588)
			(xy 174.900336 -384.186684) (xy 174.900336 -383.693416) (xy 174.89991 -383.684231) (xy 174.893407 -383.667046)
			(xy 174.887636 -383.659888) (xy 174.865813 -383.634265) (xy 174.827865 -383.578674) (xy 174.796834 -383.518947)
			(xy 174.773163 -383.455938) (xy 174.757193 -383.390553) (xy 174.749152 -383.323727) (xy 173.646507 -383.323727)
			(xy 173.646742 -383.324352) (xy 173.662713 -383.389736) (xy 173.670756 -383.456559) (xy 173.670754 -383.523865)
			(xy 173.662709 -383.590688) (xy 173.646735 -383.656071) (xy 173.623062 -383.719076) (xy 173.592028 -383.7788)
			(xy 173.55408 -383.834387) (xy 173.532292 -383.86004) (xy 173.526495 -383.867185) (xy 173.519981 -383.884376)
			(xy 173.519592 -383.893568) (xy 173.519592 -384.051556) (xy 173.519142 -384.061708) (xy 173.51136 -384.080461)
			(xy 173.496971 -384.094786) (xy 173.478184 -384.102486) (xy 173.46803 -384.102864) (xy 172.75175 -384.102864)
			(xy 172.741627 -384.102333) (xy 172.722908 -384.094622) (xy 172.70855 -384.080349) (xy 172.700728 -384.061676)
			(xy 172.700188 -384.051556) (xy 172.700188 -383.893568) (xy 172.699796 -383.884379) (xy 172.69327 -383.867194)
			(xy 172.687488 -383.86004) (xy 172.665715 -383.834376) (xy 172.627762 -383.778792) (xy 172.596725 -383.719071)
			(xy 172.57305 -383.656068) (xy 172.557074 -383.590686) (xy 172.549028 -383.523864) (xy 172.549026 -383.45656)
			(xy 172.55707 -383.389737) (xy 172.573042 -383.324355) (xy 172.596716 -383.261351) (xy 172.62775 -383.201629)
			(xy 172.6657 -383.146043) (xy 172.687488 -383.120392) (xy 172.693269 -383.113236) (xy 172.699793 -383.096054)
			(xy 172.700188 -383.086864) (xy 172.700188 -382.593342) (xy 172.69976 -382.584157) (xy 172.693259 -382.566972)
			(xy 172.687488 -382.559814) (xy 172.665689 -382.534171) (xy 172.627737 -382.478584) (xy 172.596702 -382.41886)
			(xy 172.573027 -382.355854) (xy 172.557054 -382.29047) (xy 172.54901 -382.223646) (xy 169.270947 -382.223646)
			(xy 169.262905 -382.290465) (xy 169.246934 -382.355847) (xy 169.223264 -382.41885) (xy 169.192235 -382.478574)
			(xy 169.15429 -382.534161) (xy 169.132504 -382.559814) (xy 169.126719 -382.566968) (xy 169.120197 -382.584152)
			(xy 169.119804 -382.593342) (xy 169.119804 -383.086864) (xy 169.120231 -383.096049) (xy 169.126733 -383.113234)
			(xy 169.132504 -383.120392) (xy 169.154306 -383.146032) (xy 169.192252 -383.201621) (xy 169.223282 -383.261347)
			(xy 169.246739 -383.323787) (xy 170.348832 -383.323787) (xy 170.348835 -383.256359) (xy 170.356915 -383.189418)
			(xy 170.372956 -383.123926) (xy 170.396726 -383.060827) (xy 170.427884 -383.001031) (xy 170.46598 -382.945396)
			(xy 170.487848 -382.919732) (xy 170.493662 -382.912599) (xy 170.500165 -382.895399) (xy 170.500548 -382.886204)
			(xy 170.500548 -382.728724) (xy 170.501103 -382.718623) (xy 170.508823 -382.699955) (xy 170.523098 -382.685662)
			(xy 170.541756 -382.677917) (xy 170.551856 -382.677416) (xy 171.268136 -382.677416) (xy 171.278249 -382.677856)
			(xy 171.296931 -382.685608) (xy 171.311225 -382.699919) (xy 171.318956 -382.71861) (xy 171.319444 -382.728724)
			(xy 171.319444 -382.886204) (xy 171.319865 -382.89539) (xy 171.326372 -382.912574) (xy 171.332144 -382.919732)
			(xy 171.353975 -382.945425) (xy 171.392068 -383.001055) (xy 171.423223 -383.060846) (xy 171.446992 -383.12394)
			(xy 171.463032 -383.189426) (xy 171.471111 -383.256362) (xy 171.471115 -383.323784) (xy 171.463041 -383.390721)
			(xy 171.447008 -383.456209) (xy 171.423246 -383.519304) (xy 171.392096 -383.579099) (xy 171.354008 -383.634732)
			(xy 171.332144 -383.660396) (xy 171.32636 -383.66755) (xy 171.319839 -383.684734) (xy 171.319444 -383.693924)
			(xy 171.319444 -384.186176) (xy 171.319878 -384.19536) (xy 171.326376 -384.212544) (xy 171.332144 -384.219704)
			(xy 171.354045 -384.245339) (xy 171.392137 -384.300977) (xy 171.423289 -384.360776) (xy 171.447054 -384.423877)
			(xy 171.463088 -384.489371) (xy 171.471162 -384.556313) (xy 171.471159 -384.623741) (xy 171.463078 -384.690683)
			(xy 171.447037 -384.756174) (xy 171.423267 -384.819273) (xy 171.392109 -384.87907) (xy 171.354012 -384.934704)
			(xy 171.332144 -384.960368) (xy 171.326329 -384.9675) (xy 171.319827 -384.984701) (xy 171.319444 -384.993896)
			(xy 171.319444 -385.151376) (xy 171.318896 -385.161478) (xy 171.311175 -385.180147) (xy 171.296897 -385.194441)
			(xy 171.278237 -385.202185) (xy 171.268136 -385.202684) (xy 170.551856 -385.202684) (xy 170.541742 -385.20225)
			(xy 170.52306 -385.194495) (xy 170.508766 -385.180183) (xy 170.501036 -385.16149) (xy 170.500548 -385.151376)
			(xy 170.500548 -384.993896) (xy 170.500129 -384.98471) (xy 170.49362 -384.967526) (xy 170.487848 -384.960368)
			(xy 170.466018 -384.934674) (xy 170.427925 -384.879045) (xy 170.39677 -384.819253) (xy 170.373001 -384.75616)
			(xy 170.356962 -384.690674) (xy 170.348883 -384.623738) (xy 170.348879 -384.556316) (xy 170.356952 -384.489379)
			(xy 170.372985 -384.423892) (xy 170.396748 -384.360796) (xy 170.427897 -384.301001) (xy 170.465984 -384.245368)
			(xy 170.487848 -384.219704) (xy 170.493631 -384.21255) (xy 170.500153 -384.195366) (xy 170.500548 -384.186176)
			(xy 170.500548 -383.693924) (xy 170.500116 -383.684739) (xy 170.493616 -383.667555) (xy 170.487848 -383.660396)
			(xy 170.465947 -383.634761) (xy 170.427856 -383.579123) (xy 170.396704 -383.519323) (xy 170.37294 -383.456222)
			(xy 170.356906 -383.390729) (xy 170.348832 -383.323787) (xy 169.246739 -383.323787) (xy 169.246952 -383.324353)
			(xy 169.262922 -383.389736) (xy 169.270965 -383.456559) (xy 169.270963 -383.523865) (xy 169.262918 -383.590688)
			(xy 169.246945 -383.65607) (xy 169.223272 -383.719075) (xy 169.192239 -383.7788) (xy 169.154291 -383.834387)
			(xy 169.132504 -383.86004) (xy 169.126708 -383.867186) (xy 169.120193 -383.884376) (xy 169.119804 -383.893568)
			(xy 169.119804 -384.051556) (xy 169.119342 -384.061707) (xy 169.111562 -384.080457) (xy 169.097177 -384.094782)
			(xy 169.078394 -384.102484) (xy 169.068242 -384.102864) (xy 168.351962 -384.102864) (xy 168.341833 -384.102405)
			(xy 168.323112 -384.094665) (xy 168.308757 -384.080371) (xy 168.300939 -384.061682) (xy 168.3004 -384.051556)
			(xy 168.3004 -383.893568) (xy 168.300005 -383.884379) (xy 168.293481 -383.867195) (xy 168.2877 -383.86004)
			(xy 168.265929 -383.834374) (xy 168.227982 -383.778789) (xy 168.196951 -383.719067) (xy 168.173279 -383.656064)
			(xy 168.157306 -383.590684) (xy 168.149261 -383.523864) (xy 168.149259 -383.456561) (xy 168.157301 -383.38974)
			(xy 168.173272 -383.324359) (xy 168.196941 -383.261355) (xy 168.22797 -383.201632) (xy 168.265914 -383.146045)
			(xy 168.2877 -383.120392) (xy 168.293482 -383.113237) (xy 168.300006 -383.096054) (xy 168.3004 -383.086864)
			(xy 168.3004 -382.593342) (xy 168.29997 -382.584157) (xy 168.29347 -382.566972) (xy 168.2877 -382.559814)
			(xy 168.265904 -382.534169) (xy 168.227958 -382.478581) (xy 168.196927 -382.418856) (xy 168.173256 -382.355851)
			(xy 168.157285 -382.290468) (xy 168.149243 -382.223645) (xy 164.871179 -382.223645) (xy 164.871179 -382.223704)
			(xy 164.863104 -382.290641) (xy 164.84707 -382.35613) (xy 164.823307 -382.419226) (xy 164.792158 -382.479022)
			(xy 164.754071 -382.534657) (xy 164.732208 -382.560322) (xy 164.726421 -382.567474) (xy 164.7199 -382.584659)
			(xy 164.719508 -382.59385) (xy 164.719508 -383.086356) (xy 164.719937 -383.095541) (xy 164.726437 -383.112726)
			(xy 164.732208 -383.119884) (xy 164.754087 -383.145536) (xy 164.792175 -383.201173) (xy 164.823325 -383.260971)
			(xy 164.846959 -383.323727) (xy 165.949064 -383.323727) (xy 165.949067 -383.256419) (xy 165.957115 -383.189594)
			(xy 165.973092 -383.124209) (xy 165.996769 -383.061203) (xy 166.027808 -383.001479) (xy 166.065762 -382.945892)
			(xy 166.087552 -382.92024) (xy 166.093363 -382.913105) (xy 166.099868 -382.895907) (xy 166.100252 -382.886712)
			(xy 166.100252 -382.728724) (xy 166.10074 -382.718577) (xy 166.108519 -382.699835) (xy 166.122895 -382.685512)
			(xy 166.141666 -382.677803) (xy 166.151814 -382.677416) (xy 166.868094 -382.677416) (xy 166.878217 -382.677931)
			(xy 166.896934 -382.685652) (xy 166.911289 -382.699929) (xy 166.919113 -382.718603) (xy 166.919656 -382.728724)
			(xy 166.919656 -382.886712) (xy 166.92007 -382.895899) (xy 166.926582 -382.913082) (xy 166.932356 -382.92024)
			(xy 166.954108 -382.945921) (xy 166.992059 -383.001503) (xy 167.023094 -383.061223) (xy 167.046769 -383.124224)
			(xy 167.062744 -383.189602) (xy 167.070791 -383.256422) (xy 167.070795 -383.323724) (xy 167.062754 -383.390544)
			(xy 167.046785 -383.455925) (xy 167.023116 -383.518928) (xy 166.992086 -383.57865) (xy 166.954142 -383.634236)
			(xy 166.932356 -383.659888) (xy 166.926534 -383.667015) (xy 166.920036 -383.68422) (xy 166.919656 -383.693416)
			(xy 166.919656 -384.186684) (xy 166.920084 -384.195869) (xy 166.926586 -384.213053) (xy 166.932356 -384.220212)
			(xy 166.954179 -384.245835) (xy 166.992127 -384.301425) (xy 167.023159 -384.361153) (xy 167.04683 -384.424161)
			(xy 167.062801 -384.489547) (xy 167.070842 -384.556373) (xy 167.070839 -384.623681) (xy 167.062791 -384.690506)
			(xy 167.046814 -384.75589) (xy 167.023137 -384.818897) (xy 166.9921 -384.878621) (xy 166.954146 -384.934208)
			(xy 166.932356 -384.95986) (xy 166.926546 -384.966995) (xy 166.92004 -384.984194) (xy 166.919656 -384.993388)
			(xy 166.919656 -385.151376) (xy 166.91916 -385.161522) (xy 166.911383 -385.180263) (xy 166.89701 -385.194585)
			(xy 166.878241 -385.202296) (xy 166.868094 -385.202684) (xy 166.151814 -385.202684) (xy 166.141691 -385.202163)
			(xy 166.122975 -385.194444) (xy 166.108619 -385.180169) (xy 166.100795 -385.161496) (xy 166.100252 -385.151376)
			(xy 166.100252 -384.993388) (xy 166.099836 -384.984202) (xy 166.093325 -384.967018) (xy 166.087552 -384.95986)
			(xy 166.065799 -384.934179) (xy 166.027849 -384.878597) (xy 165.996813 -384.818877) (xy 165.973138 -384.755877)
			(xy 165.957162 -384.690498) (xy 165.949115 -384.623678) (xy 165.949111 -384.556376) (xy 165.957152 -384.489555)
			(xy 165.973122 -384.424175) (xy 165.996791 -384.361172) (xy 166.027821 -384.30145) (xy 166.065766 -384.245864)
			(xy 166.087552 -384.220212) (xy 166.093375 -384.213086) (xy 166.099872 -384.19588) (xy 166.100252 -384.186684)
			(xy 166.100252 -383.693416) (xy 166.099823 -383.684231) (xy 166.093321 -383.667047) (xy 166.087552 -383.659888)
			(xy 166.065728 -383.634265) (xy 166.02778 -383.578675) (xy 165.996747 -383.518947) (xy 165.973076 -383.455939)
			(xy 165.957105 -383.390553) (xy 165.949064 -383.323727) (xy 164.846959 -383.323727) (xy 164.847088 -383.32407)
			(xy 164.863122 -383.38956) (xy 164.871196 -383.4565) (xy 164.871195 -383.523924) (xy 164.863117 -383.590864)
			(xy 164.84708 -383.656353) (xy 164.823315 -383.719451) (xy 164.792163 -383.779248) (xy 164.754073 -383.834883)
			(xy 164.732208 -383.860548) (xy 164.726409 -383.867692) (xy 164.719896 -383.884883) (xy 164.719508 -383.894076)
			(xy 164.719508 -384.051556) (xy 164.719048 -384.061675) (xy 164.711316 -384.080376) (xy 164.697013 -384.094691)
			(xy 164.678318 -384.102439) (xy 164.6682 -384.102864) (xy 163.95192 -384.102864) (xy 163.941794 -384.102467)
			(xy 163.923084 -384.094719) (xy 163.908768 -384.080396) (xy 163.901028 -384.061682) (xy 163.900612 -384.051556)
			(xy 163.900612 -383.894076) (xy 163.900211 -383.884888) (xy 163.893691 -383.867704) (xy 163.887912 -383.860548)
			(xy 163.866063 -383.83487) (xy 163.827973 -383.779238) (xy 163.796821 -383.719443) (xy 163.773056 -383.656348)
			(xy 163.757019 -383.59086) (xy 163.748941 -383.523923) (xy 163.74894 -383.456501) (xy 163.757014 -383.389563)
			(xy 163.773049 -383.324075) (xy 163.796811 -383.260979) (xy 163.827961 -383.201183) (xy 163.866049 -383.145549)
			(xy 163.887912 -383.119884) (xy 163.893699 -383.112732) (xy 163.900219 -383.095547) (xy 163.900612 -383.086356)
			(xy 163.900612 -382.59385) (xy 163.900175 -382.584666) (xy 163.89368 -382.567481) (xy 163.887912 -382.560322)
			(xy 163.866038 -382.534665) (xy 163.827949 -382.47903) (xy 163.796798 -382.419232) (xy 163.773034 -382.356134)
			(xy 163.756998 -382.290644) (xy 163.748923 -382.223705) (xy 160.470876 -382.223705) (xy 160.46284 -382.290468)
			(xy 160.446866 -382.35585) (xy 160.423193 -382.418854) (xy 160.392159 -382.478577) (xy 160.354208 -382.534162)
			(xy 160.33242 -382.559814) (xy 160.326637 -382.566969) (xy 160.320114 -382.584152) (xy 160.31972 -382.593342)
			(xy 160.31972 -383.086864) (xy 160.320143 -383.09605) (xy 160.326647 -383.113235) (xy 160.33242 -383.120392)
			(xy 160.354225 -383.146031) (xy 160.392176 -383.201618) (xy 160.42321 -383.261343) (xy 160.446672 -383.323786)
			(xy 161.548769 -383.323786) (xy 161.548772 -383.25636) (xy 161.556851 -383.18942) (xy 161.572889 -383.123929)
			(xy 161.596656 -383.060831) (xy 161.627809 -383.001034) (xy 161.665899 -382.945398) (xy 161.687764 -382.919732)
			(xy 161.69358 -382.912601) (xy 161.700081 -382.895399) (xy 161.700464 -382.886204) (xy 161.700464 -382.728724)
			(xy 161.701004 -382.718621) (xy 161.708727 -382.69995) (xy 161.723007 -382.685656) (xy 161.74167 -382.677914)
			(xy 161.751772 -382.677416) (xy 162.468052 -382.677416) (xy 162.478173 -382.677856) (xy 162.496879 -382.685591)
			(xy 162.511195 -382.699901) (xy 162.51894 -382.718603) (xy 162.51936 -382.728724) (xy 162.51936 -382.886204)
			(xy 162.519777 -382.89539) (xy 162.526287 -382.912574) (xy 162.53206 -382.919732) (xy 162.55389 -382.945426)
			(xy 162.591982 -383.001055) (xy 162.623137 -383.060847) (xy 162.646905 -383.12394) (xy 162.662944 -383.189426)
			(xy 162.671023 -383.256362) (xy 162.671027 -383.323784) (xy 162.662954 -383.39072) (xy 162.646921 -383.456208)
			(xy 162.623159 -383.519303) (xy 162.59201 -383.579098) (xy 162.553923 -383.634731) (xy 162.53206 -383.660396)
			(xy 162.526278 -383.667551) (xy 162.519755 -383.684734) (xy 162.51936 -383.693924) (xy 162.51936 -384.186176)
			(xy 162.51979 -384.195361) (xy 162.526291 -384.212545) (xy 162.53206 -384.219704) (xy 162.553961 -384.245339)
			(xy 162.592051 -384.300977) (xy 162.623202 -384.360777) (xy 162.646966 -384.423878) (xy 162.663 -384.489371)
			(xy 162.671074 -384.556313) (xy 162.671071 -384.623741) (xy 162.662991 -384.690682) (xy 162.64695 -384.756174)
			(xy 162.62318 -384.819272) (xy 162.592023 -384.879069) (xy 162.553928 -384.934703) (xy 162.53206 -384.960368)
			(xy 162.526247 -384.967501) (xy 162.519743 -384.984701) (xy 162.51936 -384.993896) (xy 162.51936 -385.151376)
			(xy 162.518964 -385.161502) (xy 162.511216 -385.180213) (xy 162.496893 -385.194529) (xy 162.478178 -385.202268)
			(xy 162.468052 -385.202684) (xy 161.751772 -385.202684) (xy 161.741659 -385.202238) (xy 161.722978 -385.194488)
			(xy 161.708683 -385.180179) (xy 161.700952 -385.161489) (xy 161.700464 -385.151376) (xy 161.700464 -384.993896)
			(xy 161.700041 -384.98471) (xy 161.693535 -384.967527) (xy 161.687764 -384.960368) (xy 161.665937 -384.934673)
			(xy 161.627849 -384.879042) (xy 161.596699 -384.819249) (xy 161.572934 -384.756157) (xy 161.556897 -384.690671)
			(xy 161.548819 -384.623737) (xy 161.548816 -384.556317) (xy 161.556888 -384.489382) (xy 161.572918 -384.423895)
			(xy 161.596677 -384.3608) (xy 161.627821 -384.301005) (xy 161.665903 -384.24537) (xy 161.687764 -384.219704)
			(xy 161.693549 -384.212551) (xy 161.700069 -384.195366) (xy 161.700464 -384.186176) (xy 161.700464 -383.693924)
			(xy 161.700028 -383.68474) (xy 161.693531 -383.667556) (xy 161.687764 -383.660396) (xy 161.665866 -383.634759)
			(xy 161.627781 -383.57912) (xy 161.596634 -383.519319) (xy 161.572873 -383.456219) (xy 161.556841 -383.390727)
			(xy 161.548769 -383.323786) (xy 160.446672 -383.323786) (xy 160.446884 -383.32435) (xy 160.462857 -383.389734)
			(xy 160.470901 -383.456558) (xy 160.470899 -383.523866) (xy 160.462853 -383.59069) (xy 160.446877 -383.656074)
			(xy 160.423201 -383.719079) (xy 160.392163 -383.778803) (xy 160.35421 -383.834388) (xy 160.33242 -383.86004)
			(xy 160.326626 -383.867187) (xy 160.320109 -383.884376) (xy 160.31972 -383.893568) (xy 160.31972 -384.051556)
			(xy 160.319248 -384.061673) (xy 160.311518 -384.080372) (xy 160.297219 -384.094687) (xy 160.278529 -384.102437)
			(xy 160.268412 -384.102864) (xy 159.551878 -384.102864) (xy 159.54175 -384.102392) (xy 159.523029 -384.094657)
			(xy 159.508674 -384.080367) (xy 159.500855 -384.061681) (xy 159.500316 -384.051556) (xy 159.500316 -383.893568)
			(xy 159.499918 -383.88438) (xy 159.493395 -383.867196) (xy 159.487616 -383.86004) (xy 159.465845 -383.834375)
			(xy 159.427897 -383.77879) (xy 159.396864 -383.719068) (xy 159.373191 -383.656065) (xy 159.357218 -383.590684)
			(xy 159.349173 -383.523864) (xy 159.349172 -383.45656) (xy 159.357214 -383.389739) (xy 159.373184 -383.324358)
			(xy 159.396854 -383.261354) (xy 159.427884 -383.201631) (xy 159.46583 -383.146044) (xy 159.487616 -383.120392)
			(xy 159.4934 -383.113238) (xy 159.499922 -383.096054) (xy 159.500316 -383.086864) (xy 159.500316 -382.593342)
			(xy 159.499882 -382.584157) (xy 159.493384 -382.566973) (xy 159.487616 -382.559814) (xy 159.465819 -382.53417)
			(xy 159.427872 -382.478582) (xy 159.396841 -382.418857) (xy 159.373169 -382.355851) (xy 159.357198 -382.290468)
			(xy 159.349155 -382.223645) (xy 129.670829 -382.223645) (xy 129.662786 -382.290466) (xy 129.646815 -382.355847)
			(xy 129.623144 -382.418851) (xy 129.592113 -382.478575) (xy 129.554167 -382.534162) (xy 129.53238 -382.559814)
			(xy 129.526593 -382.566966) (xy 129.520073 -382.584151) (xy 129.51968 -382.593342) (xy 129.51968 -383.086864)
			(xy 129.520112 -383.096049) (xy 129.526611 -383.113233) (xy 129.53238 -383.120392) (xy 129.554183 -383.146031)
			(xy 129.59213 -383.20162) (xy 129.623162 -383.261346) (xy 129.646598 -383.323727) (xy 130.749242 -383.323727)
			(xy 130.749246 -383.256419) (xy 130.757293 -383.189594) (xy 130.77327 -383.12421) (xy 130.796946 -383.061204)
			(xy 130.827982 -383.00148) (xy 130.865935 -382.945892) (xy 130.887724 -382.92024) (xy 130.893531 -382.913103)
			(xy 130.900039 -382.895906) (xy 130.900424 -382.886712) (xy 130.900424 -382.728724) (xy 130.900842 -382.718568)
			(xy 130.908634 -382.699812) (xy 130.923032 -382.685487) (xy 130.941828 -382.67779) (xy 130.951986 -382.677416)
			(xy 131.668266 -382.677416) (xy 131.678388 -382.677954) (xy 131.697103 -382.685666) (xy 131.71146 -382.699937)
			(xy 131.719284 -382.718606) (xy 131.719828 -382.728724) (xy 131.719828 -382.886712) (xy 131.720226 -382.895901)
			(xy 131.726747 -382.913085) (xy 131.732528 -382.92024) (xy 131.754281 -382.945921) (xy 131.792233 -383.001502)
			(xy 131.82327 -383.061222) (xy 131.846946 -383.124223) (xy 131.862923 -383.189602) (xy 131.87097 -383.256422)
			(xy 131.870973 -383.323724) (xy 131.862932 -383.390545) (xy 131.846962 -383.455926) (xy 131.823292 -383.518929)
			(xy 131.792261 -383.578651) (xy 131.754314 -383.634236) (xy 131.732528 -383.659888) (xy 131.726703 -383.667013)
			(xy 131.720207 -383.684219) (xy 131.719828 -383.693416) (xy 131.719828 -384.186684) (xy 131.720239 -384.195871)
			(xy 131.726751 -384.213056) (xy 131.732528 -384.220212) (xy 131.754352 -384.245834) (xy 131.792302 -384.301424)
			(xy 131.823336 -384.361152) (xy 131.847008 -384.42416) (xy 131.86298 -384.489546) (xy 131.871021 -384.556373)
			(xy 131.871018 -384.623681) (xy 131.86297 -384.690507) (xy 131.846992 -384.755892) (xy 131.823314 -384.818898)
			(xy 131.792274 -384.878622) (xy 131.754319 -384.934208) (xy 131.732528 -384.95986) (xy 131.726715 -384.966993)
			(xy 131.720212 -384.984193) (xy 131.719828 -384.993388) (xy 131.719828 -385.151376) (xy 131.719359 -385.161525)
			(xy 131.711577 -385.180272) (xy 131.697195 -385.194595) (xy 131.678417 -385.202301) (xy 131.668266 -385.202684)
			(xy 130.951986 -385.202684) (xy 130.941861 -385.202185) (xy 130.923145 -385.194457) (xy 130.90879 -385.180175)
			(xy 130.900967 -385.161498) (xy 130.900424 -385.151376) (xy 130.900424 -384.993388) (xy 130.900014 -384.984201)
			(xy 130.8935 -384.967017) (xy 130.887724 -384.95986) (xy 130.865972 -384.934178) (xy 130.828023 -384.878596)
			(xy 130.796989 -384.818876) (xy 130.773315 -384.755876) (xy 130.75734 -384.690497) (xy 130.749294 -384.623678)
			(xy 130.74929 -384.556376) (xy 130.757331 -384.489556) (xy 130.773299 -384.424176) (xy 130.796967 -384.361173)
			(xy 130.827996 -384.301451) (xy 130.865939 -384.245865) (xy 130.887724 -384.220212) (xy 130.893543 -384.213083)
			(xy 130.900044 -384.19588) (xy 130.900424 -384.186684) (xy 130.900424 -383.693416) (xy 130.900001 -383.68423)
			(xy 130.893495 -383.667046) (xy 130.887724 -383.659888) (xy 130.865901 -383.634265) (xy 130.827955 -383.578674)
			(xy 130.796924 -383.518946) (xy 130.773254 -383.455938) (xy 130.757284 -383.390552) (xy 130.749242 -383.323727)
			(xy 129.646598 -383.323727) (xy 129.646833 -383.324352) (xy 129.662804 -383.389735) (xy 129.670846 -383.456559)
			(xy 129.670845 -383.523865) (xy 129.6628 -383.590688) (xy 129.646826 -383.656071) (xy 129.623152 -383.719076)
			(xy 129.592118 -383.778801) (xy 129.554168 -383.834388) (xy 129.53238 -383.86004) (xy 129.526582 -383.867184)
			(xy 129.520069 -383.884375) (xy 129.51968 -383.893568) (xy 129.51968 -384.051556) (xy 129.519242 -384.06171)
			(xy 129.511457 -384.080465) (xy 129.497065 -384.094791) (xy 129.478274 -384.102488) (xy 129.468118 -384.102864)
			(xy 128.751838 -384.102864) (xy 128.741714 -384.102342) (xy 128.722995 -384.094628) (xy 128.708637 -384.080352)
			(xy 128.700816 -384.061677) (xy 128.700276 -384.051556) (xy 128.700276 -383.893568) (xy 128.699886 -383.884379)
			(xy 128.693359 -383.867194) (xy 128.687576 -383.86004) (xy 128.665803 -383.834375) (xy 128.627851 -383.778792)
			(xy 128.596815 -383.71907) (xy 128.57314 -383.656067) (xy 128.557165 -383.590686) (xy 128.549119 -383.523864)
			(xy 128.549117 -383.45656) (xy 128.55716 -383.389738) (xy 128.573133 -383.324356) (xy 128.596805 -383.261352)
			(xy 128.627839 -383.201629) (xy 128.665788 -383.146044) (xy 128.687576 -383.120392) (xy 128.693356 -383.113235)
			(xy 128.699881 -383.096054) (xy 128.700276 -383.086864) (xy 128.700276 -382.593342) (xy 128.699851 -382.584156)
			(xy 128.693348 -382.566971) (xy 128.687576 -382.559814) (xy 128.665777 -382.53417) (xy 128.627826 -382.478584)
			(xy 128.596792 -382.418859) (xy 128.573118 -382.355853) (xy 128.557144 -382.29047) (xy 128.5491 -382.223646)
			(xy 125.271038 -382.223646) (xy 125.262995 -382.290466) (xy 125.247025 -382.355847) (xy 125.223354 -382.418851)
			(xy 125.192324 -382.478574) (xy 125.154378 -382.534161) (xy 125.132592 -382.559814) (xy 125.126806 -382.566967)
			(xy 125.120285 -382.584151) (xy 125.119892 -382.593342) (xy 125.119892 -383.086864) (xy 125.120321 -383.096049)
			(xy 125.126822 -383.113234) (xy 125.132592 -383.120392) (xy 125.154394 -383.146032) (xy 125.192341 -383.201621)
			(xy 125.223372 -383.261346) (xy 125.24683 -383.323787) (xy 126.348923 -383.323787) (xy 126.348926 -383.256359)
			(xy 126.357006 -383.189418) (xy 126.373047 -383.123926) (xy 126.396816 -383.060828) (xy 126.427973 -383.001031)
			(xy 126.466069 -382.945397) (xy 126.487936 -382.919732) (xy 126.493749 -382.912598) (xy 126.500253 -382.895399)
			(xy 126.500636 -382.886204) (xy 126.500636 -382.728724) (xy 126.501036 -382.718599) (xy 126.508783 -382.699889)
			(xy 126.523105 -382.685572) (xy 126.541818 -382.677832) (xy 126.551944 -382.677416) (xy 127.268224 -382.677416)
			(xy 127.278336 -382.677866) (xy 127.297018 -382.685614) (xy 127.311313 -382.699922) (xy 127.319044 -382.718611)
			(xy 127.319532 -382.728724) (xy 127.319532 -382.886204) (xy 127.319956 -382.895389) (xy 127.326462 -382.912573)
			(xy 127.332232 -382.919732) (xy 127.354059 -382.945427) (xy 127.392147 -383.001058) (xy 127.423298 -383.06085)
			(xy 127.447062 -383.123943) (xy 127.463099 -383.189428) (xy 127.471178 -383.256363) (xy 127.471181 -383.323783)
			(xy 127.463109 -383.390718) (xy 127.447078 -383.456205) (xy 127.42332 -383.5193) (xy 127.392175 -383.579096)
			(xy 127.354093 -383.63473) (xy 127.332232 -383.660396) (xy 127.326446 -383.667549) (xy 127.319927 -383.684734)
			(xy 127.319532 -383.693924) (xy 127.319532 -384.186176) (xy 127.319969 -384.19536) (xy 127.326466 -384.212544)
			(xy 127.332232 -384.219704) (xy 127.35413 -384.245341) (xy 127.392216 -384.30098) (xy 127.423363 -384.36078)
			(xy 127.447124 -384.423881) (xy 127.463156 -384.489373) (xy 127.471228 -384.556314) (xy 127.471225 -384.62374)
			(xy 127.463146 -384.69068) (xy 127.447108 -384.756171) (xy 127.423341 -384.819269) (xy 127.392188 -384.879066)
			(xy 127.354097 -384.934702) (xy 127.332232 -384.960368) (xy 127.326416 -384.967499) (xy 127.319915 -384.984701)
			(xy 127.319532 -384.993896) (xy 127.319532 -385.151376) (xy 127.318996 -385.161479) (xy 127.311272 -385.180151)
			(xy 127.296991 -385.194445) (xy 127.278327 -385.202187) (xy 127.268224 -385.202684) (xy 126.551944 -385.202684)
			(xy 126.541822 -385.202247) (xy 126.523117 -385.194511) (xy 126.5088 -385.1802) (xy 126.501056 -385.161497)
			(xy 126.500636 -385.151376) (xy 126.500636 -384.993896) (xy 126.50022 -384.98471) (xy 126.49371 -384.967526)
			(xy 126.487936 -384.960368) (xy 126.466106 -384.934674) (xy 126.428014 -384.879045) (xy 126.39686 -384.819253)
			(xy 126.373092 -384.756159) (xy 126.357053 -384.690673) (xy 126.348974 -384.623738) (xy 126.34897 -384.556316)
			(xy 126.357043 -384.48938) (xy 126.373076 -384.423892) (xy 126.396838 -384.360797) (xy 126.427986 -384.301002)
			(xy 126.466073 -384.245369) (xy 126.487936 -384.219704) (xy 126.493718 -384.212549) (xy 126.50024 -384.195366)
			(xy 126.500636 -384.186176) (xy 126.500636 -383.693924) (xy 126.500206 -383.684739) (xy 126.493705 -383.667555)
			(xy 126.487936 -383.660396) (xy 126.466035 -383.634761) (xy 126.427945 -383.579123) (xy 126.396794 -383.519323)
			(xy 126.373031 -383.456222) (xy 126.356996 -383.390729) (xy 126.348923 -383.323787) (xy 125.24683 -383.323787)
			(xy 125.247042 -383.324352) (xy 125.263013 -383.389736) (xy 125.271056 -383.456559) (xy 125.271054 -383.523865)
			(xy 125.263009 -383.590688) (xy 125.247035 -383.656071) (xy 125.223362 -383.719076) (xy 125.192328 -383.7788)
			(xy 125.15438 -383.834387) (xy 125.132592 -383.86004) (xy 125.126795 -383.867185) (xy 125.120281 -383.884376)
			(xy 125.119892 -383.893568) (xy 125.119892 -384.051556) (xy 125.119442 -384.061708) (xy 125.11166 -384.080461)
			(xy 125.097271 -384.094786) (xy 125.078484 -384.102486) (xy 125.06833 -384.102864) (xy 124.35205 -384.102864)
			(xy 124.341927 -384.102333) (xy 124.323208 -384.094622) (xy 124.30885 -384.080349) (xy 124.301028 -384.061676)
			(xy 124.300488 -384.051556) (xy 124.300488 -383.893568) (xy 124.300096 -383.884379) (xy 124.29357 -383.867194)
			(xy 124.287788 -383.86004) (xy 124.266015 -383.834376) (xy 124.228062 -383.778792) (xy 124.197025 -383.719071)
			(xy 124.17335 -383.656068) (xy 124.157374 -383.590686) (xy 124.149328 -383.523864) (xy 124.149326 -383.45656)
			(xy 124.15737 -383.389737) (xy 124.173342 -383.324355) (xy 124.197016 -383.261351) (xy 124.22805 -383.201629)
			(xy 124.266 -383.146043) (xy 124.287788 -383.120392) (xy 124.293569 -383.113236) (xy 124.300093 -383.096054)
			(xy 124.300488 -383.086864) (xy 124.300488 -382.593342) (xy 124.30006 -382.584157) (xy 124.293559 -382.566972)
			(xy 124.287788 -382.559814) (xy 124.265989 -382.534171) (xy 124.228037 -382.478584) (xy 124.197002 -382.41886)
			(xy 124.173327 -382.355854) (xy 124.157354 -382.29047) (xy 124.14931 -382.223646) (xy 120.87127 -382.223646)
			(xy 120.87127 -382.223704) (xy 120.863195 -382.290642) (xy 120.84716 -382.35613) (xy 120.823397 -382.419227)
			(xy 120.792247 -382.479023) (xy 120.75416 -382.534657) (xy 120.732296 -382.560322) (xy 120.726507 -382.567473)
			(xy 120.719988 -382.584659) (xy 120.719596 -382.59385) (xy 120.719596 -383.086356) (xy 120.720028 -383.095541)
			(xy 120.726527 -383.112725) (xy 120.732296 -383.119884) (xy 120.754176 -383.145536) (xy 120.792264 -383.201173)
			(xy 120.823415 -383.26097) (xy 120.847049 -383.323727) (xy 121.949155 -383.323727) (xy 121.949158 -383.256419)
			(xy 121.957206 -383.189594) (xy 121.973182 -383.12421) (xy 121.996859 -383.061204) (xy 122.027897 -383.001479)
			(xy 122.06585 -382.945892) (xy 122.08764 -382.92024) (xy 122.09345 -382.913104) (xy 122.099955 -382.895906)
			(xy 122.10034 -382.886712) (xy 122.10034 -382.728724) (xy 122.100742 -382.718566) (xy 122.108537 -382.699807)
			(xy 122.122941 -382.685481) (xy 122.141742 -382.677788) (xy 122.151902 -382.677416) (xy 122.868182 -382.677416)
			(xy 122.878305 -382.677941) (xy 122.897021 -382.685658) (xy 122.911377 -382.699932) (xy 122.919201 -382.718604)
			(xy 122.919744 -382.728724) (xy 122.919744 -382.886712) (xy 122.920161 -382.895898) (xy 122.926671 -382.913082)
			(xy 122.932444 -382.92024) (xy 122.954197 -382.945921) (xy 122.992148 -383.001503) (xy 123.023183 -383.061222)
			(xy 123.046859 -383.124223) (xy 123.062835 -383.189602) (xy 123.070882 -383.256422) (xy 123.070886 -383.323724)
			(xy 123.062845 -383.390545) (xy 123.046875 -383.455925) (xy 123.023206 -383.518928) (xy 122.992176 -383.57865)
			(xy 122.95423 -383.634236) (xy 122.932444 -383.659888) (xy 122.926621 -383.667014) (xy 122.920124 -383.684219)
			(xy 122.919744 -383.693416) (xy 122.919744 -384.186684) (xy 122.920174 -384.195869) (xy 122.926675 -384.213053)
			(xy 122.932444 -384.220212) (xy 122.954268 -384.245835) (xy 122.992217 -384.301425) (xy 123.023249 -384.361152)
			(xy 123.046921 -384.424161) (xy 123.062892 -384.489547) (xy 123.070933 -384.556373) (xy 123.07093 -384.623681)
			(xy 123.062882 -384.690507) (xy 123.046905 -384.755891) (xy 123.023227 -384.818897) (xy 122.992189 -384.878622)
			(xy 122.954235 -384.934208) (xy 122.932444 -384.95986) (xy 122.926633 -384.966994) (xy 122.920128 -384.984193)
			(xy 122.919744 -384.993388) (xy 122.919744 -385.151376) (xy 122.91926 -385.161523) (xy 122.91148 -385.180267)
			(xy 122.897103 -385.194589) (xy 122.878331 -385.202298) (xy 122.868182 -385.202684) (xy 122.151902 -385.202684)
			(xy 122.141778 -385.202172) (xy 122.123062 -385.19445) (xy 122.108706 -385.180171) (xy 122.100883 -385.161497)
			(xy 122.10034 -385.151376) (xy 122.10034 -384.993388) (xy 122.099927 -384.984201) (xy 122.093414 -384.967017)
			(xy 122.08764 -384.95986) (xy 122.065888 -384.934179) (xy 122.027938 -384.878596) (xy 121.996903 -384.818877)
			(xy 121.973228 -384.755876) (xy 121.957253 -384.690498) (xy 121.949206 -384.623678) (xy 121.949202 -384.556376)
			(xy 121.957243 -384.489556) (xy 121.973212 -384.424176) (xy 121.996881 -384.361173) (xy 122.02791 -384.30145)
			(xy 122.065855 -384.245864) (xy 122.08764 -384.220212) (xy 122.093461 -384.213085) (xy 122.09996 -384.19588)
			(xy 122.10034 -384.186684) (xy 122.10034 -383.693416) (xy 122.099913 -383.684231) (xy 122.09341 -383.667047)
			(xy 122.08764 -383.659888) (xy 122.065817 -383.634265) (xy 122.027869 -383.578674) (xy 121.996837 -383.518947)
			(xy 121.973166 -383.455939) (xy 121.957196 -383.390553) (xy 121.949155 -383.323727) (xy 120.847049 -383.323727)
			(xy 120.847178 -383.324069) (xy 120.863212 -383.38956) (xy 120.871287 -383.4565) (xy 120.871286 -383.523925)
			(xy 120.863208 -383.590864) (xy 120.847171 -383.656354) (xy 120.823405 -383.719452) (xy 120.792252 -383.779248)
			(xy 120.754161 -383.834883) (xy 120.732296 -383.860548) (xy 120.726496 -383.867691) (xy 120.719984 -383.884883)
			(xy 120.719596 -383.894076) (xy 120.719596 -384.051556) (xy 120.719148 -384.061676) (xy 120.711413 -384.080379)
			(xy 120.697106 -384.094695) (xy 120.678408 -384.102441) (xy 120.668288 -384.102864) (xy 119.952008 -384.102864)
			(xy 119.941882 -384.102477) (xy 119.923171 -384.094724) (xy 119.908855 -384.080399) (xy 119.901116 -384.061683)
			(xy 119.9007 -384.051556) (xy 119.9007 -383.894076) (xy 119.900302 -383.884888) (xy 119.89378 -383.867703)
			(xy 119.888 -383.860548) (xy 119.866152 -383.83487) (xy 119.828063 -383.779237) (xy 119.796911 -383.719443)
			(xy 119.773146 -383.656348) (xy 119.75711 -383.59086) (xy 119.749032 -383.523923) (xy 119.749031 -383.456501)
			(xy 119.757105 -383.389564) (xy 119.773139 -383.324075) (xy 119.796901 -383.260979) (xy 119.82805 -383.201184)
			(xy 119.866137 -383.145549) (xy 119.888 -383.119884) (xy 119.893786 -383.112731) (xy 119.900307 -383.095547)
			(xy 119.9007 -383.086356) (xy 119.9007 -382.59385) (xy 119.900266 -382.584665) (xy 119.893769 -382.567481)
			(xy 119.888 -382.560322) (xy 119.866126 -382.534665) (xy 119.828038 -382.479029) (xy 119.796888 -382.419232)
			(xy 119.773124 -382.356134) (xy 119.757089 -382.290644) (xy 119.749014 -382.223705) (xy 116.470967 -382.223705)
			(xy 116.46293 -382.290468) (xy 116.446957 -382.35585) (xy 116.423283 -382.418855) (xy 116.392248 -382.478577)
			(xy 116.354297 -382.534163) (xy 116.332508 -382.559814) (xy 116.326724 -382.566968) (xy 116.320202 -382.584152)
			(xy 116.319808 -382.593342) (xy 116.319808 -383.086864) (xy 116.320234 -383.09605) (xy 116.326736 -383.113234)
			(xy 116.332508 -383.120392) (xy 116.354313 -383.146031) (xy 116.392265 -383.201618) (xy 116.4233 -383.261343)
			(xy 116.446764 -383.323787) (xy 117.548835 -383.323787) (xy 117.548838 -383.256359) (xy 117.556918 -383.189418)
			(xy 117.572959 -383.123926) (xy 117.59673 -383.060827) (xy 117.627888 -383.00103) (xy 117.665984 -382.945396)
			(xy 117.687852 -382.919732) (xy 117.693666 -382.9126) (xy 117.700169 -382.895399) (xy 117.700552 -382.886204)
			(xy 117.700552 -382.728724) (xy 117.701103 -382.718623) (xy 117.708824 -382.699954) (xy 117.7231 -382.68566)
			(xy 117.741759 -382.677916) (xy 117.75186 -382.677416) (xy 118.46814 -382.677416) (xy 118.478253 -382.677853)
			(xy 118.496935 -382.685607) (xy 118.511229 -382.699918) (xy 118.51896 -382.71861) (xy 118.519448 -382.728724)
			(xy 118.519448 -382.886204) (xy 118.519868 -382.89539) (xy 118.526376 -382.912574) (xy 118.532148 -382.919732)
			(xy 118.553978 -382.945426) (xy 118.592072 -383.001055) (xy 118.623227 -383.060847) (xy 118.646995 -383.12394)
			(xy 118.663035 -383.189426) (xy 118.671114 -383.256362) (xy 118.671118 -383.323784) (xy 118.663045 -383.390721)
			(xy 118.647011 -383.456208) (xy 118.623249 -383.519304) (xy 118.592099 -383.579099) (xy 118.554012 -383.634732)
			(xy 118.532148 -383.660396) (xy 118.526364 -383.66755) (xy 118.519843 -383.684734) (xy 118.519448 -383.693924)
			(xy 118.519448 -384.186176) (xy 118.519881 -384.195361) (xy 118.52638 -384.212545) (xy 118.532148 -384.219704)
			(xy 118.554049 -384.245339) (xy 118.59214 -384.300977) (xy 118.623292 -384.360777) (xy 118.647057 -384.423878)
			(xy 118.663091 -384.489371) (xy 118.671165 -384.556313) (xy 118.671162 -384.623741) (xy 118.663082 -384.690682)
			(xy 118.647041 -384.756174) (xy 118.62327 -384.819273) (xy 118.592112 -384.87907) (xy 118.554016 -384.934704)
			(xy 118.532148 -384.960368) (xy 118.526334 -384.9675) (xy 118.519831 -384.984701) (xy 118.519448 -384.993896)
			(xy 118.519448 -385.151376) (xy 118.518897 -385.161477) (xy 118.511176 -385.180146) (xy 118.4969 -385.19444)
			(xy 118.478241 -385.202184) (xy 118.46814 -385.202684) (xy 117.75186 -385.202684) (xy 117.741747 -385.202247)
			(xy 117.723065 -385.194493) (xy 117.708771 -385.180182) (xy 117.70104 -385.16149) (xy 117.700552 -385.151376)
			(xy 117.700552 -384.993896) (xy 117.700132 -384.98471) (xy 117.693624 -384.967526) (xy 117.687852 -384.960368)
			(xy 117.666022 -384.934674) (xy 117.627928 -384.879045) (xy 117.596773 -384.819253) (xy 117.573005 -384.75616)
			(xy 117.556965 -384.690674) (xy 117.548886 -384.623738) (xy 117.548882 -384.556316) (xy 117.556955 -384.489379)
			(xy 117.572989 -384.423892) (xy 117.596751 -384.360796) (xy 117.627901 -384.301001) (xy 117.665988 -384.245368)
			(xy 117.687852 -384.219704) (xy 117.693636 -384.21255) (xy 117.700157 -384.195366) (xy 117.700552 -384.186176)
			(xy 117.700552 -383.693924) (xy 117.700119 -383.684739) (xy 117.69362 -383.667555) (xy 117.687852 -383.660396)
			(xy 117.665951 -383.634761) (xy 117.62786 -383.579123) (xy 117.596708 -383.519323) (xy 117.572943 -383.456222)
			(xy 117.556909 -383.390729) (xy 117.548835 -383.323787) (xy 116.446764 -383.323787) (xy 116.446975 -383.324349)
			(xy 116.462948 -383.389733) (xy 116.470992 -383.456558) (xy 116.47099 -383.523866) (xy 116.462944 -383.59069)
			(xy 116.446967 -383.656074) (xy 116.423291 -383.719079) (xy 116.392252 -383.778803) (xy 116.354298 -383.834389)
			(xy 116.332508 -383.86004) (xy 116.326713 -383.867186) (xy 116.320197 -383.884376) (xy 116.319808 -383.893568)
			(xy 116.319808 -384.051556) (xy 116.319342 -384.061706) (xy 116.311563 -384.080456) (xy 116.297179 -384.094781)
			(xy 116.278398 -384.102483) (xy 116.268246 -384.102864) (xy 115.551966 -384.102864) (xy 115.541838 -384.102401)
			(xy 115.523116 -384.094663) (xy 115.508761 -384.08037) (xy 115.500943 -384.061682) (xy 115.500404 -384.051556)
			(xy 115.500404 -383.893568) (xy 115.500009 -383.884379) (xy 115.493485 -383.867195) (xy 115.487704 -383.86004)
			(xy 115.465933 -383.834374) (xy 115.427986 -383.778789) (xy 115.396954 -383.719067) (xy 115.373282 -383.656064)
			(xy 115.357309 -383.590684) (xy 115.349264 -383.523864) (xy 115.349262 -383.45656) (xy 115.357305 -383.38974)
			(xy 115.373275 -383.324359) (xy 115.396944 -383.261355) (xy 115.427974 -383.201632) (xy 115.465918 -383.146045)
			(xy 115.487704 -383.120392) (xy 115.493487 -383.113237) (xy 115.50001 -383.096054) (xy 115.500404 -383.086864)
			(xy 115.500404 -382.593342) (xy 115.499973 -382.584157) (xy 115.493474 -382.566973) (xy 115.487704 -382.559814)
			(xy 115.465908 -382.534169) (xy 115.427961 -382.478581) (xy 115.39693 -382.418856) (xy 115.37326 -382.355851)
			(xy 115.357288 -382.290468) (xy 115.349246 -382.223645) (xy 90.070711 -382.223645) (xy 90.062667 -382.290467)
			(xy 90.046695 -382.355848) (xy 90.023023 -382.418852) (xy 89.991991 -382.478576) (xy 89.954043 -382.534162)
			(xy 89.932256 -382.559814) (xy 89.926465 -382.566963) (xy 89.919948 -382.584151) (xy 89.919556 -382.593342)
			(xy 89.919556 -383.086864) (xy 89.919994 -383.096048) (xy 89.926489 -383.113232) (xy 89.932256 -383.120392)
			(xy 89.95406 -383.146031) (xy 89.992008 -383.201619) (xy 90.023041 -383.261345) (xy 90.046478 -383.323726)
			(xy 91.149124 -383.323726) (xy 91.149128 -383.256419) (xy 91.157175 -383.189595) (xy 91.17315 -383.124211)
			(xy 91.196825 -383.061205) (xy 91.227861 -383.001481) (xy 91.265811 -382.945893) (xy 91.2876 -382.92024)
			(xy 91.293405 -382.9131) (xy 91.299914 -382.895906) (xy 91.3003 -382.886712) (xy 91.3003 -382.728724)
			(xy 91.300741 -382.718571) (xy 91.308529 -382.699819) (xy 91.32292 -382.685495) (xy 91.341708 -382.677795)
			(xy 91.351862 -382.677416) (xy 92.068142 -382.677416) (xy 92.078268 -382.677891) (xy 92.096986 -382.685629)
			(xy 92.11134 -382.699918) (xy 92.119162 -382.7186) (xy 92.119704 -382.728724) (xy 92.119704 -382.886712)
			(xy 92.120108 -382.8959) (xy 92.126626 -382.913084) (xy 92.132404 -382.92024) (xy 92.154155 -382.945922)
			(xy 92.192102 -383.001505) (xy 92.223135 -383.061225) (xy 92.246808 -383.124225) (xy 92.262782 -383.189604)
			(xy 92.270828 -383.256422) (xy 92.270831 -383.323724) (xy 92.262791 -383.390543) (xy 92.246824 -383.455923)
			(xy 92.223157 -383.518926) (xy 92.19213 -383.578648) (xy 92.154188 -383.634235) (xy 92.132404 -383.659888)
			(xy 92.126588 -383.66702) (xy 92.120085 -383.68422) (xy 92.119704 -383.693416) (xy 92.119704 -384.186684)
			(xy 92.120121 -384.19587) (xy 92.12663 -384.213055) (xy 92.132404 -384.220212) (xy 92.154226 -384.245836)
			(xy 92.192171 -384.301427) (xy 92.2232 -384.361155) (xy 92.246869 -384.424163) (xy 92.262838 -384.489548)
			(xy 92.270879 -384.556374) (xy 92.270875 -384.623681) (xy 92.262828 -384.690505) (xy 92.246853 -384.755889)
			(xy 92.223178 -384.818894) (xy 92.192143 -384.878619) (xy 92.154193 -384.934207) (xy 92.132404 -384.95986)
			(xy 92.1266 -384.967) (xy 92.12009 -384.984194) (xy 92.119704 -384.993388) (xy 92.119704 -385.151376)
			(xy 92.119259 -385.161528) (xy 92.111472 -385.180279) (xy 92.097082 -385.194603) (xy 92.078296 -385.202305)
			(xy 92.068142 -385.202684) (xy 91.351862 -385.202684) (xy 91.341736 -385.202205) (xy 91.323018 -385.194469)
			(xy 91.308664 -385.180181) (xy 91.300842 -385.1615) (xy 91.3003 -385.151376) (xy 91.3003 -384.993388)
			(xy 91.299895 -384.9842) (xy 91.293378 -384.967016) (xy 91.2876 -384.95986) (xy 91.265849 -384.934178)
			(xy 91.227901 -384.878595) (xy 91.196869 -384.818875) (xy 91.173196 -384.755875) (xy 91.157221 -384.690497)
			(xy 91.149175 -384.623678) (xy 91.149172 -384.556376) (xy 91.157212 -384.489557) (xy 91.17318 -384.424177)
			(xy 91.196847 -384.361174) (xy 91.227874 -384.301451) (xy 91.265816 -384.245865) (xy 91.2876 -384.220212)
			(xy 91.293416 -384.213081) (xy 91.299919 -384.19588) (xy 91.3003 -384.186684) (xy 91.3003 -383.693416)
			(xy 91.299882 -383.68423) (xy 91.293374 -383.667045) (xy 91.2876 -383.659888) (xy 91.265778 -383.634264)
			(xy 91.227833 -383.578673) (xy 91.196803 -383.518945) (xy 91.173134 -383.455937) (xy 91.157165 -383.390552)
			(xy 91.149124 -383.323726) (xy 90.046478 -383.323726) (xy 90.046713 -383.324351) (xy 90.062685 -383.389735)
			(xy 90.070728 -383.456559) (xy 90.070727 -383.523865) (xy 90.062681 -383.590689) (xy 90.046706 -383.656072)
			(xy 90.023031 -383.719077) (xy 89.991996 -383.778801) (xy 89.954045 -383.834388) (xy 89.932256 -383.86004)
			(xy 89.926454 -383.867181) (xy 89.919944 -383.884375) (xy 89.919556 -383.893568) (xy 89.919556 -384.051556)
			(xy 89.919043 -384.0617) (xy 89.911273 -384.080441) (xy 89.896905 -384.094764) (xy 89.87814 -384.102475)
			(xy 89.867994 -384.102864) (xy 89.151714 -384.102864) (xy 89.141589 -384.102362) (xy 89.122869 -384.09464)
			(xy 89.108512 -384.080358) (xy 89.100692 -384.061679) (xy 89.100152 -384.051556) (xy 89.100152 -383.893568)
			(xy 89.099745 -383.884381) (xy 89.093228 -383.867197) (xy 89.087452 -383.86004) (xy 89.06568 -383.834375)
			(xy 89.02773 -383.778791) (xy 88.996695 -383.719069) (xy 88.973021 -383.656066) (xy 88.957046 -383.590685)
			(xy 88.949001 -383.523864) (xy 88.948999 -383.45656) (xy 88.957042 -383.389738) (xy 88.973014 -383.324357)
			(xy 88.996685 -383.261353) (xy 89.027717 -383.20163) (xy 89.065665 -383.146044) (xy 89.087452 -383.120392)
			(xy 89.093241 -383.113242) (xy 89.099759 -383.096055) (xy 89.100152 -383.086864) (xy 89.100152 -382.593342)
			(xy 89.09971 -382.584158) (xy 89.093217 -382.566975) (xy 89.087452 -382.559814) (xy 89.065654 -382.53417)
			(xy 89.027704 -382.478583) (xy 88.996671 -382.418858) (xy 88.972998 -382.355853) (xy 88.957025 -382.290469)
			(xy 88.948982 -382.223646) (xy 85.670943 -382.223646) (xy 85.670943 -382.223704) (xy 85.662867 -382.290643)
			(xy 85.646832 -382.356132) (xy 85.623067 -382.419228) (xy 85.591915 -382.479024) (xy 85.553825 -382.534657)
			(xy 85.53196 -382.560322) (xy 85.526167 -382.567469) (xy 85.519651 -382.584658) (xy 85.51926 -382.59385)
			(xy 85.51926 -383.086356) (xy 85.5197 -383.09554) (xy 85.526194 -383.112724) (xy 85.53196 -383.119884)
			(xy 85.553841 -383.145536) (xy 85.591932 -383.201171) (xy 85.623084 -383.260969) (xy 85.646743 -383.323786)
			(xy 86.748805 -383.323786) (xy 86.748808 -383.25636) (xy 86.756888 -383.189419) (xy 86.772927 -383.123927)
			(xy 86.796696 -383.060829) (xy 86.827852 -383.001032) (xy 86.865945 -382.945397) (xy 86.887812 -382.919732)
			(xy 86.893621 -382.912596) (xy 86.900128 -382.895398) (xy 86.900512 -382.886204) (xy 86.900512 -382.728724)
			(xy 86.900936 -382.718602) (xy 86.908678 -382.699896) (xy 86.922993 -382.685581) (xy 86.941698 -382.677837)
			(xy 86.95182 -382.677416) (xy 87.6681 -382.677416) (xy 87.678224 -382.677816) (xy 87.696931 -382.685568)
			(xy 87.711246 -382.699889) (xy 87.718988 -382.718599) (xy 87.719408 -382.728724) (xy 87.719408 -382.886204)
			(xy 87.719815 -382.895392) (xy 87.726331 -382.912576) (xy 87.732108 -382.919732) (xy 87.753936 -382.945427)
			(xy 87.792026 -383.001057) (xy 87.823177 -383.060849) (xy 87.846943 -383.123942) (xy 87.862981 -383.189428)
			(xy 87.87106 -383.256363) (xy 87.871063 -383.323783) (xy 87.862991 -383.390719) (xy 87.846959 -383.456206)
			(xy 87.8232 -383.519301) (xy 87.792053 -383.579096) (xy 87.75397 -383.634731) (xy 87.732108 -383.660396)
			(xy 87.726332 -383.667556) (xy 87.719805 -383.684735) (xy 87.719408 -383.693924) (xy 87.719408 -384.186176)
			(xy 87.719828 -384.195362) (xy 87.726335 -384.212547) (xy 87.732108 -384.219704) (xy 87.754007 -384.24534)
			(xy 87.792094 -384.300979) (xy 87.823243 -384.360779) (xy 87.847005 -384.42388) (xy 87.863037 -384.489373)
			(xy 87.87111 -384.556314) (xy 87.871107 -384.62374) (xy 87.863028 -384.690681) (xy 87.846989 -384.756172)
			(xy 87.823221 -384.81927) (xy 87.792066 -384.879067) (xy 87.753974 -384.934703) (xy 87.732108 -384.960368)
			(xy 87.726301 -384.967506) (xy 87.719792 -384.984702) (xy 87.719408 -384.993896) (xy 87.719408 -385.151376)
			(xy 87.718965 -385.161496) (xy 87.711226 -385.180198) (xy 87.696918 -385.194512) (xy 87.67822 -385.20226)
			(xy 87.6681 -385.202684) (xy 86.95182 -385.202684) (xy 86.941697 -385.202267) (xy 86.922991 -385.194523)
			(xy 86.908675 -385.180206) (xy 86.900932 -385.161499) (xy 86.900512 -385.151376) (xy 86.900512 -384.993896)
			(xy 86.900101 -384.984709) (xy 86.893587 -384.967525) (xy 86.887812 -384.960368) (xy 86.865983 -384.934674)
			(xy 86.827892 -384.879044) (xy 86.796739 -384.819252) (xy 86.772973 -384.756158) (xy 86.756934 -384.690673)
			(xy 86.748855 -384.623738) (xy 86.748852 -384.556316) (xy 86.756925 -384.48938) (xy 86.772957 -384.423893)
			(xy 86.796717 -384.360798) (xy 86.827865 -384.301003) (xy 86.86595 -384.245369) (xy 86.887812 -384.219704)
			(xy 86.893591 -384.212546) (xy 86.900116 -384.195365) (xy 86.900512 -384.186176) (xy 86.900512 -383.693924)
			(xy 86.900088 -383.684738) (xy 86.893583 -383.667554) (xy 86.887812 -383.660396) (xy 86.865912 -383.63476)
			(xy 86.827824 -383.579122) (xy 86.796674 -383.519322) (xy 86.772911 -383.456221) (xy 86.756878 -383.390728)
			(xy 86.748805 -383.323786) (xy 85.646743 -383.323786) (xy 85.646849 -383.324068) (xy 85.662885 -383.389559)
			(xy 85.67096 -383.456499) (xy 85.670959 -383.523925) (xy 85.662881 -383.590865) (xy 85.646842 -383.656355)
			(xy 85.623074 -383.719453) (xy 85.59192 -383.77925) (xy 85.553826 -383.834883) (xy 85.53196 -383.860548)
			(xy 85.526156 -383.867687) (xy 85.519647 -383.884883) (xy 85.51926 -383.894076) (xy 85.51926 -384.051556)
			(xy 85.518847 -384.061681) (xy 85.511106 -384.080391) (xy 85.496787 -384.094708) (xy 85.478077 -384.102448)
			(xy 85.467952 -384.102864) (xy 84.751672 -384.102864) (xy 84.741543 -384.102506) (xy 84.722832 -384.094742)
			(xy 84.708517 -384.080407) (xy 84.70078 -384.061685) (xy 84.700364 -384.051556) (xy 84.700364 -383.894076)
			(xy 84.699951 -383.884889) (xy 84.693438 -383.867706) (xy 84.687664 -383.860548) (xy 84.665817 -383.834869)
			(xy 84.62773 -383.779236) (xy 84.596581 -383.719441) (xy 84.572817 -383.656346) (xy 84.556782 -383.590859)
			(xy 84.548705 -383.523923) (xy 84.548704 -383.456501) (xy 84.556778 -383.389565) (xy 84.57281 -383.324077)
			(xy 84.596571 -383.260981) (xy 84.627718 -383.201185) (xy 84.665802 -383.14555) (xy 84.687664 -383.119884)
			(xy 84.693458 -383.112737) (xy 84.699972 -383.095548) (xy 84.700364 -383.086356) (xy 84.700364 -382.59385)
			(xy 84.699916 -382.584667) (xy 84.693427 -382.567483) (xy 84.687664 -382.560322) (xy 84.665791 -382.534664)
			(xy 84.627705 -382.479028) (xy 84.596557 -382.41923) (xy 84.572795 -382.356132) (xy 84.556761 -382.290643)
			(xy 84.548687 -382.223704) (xy 81.271152 -382.223704) (xy 81.263076 -382.290642) (xy 81.247041 -382.356131)
			(xy 81.223277 -382.419228) (xy 81.192126 -382.479023) (xy 81.154036 -382.534657) (xy 81.132172 -382.560322)
			(xy 81.12638 -382.56747) (xy 81.119863 -382.584659) (xy 81.119472 -382.59385) (xy 81.119472 -383.086356)
			(xy 81.11991 -383.09554) (xy 81.126405 -383.112724) (xy 81.132172 -383.119884) (xy 81.154053 -383.145536)
			(xy 81.192143 -383.201172) (xy 81.223294 -383.260969) (xy 81.246931 -383.323727) (xy 82.349036 -383.323727)
			(xy 82.34904 -383.256419) (xy 82.357087 -383.189595) (xy 82.373063 -383.124211) (xy 82.396739 -383.061205)
			(xy 82.427775 -383.00148) (xy 82.465727 -382.945892) (xy 82.487516 -382.92024) (xy 82.493322 -382.913102)
			(xy 82.499831 -382.895906) (xy 82.500216 -382.886712) (xy 82.500216 -382.728724) (xy 82.500636 -382.718601)
			(xy 82.508379 -382.699895) (xy 82.522695 -382.685579) (xy 82.541401 -382.677836) (xy 82.551524 -382.677416)
			(xy 83.268058 -382.677416) (xy 83.278179 -382.67796) (xy 83.296895 -382.68567) (xy 83.311252 -382.699938)
			(xy 83.319076 -382.718606) (xy 83.31962 -382.728724) (xy 83.31962 -382.886712) (xy 83.32002 -382.8959)
			(xy 83.32654 -382.913085) (xy 83.33232 -382.92024) (xy 83.354074 -382.945921) (xy 83.392026 -383.001502)
			(xy 83.423063 -383.061221) (xy 83.44674 -383.124222) (xy 83.462717 -383.189601) (xy 83.470764 -383.256421)
			(xy 83.470767 -383.323724) (xy 83.462726 -383.390545) (xy 83.446756 -383.455926) (xy 83.423085 -383.518929)
			(xy 83.392054 -383.578651) (xy 83.354107 -383.634236) (xy 83.33232 -383.659888) (xy 83.326506 -383.667021)
			(xy 83.320001 -383.684221) (xy 83.31962 -383.693416) (xy 83.31962 -384.186684) (xy 83.320033 -384.195871)
			(xy 83.326544 -384.213056) (xy 83.33232 -384.220212) (xy 83.354144 -384.245835) (xy 83.392095 -384.301424)
			(xy 83.423129 -384.361152) (xy 83.446801 -384.42416) (xy 83.462773 -384.489546) (xy 83.470815 -384.556373)
			(xy 83.470812 -384.623681) (xy 83.462763 -384.690507) (xy 83.446785 -384.755892) (xy 83.423107 -384.818898)
			(xy 83.392067 -384.878622) (xy 83.354111 -384.934208) (xy 83.33232 -384.95986) (xy 83.326518 -384.967001)
			(xy 83.320006 -384.984195) (xy 83.31962 -384.993388) (xy 83.31962 -385.151376) (xy 83.319165 -385.161494)
			(xy 83.311428 -385.180194) (xy 83.297124 -385.194508) (xy 83.27843 -385.202258) (xy 83.268312 -385.202684)
			(xy 82.551778 -385.202684) (xy 82.541653 -385.202192) (xy 82.522936 -385.194462) (xy 82.508581 -385.180178)
			(xy 82.500758 -385.161499) (xy 82.500216 -385.151376) (xy 82.500216 -384.993388) (xy 82.499808 -384.984201)
			(xy 82.493293 -384.967016) (xy 82.487516 -384.95986) (xy 82.465765 -384.934178) (xy 82.427816 -384.878595)
			(xy 82.396783 -384.818876) (xy 82.373109 -384.755875) (xy 82.357134 -384.690497) (xy 82.349088 -384.623678)
			(xy 82.349084 -384.556376) (xy 82.357125 -384.489556) (xy 82.373093 -384.424177) (xy 82.396761 -384.361174)
			(xy 82.427788 -384.301451) (xy 82.465731 -384.245865) (xy 82.487516 -384.220212) (xy 82.493334 -384.213082)
			(xy 82.499835 -384.19588) (xy 82.500216 -384.186684) (xy 82.500216 -383.693416) (xy 82.499794 -383.68423)
			(xy 82.493288 -383.667046) (xy 82.487516 -383.659888) (xy 82.465694 -383.634265) (xy 82.427747 -383.578674)
			(xy 82.396717 -383.518946) (xy 82.373047 -383.455938) (xy 82.357077 -383.390552) (xy 82.349036 -383.323727)
			(xy 81.246931 -383.323727) (xy 81.247059 -383.324068) (xy 81.263094 -383.389559) (xy 81.271169 -383.456499)
			(xy 81.271168 -383.523925) (xy 81.26309 -383.590865) (xy 81.247052 -383.656355) (xy 81.223285 -383.719453)
			(xy 81.19213 -383.779249) (xy 81.154038 -383.834883) (xy 81.132172 -383.860548) (xy 81.126369 -383.867688)
			(xy 81.119859 -383.884883) (xy 81.119472 -383.894076) (xy 81.119472 -384.051556) (xy 81.119047 -384.061679)
			(xy 81.111308 -384.080387) (xy 81.096994 -384.094704) (xy 81.078287 -384.102446) (xy 81.068164 -384.102864)
			(xy 80.351884 -384.102864) (xy 80.341756 -384.102496) (xy 80.323045 -384.094736) (xy 80.30873 -384.080405)
			(xy 80.300992 -384.061685) (xy 80.300576 -384.051556) (xy 80.300576 -383.894076) (xy 80.300183 -383.884887)
			(xy 80.293658 -383.867703) (xy 80.287876 -383.860548) (xy 80.266029 -383.834869) (xy 80.227941 -383.779236)
			(xy 80.196791 -383.719442) (xy 80.173027 -383.656347) (xy 80.156991 -383.590859) (xy 80.148914 -383.523923)
			(xy 80.148913 -383.456501) (xy 80.156987 -383.389564) (xy 80.17302 -383.324076) (xy 80.196781 -383.26098)
			(xy 80.227929 -383.201184) (xy 80.266014 -383.14555) (xy 80.287876 -383.119884) (xy 80.293659 -383.112729)
			(xy 80.300183 -383.095546) (xy 80.300576 -383.086356) (xy 80.300576 -382.59385) (xy 80.300147 -382.584665)
			(xy 80.293647 -382.56748) (xy 80.287876 -382.560322) (xy 80.266003 -382.534664) (xy 80.227916 -382.479028)
			(xy 80.196767 -382.419231) (xy 80.173005 -382.356133) (xy 80.156971 -382.290643) (xy 80.148896 -382.223704)
			(xy 76.870825 -382.223704) (xy 76.862789 -382.290466) (xy 76.846818 -382.355847) (xy 76.823147 -382.418851)
			(xy 76.792117 -382.478575) (xy 76.75417 -382.534162) (xy 76.732384 -382.559814) (xy 76.726597 -382.566966)
			(xy 76.720077 -382.584151) (xy 76.719684 -382.593342) (xy 76.719684 -383.086864) (xy 76.720115 -383.096049)
			(xy 76.726615 -383.113233) (xy 76.732384 -383.120392) (xy 76.754187 -383.146031) (xy 76.792134 -383.20162)
			(xy 76.823165 -383.261346) (xy 76.846624 -383.323787) (xy 77.948717 -383.323787) (xy 77.94872 -383.256359)
			(xy 77.9568 -383.189418) (xy 77.97284 -383.123927) (xy 77.99661 -383.060828) (xy 78.027766 -383.001031)
			(xy 78.065861 -382.945397) (xy 78.087728 -382.919732) (xy 78.09354 -382.912598) (xy 78.100045 -382.895399)
			(xy 78.100428 -382.886204) (xy 78.100428 -382.728724) (xy 78.100836 -382.7186) (xy 78.108582 -382.699891)
			(xy 78.122901 -382.685575) (xy 78.141611 -382.677834) (xy 78.151736 -382.677416) (xy 78.868016 -382.677416)
			(xy 78.878142 -382.677803) (xy 78.896849 -382.685559) (xy 78.911163 -382.699885) (xy 78.918905 -382.718598)
			(xy 78.919324 -382.728724) (xy 78.919324 -382.886204) (xy 78.919727 -382.895392) (xy 78.926245 -382.912577)
			(xy 78.932024 -382.919732) (xy 78.953852 -382.945427) (xy 78.99194 -383.001058) (xy 79.023091 -383.06085)
			(xy 79.046856 -383.123943) (xy 79.062893 -383.189428) (xy 79.070972 -383.256363) (xy 79.070975 -383.323783)
			(xy 79.062903 -383.390719) (xy 79.046872 -383.456205) (xy 79.023113 -383.519301) (xy 78.991968 -383.579096)
			(xy 78.953885 -383.63473) (xy 78.932024 -383.660396) (xy 78.926249 -383.667557) (xy 78.919721 -383.684735)
			(xy 78.919324 -383.693924) (xy 78.919324 -384.186176) (xy 78.91974 -384.195363) (xy 78.926249 -384.212547)
			(xy 78.932024 -384.219704) (xy 78.953922 -384.24534) (xy 78.992009 -384.30098) (xy 79.023156 -384.36078)
			(xy 79.046917 -384.423881) (xy 79.06295 -384.489373) (xy 79.071022 -384.556314) (xy 79.071019 -384.62374)
			(xy 79.06294 -384.69068) (xy 79.046901 -384.756171) (xy 79.023134 -384.819269) (xy 78.991981 -384.879067)
			(xy 78.953889 -384.934702) (xy 78.932024 -384.960368) (xy 78.926219 -384.967507) (xy 78.919709 -384.984702)
			(xy 78.919324 -384.993896) (xy 78.919324 -385.151376) (xy 78.918865 -385.161494) (xy 78.911129 -385.180193)
			(xy 78.896826 -385.194507) (xy 78.878134 -385.202257) (xy 78.868016 -385.202684) (xy 78.151736 -385.202684)
			(xy 78.141614 -385.202254) (xy 78.122908 -385.194515) (xy 78.108592 -385.180202) (xy 78.100848 -385.161498)
			(xy 78.100428 -385.151376) (xy 78.100428 -384.993896) (xy 78.100014 -384.984709) (xy 78.093502 -384.967525)
			(xy 78.087728 -384.960368) (xy 78.065898 -384.934674) (xy 78.027807 -384.879044) (xy 77.996653 -384.819252)
			(xy 77.972886 -384.756159) (xy 77.956847 -384.690673) (xy 77.948768 -384.623738) (xy 77.948764 -384.556316)
			(xy 77.956837 -384.48938) (xy 77.972869 -384.423893) (xy 77.996631 -384.360797) (xy 78.027779 -384.301002)
			(xy 78.065865 -384.245369) (xy 78.087728 -384.219704) (xy 78.093509 -384.212548) (xy 78.100032 -384.195366)
			(xy 78.100428 -384.186176) (xy 78.100428 -383.693924) (xy 78.1 -383.684739) (xy 78.093498 -383.667555)
			(xy 78.087728 -383.660396) (xy 78.065828 -383.63476) (xy 78.027738 -383.579122) (xy 77.996587 -383.519322)
			(xy 77.972824 -383.456221) (xy 77.95679 -383.390728) (xy 77.948717 -383.323787) (xy 76.846624 -383.323787)
			(xy 76.846836 -383.324352) (xy 76.862807 -383.389735) (xy 76.870849 -383.456559) (xy 76.870848 -383.523865)
			(xy 76.862803 -383.590688) (xy 76.846829 -383.656071) (xy 76.823155 -383.719076) (xy 76.792121 -383.7788)
			(xy 76.754172 -383.834388) (xy 76.732384 -383.86004) (xy 76.726586 -383.867184) (xy 76.720073 -383.884376)
			(xy 76.719684 -383.893568) (xy 76.719684 -384.051556) (xy 76.719242 -384.061709) (xy 76.711458 -384.080464)
			(xy 76.697067 -384.094789) (xy 76.678277 -384.102488) (xy 76.668122 -384.102864) (xy 75.951842 -384.102864)
			(xy 75.941718 -384.102339) (xy 75.922999 -384.094626) (xy 75.908642 -384.080351) (xy 75.90082 -384.061677)
			(xy 75.90028 -384.051556) (xy 75.90028 -383.893568) (xy 75.89989 -383.884379) (xy 75.893363 -383.867194)
			(xy 75.88758 -383.86004) (xy 75.865807 -383.834375) (xy 75.827855 -383.778792) (xy 75.796819 -383.71907)
			(xy 75.773143 -383.656067) (xy 75.757168 -383.590686) (xy 75.749122 -383.523864) (xy 75.74912 -383.45656)
			(xy 75.757164 -383.389738) (xy 75.773136 -383.324356) (xy 75.796809 -383.261352) (xy 75.827842 -383.201629)
			(xy 75.865792 -383.146044) (xy 75.88758 -383.120392) (xy 75.89336 -383.113235) (xy 75.899885 -383.096054)
			(xy 75.90028 -383.086864) (xy 75.90028 -382.593342) (xy 75.899854 -382.584156) (xy 75.893352 -382.566972)
			(xy 75.88758 -382.559814) (xy 75.865781 -382.53417) (xy 75.82783 -382.478584) (xy 75.796795 -382.418859)
			(xy 75.773121 -382.355854) (xy 75.757147 -382.29047) (xy 75.749104 -382.223646) (xy 72.471064 -382.223646)
			(xy 72.471064 -382.223704) (xy 72.462989 -382.290642) (xy 72.446954 -382.356131) (xy 72.42319 -382.419227)
			(xy 72.39204 -382.479023) (xy 72.353952 -382.534657) (xy 72.332088 -382.560322) (xy 72.326298 -382.567472)
			(xy 72.31978 -382.584659) (xy 72.319388 -382.59385) (xy 72.319388 -383.086356) (xy 72.319822 -383.095541)
			(xy 72.326319 -383.112725) (xy 72.332088 -383.119884) (xy 72.353968 -383.145536) (xy 72.392057 -383.201172)
			(xy 72.423208 -383.26097) (xy 72.446843 -383.323727) (xy 73.548949 -383.323727) (xy 73.548952 -383.256419)
			(xy 73.556999 -383.189594) (xy 73.572976 -383.12421) (xy 73.596652 -383.061204) (xy 73.62769 -383.001479)
			(xy 73.665642 -382.945892) (xy 73.687432 -382.92024) (xy 73.693241 -382.913103) (xy 73.699747 -382.895906)
			(xy 73.700132 -382.886712) (xy 73.700132 -382.728724) (xy 73.700542 -382.718567) (xy 73.708335 -382.699809)
			(xy 73.722736 -382.685484) (xy 73.741535 -382.677789) (xy 73.751694 -382.677416) (xy 74.467974 -382.677416)
			(xy 74.478096 -382.677947) (xy 74.496812 -382.685662) (xy 74.511169 -382.699934) (xy 74.518993 -382.718605)
			(xy 74.519536 -382.728724) (xy 74.519536 -382.886712) (xy 74.519955 -382.895898) (xy 74.526464 -382.913082)
			(xy 74.532236 -382.92024) (xy 74.553989 -382.945921) (xy 74.591941 -383.001503) (xy 74.622977 -383.061222)
			(xy 74.646653 -383.124223) (xy 74.662629 -383.189602) (xy 74.670676 -383.256422) (xy 74.670679 -383.323724)
			(xy 74.662639 -383.390545) (xy 74.646669 -383.455925) (xy 74.622999 -383.518928) (xy 74.591968 -383.578651)
			(xy 74.554022 -383.634236) (xy 74.532236 -383.659888) (xy 74.526412 -383.667013) (xy 74.519915 -383.684219)
			(xy 74.519536 -383.693416) (xy 74.519536 -384.186684) (xy 74.519968 -384.195869) (xy 74.526468 -384.213052)
			(xy 74.532236 -384.220212) (xy 74.55406 -384.245835) (xy 74.592009 -384.301425) (xy 74.623043 -384.361152)
			(xy 74.646714 -384.424161) (xy 74.662686 -384.489547) (xy 74.670727 -384.556373) (xy 74.670724 -384.623681)
			(xy 74.662676 -384.690507) (xy 74.646698 -384.755891) (xy 74.623021 -384.818897) (xy 74.591982 -384.878622)
			(xy 74.554027 -384.934208) (xy 74.532236 -384.95986) (xy 74.526424 -384.966994) (xy 74.51992 -384.984193)
			(xy 74.519536 -384.993388) (xy 74.519536 -385.151376) (xy 74.51906 -385.161524) (xy 74.511279 -385.180269)
			(xy 74.496899 -385.194592) (xy 74.478124 -385.202299) (xy 74.467974 -385.202684) (xy 73.751694 -385.202684)
			(xy 73.74157 -385.202179) (xy 73.722853 -385.194454) (xy 73.708498 -385.180173) (xy 73.700675 -385.161497)
			(xy 73.700132 -385.151376) (xy 73.700132 -384.993388) (xy 73.699721 -384.984201) (xy 73.693207 -384.967017)
			(xy 73.687432 -384.95986) (xy 73.66568 -384.934178) (xy 73.627731 -384.878596) (xy 73.596696 -384.818877)
			(xy 73.573022 -384.755876) (xy 73.557047 -384.690497) (xy 73.549 -384.623678) (xy 73.548996 -384.556376)
			(xy 73.557037 -384.489556) (xy 73.573006 -384.424176) (xy 73.596674 -384.361173) (xy 73.627703 -384.30145)
			(xy 73.665647 -384.245864) (xy 73.687432 -384.220212) (xy 73.693253 -384.213084) (xy 73.699752 -384.19588)
			(xy 73.700132 -384.186684) (xy 73.700132 -383.693416) (xy 73.699707 -383.684231) (xy 73.693203 -383.667046)
			(xy 73.687432 -383.659888) (xy 73.665609 -383.634265) (xy 73.627662 -383.578674) (xy 73.59663 -383.518946)
			(xy 73.57296 -383.455938) (xy 73.55699 -383.390553) (xy 73.548949 -383.323727) (xy 72.446843 -383.323727)
			(xy 72.446972 -383.324069) (xy 72.463006 -383.38956) (xy 72.471081 -383.456499) (xy 72.47108 -383.523925)
			(xy 72.463002 -383.590864) (xy 72.446964 -383.656354) (xy 72.423198 -383.719452) (xy 72.392045 -383.779248)
			(xy 72.353953 -383.834883) (xy 72.332088 -383.860548) (xy 72.326287 -383.86769) (xy 72.319775 -383.884883)
			(xy 72.319388 -383.894076) (xy 72.319388 -384.051556) (xy 72.318948 -384.061677) (xy 72.311212 -384.080382)
			(xy 72.296902 -384.094698) (xy 72.278201 -384.102443) (xy 72.26808 -384.102864) (xy 71.5518 -384.102864)
			(xy 71.541673 -384.102483) (xy 71.522963 -384.094728) (xy 71.508647 -384.0804) (xy 71.500908 -384.061683)
			(xy 71.500492 -384.051556) (xy 71.500492 -383.894076) (xy 71.500095 -383.884887) (xy 71.493572 -383.867703)
			(xy 71.487792 -383.860548) (xy 71.465944 -383.83487) (xy 71.427855 -383.779237) (xy 71.396704 -383.719442)
			(xy 71.37294 -383.656347) (xy 71.356903 -383.59086) (xy 71.348826 -383.523923) (xy 71.348825 -383.456501)
			(xy 71.356899 -383.389564) (xy 71.372933 -383.324076) (xy 71.396695 -383.26098) (xy 71.427843 -383.201184)
			(xy 71.465929 -383.145549) (xy 71.487792 -383.119884) (xy 71.493577 -383.11273) (xy 71.500099 -383.095546)
			(xy 71.500492 -383.086356) (xy 71.500492 -382.59385) (xy 71.50006 -382.584665) (xy 71.493562 -382.56748)
			(xy 71.487792 -382.560322) (xy 71.465918 -382.534665) (xy 71.427831 -382.479029) (xy 71.396681 -382.419231)
			(xy 71.372918 -382.356134) (xy 71.356883 -382.290644) (xy 71.348808 -382.223705) (xy 46.070794 -382.223705)
			(xy 46.062758 -382.290467) (xy 46.046786 -382.355849) (xy 46.023113 -382.418853) (xy 45.99208 -382.478576)
			(xy 45.954131 -382.534162) (xy 45.932344 -382.559814) (xy 45.926552 -382.566962) (xy 45.920036 -382.584151)
			(xy 45.919644 -382.593342) (xy 45.919644 -383.086864) (xy 45.920084 -383.096048) (xy 45.926578 -383.113232)
			(xy 45.932344 -383.120392) (xy 45.954148 -383.146031) (xy 45.992098 -383.201619) (xy 46.023131 -383.261344)
			(xy 46.04657 -383.323727) (xy 47.149191 -383.323727) (xy 47.149195 -383.256419) (xy 47.157243 -383.189593)
			(xy 47.173221 -383.124208) (xy 47.1969 -383.061202) (xy 47.22794 -383.001477) (xy 47.265897 -382.945892)
			(xy 47.287688 -382.92024) (xy 47.293491 -382.913099) (xy 47.300002 -382.895905) (xy 47.300388 -382.886712)
			(xy 47.300388 -382.728724) (xy 47.300841 -382.718573) (xy 47.308626 -382.699823) (xy 47.323013 -382.685499)
			(xy 47.341797 -382.677797) (xy 47.35195 -382.677416) (xy 48.06823 -382.677416) (xy 48.078356 -382.677901)
			(xy 48.097073 -382.685634) (xy 48.111427 -382.699921) (xy 48.11925 -382.718601) (xy 48.119792 -382.728724)
			(xy 48.119792 -382.886712) (xy 48.120198 -382.8959) (xy 48.126715 -382.913084) (xy 48.132492 -382.92024)
			(xy 48.154243 -382.945922) (xy 48.192191 -383.001505) (xy 48.223224 -383.061224) (xy 48.246898 -383.124225)
			(xy 48.262872 -383.189603) (xy 48.270919 -383.256422) (xy 48.270922 -383.323724) (xy 48.262882 -383.390543)
			(xy 48.246914 -383.455923) (xy 48.223247 -383.518926) (xy 48.192219 -383.578649) (xy 48.154277 -383.634236)
			(xy 48.132492 -383.659888) (xy 48.126675 -383.667018) (xy 48.120173 -383.68422) (xy 48.119792 -383.693416)
			(xy 48.119792 -384.186684) (xy 48.120212 -384.19587) (xy 48.126719 -384.213054) (xy 48.132492 -384.220212)
			(xy 48.154314 -384.245835) (xy 48.19226 -384.301427) (xy 48.22329 -384.361155) (xy 48.246959 -384.424163)
			(xy 48.262929 -384.489548) (xy 48.27097 -384.556373) (xy 48.270966 -384.623681) (xy 48.262919 -384.690505)
			(xy 48.246943 -384.755889) (xy 48.223268 -384.818895) (xy 48.192232 -384.87862) (xy 48.154281 -384.934207)
			(xy 48.132492 -384.95986) (xy 48.126687 -384.966999) (xy 48.120177 -384.984194) (xy 48.119792 -384.993388)
			(xy 48.119792 -385.151376) (xy 48.119359 -385.16153) (xy 48.11157 -385.180283) (xy 48.097176 -385.194608)
			(xy 48.078386 -385.202307) (xy 48.06823 -385.202684) (xy 47.35195 -385.202684) (xy 47.341829 -385.202133)
			(xy 47.323114 -385.194426) (xy 47.308757 -385.18016) (xy 47.300932 -385.161493) (xy 47.300388 -385.151376)
			(xy 47.300388 -384.993388) (xy 47.299986 -384.9842) (xy 47.293467 -384.967016) (xy 47.287688 -384.95986)
			(xy 47.265934 -384.934179) (xy 47.227981 -384.878598) (xy 47.196944 -384.818879) (xy 47.173267 -384.755878)
			(xy 47.15729 -384.690499) (xy 47.149242 -384.623679) (xy 47.149239 -384.556376) (xy 47.15728 -384.489554)
			(xy 47.173251 -384.424174) (xy 47.196921 -384.361171) (xy 47.227953 -384.301448) (xy 47.265901 -384.245863)
			(xy 47.287688 -384.220212) (xy 47.293503 -384.21308) (xy 47.300007 -384.195879) (xy 47.300388 -384.186684)
			(xy 47.300388 -383.693416) (xy 47.299973 -383.684229) (xy 47.293463 -383.667045) (xy 47.287688 -383.659888)
			(xy 47.265863 -383.634266) (xy 47.227913 -383.578676) (xy 47.196878 -383.518949) (xy 47.173205 -383.45594)
			(xy 47.157233 -383.390554) (xy 47.149191 -383.323727) (xy 46.04657 -383.323727) (xy 46.046804 -383.32435)
			(xy 46.062776 -383.389734) (xy 46.070819 -383.456559) (xy 46.070818 -383.523865) (xy 46.062772 -383.590689)
			(xy 46.046797 -383.656073) (xy 46.023121 -383.719078) (xy 45.992085 -383.778802) (xy 45.954133 -383.834388)
			(xy 45.932344 -383.86004) (xy 45.926541 -383.86718) (xy 45.920032 -383.884375) (xy 45.919644 -383.893568)
			(xy 45.919644 -384.051556) (xy 45.919143 -384.061702) (xy 45.91137 -384.080445) (xy 45.896998 -384.094768)
			(xy 45.878229 -384.102477) (xy 45.868082 -384.102864) (xy 45.151802 -384.102864) (xy 45.141676 -384.102372)
			(xy 45.122956 -384.094645) (xy 45.108599 -384.080361) (xy 45.100779 -384.06168) (xy 45.10024 -384.051556)
			(xy 45.10024 -383.893568) (xy 45.099836 -383.88438) (xy 45.093317 -383.867197) (xy 45.08754 -383.86004)
			(xy 45.065768 -383.834375) (xy 45.027819 -383.77879) (xy 44.996785 -383.719068) (xy 44.973111 -383.656066)
			(xy 44.957137 -383.590685) (xy 44.949092 -383.523864) (xy 44.94909 -383.45656) (xy 44.957133 -383.389739)
			(xy 44.973104 -383.324357) (xy 44.996775 -383.261354) (xy 45.027806 -383.20163) (xy 45.065753 -383.146044)
			(xy 45.08754 -383.120392) (xy 45.093328 -383.113241) (xy 45.099847 -383.096055) (xy 45.10024 -383.086864)
			(xy 45.10024 -382.593342) (xy 45.0998 -382.584158) (xy 45.093306 -382.566974) (xy 45.08754 -382.559814)
			(xy 45.065742 -382.53417) (xy 45.027794 -382.478582) (xy 44.996761 -382.418858) (xy 44.973088 -382.355852)
			(xy 44.957116 -382.290469) (xy 44.949073 -382.223645) (xy 41.671034 -382.223645) (xy 41.671034 -382.223704)
			(xy 41.662958 -382.290643) (xy 41.646922 -382.356132) (xy 41.623157 -382.419229) (xy 41.592004 -382.479024)
			(xy 41.553913 -382.534658) (xy 41.532048 -382.560322) (xy 41.526253 -382.567468) (xy 41.519739 -382.584658)
			(xy 41.519348 -382.59385) (xy 41.519348 -383.086356) (xy 41.519791 -383.095539) (xy 41.526283 -383.112723)
			(xy 41.532048 -383.119884) (xy 41.55393 -383.145535) (xy 41.592021 -383.201171) (xy 41.623174 -383.260968)
			(xy 41.646834 -383.323786) (xy 42.748896 -383.323786) (xy 42.748899 -383.25636) (xy 42.756978 -383.189419)
			(xy 42.773018 -383.123928) (xy 42.796786 -383.06083) (xy 42.827941 -383.001032) (xy 42.866034 -382.945397)
			(xy 42.8879 -382.919732) (xy 42.893708 -382.912595) (xy 42.900216 -382.895398) (xy 42.9006 -382.886204)
			(xy 42.9006 -382.728724) (xy 42.901035 -382.718603) (xy 42.908776 -382.6999) (xy 42.923086 -382.685585)
			(xy 42.941787 -382.677839) (xy 42.951908 -382.677416) (xy 43.668188 -382.677416) (xy 43.678312 -382.677826)
			(xy 43.697018 -382.685573) (xy 43.711333 -382.699892) (xy 43.719076 -382.7186) (xy 43.719496 -382.728724)
			(xy 43.719496 -382.886204) (xy 43.719905 -382.895391) (xy 43.72642 -382.912575) (xy 43.732196 -382.919732)
			(xy 43.754025 -382.945426) (xy 43.792115 -383.001057) (xy 43.823267 -383.060849) (xy 43.847034 -383.123942)
			(xy 43.863072 -383.189427) (xy 43.871151 -383.256363) (xy 43.871154 -383.323783) (xy 43.863081 -383.390719)
			(xy 43.84705 -383.456206) (xy 43.823289 -383.519302) (xy 43.792143 -383.579097) (xy 43.754058 -383.634731)
			(xy 43.732196 -383.660396) (xy 43.726418 -383.667554) (xy 43.719892 -383.684735) (xy 43.719496 -383.693924)
			(xy 43.719496 -384.186176) (xy 43.719919 -384.195362) (xy 43.726424 -384.212546) (xy 43.732196 -384.219704)
			(xy 43.754095 -384.24534) (xy 43.792183 -384.300979) (xy 43.823333 -384.360779) (xy 43.847095 -384.42388)
			(xy 43.863128 -384.489372) (xy 43.871201 -384.556314) (xy 43.871198 -384.62374) (xy 43.863118 -384.690681)
			(xy 43.847079 -384.756172) (xy 43.823311 -384.819271) (xy 43.792156 -384.879068) (xy 43.754062 -384.934703)
			(xy 43.732196 -384.960368) (xy 43.726388 -384.967505) (xy 43.71988 -384.984702) (xy 43.719496 -384.993896)
			(xy 43.719496 -385.151376) (xy 43.719064 -385.161497) (xy 43.711323 -385.180201) (xy 43.697011 -385.194517)
			(xy 43.678309 -385.202262) (xy 43.668188 -385.202684) (xy 42.951908 -385.202684) (xy 42.941784 -385.202277)
			(xy 42.923078 -385.194529) (xy 42.908762 -385.180209) (xy 42.90102 -385.1615) (xy 42.9006 -385.151376)
			(xy 42.9006 -384.993896) (xy 42.900192 -384.984709) (xy 42.893677 -384.967524) (xy 42.8879 -384.960368)
			(xy 42.866071 -384.934674) (xy 42.827982 -384.879043) (xy 42.796829 -384.819251) (xy 42.773063 -384.756158)
			(xy 42.757025 -384.690672) (xy 42.748946 -384.623737) (xy 42.748943 -384.556317) (xy 42.757015 -384.489381)
			(xy 42.773047 -384.423894) (xy 42.796807 -384.360798) (xy 42.827954 -384.301003) (xy 42.866038 -384.245369)
			(xy 42.8879 -384.219704) (xy 42.893677 -384.212545) (xy 42.900204 -384.195365) (xy 42.9006 -384.186176)
			(xy 42.9006 -383.693924) (xy 42.900178 -383.684738) (xy 42.893673 -383.667554) (xy 42.8879 -383.660396)
			(xy 42.866001 -383.63476) (xy 42.827913 -383.579121) (xy 42.796764 -383.519321) (xy 42.773002 -383.45622)
			(xy 42.756969 -383.390728) (xy 42.748896 -383.323786) (xy 41.646834 -383.323786) (xy 41.64694 -383.324067)
			(xy 41.662976 -383.389558) (xy 41.671051 -383.456499) (xy 41.67105 -383.523925) (xy 41.662971 -383.590865)
			(xy 41.646933 -383.656356) (xy 41.623164 -383.719454) (xy 41.592009 -383.77925) (xy 41.553915 -383.834884)
			(xy 41.532048 -383.860548) (xy 41.526242 -383.867686) (xy 41.519734 -383.884882) (xy 41.519348 -383.894076)
			(xy 41.519348 -384.051556) (xy 41.518849 -384.06167) (xy 41.511124 -384.080363) (xy 41.496834 -384.094677)
			(xy 41.478153 -384.102432) (xy 41.46804 -384.102864) (xy 40.75176 -384.102864) (xy 40.74163 -384.102516)
			(xy 40.722919 -384.094748) (xy 40.708605 -384.08041) (xy 40.700868 -384.061686) (xy 40.700452 -384.051556)
			(xy 40.700452 -383.894076) (xy 40.700042 -383.884889) (xy 40.693527 -383.867705) (xy 40.687752 -383.860548)
			(xy 40.665902 -383.834871) (xy 40.627809 -383.779239) (xy 40.596655 -383.719445) (xy 40.572888 -383.65635)
			(xy 40.556849 -383.590862) (xy 40.548772 -383.523924) (xy 40.54877 -383.4565) (xy 40.556845 -383.389562)
			(xy 40.572881 -383.324073) (xy 40.596645 -383.260977) (xy 40.627797 -383.201182) (xy 40.665887 -383.145548)
			(xy 40.687752 -383.119884) (xy 40.693544 -383.112736) (xy 40.70006 -383.095547) (xy 40.700452 -383.086356)
			(xy 40.700452 -382.59385) (xy 40.700006 -382.584667) (xy 40.693516 -382.567483) (xy 40.687752 -382.560322)
			(xy 40.665876 -382.534666) (xy 40.627785 -382.479031) (xy 40.596631 -382.419234) (xy 40.572865 -382.356136)
			(xy 40.556829 -382.290645) (xy 40.548753 -382.223705) (xy 37.271243 -382.223705) (xy 37.263167 -382.290643)
			(xy 37.247132 -382.356132) (xy 37.223367 -382.419228) (xy 37.192215 -382.479024) (xy 37.154125 -382.534657)
			(xy 37.13226 -382.560322) (xy 37.126467 -382.567469) (xy 37.119951 -382.584658) (xy 37.11956 -382.59385)
			(xy 37.11956 -383.086356) (xy 37.12 -383.09554) (xy 37.126494 -383.112724) (xy 37.13226 -383.119884)
			(xy 37.154141 -383.145536) (xy 37.192232 -383.201171) (xy 37.223384 -383.260969) (xy 37.247021 -383.323727)
			(xy 38.349127 -383.323727) (xy 38.349131 -383.256419) (xy 38.357178 -383.189595) (xy 38.373154 -383.124211)
			(xy 38.396829 -383.061205) (xy 38.427864 -383.00148) (xy 38.465815 -382.945893) (xy 38.487604 -382.92024)
			(xy 38.493409 -382.913101) (xy 38.499919 -382.895906) (xy 38.500304 -382.886712) (xy 38.500304 -382.728724)
			(xy 38.500741 -382.718571) (xy 38.50853 -382.699818) (xy 38.522922 -382.685494) (xy 38.541711 -382.677794)
			(xy 38.551866 -382.677416) (xy 39.268146 -382.677416) (xy 39.278273 -382.677888) (xy 39.29699 -382.685627)
			(xy 39.311344 -382.699917) (xy 39.319166 -382.7186) (xy 39.319708 -382.728724) (xy 39.319708 -382.886712)
			(xy 39.320111 -382.8959) (xy 39.326629 -382.913084) (xy 39.332408 -382.92024) (xy 39.354162 -382.945921)
			(xy 39.392115 -383.001502) (xy 39.423153 -383.061221) (xy 39.44683 -383.124222) (xy 39.462807 -383.189601)
			(xy 39.470855 -383.256421) (xy 39.470858 -383.323725) (xy 39.462817 -383.390546) (xy 39.446846 -383.455926)
			(xy 39.423175 -383.51893) (xy 39.392143 -383.578652) (xy 39.354195 -383.634237) (xy 39.332408 -383.659888)
			(xy 39.326592 -383.66702) (xy 39.320089 -383.684221) (xy 39.319708 -383.693416) (xy 39.319708 -384.186684)
			(xy 39.320124 -384.195871) (xy 39.326633 -384.213055) (xy 39.332408 -384.220212) (xy 39.354233 -384.245834)
			(xy 39.392184 -384.301424) (xy 39.423219 -384.361151) (xy 39.446892 -384.42416) (xy 39.462864 -384.489546)
			(xy 39.470906 -384.556373) (xy 39.470902 -384.623682) (xy 39.462854 -384.690507) (xy 39.446876 -384.755892)
			(xy 39.423196 -384.818898) (xy 39.392156 -384.878623) (xy 39.354199 -384.934209) (xy 39.332408 -384.95986)
			(xy 39.326604 -384.967) (xy 39.320094 -384.984195) (xy 39.319708 -384.993388) (xy 39.319708 -385.151376)
			(xy 39.319259 -385.161528) (xy 39.311473 -385.180278) (xy 39.297085 -385.194602) (xy 39.278299 -385.202304)
			(xy 39.268146 -385.202684) (xy 38.551866 -385.202684) (xy 38.54174 -385.202202) (xy 38.523023 -385.194468)
			(xy 38.508668 -385.18018) (xy 38.500846 -385.1615) (xy 38.500304 -385.151376) (xy 38.500304 -384.993388)
			(xy 38.499899 -384.9842) (xy 38.493381 -384.967016) (xy 38.487604 -384.95986) (xy 38.465853 -384.934178)
			(xy 38.427905 -384.878595) (xy 38.396872 -384.818875) (xy 38.373199 -384.755875) (xy 38.357224 -384.690497)
			(xy 38.349178 -384.623678) (xy 38.349175 -384.556376) (xy 38.357215 -384.489557) (xy 38.373183 -384.424177)
			(xy 38.39685 -384.361174) (xy 38.427877 -384.301451) (xy 38.465819 -384.245865) (xy 38.487604 -384.220212)
			(xy 38.493421 -384.213081) (xy 38.499923 -384.19588) (xy 38.500304 -384.186684) (xy 38.500304 -383.693416)
			(xy 38.499885 -383.68423) (xy 38.493377 -383.667045) (xy 38.487604 -383.659888) (xy 38.465782 -383.634264)
			(xy 38.427837 -383.578673) (xy 38.396807 -383.518945) (xy 38.373138 -383.455937) (xy 38.357168 -383.390552)
			(xy 38.349127 -383.323727) (xy 37.247021 -383.323727) (xy 37.247149 -383.324068) (xy 37.263185 -383.389559)
			(xy 37.27126 -383.456499) (xy 37.271259 -383.523925) (xy 37.263181 -383.590865) (xy 37.247142 -383.656355)
			(xy 37.223374 -383.719453) (xy 37.19222 -383.77925) (xy 37.154126 -383.834883) (xy 37.13226 -383.860548)
			(xy 37.126456 -383.867687) (xy 37.119947 -383.884883) (xy 37.11956 -383.894076) (xy 37.11956 -384.051556)
			(xy 37.119147 -384.061681) (xy 37.111406 -384.080391) (xy 37.097087 -384.094708) (xy 37.078377 -384.102448)
			(xy 37.068252 -384.102864) (xy 36.351972 -384.102864) (xy 36.341843 -384.102506) (xy 36.323132 -384.094742)
			(xy 36.308817 -384.080407) (xy 36.30108 -384.061685) (xy 36.300664 -384.051556) (xy 36.300664 -383.894076)
			(xy 36.300251 -383.884889) (xy 36.293738 -383.867706) (xy 36.287964 -383.860548) (xy 36.266117 -383.834869)
			(xy 36.22803 -383.779236) (xy 36.196881 -383.719441) (xy 36.173117 -383.656346) (xy 36.157082 -383.590859)
			(xy 36.149005 -383.523923) (xy 36.149004 -383.456501) (xy 36.157078 -383.389565) (xy 36.17311 -383.324077)
			(xy 36.196871 -383.260981) (xy 36.228018 -383.201185) (xy 36.266102 -383.14555) (xy 36.287964 -383.119884)
			(xy 36.293758 -383.112737) (xy 36.300272 -383.095548) (xy 36.300664 -383.086356) (xy 36.300664 -382.59385)
			(xy 36.300216 -382.584667) (xy 36.293727 -382.567483) (xy 36.287964 -382.560322) (xy 36.266091 -382.534664)
			(xy 36.228005 -382.479028) (xy 36.196857 -382.41923) (xy 36.173095 -382.356132) (xy 36.157061 -382.290643)
			(xy 36.148987 -382.223704) (xy 32.870916 -382.223704) (xy 32.86288 -382.290466) (xy 32.846909 -382.355848)
			(xy 32.823237 -382.418852) (xy 32.792206 -382.478575) (xy 32.754259 -382.534162) (xy 32.732472 -382.559814)
			(xy 32.726683 -382.566965) (xy 32.720165 -382.584151) (xy 32.719772 -382.593342) (xy 32.719772 -383.086864)
			(xy 32.720206 -383.096049) (xy 32.726704 -383.113233) (xy 32.732472 -383.120392) (xy 32.754275 -383.146031)
			(xy 32.792223 -383.20162) (xy 32.823255 -383.261345) (xy 32.846714 -383.323786) (xy 33.948808 -383.323786)
			(xy 33.948811 -383.25636) (xy 33.956891 -383.189419) (xy 33.972931 -383.123927) (xy 33.996699 -383.060829)
			(xy 34.027855 -383.001032) (xy 34.065949 -382.945397) (xy 34.087816 -382.919732) (xy 34.093626 -382.912596)
			(xy 34.100132 -382.895398) (xy 34.100516 -382.886204) (xy 34.100516 -382.728724) (xy 34.100936 -382.718601)
			(xy 34.108679 -382.699895) (xy 34.122995 -382.685579) (xy 34.141701 -382.677836) (xy 34.151824 -382.677416)
			(xy 34.868104 -382.677416) (xy 34.878229 -382.677813) (xy 34.896935 -382.685566) (xy 34.91125 -382.699888)
			(xy 34.918992 -382.718599) (xy 34.919412 -382.728724) (xy 34.919412 -382.886204) (xy 34.919818 -382.895392)
			(xy 34.926334 -382.912576) (xy 34.932112 -382.919732) (xy 34.95394 -382.945427) (xy 34.992029 -383.001057)
			(xy 35.023181 -383.060849) (xy 35.046946 -383.123942) (xy 35.062984 -383.189428) (xy 35.071063 -383.256363)
			(xy 35.071066 -383.323783) (xy 35.062994 -383.390719) (xy 35.046962 -383.456206) (xy 35.023203 -383.519301)
			(xy 34.992057 -383.579096) (xy 34.953973 -383.634731) (xy 34.932112 -383.660396) (xy 34.926336 -383.667556)
			(xy 34.919809 -383.684735) (xy 34.919412 -383.693924) (xy 34.919412 -384.186176) (xy 34.919831 -384.195362)
			(xy 34.926338 -384.212547) (xy 34.932112 -384.219704) (xy 34.954011 -384.24534) (xy 34.992098 -384.300979)
			(xy 35.023246 -384.36078) (xy 35.047008 -384.42388) (xy 35.06304 -384.489373) (xy 35.071113 -384.556314)
			(xy 35.07111 -384.62374) (xy 35.063031 -384.690681) (xy 35.046992 -384.756172) (xy 35.023224 -384.81927)
			(xy 34.99207 -384.879067) (xy 34.953978 -384.934703) (xy 34.932112 -384.960368) (xy 34.926305 -384.967506)
			(xy 34.919796 -384.984702) (xy 34.919412 -384.993896) (xy 34.919412 -385.151376) (xy 34.918965 -385.161495)
			(xy 34.911227 -385.180196) (xy 34.89692 -385.194511) (xy 34.878223 -385.202259) (xy 34.868104 -385.202684)
			(xy 34.151824 -385.202684) (xy 34.141701 -385.202264) (xy 34.122995 -385.194521) (xy 34.108679 -385.180205)
			(xy 34.100936 -385.161499) (xy 34.100516 -385.151376) (xy 34.100516 -384.993896) (xy 34.100104 -384.984709)
			(xy 34.093591 -384.967525) (xy 34.087816 -384.960368) (xy 34.065987 -384.934674) (xy 34.027896 -384.879044)
			(xy 33.996743 -384.819252) (xy 33.972976 -384.756159) (xy 33.956937 -384.690673) (xy 33.948858 -384.623738)
			(xy 33.948855 -384.556316) (xy 33.956928 -384.48938) (xy 33.97296 -384.423893) (xy 33.996721 -384.360798)
			(xy 34.027868 -384.301003) (xy 34.065954 -384.245369) (xy 34.087816 -384.219704) (xy 34.093595 -384.212547)
			(xy 34.10012 -384.195365) (xy 34.100516 -384.186176) (xy 34.100516 -383.693924) (xy 34.100091 -383.684739)
			(xy 34.093587 -383.667554) (xy 34.087816 -383.660396) (xy 34.065916 -383.63476) (xy 34.027827 -383.579122)
			(xy 33.996677 -383.519322) (xy 33.972915 -383.456221) (xy 33.956881 -383.390728) (xy 33.948808 -383.323786)
			(xy 32.846714 -383.323786) (xy 32.846926 -383.324351) (xy 32.862898 -383.389735) (xy 32.87094 -383.456559)
			(xy 32.870939 -383.523865) (xy 32.862893 -383.590689) (xy 32.846919 -383.656072) (xy 32.823245 -383.719077)
			(xy 32.79221 -383.778801) (xy 32.75426 -383.834388) (xy 32.732472 -383.86004) (xy 32.726672 -383.867183)
			(xy 32.72016 -383.884375) (xy 32.719772 -383.893568) (xy 32.719772 -384.051556) (xy 32.719342 -384.061711)
			(xy 32.711555 -384.080468) (xy 32.697161 -384.094793) (xy 32.678367 -384.10249) (xy 32.66821 -384.102864)
			(xy 31.95193 -384.102864) (xy 31.941806 -384.102349) (xy 31.923086 -384.094632) (xy 31.908729 -384.080354)
			(xy 31.900908 -384.061678) (xy 31.900368 -384.051556) (xy 31.900368 -383.893568) (xy 31.899958 -383.884381)
			(xy 31.893443 -383.867197) (xy 31.887668 -383.86004) (xy 31.865895 -383.834375) (xy 31.827944 -383.778791)
			(xy 31.796908 -383.71907) (xy 31.773234 -383.656067) (xy 31.757259 -383.590686) (xy 31.749213 -383.523864)
			(xy 31.749211 -383.45656) (xy 31.757254 -383.389738) (xy 31.773226 -383.324356) (xy 31.796899 -383.261352)
			(xy 31.827932 -383.201629) (xy 31.86588 -383.146044) (xy 31.887668 -383.120392) (xy 31.893459 -383.113243)
			(xy 31.899975 -383.096055) (xy 31.900368 -383.086864) (xy 31.900368 -382.593342) (xy 31.899923 -382.584159)
			(xy 31.893432 -382.566975) (xy 31.887668 -382.559814) (xy 31.86587 -382.53417) (xy 31.827919 -382.478583)
			(xy 31.796885 -382.418859) (xy 31.773211 -382.355853) (xy 31.757238 -382.29047) (xy 31.749194 -382.223646)
			(xy 28.471155 -382.223646) (xy 28.471155 -382.223704) (xy 28.463079 -382.290642) (xy 28.447044 -382.356131)
			(xy 28.42328 -382.419228) (xy 28.392129 -382.479023) (xy 28.35404 -382.534657) (xy 28.332176 -382.560322)
			(xy 28.326385 -382.567471) (xy 28.319868 -382.584659) (xy 28.319476 -382.59385) (xy 28.319476 -383.086356)
			(xy 28.319913 -383.09554) (xy 28.326409 -383.112725) (xy 28.332176 -383.119884) (xy 28.354057 -383.145536)
			(xy 28.392146 -383.201172) (xy 28.423298 -383.26097) (xy 28.446934 -383.323727) (xy 29.549039 -383.323727)
			(xy 29.549043 -383.256419) (xy 29.55709 -383.189594) (xy 29.573066 -383.12421) (xy 29.596742 -383.061205)
			(xy 29.627779 -383.00148) (xy 29.665731 -382.945892) (xy 29.68752 -382.92024) (xy 29.693327 -382.913102)
			(xy 29.699835 -382.895906) (xy 29.70022 -382.886712) (xy 29.70022 -382.728724) (xy 29.700636 -382.718601)
			(xy 29.70838 -382.699894) (xy 29.722697 -382.685578) (xy 29.741405 -382.677835) (xy 29.751528 -382.677416)
			(xy 30.468062 -382.677416) (xy 30.478183 -382.677957) (xy 30.496899 -382.685668) (xy 30.511256 -382.699938)
			(xy 30.51908 -382.718606) (xy 30.519624 -382.728724) (xy 30.519624 -382.886712) (xy 30.520023 -382.8959)
			(xy 30.526544 -382.913085) (xy 30.532324 -382.92024) (xy 30.554077 -382.945921) (xy 30.59203 -383.001502)
			(xy 30.623067 -383.061222) (xy 30.646743 -383.124222) (xy 30.66272 -383.189601) (xy 30.670767 -383.256421)
			(xy 30.67077 -383.323724) (xy 30.662729 -383.390545) (xy 30.646759 -383.455926) (xy 30.623089 -383.518929)
			(xy 30.592058 -383.578651) (xy 30.554111 -383.634236) (xy 30.532324 -383.659888) (xy 30.52651 -383.667021)
			(xy 30.520005 -383.684221) (xy 30.519624 -383.693416) (xy 30.519624 -384.186684) (xy 30.520036 -384.195871)
			(xy 30.526548 -384.213056) (xy 30.532324 -384.220212) (xy 30.554149 -384.245834) (xy 30.592099 -384.301424)
			(xy 30.623132 -384.361152) (xy 30.646805 -384.42416) (xy 30.662776 -384.489546) (xy 30.670818 -384.556373)
			(xy 30.670815 -384.623681) (xy 30.662767 -384.690507) (xy 30.646789 -384.755892) (xy 30.62311 -384.818898)
			(xy 30.592071 -384.878622) (xy 30.554115 -384.934209) (xy 30.532324 -384.95986) (xy 30.526522 -384.967002)
			(xy 30.52001 -384.984195) (xy 30.519624 -384.993388) (xy 30.519624 -385.151376) (xy 30.519165 -385.161494)
			(xy 30.511429 -385.180193) (xy 30.497126 -385.194507) (xy 30.478434 -385.202257) (xy 30.468316 -385.202684)
			(xy 29.751782 -385.202684) (xy 29.741657 -385.202189) (xy 29.72294 -385.19446) (xy 29.708585 -385.180177)
			(xy 29.700762 -385.161498) (xy 29.70022 -385.151376) (xy 29.70022 -384.993388) (xy 29.699811 -384.984201)
			(xy 29.693296 -384.967017) (xy 29.68752 -384.95986) (xy 29.665769 -384.934178) (xy 29.62782 -384.878596)
			(xy 29.596786 -384.818876) (xy 29.573112 -384.755875) (xy 29.557137 -384.690497) (xy 29.549091 -384.623678)
			(xy 29.549087 -384.556376) (xy 29.557128 -384.489556) (xy 29.573096 -384.424176) (xy 29.596764 -384.361174)
			(xy 29.627792 -384.301451) (xy 29.665735 -384.245865) (xy 29.68752 -384.220212) (xy 29.693339 -384.213083)
			(xy 29.69984 -384.19588) (xy 29.70022 -384.186684) (xy 29.70022 -383.693416) (xy 29.699797 -383.68423)
			(xy 29.693292 -383.667046) (xy 29.68752 -383.659888) (xy 29.665697 -383.634265) (xy 29.627751 -383.578674)
			(xy 29.59672 -383.518946) (xy 29.57305 -383.455938) (xy 29.55708 -383.390552) (xy 29.549039 -383.323727)
			(xy 28.446934 -383.323727) (xy 28.447062 -383.324068) (xy 28.463097 -383.389559) (xy 28.471172 -383.456499)
			(xy 28.471171 -383.523925) (xy 28.463093 -383.590865) (xy 28.447055 -383.656355) (xy 28.423288 -383.719452)
			(xy 28.392134 -383.779249) (xy 28.354042 -383.834883) (xy 28.332176 -383.860548) (xy 28.326374 -383.867689)
			(xy 28.319863 -383.884883) (xy 28.319476 -383.894076) (xy 28.319476 -384.051556) (xy 28.319047 -384.061679)
			(xy 28.311309 -384.080386) (xy 28.296996 -384.094702) (xy 28.27829 -384.102445) (xy 28.268168 -384.102864)
			(xy 27.551888 -384.102864) (xy 27.54176 -384.102493) (xy 27.523049 -384.094734) (xy 27.508734 -384.080404)
			(xy 27.500996 -384.061684) (xy 27.50058 -384.051556) (xy 27.50058 -383.894076) (xy 27.500186 -383.884887)
			(xy 27.493661 -383.867703) (xy 27.48788 -383.860548) (xy 27.466032 -383.834869) (xy 27.427945 -383.779236)
			(xy 27.396794 -383.719442) (xy 27.37303 -383.656347) (xy 27.356994 -383.59086) (xy 27.348917 -383.523923)
			(xy 27.348916 -383.456501) (xy 27.35699 -383.389564) (xy 27.373023 -383.324076) (xy 27.396784 -383.26098)
			(xy 27.427932 -383.201184) (xy 27.466018 -383.14555) (xy 27.48788 -383.119884) (xy 27.493664 -383.112729)
			(xy 27.500187 -383.095546) (xy 27.50058 -383.086356) (xy 27.50058 -382.59385) (xy 27.50015 -382.584665)
			(xy 27.49365 -382.56748) (xy 27.48788 -382.560322) (xy 27.466007 -382.534665) (xy 27.42792 -382.479028)
			(xy 27.396771 -382.419231) (xy 27.373008 -382.356133) (xy 27.356974 -382.290643) (xy 27.348899 -382.223705)
			(xy 0.508 -382.223705) (xy 0.508 -385.583938) (xy 100.447856 -385.583938) (xy 100.447856 -384.720338)
			(xy 100.448346 -384.690354) (xy 100.456174 -384.630898) (xy 100.471695 -384.572973) (xy 100.494644 -384.517569)
			(xy 100.524628 -384.465635) (xy 100.561134 -384.418059) (xy 100.603539 -384.375654) (xy 100.651115 -384.339148)
			(xy 100.703049 -384.309164) (xy 100.758453 -384.286215) (xy 100.816378 -384.270694) (xy 100.875834 -384.262866)
			(xy 100.935802 -384.262866) (xy 100.995258 -384.270694) (xy 101.053183 -384.286215) (xy 101.108587 -384.309164)
			(xy 101.160521 -384.339148) (xy 101.208097 -384.375654) (xy 101.250502 -384.418059) (xy 101.287008 -384.465635)
			(xy 101.316992 -384.517569) (xy 101.339941 -384.572973) (xy 101.355462 -384.630898) (xy 101.36329 -384.690354)
			(xy 101.36378 -384.720338) (xy 101.36378 -385.319283) (xy 104.635826 -385.319283) (xy 104.635826 -385.259317)
			(xy 104.643653 -385.199864) (xy 104.659172 -385.141942) (xy 104.682119 -385.08654) (xy 104.7121 -385.034608)
			(xy 104.748603 -384.987032) (xy 104.791004 -384.944628) (xy 104.838576 -384.908121) (xy 104.890506 -384.878136)
			(xy 104.945906 -384.855184) (xy 105.003827 -384.83966) (xy 105.063279 -384.831828) (xy 105.093262 -384.831336)
			(xy 105.956862 -384.831336) (xy 105.986849 -384.831807) (xy 106.046311 -384.83963) (xy 106.104243 -384.855149)
			(xy 106.159653 -384.878097) (xy 106.211594 -384.908081) (xy 106.259176 -384.944589) (xy 106.301586 -384.986995)
			(xy 106.338098 -385.034574) (xy 106.368087 -385.086513) (xy 106.391039 -385.141921) (xy 106.406562 -385.199852)
			(xy 106.414391 -385.259313) (xy 106.414391 -385.319287) (xy 106.406562 -385.378748) (xy 106.391039 -385.436679)
			(xy 106.368087 -385.492087) (xy 106.338098 -385.544026) (xy 106.301586 -385.591605) (xy 106.259176 -385.634011)
			(xy 106.211594 -385.670519) (xy 106.159653 -385.700503) (xy 106.104243 -385.723451) (xy 106.046311 -385.73897)
			(xy 105.986849 -385.746793) (xy 105.956862 -385.74726) (xy 105.093262 -385.74726) (xy 105.063279 -385.746772)
			(xy 105.003827 -385.73894) (xy 104.945906 -385.723416) (xy 104.890506 -385.700464) (xy 104.838576 -385.670479)
			(xy 104.791004 -385.633972) (xy 104.748603 -385.591568) (xy 104.7121 -385.543992) (xy 104.682119 -385.49206)
			(xy 104.659172 -385.436658) (xy 104.643653 -385.378736) (xy 104.635826 -385.319283) (xy 101.36378 -385.319283)
			(xy 101.36378 -385.583938) (xy 101.36329 -385.613922) (xy 101.355462 -385.673378) (xy 101.339941 -385.731303)
			(xy 101.316992 -385.786707) (xy 101.287008 -385.838641) (xy 101.250502 -385.886217) (xy 101.208097 -385.928622)
			(xy 101.160521 -385.965128) (xy 101.108587 -385.995112) (xy 101.053183 -386.018061) (xy 100.995258 -386.033582)
			(xy 100.935802 -386.04141) (xy 100.875834 -386.04141) (xy 100.816378 -386.033582) (xy 100.758453 -386.018061)
			(xy 100.703049 -385.995112) (xy 100.651115 -385.965128) (xy 100.603539 -385.928622) (xy 100.561134 -385.886217)
			(xy 100.524628 -385.838641) (xy 100.494644 -385.786707) (xy 100.471695 -385.731303) (xy 100.456174 -385.673378)
			(xy 100.448346 -385.613922) (xy 100.447856 -385.583938) (xy 0.508 -385.583938) (xy 0.508 -388.37489)
			(xy 1.56972 -388.37489) (xy 1.56972 -387.51129) (xy 1.57021 -387.481322) (xy 1.578033 -387.4219)
			(xy 1.593546 -387.364007) (xy 1.616482 -387.308634) (xy 1.646449 -387.256728) (xy 1.682936 -387.209178)
			(xy 1.725316 -387.166798) (xy 1.772866 -387.130311) (xy 1.824772 -387.100344) (xy 1.880145 -387.077408)
			(xy 1.938038 -387.061895) (xy 1.99746 -387.054072) (xy 2.057396 -387.054072) (xy 2.116818 -387.061895)
			(xy 2.174711 -387.077408) (xy 2.230084 -387.100344) (xy 2.28199 -387.130311) (xy 2.32954 -387.166798)
			(xy 2.37192 -387.209178) (xy 2.408407 -387.256728) (xy 2.438374 -387.308634) (xy 2.46131 -387.364007)
			(xy 2.476823 -387.4219) (xy 2.484646 -387.481322) (xy 2.485136 -387.51129) (xy 2.485136 -388.37489)
			(xy 2.484646 -388.404858) (xy 2.476823 -388.46428) (xy 2.46131 -388.522173) (xy 2.438374 -388.577546)
			(xy 2.408407 -388.629452) (xy 2.37192 -388.677002) (xy 2.32954 -388.719382) (xy 2.28199 -388.755869)
			(xy 2.230084 -388.785836) (xy 2.174711 -388.808772) (xy 2.116818 -388.824285) (xy 2.057396 -388.832108)
			(xy 1.99746 -388.832108) (xy 1.938038 -388.824285) (xy 1.880145 -388.808772) (xy 1.824772 -388.785836)
			(xy 1.772866 -388.755869) (xy 1.725316 -388.719382) (xy 1.682936 -388.677002) (xy 1.646449 -388.629452)
			(xy 1.616482 -388.577546) (xy 1.593546 -388.522173) (xy 1.578033 -388.46428) (xy 1.57021 -388.404858)
			(xy 1.56972 -388.37489) (xy 0.508 -388.37489) (xy 0.508 -398.164722) (xy 3.141726 -398.164722) (xy 3.141726 -398.035362)
			(xy 3.149849 -397.906256) (xy 3.166062 -397.777916) (xy 3.190302 -397.650846) (xy 3.222472 -397.52555)
			(xy 3.262447 -397.40252) (xy 3.310068 -397.282244) (xy 3.365147 -397.165195) (xy 3.427467 -397.051835)
			(xy 3.496782 -396.942612) (xy 3.572818 -396.837957) (xy 3.655276 -396.738283) (xy 3.743829 -396.643983)
			(xy 3.838129 -396.55543) (xy 3.937803 -396.472972) (xy 4.042458 -396.396936) (xy 4.151681 -396.327621)
			(xy 4.265041 -396.265301) (xy 4.38209 -396.210222) (xy 4.502366 -396.162601) (xy 4.625396 -396.122626)
			(xy 4.750692 -396.090456) (xy 4.877762 -396.066216) (xy 5.006102 -396.050003) (xy 5.135208 -396.04188)
			(xy 5.199888 -396.041372) (xy 6.800088 -396.041372) (xy 6.864769 -396.041866) (xy 6.993875 -396.049988)
			(xy 7.122217 -396.066201) (xy 7.249287 -396.090441) (xy 7.374584 -396.122612) (xy 7.497614 -396.162587)
			(xy 7.617892 -396.210208) (xy 7.734942 -396.265287) (xy 7.848302 -396.327608) (xy 7.957526 -396.396923)
			(xy 8.062181 -396.47296) (xy 8.161856 -396.555418) (xy 8.256157 -396.643972) (xy 8.344711 -396.738272)
			(xy 8.427169 -396.837947) (xy 8.503206 -396.942603) (xy 8.572521 -397.051826) (xy 8.634842 -397.165187)
			(xy 8.689921 -397.282236) (xy 8.737543 -397.402514) (xy 8.777518 -397.525544) (xy 8.809688 -397.650841)
			(xy 8.833928 -397.777911) (xy 8.839736 -397.823885) (xy 27.348879 -397.823885) (xy 27.348883 -397.756458)
			(xy 27.356962 -397.689518) (xy 27.373001 -397.624027) (xy 27.396769 -397.560929) (xy 27.427923 -397.501131)
			(xy 27.466014 -397.445496) (xy 27.48788 -397.41983) (xy 27.493686 -397.412692) (xy 27.500196 -397.395496)
			(xy 27.50058 -397.386302) (xy 27.50058 -396.89405) (xy 27.50015 -396.884865) (xy 27.49365 -396.86768)
			(xy 27.48788 -396.860522) (xy 27.466007 -396.834865) (xy 27.42792 -396.779228) (xy 27.396771 -396.719431)
			(xy 27.373008 -396.656333) (xy 27.356974 -396.590843) (xy 27.348899 -396.523905) (xy 27.3489 -396.45648)
			(xy 27.356976 -396.389542) (xy 27.373012 -396.324053) (xy 27.396777 -396.260955) (xy 27.427928 -396.201159)
			(xy 27.466016 -396.145524) (xy 27.48788 -396.119858) (xy 27.493675 -396.112711) (xy 27.500191 -396.095522)
			(xy 27.50058 -396.08633) (xy 27.50058 -395.92885) (xy 27.501069 -395.918722) (xy 27.508787 -395.899994)
			(xy 27.523074 -395.885635) (xy 27.541762 -395.877821) (xy 27.551888 -395.877288) (xy 28.268168 -395.877288)
			(xy 28.278319 -395.877747) (xy 28.297068 -395.88553) (xy 28.311392 -395.899915) (xy 28.319095 -395.918698)
			(xy 28.319476 -395.92885) (xy 28.319476 -396.08633) (xy 28.319877 -396.095518) (xy 28.326398 -396.112702)
			(xy 28.332176 -396.119858) (xy 28.354031 -396.145531) (xy 28.392122 -396.201164) (xy 28.423274 -396.260959)
			(xy 28.44704 -396.324055) (xy 28.463077 -396.389543) (xy 28.471154 -396.456481) (xy 28.471155 -396.523904)
			(xy 28.463079 -396.590842) (xy 28.447044 -396.656331) (xy 28.42328 -396.719428) (xy 28.392129 -396.779223)
			(xy 28.35404 -396.834857) (xy 28.332176 -396.860522) (xy 28.326385 -396.867671) (xy 28.319868 -396.884859)
			(xy 28.319476 -396.89405) (xy 28.319476 -397.386302) (xy 28.31989 -397.395489) (xy 28.326402 -397.412673)
			(xy 28.332176 -397.41983) (xy 28.354003 -397.445526) (xy 28.392095 -397.501155) (xy 28.420857 -397.556356)
			(xy 29.549071 -397.556356) (xy 29.557114 -397.489534) (xy 29.573085 -397.424153) (xy 29.596756 -397.361149)
			(xy 29.627787 -397.301425) (xy 29.665733 -397.245838) (xy 29.68752 -397.220186) (xy 29.693307 -397.213034)
			(xy 29.699827 -397.195849) (xy 29.70022 -397.186658) (xy 29.70022 -397.028924) (xy 29.700641 -397.018769)
			(xy 29.708433 -397.000013) (xy 29.72283 -396.985688) (xy 29.741625 -396.977991) (xy 29.751782 -396.977616)
			(xy 30.468062 -396.977616) (xy 30.478183 -396.978157) (xy 30.496899 -396.985868) (xy 30.511256 -397.000138)
			(xy 30.51908 -397.018806) (xy 30.519624 -397.028924) (xy 30.519624 -397.186658) (xy 30.520049 -397.195844)
			(xy 30.526552 -397.213029) (xy 30.532324 -397.220186) (xy 30.554123 -397.24583) (xy 30.592074 -397.301416)
			(xy 30.623108 -397.361141) (xy 30.646782 -397.424147) (xy 30.662756 -397.48953) (xy 30.6708 -397.556354)
			(xy 30.670799 -397.623661) (xy 30.662753 -397.690485) (xy 30.646778 -397.755868) (xy 30.623102 -397.818873)
			(xy 30.620528 -397.823826) (xy 31.749174 -397.823826) (xy 31.749178 -397.756517) (xy 31.757226 -397.689691)
			(xy 31.773204 -397.624307) (xy 31.796882 -397.5613) (xy 31.827922 -397.501576) (xy 31.865877 -397.44599)
			(xy 31.887668 -397.420338) (xy 31.893482 -397.413205) (xy 31.899984 -397.396005) (xy 31.900368 -397.38681)
			(xy 31.900368 -396.893542) (xy 31.899923 -396.884359) (xy 31.893432 -396.867175) (xy 31.887668 -396.860014)
			(xy 31.86587 -396.83437) (xy 31.827919 -396.778783) (xy 31.796885 -396.719059) (xy 31.773211 -396.656053)
			(xy 31.757238 -396.59067) (xy 31.749194 -396.523846) (xy 31.749195 -396.456539) (xy 31.757241 -396.389716)
			(xy 31.773216 -396.324332) (xy 31.796891 -396.261327) (xy 31.827927 -396.201604) (xy 31.865879 -396.146018)
			(xy 31.887668 -396.120366) (xy 31.89347 -396.113225) (xy 31.899979 -396.096031) (xy 31.900368 -396.086838)
			(xy 31.900368 -395.92885) (xy 31.900805 -395.918678) (xy 31.90858 -395.899879) (xy 31.922962 -395.885491)
			(xy 31.941758 -395.877709) (xy 31.95193 -395.877288) (xy 32.66821 -395.877288) (xy 32.678388 -395.877657)
			(xy 32.697193 -395.885455) (xy 32.711579 -395.899858) (xy 32.719355 -395.918671) (xy 32.719772 -395.92885)
			(xy 32.719772 -396.086838) (xy 32.72017 -396.096026) (xy 32.726693 -396.11321) (xy 32.732472 -396.120366)
			(xy 32.75425 -396.146026) (xy 32.792198 -396.201612) (xy 32.823231 -396.261334) (xy 32.846904 -396.324338)
			(xy 32.862877 -396.389719) (xy 32.870922 -396.45654) (xy 32.870923 -396.523845) (xy 32.86288 -396.590666)
			(xy 32.846909 -396.656048) (xy 32.823237 -396.719052) (xy 32.792206 -396.778775) (xy 32.754259 -396.834362)
			(xy 32.732472 -396.860014) (xy 32.726683 -396.867165) (xy 32.720165 -396.884351) (xy 32.719772 -396.893542)
			(xy 32.719772 -397.38681) (xy 32.720183 -397.395997) (xy 32.726697 -397.413181) (xy 32.732472 -397.420338)
			(xy 32.754222 -397.446021) (xy 32.792171 -397.501603) (xy 32.820593 -397.556296) (xy 33.948839 -397.556296)
			(xy 33.956914 -397.489358) (xy 33.972949 -397.423869) (xy 33.996713 -397.360773) (xy 34.027863 -397.300977)
			(xy 34.065952 -397.245343) (xy 34.087816 -397.219678) (xy 34.093606 -397.212528) (xy 34.100124 -397.195341)
			(xy 34.100516 -397.18615) (xy 34.100516 -397.028924) (xy 34.100936 -397.018801) (xy 34.108679 -397.000095)
			(xy 34.122995 -396.985779) (xy 34.141701 -396.978036) (xy 34.151824 -396.977616) (xy 34.868104 -396.977616)
			(xy 34.878229 -396.978013) (xy 34.896935 -396.985766) (xy 34.91125 -397.000088) (xy 34.918992 -397.018799)
			(xy 34.919412 -397.028924) (xy 34.919412 -397.18615) (xy 34.919843 -397.195335) (xy 34.926342 -397.21252)
			(xy 34.932112 -397.219678) (xy 34.953985 -397.245335) (xy 34.992073 -397.300971) (xy 35.023223 -397.360769)
			(xy 35.046986 -397.423867) (xy 35.06302 -397.489356) (xy 35.071095 -397.556295) (xy 35.071094 -397.62372)
			(xy 35.063017 -397.690658) (xy 35.046981 -397.756148) (xy 35.023216 -397.819245) (xy 35.020799 -397.823884)
			(xy 36.148967 -397.823884) (xy 36.148971 -397.756458) (xy 36.15705 -397.689518) (xy 36.173088 -397.624028)
			(xy 36.196855 -397.560929) (xy 36.228008 -397.501132) (xy 36.266099 -397.445496) (xy 36.287964 -397.41983)
			(xy 36.293781 -397.412699) (xy 36.300282 -397.395497) (xy 36.300664 -397.386302) (xy 36.300664 -396.89405)
			(xy 36.300216 -396.884867) (xy 36.293727 -396.867683) (xy 36.287964 -396.860522) (xy 36.266091 -396.834864)
			(xy 36.228005 -396.779228) (xy 36.196857 -396.71943) (xy 36.173095 -396.656332) (xy 36.157061 -396.590843)
			(xy 36.148987 -396.523904) (xy 36.148988 -396.456481) (xy 36.157064 -396.389542) (xy 36.1731 -396.324053)
			(xy 36.196863 -396.260956) (xy 36.228013 -396.201159) (xy 36.266101 -396.145524) (xy 36.287964 -396.119858)
			(xy 36.293769 -396.112719) (xy 36.300277 -396.095523) (xy 36.300664 -396.08633) (xy 36.300664 -395.92885)
			(xy 36.301168 -395.918724) (xy 36.308884 -395.899999) (xy 36.323166 -395.88564) (xy 36.341848 -395.877823)
			(xy 36.351972 -395.877288) (xy 37.068252 -395.877288) (xy 37.078402 -395.877761) (xy 37.097151 -395.885538)
			(xy 37.111475 -395.899919) (xy 37.119179 -395.918699) (xy 37.11956 -395.92885) (xy 37.11956 -396.08633)
			(xy 37.119965 -396.095518) (xy 37.126483 -396.112701) (xy 37.13226 -396.119858) (xy 37.154116 -396.145531)
			(xy 37.192207 -396.201163) (xy 37.223361 -396.260958) (xy 37.247127 -396.324054) (xy 37.263164 -396.389543)
			(xy 37.271242 -396.456481) (xy 37.271243 -396.523904) (xy 37.263167 -396.590843) (xy 37.247132 -396.656332)
			(xy 37.223367 -396.719428) (xy 37.192215 -396.779224) (xy 37.154125 -396.834857) (xy 37.13226 -396.860522)
			(xy 37.126467 -396.867669) (xy 37.119951 -396.884858) (xy 37.11956 -396.89405) (xy 37.11956 -397.386302)
			(xy 37.119978 -397.395488) (xy 37.126487 -397.412672) (xy 37.13226 -397.41983) (xy 37.154088 -397.445525)
			(xy 37.192181 -397.501155) (xy 37.220943 -397.556356) (xy 38.349159 -397.556356) (xy 38.357201 -397.489534)
			(xy 38.373172 -397.424153) (xy 38.396842 -397.361149) (xy 38.427873 -397.301426) (xy 38.465818 -397.245839)
			(xy 38.487604 -397.220186) (xy 38.493389 -397.213033) (xy 38.499911 -397.195848) (xy 38.500304 -397.186658)
			(xy 38.500304 -397.028924) (xy 38.500741 -397.018771) (xy 38.50853 -397.000018) (xy 38.522922 -396.985694)
			(xy 38.541711 -396.977994) (xy 38.551866 -396.977616) (xy 39.268146 -396.977616) (xy 39.278273 -396.978088)
			(xy 39.29699 -396.985827) (xy 39.311344 -397.000117) (xy 39.319166 -397.0188) (xy 39.319708 -397.028924)
			(xy 39.319708 -397.186658) (xy 39.320136 -397.195843) (xy 39.326637 -397.213028) (xy 39.332408 -397.220186)
			(xy 39.354207 -397.245829) (xy 39.392159 -397.301416) (xy 39.423195 -397.36114) (xy 39.446869 -397.424146)
			(xy 39.462843 -397.48953) (xy 39.470887 -397.556354) (xy 39.470887 -397.623661) (xy 39.462841 -397.690485)
			(xy 39.446865 -397.755869) (xy 39.423189 -397.818874) (xy 39.420585 -397.823885) (xy 40.548734 -397.823885)
			(xy 40.548737 -397.756458) (xy 40.556817 -397.689516) (xy 40.572859 -397.624024) (xy 40.596629 -397.560925)
			(xy 40.627787 -397.501128) (xy 40.665884 -397.445494) (xy 40.687752 -397.41983) (xy 40.693567 -397.412698)
			(xy 40.700069 -397.395497) (xy 40.700452 -397.386302) (xy 40.700452 -396.89405) (xy 40.700006 -396.884867)
			(xy 40.693516 -396.867683) (xy 40.687752 -396.860522) (xy 40.665876 -396.834866) (xy 40.627785 -396.779231)
			(xy 40.596631 -396.719434) (xy 40.572865 -396.656336) (xy 40.556829 -396.590845) (xy 40.548753 -396.523905)
			(xy 40.548754 -396.45648) (xy 40.556832 -396.38954) (xy 40.57287 -396.32405) (xy 40.596638 -396.260952)
			(xy 40.627792 -396.201156) (xy 40.665886 -396.145522) (xy 40.687752 -396.119858) (xy 40.693555 -396.112718)
			(xy 40.700065 -396.095523) (xy 40.700452 -396.08633) (xy 40.700452 -395.92885) (xy 40.700968 -395.918725)
			(xy 40.708682 -395.900003) (xy 40.722959 -395.885644) (xy 40.741638 -395.877825) (xy 40.75176 -395.877288)
			(xy 41.46804 -395.877288) (xy 41.478195 -395.877689) (xy 41.496946 -395.885495) (xy 41.511268 -395.899898)
			(xy 41.518968 -395.918693) (xy 41.519348 -395.92885) (xy 41.519348 -396.08633) (xy 41.519755 -396.095517)
			(xy 41.526272 -396.112701) (xy 41.532048 -396.119858) (xy 41.553904 -396.14553) (xy 41.591996 -396.201163)
			(xy 41.62315 -396.260957) (xy 41.646917 -396.324053) (xy 41.662955 -396.389542) (xy 41.671033 -396.456481)
			(xy 41.671034 -396.523904) (xy 41.662958 -396.590843) (xy 41.646922 -396.656332) (xy 41.623157 -396.719429)
			(xy 41.592004 -396.779224) (xy 41.553913 -396.834858) (xy 41.532048 -396.860522) (xy 41.526253 -396.867668)
			(xy 41.519739 -396.884858) (xy 41.519348 -396.89405) (xy 41.519348 -397.386302) (xy 41.519769 -397.395488)
			(xy 41.526276 -397.412672) (xy 41.532048 -397.41983) (xy 41.553876 -397.445525) (xy 41.59197 -397.501154)
			(xy 41.620702 -397.556296) (xy 42.748927 -397.556296) (xy 42.757002 -397.489358) (xy 42.773037 -397.42387)
			(xy 42.7968 -397.360774) (xy 42.827949 -397.300978) (xy 42.866037 -397.245343) (xy 42.8879 -397.219678)
			(xy 42.893688 -397.212527) (xy 42.900208 -397.195341) (xy 42.9006 -397.18615) (xy 42.9006 -397.028924)
			(xy 42.901035 -397.018803) (xy 42.908776 -397.0001) (xy 42.923086 -396.985785) (xy 42.941787 -396.978039)
			(xy 42.951908 -396.977616) (xy 43.668188 -396.977616) (xy 43.678312 -396.978026) (xy 43.697018 -396.985773)
			(xy 43.711333 -397.000092) (xy 43.719076 -397.0188) (xy 43.719496 -397.028924) (xy 43.719496 -397.18615)
			(xy 43.719931 -397.195335) (xy 43.726427 -397.212519) (xy 43.732196 -397.219678) (xy 43.75407 -397.245335)
			(xy 43.792159 -397.300971) (xy 43.823309 -397.360768) (xy 43.847073 -397.423866) (xy 43.863108 -397.489356)
			(xy 43.871183 -397.556295) (xy 43.871182 -397.62372) (xy 43.863105 -397.690659) (xy 43.847068 -397.756148)
			(xy 43.823303 -397.819246) (xy 43.820917 -397.823825) (xy 44.949053 -397.823825) (xy 44.949057 -397.756517)
			(xy 44.957105 -397.689692) (xy 44.973082 -397.624308) (xy 44.996759 -397.561302) (xy 45.027796 -397.501577)
			(xy 45.06575 -397.44599) (xy 45.08754 -397.420338) (xy 45.09335 -397.413203) (xy 45.099856 -397.396004)
			(xy 45.10024 -397.38681) (xy 45.10024 -396.893542) (xy 45.0998 -396.884358) (xy 45.093306 -396.867174)
			(xy 45.08754 -396.860014) (xy 45.065742 -396.83437) (xy 45.027794 -396.778782) (xy 44.996761 -396.719058)
			(xy 44.973088 -396.656052) (xy 44.957116 -396.590669) (xy 44.949073 -396.523845) (xy 44.949074 -396.45654)
			(xy 44.957119 -396.389716) (xy 44.973093 -396.324333) (xy 44.996767 -396.261328) (xy 45.027801 -396.201605)
			(xy 45.065751 -396.146018) (xy 45.08754 -396.120366) (xy 45.093339 -396.113222) (xy 45.099851 -396.096031)
			(xy 45.10024 -396.086838) (xy 45.10024 -395.92885) (xy 45.100705 -395.918681) (xy 45.108474 -395.899887)
			(xy 45.122847 -395.885501) (xy 45.141634 -395.877714) (xy 45.151802 -395.877288) (xy 45.868082 -395.877288)
			(xy 45.878259 -395.87768) (xy 45.897063 -395.885468) (xy 45.91145 -395.899864) (xy 45.919227 -395.918673)
			(xy 45.919644 -395.92885) (xy 45.919644 -396.086838) (xy 45.920049 -396.096026) (xy 45.926568 -396.113209)
			(xy 45.932344 -396.120366) (xy 45.954122 -396.146026) (xy 45.992072 -396.201611) (xy 46.023107 -396.261333)
			(xy 46.046781 -396.324337) (xy 46.062755 -396.389718) (xy 46.070801 -396.45654) (xy 46.070801 -396.523845)
			(xy 46.062758 -396.590667) (xy 46.046786 -396.656049) (xy 46.023113 -396.719053) (xy 45.99208 -396.778776)
			(xy 45.954131 -396.834362) (xy 45.932344 -396.860014) (xy 45.926552 -396.867162) (xy 45.920036 -396.884351)
			(xy 45.919644 -396.893542) (xy 45.919644 -397.38681) (xy 45.920062 -397.395996) (xy 45.926572 -397.41318)
			(xy 45.932344 -397.420338) (xy 45.954095 -397.446021) (xy 45.992046 -397.501602) (xy 46.020501 -397.556355)
			(xy 47.149223 -397.556355) (xy 47.157267 -397.489532) (xy 47.17324 -397.42415) (xy 47.196914 -397.361146)
			(xy 47.227949 -397.301423) (xy 47.265899 -397.245837) (xy 47.287688 -397.220186) (xy 47.293472 -397.213032)
			(xy 47.299994 -397.195848) (xy 47.300388 -397.186658) (xy 47.300388 -397.028924) (xy 47.300841 -397.018773)
			(xy 47.308626 -397.000023) (xy 47.323013 -396.985699) (xy 47.341797 -396.977997) (xy 47.35195 -396.977616)
			(xy 48.06823 -396.977616) (xy 48.078356 -396.978101) (xy 48.097073 -396.985834) (xy 48.111427 -397.000121)
			(xy 48.11925 -397.018801) (xy 48.119792 -397.028924) (xy 48.119792 -397.186658) (xy 48.120224 -397.195843)
			(xy 48.126723 -397.213027) (xy 48.132492 -397.220186) (xy 48.154289 -397.24583) (xy 48.192235 -397.301419)
			(xy 48.223266 -397.361144) (xy 48.246937 -397.424149) (xy 48.262908 -397.489532) (xy 48.270951 -397.556355)
			(xy 48.27095 -397.62366) (xy 48.262906 -397.690483) (xy 48.246933 -397.755865) (xy 48.22326 -397.81887)
			(xy 48.192227 -397.878594) (xy 48.154279 -397.934181) (xy 48.132492 -397.959834) (xy 48.126698 -397.966981)
			(xy 48.120182 -397.98417) (xy 48.119792 -397.993362) (xy 48.119792 -398.486884) (xy 48.120212 -398.49607)
			(xy 48.126719 -398.513254) (xy 48.132492 -398.520412) (xy 48.154314 -398.546035) (xy 48.19226 -398.601627)
			(xy 48.22329 -398.661355) (xy 48.246959 -398.724363) (xy 48.262929 -398.789748) (xy 48.27097 -398.856573)
			(xy 48.270966 -398.923881) (xy 48.262919 -398.990705) (xy 48.246943 -399.056089) (xy 48.223268 -399.119095)
			(xy 48.192232 -399.17882) (xy 48.154281 -399.234407) (xy 48.132492 -399.26006) (xy 48.126687 -399.267199)
			(xy 48.120177 -399.284394) (xy 48.119792 -399.293588) (xy 48.119792 -399.451576) (xy 48.119359 -399.46173)
			(xy 48.11157 -399.480483) (xy 48.097176 -399.494808) (xy 48.078386 -399.502507) (xy 48.06823 -399.502884)
			(xy 47.35195 -399.502884) (xy 47.341829 -399.502333) (xy 47.323114 -399.494626) (xy 47.308757 -399.48036)
			(xy 47.300932 -399.461693) (xy 47.300388 -399.451576) (xy 47.300388 -399.293588) (xy 47.299986 -399.2844)
			(xy 47.293467 -399.267216) (xy 47.287688 -399.26006) (xy 47.265934 -399.234379) (xy 47.227981 -399.178798)
			(xy 47.196944 -399.119079) (xy 47.173267 -399.056078) (xy 47.15729 -398.990699) (xy 47.149242 -398.923879)
			(xy 47.149239 -398.856576) (xy 47.15728 -398.789754) (xy 47.173251 -398.724374) (xy 47.196921 -398.661371)
			(xy 47.227953 -398.601648) (xy 47.265901 -398.546063) (xy 47.287688 -398.520412) (xy 47.293503 -398.51328)
			(xy 47.300007 -398.496079) (xy 47.300388 -398.486884) (xy 47.300388 -397.993362) (xy 47.299999 -397.984172)
			(xy 47.293471 -397.966988) (xy 47.287688 -397.959834) (xy 47.265909 -397.934174) (xy 47.227956 -397.87859)
			(xy 47.19692 -397.818868) (xy 47.173244 -397.755864) (xy 47.157269 -397.690483) (xy 47.149224 -397.62366)
			(xy 47.149223 -397.556355) (xy 46.020501 -397.556355) (xy 46.023082 -397.561322) (xy 46.046757 -397.624322)
			(xy 46.062733 -397.689701) (xy 46.070781 -397.75652) (xy 46.070784 -397.823823) (xy 46.062744 -397.890643)
			(xy 46.046774 -397.956023) (xy 46.023105 -398.019026) (xy 45.992075 -398.078748) (xy 45.95413 -398.134334)
			(xy 45.932344 -398.159986) (xy 45.926522 -398.167113) (xy 45.920024 -398.184318) (xy 45.919644 -398.193514)
			(xy 45.919644 -398.351502) (xy 45.919237 -398.361676) (xy 45.911448 -398.380474) (xy 45.897057 -398.39486)
			(xy 45.878256 -398.402641) (xy 45.868082 -398.403064) (xy 45.151802 -398.403064) (xy 45.141645 -398.402565)
			(xy 45.122876 -398.394792) (xy 45.108511 -398.380427) (xy 45.100736 -398.361659) (xy 45.10024 -398.351502)
			(xy 45.10024 -398.193514) (xy 45.099814 -398.184329) (xy 45.093311 -398.167145) (xy 45.08754 -398.159986)
			(xy 45.065715 -398.134365) (xy 45.027767 -398.078774) (xy 44.996735 -398.019046) (xy 44.973065 -397.956037)
			(xy 44.957094 -397.890651) (xy 44.949053 -397.823825) (xy 43.820917 -397.823825) (xy 43.792151 -397.879042)
			(xy 43.754061 -397.934677) (xy 43.732196 -397.960342) (xy 43.726399 -397.967487) (xy 43.719885 -397.984678)
			(xy 43.719496 -397.99387) (xy 43.719496 -398.486376) (xy 43.719919 -398.495562) (xy 43.726424 -398.512746)
			(xy 43.732196 -398.519904) (xy 43.754095 -398.54554) (xy 43.792183 -398.601179) (xy 43.823333 -398.660979)
			(xy 43.847095 -398.72408) (xy 43.863128 -398.789572) (xy 43.871201 -398.856514) (xy 43.871198 -398.92394)
			(xy 43.863118 -398.990881) (xy 43.847079 -399.056372) (xy 43.823311 -399.119471) (xy 43.792156 -399.179268)
			(xy 43.754062 -399.234903) (xy 43.732196 -399.260568) (xy 43.726388 -399.267705) (xy 43.71988 -399.284902)
			(xy 43.719496 -399.294096) (xy 43.719496 -399.451576) (xy 43.719064 -399.461697) (xy 43.711323 -399.480401)
			(xy 43.697011 -399.494717) (xy 43.678309 -399.502462) (xy 43.668188 -399.502884) (xy 42.951908 -399.502884)
			(xy 42.941784 -399.502477) (xy 42.923078 -399.494729) (xy 42.908762 -399.480409) (xy 42.90102 -399.4617)
			(xy 42.9006 -399.451576) (xy 42.9006 -399.294096) (xy 42.900192 -399.284909) (xy 42.893677 -399.267724)
			(xy 42.8879 -399.260568) (xy 42.866071 -399.234874) (xy 42.827982 -399.179243) (xy 42.796829 -399.119451)
			(xy 42.773063 -399.056358) (xy 42.757025 -398.990872) (xy 42.748946 -398.923937) (xy 42.748943 -398.856517)
			(xy 42.757015 -398.789581) (xy 42.773047 -398.724094) (xy 42.796807 -398.660998) (xy 42.827954 -398.601203)
			(xy 42.866038 -398.545569) (xy 42.8879 -398.519904) (xy 42.893677 -398.512745) (xy 42.900204 -398.495565)
			(xy 42.9006 -398.486376) (xy 42.9006 -397.99387) (xy 42.900204 -397.984681) (xy 42.893681 -397.967497)
			(xy 42.8879 -397.960342) (xy 42.866046 -397.934669) (xy 42.827957 -397.879035) (xy 42.796806 -397.81924)
			(xy 42.773041 -397.756144) (xy 42.757005 -397.690656) (xy 42.748928 -397.623719) (xy 42.748927 -397.556296)
			(xy 41.620702 -397.556296) (xy 41.623125 -397.560946) (xy 41.646894 -397.624039) (xy 41.662933 -397.689525)
			(xy 41.671013 -397.756461) (xy 41.671016 -397.823882) (xy 41.662944 -397.890819) (xy 41.646911 -397.956307)
			(xy 41.623148 -398.019402) (xy 41.591999 -398.079197) (xy 41.553912 -398.13483) (xy 41.532048 -398.160494)
			(xy 41.526265 -398.167649) (xy 41.519744 -398.184832) (xy 41.519348 -398.194022) (xy 41.519348 -398.351502)
			(xy 41.518875 -398.36163) (xy 41.511144 -398.380354) (xy 41.496853 -398.39471) (xy 41.478166 -398.402527)
			(xy 41.46804 -398.403064) (xy 40.75176 -398.403064) (xy 40.741599 -398.40271) (xy 40.722839 -398.394895)
			(xy 40.708515 -398.380477) (xy 40.700824 -398.361666) (xy 40.700452 -398.351502) (xy 40.700452 -398.194022)
			(xy 40.70002 -398.184837) (xy 40.69352 -398.167653) (xy 40.687752 -398.160494) (xy 40.665849 -398.13486)
			(xy 40.627758 -398.079223) (xy 40.596606 -398.019423) (xy 40.572842 -397.956321) (xy 40.556807 -397.890828)
			(xy 40.548734 -397.823885) (xy 39.420585 -397.823885) (xy 39.392151 -397.878597) (xy 39.354198 -397.934183)
			(xy 39.332408 -397.959834) (xy 39.326615 -397.966982) (xy 39.320098 -397.98417) (xy 39.319708 -397.993362)
			(xy 39.319708 -398.486884) (xy 39.320124 -398.496071) (xy 39.326633 -398.513255) (xy 39.332408 -398.520412)
			(xy 39.354233 -398.546034) (xy 39.392184 -398.601624) (xy 39.423219 -398.661351) (xy 39.446892 -398.72436)
			(xy 39.462864 -398.789746) (xy 39.470906 -398.856573) (xy 39.470902 -398.923882) (xy 39.462854 -398.990707)
			(xy 39.446876 -399.056092) (xy 39.423196 -399.119098) (xy 39.392156 -399.178823) (xy 39.354199 -399.234409)
			(xy 39.332408 -399.26006) (xy 39.326604 -399.2672) (xy 39.320094 -399.284395) (xy 39.319708 -399.293588)
			(xy 39.319708 -399.451576) (xy 39.319259 -399.461728) (xy 39.311473 -399.480478) (xy 39.297085 -399.494802)
			(xy 39.278299 -399.502504) (xy 39.268146 -399.502884) (xy 38.551866 -399.502884) (xy 38.54174 -399.502402)
			(xy 38.523023 -399.494668) (xy 38.508668 -399.48038) (xy 38.500846 -399.4617) (xy 38.500304 -399.451576)
			(xy 38.500304 -399.293588) (xy 38.499899 -399.2844) (xy 38.493381 -399.267216) (xy 38.487604 -399.26006)
			(xy 38.465853 -399.234378) (xy 38.427905 -399.178795) (xy 38.396872 -399.119075) (xy 38.373199 -399.056075)
			(xy 38.357224 -398.990697) (xy 38.349178 -398.923878) (xy 38.349175 -398.856576) (xy 38.357215 -398.789757)
			(xy 38.373183 -398.724377) (xy 38.39685 -398.661374) (xy 38.427877 -398.601651) (xy 38.465819 -398.546065)
			(xy 38.487604 -398.520412) (xy 38.493421 -398.513281) (xy 38.499923 -398.49608) (xy 38.500304 -398.486884)
			(xy 38.500304 -397.993362) (xy 38.499911 -397.984173) (xy 38.493385 -397.966989) (xy 38.487604 -397.959834)
			(xy 38.465827 -397.934173) (xy 38.42788 -397.878587) (xy 38.396849 -397.818865) (xy 38.373177 -397.755861)
			(xy 38.357204 -397.69048) (xy 38.34916 -397.623659) (xy 38.349159 -397.556356) (xy 37.220943 -397.556356)
			(xy 37.223335 -397.560946) (xy 37.247103 -397.624039) (xy 37.263142 -397.689525) (xy 37.271222 -397.756461)
			(xy 37.271225 -397.823882) (xy 37.263153 -397.890819) (xy 37.24712 -397.956306) (xy 37.223358 -398.019402)
			(xy 37.19221 -398.079196) (xy 37.154123 -398.134829) (xy 37.13226 -398.160494) (xy 37.126478 -398.16765)
			(xy 37.119956 -398.184832) (xy 37.11956 -398.194022) (xy 37.11956 -398.351502) (xy 37.119075 -398.361629)
			(xy 37.111347 -398.38035) (xy 37.09706 -398.394706) (xy 37.078376 -398.402525) (xy 37.068252 -398.403064)
			(xy 36.351972 -398.403064) (xy 36.341812 -398.402701) (xy 36.323052 -398.394889) (xy 36.308728 -398.380474)
			(xy 36.301036 -398.361665) (xy 36.300664 -398.351502) (xy 36.300664 -398.194022) (xy 36.300229 -398.184838)
			(xy 36.293731 -398.167654) (xy 36.287964 -398.160494) (xy 36.266064 -398.134859) (xy 36.227979 -398.079219)
			(xy 36.196832 -398.019419) (xy 36.173071 -397.956318) (xy 36.15704 -397.890825) (xy 36.148967 -397.823884)
			(xy 35.020799 -397.823884) (xy 34.992065 -397.879042) (xy 34.953976 -397.934677) (xy 34.932112 -397.960342)
			(xy 34.926316 -397.967488) (xy 34.919801 -397.984678) (xy 34.919412 -397.99387) (xy 34.919412 -398.486376)
			(xy 34.919831 -398.495562) (xy 34.926338 -398.512747) (xy 34.932112 -398.519904) (xy 34.954011 -398.54554)
			(xy 34.992098 -398.601179) (xy 35.023246 -398.66098) (xy 35.047008 -398.72408) (xy 35.06304 -398.789573)
			(xy 35.071113 -398.856514) (xy 35.07111 -398.92394) (xy 35.063031 -398.990881) (xy 35.046992 -399.056372)
			(xy 35.023224 -399.11947) (xy 34.99207 -399.179267) (xy 34.953978 -399.234903) (xy 34.932112 -399.260568)
			(xy 34.926305 -399.267706) (xy 34.919796 -399.284902) (xy 34.919412 -399.294096) (xy 34.919412 -399.451576)
			(xy 34.918965 -399.461695) (xy 34.911227 -399.480396) (xy 34.89692 -399.494711) (xy 34.878223 -399.502459)
			(xy 34.868104 -399.502884) (xy 34.151824 -399.502884) (xy 34.141701 -399.502464) (xy 34.122995 -399.494721)
			(xy 34.108679 -399.480405) (xy 34.100936 -399.461699) (xy 34.100516 -399.451576) (xy 34.100516 -399.294096)
			(xy 34.100104 -399.284909) (xy 34.093591 -399.267725) (xy 34.087816 -399.260568) (xy 34.065987 -399.234874)
			(xy 34.027896 -399.179244) (xy 33.996743 -399.119452) (xy 33.972976 -399.056359) (xy 33.956937 -398.990873)
			(xy 33.948858 -398.923938) (xy 33.948855 -398.856516) (xy 33.956928 -398.78958) (xy 33.97296 -398.724093)
			(xy 33.996721 -398.660998) (xy 34.027868 -398.601203) (xy 34.065954 -398.545569) (xy 34.087816 -398.519904)
			(xy 34.093595 -398.512747) (xy 34.10012 -398.495565) (xy 34.100516 -398.486376) (xy 34.100516 -397.99387)
			(xy 34.100117 -397.984682) (xy 34.093595 -397.967498) (xy 34.087816 -397.960342) (xy 34.065961 -397.934669)
			(xy 34.027871 -397.879036) (xy 33.996719 -397.819241) (xy 33.972954 -397.756145) (xy 33.956917 -397.690657)
			(xy 33.94884 -397.623719) (xy 33.948839 -397.556296) (xy 32.820593 -397.556296) (xy 32.823205 -397.561323)
			(xy 32.84688 -397.624323) (xy 32.862855 -397.689702) (xy 32.870902 -397.756521) (xy 32.870905 -397.823822)
			(xy 32.862865 -397.890642) (xy 32.846897 -397.956022) (xy 32.823229 -398.019025) (xy 32.7922 -398.078747)
			(xy 32.754257 -398.134334) (xy 32.732472 -398.159986) (xy 32.726653 -398.167115) (xy 32.720152 -398.184318)
			(xy 32.719772 -398.193514) (xy 32.719772 -398.351502) (xy 32.719268 -398.361659) (xy 32.711495 -398.380426)
			(xy 32.697133 -398.394791) (xy 32.678367 -398.402567) (xy 32.66821 -398.403064) (xy 31.95193 -398.403064)
			(xy 31.941761 -398.402611) (xy 31.922967 -398.394837) (xy 31.908581 -398.38046) (xy 31.900795 -398.361671)
			(xy 31.900368 -398.351502) (xy 31.900368 -398.193514) (xy 31.899936 -398.184329) (xy 31.893436 -398.167146)
			(xy 31.887668 -398.159986) (xy 31.865842 -398.134365) (xy 31.827892 -398.078775) (xy 31.796859 -398.019047)
			(xy 31.773187 -397.956039) (xy 31.757216 -397.890652) (xy 31.749174 -397.823826) (xy 30.620528 -397.823826)
			(xy 30.592066 -397.878596) (xy 30.554113 -397.934182) (xy 30.532324 -397.959834) (xy 30.526533 -397.966984)
			(xy 30.520014 -397.984171) (xy 30.519624 -397.993362) (xy 30.519624 -398.486884) (xy 30.520036 -398.496071)
			(xy 30.526548 -398.513256) (xy 30.532324 -398.520412) (xy 30.554149 -398.546034) (xy 30.592099 -398.601624)
			(xy 30.623132 -398.661352) (xy 30.646805 -398.72436) (xy 30.662776 -398.789746) (xy 30.670818 -398.856573)
			(xy 30.670815 -398.923881) (xy 30.662767 -398.990707) (xy 30.646789 -399.056092) (xy 30.62311 -399.119098)
			(xy 30.592071 -399.178822) (xy 30.554115 -399.234409) (xy 30.532324 -399.26006) (xy 30.526522 -399.267202)
			(xy 30.52001 -399.284395) (xy 30.519624 -399.293588) (xy 30.519624 -399.451576) (xy 30.519159 -399.461726)
			(xy 30.511376 -399.480473) (xy 30.496993 -399.494796) (xy 30.478213 -399.502501) (xy 30.468062 -399.502884)
			(xy 29.751782 -399.502884) (xy 29.741657 -399.502389) (xy 29.72294 -399.49466) (xy 29.708585 -399.480377)
			(xy 29.700762 -399.461698) (xy 29.70022 -399.451576) (xy 29.70022 -399.293588) (xy 29.699811 -399.284401)
			(xy 29.693296 -399.267217) (xy 29.68752 -399.26006) (xy 29.665769 -399.234378) (xy 29.62782 -399.178796)
			(xy 29.596786 -399.119076) (xy 29.573112 -399.056075) (xy 29.557137 -398.990697) (xy 29.549091 -398.923878)
			(xy 29.549087 -398.856576) (xy 29.557128 -398.789756) (xy 29.573096 -398.724376) (xy 29.596764 -398.661374)
			(xy 29.627792 -398.601651) (xy 29.665735 -398.546065) (xy 29.68752 -398.520412) (xy 29.693339 -398.513283)
			(xy 29.69984 -398.49608) (xy 29.70022 -398.486884) (xy 29.70022 -397.993362) (xy 29.699824 -397.984173)
			(xy 29.6933 -397.966989) (xy 29.68752 -397.959834) (xy 29.665743 -397.934174) (xy 29.627795 -397.878588)
			(xy 29.596762 -397.818865) (xy 29.57309 -397.755862) (xy 29.557116 -397.690481) (xy 29.549072 -397.623659)
			(xy 29.549071 -397.556356) (xy 28.420857 -397.556356) (xy 28.423249 -397.560947) (xy 28.447016 -397.62404)
			(xy 28.463055 -397.689526) (xy 28.471134 -397.756461) (xy 28.471138 -397.823882) (xy 28.463065 -397.890818)
			(xy 28.447033 -397.956305) (xy 28.423272 -398.019401) (xy 28.392124 -398.079196) (xy 28.354039 -398.134829)
			(xy 28.332176 -398.160494) (xy 28.326397 -398.167651) (xy 28.319873 -398.184833) (xy 28.319476 -398.194022)
			(xy 28.319476 -398.351502) (xy 28.318975 -398.361627) (xy 28.31125 -398.380345) (xy 28.296968 -398.394701)
			(xy 28.27829 -398.402523) (xy 28.268168 -398.403064) (xy 27.551888 -398.403064) (xy 27.541729 -398.402688)
			(xy 27.522969 -398.394881) (xy 27.508645 -398.38047) (xy 27.500952 -398.361664) (xy 27.50058 -398.351502)
			(xy 27.50058 -398.194022) (xy 27.500164 -398.184835) (xy 27.493655 -398.167651) (xy 27.48788 -398.160494)
			(xy 27.465979 -398.134859) (xy 27.427893 -398.07922) (xy 27.396745 -398.019419) (xy 27.372984 -397.956318)
			(xy 27.356952 -397.890826) (xy 27.348879 -397.823885) (xy 8.839736 -397.823885) (xy 8.850142 -397.906253)
			(xy 8.858264 -398.035359) (xy 8.858264 -398.164721) (xy 8.850142 -398.293827) (xy 8.833928 -398.422169)
			(xy 8.809688 -398.549239) (xy 8.777518 -398.674536) (xy 8.737543 -398.797566) (xy 8.689921 -398.917844)
			(xy 8.634842 -399.034893) (xy 8.572521 -399.148254) (xy 8.503206 -399.257477) (xy 8.427169 -399.362133)
			(xy 8.344711 -399.461808) (xy 8.256157 -399.556108) (xy 8.161856 -399.644662) (xy 8.062181 -399.72712)
			(xy 7.957526 -399.803157) (xy 7.848302 -399.872472) (xy 7.734942 -399.934793) (xy 7.617892 -399.989872)
			(xy 7.497614 -400.037493) (xy 7.374584 -400.077468) (xy 7.249287 -400.109639) (xy 7.122217 -400.133879)
			(xy 6.993875 -400.150092) (xy 6.864769 -400.158214) (xy 6.800088 -400.158712) (xy 5.199888 -400.158712)
			(xy 5.135208 -400.158204) (xy 5.006102 -400.150081) (xy 4.877762 -400.133868) (xy 4.750692 -400.109628)
			(xy 4.625396 -400.077458) (xy 4.502366 -400.037483) (xy 4.38209 -399.989862) (xy 4.265041 -399.934783)
			(xy 4.151681 -399.872463) (xy 4.042458 -399.803148) (xy 3.937803 -399.727112) (xy 3.838129 -399.644654)
			(xy 3.743829 -399.556101) (xy 3.655276 -399.461801) (xy 3.572818 -399.362127) (xy 3.496782 -399.257472)
			(xy 3.427467 -399.148249) (xy 3.365147 -399.034889) (xy 3.310068 -398.91784) (xy 3.262447 -398.797564)
			(xy 3.222472 -398.674534) (xy 3.190302 -398.549238) (xy 3.166062 -398.422168) (xy 3.149849 -398.293828)
			(xy 3.141726 -398.164722) (xy 0.508 -398.164722) (xy 0.508 -401.723796) (xy 27.348891 -401.723796)
			(xy 27.348893 -401.656371) (xy 27.35697 -401.589432) (xy 27.373007 -401.523942) (xy 27.396773 -401.460844)
			(xy 27.427925 -401.401047) (xy 27.466015 -401.345412) (xy 27.48788 -401.319746) (xy 27.49368 -401.312603)
			(xy 27.500193 -401.295411) (xy 27.50058 -401.286218) (xy 27.50058 -400.793966) (xy 27.500191 -400.784777)
			(xy 27.493663 -400.767592) (xy 27.48788 -400.760438) (xy 27.466023 -400.734768) (xy 27.427935 -400.679133)
			(xy 27.396785 -400.619338) (xy 27.373022 -400.556241) (xy 27.356986 -400.490753) (xy 27.34891 -400.423816)
			(xy 27.34891 -400.356393) (xy 27.356985 -400.289456) (xy 27.373019 -400.223967) (xy 27.396782 -400.160871)
			(xy 27.42793 -400.101074) (xy 27.466017 -400.04544) (xy 27.48788 -400.019774) (xy 27.493668 -400.012622)
			(xy 27.500188 -399.995437) (xy 27.50058 -399.986246) (xy 27.50058 -399.828766) (xy 27.501 -399.818632)
			(xy 27.508746 -399.799903) (xy 27.523053 -399.785546) (xy 27.541756 -399.777735) (xy 27.551888 -399.777204)
			(xy 28.268168 -399.777204) (xy 28.278321 -399.777648) (xy 28.297073 -399.785433) (xy 28.311398 -399.799824)
			(xy 28.319098 -399.818612) (xy 28.319476 -399.828766) (xy 28.319476 -399.986246) (xy 28.319918 -399.99543)
			(xy 28.32641 -400.012614) (xy 28.332176 -400.019774) (xy 28.354047 -400.045434) (xy 28.392137 -400.101069)
			(xy 28.423289 -400.160865) (xy 28.447053 -400.223963) (xy 28.463089 -400.289453) (xy 28.471165 -400.356392)
			(xy 28.471165 -400.423817) (xy 28.463088 -400.490756) (xy 28.447051 -400.556246) (xy 28.423285 -400.619343)
			(xy 28.392132 -400.679139) (xy 28.354041 -400.734773) (xy 28.332176 -400.760438) (xy 28.326378 -400.767582)
			(xy 28.319865 -400.784774) (xy 28.319476 -400.793966) (xy 28.319476 -401.286218) (xy 28.319883 -401.295405)
			(xy 28.326399 -401.31259) (xy 28.332176 -401.319746) (xy 28.354019 -401.345429) (xy 28.39211 -401.40106)
			(xy 28.423263 -401.460854) (xy 28.446989 -401.523838) (xy 29.549051 -401.523838) (xy 29.549053 -401.456532)
			(xy 29.557098 -401.389708) (xy 29.573073 -401.324325) (xy 29.596747 -401.26132) (xy 29.627782 -401.201596)
			(xy 29.665732 -401.146008) (xy 29.68752 -401.120356) (xy 29.69332 -401.113213) (xy 29.699832 -401.096021)
			(xy 29.70022 -401.086828) (xy 29.70022 -400.92884) (xy 29.700655 -400.918686) (xy 29.708441 -400.899931)
			(xy 29.722834 -400.885605) (xy 29.741626 -400.877908) (xy 29.751782 -400.877532) (xy 30.468062 -400.877532)
			(xy 30.478185 -400.878058) (xy 30.496904 -400.885771) (xy 30.511261 -400.900046) (xy 30.519083 -400.91872)
			(xy 30.519624 -400.92884) (xy 30.519624 -401.086828) (xy 30.520015 -401.096017) (xy 30.526542 -401.113202)
			(xy 30.532324 -401.120356) (xy 30.554093 -401.146024) (xy 30.592045 -401.201607) (xy 30.623081 -401.261328)
			(xy 30.646757 -401.324331) (xy 30.662732 -401.389711) (xy 30.670778 -401.456533) (xy 30.67078 -401.523837)
			(xy 30.662738 -401.590659) (xy 30.646766 -401.65604) (xy 30.623093 -401.719044) (xy 30.620654 -401.723737)
			(xy 31.749186 -401.723737) (xy 31.749188 -401.65643) (xy 31.757235 -401.589605) (xy 31.773211 -401.524221)
			(xy 31.796887 -401.461216) (xy 31.827925 -401.401492) (xy 31.865878 -401.345906) (xy 31.887668 -401.320254)
			(xy 31.893475 -401.313116) (xy 31.899981 -401.29592) (xy 31.900368 -401.286726) (xy 31.900368 -400.793458)
			(xy 31.899963 -400.784271) (xy 31.893444 -400.767087) (xy 31.887668 -400.75993) (xy 31.865885 -400.734273)
			(xy 31.827935 -400.678688) (xy 31.796899 -400.618966) (xy 31.773225 -400.555962) (xy 31.757251 -400.49058)
			(xy 31.749206 -400.423757) (xy 31.749205 -400.356452) (xy 31.757249 -400.289629) (xy 31.773222 -400.224247)
			(xy 31.796896 -400.161243) (xy 31.82793 -400.10152) (xy 31.86588 -400.045934) (xy 31.887668 -400.020282)
			(xy 31.893463 -400.013136) (xy 31.899977 -399.995946) (xy 31.900368 -399.986754) (xy 31.900368 -399.828766)
			(xy 31.900806 -399.818602) (xy 31.908597 -399.799827) (xy 31.92298 -399.785462) (xy 31.941766 -399.777694)
			(xy 31.95193 -399.777204) (xy 32.66821 -399.777204) (xy 32.678364 -399.777725) (xy 32.697127 -399.785496)
			(xy 32.711491 -399.799853) (xy 32.719271 -399.818612) (xy 32.719772 -399.828766) (xy 32.719772 -399.986754)
			(xy 32.720211 -399.995938) (xy 32.726705 -400.013122) (xy 32.732472 -400.020282) (xy 32.754265 -400.045929)
			(xy 32.792213 -400.101517) (xy 32.823246 -400.161241) (xy 32.846918 -400.224246) (xy 32.86289 -400.289629)
			(xy 32.870933 -400.356452) (xy 32.870933 -400.423757) (xy 32.862888 -400.49058) (xy 32.846915 -400.555962)
			(xy 32.823242 -400.618967) (xy 32.792209 -400.678691) (xy 32.75426 -400.734278) (xy 32.732472 -400.75993)
			(xy 32.726677 -400.767076) (xy 32.720162 -400.784266) (xy 32.719772 -400.793458) (xy 32.719772 -401.286726)
			(xy 32.720176 -401.295914) (xy 32.726695 -401.313098) (xy 32.732472 -401.320254) (xy 32.754237 -401.345924)
			(xy 32.792186 -401.401508) (xy 32.82322 -401.46123) (xy 32.846893 -401.524232) (xy 32.862868 -401.589612)
			(xy 32.870913 -401.656432) (xy 32.870915 -401.723735) (xy 32.862873 -401.790556) (xy 32.846903 -401.855937)
			(xy 32.823233 -401.91894) (xy 32.792203 -401.978663) (xy 32.754258 -402.03425) (xy 32.732472 -402.059902)
			(xy 32.726688 -402.067056) (xy 32.720167 -402.08424) (xy 32.719772 -402.09343) (xy 32.719772 -402.251418)
			(xy 32.719282 -402.261576) (xy 32.711503 -402.280343) (xy 32.697137 -402.294708) (xy 32.678368 -402.302483)
			(xy 32.66821 -402.30298) (xy 31.95193 -402.30298) (xy 31.941763 -402.302512) (xy 31.922972 -402.29474)
			(xy 31.908587 -402.280368) (xy 31.900798 -402.261585) (xy 31.900368 -402.251418) (xy 31.900368 -402.09343)
			(xy 31.899928 -402.084246) (xy 31.893434 -402.067062) (xy 31.887668 -402.059902) (xy 31.865858 -402.034268)
			(xy 31.827908 -401.97868) (xy 31.796874 -401.918954) (xy 31.773201 -401.855947) (xy 31.757229 -401.790562)
			(xy 31.749186 -401.723737) (xy 30.620654 -401.723737) (xy 30.59206 -401.778767) (xy 30.554112 -401.834352)
			(xy 30.532324 -401.860004) (xy 30.526546 -401.867163) (xy 30.520019 -401.884343) (xy 30.519624 -401.893532)
			(xy 30.519624 -402.3868) (xy 30.520029 -402.395988) (xy 30.526546 -402.413172) (xy 30.532324 -402.420328)
			(xy 30.554114 -402.445978) (xy 30.592063 -402.501565) (xy 30.623097 -402.561289) (xy 30.64677 -402.624293)
			(xy 30.662743 -402.689676) (xy 30.670787 -402.756499) (xy 30.670787 -402.823804) (xy 30.670778 -402.823878)
			(xy 33.948799 -402.823878) (xy 33.948804 -402.75645) (xy 33.956885 -402.689508) (xy 33.972926 -402.624016)
			(xy 33.996696 -402.560917) (xy 34.027853 -402.50112) (xy 34.065949 -402.445485) (xy 34.087816 -402.41982)
			(xy 34.093631 -402.412688) (xy 34.100134 -402.395487) (xy 34.100516 -402.386292) (xy 34.100516 -401.89404)
			(xy 34.100083 -401.884855) (xy 34.093585 -401.867671) (xy 34.087816 -401.860512) (xy 34.065932 -401.834863)
			(xy 34.027843 -401.779227) (xy 33.996692 -401.719428) (xy 33.972928 -401.656329) (xy 33.956894 -401.590838)
			(xy 33.948819 -401.523898) (xy 33.948821 -401.456472) (xy 33.956899 -401.389532) (xy 33.972937 -401.324042)
			(xy 33.996704 -401.260944) (xy 34.027858 -401.201147) (xy 34.06595 -401.145513) (xy 34.087816 -401.119848)
			(xy 34.093619 -401.112707) (xy 34.100129 -401.095513) (xy 34.100516 -401.08632) (xy 34.100516 -400.92884)
			(xy 34.100949 -400.918718) (xy 34.108687 -400.900012) (xy 34.122999 -400.885696) (xy 34.141702 -400.877952)
			(xy 34.151824 -400.877532) (xy 34.868104 -400.877532) (xy 34.878231 -400.877914) (xy 34.89694 -400.885669)
			(xy 34.911256 -400.899997) (xy 34.918995 -400.918713) (xy 34.919412 -400.92884) (xy 34.919412 -401.08632)
			(xy 34.91981 -401.095509) (xy 34.926332 -401.112693) (xy 34.932112 -401.119848) (xy 34.953956 -401.14553)
			(xy 34.992044 -401.201162) (xy 35.023195 -401.260956) (xy 35.04696 -401.324051) (xy 35.062997 -401.389538)
			(xy 35.071074 -401.456474) (xy 35.071076 -401.523896) (xy 35.063002 -401.590833) (xy 35.046969 -401.65632)
			(xy 35.023208 -401.719416) (xy 35.020926 -401.723796) (xy 36.148978 -401.723796) (xy 36.14898 -401.656371)
			(xy 36.157058 -401.589432) (xy 36.173095 -401.523942) (xy 36.19686 -401.460845) (xy 36.228011 -401.401047)
			(xy 36.2661 -401.345412) (xy 36.287964 -401.319746) (xy 36.293774 -401.312611) (xy 36.300279 -401.295412)
			(xy 36.300664 -401.286218) (xy 36.300664 -400.793966) (xy 36.300256 -400.784779) (xy 36.293739 -400.767595)
			(xy 36.287964 -400.760438) (xy 36.266107 -400.734767) (xy 36.228021 -400.679133) (xy 36.196872 -400.619337)
			(xy 36.173109 -400.556241) (xy 36.157074 -400.490753) (xy 36.148998 -400.423816) (xy 36.148998 -400.356393)
			(xy 36.157072 -400.289456) (xy 36.173106 -400.223968) (xy 36.196868 -400.160871) (xy 36.228016 -400.101075)
			(xy 36.266102 -400.04544) (xy 36.287964 -400.019774) (xy 36.293762 -400.01263) (xy 36.300274 -399.995438)
			(xy 36.300664 -399.986246) (xy 36.300664 -399.828766) (xy 36.301099 -399.818634) (xy 36.308843 -399.799908)
			(xy 36.323145 -399.785552) (xy 36.341842 -399.777738) (xy 36.351972 -399.777204) (xy 37.068252 -399.777204)
			(xy 37.078404 -399.777661) (xy 37.097156 -399.785442) (xy 37.111481 -399.799828) (xy 37.119181 -399.818613)
			(xy 37.11956 -399.828766) (xy 37.11956 -399.986246) (xy 37.120005 -399.995429) (xy 37.126496 -400.012613)
			(xy 37.13226 -400.019774) (xy 37.154131 -400.045434) (xy 37.192222 -400.101068) (xy 37.223375 -400.160865)
			(xy 37.247141 -400.223962) (xy 37.263177 -400.289453) (xy 37.271253 -400.356392) (xy 37.271252 -400.423817)
			(xy 37.263175 -400.490756) (xy 37.247138 -400.556246) (xy 37.223371 -400.619344) (xy 37.192218 -400.67914)
			(xy 37.154126 -400.734773) (xy 37.13226 -400.760438) (xy 37.12646 -400.76758) (xy 37.119948 -400.784773)
			(xy 37.11956 -400.793966) (xy 37.11956 -401.286218) (xy 37.11997 -401.295405) (xy 37.126485 -401.312589)
			(xy 37.13226 -401.319746) (xy 37.154104 -401.345428) (xy 37.192196 -401.40106) (xy 37.22335 -401.460853)
			(xy 37.247117 -401.523948) (xy 37.263155 -401.589435) (xy 37.271233 -401.656372) (xy 37.271235 -401.723795)
			(xy 37.263161 -401.790732) (xy 37.247127 -401.856221) (xy 37.223363 -401.919317) (xy 37.192213 -401.979112)
			(xy 37.154124 -402.034745) (xy 37.13226 -402.06041) (xy 37.126472 -402.067561) (xy 37.119953 -402.084747)
			(xy 37.11956 -402.093938) (xy 37.11956 -402.251418) (xy 37.119088 -402.261546) (xy 37.111355 -402.280268)
			(xy 37.097064 -402.294623) (xy 37.078378 -402.302442) (xy 37.068252 -402.30298) (xy 36.351972 -402.30298)
			(xy 36.341814 -402.302601) (xy 36.323057 -402.294792) (xy 36.308734 -402.280383) (xy 36.301038 -402.261579)
			(xy 36.300664 -402.251418) (xy 36.300664 -402.093938) (xy 36.300221 -402.084755) (xy 36.293729 -402.067571)
			(xy 36.287964 -402.06041) (xy 36.26608 -402.034762) (xy 36.227994 -401.979124) (xy 36.196846 -401.919325)
			(xy 36.173085 -401.856226) (xy 36.157052 -401.790735) (xy 36.148978 -401.723796) (xy 35.020926 -401.723796)
			(xy 34.99206 -401.779212) (xy 34.953974 -401.834847) (xy 34.932112 -401.860512) (xy 34.926329 -401.867667)
			(xy 34.919806 -401.88485) (xy 34.919412 -401.89404) (xy 34.919412 -402.386292) (xy 34.919823 -402.395479)
			(xy 34.926336 -402.412664) (xy 34.932112 -402.41982) (xy 34.953928 -402.445524) (xy 34.992018 -402.501154)
			(xy 35.02317 -402.560944) (xy 35.046936 -402.624036) (xy 35.062975 -402.68952) (xy 35.071054 -402.756454)
			(xy 35.071059 -402.823818) (xy 38.349119 -402.823818) (xy 38.349123 -402.75651) (xy 38.357172 -402.689685)
			(xy 38.373149 -402.6243) (xy 38.396825 -402.561294) (xy 38.427862 -402.501569) (xy 38.465814 -402.445981)
			(xy 38.487604 -402.420328) (xy 38.493414 -402.413192) (xy 38.499921 -402.395995) (xy 38.500304 -402.3868)
			(xy 38.500304 -401.893532) (xy 38.499878 -401.884347) (xy 38.493375 -401.867162) (xy 38.487604 -401.860004)
			(xy 38.465798 -401.834368) (xy 38.427852 -401.778778) (xy 38.396821 -401.719052) (xy 38.373151 -401.656045)
			(xy 38.357181 -401.590662) (xy 38.349139 -401.523838) (xy 38.34914 -401.456532) (xy 38.357186 -401.389709)
			(xy 38.37316 -401.324326) (xy 38.396834 -401.261321) (xy 38.427867 -401.201596) (xy 38.465816 -401.146009)
			(xy 38.487604 -401.120356) (xy 38.493402 -401.113212) (xy 38.499916 -401.096021) (xy 38.500304 -401.086828)
			(xy 38.500304 -400.92884) (xy 38.500755 -400.918688) (xy 38.508538 -400.899936) (xy 38.522926 -400.885611)
			(xy 38.541712 -400.87791) (xy 38.551866 -400.877532) (xy 39.268146 -400.877532) (xy 39.278275 -400.877989)
			(xy 39.296995 -400.88573) (xy 39.31135 -400.900025) (xy 39.319169 -400.918714) (xy 39.319708 -400.92884)
			(xy 39.319708 -401.086828) (xy 39.320103 -401.096017) (xy 39.326627 -401.113201) (xy 39.332408 -401.120356)
			(xy 39.354178 -401.146024) (xy 39.392131 -401.201607) (xy 39.423168 -401.261328) (xy 39.446844 -401.32433)
			(xy 39.46282 -401.389711) (xy 39.470866 -401.456533) (xy 39.470868 -401.523837) (xy 39.462825 -401.590659)
			(xy 39.446853 -401.656041) (xy 39.42318 -401.719045) (xy 39.420711 -401.723797) (xy 40.548745 -401.723797)
			(xy 40.548747 -401.65637) (xy 40.556826 -401.58943) (xy 40.572865 -401.523939) (xy 40.596634 -401.460841)
			(xy 40.62779 -401.401044) (xy 40.665885 -401.34541) (xy 40.687752 -401.319746) (xy 40.69356 -401.312609)
			(xy 40.700067 -401.295412) (xy 40.700452 -401.286218) (xy 40.700452 -400.793966) (xy 40.700046 -400.784779)
			(xy 40.693528 -400.767595) (xy 40.687752 -400.760438) (xy 40.665892 -400.734769) (xy 40.6278 -400.679136)
			(xy 40.596646 -400.619341) (xy 40.572879 -400.556244) (xy 40.556842 -400.490755) (xy 40.548764 -400.423817)
			(xy 40.548764 -400.356392) (xy 40.55684 -400.289454) (xy 40.572876 -400.223964) (xy 40.596642 -400.160867)
			(xy 40.627795 -400.101072) (xy 40.665887 -400.045438) (xy 40.687752 -400.019774) (xy 40.693549 -400.012629)
			(xy 40.700062 -399.995438) (xy 40.700452 -399.986246) (xy 40.700452 -399.828766) (xy 40.700899 -399.818636)
			(xy 40.70864 -399.799911) (xy 40.722939 -399.785556) (xy 40.741632 -399.77774) (xy 40.75176 -399.777204)
			(xy 41.46804 -399.777204) (xy 41.478197 -399.777589) (xy 41.496951 -399.785399) (xy 41.511273 -399.799806)
			(xy 41.518971 -399.818606) (xy 41.519348 -399.828766) (xy 41.519348 -399.986246) (xy 41.519796 -399.995429)
			(xy 41.526285 -400.012613) (xy 41.532048 -400.019774) (xy 41.55392 -400.045433) (xy 41.592012 -400.101068)
			(xy 41.623165 -400.160864) (xy 41.646931 -400.223962) (xy 41.662968 -400.289452) (xy 41.671044 -400.356392)
			(xy 41.671043 -400.423817) (xy 41.662966 -400.490757) (xy 41.646928 -400.556247) (xy 41.623161 -400.619344)
			(xy 41.592007 -400.67914) (xy 41.553914 -400.734774) (xy 41.532048 -400.760438) (xy 41.526246 -400.767579)
			(xy 41.519736 -400.784773) (xy 41.519348 -400.793966) (xy 41.519348 -401.286218) (xy 41.519761 -401.295405)
			(xy 41.526274 -401.312588) (xy 41.532048 -401.319746) (xy 41.553892 -401.345428) (xy 41.591985 -401.401059)
			(xy 41.62314 -401.460852) (xy 41.646907 -401.523947) (xy 41.662946 -401.589435) (xy 41.671024 -401.656372)
			(xy 41.671026 -401.723795) (xy 41.662952 -401.790733) (xy 41.646917 -401.856221) (xy 41.623153 -401.919317)
			(xy 41.592002 -401.979113) (xy 41.553912 -402.034746) (xy 41.532048 -402.06041) (xy 41.526258 -402.06756)
			(xy 41.519741 -402.084747) (xy 41.519348 -402.093938) (xy 41.519348 -402.251418) (xy 41.518888 -402.261547)
			(xy 41.511152 -402.280271) (xy 41.496858 -402.294627) (xy 41.478167 -402.302444) (xy 41.46804 -402.30298)
			(xy 40.75176 -402.30298) (xy 40.741601 -402.302611) (xy 40.722844 -402.294798) (xy 40.708521 -402.280385)
			(xy 40.700826 -402.26158) (xy 40.700452 -402.251418) (xy 40.700452 -402.093938) (xy 40.700012 -402.084754)
			(xy 40.693518 -402.06757) (xy 40.687752 -402.06041) (xy 40.665865 -402.034763) (xy 40.627773 -401.979127)
			(xy 40.59662 -401.919329) (xy 40.572855 -401.85623) (xy 40.55682 -401.790738) (xy 40.548745 -401.723797)
			(xy 39.420711 -401.723797) (xy 39.392146 -401.778768) (xy 39.354196 -401.834353) (xy 39.332408 -401.860004)
			(xy 39.326628 -401.867161) (xy 39.320103 -401.884342) (xy 39.319708 -401.893532) (xy 39.319708 -402.3868)
			(xy 39.320116 -402.395987) (xy 39.326631 -402.413172) (xy 39.332408 -402.420328) (xy 39.35415 -402.446018)
			(xy 39.392104 -402.501598) (xy 39.423142 -402.561316) (xy 39.44682 -402.624315) (xy 39.462798 -402.689694)
			(xy 39.470847 -402.756513) (xy 39.470851 -402.823815) (xy 39.470843 -402.823878) (xy 42.748887 -402.823878)
			(xy 42.748892 -402.75645) (xy 42.756972 -402.689509) (xy 42.773013 -402.624017) (xy 42.796782 -402.560918)
			(xy 42.827939 -402.501121) (xy 42.866033 -402.445485) (xy 42.8879 -402.41982) (xy 42.893713 -402.412686)
			(xy 42.900218 -402.395487) (xy 42.9006 -402.386292) (xy 42.9006 -401.89404) (xy 42.900171 -401.884855)
			(xy 42.89367 -401.86767) (xy 42.8879 -401.860512) (xy 42.866016 -401.834863) (xy 42.827928 -401.779226)
			(xy 42.796778 -401.719428) (xy 42.773015 -401.656329) (xy 42.756981 -401.590838) (xy 42.748907 -401.523898)
			(xy 42.748909 -401.456472) (xy 42.756987 -401.389533) (xy 42.773024 -401.324043) (xy 42.796791 -401.260945)
			(xy 42.827944 -401.201148) (xy 42.866035 -401.145513) (xy 42.8879 -401.119848) (xy 42.893701 -401.112706)
			(xy 42.900213 -401.095513) (xy 42.9006 -401.08632) (xy 42.9006 -400.92884) (xy 42.901049 -400.91872)
			(xy 42.908784 -400.900017) (xy 42.923091 -400.885702) (xy 42.941788 -400.877955) (xy 42.951908 -400.877532)
			(xy 43.668188 -400.877532) (xy 43.678314 -400.877927) (xy 43.697023 -400.885677) (xy 43.711339 -400.9)
			(xy 43.719079 -400.918714) (xy 43.719496 -400.92884) (xy 43.719496 -401.08632) (xy 43.719897 -401.095508)
			(xy 43.726417 -401.112692) (xy 43.732196 -401.119848) (xy 43.75404 -401.145529) (xy 43.79213 -401.201162)
			(xy 43.823282 -401.260955) (xy 43.847047 -401.32405) (xy 43.863084 -401.389537) (xy 43.871162 -401.456474)
			(xy 43.871164 -401.523896) (xy 43.86309 -401.590833) (xy 43.847056 -401.656321) (xy 43.823294 -401.719417)
			(xy 43.821044 -401.723737) (xy 44.949064 -401.723737) (xy 44.949066 -401.65643) (xy 44.957113 -401.589606)
			(xy 44.973088 -401.524222) (xy 44.996763 -401.461217) (xy 45.027799 -401.401493) (xy 45.065751 -401.345906)
			(xy 45.08754 -401.320254) (xy 45.093344 -401.313114) (xy 45.099853 -401.295919) (xy 45.10024 -401.286726)
			(xy 45.10024 -400.793458) (xy 45.099841 -400.78427) (xy 45.093319 -400.767086) (xy 45.08754 -400.75993)
			(xy 45.065758 -400.734273) (xy 45.027809 -400.678687) (xy 44.996776 -400.618964) (xy 44.973103 -400.55596)
			(xy 44.957129 -400.490579) (xy 44.949085 -400.423757) (xy 44.949084 -400.356452) (xy 44.957128 -400.28963)
			(xy 44.9731 -400.224248) (xy 44.996772 -400.161244) (xy 45.027805 -400.101521) (xy 45.065753 -400.045934)
			(xy 45.08754 -400.020282) (xy 45.093332 -400.013134) (xy 45.099848 -399.995945) (xy 45.10024 -399.986754)
			(xy 45.10024 -399.828766) (xy 45.100706 -399.818606) (xy 45.108492 -399.799835) (xy 45.122866 -399.785471)
			(xy 45.141641 -399.777698) (xy 45.151802 -399.777204) (xy 45.868082 -399.777204) (xy 45.878234 -399.777747)
			(xy 45.896997 -399.785509) (xy 45.911361 -399.79986) (xy 45.919143 -399.818614) (xy 45.919644 -399.828766)
			(xy 45.919644 -399.986754) (xy 45.920089 -399.995937) (xy 45.92658 -400.013121) (xy 45.932344 -400.020282)
			(xy 45.954138 -400.045929) (xy 45.992088 -400.101516) (xy 46.023122 -400.16124) (xy 46.046795 -400.224245)
			(xy 46.062768 -400.289628) (xy 46.070812 -400.356452) (xy 46.070811 -400.423757) (xy 46.062766 -400.490581)
			(xy 46.046792 -400.555963) (xy 46.023118 -400.618968) (xy 45.992083 -400.678692) (xy 45.954132 -400.734278)
			(xy 45.932344 -400.75993) (xy 45.926545 -400.767073) (xy 45.920033 -400.784266) (xy 45.919644 -400.793458)
			(xy 45.919644 -401.286726) (xy 45.920054 -401.295913) (xy 45.926569 -401.313097) (xy 45.932344 -401.320254)
			(xy 45.95411 -401.345924) (xy 45.992061 -401.401507) (xy 46.023096 -401.461228) (xy 46.046771 -401.524231)
			(xy 46.062746 -401.589611) (xy 46.070792 -401.656432) (xy 46.070794 -401.723735) (xy 46.062752 -401.790557)
			(xy 46.046781 -401.855938) (xy 46.02311 -401.918941) (xy 45.992078 -401.978664) (xy 45.954131 -402.03425)
			(xy 45.932344 -402.059902) (xy 45.926557 -402.067054) (xy 45.920038 -402.084239) (xy 45.919644 -402.09343)
			(xy 45.919644 -402.251418) (xy 45.919181 -402.261579) (xy 45.911397 -402.280352) (xy 45.897022 -402.294718)
			(xy 45.878244 -402.302488) (xy 45.868082 -402.30298) (xy 45.151802 -402.30298) (xy 45.141647 -402.302465)
			(xy 45.122881 -402.294695) (xy 45.108516 -402.280336) (xy 45.100739 -402.261573) (xy 45.10024 -402.251418)
			(xy 45.10024 -402.09343) (xy 45.099806 -402.084246) (xy 45.093308 -402.067061) (xy 45.08754 -402.059902)
			(xy 45.06573 -402.034268) (xy 45.027782 -401.978679) (xy 44.99675 -401.918953) (xy 44.973078 -401.855946)
			(xy 44.957107 -401.790561) (xy 44.949064 -401.723737) (xy 43.821044 -401.723737) (xy 43.792146 -401.779213)
			(xy 43.754059 -401.834847) (xy 43.732196 -401.860512) (xy 43.726411 -401.867666) (xy 43.71989 -401.88485)
			(xy 43.719496 -401.89404) (xy 43.719496 -402.386292) (xy 43.719911 -402.395479) (xy 43.726421 -402.412663)
			(xy 43.732196 -402.41982) (xy 43.754013 -402.445524) (xy 43.792103 -402.501153) (xy 43.823256 -402.560944)
			(xy 43.847023 -402.624036) (xy 43.863062 -402.68952) (xy 43.871142 -402.756454) (xy 43.871146 -402.823874)
			(xy 43.863075 -402.890809) (xy 43.847045 -402.956295) (xy 43.823286 -403.01939) (xy 43.792141 -403.079185)
			(xy 43.754057 -403.134819) (xy 43.732196 -403.160484) (xy 43.726381 -403.167616) (xy 43.719877 -403.184817)
			(xy 43.719496 -403.194012) (xy 43.719496 -403.351492) (xy 43.719077 -403.361614) (xy 43.711331 -403.380319)
			(xy 43.697015 -403.394633) (xy 43.67831 -403.402378) (xy 43.668188 -403.4028) (xy 42.951908 -403.4028)
			(xy 42.941786 -403.402377) (xy 42.923083 -403.394632) (xy 42.908768 -403.380317) (xy 42.901023 -403.361614)
			(xy 42.9006 -403.351492) (xy 42.9006 -403.194012) (xy 42.900184 -403.184825) (xy 42.893674 -403.167641)
			(xy 42.8879 -403.160484) (xy 42.865989 -403.134858) (xy 42.827902 -403.079218) (xy 42.796753 -403.019416)
			(xy 42.772992 -402.956314) (xy 42.756959 -402.89082) (xy 42.748887 -402.823878) (xy 39.470843 -402.823878)
			(xy 39.462811 -402.890635) (xy 39.446841 -402.956016) (xy 39.423172 -403.019018) (xy 39.392141 -403.07874)
			(xy 39.354194 -403.134325) (xy 39.332408 -403.159976) (xy 39.326598 -403.167111) (xy 39.320091 -403.184309)
			(xy 39.319708 -403.193504) (xy 39.319708 -403.351492) (xy 39.319272 -403.361645) (xy 39.311481 -403.380395)
			(xy 39.297088 -403.394719) (xy 39.278301 -403.40242) (xy 39.268146 -403.4028) (xy 38.551866 -403.4028)
			(xy 38.541742 -403.402303) (xy 38.523028 -403.394571) (xy 38.508674 -403.380289) (xy 38.500849 -403.361613)
			(xy 38.500304 -403.351492) (xy 38.500304 -403.193504) (xy 38.499891 -403.184317) (xy 38.493379 -403.167133)
			(xy 38.487604 -403.159976) (xy 38.46577 -403.134362) (xy 38.427825 -403.078769) (xy 38.396796 -403.01904)
			(xy 38.373127 -402.956031) (xy 38.357159 -402.890644) (xy 38.349119 -402.823818) (xy 35.071059 -402.823818)
			(xy 35.071059 -402.823874) (xy 35.062988 -402.890809) (xy 35.046958 -402.956295) (xy 35.023199 -403.01939)
			(xy 34.992055 -403.079185) (xy 34.953973 -403.134819) (xy 34.932112 -403.160484) (xy 34.926299 -403.167617)
			(xy 34.919794 -403.184817) (xy 34.919412 -403.194012) (xy 34.919412 -403.351492) (xy 34.918978 -403.361612)
			(xy 34.911234 -403.380314) (xy 34.896924 -403.394628) (xy 34.878224 -403.402375) (xy 34.868104 -403.4028)
			(xy 34.151824 -403.4028) (xy 34.141703 -403.402365) (xy 34.123 -403.394624) (xy 34.108685 -403.380314)
			(xy 34.100939 -403.361613) (xy 34.100516 -403.351492) (xy 34.100516 -403.194012) (xy 34.100096 -403.184826)
			(xy 34.093589 -403.167642) (xy 34.087816 -403.160484) (xy 34.065904 -403.134858) (xy 34.027816 -403.079218)
			(xy 33.996666 -403.019417) (xy 33.972904 -402.956315) (xy 33.956872 -402.890821) (xy 33.948799 -402.823878)
			(xy 30.670778 -402.823878) (xy 30.662742 -402.890627) (xy 30.646769 -402.956009) (xy 30.623096 -403.019014)
			(xy 30.592062 -403.078738) (xy 30.554112 -403.134324) (xy 30.532324 -403.159976) (xy 30.526515 -403.167113)
			(xy 30.520007 -403.18431) (xy 30.519624 -403.193504) (xy 30.519624 -403.351492) (xy 30.519172 -403.361643)
			(xy 30.511384 -403.38039) (xy 30.496997 -403.394713) (xy 30.478214 -403.402417) (xy 30.468062 -403.4028)
			(xy 29.751782 -403.4028) (xy 29.741659 -403.40229) (xy 29.722945 -403.394563) (xy 29.708591 -403.380285)
			(xy 29.700765 -403.361612) (xy 29.70022 -403.351492) (xy 29.70022 -403.193504) (xy 29.699804 -403.184318)
			(xy 29.693294 -403.167133) (xy 29.68752 -403.159976) (xy 29.665734 -403.134322) (xy 29.627785 -403.078736)
			(xy 29.596752 -403.019013) (xy 29.573079 -402.956008) (xy 29.557106 -402.890626) (xy 29.549061 -402.823804)
			(xy 29.549061 -402.756499) (xy 29.557105 -402.689677) (xy 29.573078 -402.624294) (xy 29.59675 -402.56129)
			(xy 29.627784 -402.501566) (xy 29.665732 -402.44598) (xy 29.68752 -402.420328) (xy 29.693332 -402.413194)
			(xy 29.699837 -402.395995) (xy 29.70022 -402.3868) (xy 29.70022 -401.893532) (xy 29.69979 -401.884347)
			(xy 29.69329 -401.867163) (xy 29.68752 -401.860004) (xy 29.665713 -401.834368) (xy 29.627766 -401.778779)
			(xy 29.596735 -401.719053) (xy 29.573064 -401.656046) (xy 29.557093 -401.590662) (xy 29.549051 -401.523838)
			(xy 28.446989 -401.523838) (xy 28.44703 -401.523948) (xy 28.463067 -401.589436) (xy 28.471145 -401.656372)
			(xy 28.471147 -401.723795) (xy 28.463073 -401.790732) (xy 28.447039 -401.85622) (xy 28.423277 -401.919316)
			(xy 28.392127 -401.979111) (xy 28.354039 -402.034745) (xy 28.332176 -402.06041) (xy 28.32639 -402.067562)
			(xy 28.31987 -402.084748) (xy 28.319476 -402.093938) (xy 28.319476 -402.251418) (xy 28.318989 -402.261544)
			(xy 28.311258 -402.280263) (xy 28.296972 -402.294618) (xy 28.278291 -402.302439) (xy 28.268168 -402.30298)
			(xy 27.551888 -402.30298) (xy 27.541731 -402.302588) (xy 27.522974 -402.294785) (xy 27.50865 -402.280379)
			(xy 27.500954 -402.261578) (xy 27.50058 -402.251418) (xy 27.50058 -402.093938) (xy 27.500156 -402.084752)
			(xy 27.493653 -402.067567) (xy 27.48788 -402.06041) (xy 27.465995 -402.034762) (xy 27.427908 -401.979125)
			(xy 27.39676 -401.919326) (xy 27.372998 -401.856227) (xy 27.356964 -401.790736) (xy 27.348891 -401.723796)
			(xy 0.508 -401.723796) (xy 0.508 -405.623707) (xy 27.348902 -405.623707) (xy 27.348902 -405.556284)
			(xy 27.356979 -405.489345) (xy 27.373014 -405.423856) (xy 27.396778 -405.360759) (xy 27.427928 -405.300963)
			(xy 27.466016 -405.245328) (xy 27.48788 -405.219662) (xy 27.493673 -405.212514) (xy 27.50019 -405.195326)
			(xy 27.50058 -405.186134) (xy 27.50058 -404.693882) (xy 27.500183 -404.684693) (xy 27.493661 -404.667509)
			(xy 27.48788 -404.660354) (xy 27.466038 -404.634671) (xy 27.42795 -404.579038) (xy 27.3968 -404.519244)
			(xy 27.373035 -404.45615) (xy 27.356999 -404.390663) (xy 27.348922 -404.323727) (xy 27.34892 -404.256306)
			(xy 27.356993 -404.189369) (xy 27.373025 -404.123882) (xy 27.396786 -404.060786) (xy 27.427933 -404.00099)
			(xy 27.466018 -403.945356) (xy 27.48788 -403.91969) (xy 27.493661 -403.912534) (xy 27.500186 -403.895352)
			(xy 27.50058 -403.886162) (xy 27.50058 -403.728682) (xy 27.501013 -403.718549) (xy 27.508754 -403.69982)
			(xy 27.523057 -403.685463) (xy 27.541757 -403.677651) (xy 27.551888 -403.67712) (xy 28.268168 -403.67712)
			(xy 28.278323 -403.677548) (xy 28.297078 -403.685337) (xy 28.311404 -403.699732) (xy 28.319101 -403.718525)
			(xy 28.319476 -403.728682) (xy 28.319476 -403.886162) (xy 28.31991 -403.895347) (xy 28.326408 -403.912531)
			(xy 28.332176 -403.91969) (xy 28.354062 -403.945337) (xy 28.392152 -404.000974) (xy 28.423303 -404.060772)
			(xy 28.447067 -404.123871) (xy 28.463102 -404.189363) (xy 28.471176 -404.256304) (xy 28.471174 -404.323729)
			(xy 28.463096 -404.39067) (xy 28.447057 -404.45616) (xy 28.42329 -404.519258) (xy 28.392135 -404.579055)
			(xy 28.354042 -404.634689) (xy 28.332176 -404.660354) (xy 28.326371 -404.667493) (xy 28.319862 -404.684688)
			(xy 28.319476 -404.693882) (xy 28.319476 -405.186134) (xy 28.319875 -405.195322) (xy 28.326397 -405.212506)
			(xy 28.332176 -405.219662) (xy 28.354035 -405.245332) (xy 28.392125 -405.300965) (xy 28.423278 -405.36076)
			(xy 28.447043 -405.423857) (xy 28.46308 -405.489345) (xy 28.471157 -405.556284) (xy 28.471157 -405.623707)
			(xy 28.463081 -405.690646) (xy 28.447046 -405.756135) (xy 28.423281 -405.819231) (xy 28.39213 -405.879027)
			(xy 28.35404 -405.934661) (xy 28.332176 -405.960326) (xy 28.326383 -405.967474) (xy 28.319867 -405.984662)
			(xy 28.319476 -405.993854) (xy 28.319476 -406.151334) (xy 28.319002 -406.161461) (xy 28.311266 -406.18018)
			(xy 28.296976 -406.194534) (xy 28.278293 -406.202355) (xy 28.268168 -406.202896) (xy 27.551888 -406.202896)
			(xy 27.541733 -406.202488) (xy 27.522979 -406.194688) (xy 27.508656 -406.180287) (xy 27.500957 -406.161492)
			(xy 27.50058 -406.151334) (xy 27.50058 -405.993854) (xy 27.500148 -405.984669) (xy 27.49365 -405.967484)
			(xy 27.48788 -405.960326) (xy 27.466011 -405.934665) (xy 27.427924 -405.87903) (xy 27.396774 -405.819233)
			(xy 27.373011 -405.756135) (xy 27.356977 -405.690646) (xy 27.348902 -405.623707) (xy 0.508 -405.623707)
			(xy 0.508 -406.72373) (xy 29.549042 -406.72373) (xy 29.549045 -406.656422) (xy 29.557092 -406.589598)
			(xy 29.573068 -406.524214) (xy 29.596744 -406.461208) (xy 29.627779 -406.401484) (xy 29.665731 -406.345896)
			(xy 29.68752 -406.320244) (xy 29.693325 -406.313105) (xy 29.699834 -406.29591) (xy 29.70022 -406.286716)
			(xy 29.70022 -405.793448) (xy 29.699782 -405.784264) (xy 29.693287 -405.767079) (xy 29.68752 -405.75992)
			(xy 29.665729 -405.734271) (xy 29.627781 -405.678684) (xy 29.596749 -405.618959) (xy 29.573078 -405.555955)
			(xy 29.557105 -405.490572) (xy 29.549062 -405.423749) (xy 29.549062 -405.356444) (xy 29.557107 -405.289622)
			(xy 29.573079 -405.22424) (xy 29.596752 -405.161235) (xy 29.627784 -405.101511) (xy 29.665733 -405.045924)
			(xy 29.68752 -405.020272) (xy 29.693313 -405.013125) (xy 29.699829 -404.995936) (xy 29.70022 -404.986744)
			(xy 29.70022 -404.828756) (xy 29.700586 -404.818597) (xy 29.7084 -404.799839) (xy 29.722814 -404.785517)
			(xy 29.74162 -404.777822) (xy 29.751782 -404.777448) (xy 30.468062 -404.777448) (xy 30.478187 -404.777958)
			(xy 30.496909 -404.785675) (xy 30.511267 -404.799954) (xy 30.519086 -404.818634) (xy 30.519624 -404.828756)
			(xy 30.519624 -404.986744) (xy 30.520008 -404.995934) (xy 30.526539 -405.013118) (xy 30.532324 -405.020272)
			(xy 30.554109 -405.045927) (xy 30.59206 -405.101512) (xy 30.623096 -405.161235) (xy 30.64677 -405.224239)
			(xy 30.662745 -405.289621) (xy 30.67079 -405.356444) (xy 30.67079 -405.42375) (xy 30.662746 -405.490573)
			(xy 30.646772 -405.555955) (xy 30.623098 -405.61896) (xy 30.620661 -405.623649) (xy 31.749197 -405.623649)
			(xy 31.749198 -405.556342) (xy 31.757243 -405.489519) (xy 31.773217 -405.424136) (xy 31.796892 -405.361131)
			(xy 31.827928 -405.301408) (xy 31.865879 -405.245822) (xy 31.887668 -405.22017) (xy 31.893468 -405.213028)
			(xy 31.899979 -405.195835) (xy 31.900368 -405.186642) (xy 31.900368 -404.693374) (xy 31.899955 -404.684187)
			(xy 31.893441 -404.667004) (xy 31.887668 -404.659846) (xy 31.865901 -404.634176) (xy 31.82795 -404.578593)
			(xy 31.796914 -404.518872) (xy 31.773239 -404.45587) (xy 31.757263 -404.39049) (xy 31.749217 -404.323668)
			(xy 31.749215 -404.256365) (xy 31.757257 -404.189543) (xy 31.773229 -404.124162) (xy 31.7969 -404.061158)
			(xy 31.827933 -404.001435) (xy 31.865881 -403.94585) (xy 31.887668 -403.920198) (xy 31.893456 -403.913047)
			(xy 31.899974 -403.895861) (xy 31.900368 -403.88667) (xy 31.900368 -403.728682) (xy 31.90075 -403.718506)
			(xy 31.908547 -403.699705) (xy 31.922945 -403.68532) (xy 31.941753 -403.677541) (xy 31.95193 -403.67712)
			(xy 32.66821 -403.67712) (xy 32.678366 -403.677625) (xy 32.697132 -403.685399) (xy 32.711496 -403.699761)
			(xy 32.719273 -403.718526) (xy 32.719772 -403.728682) (xy 32.719772 -403.88667) (xy 32.720203 -403.895855)
			(xy 32.726703 -403.913039) (xy 32.732472 -403.920198) (xy 32.754281 -403.945832) (xy 32.792229 -404.001422)
			(xy 32.82326 -404.061148) (xy 32.846931 -404.124155) (xy 32.862902 -404.189539) (xy 32.870945 -404.256363)
			(xy 32.870943 -404.32367) (xy 32.862897 -404.390494) (xy 32.846922 -404.455877) (xy 32.823247 -404.518882)
			(xy 32.792212 -404.578607) (xy 32.754261 -404.634194) (xy 32.732472 -404.659846) (xy 32.72667 -404.666987)
			(xy 32.720159 -404.684181) (xy 32.719772 -404.693374) (xy 32.719772 -405.186642) (xy 32.720168 -405.195831)
			(xy 32.726692 -405.213014) (xy 32.732472 -405.22017) (xy 32.754254 -405.245827) (xy 32.792202 -405.301413)
			(xy 32.823235 -405.361136) (xy 32.846907 -405.42414) (xy 32.862881 -405.489521) (xy 32.870925 -405.556343)
			(xy 32.870926 -405.623648) (xy 32.862882 -405.69047) (xy 32.84691 -405.755851) (xy 32.823239 -405.818856)
			(xy 32.792207 -405.878579) (xy 32.754259 -405.934166) (xy 32.732472 -405.959818) (xy 32.726682 -405.966967)
			(xy 32.720164 -405.984155) (xy 32.719772 -405.993346) (xy 32.719772 -406.151334) (xy 32.719295 -406.161493)
			(xy 32.711511 -406.180261) (xy 32.697141 -406.194624) (xy 32.678369 -406.202399) (xy 32.66821 -406.202896)
			(xy 31.95193 -406.202896) (xy 31.941778 -406.202343) (xy 31.923016 -406.194585) (xy 31.908651 -406.180237)
			(xy 31.900869 -406.161485) (xy 31.900368 -406.151334) (xy 31.900368 -405.993346) (xy 31.899921 -405.984163)
			(xy 31.893431 -405.966979) (xy 31.887668 -405.959818) (xy 31.865874 -405.934171) (xy 31.827923 -405.878584)
			(xy 31.796888 -405.81886) (xy 31.773215 -405.755855) (xy 31.757241 -405.690472) (xy 31.749197 -405.623649)
			(xy 30.620661 -405.623649) (xy 30.592063 -405.678683) (xy 30.554113 -405.734268) (xy 30.532324 -405.75992)
			(xy 30.526539 -405.767074) (xy 30.520017 -405.784258) (xy 30.519624 -405.793448) (xy 30.519624 -406.286716)
			(xy 30.520021 -406.295905) (xy 30.526543 -406.313089) (xy 30.532324 -406.320244) (xy 30.554081 -406.345922)
			(xy 30.592034 -406.401503) (xy 30.62307 -406.461223) (xy 30.646746 -406.524224) (xy 30.662723 -406.589604)
			(xy 30.67077 -406.656424) (xy 30.670773 -406.723728) (xy 30.670766 -406.723789) (xy 33.948811 -406.723789)
			(xy 33.948814 -406.656363) (xy 33.956893 -406.589422) (xy 33.972932 -406.523931) (xy 33.996701 -406.460833)
			(xy 34.027856 -406.401036) (xy 34.06595 -406.345401) (xy 34.087816 -406.319736) (xy 34.093624 -406.312599)
			(xy 34.100131 -406.295402) (xy 34.100516 -406.286208) (xy 34.100516 -405.793956) (xy 34.100123 -405.784767)
			(xy 34.093597 -405.767583) (xy 34.087816 -405.760428) (xy 34.065948 -405.734766) (xy 34.027858 -405.679132)
			(xy 33.996706 -405.619335) (xy 33.972942 -405.556238) (xy 33.956906 -405.490748) (xy 33.94883 -405.423809)
			(xy 33.948831 -405.356385) (xy 33.956907 -405.289446) (xy 33.972944 -405.223957) (xy 33.996709 -405.160859)
			(xy 34.027861 -405.101063) (xy 34.065951 -405.045429) (xy 34.087816 -405.019764) (xy 34.093612 -405.012619)
			(xy 34.100127 -404.995428) (xy 34.100516 -404.986236) (xy 34.100516 -404.828756) (xy 34.10095 -404.818642)
			(xy 34.108705 -404.79996) (xy 34.123017 -404.785666) (xy 34.14171 -404.777936) (xy 34.151824 -404.777448)
			(xy 34.868104 -404.777448) (xy 34.878207 -404.777981) (xy 34.896875 -404.78571) (xy 34.911168 -404.799992)
			(xy 34.918911 -404.818654) (xy 34.919412 -404.828756) (xy 34.919412 -404.986236) (xy 34.919802 -404.995425)
			(xy 34.926329 -405.01261) (xy 34.932112 -405.019764) (xy 34.953972 -405.045433) (xy 34.99206 -405.101067)
			(xy 35.02321 -405.160863) (xy 35.046974 -405.223959) (xy 35.063009 -405.289448) (xy 35.071085 -405.356385)
			(xy 35.071085 -405.423809) (xy 35.06301 -405.490746) (xy 35.046976 -405.556235) (xy 35.023212 -405.619332)
			(xy 35.020933 -405.623707) (xy 36.14899 -405.623707) (xy 36.14899 -405.556284) (xy 36.157066 -405.489346)
			(xy 36.173101 -405.423857) (xy 36.196864 -405.36076) (xy 36.228014 -405.300963) (xy 36.266101 -405.245328)
			(xy 36.287964 -405.219662) (xy 36.293767 -405.212522) (xy 36.300276 -405.195327) (xy 36.300664 -405.186134)
			(xy 36.300664 -404.693882) (xy 36.300248 -404.684696) (xy 36.293737 -404.667512) (xy 36.287964 -404.660354)
			(xy 36.266123 -404.63467) (xy 36.228036 -404.579038) (xy 36.196886 -404.519244) (xy 36.173122 -404.456149)
			(xy 36.157087 -404.390663) (xy 36.149009 -404.323727) (xy 36.149007 -404.256306) (xy 36.157081 -404.18937)
			(xy 36.173113 -404.123882) (xy 36.196873 -404.060787) (xy 36.228019 -404.000991) (xy 36.266103 -403.945356)
			(xy 36.287964 -403.91969) (xy 36.293755 -403.912541) (xy 36.300271 -403.895353) (xy 36.300664 -403.886162)
			(xy 36.300664 -403.728682) (xy 36.301112 -403.718551) (xy 36.30885 -403.699825) (xy 36.323149 -403.685468)
			(xy 36.341843 -403.677654) (xy 36.351972 -403.67712) (xy 37.068252 -403.67712) (xy 37.078405 -403.677561)
			(xy 37.097161 -403.685345) (xy 37.111486 -403.699736) (xy 37.119184 -403.718527) (xy 37.11956 -403.728682)
			(xy 37.11956 -403.886162) (xy 37.119998 -403.895346) (xy 37.126493 -403.91253) (xy 37.13226 -403.91969)
			(xy 37.154147 -403.945337) (xy 37.192238 -404.000973) (xy 37.22339 -404.060771) (xy 37.247154 -404.123871)
			(xy 37.26319 -404.189362) (xy 37.271264 -404.256303) (xy 37.271262 -404.32373) (xy 37.263184 -404.39067)
			(xy 37.247145 -404.456161) (xy 37.223376 -404.519259) (xy 37.192221 -404.579055) (xy 37.154127 -404.634689)
			(xy 37.13226 -404.660354) (xy 37.126453 -404.667492) (xy 37.119946 -404.684688) (xy 37.11956 -404.693882)
			(xy 37.11956 -405.186134) (xy 37.119963 -405.195322) (xy 37.126483 -405.212506) (xy 37.13226 -405.219662)
			(xy 37.154119 -405.245331) (xy 37.192211 -405.300964) (xy 37.223364 -405.36076) (xy 37.24713 -405.423856)
			(xy 37.263168 -405.489345) (xy 37.271245 -405.556284) (xy 37.271245 -405.623707) (xy 37.263169 -405.690646)
			(xy 37.247133 -405.756135) (xy 37.223368 -405.819232) (xy 37.192216 -405.879028) (xy 37.154125 -405.934661)
			(xy 37.13226 -405.960326) (xy 37.126465 -405.967472) (xy 37.11995 -405.984662) (xy 37.11956 -405.993854)
			(xy 37.11956 -406.151334) (xy 37.119101 -406.161463) (xy 37.111362 -406.180185) (xy 37.097068 -406.19454)
			(xy 37.078379 -406.202358) (xy 37.068252 -406.202896) (xy 36.351972 -406.202896) (xy 36.341816 -406.202501)
			(xy 36.323062 -406.194696) (xy 36.308739 -406.180291) (xy 36.301041 -406.161493) (xy 36.300664 -406.151334)
			(xy 36.300664 -405.993854) (xy 36.300214 -405.984671) (xy 36.293726 -405.967487) (xy 36.287964 -405.960326)
			(xy 36.266095 -405.934665) (xy 36.228009 -405.879029) (xy 36.196861 -405.819232) (xy 36.173099 -405.756135)
			(xy 36.157065 -405.690645) (xy 36.14899 -405.623707) (xy 35.020933 -405.623707) (xy 34.992063 -405.679128)
			(xy 34.953975 -405.734763) (xy 34.932112 -405.760428) (xy 34.926322 -405.767578) (xy 34.919803 -405.784765)
			(xy 34.919412 -405.793956) (xy 34.919412 -406.286208) (xy 34.919816 -406.295396) (xy 34.926334 -406.31258)
			(xy 34.932112 -406.319736) (xy 34.953944 -406.345427) (xy 34.992033 -406.401058) (xy 35.023184 -406.460851)
			(xy 35.04695 -406.523945) (xy 35.062987 -406.58943) (xy 35.071065 -406.656366) (xy 35.071068 -406.723729)
			(xy 38.34913 -406.723729) (xy 38.349133 -406.656422) (xy 38.35718 -406.589598) (xy 38.373155 -406.524215)
			(xy 38.39683 -406.461209) (xy 38.427865 -406.401484) (xy 38.465815 -406.345897) (xy 38.487604 -406.320244)
			(xy 38.493407 -406.313104) (xy 38.499918 -406.295909) (xy 38.500304 -406.286716) (xy 38.500304 -405.793448)
			(xy 38.49987 -405.784263) (xy 38.493373 -405.767079) (xy 38.487604 -405.75992) (xy 38.465813 -405.734271)
			(xy 38.427867 -405.678683) (xy 38.396836 -405.618959) (xy 38.373165 -405.555954) (xy 38.357193 -405.490572)
			(xy 38.34915 -405.423749) (xy 38.34915 -405.356445) (xy 38.357194 -405.289622) (xy 38.373167 -405.22424)
			(xy 38.396838 -405.161236) (xy 38.42787 -405.101512) (xy 38.465817 -405.045925) (xy 38.487604 -405.020272)
			(xy 38.493395 -405.013123) (xy 38.499913 -404.995935) (xy 38.500304 -404.986744) (xy 38.500304 -404.828756)
			(xy 38.500686 -404.818599) (xy 38.508497 -404.799844) (xy 38.522905 -404.785523) (xy 38.541706 -404.777825)
			(xy 38.551866 -404.777448) (xy 39.268146 -404.777448) (xy 39.278277 -404.777889) (xy 39.297 -404.785634)
			(xy 39.311355 -404.799934) (xy 39.319171 -404.818627) (xy 39.319708 -404.828756) (xy 39.319708 -404.986744)
			(xy 39.320095 -404.995934) (xy 39.326624 -405.013118) (xy 39.332408 -405.020272) (xy 39.354193 -405.045927)
			(xy 39.392146 -405.101512) (xy 39.423182 -405.161234) (xy 39.446858 -405.224239) (xy 39.462832 -405.289621)
			(xy 39.470878 -405.356444) (xy 39.470878 -405.42375) (xy 39.462833 -405.490573) (xy 39.446859 -405.555956)
			(xy 39.423185 -405.61896) (xy 39.420718 -405.623708) (xy 40.548756 -405.623708) (xy 40.548757 -405.556283)
			(xy 40.556834 -405.489343) (xy 40.572872 -405.423853) (xy 40.596639 -405.360756) (xy 40.627793 -405.30096)
			(xy 40.665886 -405.245326) (xy 40.687752 -405.219662) (xy 40.693554 -405.212521) (xy 40.700064 -405.195327)
			(xy 40.700452 -405.186134) (xy 40.700452 -404.693882) (xy 40.700039 -404.684695) (xy 40.693526 -404.667512)
			(xy 40.687752 -404.660354) (xy 40.665908 -404.634672) (xy 40.627815 -404.579041) (xy 40.59666 -404.519248)
			(xy 40.572893 -404.456153) (xy 40.556854 -404.390665) (xy 40.548776 -404.323728) (xy 40.548774 -404.256305)
			(xy 40.556848 -404.189367) (xy 40.572883 -404.123879) (xy 40.596647 -404.060783) (xy 40.627798 -404.000987)
			(xy 40.665888 -403.945354) (xy 40.687752 -403.91969) (xy 40.693542 -403.91254) (xy 40.700059 -403.895353)
			(xy 40.700452 -403.886162) (xy 40.700452 -403.728682) (xy 40.700912 -403.718553) (xy 40.708648 -403.699829)
			(xy 40.722942 -403.685473) (xy 40.741633 -403.677656) (xy 40.75176 -403.67712) (xy 41.46804 -403.67712)
			(xy 41.478199 -403.677489) (xy 41.496956 -403.685302) (xy 41.511279 -403.699715) (xy 41.518974 -403.71852)
			(xy 41.519348 -403.728682) (xy 41.519348 -403.886162) (xy 41.519788 -403.895346) (xy 41.526282 -403.91253)
			(xy 41.532048 -403.91969) (xy 41.553935 -403.945337) (xy 41.592027 -404.000973) (xy 41.62318 -404.060771)
			(xy 41.646945 -404.12387) (xy 41.66298 -404.189362) (xy 41.671055 -404.256303) (xy 41.671053 -404.32373)
			(xy 41.662974 -404.39067) (xy 41.646935 -404.456161) (xy 41.623166 -404.519259) (xy 41.59201 -404.579056)
			(xy 41.553915 -404.63469) (xy 41.532048 -404.660354) (xy 41.52624 -404.667491) (xy 41.519733 -404.684688)
			(xy 41.519348 -404.693882) (xy 41.519348 -405.186134) (xy 41.519754 -405.195321) (xy 41.526272 -405.212505)
			(xy 41.532048 -405.219662) (xy 41.553908 -405.245331) (xy 41.592 -405.300964) (xy 41.623154 -405.360759)
			(xy 41.646921 -405.423856) (xy 41.662958 -405.489345) (xy 41.671036 -405.556283) (xy 41.671036 -405.623708)
			(xy 41.66296 -405.690646) (xy 41.646924 -405.756136) (xy 41.623158 -405.819233) (xy 41.592005 -405.879028)
			(xy 41.553913 -405.934662) (xy 41.532048 -405.960326) (xy 41.526251 -405.967471) (xy 41.519738 -405.984662)
			(xy 41.519348 -405.993854) (xy 41.519348 -406.151334) (xy 41.518901 -406.161464) (xy 41.51116 -406.180189)
			(xy 41.496861 -406.194544) (xy 41.478168 -406.20236) (xy 41.46804 -406.202896) (xy 40.75176 -406.202896)
			(xy 40.741603 -406.202511) (xy 40.722849 -406.194701) (xy 40.708527 -406.180294) (xy 40.700829 -406.161494)
			(xy 40.700452 -406.151334) (xy 40.700452 -405.993854) (xy 40.700004 -405.984671) (xy 40.693515 -405.967487)
			(xy 40.687752 -405.960326) (xy 40.66588 -405.934667) (xy 40.627788 -405.879032) (xy 40.596635 -405.819236)
			(xy 40.572869 -405.756138) (xy 40.556832 -405.690648) (xy 40.548756 -405.623708) (xy 39.420718 -405.623708)
			(xy 39.392149 -405.678683) (xy 39.354197 -405.734269) (xy 39.332408 -405.75992) (xy 39.326621 -405.767072)
			(xy 39.3201 -405.784257) (xy 39.319708 -405.793448) (xy 39.319708 -406.286716) (xy 39.320109 -406.295904)
			(xy 39.326629 -406.313088) (xy 39.332408 -406.320244) (xy 39.354166 -406.345921) (xy 39.392119 -406.401503)
			(xy 39.423157 -406.461222) (xy 39.446834 -406.524224) (xy 39.46281 -406.589604) (xy 39.470858 -406.656424)
			(xy 39.470861 -406.723728) (xy 39.470854 -406.723789) (xy 42.748899 -406.723789) (xy 42.748901 -406.656363)
			(xy 42.756981 -406.589422) (xy 42.773019 -406.523932) (xy 42.796787 -406.460833) (xy 42.827942 -406.401036)
			(xy 42.866034 -406.345401) (xy 42.8879 -406.319736) (xy 42.893706 -406.312598) (xy 42.900215 -406.295402)
			(xy 42.9006 -406.286208) (xy 42.9006 -405.793956) (xy 42.900211 -405.784767) (xy 42.893683 -405.767582)
			(xy 42.8879 -405.760428) (xy 42.866032 -405.734766) (xy 42.827944 -405.679131) (xy 42.796793 -405.619334)
			(xy 42.773029 -405.556237) (xy 42.756994 -405.490748) (xy 42.748918 -405.423809) (xy 42.748919 -405.356385)
			(xy 42.756995 -405.289446) (xy 42.773031 -405.223957) (xy 42.796795 -405.16086) (xy 42.827947 -405.101064)
			(xy 42.866036 -405.045429) (xy 42.8879 -405.019764) (xy 42.893694 -405.012617) (xy 42.90021 -404.995428)
			(xy 42.9006 -404.986236) (xy 42.9006 -404.828756) (xy 42.901049 -404.818644) (xy 42.908801 -404.799965)
			(xy 42.923109 -404.785672) (xy 42.941796 -404.777939) (xy 42.951908 -404.777448) (xy 43.668188 -404.777448)
			(xy 43.67829 -404.777994) (xy 43.696958 -404.785718) (xy 43.711251 -404.799995) (xy 43.718995 -404.818655)
			(xy 43.719496 -404.828756) (xy 43.719496 -404.986236) (xy 43.71989 -404.995425) (xy 43.726415 -405.012609)
			(xy 43.732196 -405.019764) (xy 43.754056 -405.045432) (xy 43.792145 -405.101066) (xy 43.823296 -405.160862)
			(xy 43.847061 -405.223959) (xy 43.863097 -405.289447) (xy 43.871173 -405.356385) (xy 43.871173 -405.423809)
			(xy 43.863098 -405.490747) (xy 43.847063 -405.556236) (xy 43.823299 -405.619332) (xy 43.792148 -405.679128)
			(xy 43.75406 -405.734763) (xy 43.732196 -405.760428) (xy 43.726405 -405.767577) (xy 43.719887 -405.784765)
			(xy 43.719496 -405.793956) (xy 43.719496 -406.286208) (xy 43.719903 -406.295395) (xy 43.726419 -406.31258)
			(xy 43.732196 -406.319736) (xy 43.754029 -406.345427) (xy 43.792119 -406.401058) (xy 43.823271 -406.46085)
			(xy 43.847037 -406.523944) (xy 43.863075 -406.58943) (xy 43.871153 -406.656365) (xy 43.871156 -406.72373)
			(xy 47.149194 -406.72373) (xy 47.149197 -406.656422) (xy 47.157245 -406.589596) (xy 47.173223 -406.524212)
			(xy 47.196901 -406.461206) (xy 47.227941 -406.401481) (xy 47.265897 -406.345896) (xy 47.287688 -406.320244)
			(xy 47.293489 -406.313102) (xy 47.300002 -406.295909) (xy 47.300388 -406.286716) (xy 47.300388 -405.793448)
			(xy 47.299958 -405.784263) (xy 47.293458 -405.767078) (xy 47.287688 -405.75992) (xy 47.265895 -405.734272)
			(xy 47.227943 -405.678686) (xy 47.196907 -405.618962) (xy 47.173232 -405.555957) (xy 47.157258 -405.490574)
			(xy 47.149214 -405.42375) (xy 47.149214 -405.356444) (xy 47.157259 -405.28962) (xy 47.173234 -405.224237)
			(xy 47.19691 -405.161232) (xy 47.227946 -405.101509) (xy 47.265899 -405.045924) (xy 47.287688 -405.020272)
			(xy 47.293478 -405.013122) (xy 47.299997 -404.995935) (xy 47.300388 -404.986744) (xy 47.300388 -404.828756)
			(xy 47.300785 -404.818601) (xy 47.308593 -404.79985) (xy 47.322997 -404.785528) (xy 47.341792 -404.777828)
			(xy 47.35195 -404.777448) (xy 48.06823 -404.777448) (xy 48.07836 -404.777902) (xy 48.097083 -404.785641)
			(xy 48.111439 -404.799937) (xy 48.119255 -404.818629) (xy 48.119792 -404.828756) (xy 48.119792 -404.986744)
			(xy 48.120183 -404.995933) (xy 48.12671 -405.013117) (xy 48.132492 -405.020272) (xy 48.154275 -405.045928)
			(xy 48.192222 -405.101514) (xy 48.223254 -405.161238) (xy 48.246925 -405.224242) (xy 48.262897 -405.289623)
			(xy 48.270941 -405.356445) (xy 48.270942 -405.423749) (xy 48.262899 -405.490571) (xy 48.246927 -405.555952)
			(xy 48.223256 -405.618957) (xy 48.192225 -405.67868) (xy 48.154279 -405.734267) (xy 48.132492 -405.75992)
			(xy 48.126704 -405.767071) (xy 48.120184 -405.784257) (xy 48.119792 -405.793448) (xy 48.119792 -406.286716)
			(xy 48.120196 -406.295904) (xy 48.126714 -406.313088) (xy 48.132492 -406.320244) (xy 48.154247 -406.345922)
			(xy 48.192195 -406.401506) (xy 48.223228 -406.461226) (xy 48.246901 -406.524227) (xy 48.262876 -406.589606)
			(xy 48.270922 -406.656425) (xy 48.270925 -406.723727) (xy 48.262884 -406.790547) (xy 48.246916 -406.855927)
			(xy 48.223248 -406.91893) (xy 48.19222 -406.978653) (xy 48.154277 -407.034239) (xy 48.132492 -407.059892)
			(xy 48.126715 -407.067051) (xy 48.120189 -407.084231) (xy 48.119792 -407.09342) (xy 48.119792 -407.251408)
			(xy 48.119385 -407.261564) (xy 48.111585 -407.280318) (xy 48.097184 -407.294641) (xy 48.078388 -407.302339)
			(xy 48.06823 -407.302716) (xy 47.35195 -407.302716) (xy 47.341821 -407.302231) (xy 47.323093 -407.294512)
			(xy 47.308733 -407.280224) (xy 47.30092 -407.261534) (xy 47.300388 -407.251408) (xy 47.300388 -407.09342)
			(xy 47.299971 -407.084233) (xy 47.293462 -407.067049) (xy 47.287688 -407.059892) (xy 47.265867 -407.034266)
			(xy 47.227916 -406.978677) (xy 47.196882 -406.91895) (xy 47.173209 -406.855942) (xy 47.157236 -406.790556)
			(xy 47.149194 -406.72373) (xy 43.871156 -406.72373) (xy 43.871156 -406.723787) (xy 43.863084 -406.790723)
			(xy 43.847051 -406.85621) (xy 43.823291 -406.919306) (xy 43.792143 -406.979101) (xy 43.754058 -407.034735)
			(xy 43.732196 -407.0604) (xy 43.726416 -407.067557) (xy 43.719892 -407.084739) (xy 43.719496 -407.093928)
			(xy 43.719496 -407.251408) (xy 43.71909 -407.261531) (xy 43.711339 -407.280236) (xy 43.697019 -407.29455)
			(xy 43.678312 -407.302294) (xy 43.668188 -407.302716) (xy 42.951908 -407.302716) (xy 42.941802 -407.302209)
			(xy 42.923127 -407.294477) (xy 42.908832 -407.280187) (xy 42.901094 -407.261514) (xy 42.9006 -407.251408)
			(xy 42.9006 -407.093928) (xy 42.900176 -407.084742) (xy 42.893672 -407.067558) (xy 42.8879 -407.0604)
			(xy 42.866005 -407.034761) (xy 42.827917 -406.979122) (xy 42.796768 -406.919323) (xy 42.773005 -406.856222)
			(xy 42.756972 -406.79073) (xy 42.748899 -406.723789) (xy 39.470854 -406.723789) (xy 39.462819 -406.790549)
			(xy 39.446848 -406.85593) (xy 39.423176 -406.918933) (xy 39.392144 -406.978656) (xy 39.354195 -407.034241)
			(xy 39.332408 -407.059892) (xy 39.326633 -407.067053) (xy 39.320105 -407.084231) (xy 39.319708 -407.09342)
			(xy 39.319708 -407.251408) (xy 39.319285 -407.261562) (xy 39.311488 -407.280313) (xy 39.297092 -407.294635)
			(xy 39.278302 -407.302336) (xy 39.268146 -407.302716) (xy 38.551866 -407.302716) (xy 38.541732 -407.3023)
			(xy 38.523001 -407.294553) (xy 38.508645 -407.280245) (xy 38.500835 -407.261541) (xy 38.500304 -407.251408)
			(xy 38.500304 -407.09342) (xy 38.499883 -407.084234) (xy 38.493377 -407.06705) (xy 38.487604 -407.059892)
			(xy 38.465786 -407.034265) (xy 38.42784 -406.978674) (xy 38.39681 -406.918947) (xy 38.373141 -406.855939)
			(xy 38.357171 -406.790554) (xy 38.34913 -406.723729) (xy 35.071068 -406.723729) (xy 35.071068 -406.723786)
			(xy 35.062996 -406.790722) (xy 35.046964 -406.856209) (xy 35.023204 -406.919305) (xy 34.992058 -406.9791)
			(xy 34.953974 -407.034735) (xy 34.932112 -407.0604) (xy 34.926334 -407.067559) (xy 34.919808 -407.084739)
			(xy 34.919412 -407.093928) (xy 34.919412 -407.251408) (xy 34.918922 -407.261516) (xy 34.911184 -407.280192)
			(xy 34.896888 -407.294486) (xy 34.878212 -407.302222) (xy 34.868104 -407.302716) (xy 34.151824 -407.302716)
			(xy 34.141705 -407.302265) (xy 34.123005 -407.294528) (xy 34.10869 -407.280222) (xy 34.100941 -407.261527)
			(xy 34.100516 -407.251408) (xy 34.100516 -407.093928) (xy 34.100089 -407.084743) (xy 34.093586 -407.067558)
			(xy 34.087816 -407.0604) (xy 34.06592 -407.034761) (xy 34.027831 -406.979123) (xy 33.996681 -406.919323)
			(xy 33.972918 -406.856223) (xy 33.956884 -406.790731) (xy 33.948811 -406.723789) (xy 30.670766 -406.723789)
			(xy 30.662731 -406.790549) (xy 30.646761 -406.855929) (xy 30.62309 -406.918933) (xy 30.592058 -406.978655)
			(xy 30.554111 -407.03424) (xy 30.532324 -407.059892) (xy 30.526551 -407.067054) (xy 30.520022 -407.084232)
			(xy 30.519624 -407.09342) (xy 30.519624 -407.251408) (xy 30.519185 -407.26156) (xy 30.511392 -407.280307)
			(xy 30.497001 -407.29463) (xy 30.478216 -407.302333) (xy 30.468062 -407.302716) (xy 29.751782 -407.302716)
			(xy 29.741649 -407.302287) (xy 29.722919 -407.294545) (xy 29.708561 -407.280241) (xy 29.700751 -407.261539)
			(xy 29.70022 -407.251408) (xy 29.70022 -407.09342) (xy 29.699796 -407.084234) (xy 29.693291 -407.06705)
			(xy 29.68752 -407.059892) (xy 29.665701 -407.034265) (xy 29.627755 -406.978675) (xy 29.596724 -406.918948)
			(xy 29.573054 -406.85594) (xy 29.557084 -406.790555) (xy 29.549042 -406.72373) (xy 0.508 -406.72373)
			(xy 0.508 -409.523886) (xy 27.348881 -409.523886) (xy 27.348884 -409.45646) (xy 27.356963 -409.38952)
			(xy 27.373002 -409.324029) (xy 27.396769 -409.26093) (xy 27.427923 -409.201133) (xy 27.466015 -409.145498)
			(xy 27.48788 -409.119832) (xy 27.493686 -409.112693) (xy 27.500196 -409.095498) (xy 27.50058 -409.086304)
			(xy 27.50058 -408.594052) (xy 27.500149 -408.584867) (xy 27.49365 -408.567682) (xy 27.48788 -408.560524)
			(xy 27.466009 -408.534865) (xy 27.427922 -408.479229) (xy 27.396772 -408.419432) (xy 27.37301 -408.356334)
			(xy 27.356975 -408.290845) (xy 27.3489 -408.223906) (xy 27.348901 -408.156482) (xy 27.356977 -408.089544)
			(xy 27.373013 -408.024054) (xy 27.396777 -407.960957) (xy 27.427928 -407.901161) (xy 27.466016 -407.845526)
			(xy 27.48788 -407.81986) (xy 27.493674 -407.812713) (xy 27.500191 -407.795524) (xy 27.50058 -407.786332)
			(xy 27.50058 -407.628852) (xy 27.501045 -407.618743) (xy 27.508795 -407.600067) (xy 27.523098 -407.585775)
			(xy 27.541778 -407.578038) (xy 27.551888 -407.577544) (xy 28.268168 -407.577544) (xy 28.278268 -407.57811)
			(xy 28.296935 -407.585826) (xy 28.311229 -407.600098) (xy 28.318975 -407.618753) (xy 28.319476 -407.628852)
			(xy 28.319476 -407.786332) (xy 28.319876 -407.79552) (xy 28.326397 -407.812704) (xy 28.332176 -407.81986)
			(xy 28.354033 -407.845531) (xy 28.392123 -407.901164) (xy 28.423276 -407.96096) (xy 28.447042 -408.024056)
			(xy 28.463078 -408.089544) (xy 28.471155 -408.156482) (xy 28.471156 -408.223906) (xy 28.46308 -408.290844)
			(xy 28.447045 -408.356333) (xy 28.423281 -408.419429) (xy 28.39213 -408.479225) (xy 28.35404 -408.534859)
			(xy 28.332176 -408.560524) (xy 28.326384 -408.567672) (xy 28.319867 -408.584861) (xy 28.319476 -408.594052)
			(xy 28.319476 -409.086304) (xy 28.319889 -409.095491) (xy 28.326401 -409.112675) (xy 28.332176 -409.119832)
			(xy 28.354005 -409.145526) (xy 28.392097 -409.201156) (xy 28.42325 -409.260948) (xy 28.447018 -409.324041)
			(xy 28.463056 -409.389527) (xy 28.471135 -409.456462) (xy 28.471139 -409.523884) (xy 28.463066 -409.59082)
			(xy 28.447034 -409.656307) (xy 28.423273 -409.719403) (xy 28.392125 -409.779198) (xy 28.354039 -409.834831)
			(xy 28.332176 -409.860496) (xy 28.326396 -409.867653) (xy 28.319872 -409.884835) (xy 28.319476 -409.894024)
			(xy 28.319476 -410.051504) (xy 28.319087 -410.06163) (xy 28.311333 -410.080338) (xy 28.297008 -410.094653)
			(xy 28.278294 -410.102394) (xy 28.268168 -410.102812) (xy 27.551888 -410.102812) (xy 27.54178 -410.102325)
			(xy 27.523104 -410.094585) (xy 27.50881 -410.080289) (xy 27.501074 -410.061612) (xy 27.50058 -410.051504)
			(xy 27.50058 -409.894024) (xy 27.500163 -409.884837) (xy 27.493655 -409.867653) (xy 27.48788 -409.860496)
			(xy 27.465981 -409.83486) (xy 27.427895 -409.77922) (xy 27.396747 -409.71942) (xy 27.372986 -409.656319)
			(xy 27.356953 -409.590827) (xy 27.348881 -409.523886) (xy 0.508 -409.523886) (xy 0.508 -410.623641)
			(xy 29.549054 -410.623641) (xy 29.549055 -410.556335) (xy 29.5571 -410.489512) (xy 29.573074 -410.424129)
			(xy 29.596748 -410.361124) (xy 29.627782 -410.301399) (xy 29.665732 -410.245812) (xy 29.68752 -410.22016)
			(xy 29.693318 -410.213016) (xy 29.699831 -410.195825) (xy 29.70022 -410.186632) (xy 29.70022 -409.693364)
			(xy 29.699823 -409.684176) (xy 29.6933 -409.666992) (xy 29.68752 -409.659836) (xy 29.665745 -409.634174)
			(xy 29.627797 -409.578588) (xy 29.596764 -409.518866) (xy 29.573091 -409.455863) (xy 29.557118 -409.390482)
			(xy 29.549073 -409.323661) (xy 29.549072 -409.256357) (xy 29.557115 -409.189536) (xy 29.573086 -409.124154)
			(xy 29.596757 -409.06115) (xy 29.627787 -409.001427) (xy 29.665734 -408.94584) (xy 29.68752 -408.920188)
			(xy 29.693306 -408.913036) (xy 29.699827 -408.895851) (xy 29.70022 -408.88666) (xy 29.70022 -408.728672)
			(xy 29.700599 -408.718514) (xy 29.708408 -408.699757) (xy 29.722817 -408.685434) (xy 29.741621 -408.677738)
			(xy 29.751782 -408.677364) (xy 30.468062 -408.677364) (xy 30.478189 -408.677859) (xy 30.496914 -408.685578)
			(xy 30.511272 -408.699863) (xy 30.519089 -408.718547) (xy 30.519624 -408.728672) (xy 30.519624 -408.88666)
			(xy 30.520048 -408.895846) (xy 30.526551 -408.913031) (xy 30.532324 -408.920188) (xy 30.554125 -408.94583)
			(xy 30.592075 -409.001417) (xy 30.62311 -409.061142) (xy 30.646784 -409.124148) (xy 30.662757 -409.189531)
			(xy 30.670801 -409.256356) (xy 30.6708 -409.323662) (xy 30.662754 -409.390486) (xy 30.646779 -409.45587)
			(xy 30.623103 -409.518875) (xy 30.62053 -409.523827) (xy 31.749176 -409.523827) (xy 31.749179 -409.456519)
			(xy 31.757227 -409.389693) (xy 31.773205 -409.324309) (xy 31.796883 -409.261302) (xy 31.827922 -409.201578)
			(xy 31.865877 -409.145992) (xy 31.887668 -409.12034) (xy 31.893481 -409.113207) (xy 31.899984 -409.096007)
			(xy 31.900368 -409.086812) (xy 31.900368 -408.593544) (xy 31.899922 -408.584361) (xy 31.893432 -408.567177)
			(xy 31.887668 -408.560016) (xy 31.865872 -408.534371) (xy 31.827921 -408.478784) (xy 31.796887 -408.41906)
			(xy 31.773213 -408.356054) (xy 31.75724 -408.290671) (xy 31.749196 -408.223847) (xy 31.749197 -408.156541)
			(xy 31.757242 -408.089717) (xy 31.773217 -408.024334) (xy 31.796892 -407.961329) (xy 31.827927 -407.901606)
			(xy 31.865879 -407.84602) (xy 31.887668 -407.820368) (xy 31.893469 -407.813226) (xy 31.899979 -407.796033)
			(xy 31.900368 -407.78684) (xy 31.900368 -407.628852) (xy 31.900782 -407.618699) (xy 31.908587 -407.599952)
			(xy 31.922985 -407.585631) (xy 31.941775 -407.577927) (xy 31.95193 -407.577544) (xy 32.66821 -407.577544)
			(xy 32.678338 -407.578019) (xy 32.69706 -407.58575) (xy 32.711416 -407.60004) (xy 32.719234 -407.618727)
			(xy 32.719772 -407.628852) (xy 32.719772 -407.78684) (xy 32.720169 -407.796028) (xy 32.726693 -407.813212)
			(xy 32.732472 -407.820368) (xy 32.754252 -407.846027) (xy 32.7922 -407.901612) (xy 32.823233 -407.961335)
			(xy 32.846906 -408.024339) (xy 32.862879 -408.08972) (xy 32.870924 -408.156542) (xy 32.870924 -408.223846)
			(xy 32.862881 -408.290668) (xy 32.846909 -408.35605) (xy 32.823238 -408.419054) (xy 32.792206 -408.478777)
			(xy 32.754259 -408.534364) (xy 32.732472 -408.560016) (xy 32.726682 -408.567166) (xy 32.720164 -408.584353)
			(xy 32.719772 -408.593544) (xy 32.719772 -409.086812) (xy 32.720183 -409.095999) (xy 32.726697 -409.113183)
			(xy 32.732472 -409.12034) (xy 32.754224 -409.146022) (xy 32.792173 -409.201604) (xy 32.823207 -409.261324)
			(xy 32.846881 -409.324324) (xy 32.862857 -409.389703) (xy 32.870903 -409.456522) (xy 32.870907 -409.523824)
			(xy 32.862866 -409.590644) (xy 32.846897 -409.656024) (xy 32.823229 -409.719027) (xy 32.792201 -409.778749)
			(xy 32.754257 -409.834336) (xy 32.732472 -409.859988) (xy 32.726652 -409.867116) (xy 32.720152 -409.88432)
			(xy 32.719772 -409.893516) (xy 32.719772 -410.051504) (xy 32.719381 -410.061662) (xy 32.711579 -410.08042)
			(xy 32.697172 -410.094744) (xy 32.67837 -410.102438) (xy 32.66821 -410.102812) (xy 31.95193 -410.102812)
			(xy 31.941812 -410.102251) (xy 31.923101 -410.094542) (xy 31.908745 -410.080279) (xy 31.900916 -410.061619)
			(xy 31.900368 -410.051504) (xy 31.900368 -409.893516) (xy 31.899935 -409.884332) (xy 31.893436 -409.867148)
			(xy 31.887668 -409.859988) (xy 31.865844 -409.834366) (xy 31.827894 -409.778775) (xy 31.796861 -409.719048)
			(xy 31.773189 -409.65604) (xy 31.757217 -409.590654) (xy 31.749176 -409.523827) (xy 30.62053 -409.523827)
			(xy 30.592066 -409.578598) (xy 30.554113 -409.634184) (xy 30.532324 -409.659836) (xy 30.526532 -409.666985)
			(xy 30.520014 -409.684172) (xy 30.519624 -409.693364) (xy 30.519624 -410.186632) (xy 30.520014 -410.195821)
			(xy 30.526541 -410.213006) (xy 30.532324 -410.22016) (xy 30.554097 -410.245825) (xy 30.592049 -410.301408)
			(xy 30.623085 -410.36113) (xy 30.64676 -410.424133) (xy 30.662735 -410.489514) (xy 30.670781 -410.556336)
			(xy 30.670783 -410.62364) (xy 30.670776 -410.623701) (xy 33.948822 -410.623701) (xy 33.948823 -410.556275)
			(xy 33.956901 -410.489336) (xy 33.972939 -410.423846) (xy 33.996705 -410.360748) (xy 34.027859 -410.300951)
			(xy 34.065951 -410.245317) (xy 34.087816 -410.219652) (xy 34.093617 -410.21251) (xy 34.100129 -410.195317)
			(xy 34.100516 -410.186124) (xy 34.100516 -409.693872) (xy 34.100116 -409.684684) (xy 34.093595 -409.6675)
			(xy 34.087816 -409.660344) (xy 34.065963 -409.634669) (xy 34.027873 -409.579037) (xy 33.996721 -409.519242)
			(xy 33.972955 -409.456146) (xy 33.956919 -409.390658) (xy 33.948842 -409.323721) (xy 33.948841 -409.256297)
			(xy 33.956915 -409.18936) (xy 33.97295 -409.123871) (xy 33.996714 -409.060775) (xy 34.027864 -409.000979)
			(xy 34.065952 -408.945345) (xy 34.087816 -408.91968) (xy 34.093605 -408.91253) (xy 34.100124 -408.895343)
			(xy 34.100516 -408.886152) (xy 34.100516 -408.728672) (xy 34.100962 -408.718559) (xy 34.108712 -408.699878)
			(xy 34.123021 -408.685583) (xy 34.141711 -408.677852) (xy 34.151824 -408.677364) (xy 34.868104 -408.677364)
			(xy 34.878209 -408.677881) (xy 34.89688 -408.685613) (xy 34.911173 -408.6999) (xy 34.918914 -408.718568)
			(xy 34.919412 -408.728672) (xy 34.919412 -408.886152) (xy 34.919842 -408.895337) (xy 34.926342 -408.912522)
			(xy 34.932112 -408.91968) (xy 34.953987 -408.945336) (xy 34.992075 -409.000972) (xy 35.023224 -409.06077)
			(xy 35.046987 -409.123868) (xy 35.063022 -409.189358) (xy 35.071096 -409.256297) (xy 35.071095 -409.323721)
			(xy 35.063018 -409.39066) (xy 35.046982 -409.45615) (xy 35.023217 -409.519247) (xy 35.0208 -409.523886)
			(xy 36.148969 -409.523886) (xy 36.148972 -409.45646) (xy 36.157051 -409.38952) (xy 36.173089 -409.324029)
			(xy 36.196856 -409.260931) (xy 36.228009 -409.201134) (xy 36.266099 -409.145498) (xy 36.287964 -409.119832)
			(xy 36.29378 -409.112701) (xy 36.300281 -409.095499) (xy 36.300664 -409.086304) (xy 36.300664 -408.594052)
			(xy 36.300215 -408.584869) (xy 36.293727 -408.567685) (xy 36.287964 -408.560524) (xy 36.266093 -408.534865)
			(xy 36.228007 -408.479228) (xy 36.196859 -408.419431) (xy 36.173097 -408.356334) (xy 36.157063 -408.290844)
			(xy 36.148988 -408.223906) (xy 36.148989 -408.156482) (xy 36.157065 -408.089544) (xy 36.1731 -408.024055)
			(xy 36.196864 -407.960958) (xy 36.228014 -407.901161) (xy 36.266101 -407.845526) (xy 36.287964 -407.81986)
			(xy 36.293768 -407.81272) (xy 36.300276 -407.795525) (xy 36.300664 -407.786332) (xy 36.300664 -407.628852)
			(xy 36.301145 -407.618745) (xy 36.308892 -407.600072) (xy 36.323189 -407.585781) (xy 36.341864 -407.578041)
			(xy 36.351972 -407.577544) (xy 37.068252 -407.577544) (xy 37.078351 -407.578123) (xy 37.097017 -407.585835)
			(xy 37.111312 -407.600102) (xy 37.119058 -407.618754) (xy 37.11956 -407.628852) (xy 37.11956 -407.786332)
			(xy 37.119964 -407.79552) (xy 37.126483 -407.812703) (xy 37.13226 -407.81986) (xy 37.154118 -407.845531)
			(xy 37.192209 -407.901164) (xy 37.223362 -407.960959) (xy 37.247129 -408.024055) (xy 37.263166 -408.089544)
			(xy 37.271243 -408.156482) (xy 37.271244 -408.223906) (xy 37.263168 -408.290844) (xy 37.247132 -408.356333)
			(xy 37.223367 -408.41943) (xy 37.192215 -408.479226) (xy 37.154125 -408.534859) (xy 37.13226 -408.560524)
			(xy 37.126466 -408.567671) (xy 37.119951 -408.58486) (xy 37.11956 -408.594052) (xy 37.11956 -409.086304)
			(xy 37.119977 -409.09549) (xy 37.126487 -409.112674) (xy 37.13226 -409.119832) (xy 37.15409 -409.145526)
			(xy 37.192182 -409.201155) (xy 37.223337 -409.260947) (xy 37.247105 -409.32404) (xy 37.263144 -409.389526)
			(xy 37.271223 -409.456462) (xy 37.271227 -409.523884) (xy 37.263154 -409.59082) (xy 37.247121 -409.656308)
			(xy 37.223359 -409.719403) (xy 37.19221 -409.779198) (xy 37.154123 -409.834831) (xy 37.13226 -409.860496)
			(xy 37.126478 -409.867651) (xy 37.119955 -409.884834) (xy 37.11956 -409.894024) (xy 37.11956 -410.051504)
			(xy 37.119186 -410.061632) (xy 37.111429 -410.080343) (xy 37.097099 -410.094659) (xy 37.07838 -410.102396)
			(xy 37.068252 -410.102812) (xy 36.351972 -410.102812) (xy 36.341863 -410.102338) (xy 36.323186 -410.094594)
			(xy 36.308893 -410.080293) (xy 36.301157 -410.061613) (xy 36.300664 -410.051504) (xy 36.300664 -409.894024)
			(xy 36.300228 -409.88484) (xy 36.293731 -409.867656) (xy 36.287964 -409.860496) (xy 36.266066 -409.834859)
			(xy 36.227981 -409.77922) (xy 36.196834 -409.719419) (xy 36.173073 -409.656319) (xy 36.157041 -409.590827)
			(xy 36.148969 -409.523886) (xy 35.0208 -409.523886) (xy 34.992066 -409.579044) (xy 34.953976 -409.634679)
			(xy 34.932112 -409.660344) (xy 34.926316 -409.667489) (xy 34.9198 -409.68468) (xy 34.919412 -409.693872)
			(xy 34.919412 -410.186124) (xy 34.919808 -410.195313) (xy 34.926331 -410.212497) (xy 34.932112 -410.219652)
			(xy 34.95396 -410.24533) (xy 34.992048 -410.300963) (xy 35.023199 -410.360758) (xy 35.046964 -410.423853)
			(xy 35.063 -410.48934) (xy 35.071077 -410.556277) (xy 35.071078 -410.623641) (xy 38.349141 -410.623641)
			(xy 38.349143 -410.556335) (xy 38.357188 -410.489512) (xy 38.373162 -410.424129) (xy 38.396835 -410.361124)
			(xy 38.427868 -410.3014) (xy 38.465816 -410.245813) (xy 38.487604 -410.22016) (xy 38.493401 -410.213015)
			(xy 38.499915 -410.195824) (xy 38.500304 -410.186632) (xy 38.500304 -409.693364) (xy 38.49991 -409.684175)
			(xy 38.493385 -409.666991) (xy 38.487604 -409.659836) (xy 38.465829 -409.634174) (xy 38.427882 -409.578588)
			(xy 38.39685 -409.518865) (xy 38.373178 -409.455862) (xy 38.357206 -409.390482) (xy 38.349161 -409.323661)
			(xy 38.34916 -409.256357) (xy 38.357202 -409.189536) (xy 38.373173 -409.124155) (xy 38.396843 -409.061151)
			(xy 38.427873 -409.001428) (xy 38.465818 -408.945841) (xy 38.487604 -408.920188) (xy 38.493389 -408.913034)
			(xy 38.49991 -408.89585) (xy 38.500304 -408.88666) (xy 38.500304 -408.728672) (xy 38.500699 -408.718516)
			(xy 38.508504 -408.699762) (xy 38.522909 -408.685439) (xy 38.541707 -408.677741) (xy 38.551866 -408.677364)
			(xy 39.268146 -408.677364) (xy 39.278279 -408.67779) (xy 39.297005 -408.685537) (xy 39.311361 -408.699842)
			(xy 39.319174 -408.718541) (xy 39.319708 -408.728672) (xy 39.319708 -408.88666) (xy 39.320136 -408.895845)
			(xy 39.326637 -408.91303) (xy 39.332408 -408.920188) (xy 39.354209 -408.94583) (xy 39.392161 -409.001416)
			(xy 39.423197 -409.061141) (xy 39.446871 -409.124147) (xy 39.462845 -409.189531) (xy 39.470889 -409.256356)
			(xy 39.470888 -409.323663) (xy 39.462842 -409.390487) (xy 39.446866 -409.45587) (xy 39.423189 -409.518876)
			(xy 39.420585 -409.523887) (xy 40.548735 -409.523887) (xy 40.548738 -409.456459) (xy 40.556818 -409.389518)
			(xy 40.572859 -409.324026) (xy 40.59663 -409.260927) (xy 40.627788 -409.20113) (xy 40.665884 -409.145496)
			(xy 40.687752 -409.119832) (xy 40.693566 -409.1127) (xy 40.700069 -409.095499) (xy 40.700452 -409.086304)
			(xy 40.700452 -408.594052) (xy 40.700005 -408.584869) (xy 40.693516 -408.567685) (xy 40.687752 -408.560524)
			(xy 40.665878 -408.534866) (xy 40.627786 -408.479232) (xy 40.596633 -408.419435) (xy 40.572867 -408.356337)
			(xy 40.556831 -408.290847) (xy 40.548755 -408.223907) (xy 40.548755 -408.156481) (xy 40.556833 -408.089542)
			(xy 40.572871 -408.024051) (xy 40.596638 -407.960954) (xy 40.627793 -407.901158) (xy 40.665886 -407.845524)
			(xy 40.687752 -407.81986) (xy 40.693554 -407.812719) (xy 40.700064 -407.795525) (xy 40.700452 -407.786332)
			(xy 40.700452 -407.628852) (xy 40.700945 -407.618746) (xy 40.708689 -407.600076) (xy 40.722983 -407.585785)
			(xy 40.741654 -407.578043) (xy 40.75176 -407.577544) (xy 41.46804 -407.577544) (xy 41.478144 -407.578051)
			(xy 41.496813 -407.585791) (xy 41.511104 -407.600081) (xy 41.518847 -407.618748) (xy 41.519348 -407.628852)
			(xy 41.519348 -407.786332) (xy 41.519755 -407.795519) (xy 41.526272 -407.812703) (xy 41.532048 -407.81986)
			(xy 41.553906 -407.845531) (xy 41.591998 -407.901163) (xy 41.623152 -407.960958) (xy 41.646919 -408.024055)
			(xy 41.662957 -408.089543) (xy 41.671034 -408.156482) (xy 41.671035 -408.223906) (xy 41.662959 -408.290845)
			(xy 41.646923 -408.356334) (xy 41.623157 -408.419431) (xy 41.592004 -408.479226) (xy 41.553913 -408.53486)
			(xy 41.532048 -408.560524) (xy 41.526252 -408.56767) (xy 41.519739 -408.58486) (xy 41.519348 -408.594052)
			(xy 41.519348 -409.086304) (xy 41.519768 -409.09549) (xy 41.526276 -409.112674) (xy 41.532048 -409.119832)
			(xy 41.553878 -409.145526) (xy 41.591972 -409.201155) (xy 41.623127 -409.260947) (xy 41.646895 -409.32404)
			(xy 41.662935 -409.389526) (xy 41.671014 -409.456462) (xy 41.671018 -409.523884) (xy 41.662945 -409.590821)
			(xy 41.646911 -409.656308) (xy 41.623149 -409.719404) (xy 41.591999 -409.779199) (xy 41.553912 -409.834832)
			(xy 41.532048 -409.860496) (xy 41.526264 -409.86765) (xy 41.519743 -409.884834) (xy 41.519348 -409.894024)
			(xy 41.519348 -410.051504) (xy 41.518819 -410.061607) (xy 41.511089 -410.080276) (xy 41.496806 -410.094569)
			(xy 41.478143 -410.102312) (xy 41.46804 -410.102812) (xy 40.75176 -410.102812) (xy 40.74165 -410.102348)
			(xy 40.722973 -410.094599) (xy 40.70868 -410.080296) (xy 40.700945 -410.061614) (xy 40.700452 -410.051504)
			(xy 40.700452 -409.894024) (xy 40.700019 -409.884839) (xy 40.69352 -409.867655) (xy 40.687752 -409.860496)
			(xy 40.665851 -409.834861) (xy 40.62776 -409.779223) (xy 40.596608 -409.719423) (xy 40.572843 -409.656322)
			(xy 40.556809 -409.590829) (xy 40.548735 -409.523887) (xy 39.420585 -409.523887) (xy 39.392152 -409.578599)
			(xy 39.354198 -409.634185) (xy 39.332408 -409.659836) (xy 39.326615 -409.666984) (xy 39.320098 -409.684172)
			(xy 39.319708 -409.693364) (xy 39.319708 -410.186632) (xy 39.320101 -410.195821) (xy 39.326626 -410.213005)
			(xy 39.332408 -410.22016) (xy 39.354182 -410.245824) (xy 39.392134 -410.301408) (xy 39.423171 -410.361129)
			(xy 39.446847 -410.424132) (xy 39.462823 -410.489513) (xy 39.470869 -410.556336) (xy 39.470871 -410.62364)
			(xy 39.470864 -410.6237) (xy 42.74891 -410.6237) (xy 42.748911 -410.556276) (xy 42.756989 -410.489336)
			(xy 42.773026 -410.423846) (xy 42.796792 -410.360749) (xy 42.827944 -410.300952) (xy 42.866035 -410.245317)
			(xy 42.8879 -410.219652) (xy 42.893699 -410.212509) (xy 42.900212 -410.195317) (xy 42.9006 -410.186124)
			(xy 42.9006 -409.693872) (xy 42.900204 -409.684683) (xy 42.89368 -409.667499) (xy 42.8879 -409.660344)
			(xy 42.866048 -409.634669) (xy 42.827959 -409.579036) (xy 42.796808 -409.519241) (xy 42.773043 -409.456145)
			(xy 42.757006 -409.390658) (xy 42.74893 -409.32372) (xy 42.748928 -409.256298) (xy 42.757003 -409.18936)
			(xy 42.773037 -409.123872) (xy 42.7968 -409.060775) (xy 42.827949 -409.00098) (xy 42.866037 -408.945345)
			(xy 42.8879 -408.91968) (xy 42.893688 -408.912528) (xy 42.900208 -408.895343) (xy 42.9006 -408.886152)
			(xy 42.9006 -408.728672) (xy 42.901062 -408.718561) (xy 42.908809 -408.699883) (xy 42.923113 -408.685589)
			(xy 42.941797 -408.677855) (xy 42.951908 -408.677364) (xy 43.668188 -408.677364) (xy 43.678292 -408.677894)
			(xy 43.696963 -408.685621) (xy 43.711257 -408.699904) (xy 43.718998 -408.718569) (xy 43.719496 -408.728672)
			(xy 43.719496 -408.886152) (xy 43.71993 -408.895337) (xy 43.726427 -408.912521) (xy 43.732196 -408.91968)
			(xy 43.754072 -408.945335) (xy 43.792161 -409.000971) (xy 43.823311 -409.060769) (xy 43.847075 -409.123867)
			(xy 43.863109 -409.189357) (xy 43.871184 -409.256297) (xy 43.871183 -409.323721) (xy 43.863106 -409.390661)
			(xy 43.847069 -409.45615) (xy 43.823304 -409.519248) (xy 43.792151 -409.579044) (xy 43.754061 -409.634679)
			(xy 43.732196 -409.660344) (xy 43.726398 -409.667488) (xy 43.719884 -409.684679) (xy 43.719496 -409.693872)
			(xy 43.719496 -410.186124) (xy 43.719895 -410.195312) (xy 43.726417 -410.212497) (xy 43.732196 -410.219652)
			(xy 43.754044 -410.24533) (xy 43.792134 -410.300963) (xy 43.823285 -410.360757) (xy 43.847051 -410.423852)
			(xy 43.863087 -410.48934) (xy 43.871165 -410.556277) (xy 43.871166 -410.623642) (xy 47.149205 -410.623642)
			(xy 47.149207 -410.556334) (xy 47.157253 -410.48951) (xy 47.173229 -410.424126) (xy 47.196906 -410.361121)
			(xy 47.227944 -410.301397) (xy 47.265898 -410.245812) (xy 47.287688 -410.22016) (xy 47.293483 -410.213013)
			(xy 47.299999 -410.195824) (xy 47.300388 -410.186632) (xy 47.300388 -409.693364) (xy 47.299998 -409.684175)
			(xy 47.293471 -409.66699) (xy 47.287688 -409.659836) (xy 47.265911 -409.634175) (xy 47.227958 -409.578591)
			(xy 47.196922 -409.518869) (xy 47.173246 -409.455866) (xy 47.157271 -409.390484) (xy 47.149225 -409.323662)
			(xy 47.149224 -409.256357) (xy 47.157268 -409.189534) (xy 47.173241 -409.124152) (xy 47.196914 -409.061148)
			(xy 47.227949 -409.001425) (xy 47.2659 -408.945839) (xy 47.287688 -408.920188) (xy 47.293471 -408.913033)
			(xy 47.299994 -408.89585) (xy 47.300388 -408.88666) (xy 47.300388 -408.728672) (xy 47.300798 -408.718518)
			(xy 47.308601 -408.699767) (xy 47.323001 -408.685445) (xy 47.341793 -408.677744) (xy 47.35195 -408.677364)
			(xy 48.06823 -408.677364) (xy 48.078362 -408.677803) (xy 48.097088 -408.685545) (xy 48.111444 -408.699846)
			(xy 48.119258 -408.718542) (xy 48.119792 -408.728672) (xy 48.119792 -408.88666) (xy 48.120223 -408.895845)
			(xy 48.126722 -408.913029) (xy 48.132492 -408.920188) (xy 48.154291 -408.945831) (xy 48.192237 -409.001419)
			(xy 48.223268 -409.061145) (xy 48.246939 -409.12415) (xy 48.26291 -409.189533) (xy 48.270953 -409.256356)
			(xy 48.270952 -409.323662) (xy 48.262907 -409.390485) (xy 48.246933 -409.455867) (xy 48.223261 -409.518872)
			(xy 48.192228 -409.578596) (xy 48.15428 -409.634183) (xy 48.132492 -409.659836) (xy 48.126697 -409.666982)
			(xy 48.120182 -409.684172) (xy 48.119792 -409.693364) (xy 48.119792 -410.186632) (xy 48.120188 -410.195821)
			(xy 48.126712 -410.213005) (xy 48.132492 -410.22016) (xy 48.154263 -410.245825) (xy 48.19221 -410.301411)
			(xy 48.223243 -410.361133) (xy 48.246915 -410.424135) (xy 48.262888 -410.489516) (xy 48.270933 -410.556336)
			(xy 48.270934 -410.62364) (xy 48.262892 -410.690461) (xy 48.246922 -410.755842) (xy 48.223252 -410.818845)
			(xy 48.192223 -410.878569) (xy 48.154278 -410.934155) (xy 48.132492 -410.959808) (xy 48.126709 -410.966963)
			(xy 48.120186 -410.984146) (xy 48.119792 -410.993336) (xy 48.119792 -411.151324) (xy 48.119398 -411.161481)
			(xy 48.111593 -411.180235) (xy 48.097188 -411.194558) (xy 48.078389 -411.202255) (xy 48.06823 -411.202632)
			(xy 47.35195 -411.202632) (xy 47.341823 -411.202132) (xy 47.323098 -411.194415) (xy 47.308739 -411.180132)
			(xy 47.300923 -411.161448) (xy 47.300388 -411.151324) (xy 47.300388 -410.993336) (xy 47.299963 -410.98415)
			(xy 47.29346 -410.966966) (xy 47.287688 -410.959808) (xy 47.265883 -410.934169) (xy 47.227932 -410.878582)
			(xy 47.196896 -410.818857) (xy 47.173222 -410.755851) (xy 47.157249 -410.690466) (xy 47.149205 -410.623642)
			(xy 43.871166 -410.623642) (xy 43.871166 -410.623699) (xy 43.863092 -410.690636) (xy 43.847058 -410.756125)
			(xy 43.823295 -410.819221) (xy 43.792146 -410.879017) (xy 43.754059 -410.934651) (xy 43.732196 -410.960316)
			(xy 43.72641 -410.967468) (xy 43.719889 -410.984653) (xy 43.719496 -410.993844) (xy 43.719496 -411.151324)
			(xy 43.719035 -411.161435) (xy 43.711288 -411.180114) (xy 43.696984 -411.194408) (xy 43.678299 -411.202142)
			(xy 43.668188 -411.202632) (xy 42.951908 -411.202632) (xy 42.941804 -411.202109) (xy 42.923132 -411.19438)
			(xy 42.908838 -411.180095) (xy 42.901097 -411.161428) (xy 42.9006 -411.151324) (xy 42.9006 -410.993844)
			(xy 42.900169 -410.984659) (xy 42.89367 -410.967474) (xy 42.8879 -410.960316) (xy 42.86602 -410.934664)
			(xy 42.827932 -410.879027) (xy 42.796782 -410.819229) (xy 42.773019 -410.756131) (xy 42.756984 -410.69064)
			(xy 42.74891 -410.6237) (xy 39.470864 -410.6237) (xy 39.462827 -410.690463) (xy 39.446854 -410.755845)
			(xy 39.423181 -410.818849) (xy 39.392147 -410.878572) (xy 39.354196 -410.934157) (xy 39.332408 -410.959808)
			(xy 39.326626 -410.966964) (xy 39.320103 -410.984146) (xy 39.319708 -410.993336) (xy 39.319708 -411.151324)
			(xy 39.319298 -411.161479) (xy 39.311496 -411.18023) (xy 39.297096 -411.194552) (xy 39.278303 -411.202253)
			(xy 39.268146 -411.202632) (xy 38.551866 -411.202632) (xy 38.541734 -411.202201) (xy 38.523006 -411.194456)
			(xy 38.50865 -411.180153) (xy 38.500837 -411.161454) (xy 38.500304 -411.151324) (xy 38.500304 -410.993336)
			(xy 38.499876 -410.984151) (xy 38.493375 -410.966966) (xy 38.487604 -410.959808) (xy 38.465802 -410.934168)
			(xy 38.427856 -410.878579) (xy 38.396825 -410.818854) (xy 38.373155 -410.755848) (xy 38.357184 -410.690464)
			(xy 38.349141 -410.623641) (xy 35.071078 -410.623641) (xy 35.071078 -410.623699) (xy 35.063004 -410.690636)
			(xy 35.046971 -410.756124) (xy 35.023209 -410.81922) (xy 34.992061 -410.879016) (xy 34.953975 -410.934651)
			(xy 34.932112 -410.960316) (xy 34.926328 -410.96747) (xy 34.919805 -410.984654) (xy 34.919412 -410.993844)
			(xy 34.919412 -411.151324) (xy 34.918935 -411.161433) (xy 34.911192 -411.180109) (xy 34.896893 -411.194403)
			(xy 34.878213 -411.202139) (xy 34.868104 -411.202632) (xy 34.151824 -411.202632) (xy 34.141721 -411.202096)
			(xy 34.123049 -411.194372) (xy 34.108755 -411.180091) (xy 34.101013 -411.161427) (xy 34.100516 -411.151324)
			(xy 34.100516 -410.993844) (xy 34.100081 -410.98466) (xy 34.093584 -410.967475) (xy 34.087816 -410.960316)
			(xy 34.065936 -410.934664) (xy 34.027846 -410.879028) (xy 33.996696 -410.81923) (xy 33.972932 -410.756131)
			(xy 33.956897 -410.690641) (xy 33.948822 -410.623701) (xy 30.670776 -410.623701) (xy 30.66274 -410.690462)
			(xy 30.646767 -410.755844) (xy 30.623095 -410.818848) (xy 30.592061 -410.878571) (xy 30.554112 -410.934156)
			(xy 30.532324 -410.959808) (xy 30.526544 -410.966965) (xy 30.520019 -410.984146) (xy 30.519624 -410.993336)
			(xy 30.519624 -411.151324) (xy 30.519199 -411.161477) (xy 30.5114 -411.180225) (xy 30.497005 -411.194547)
			(xy 30.478217 -411.20225) (xy 30.468062 -411.202632) (xy 29.751782 -411.202632) (xy 29.741651 -411.202188)
			(xy 29.722924 -411.194449) (xy 29.708567 -411.180149) (xy 29.700753 -411.161453) (xy 29.70022 -411.151324)
			(xy 29.70022 -410.993336) (xy 29.699788 -410.984151) (xy 29.693289 -410.966967) (xy 29.68752 -410.959808)
			(xy 29.665717 -410.934169) (xy 29.62777 -410.87858) (xy 29.596738 -410.818854) (xy 29.573067 -410.755848)
			(xy 29.557096 -410.690465) (xy 29.549054 -410.623641) (xy 0.508 -410.623641) (xy 0.508 -416.589972)
			(xy 0.508522 -416.645779) (xy 0.516863 -416.757081) (xy 0.533498 -416.867448) (xy 0.558335 -416.976264)
			(xy 0.591234 -417.082919) (xy 0.632011 -417.186818) (xy 0.680438 -417.287379) (xy 0.681656 -417.289488)
			(xy 53.073808 -417.289488) (xy 53.073808 -394.27912) (xy 66.477388 -394.27912) (xy 66.525648 -394.32738)
			(xy 66.525648 -397.823885) (xy 71.348788 -397.823885) (xy 71.348792 -397.756458) (xy 71.356871 -397.689518)
			(xy 71.372911 -397.624026) (xy 71.396679 -397.560928) (xy 71.427833 -397.501131) (xy 71.465926 -397.445495)
			(xy 71.487792 -397.41983) (xy 71.4936 -397.412693) (xy 71.500108 -397.395496) (xy 71.500492 -397.386302)
			(xy 71.500492 -396.89405) (xy 71.50006 -396.884865) (xy 71.493562 -396.86768) (xy 71.487792 -396.860522)
			(xy 71.465918 -396.834865) (xy 71.427831 -396.779229) (xy 71.396681 -396.719431) (xy 71.372918 -396.656334)
			(xy 71.356883 -396.590844) (xy 71.348808 -396.523905) (xy 71.348809 -396.45648) (xy 71.356886 -396.389542)
			(xy 71.372922 -396.324052) (xy 71.396687 -396.260955) (xy 71.427838 -396.201158) (xy 71.465928 -396.145523)
			(xy 71.487792 -396.119858) (xy 71.493588 -396.112712) (xy 71.500103 -396.095522) (xy 71.500492 -396.08633)
			(xy 71.500492 -395.92885) (xy 71.501066 -395.918732) (xy 71.508769 -395.900021) (xy 71.523028 -395.885665)
			(xy 71.541686 -395.877836) (xy 71.5518 -395.877288) (xy 72.26808 -395.877288) (xy 72.278231 -395.877738)
			(xy 72.296981 -395.885524) (xy 72.311305 -395.899912) (xy 72.319007 -395.918697) (xy 72.319388 -395.92885)
			(xy 72.319388 -396.08633) (xy 72.319786 -396.095518) (xy 72.326308 -396.112703) (xy 72.332088 -396.119858)
			(xy 72.353943 -396.145531) (xy 72.392032 -396.201164) (xy 72.423184 -396.260959) (xy 72.446949 -396.324055)
			(xy 72.462986 -396.389543) (xy 72.471063 -396.456481) (xy 72.471064 -396.523904) (xy 72.462989 -396.590842)
			(xy 72.446954 -396.656331) (xy 72.42319 -396.719427) (xy 72.39204 -396.779223) (xy 72.353952 -396.834857)
			(xy 72.332088 -396.860522) (xy 72.326298 -396.867672) (xy 72.31978 -396.884859) (xy 72.319388 -396.89405)
			(xy 72.319388 -397.386302) (xy 72.3198 -397.395489) (xy 72.326313 -397.412673) (xy 72.332088 -397.41983)
			(xy 72.353915 -397.445526) (xy 72.392006 -397.501156) (xy 72.420766 -397.556355) (xy 73.54898 -397.556355)
			(xy 73.557023 -397.489534) (xy 73.572995 -397.424152) (xy 73.596666 -397.361148) (xy 73.627698 -397.301425)
			(xy 73.665645 -397.245838) (xy 73.687432 -397.220186) (xy 73.693221 -397.213036) (xy 73.69974 -397.195849)
			(xy 73.700132 -397.186658) (xy 73.700132 -397.028924) (xy 73.700542 -397.018767) (xy 73.708335 -397.000009)
			(xy 73.722736 -396.985684) (xy 73.741535 -396.977989) (xy 73.751694 -396.977616) (xy 74.467974 -396.977616)
			(xy 74.478096 -396.978147) (xy 74.496812 -396.985862) (xy 74.511169 -397.000134) (xy 74.518993 -397.018805)
			(xy 74.519536 -397.028924) (xy 74.519536 -397.186658) (xy 74.519981 -397.195841) (xy 74.526472 -397.213025)
			(xy 74.532236 -397.220186) (xy 74.554034 -397.24583) (xy 74.591984 -397.301417) (xy 74.623019 -397.361141)
			(xy 74.646692 -397.424147) (xy 74.662665 -397.48953) (xy 74.670709 -397.556354) (xy 74.670708 -397.623661)
			(xy 74.662662 -397.690484) (xy 74.646687 -397.755867) (xy 74.623012 -397.818872) (xy 74.620438 -397.823826)
			(xy 75.749084 -397.823826) (xy 75.749087 -397.756517) (xy 75.757136 -397.689691) (xy 75.773114 -397.624306)
			(xy 75.796793 -397.5613) (xy 75.827833 -397.501576) (xy 75.865789 -397.44599) (xy 75.88758 -397.420338)
			(xy 75.893383 -397.413197) (xy 75.899895 -397.396003) (xy 75.90028 -397.38681) (xy 75.90028 -396.893542)
			(xy 75.899854 -396.884356) (xy 75.893352 -396.867172) (xy 75.88758 -396.860014) (xy 75.865781 -396.83437)
			(xy 75.82783 -396.778784) (xy 75.796795 -396.719059) (xy 75.773121 -396.656054) (xy 75.757147 -396.59067)
			(xy 75.749104 -396.523846) (xy 75.749104 -396.456539) (xy 75.75715 -396.389715) (xy 75.773125 -396.324332)
			(xy 75.796801 -396.261327) (xy 75.827838 -396.201603) (xy 75.86579 -396.146018) (xy 75.88758 -396.120366)
			(xy 75.893371 -396.113217) (xy 75.89989 -396.096029) (xy 75.90028 -396.086838) (xy 75.90028 -395.92885)
			(xy 75.900706 -395.918676) (xy 75.908482 -395.899875) (xy 75.922868 -395.885487) (xy 75.941668 -395.877707)
			(xy 75.951842 -395.877288) (xy 76.668122 -395.877288) (xy 76.678301 -395.877647) (xy 76.697106 -395.885449)
			(xy 76.711492 -395.899855) (xy 76.719267 -395.91867) (xy 76.719684 -395.92885) (xy 76.719684 -396.086838)
			(xy 76.720079 -396.096027) (xy 76.726604 -396.113211) (xy 76.732384 -396.120366) (xy 76.754161 -396.146026)
			(xy 76.792109 -396.201612) (xy 76.823141 -396.261335) (xy 76.846814 -396.324338) (xy 76.862787 -396.389719)
			(xy 76.870831 -396.456541) (xy 76.870832 -396.523844) (xy 76.862789 -396.590666) (xy 76.846818 -396.656047)
			(xy 76.823147 -396.719051) (xy 76.792117 -396.778775) (xy 76.75417 -396.834362) (xy 76.732384 -396.860014)
			(xy 76.726597 -396.867166) (xy 76.720077 -396.884351) (xy 76.719684 -396.893542) (xy 76.719684 -397.38681)
			(xy 76.720093 -397.395997) (xy 76.726608 -397.413181) (xy 76.732384 -397.420338) (xy 76.754133 -397.446021)
			(xy 76.792082 -397.501604) (xy 76.820503 -397.556296) (xy 77.948748 -397.556296) (xy 77.956824 -397.489358)
			(xy 77.972859 -397.423869) (xy 77.996623 -397.360772) (xy 78.027774 -397.300977) (xy 78.065864 -397.245343)
			(xy 78.087728 -397.219678) (xy 78.09352 -397.21253) (xy 78.100037 -397.195341) (xy 78.100428 -397.18615)
			(xy 78.100428 -397.028924) (xy 78.100836 -397.0188) (xy 78.108582 -397.000091) (xy 78.122901 -396.985775)
			(xy 78.141611 -396.978034) (xy 78.151736 -396.977616) (xy 78.868016 -396.977616) (xy 78.878142 -396.978003)
			(xy 78.896849 -396.985759) (xy 78.911163 -397.000085) (xy 78.918905 -397.018798) (xy 78.919324 -397.028924)
			(xy 78.919324 -397.18615) (xy 78.919753 -397.195335) (xy 78.926253 -397.21252) (xy 78.932024 -397.219678)
			(xy 78.953897 -397.245336) (xy 78.991984 -397.300972) (xy 79.023133 -397.360769) (xy 79.046895 -397.423867)
			(xy 79.062929 -397.489357) (xy 79.071004 -397.556296) (xy 79.071003 -397.62372) (xy 79.062927 -397.690658)
			(xy 79.046891 -397.756147) (xy 79.023127 -397.819245) (xy 79.02071 -397.823885) (xy 80.148876 -397.823885)
			(xy 80.14888 -397.756458) (xy 80.156959 -397.689518) (xy 80.172998 -397.624027) (xy 80.196765 -397.560929)
			(xy 80.227919 -397.501131) (xy 80.266011 -397.445496) (xy 80.287876 -397.41983) (xy 80.293682 -397.412691)
			(xy 80.300192 -397.395496) (xy 80.300576 -397.386302) (xy 80.300576 -396.89405) (xy 80.300147 -396.884865)
			(xy 80.293647 -396.86768) (xy 80.287876 -396.860522) (xy 80.266003 -396.834864) (xy 80.227916 -396.779228)
			(xy 80.196767 -396.719431) (xy 80.173005 -396.656333) (xy 80.156971 -396.590843) (xy 80.148896 -396.523904)
			(xy 80.148897 -396.45648) (xy 80.156973 -396.389542) (xy 80.173009 -396.324053) (xy 80.196773 -396.260955)
			(xy 80.227924 -396.201159) (xy 80.266012 -396.145524) (xy 80.287876 -396.119858) (xy 80.29367 -396.112711)
			(xy 80.300187 -396.095522) (xy 80.300576 -396.08633) (xy 80.300576 -395.92885) (xy 80.301069 -395.918722)
			(xy 80.308787 -395.899995) (xy 80.323072 -395.885636) (xy 80.341759 -395.877821) (xy 80.351884 -395.877288)
			(xy 81.068164 -395.877288) (xy 81.078314 -395.877751) (xy 81.097063 -395.885532) (xy 81.111388 -395.899917)
			(xy 81.119091 -395.918698) (xy 81.119472 -395.92885) (xy 81.119472 -396.08633) (xy 81.119874 -396.095518)
			(xy 81.126394 -396.112702) (xy 81.132172 -396.119858) (xy 81.154027 -396.145531) (xy 81.192118 -396.201164)
			(xy 81.223271 -396.260959) (xy 81.247037 -396.324054) (xy 81.263074 -396.389543) (xy 81.271151 -396.456481)
			(xy 81.271152 -396.523904) (xy 81.263076 -396.590842) (xy 81.247041 -396.656331) (xy 81.223277 -396.719428)
			(xy 81.192126 -396.779223) (xy 81.154036 -396.834857) (xy 81.132172 -396.860522) (xy 81.12638 -396.86767)
			(xy 81.119863 -396.884859) (xy 81.119472 -396.89405) (xy 81.119472 -397.386302) (xy 81.119887 -397.395489)
			(xy 81.126398 -397.412673) (xy 81.132172 -397.41983) (xy 81.154 -397.445526) (xy 81.192091 -397.501155)
			(xy 81.220853 -397.556356) (xy 82.349068 -397.556356) (xy 82.357111 -397.489534) (xy 82.373082 -397.424153)
			(xy 82.396753 -397.361149) (xy 82.427783 -397.301425) (xy 82.46573 -397.245838) (xy 82.487516 -397.220186)
			(xy 82.493303 -397.213034) (xy 82.499823 -397.195849) (xy 82.500216 -397.186658) (xy 82.500216 -397.028924)
			(xy 82.500641 -397.018769) (xy 82.508432 -397.000014) (xy 82.522828 -396.98569) (xy 82.541621 -396.977992)
			(xy 82.551778 -396.977616) (xy 83.268058 -396.977616) (xy 83.278179 -396.97816) (xy 83.296895 -396.98587)
			(xy 83.311252 -397.000138) (xy 83.319076 -397.018806) (xy 83.31962 -397.028924) (xy 83.31962 -397.186658)
			(xy 83.320046 -397.195844) (xy 83.326548 -397.213028) (xy 83.33232 -397.220186) (xy 83.354119 -397.24583)
			(xy 83.39207 -397.301416) (xy 83.423105 -397.361141) (xy 83.446779 -397.424146) (xy 83.462753 -397.48953)
			(xy 83.470796 -397.556354) (xy 83.470796 -397.623661) (xy 83.46275 -397.690485) (xy 83.446775 -397.755868)
			(xy 83.423099 -397.818873) (xy 83.420495 -397.823884) (xy 84.548667 -397.823884) (xy 84.548671 -397.756458)
			(xy 84.55675 -397.689518) (xy 84.572788 -397.624028) (xy 84.596555 -397.560929) (xy 84.627708 -397.501132)
			(xy 84.665799 -397.445496) (xy 84.687664 -397.41983) (xy 84.693481 -397.412699) (xy 84.699982 -397.395497)
			(xy 84.700364 -397.386302) (xy 84.700364 -396.89405) (xy 84.699916 -396.884867) (xy 84.693427 -396.867683)
			(xy 84.687664 -396.860522) (xy 84.665791 -396.834864) (xy 84.627705 -396.779228) (xy 84.596557 -396.71943)
			(xy 84.572795 -396.656332) (xy 84.556761 -396.590843) (xy 84.548687 -396.523904) (xy 84.548688 -396.456481)
			(xy 84.556764 -396.389542) (xy 84.5728 -396.324053) (xy 84.596563 -396.260956) (xy 84.627713 -396.201159)
			(xy 84.665801 -396.145524) (xy 84.687664 -396.119858) (xy 84.693469 -396.112719) (xy 84.699977 -396.095523)
			(xy 84.700364 -396.08633) (xy 84.700364 -395.92885) (xy 84.700868 -395.918724) (xy 84.708584 -395.899999)
			(xy 84.722866 -395.88564) (xy 84.741548 -395.877823) (xy 84.751672 -395.877288) (xy 85.467952 -395.877288)
			(xy 85.478102 -395.877761) (xy 85.496851 -395.885538) (xy 85.511175 -395.899919) (xy 85.518879 -395.918699)
			(xy 85.51926 -395.92885) (xy 85.51926 -396.08633) (xy 85.519665 -396.095518) (xy 85.526183 -396.112701)
			(xy 85.53196 -396.119858) (xy 85.553816 -396.145531) (xy 85.591907 -396.201163) (xy 85.623061 -396.260958)
			(xy 85.646827 -396.324054) (xy 85.662864 -396.389543) (xy 85.670942 -396.456481) (xy 85.670943 -396.523904)
			(xy 85.662867 -396.590843) (xy 85.646832 -396.656332) (xy 85.623067 -396.719428) (xy 85.591915 -396.779224)
			(xy 85.553825 -396.834857) (xy 85.53196 -396.860522) (xy 85.526167 -396.867669) (xy 85.519651 -396.884858)
			(xy 85.51926 -396.89405) (xy 85.51926 -397.386302) (xy 85.519678 -397.395488) (xy 85.526187 -397.412672)
			(xy 85.53196 -397.41983) (xy 85.553788 -397.445525) (xy 85.591881 -397.501155) (xy 85.620612 -397.556296)
			(xy 86.748836 -397.556296) (xy 86.756911 -397.489358) (xy 86.772946 -397.423869) (xy 86.79671 -397.360773)
			(xy 86.82786 -397.300977) (xy 86.865948 -397.245343) (xy 86.887812 -397.219678) (xy 86.893602 -397.212528)
			(xy 86.90012 -397.195341) (xy 86.900512 -397.18615) (xy 86.900512 -397.028924) (xy 86.900936 -397.018802)
			(xy 86.908678 -397.000096) (xy 86.922993 -396.985781) (xy 86.941698 -396.978037) (xy 86.95182 -396.977616)
			(xy 87.6681 -396.977616) (xy 87.678224 -396.978016) (xy 87.696931 -396.985768) (xy 87.711246 -397.000089)
			(xy 87.718988 -397.018799) (xy 87.719408 -397.028924) (xy 87.719408 -397.18615) (xy 87.71984 -397.195335)
			(xy 87.726338 -397.21252) (xy 87.732108 -397.219678) (xy 87.753982 -397.245335) (xy 87.792069 -397.300971)
			(xy 87.823219 -397.360769) (xy 87.846982 -397.423866) (xy 87.863017 -397.489356) (xy 87.871092 -397.556295)
			(xy 87.871091 -397.62372) (xy 87.863014 -397.690658) (xy 87.846978 -397.756148) (xy 87.823213 -397.819245)
			(xy 87.820827 -397.823826) (xy 88.948962 -397.823826) (xy 88.948966 -397.756517) (xy 88.957014 -397.689692)
			(xy 88.972991 -397.624307) (xy 88.996669 -397.561301) (xy 89.027707 -397.501577) (xy 89.065661 -397.44599)
			(xy 89.087452 -397.420338) (xy 89.093264 -397.413204) (xy 89.099768 -397.396005) (xy 89.100152 -397.38681)
			(xy 89.100152 -396.893542) (xy 89.09971 -396.884358) (xy 89.093217 -396.867175) (xy 89.087452 -396.860014)
			(xy 89.065654 -396.83437) (xy 89.027704 -396.778783) (xy 88.996671 -396.719058) (xy 88.972998 -396.656053)
			(xy 88.957025 -396.590669) (xy 88.948982 -396.523846) (xy 88.948983 -396.456539) (xy 88.957028 -396.389716)
			(xy 88.973003 -396.324333) (xy 88.996677 -396.261328) (xy 89.027712 -396.201604) (xy 89.065663 -396.146018)
			(xy 89.087452 -396.120366) (xy 89.093252 -396.113223) (xy 89.099763 -396.096031) (xy 89.100152 -396.086838)
			(xy 89.100152 -395.92885) (xy 89.100605 -395.91868) (xy 89.108376 -395.899884) (xy 89.122753 -395.885496)
			(xy 89.141544 -395.877712) (xy 89.151714 -395.877288) (xy 89.867994 -395.877288) (xy 89.878171 -395.87767)
			(xy 89.896976 -395.885462) (xy 89.911362 -395.899861) (xy 89.919139 -395.918672) (xy 89.919556 -395.92885)
			(xy 89.919556 -396.086838) (xy 89.919958 -396.096026) (xy 89.926478 -396.11321) (xy 89.932256 -396.120366)
			(xy 89.954034 -396.146026) (xy 89.991983 -396.201611) (xy 90.023017 -396.261334) (xy 90.046691 -396.324337)
			(xy 90.062665 -396.389719) (xy 90.07071 -396.45654) (xy 90.070711 -396.523845) (xy 90.062667 -396.590667)
			(xy 90.046695 -396.656048) (xy 90.023023 -396.719052) (xy 89.991991 -396.778776) (xy 89.954043 -396.834362)
			(xy 89.932256 -396.860014) (xy 89.926465 -396.867163) (xy 89.919948 -396.884351) (xy 89.919556 -396.893542)
			(xy 89.919556 -397.38681) (xy 89.919971 -397.395996) (xy 89.926482 -397.41318) (xy 89.932256 -397.420338)
			(xy 89.954006 -397.446021) (xy 89.991957 -397.501603) (xy 90.020411 -397.556356) (xy 91.149156 -397.556356)
			(xy 91.157198 -397.489535) (xy 91.173169 -397.424153) (xy 91.196839 -397.361149) (xy 91.227869 -397.301426)
			(xy 91.265814 -397.245839) (xy 91.2876 -397.220186) (xy 91.293385 -397.213033) (xy 91.299907 -397.195848)
			(xy 91.3003 -397.186658) (xy 91.3003 -397.028924) (xy 91.300741 -397.018771) (xy 91.308529 -397.000019)
			(xy 91.32292 -396.985695) (xy 91.341708 -396.977995) (xy 91.351862 -396.977616) (xy 92.068142 -396.977616)
			(xy 92.078268 -396.978091) (xy 92.096986 -396.985829) (xy 92.11134 -397.000118) (xy 92.119162 -397.0188)
			(xy 92.119704 -397.028924) (xy 92.119704 -397.186658) (xy 92.120133 -397.195843) (xy 92.126634 -397.213028)
			(xy 92.132404 -397.220186) (xy 92.1542 -397.245831) (xy 92.192146 -397.301419) (xy 92.223176 -397.361144)
			(xy 92.246847 -397.42415) (xy 92.262818 -397.489532) (xy 92.27086 -397.556355) (xy 92.270859 -397.62366)
			(xy 92.262815 -397.690483) (xy 92.246842 -397.755865) (xy 92.22317 -397.81887) (xy 92.220595 -397.823825)
			(xy 115.349226 -397.823825) (xy 115.349229 -397.756518) (xy 115.357277 -397.689693) (xy 115.373253 -397.624309)
			(xy 115.396928 -397.561303) (xy 115.427964 -397.501578) (xy 115.465915 -397.445991) (xy 115.487704 -397.420338)
			(xy 115.49351 -397.413199) (xy 115.500019 -397.396004) (xy 115.500404 -397.38681) (xy 115.500404 -396.893542)
			(xy 115.499973 -396.884357) (xy 115.493474 -396.867173) (xy 115.487704 -396.860014) (xy 115.465908 -396.834369)
			(xy 115.427961 -396.778781) (xy 115.39693 -396.719056) (xy 115.37326 -396.656051) (xy 115.357288 -396.590668)
			(xy 115.349246 -396.523845) (xy 115.349247 -396.45654) (xy 115.357291 -396.389717) (xy 115.373264 -396.324335)
			(xy 115.396937 -396.26133) (xy 115.427969 -396.201606) (xy 115.465917 -396.146019) (xy 115.487704 -396.120366)
			(xy 115.493498 -396.113219) (xy 115.500014 -396.09603) (xy 115.500404 -396.086838) (xy 115.500404 -395.92885)
			(xy 115.500904 -395.918686) (xy 115.508666 -395.899899) (xy 115.523028 -395.885513) (xy 115.541803 -395.87772)
			(xy 115.551966 -395.877288) (xy 116.268246 -395.877288) (xy 116.278427 -395.877627) (xy 116.297232 -395.885437)
			(xy 116.311617 -395.899849) (xy 116.319392 -395.918668) (xy 116.319808 -395.92885) (xy 116.319808 -396.086838)
			(xy 116.320198 -396.096027) (xy 116.326725 -396.113212) (xy 116.332508 -396.120366) (xy 116.354288 -396.146026)
			(xy 116.39224 -396.20161) (xy 116.423277 -396.261332) (xy 116.446952 -396.324335) (xy 116.462928 -396.389717)
			(xy 116.470973 -396.45654) (xy 116.470974 -396.523845) (xy 116.46293 -396.590668) (xy 116.446957 -396.65605)
			(xy 116.423283 -396.719055) (xy 116.392248 -396.778777) (xy 116.354297 -396.834363) (xy 116.332508 -396.860014)
			(xy 116.326724 -396.867168) (xy 116.320202 -396.884352) (xy 116.319808 -396.893542) (xy 116.319808 -397.38681)
			(xy 116.320212 -397.395998) (xy 116.32673 -397.413182) (xy 116.332508 -397.420338) (xy 116.35426 -397.44602)
			(xy 116.392213 -397.501601) (xy 116.42064 -397.556296) (xy 117.548866 -397.556296) (xy 117.556942 -397.489357)
			(xy 117.572978 -397.423868) (xy 117.596743 -397.360771) (xy 117.627896 -397.300976) (xy 117.665987 -397.245342)
			(xy 117.687852 -397.219678) (xy 117.693647 -397.212532) (xy 117.700161 -397.195342) (xy 117.700552 -397.18615)
			(xy 117.700552 -397.028924) (xy 117.701103 -397.018823) (xy 117.708824 -397.000154) (xy 117.7231 -396.98586)
			(xy 117.741759 -396.978116) (xy 117.75186 -396.977616) (xy 118.46814 -396.977616) (xy 118.478253 -396.978053)
			(xy 118.496935 -396.985807) (xy 118.511229 -397.000118) (xy 118.51896 -397.01881) (xy 118.519448 -397.028924)
			(xy 118.519448 -397.18615) (xy 118.519894 -397.195333) (xy 118.526384 -397.212517) (xy 118.532148 -397.219678)
			(xy 118.554024 -397.245334) (xy 118.592115 -397.300969) (xy 118.623269 -397.360766) (xy 118.647035 -397.423864)
			(xy 118.663071 -397.489355) (xy 118.671147 -397.556295) (xy 118.671146 -397.62372) (xy 118.663068 -397.69066)
			(xy 118.64703 -397.75615) (xy 118.623262 -397.819248) (xy 118.620846 -397.823885) (xy 119.748994 -397.823885)
			(xy 119.748998 -397.756458) (xy 119.757077 -397.689517) (xy 119.773117 -397.624026) (xy 119.796885 -397.560928)
			(xy 119.828041 -397.50113) (xy 119.866134 -397.445495) (xy 119.888 -397.41983) (xy 119.893809 -397.412693)
			(xy 119.900316 -397.395496) (xy 119.9007 -397.386302) (xy 119.9007 -396.89405) (xy 119.900266 -396.884865)
			(xy 119.893769 -396.867681) (xy 119.888 -396.860522) (xy 119.866126 -396.834865) (xy 119.828038 -396.779229)
			(xy 119.796888 -396.719432) (xy 119.773124 -396.656334) (xy 119.757089 -396.590844) (xy 119.749014 -396.523905)
			(xy 119.749015 -396.45648) (xy 119.757092 -396.389541) (xy 119.773128 -396.324052) (xy 119.796894 -396.260954)
			(xy 119.828046 -396.201158) (xy 119.866135 -396.145523) (xy 119.888 -396.119858) (xy 119.893797 -396.112713)
			(xy 119.900311 -396.095522) (xy 119.9007 -396.08633) (xy 119.9007 -395.92885) (xy 119.901266 -395.918731)
			(xy 119.90897 -395.900019) (xy 119.923232 -395.885662) (xy 119.941893 -395.877834) (xy 119.952008 -395.877288)
			(xy 120.668288 -395.877288) (xy 120.678408 -395.877725) (xy 120.697109 -395.885467) (xy 120.711424 -395.899777)
			(xy 120.719171 -395.918476) (xy 120.719596 -395.928596) (xy 120.719596 -396.08633) (xy 120.719992 -396.095519)
			(xy 120.726516 -396.112703) (xy 120.732296 -396.119858) (xy 120.75415 -396.145531) (xy 120.79224 -396.201165)
			(xy 120.823391 -396.26096) (xy 120.847156 -396.324055) (xy 120.863192 -396.389544) (xy 120.871269 -396.456481)
			(xy 120.87127 -396.523904) (xy 120.863195 -396.590842) (xy 120.84716 -396.65633) (xy 120.823397 -396.719427)
			(xy 120.792247 -396.779223) (xy 120.75416 -396.834857) (xy 120.732296 -396.860522) (xy 120.726507 -396.867673)
			(xy 120.719988 -396.884859) (xy 120.719596 -396.89405) (xy 120.719596 -397.386302) (xy 120.720006 -397.395489)
			(xy 120.72652 -397.412673) (xy 120.732296 -397.41983) (xy 120.754123 -397.445526) (xy 120.792213 -397.501156)
			(xy 120.820972 -397.556355) (xy 121.949186 -397.556355) (xy 121.95723 -397.489533) (xy 121.973202 -397.424152)
			(xy 121.996873 -397.361148) (xy 122.027905 -397.301425) (xy 122.065853 -397.245838) (xy 122.08764 -397.220186)
			(xy 122.09343 -397.213036) (xy 122.099948 -397.195849) (xy 122.10034 -397.186658) (xy 122.10034 -397.028924)
			(xy 122.100736 -397.018798) (xy 122.108484 -397.000087) (xy 122.122807 -396.985771) (xy 122.141522 -396.978032)
			(xy 122.151648 -396.977616) (xy 122.868182 -396.977616) (xy 122.878305 -396.978141) (xy 122.897021 -396.985858)
			(xy 122.911377 -397.000132) (xy 122.919201 -397.018804) (xy 122.919744 -397.028924) (xy 122.919744 -397.186658)
			(xy 122.920187 -397.195841) (xy 122.926679 -397.213026) (xy 122.932444 -397.220186) (xy 122.954242 -397.24583)
			(xy 122.992192 -397.301417) (xy 123.023225 -397.361142) (xy 123.046898 -397.424147) (xy 123.062871 -397.489531)
			(xy 123.070915 -397.556354) (xy 123.070914 -397.623661) (xy 123.062868 -397.690484) (xy 123.046894 -397.755867)
			(xy 123.023219 -397.818872) (xy 123.020645 -397.823826) (xy 124.14929 -397.823826) (xy 124.149293 -397.756517)
			(xy 124.157342 -397.689691) (xy 124.17332 -397.624306) (xy 124.197 -397.5613) (xy 124.22804 -397.501575)
			(xy 124.265997 -397.44599) (xy 124.287788 -397.420338) (xy 124.293592 -397.413198) (xy 124.300103 -397.396004)
			(xy 124.300488 -397.38681) (xy 124.300488 -396.893542) (xy 124.30006 -396.884357) (xy 124.293559 -396.867172)
			(xy 124.287788 -396.860014) (xy 124.265989 -396.834371) (xy 124.228037 -396.778784) (xy 124.197002 -396.71906)
			(xy 124.173327 -396.656054) (xy 124.157354 -396.59067) (xy 124.14931 -396.523846) (xy 124.14931 -396.456539)
			(xy 124.157356 -396.389715) (xy 124.173332 -396.324332) (xy 124.197008 -396.261327) (xy 124.228045 -396.201603)
			(xy 124.265998 -396.146018) (xy 124.287788 -396.120366) (xy 124.29358 -396.113218) (xy 124.300098 -396.09603)
			(xy 124.300488 -396.086838) (xy 124.300488 -395.92885) (xy 124.300906 -395.918675) (xy 124.308684 -395.899872)
			(xy 124.323072 -395.885484) (xy 124.341875 -395.877706) (xy 124.35205 -395.877288) (xy 125.06833 -395.877288)
			(xy 125.07851 -395.87764) (xy 125.097315 -395.885445) (xy 125.1117 -395.899852) (xy 125.119475 -395.91867)
			(xy 125.119892 -395.92885) (xy 125.119892 -396.086838) (xy 125.120286 -396.096027) (xy 125.126811 -396.113211)
			(xy 125.132592 -396.120366) (xy 125.154369 -396.146027) (xy 125.192316 -396.201613) (xy 125.223348 -396.261335)
			(xy 125.24702 -396.324339) (xy 125.262993 -396.389719) (xy 125.271037 -396.456541) (xy 125.271038 -396.523844)
			(xy 125.262995 -396.590666) (xy 125.247025 -396.656047) (xy 125.223354 -396.719051) (xy 125.192324 -396.778774)
			(xy 125.154378 -396.834361) (xy 125.132592 -396.860014) (xy 125.126806 -396.867167) (xy 125.120285 -396.884351)
			(xy 125.119892 -396.893542) (xy 125.119892 -397.38681) (xy 125.120299 -397.395998) (xy 125.126815 -397.413182)
			(xy 125.132592 -397.420338) (xy 125.154341 -397.446021) (xy 125.192289 -397.501604) (xy 125.22071 -397.556296)
			(xy 126.348954 -397.556296) (xy 126.35703 -397.489357) (xy 126.373065 -397.423869) (xy 126.39683 -397.360772)
			(xy 126.427981 -397.300976) (xy 126.466071 -397.245343) (xy 126.487936 -397.219678) (xy 126.493729 -397.21253)
			(xy 126.500245 -397.195342) (xy 126.500636 -397.18615) (xy 126.500636 -397.028924) (xy 126.501036 -397.018799)
			(xy 126.508783 -397.000089) (xy 126.523105 -396.985772) (xy 126.541818 -396.978032) (xy 126.551944 -396.977616)
			(xy 127.268224 -396.977616) (xy 127.278336 -396.978066) (xy 127.297018 -396.985814) (xy 127.311313 -397.000122)
			(xy 127.319044 -397.018811) (xy 127.319532 -397.028924) (xy 127.319532 -397.18615) (xy 127.319981 -397.195333)
			(xy 127.326469 -397.212517) (xy 127.332232 -397.219678) (xy 127.354105 -397.245336) (xy 127.392191 -397.300972)
			(xy 127.423339 -397.36077) (xy 127.447102 -397.423867) (xy 127.463135 -397.489357) (xy 127.47121 -397.556296)
			(xy 127.471209 -397.623719) (xy 127.463133 -397.690658) (xy 127.447097 -397.756147) (xy 127.423333 -397.819244)
			(xy 127.420946 -397.823826) (xy 128.54908 -397.823826) (xy 128.549084 -397.756517) (xy 128.557132 -397.689691)
			(xy 128.57311 -397.624306) (xy 128.596789 -397.5613) (xy 128.627829 -397.501576) (xy 128.665785 -397.445989)
			(xy 128.687576 -397.420338) (xy 128.693379 -397.413197) (xy 128.69989 -397.396003) (xy 128.700276 -397.38681)
			(xy 128.700276 -396.893542) (xy 128.699851 -396.884356) (xy 128.693348 -396.867171) (xy 128.687576 -396.860014)
			(xy 128.665777 -396.83437) (xy 128.627826 -396.778784) (xy 128.596792 -396.719059) (xy 128.573118 -396.656053)
			(xy 128.557144 -396.59067) (xy 128.5491 -396.523846) (xy 128.549101 -396.456539) (xy 128.557147 -396.389715)
			(xy 128.573122 -396.324332) (xy 128.596798 -396.261327) (xy 128.627834 -396.201604) (xy 128.665787 -396.146018)
			(xy 128.687576 -396.120366) (xy 128.693367 -396.113216) (xy 128.699886 -396.096029) (xy 128.700276 -396.086838)
			(xy 128.700276 -395.92885) (xy 128.700706 -395.918677) (xy 128.708481 -395.899876) (xy 128.722866 -395.885488)
			(xy 128.741665 -395.877708) (xy 128.751838 -395.877288) (xy 129.468118 -395.877288) (xy 129.478297 -395.87765)
			(xy 129.497102 -395.885451) (xy 129.511487 -395.899856) (xy 129.519263 -395.91867) (xy 129.51968 -395.92885)
			(xy 129.51968 -396.086838) (xy 129.520076 -396.096027) (xy 129.5266 -396.113211) (xy 129.53238 -396.120366)
			(xy 129.554157 -396.146026) (xy 129.592105 -396.201612) (xy 129.623138 -396.261335) (xy 129.64681 -396.324338)
			(xy 129.662784 -396.389719) (xy 129.670828 -396.456541) (xy 129.670829 -396.523844) (xy 129.662786 -396.590666)
			(xy 129.646815 -396.656047) (xy 129.623144 -396.719051) (xy 129.592113 -396.778775) (xy 129.554167 -396.834362)
			(xy 129.53238 -396.860014) (xy 129.526593 -396.867166) (xy 129.520073 -396.884351) (xy 129.51968 -396.893542)
			(xy 129.51968 -397.38681) (xy 129.52009 -397.395997) (xy 129.526604 -397.413181) (xy 129.53238 -397.420338)
			(xy 129.55413 -397.446021) (xy 129.592078 -397.501604) (xy 129.620531 -397.556356) (xy 130.749274 -397.556356)
			(xy 130.757317 -397.489534) (xy 130.773288 -397.424152) (xy 130.796959 -397.361148) (xy 130.827991 -397.301425)
			(xy 130.865937 -397.245838) (xy 130.887724 -397.220186) (xy 130.893512 -397.213035) (xy 130.900031 -397.195849)
			(xy 130.900424 -397.186658) (xy 130.900424 -397.028924) (xy 130.900842 -397.018768) (xy 130.908634 -397.000012)
			(xy 130.923032 -396.985687) (xy 130.941828 -396.97799) (xy 130.951986 -396.977616) (xy 131.668266 -396.977616)
			(xy 131.678388 -396.978154) (xy 131.697103 -396.985866) (xy 131.71146 -397.000137) (xy 131.719284 -397.018806)
			(xy 131.719828 -397.028924) (xy 131.719828 -397.186658) (xy 131.720252 -397.195844) (xy 131.726756 -397.213029)
			(xy 131.732528 -397.220186) (xy 131.754326 -397.24583) (xy 131.792277 -397.301417) (xy 131.823312 -397.361141)
			(xy 131.846985 -397.424147) (xy 131.862959 -397.48953) (xy 131.871003 -397.556354) (xy 131.871002 -397.623661)
			(xy 131.862956 -397.690485) (xy 131.846981 -397.755868) (xy 131.823306 -397.818873) (xy 131.792269 -397.878596)
			(xy 131.754317 -397.934182) (xy 131.732528 -397.959834) (xy 131.726726 -397.966975) (xy 131.720217 -397.984169)
			(xy 131.719828 -397.993362) (xy 131.719828 -398.486884) (xy 131.720239 -398.496071) (xy 131.726751 -398.513256)
			(xy 131.732528 -398.520412) (xy 131.754352 -398.546034) (xy 131.792302 -398.601624) (xy 131.823336 -398.661352)
			(xy 131.847008 -398.72436) (xy 131.86298 -398.789746) (xy 131.871021 -398.856573) (xy 131.871018 -398.923881)
			(xy 131.86297 -398.990707) (xy 131.846992 -399.056092) (xy 131.823314 -399.119098) (xy 131.792274 -399.178822)
			(xy 131.754319 -399.234408) (xy 131.732528 -399.26006) (xy 131.726715 -399.267193) (xy 131.720212 -399.284393)
			(xy 131.719828 -399.293588) (xy 131.719828 -399.451576) (xy 131.719359 -399.461725) (xy 131.711577 -399.480472)
			(xy 131.697195 -399.494795) (xy 131.678417 -399.502501) (xy 131.668266 -399.502884) (xy 130.951986 -399.502884)
			(xy 130.941861 -399.502385) (xy 130.923145 -399.494657) (xy 130.90879 -399.480375) (xy 130.900967 -399.461698)
			(xy 130.900424 -399.451576) (xy 130.900424 -399.293588) (xy 130.900014 -399.284401) (xy 130.8935 -399.267217)
			(xy 130.887724 -399.26006) (xy 130.865972 -399.234378) (xy 130.828023 -399.178796) (xy 130.796989 -399.119076)
			(xy 130.773315 -399.056076) (xy 130.75734 -398.990697) (xy 130.749294 -398.923878) (xy 130.74929 -398.856576)
			(xy 130.757331 -398.789756) (xy 130.773299 -398.724376) (xy 130.796967 -398.661373) (xy 130.827996 -398.601651)
			(xy 130.865939 -398.546065) (xy 130.887724 -398.520412) (xy 130.893543 -398.513283) (xy 130.900044 -398.49608)
			(xy 130.900424 -398.486884) (xy 130.900424 -397.993362) (xy 130.900027 -397.984174) (xy 130.893504 -397.96699)
			(xy 130.887724 -397.959834) (xy 130.865946 -397.934174) (xy 130.827998 -397.878588) (xy 130.796965 -397.818865)
			(xy 130.773293 -397.755862) (xy 130.75732 -397.690481) (xy 130.749275 -397.62366) (xy 130.749274 -397.556356)
			(xy 129.620531 -397.556356) (xy 129.623112 -397.561323) (xy 129.646786 -397.624324) (xy 129.662761 -397.689702)
			(xy 129.670808 -397.756521) (xy 129.670811 -397.823822) (xy 129.662771 -397.890642) (xy 129.646803 -397.956022)
			(xy 129.623135 -398.019025) (xy 129.592108 -398.078747) (xy 129.554165 -398.134333) (xy 129.53238 -398.159986)
			(xy 129.526562 -398.167116) (xy 129.520061 -398.184318) (xy 129.51968 -398.193514) (xy 129.51968 -398.351502)
			(xy 129.519169 -398.361658) (xy 129.511397 -398.380423) (xy 129.497037 -398.394788) (xy 129.478274 -398.402565)
			(xy 129.468118 -398.403064) (xy 128.751838 -398.403064) (xy 128.741669 -398.402605) (xy 128.722876 -398.394833)
			(xy 128.70849 -398.380458) (xy 128.700703 -398.361671) (xy 128.700276 -398.351502) (xy 128.700276 -398.193514)
			(xy 128.699865 -398.184327) (xy 128.693352 -398.167142) (xy 128.687576 -398.159986) (xy 128.66575 -398.134365)
			(xy 128.627799 -398.078775) (xy 128.596766 -398.019048) (xy 128.573093 -397.956039) (xy 128.557122 -397.890652)
			(xy 128.54908 -397.823826) (xy 127.420946 -397.823826) (xy 127.392183 -397.879041) (xy 127.354095 -397.934676)
			(xy 127.332232 -397.960342) (xy 127.326427 -397.967481) (xy 127.319919 -397.984676) (xy 127.319532 -397.99387)
			(xy 127.319532 -398.486376) (xy 127.319969 -398.49556) (xy 127.326466 -398.512744) (xy 127.332232 -398.519904)
			(xy 127.35413 -398.545541) (xy 127.392216 -398.60118) (xy 127.423363 -398.66098) (xy 127.447124 -398.724081)
			(xy 127.463156 -398.789573) (xy 127.471228 -398.856514) (xy 127.471225 -398.92394) (xy 127.463146 -398.99088)
			(xy 127.447108 -399.056371) (xy 127.423341 -399.119469) (xy 127.392188 -399.179266) (xy 127.354097 -399.234902)
			(xy 127.332232 -399.260568) (xy 127.326416 -399.267699) (xy 127.319915 -399.284901) (xy 127.319532 -399.294096)
			(xy 127.319532 -399.451576) (xy 127.318996 -399.461679) (xy 127.311272 -399.480351) (xy 127.296991 -399.494645)
			(xy 127.278327 -399.502387) (xy 127.268224 -399.502884) (xy 126.551944 -399.502884) (xy 126.541822 -399.502447)
			(xy 126.523117 -399.494711) (xy 126.5088 -399.4804) (xy 126.501056 -399.461697) (xy 126.500636 -399.451576)
			(xy 126.500636 -399.294096) (xy 126.50022 -399.28491) (xy 126.49371 -399.267726) (xy 126.487936 -399.260568)
			(xy 126.466106 -399.234874) (xy 126.428014 -399.179245) (xy 126.39686 -399.119453) (xy 126.373092 -399.056359)
			(xy 126.357053 -398.990873) (xy 126.348974 -398.923938) (xy 126.34897 -398.856516) (xy 126.357043 -398.78958)
			(xy 126.373076 -398.724092) (xy 126.396838 -398.660997) (xy 126.427986 -398.601202) (xy 126.466073 -398.545569)
			(xy 126.487936 -398.519904) (xy 126.493718 -398.512749) (xy 126.50024 -398.495566) (xy 126.500636 -398.486376)
			(xy 126.500636 -397.99387) (xy 126.500232 -397.984682) (xy 126.493713 -397.967498) (xy 126.487936 -397.960342)
			(xy 126.466081 -397.934669) (xy 126.427989 -397.879037) (xy 126.396836 -397.819242) (xy 126.37307 -397.756146)
			(xy 126.357032 -397.690657) (xy 126.348955 -397.623719) (xy 126.348954 -397.556296) (xy 125.22071 -397.556296)
			(xy 125.223323 -397.561324) (xy 125.246996 -397.624324) (xy 125.262971 -397.689702) (xy 125.271018 -397.756521)
			(xy 125.271021 -397.823822) (xy 125.262981 -397.890642) (xy 125.247013 -397.956021) (xy 125.223346 -398.019024)
			(xy 125.192319 -398.078747) (xy 125.154377 -398.134334) (xy 125.132592 -398.159986) (xy 125.126775 -398.167117)
			(xy 125.120273 -398.184318) (xy 125.119892 -398.193514) (xy 125.119892 -398.351502) (xy 125.119369 -398.361656)
			(xy 125.111599 -398.38042) (xy 125.097243 -398.394784) (xy 125.078484 -398.402563) (xy 125.06833 -398.403064)
			(xy 124.35205 -398.403064) (xy 124.341882 -398.402595) (xy 124.323089 -398.394827) (xy 124.308702 -398.380455)
			(xy 124.300915 -398.36167) (xy 124.300488 -398.351502) (xy 124.300488 -398.193514) (xy 124.300074 -398.184327)
			(xy 124.293563 -398.167143) (xy 124.287788 -398.159986) (xy 124.265961 -398.134365) (xy 124.228011 -398.078775)
			(xy 124.196976 -398.019048) (xy 124.173304 -397.956039) (xy 124.157332 -397.890653) (xy 124.14929 -397.823826)
			(xy 123.020645 -397.823826) (xy 122.992184 -397.878596) (xy 122.954233 -397.934182) (xy 122.932444 -397.959834)
			(xy 122.926644 -397.966976) (xy 122.920133 -397.984169) (xy 122.919744 -397.993362) (xy 122.919744 -398.486884)
			(xy 122.920174 -398.496069) (xy 122.926675 -398.513253) (xy 122.932444 -398.520412) (xy 122.954268 -398.546035)
			(xy 122.992217 -398.601625) (xy 123.023249 -398.661352) (xy 123.046921 -398.724361) (xy 123.062892 -398.789747)
			(xy 123.070933 -398.856573) (xy 123.07093 -398.923881) (xy 123.062882 -398.990707) (xy 123.046905 -399.056091)
			(xy 123.023227 -399.119097) (xy 122.992189 -399.178822) (xy 122.954235 -399.234408) (xy 122.932444 -399.26006)
			(xy 122.926633 -399.267194) (xy 122.920128 -399.284393) (xy 122.919744 -399.293588) (xy 122.919744 -399.451576)
			(xy 122.919196 -399.461678) (xy 122.911475 -399.480347) (xy 122.897197 -399.494641) (xy 122.878537 -399.502385)
			(xy 122.868436 -399.502884) (xy 122.151902 -399.502884) (xy 122.141778 -399.502372) (xy 122.123062 -399.49465)
			(xy 122.108706 -399.480371) (xy 122.100883 -399.461697) (xy 122.10034 -399.451576) (xy 122.10034 -399.293588)
			(xy 122.099927 -399.284401) (xy 122.093414 -399.267217) (xy 122.08764 -399.26006) (xy 122.065888 -399.234379)
			(xy 122.027938 -399.178796) (xy 121.996903 -399.119077) (xy 121.973228 -399.056076) (xy 121.957253 -398.990698)
			(xy 121.949206 -398.923878) (xy 121.949202 -398.856576) (xy 121.957243 -398.789756) (xy 121.973212 -398.724376)
			(xy 121.996881 -398.661373) (xy 122.02791 -398.60165) (xy 122.065855 -398.546064) (xy 122.08764 -398.520412)
			(xy 122.093461 -398.513285) (xy 122.09996 -398.49608) (xy 122.10034 -398.486884) (xy 122.10034 -397.993362)
			(xy 122.099939 -397.984174) (xy 122.093418 -397.96699) (xy 122.08764 -397.959834) (xy 122.065862 -397.934174)
			(xy 122.027913 -397.878588) (xy 121.996879 -397.818866) (xy 121.973206 -397.755863) (xy 121.957232 -397.690481)
			(xy 121.949187 -397.62366) (xy 121.949186 -397.556355) (xy 120.820972 -397.556355) (xy 120.823365 -397.560948)
			(xy 120.847132 -397.624041) (xy 120.86317 -397.689526) (xy 120.871249 -397.756461) (xy 120.871253 -397.823882)
			(xy 120.86318 -397.890818) (xy 120.847149 -397.956305) (xy 120.823389 -398.0194) (xy 120.792242 -398.079195)
			(xy 120.754158 -398.134829) (xy 120.732296 -398.160494) (xy 120.726519 -398.167653) (xy 120.719993 -398.184833)
			(xy 120.719596 -398.194022) (xy 120.719596 -398.351502) (xy 120.719076 -398.361624) (xy 120.711354 -398.380339)
			(xy 120.697079 -398.394694) (xy 120.678408 -398.402519) (xy 120.668288 -398.403064) (xy 119.952008 -398.403064)
			(xy 119.941882 -398.402677) (xy 119.923171 -398.394924) (xy 119.908855 -398.380599) (xy 119.901116 -398.361883)
			(xy 119.9007 -398.351756) (xy 119.9007 -398.194022) (xy 119.900279 -398.184836) (xy 119.893773 -398.167651)
			(xy 119.888 -398.160494) (xy 119.866099 -398.13486) (xy 119.828011 -398.079221) (xy 119.796862 -398.01942)
			(xy 119.7731 -397.956319) (xy 119.757067 -397.890826) (xy 119.748994 -397.823885) (xy 118.620846 -397.823885)
			(xy 118.592108 -397.879044) (xy 118.554014 -397.934678) (xy 118.532148 -397.960342) (xy 118.526345 -397.967482)
			(xy 118.519835 -397.984677) (xy 118.519448 -397.99387) (xy 118.519448 -398.486376) (xy 118.519881 -398.495561)
			(xy 118.52638 -398.512745) (xy 118.532148 -398.519904) (xy 118.554049 -398.545539) (xy 118.59214 -398.601177)
			(xy 118.623292 -398.660977) (xy 118.647057 -398.724078) (xy 118.663091 -398.789571) (xy 118.671165 -398.856513)
			(xy 118.671162 -398.923941) (xy 118.663082 -398.990882) (xy 118.647041 -399.056374) (xy 118.62327 -399.119473)
			(xy 118.592112 -399.17927) (xy 118.554016 -399.234904) (xy 118.532148 -399.260568) (xy 118.526334 -399.2677)
			(xy 118.519831 -399.284901) (xy 118.519448 -399.294096) (xy 118.519448 -399.451576) (xy 118.518897 -399.461677)
			(xy 118.511176 -399.480346) (xy 118.4969 -399.49464) (xy 118.478241 -399.502384) (xy 118.46814 -399.502884)
			(xy 117.75186 -399.502884) (xy 117.741747 -399.502447) (xy 117.723065 -399.494693) (xy 117.708771 -399.480382)
			(xy 117.70104 -399.46169) (xy 117.700552 -399.451576) (xy 117.700552 -399.294096) (xy 117.700132 -399.28491)
			(xy 117.693624 -399.267726) (xy 117.687852 -399.260568) (xy 117.666022 -399.234874) (xy 117.627928 -399.179245)
			(xy 117.596773 -399.119453) (xy 117.573005 -399.05636) (xy 117.556965 -398.990874) (xy 117.548886 -398.923938)
			(xy 117.548882 -398.856516) (xy 117.556955 -398.789579) (xy 117.572989 -398.724092) (xy 117.596751 -398.660996)
			(xy 117.627901 -398.601201) (xy 117.665988 -398.545568) (xy 117.687852 -398.519904) (xy 117.693636 -398.51275)
			(xy 117.700157 -398.495566) (xy 117.700552 -398.486376) (xy 117.700552 -397.99387) (xy 117.700145 -397.984683)
			(xy 117.693628 -397.967499) (xy 117.687852 -397.960342) (xy 117.665996 -397.93467) (xy 117.627904 -397.879037)
			(xy 117.59675 -397.819243) (xy 117.572983 -397.756147) (xy 117.556945 -397.690658) (xy 117.548867 -397.623719)
			(xy 117.548866 -397.556296) (xy 116.42064 -397.556296) (xy 116.423251 -397.56132) (xy 116.446929 -397.624321)
			(xy 116.462906 -397.6897) (xy 116.470954 -397.75652) (xy 116.470957 -397.823823) (xy 116.462916 -397.890644)
			(xy 116.446945 -397.956025) (xy 116.423275 -398.019028) (xy 116.392243 -398.07875) (xy 116.354295 -398.134335)
			(xy 116.332508 -398.159986) (xy 116.326693 -398.167118) (xy 116.320189 -398.184319) (xy 116.319808 -398.193514)
			(xy 116.319808 -398.351502) (xy 116.319269 -398.361654) (xy 116.311503 -398.380415) (xy 116.297152 -398.394778)
			(xy 116.278398 -398.402561) (xy 116.268246 -398.403064) (xy 115.551966 -398.403064) (xy 115.541806 -398.402595)
			(xy 115.523037 -398.394809) (xy 115.508673 -398.380436) (xy 115.500899 -398.361662) (xy 115.500404 -398.351502)
			(xy 115.500404 -398.193514) (xy 115.499986 -398.184328) (xy 115.493478 -398.167143) (xy 115.487704 -398.159986)
			(xy 115.46588 -398.134364) (xy 115.427935 -398.078772) (xy 115.396905 -398.019044) (xy 115.373236 -397.956036)
			(xy 115.357267 -397.89065) (xy 115.349226 -397.823825) (xy 92.220595 -397.823825) (xy 92.192138 -397.878594)
			(xy 92.154191 -397.934181) (xy 92.132404 -397.959834) (xy 92.126611 -397.966982) (xy 92.120094 -397.98417)
			(xy 92.119704 -397.993362) (xy 92.119704 -398.486884) (xy 92.120121 -398.49607) (xy 92.12663 -398.513255)
			(xy 92.132404 -398.520412) (xy 92.154226 -398.546036) (xy 92.192171 -398.601627) (xy 92.2232 -398.661355)
			(xy 92.246869 -398.724363) (xy 92.262838 -398.789748) (xy 92.270879 -398.856574) (xy 92.270875 -398.923881)
			(xy 92.262828 -398.990705) (xy 92.246853 -399.056089) (xy 92.223178 -399.119094) (xy 92.192143 -399.178819)
			(xy 92.154193 -399.234407) (xy 92.132404 -399.26006) (xy 92.1266 -399.2672) (xy 92.12009 -399.284394)
			(xy 92.119704 -399.293588) (xy 92.119704 -399.451576) (xy 92.119259 -399.461728) (xy 92.111472 -399.480479)
			(xy 92.097082 -399.494803) (xy 92.078296 -399.502505) (xy 92.068142 -399.502884) (xy 91.351862 -399.502884)
			(xy 91.341736 -399.502405) (xy 91.323018 -399.494669) (xy 91.308664 -399.480381) (xy 91.300842 -399.4617)
			(xy 91.3003 -399.451576) (xy 91.3003 -399.293588) (xy 91.299895 -399.2844) (xy 91.293378 -399.267216)
			(xy 91.2876 -399.26006) (xy 91.265849 -399.234378) (xy 91.227901 -399.178795) (xy 91.196869 -399.119075)
			(xy 91.173196 -399.056075) (xy 91.157221 -398.990697) (xy 91.149175 -398.923878) (xy 91.149172 -398.856576)
			(xy 91.157212 -398.789757) (xy 91.17318 -398.724377) (xy 91.196847 -398.661374) (xy 91.227874 -398.601651)
			(xy 91.265816 -398.546065) (xy 91.2876 -398.520412) (xy 91.293416 -398.513281) (xy 91.299919 -398.49608)
			(xy 91.3003 -398.486884) (xy 91.3003 -397.993362) (xy 91.299908 -397.984173) (xy 91.293382 -397.966989)
			(xy 91.2876 -397.959834) (xy 91.265823 -397.934173) (xy 91.227877 -397.878587) (xy 91.196845 -397.818864)
			(xy 91.173174 -397.755861) (xy 91.157201 -397.69048) (xy 91.149157 -397.623659) (xy 91.149156 -397.556356)
			(xy 90.020411 -397.556356) (xy 90.022992 -397.561322) (xy 90.046667 -397.624323) (xy 90.062643 -397.689701)
			(xy 90.07069 -397.75652) (xy 90.070693 -397.823822) (xy 90.062653 -397.890643) (xy 90.046684 -397.956023)
			(xy 90.023015 -398.019026) (xy 89.991986 -398.078748) (xy 89.954041 -398.134334) (xy 89.932256 -398.159986)
			(xy 89.926435 -398.167114) (xy 89.919936 -398.184318) (xy 89.919556 -398.193514) (xy 89.919556 -398.351502)
			(xy 89.919138 -398.361674) (xy 89.911351 -398.38047) (xy 89.896964 -398.394855) (xy 89.878167 -398.402639)
			(xy 89.867994 -398.403064) (xy 89.151714 -398.403064) (xy 89.141544 -398.402625) (xy 89.122749 -398.394845)
			(xy 89.108364 -398.380464) (xy 89.100578 -398.361672) (xy 89.100152 -398.351502) (xy 89.100152 -398.193514)
			(xy 89.099724 -398.184329) (xy 89.093221 -398.167145) (xy 89.087452 -398.159986) (xy 89.065626 -398.134365)
			(xy 89.027678 -398.078774) (xy 88.996645 -398.019047) (xy 88.972974 -397.956038) (xy 88.957004 -397.890652)
			(xy 88.948962 -397.823826) (xy 87.820827 -397.823826) (xy 87.792062 -397.879042) (xy 87.753972 -397.934677)
			(xy 87.732108 -397.960342) (xy 87.726312 -397.967488) (xy 87.719797 -397.984678) (xy 87.719408 -397.99387)
			(xy 87.719408 -398.486376) (xy 87.719828 -398.495562) (xy 87.726335 -398.512747) (xy 87.732108 -398.519904)
			(xy 87.754007 -398.54554) (xy 87.792094 -398.601179) (xy 87.823243 -398.660979) (xy 87.847005 -398.72408)
			(xy 87.863037 -398.789573) (xy 87.87111 -398.856514) (xy 87.871107 -398.92394) (xy 87.863028 -398.990881)
			(xy 87.846989 -399.056372) (xy 87.823221 -399.11947) (xy 87.792066 -399.179267) (xy 87.753974 -399.234903)
			(xy 87.732108 -399.260568) (xy 87.726301 -399.267706) (xy 87.719792 -399.284902) (xy 87.719408 -399.294096)
			(xy 87.719408 -399.451576) (xy 87.718965 -399.461696) (xy 87.711226 -399.480398) (xy 87.696918 -399.494712)
			(xy 87.67822 -399.50246) (xy 87.6681 -399.502884) (xy 86.95182 -399.502884) (xy 86.941697 -399.502467)
			(xy 86.922991 -399.494723) (xy 86.908675 -399.480406) (xy 86.900932 -399.461699) (xy 86.900512 -399.451576)
			(xy 86.900512 -399.294096) (xy 86.900101 -399.284909) (xy 86.893587 -399.267725) (xy 86.887812 -399.260568)
			(xy 86.865983 -399.234874) (xy 86.827892 -399.179244) (xy 86.796739 -399.119452) (xy 86.772973 -399.056358)
			(xy 86.756934 -398.990873) (xy 86.748855 -398.923938) (xy 86.748852 -398.856516) (xy 86.756925 -398.78958)
			(xy 86.772957 -398.724093) (xy 86.796717 -398.660998) (xy 86.827865 -398.601203) (xy 86.86595 -398.545569)
			(xy 86.887812 -398.519904) (xy 86.893591 -398.512746) (xy 86.900116 -398.495565) (xy 86.900512 -398.486376)
			(xy 86.900512 -397.99387) (xy 86.900114 -397.984682) (xy 86.893592 -397.967497) (xy 86.887812 -397.960342)
			(xy 86.865957 -397.934669) (xy 86.827868 -397.879036) (xy 86.796716 -397.819241) (xy 86.772951 -397.756145)
			(xy 86.756914 -397.690657) (xy 86.748837 -397.623719) (xy 86.748836 -397.556296) (xy 85.620612 -397.556296)
			(xy 85.623035 -397.560946) (xy 85.646803 -397.624039) (xy 85.662842 -397.689525) (xy 85.670922 -397.756461)
			(xy 85.670925 -397.823882) (xy 85.662853 -397.890819) (xy 85.64682 -397.956306) (xy 85.623058 -398.019402)
			(xy 85.59191 -398.079196) (xy 85.553823 -398.134829) (xy 85.53196 -398.160494) (xy 85.526178 -398.16765)
			(xy 85.519656 -398.184832) (xy 85.51926 -398.194022) (xy 85.51926 -398.351502) (xy 85.518775 -398.361629)
			(xy 85.511047 -398.38035) (xy 85.49676 -398.394706) (xy 85.478076 -398.402525) (xy 85.467952 -398.403064)
			(xy 84.751672 -398.403064) (xy 84.741512 -398.402701) (xy 84.722752 -398.394889) (xy 84.708428 -398.380474)
			(xy 84.700736 -398.361665) (xy 84.700364 -398.351502) (xy 84.700364 -398.194022) (xy 84.699929 -398.184838)
			(xy 84.693431 -398.167654) (xy 84.687664 -398.160494) (xy 84.665764 -398.134859) (xy 84.627679 -398.079219)
			(xy 84.596532 -398.019419) (xy 84.572771 -397.956318) (xy 84.55674 -397.890825) (xy 84.548667 -397.823884)
			(xy 83.420495 -397.823884) (xy 83.392062 -397.878597) (xy 83.35411 -397.934182) (xy 83.33232 -397.959834)
			(xy 83.326529 -397.966983) (xy 83.32001 -397.984171) (xy 83.31962 -397.993362) (xy 83.31962 -398.486884)
			(xy 83.320033 -398.496071) (xy 83.326544 -398.513256) (xy 83.33232 -398.520412) (xy 83.354144 -398.546035)
			(xy 83.392095 -398.601624) (xy 83.423129 -398.661352) (xy 83.446801 -398.72436) (xy 83.462773 -398.789746)
			(xy 83.470815 -398.856573) (xy 83.470812 -398.923881) (xy 83.462763 -398.990707) (xy 83.446785 -399.056092)
			(xy 83.423107 -399.119098) (xy 83.392067 -399.178822) (xy 83.354111 -399.234408) (xy 83.33232 -399.26006)
			(xy 83.326518 -399.267201) (xy 83.320006 -399.284395) (xy 83.31962 -399.293588) (xy 83.31962 -399.451576)
			(xy 83.319159 -399.461726) (xy 83.311375 -399.480474) (xy 83.296991 -399.494798) (xy 83.27821 -399.502502)
			(xy 83.268058 -399.502884) (xy 82.551778 -399.502884) (xy 82.541653 -399.502392) (xy 82.522936 -399.494662)
			(xy 82.508581 -399.480378) (xy 82.500758 -399.461699) (xy 82.500216 -399.451576) (xy 82.500216 -399.293588)
			(xy 82.499808 -399.284401) (xy 82.493293 -399.267216) (xy 82.487516 -399.26006) (xy 82.465765 -399.234378)
			(xy 82.427816 -399.178795) (xy 82.396783 -399.119076) (xy 82.373109 -399.056075) (xy 82.357134 -398.990697)
			(xy 82.349088 -398.923878) (xy 82.349084 -398.856576) (xy 82.357125 -398.789756) (xy 82.373093 -398.724377)
			(xy 82.396761 -398.661374) (xy 82.427788 -398.601651) (xy 82.465731 -398.546065) (xy 82.487516 -398.520412)
			(xy 82.493334 -398.513282) (xy 82.499835 -398.49608) (xy 82.500216 -398.486884) (xy 82.500216 -397.993362)
			(xy 82.499821 -397.984173) (xy 82.493296 -397.966989) (xy 82.487516 -397.959834) (xy 82.465739 -397.934174)
			(xy 82.427791 -397.878588) (xy 82.396759 -397.818865) (xy 82.373086 -397.755862) (xy 82.357113 -397.690481)
			(xy 82.349069 -397.623659) (xy 82.349068 -397.556356) (xy 81.220853 -397.556356) (xy 81.223245 -397.560947)
			(xy 81.247013 -397.62404) (xy 81.263052 -397.689525) (xy 81.271131 -397.756461) (xy 81.271135 -397.823882)
			(xy 81.263062 -397.890818) (xy 81.24703 -397.956306) (xy 81.223269 -398.019401) (xy 81.192121 -398.079196)
			(xy 81.154035 -398.134829) (xy 81.132172 -398.160494) (xy 81.126392 -398.167651) (xy 81.119868 -398.184832)
			(xy 81.119472 -398.194022) (xy 81.119472 -398.351502) (xy 81.118975 -398.361627) (xy 81.111249 -398.380346)
			(xy 81.096966 -398.394702) (xy 81.078287 -398.402523) (xy 81.068164 -398.403064) (xy 80.351884 -398.403064)
			(xy 80.341724 -398.402691) (xy 80.322965 -398.394883) (xy 80.30864 -398.380471) (xy 80.300948 -398.361664)
			(xy 80.300576 -398.351502) (xy 80.300576 -398.194022) (xy 80.300161 -398.184835) (xy 80.293651 -398.16765)
			(xy 80.287876 -398.160494) (xy 80.265976 -398.134859) (xy 80.22789 -398.07922) (xy 80.196742 -398.019419)
			(xy 80.172981 -397.956318) (xy 80.156949 -397.890826) (xy 80.148876 -397.823885) (xy 79.02071 -397.823885)
			(xy 78.991976 -397.879041) (xy 78.953888 -397.934676) (xy 78.932024 -397.960342) (xy 78.92623 -397.967489)
			(xy 78.919713 -397.984678) (xy 78.919324 -397.99387) (xy 78.919324 -398.486376) (xy 78.91974 -398.495563)
			(xy 78.926249 -398.512747) (xy 78.932024 -398.519904) (xy 78.953922 -398.54554) (xy 78.992009 -398.60118)
			(xy 79.023156 -398.66098) (xy 79.046917 -398.724081) (xy 79.06295 -398.789573) (xy 79.071022 -398.856514)
			(xy 79.071019 -398.92394) (xy 79.06294 -398.99088) (xy 79.046901 -399.056371) (xy 79.023134 -399.119469)
			(xy 78.991981 -399.179267) (xy 78.953889 -399.234902) (xy 78.932024 -399.260568) (xy 78.926219 -399.267707)
			(xy 78.919709 -399.284902) (xy 78.919324 -399.294096) (xy 78.919324 -399.451576) (xy 78.918865 -399.461694)
			(xy 78.911129 -399.480393) (xy 78.896826 -399.494707) (xy 78.878134 -399.502457) (xy 78.868016 -399.502884)
			(xy 78.151736 -399.502884) (xy 78.141614 -399.502454) (xy 78.122908 -399.494715) (xy 78.108592 -399.480402)
			(xy 78.100848 -399.461698) (xy 78.100428 -399.451576) (xy 78.100428 -399.294096) (xy 78.100014 -399.284909)
			(xy 78.093502 -399.267725) (xy 78.087728 -399.260568) (xy 78.065898 -399.234874) (xy 78.027807 -399.179244)
			(xy 77.996653 -399.119452) (xy 77.972886 -399.056359) (xy 77.956847 -398.990873) (xy 77.948768 -398.923938)
			(xy 77.948764 -398.856516) (xy 77.956837 -398.78958) (xy 77.972869 -398.724093) (xy 77.996631 -398.660997)
			(xy 78.027779 -398.601202) (xy 78.065865 -398.545569) (xy 78.087728 -398.519904) (xy 78.093509 -398.512748)
			(xy 78.100032 -398.495566) (xy 78.100428 -398.486376) (xy 78.100428 -397.99387) (xy 78.100026 -397.984682)
			(xy 78.093506 -397.967498) (xy 78.087728 -397.960342) (xy 78.065873 -397.934669) (xy 78.027782 -397.879036)
			(xy 77.996629 -397.819241) (xy 77.972863 -397.756146) (xy 77.956826 -397.690657) (xy 77.948749 -397.623719)
			(xy 77.948748 -397.556296) (xy 76.820503 -397.556296) (xy 76.823115 -397.561323) (xy 76.846789 -397.624324)
			(xy 76.862764 -397.689702) (xy 76.870811 -397.756521) (xy 76.870814 -397.823822) (xy 76.862774 -397.890642)
			(xy 76.846806 -397.956022) (xy 76.823139 -398.019024) (xy 76.792111 -398.078747) (xy 76.754168 -398.134333)
			(xy 76.732384 -398.159986) (xy 76.726567 -398.167116) (xy 76.720065 -398.184318) (xy 76.719684 -398.193514)
			(xy 76.719684 -398.351502) (xy 76.719169 -398.361657) (xy 76.711398 -398.380422) (xy 76.697039 -398.394787)
			(xy 76.678277 -398.402565) (xy 76.668122 -398.403064) (xy 75.951842 -398.403064) (xy 75.941673 -398.402602)
			(xy 75.92288 -398.394831) (xy 75.908494 -398.380457) (xy 75.900707 -398.36167) (xy 75.90028 -398.351502)
			(xy 75.90028 -398.193514) (xy 75.899868 -398.184327) (xy 75.893356 -398.167142) (xy 75.88758 -398.159986)
			(xy 75.865754 -398.134365) (xy 75.827803 -398.078775) (xy 75.79677 -398.019048) (xy 75.773097 -397.956039)
			(xy 75.757126 -397.890653) (xy 75.749084 -397.823826) (xy 74.620438 -397.823826) (xy 74.591977 -397.878596)
			(xy 74.554025 -397.934182) (xy 74.532236 -397.959834) (xy 74.526435 -397.966975) (xy 74.519925 -397.984169)
			(xy 74.519536 -397.993362) (xy 74.519536 -398.486884) (xy 74.519968 -398.496069) (xy 74.526468 -398.513252)
			(xy 74.532236 -398.520412) (xy 74.55406 -398.546035) (xy 74.592009 -398.601625) (xy 74.623043 -398.661352)
			(xy 74.646714 -398.724361) (xy 74.662686 -398.789747) (xy 74.670727 -398.856573) (xy 74.670724 -398.923881)
			(xy 74.662676 -398.990707) (xy 74.646698 -399.056091) (xy 74.623021 -399.119097) (xy 74.591982 -399.178822)
			(xy 74.554027 -399.234408) (xy 74.532236 -399.26006) (xy 74.526424 -399.267194) (xy 74.51992 -399.284393)
			(xy 74.519536 -399.293588) (xy 74.519536 -399.451576) (xy 74.51906 -399.461724) (xy 74.511279 -399.480469)
			(xy 74.496899 -399.494792) (xy 74.478124 -399.502499) (xy 74.467974 -399.502884) (xy 73.751694 -399.502884)
			(xy 73.74157 -399.502379) (xy 73.722853 -399.494654) (xy 73.708498 -399.480373) (xy 73.700675 -399.461697)
			(xy 73.700132 -399.451576) (xy 73.700132 -399.293588) (xy 73.699721 -399.284401) (xy 73.693207 -399.267217)
			(xy 73.687432 -399.26006) (xy 73.66568 -399.234378) (xy 73.627731 -399.178796) (xy 73.596696 -399.119077)
			(xy 73.573022 -399.056076) (xy 73.557047 -398.990697) (xy 73.549 -398.923878) (xy 73.548996 -398.856576)
			(xy 73.557037 -398.789756) (xy 73.573006 -398.724376) (xy 73.596674 -398.661373) (xy 73.627703 -398.60165)
			(xy 73.665647 -398.546064) (xy 73.687432 -398.520412) (xy 73.693253 -398.513284) (xy 73.699752 -398.49608)
			(xy 73.700132 -398.486884) (xy 73.700132 -397.993362) (xy 73.699733 -397.984174) (xy 73.693211 -397.96699)
			(xy 73.687432 -397.959834) (xy 73.665654 -397.934174) (xy 73.627705 -397.878588) (xy 73.596672 -397.818866)
			(xy 73.572999 -397.755862) (xy 73.557026 -397.690481) (xy 73.548981 -397.62366) (xy 73.54898 -397.556355)
			(xy 72.420766 -397.556355) (xy 72.423159 -397.560948) (xy 72.446926 -397.62404) (xy 72.462964 -397.689526)
			(xy 72.471043 -397.756461) (xy 72.471047 -397.823882) (xy 72.462974 -397.890818) (xy 72.446942 -397.956305)
			(xy 72.423182 -398.0194) (xy 72.392035 -398.079195) (xy 72.35395 -398.134829) (xy 72.332088 -398.160494)
			(xy 72.32631 -398.167652) (xy 72.319785 -398.184833) (xy 72.319388 -398.194022) (xy 72.319388 -398.351502)
			(xy 72.318876 -398.361625) (xy 72.311153 -398.380341) (xy 72.296875 -398.394696) (xy 72.278201 -398.40252)
			(xy 72.26808 -398.403064) (xy 71.5518 -398.403064) (xy 71.541641 -398.402678) (xy 71.522882 -398.394875)
			(xy 71.508557 -398.380467) (xy 71.500864 -398.361663) (xy 71.500492 -398.351502) (xy 71.500492 -398.194022)
			(xy 71.500073 -398.184836) (xy 71.493566 -398.167651) (xy 71.487792 -398.160494) (xy 71.465891 -398.134859)
			(xy 71.427804 -398.07922) (xy 71.396655 -398.01942) (xy 71.372894 -397.956319) (xy 71.356861 -397.890826)
			(xy 71.348788 -397.823885) (xy 66.525648 -397.823885) (xy 66.525648 -401.723796) (xy 71.3488 -401.723796)
			(xy 71.348802 -401.656371) (xy 71.35688 -401.589431) (xy 71.372917 -401.523941) (xy 71.396683 -401.460843)
			(xy 71.427836 -401.401046) (xy 71.465927 -401.345411) (xy 71.487792 -401.319746) (xy 71.493593 -401.312604)
			(xy 71.500105 -401.295411) (xy 71.500492 -401.286218) (xy 71.500492 -400.793966) (xy 71.5001 -400.784777)
			(xy 71.493574 -400.767592) (xy 71.487792 -400.760438) (xy 71.465934 -400.734768) (xy 71.427846 -400.679134)
			(xy 71.396695 -400.619338) (xy 71.372931 -400.556242) (xy 71.356896 -400.490754) (xy 71.348819 -400.423816)
			(xy 71.348819 -400.356393) (xy 71.356894 -400.289455) (xy 71.372928 -400.223967) (xy 71.396692 -400.16087)
			(xy 71.427841 -400.101074) (xy 71.465929 -400.045439) (xy 71.487792 -400.019774) (xy 71.493581 -400.012623)
			(xy 71.500101 -399.995437) (xy 71.500492 -399.986246) (xy 71.500492 -399.828766) (xy 71.500997 -399.818643)
			(xy 71.508727 -399.79993) (xy 71.523007 -399.785577) (xy 71.54168 -399.77775) (xy 71.5518 -399.777204)
			(xy 72.26808 -399.777204) (xy 72.278233 -399.777638) (xy 72.296986 -399.785428) (xy 72.31131 -399.799821)
			(xy 72.31901 -399.818611) (xy 72.319388 -399.828766) (xy 72.319388 -399.986246) (xy 72.319827 -399.99543)
			(xy 72.326321 -400.012615) (xy 72.332088 -400.019774) (xy 72.353958 -400.045434) (xy 72.392048 -400.101069)
			(xy 72.423199 -400.160866) (xy 72.446963 -400.223963) (xy 72.462999 -400.289453) (xy 72.471074 -400.356392)
			(xy 72.471074 -400.423817) (xy 72.462997 -400.490756) (xy 72.44696 -400.556245) (xy 72.423195 -400.619342)
			(xy 72.392043 -400.679139) (xy 72.353953 -400.734773) (xy 72.332088 -400.760438) (xy 72.326291 -400.767583)
			(xy 72.319777 -400.784774) (xy 72.319388 -400.793966) (xy 72.319388 -401.286218) (xy 72.319792 -401.295406)
			(xy 72.32631 -401.31259) (xy 72.332088 -401.319746) (xy 72.353931 -401.345429) (xy 72.392021 -401.401061)
			(xy 72.423173 -401.460854) (xy 72.446939 -401.523949) (xy 72.462977 -401.589436) (xy 72.471054 -401.656372)
			(xy 72.471056 -401.723795) (xy 72.462982 -401.790732) (xy 72.446949 -401.85622) (xy 72.423187 -401.919316)
			(xy 72.392038 -401.979111) (xy 72.353951 -402.034745) (xy 72.332088 -402.06041) (xy 72.326303 -402.067564)
			(xy 72.319782 -402.084748) (xy 72.319388 -402.093938) (xy 72.319388 -402.251418) (xy 72.318889 -402.261542)
			(xy 72.311161 -402.280259) (xy 72.296879 -402.294614) (xy 72.278202 -402.302437) (xy 72.26808 -402.30298)
			(xy 71.5518 -402.30298) (xy 71.541643 -402.302578) (xy 71.522887 -402.294779) (xy 71.508563 -402.280376)
			(xy 71.500867 -402.261577) (xy 71.500492 -402.251418) (xy 71.500492 -402.093938) (xy 71.500065 -402.084753)
			(xy 71.493563 -402.067568) (xy 71.487792 -402.06041) (xy 71.465907 -402.034762) (xy 71.427819 -401.979125)
			(xy 71.39667 -401.919326) (xy 71.372907 -401.856227) (xy 71.356874 -401.790736) (xy 71.3488 -401.723796)
			(xy 66.525648 -401.723796) (xy 66.525648 -402.823818) (xy 73.54894 -402.823818) (xy 73.548944 -402.75651)
			(xy 73.556993 -402.689684) (xy 73.572971 -402.624299) (xy 73.596649 -402.561293) (xy 73.627687 -402.501568)
			(xy 73.665642 -402.44598) (xy 73.687432 -402.420328) (xy 73.693246 -402.413195) (xy 73.699749 -402.395995)
			(xy 73.700132 -402.3868) (xy 73.700132 -401.893532) (xy 73.699699 -401.884347) (xy 73.6932 -401.867163)
			(xy 73.687432 -401.860004) (xy 73.665625 -401.834368) (xy 73.627677 -401.778779) (xy 73.596645 -401.719053)
			(xy 73.572974 -401.656047) (xy 73.557002 -401.590662) (xy 73.54896 -401.523838) (xy 73.548962 -401.456532)
			(xy 73.557008 -401.389708) (xy 73.572982 -401.324325) (xy 73.596657 -401.261319) (xy 73.627692 -401.201595)
			(xy 73.665643 -401.146008) (xy 73.687432 -401.120356) (xy 73.693234 -401.113215) (xy 73.699745 -401.096021)
			(xy 73.700132 -401.086828) (xy 73.700132 -400.92884) (xy 73.700555 -400.918685) (xy 73.708343 -400.899927)
			(xy 73.722741 -400.885601) (xy 73.741537 -400.877906) (xy 73.751694 -400.877532) (xy 74.467974 -400.877532)
			(xy 74.478098 -400.878047) (xy 74.496817 -400.885765) (xy 74.511174 -400.900043) (xy 74.518996 -400.918719)
			(xy 74.519536 -400.92884) (xy 74.519536 -401.086828) (xy 74.519947 -401.096015) (xy 74.526462 -401.113198)
			(xy 74.532236 -401.120356) (xy 74.554005 -401.146024) (xy 74.591956 -401.201608) (xy 74.622991 -401.261329)
			(xy 74.646666 -401.324331) (xy 74.662641 -401.389712) (xy 74.670687 -401.456533) (xy 74.670689 -401.523837)
			(xy 74.662647 -401.590659) (xy 74.646675 -401.65604) (xy 74.623004 -401.719044) (xy 74.620565 -401.723737)
			(xy 75.749095 -401.723737) (xy 75.749097 -401.65643) (xy 75.757144 -401.589605) (xy 75.773121 -401.524221)
			(xy 75.796798 -401.461215) (xy 75.827836 -401.401492) (xy 75.86579 -401.345906) (xy 75.88758 -401.320254)
			(xy 75.893376 -401.313108) (xy 75.899892 -401.295918) (xy 75.90028 -401.286726) (xy 75.90028 -400.793458)
			(xy 75.899895 -400.784268) (xy 75.893364 -400.767084) (xy 75.88758 -400.75993) (xy 75.865797 -400.734274)
			(xy 75.827845 -400.678689) (xy 75.79681 -400.618966) (xy 75.773135 -400.555962) (xy 75.75716 -400.49058)
			(xy 75.749115 -400.423757) (xy 75.749114 -400.356452) (xy 75.757158 -400.289629) (xy 75.773132 -400.224247)
			(xy 75.796806 -400.161242) (xy 75.827841 -400.101519) (xy 75.865791 -400.045934) (xy 75.88758 -400.020282)
			(xy 75.893364 -400.013128) (xy 75.899887 -399.995944) (xy 75.90028 -399.986754) (xy 75.90028 -399.828766)
			(xy 75.900637 -399.818587) (xy 75.908441 -399.799783) (xy 75.922847 -399.785398) (xy 75.941662 -399.777622)
			(xy 75.951842 -399.777204) (xy 76.668122 -399.777204) (xy 76.678277 -399.777714) (xy 76.69704 -399.78549)
			(xy 76.711404 -399.79985) (xy 76.719183 -399.818611) (xy 76.719684 -399.828766) (xy 76.719684 -399.986754)
			(xy 76.72012 -399.995938) (xy 76.726616 -400.013123) (xy 76.732384 -400.020282) (xy 76.754177 -400.04593)
			(xy 76.792124 -400.101517) (xy 76.823156 -400.161242) (xy 76.846827 -400.224247) (xy 76.862799 -400.289629)
			(xy 76.870842 -400.356452) (xy 76.870842 -400.423757) (xy 76.862798 -400.49058) (xy 76.846825 -400.555962)
			(xy 76.823152 -400.618967) (xy 76.792119 -400.678691) (xy 76.754171 -400.734278) (xy 76.732384 -400.75993)
			(xy 76.72659 -400.767077) (xy 76.720074 -400.784266) (xy 76.719684 -400.793458) (xy 76.719684 -401.286726)
			(xy 76.720085 -401.295914) (xy 76.726605 -401.313098) (xy 76.732384 -401.320254) (xy 76.754149 -401.345924)
			(xy 76.792097 -401.401509) (xy 76.82313 -401.46123) (xy 76.846803 -401.524232) (xy 76.862777 -401.589612)
			(xy 76.870823 -401.656432) (xy 76.870825 -401.723735) (xy 76.862783 -401.790556) (xy 76.846813 -401.855936)
			(xy 76.823144 -401.91894) (xy 76.792114 -401.978663) (xy 76.75417 -402.03425) (xy 76.732384 -402.059902)
			(xy 76.726602 -402.067058) (xy 76.720079 -402.08424) (xy 76.719684 -402.09343) (xy 76.719684 -402.251418)
			(xy 76.719182 -402.261574) (xy 76.711406 -402.28034) (xy 76.697043 -402.294704) (xy 76.678278 -402.302481)
			(xy 76.668122 -402.30298) (xy 75.951842 -402.30298) (xy 75.941675 -402.302502) (xy 75.922885 -402.294734)
			(xy 75.908499 -402.280365) (xy 75.90071 -402.261584) (xy 75.90028 -402.251418) (xy 75.90028 -402.09343)
			(xy 75.89986 -402.084244) (xy 75.893354 -402.067059) (xy 75.88758 -402.059902) (xy 75.865769 -402.034268)
			(xy 75.827819 -401.97868) (xy 75.796784 -401.918954) (xy 75.773111 -401.855947) (xy 75.757138 -401.790562)
			(xy 75.749095 -401.723737) (xy 74.620565 -401.723737) (xy 74.591971 -401.778767) (xy 74.554023 -401.834352)
			(xy 74.532236 -401.860004) (xy 74.526447 -401.867155) (xy 74.51993 -401.884341) (xy 74.519536 -401.893532)
			(xy 74.519536 -402.3868) (xy 74.519961 -402.395985) (xy 74.526466 -402.413169) (xy 74.532236 -402.420328)
			(xy 74.553977 -402.446019) (xy 74.591929 -402.501599) (xy 74.622966 -402.561317) (xy 74.646642 -402.624317)
			(xy 74.662619 -402.689694) (xy 74.670668 -402.756513) (xy 74.670672 -402.823815) (xy 74.670664 -402.823878)
			(xy 77.948708 -402.823878) (xy 77.948713 -402.75645) (xy 77.956794 -402.689508) (xy 77.972835 -402.624016)
			(xy 77.996606 -402.560917) (xy 78.027764 -402.501119) (xy 78.06586 -402.445485) (xy 78.087728 -402.41982)
			(xy 78.093545 -402.412689) (xy 78.100047 -402.395488) (xy 78.100428 -402.386292) (xy 78.100428 -401.89404)
			(xy 78.099992 -401.884856) (xy 78.093496 -401.867671) (xy 78.087728 -401.860512) (xy 78.065843 -401.834863)
			(xy 78.027753 -401.779227) (xy 77.996602 -401.719429) (xy 77.972838 -401.65633) (xy 77.956803 -401.590838)
			(xy 77.948728 -401.523898) (xy 77.94873 -401.456472) (xy 77.956808 -401.389532) (xy 77.972847 -401.324041)
			(xy 77.996614 -401.260944) (xy 78.027769 -401.201147) (xy 78.065862 -401.145513) (xy 78.087728 -401.119848)
			(xy 78.093533 -401.112709) (xy 78.100042 -401.095514) (xy 78.100428 -401.08632) (xy 78.100428 -400.92884)
			(xy 78.10085 -400.918717) (xy 78.10859 -400.900009) (xy 78.122905 -400.885692) (xy 78.141613 -400.87795)
			(xy 78.151736 -400.877532) (xy 78.868016 -400.877532) (xy 78.878144 -400.877903) (xy 78.896854 -400.885663)
			(xy 78.911169 -400.899993) (xy 78.918908 -400.918712) (xy 78.919324 -400.92884) (xy 78.919324 -401.08632)
			(xy 78.919719 -401.095509) (xy 78.926243 -401.112693) (xy 78.932024 -401.119848) (xy 78.953867 -401.14553)
			(xy 78.991955 -401.201163) (xy 79.023105 -401.260957) (xy 79.04687 -401.324051) (xy 79.062906 -401.389538)
			(xy 79.070983 -401.456474) (xy 79.070985 -401.523896) (xy 79.062911 -401.590832) (xy 79.046879 -401.65632)
			(xy 79.023118 -401.719416) (xy 79.020837 -401.723796) (xy 80.148888 -401.723796) (xy 80.14889 -401.656371)
			(xy 80.156967 -401.589432) (xy 80.173004 -401.523942) (xy 80.19677 -401.460844) (xy 80.227922 -401.401047)
			(xy 80.266012 -401.345412) (xy 80.287876 -401.319746) (xy 80.293675 -401.312603) (xy 80.300189 -401.295411)
			(xy 80.300576 -401.286218) (xy 80.300576 -400.793966) (xy 80.300187 -400.784776) (xy 80.293659 -400.767592)
			(xy 80.287876 -400.760438) (xy 80.266019 -400.734767) (xy 80.227931 -400.679133) (xy 80.196782 -400.619337)
			(xy 80.173018 -400.556241) (xy 80.156983 -400.490753) (xy 80.148907 -400.423816) (xy 80.148907 -400.356393)
			(xy 80.156982 -400.289456) (xy 80.173016 -400.223967) (xy 80.196778 -400.160871) (xy 80.227927 -400.101075)
			(xy 80.266013 -400.04544) (xy 80.287876 -400.019774) (xy 80.293663 -400.012622) (xy 80.300184 -399.995437)
			(xy 80.300576 -399.986246) (xy 80.300576 -399.828766) (xy 80.301 -399.818633) (xy 80.308745 -399.799904)
			(xy 80.323051 -399.785548) (xy 80.341753 -399.777736) (xy 80.351884 -399.777204) (xy 81.068164 -399.777204)
			(xy 81.078316 -399.777651) (xy 81.097069 -399.785436) (xy 81.111393 -399.799825) (xy 81.119094 -399.818612)
			(xy 81.119472 -399.828766) (xy 81.119472 -399.986246) (xy 81.119914 -399.99543) (xy 81.126406 -400.012614)
			(xy 81.132172 -400.019774) (xy 81.154043 -400.045434) (xy 81.192133 -400.101069) (xy 81.223285 -400.160865)
			(xy 81.24705 -400.223963) (xy 81.263086 -400.289453) (xy 81.271162 -400.356392) (xy 81.271161 -400.423817)
			(xy 81.263085 -400.490756) (xy 81.247048 -400.556246) (xy 81.223282 -400.619343) (xy 81.192129 -400.679139)
			(xy 81.154037 -400.734773) (xy 81.132172 -400.760438) (xy 81.126373 -400.767581) (xy 81.11986 -400.784773)
			(xy 81.119472 -400.793966) (xy 81.119472 -401.286218) (xy 81.11988 -401.295405) (xy 81.126396 -401.312589)
			(xy 81.132172 -401.319746) (xy 81.154015 -401.345429) (xy 81.192107 -401.40106) (xy 81.22326 -401.460854)
			(xy 81.247026 -401.523948) (xy 81.263064 -401.589435) (xy 81.271142 -401.656372) (xy 81.271144 -401.723795)
			(xy 81.26307 -401.790732) (xy 81.247036 -401.85622) (xy 81.223273 -401.919316) (xy 81.192124 -401.979112)
			(xy 81.154036 -402.034745) (xy 81.132172 -402.06041) (xy 81.126385 -402.067562) (xy 81.119865 -402.084747)
			(xy 81.119472 -402.093938) (xy 81.119472 -402.251418) (xy 81.118989 -402.261544) (xy 81.111257 -402.280264)
			(xy 81.09697 -402.294619) (xy 81.078288 -402.30244) (xy 81.068164 -402.30298) (xy 80.351884 -402.30298)
			(xy 80.341726 -402.302591) (xy 80.32297 -402.294787) (xy 80.308646 -402.28038) (xy 80.30095 -402.261578)
			(xy 80.300576 -402.251418) (xy 80.300576 -402.093938) (xy 80.300153 -402.084752) (xy 80.293649 -402.067567)
			(xy 80.287876 -402.06041) (xy 80.265991 -402.034762) (xy 80.227905 -401.979125) (xy 80.196756 -401.919326)
			(xy 80.172994 -401.856227) (xy 80.156961 -401.790736) (xy 80.148888 -401.723796) (xy 79.020837 -401.723796)
			(xy 78.991971 -401.779212) (xy 78.953886 -401.834846) (xy 78.932024 -401.860512) (xy 78.926243 -401.867668)
			(xy 78.919718 -401.88485) (xy 78.919324 -401.89404) (xy 78.919324 -402.386292) (xy 78.919733 -402.395479)
			(xy 78.926247 -402.412664) (xy 78.932024 -402.41982) (xy 78.95384 -402.445525) (xy 78.991929 -402.501154)
			(xy 79.02308 -402.560945) (xy 79.046846 -402.624037) (xy 79.062884 -402.689521) (xy 79.070963 -402.756454)
			(xy 79.070968 -402.823818) (xy 82.349028 -402.823818) (xy 82.349032 -402.75651) (xy 82.357081 -402.689684)
			(xy 82.373058 -402.6243) (xy 82.396735 -402.561293) (xy 82.427773 -402.501568) (xy 82.465726 -402.44598)
			(xy 82.487516 -402.420328) (xy 82.493327 -402.413193) (xy 82.499833 -402.395995) (xy 82.500216 -402.3868)
			(xy 82.500216 -401.893532) (xy 82.499787 -401.884347) (xy 82.493286 -401.867163) (xy 82.487516 -401.860004)
			(xy 82.465709 -401.834368) (xy 82.427763 -401.778778) (xy 82.396731 -401.719052) (xy 82.373061 -401.656046)
			(xy 82.35709 -401.590662) (xy 82.349048 -401.523838) (xy 82.34905 -401.456532) (xy 82.357095 -401.389708)
			(xy 82.37307 -401.324325) (xy 82.396744 -401.26132) (xy 82.427778 -401.201596) (xy 82.465728 -401.146008)
			(xy 82.487516 -401.120356) (xy 82.493316 -401.113213) (xy 82.499828 -401.096021) (xy 82.500216 -401.086828)
			(xy 82.500216 -400.92884) (xy 82.500655 -400.918687) (xy 82.50844 -400.899932) (xy 82.522832 -400.885607)
			(xy 82.541623 -400.877908) (xy 82.551778 -400.877532) (xy 83.268058 -400.877532) (xy 83.278181 -400.878061)
			(xy 83.2969 -400.885773) (xy 83.311257 -400.900047) (xy 83.319079 -400.91872) (xy 83.31962 -400.92884)
			(xy 83.31962 -401.086828) (xy 83.320012 -401.096017) (xy 83.326538 -401.113202) (xy 83.33232 -401.120356)
			(xy 83.354089 -401.146024) (xy 83.392041 -401.201607) (xy 83.423078 -401.261328) (xy 83.446753 -401.324331)
			(xy 83.462729 -401.389711) (xy 83.470775 -401.456533) (xy 83.470777 -401.523837) (xy 83.462734 -401.590659)
			(xy 83.446762 -401.656041) (xy 83.42309 -401.719044) (xy 83.420621 -401.723796) (xy 84.548678 -401.723796)
			(xy 84.54868 -401.656371) (xy 84.556758 -401.589432) (xy 84.572795 -401.523942) (xy 84.59656 -401.460845)
			(xy 84.627711 -401.401047) (xy 84.6658 -401.345412) (xy 84.687664 -401.319746) (xy 84.693474 -401.312611)
			(xy 84.699979 -401.295412) (xy 84.700364 -401.286218) (xy 84.700364 -400.793966) (xy 84.699956 -400.784779)
			(xy 84.693439 -400.767595) (xy 84.687664 -400.760438) (xy 84.665807 -400.734767) (xy 84.627721 -400.679133)
			(xy 84.596572 -400.619337) (xy 84.572809 -400.556241) (xy 84.556774 -400.490753) (xy 84.548698 -400.423816)
			(xy 84.548698 -400.356393) (xy 84.556772 -400.289456) (xy 84.572806 -400.223968) (xy 84.596568 -400.160871)
			(xy 84.627716 -400.101075) (xy 84.665802 -400.04544) (xy 84.687664 -400.019774) (xy 84.693462 -400.01263)
			(xy 84.699974 -399.995438) (xy 84.700364 -399.986246) (xy 84.700364 -399.828766) (xy 84.700799 -399.818634)
			(xy 84.708543 -399.799908) (xy 84.722845 -399.785552) (xy 84.741542 -399.777738) (xy 84.751672 -399.777204)
			(xy 85.467952 -399.777204) (xy 85.478104 -399.777661) (xy 85.496856 -399.785442) (xy 85.511181 -399.799828)
			(xy 85.518881 -399.818613) (xy 85.51926 -399.828766) (xy 85.51926 -399.986246) (xy 85.519705 -399.995429)
			(xy 85.526196 -400.012613) (xy 85.53196 -400.019774) (xy 85.553831 -400.045434) (xy 85.591922 -400.101068)
			(xy 85.623075 -400.160865) (xy 85.646841 -400.223962) (xy 85.662877 -400.289453) (xy 85.670953 -400.356392)
			(xy 85.670952 -400.423817) (xy 85.662875 -400.490756) (xy 85.646838 -400.556246) (xy 85.623071 -400.619344)
			(xy 85.591918 -400.67914) (xy 85.553826 -400.734773) (xy 85.53196 -400.760438) (xy 85.52616 -400.76758)
			(xy 85.519648 -400.784773) (xy 85.51926 -400.793966) (xy 85.51926 -401.286218) (xy 85.51967 -401.295405)
			(xy 85.526185 -401.312589) (xy 85.53196 -401.319746) (xy 85.553804 -401.345428) (xy 85.591896 -401.40106)
			(xy 85.62305 -401.460853) (xy 85.646817 -401.523948) (xy 85.662855 -401.589435) (xy 85.670933 -401.656372)
			(xy 85.670935 -401.723795) (xy 85.662861 -401.790732) (xy 85.646827 -401.856221) (xy 85.623063 -401.919317)
			(xy 85.591913 -401.979112) (xy 85.553824 -402.034745) (xy 85.53196 -402.06041) (xy 85.526172 -402.067561)
			(xy 85.519653 -402.084747) (xy 85.51926 -402.093938) (xy 85.51926 -402.251418) (xy 85.518788 -402.261546)
			(xy 85.511055 -402.280268) (xy 85.496764 -402.294623) (xy 85.478078 -402.302442) (xy 85.467952 -402.30298)
			(xy 84.751672 -402.30298) (xy 84.741514 -402.302601) (xy 84.722757 -402.294792) (xy 84.708434 -402.280383)
			(xy 84.700738 -402.261579) (xy 84.700364 -402.251418) (xy 84.700364 -402.093938) (xy 84.699921 -402.084755)
			(xy 84.693429 -402.067571) (xy 84.687664 -402.06041) (xy 84.66578 -402.034762) (xy 84.627694 -401.979124)
			(xy 84.596546 -401.919325) (xy 84.572785 -401.856226) (xy 84.556752 -401.790735) (xy 84.548678 -401.723796)
			(xy 83.420621 -401.723796) (xy 83.392057 -401.778767) (xy 83.354108 -401.834352) (xy 83.33232 -401.860004)
			(xy 83.326542 -401.867162) (xy 83.320015 -401.884343) (xy 83.31962 -401.893532) (xy 83.31962 -402.3868)
			(xy 83.320026 -402.395988) (xy 83.326542 -402.413172) (xy 83.33232 -402.420328) (xy 83.354062 -402.446018)
			(xy 83.392015 -402.501598) (xy 83.423052 -402.561316) (xy 83.44673 -402.624316) (xy 83.462707 -402.689694)
			(xy 83.470756 -402.756513) (xy 83.47076 -402.823815) (xy 83.470752 -402.823878) (xy 86.748796 -402.823878)
			(xy 86.748801 -402.75645) (xy 86.756882 -402.689508) (xy 86.772922 -402.624016) (xy 86.796693 -402.560918)
			(xy 86.82785 -402.50112) (xy 86.865945 -402.445485) (xy 86.887812 -402.41982) (xy 86.893626 -402.412687)
			(xy 86.90013 -402.395487) (xy 86.900512 -402.386292) (xy 86.900512 -401.89404) (xy 86.90008 -401.884855)
			(xy 86.893581 -401.867671) (xy 86.887812 -401.860512) (xy 86.865928 -401.834863) (xy 86.827839 -401.779227)
			(xy 86.796689 -401.719428) (xy 86.772925 -401.656329) (xy 86.756891 -401.590838) (xy 86.748816 -401.523898)
			(xy 86.748818 -401.456472) (xy 86.756896 -401.389532) (xy 86.772934 -401.324042) (xy 86.796701 -401.260944)
			(xy 86.827855 -401.201148) (xy 86.865946 -401.145513) (xy 86.887812 -401.119848) (xy 86.893615 -401.112707)
			(xy 86.900125 -401.095513) (xy 86.900512 -401.08632) (xy 86.900512 -400.92884) (xy 86.900949 -400.918719)
			(xy 86.908686 -400.900014) (xy 86.922997 -400.885698) (xy 86.941699 -400.877953) (xy 86.95182 -400.877532)
			(xy 87.6681 -400.877532) (xy 87.678226 -400.877917) (xy 87.696936 -400.885671) (xy 87.711252 -400.899997)
			(xy 87.718991 -400.918713) (xy 87.719408 -400.92884) (xy 87.719408 -401.08632) (xy 87.719807 -401.095508)
			(xy 87.726328 -401.112693) (xy 87.732108 -401.119848) (xy 87.753952 -401.14553) (xy 87.792041 -401.201162)
			(xy 87.823192 -401.260956) (xy 87.846957 -401.324051) (xy 87.862994 -401.389538) (xy 87.871071 -401.456474)
			(xy 87.871073 -401.523896) (xy 87.862999 -401.590833) (xy 87.846966 -401.656321) (xy 87.823204 -401.719417)
			(xy 87.820954 -401.723737) (xy 115.349237 -401.723737) (xy 115.349239 -401.65643) (xy 115.357285 -401.589607)
			(xy 115.373259 -401.524224) (xy 115.396933 -401.461219) (xy 115.427967 -401.401494) (xy 115.465916 -401.345907)
			(xy 115.487704 -401.320254) (xy 115.493503 -401.313111) (xy 115.500016 -401.295919) (xy 115.500404 -401.286726)
			(xy 115.500404 -400.793458) (xy 115.500013 -400.784269) (xy 115.493486 -400.767085) (xy 115.487704 -400.75993)
			(xy 115.465923 -400.734273) (xy 115.427977 -400.678686) (xy 115.396945 -400.618963) (xy 115.373273 -400.555959)
			(xy 115.357301 -400.490578) (xy 115.349257 -400.423756) (xy 115.349256 -400.356453) (xy 115.357299 -400.289631)
			(xy 115.373271 -400.22425) (xy 115.396941 -400.161245) (xy 115.427972 -400.101522) (xy 115.465918 -400.045935)
			(xy 115.487704 -400.020282) (xy 115.493491 -400.01313) (xy 115.500011 -399.995945) (xy 115.500404 -399.986754)
			(xy 115.500404 -399.828766) (xy 115.500905 -399.81861) (xy 115.508684 -399.799847) (xy 115.523047 -399.785484)
			(xy 115.54181 -399.777705) (xy 115.551966 -399.777204) (xy 116.268246 -399.777204) (xy 116.278403 -399.777695)
			(xy 116.297166 -399.785478) (xy 116.311529 -399.799844) (xy 116.319307 -399.818609) (xy 116.319808 -399.828766)
			(xy 116.319808 -399.986754) (xy 116.320238 -399.995939) (xy 116.326738 -400.013124) (xy 116.332508 -400.020282)
			(xy 116.354303 -400.045929) (xy 116.392255 -400.101515) (xy 116.423291 -400.161238) (xy 116.446966 -400.224244)
			(xy 116.46294 -400.289627) (xy 116.470985 -400.356451) (xy 116.470984 -400.423758) (xy 116.462939 -400.490582)
			(xy 116.446963 -400.555965) (xy 116.423288 -400.61897) (xy 116.392251 -400.678693) (xy 116.354298 -400.734279)
			(xy 116.332508 -400.75993) (xy 116.326717 -400.767079) (xy 116.320199 -400.784267) (xy 116.319808 -400.793458)
			(xy 116.319808 -401.286726) (xy 116.320204 -401.295915) (xy 116.326727 -401.313099) (xy 116.332508 -401.320254)
			(xy 116.354276 -401.345923) (xy 116.392229 -401.401506) (xy 116.423266 -401.461227) (xy 116.446942 -401.524229)
			(xy 116.462918 -401.58961) (xy 116.470965 -401.656431) (xy 116.470967 -401.723736) (xy 116.462924 -401.790558)
			(xy 116.446952 -401.855939) (xy 116.423279 -401.918943) (xy 116.392246 -401.978666) (xy 116.354296 -402.034251)
			(xy 116.332508 -402.059902) (xy 116.326729 -402.06706) (xy 116.320204 -402.084241) (xy 116.319808 -402.09343)
			(xy 116.319808 -402.251418) (xy 116.319283 -402.261571) (xy 116.311511 -402.280332) (xy 116.297156 -402.294695)
			(xy 116.278399 -402.302477) (xy 116.268246 -402.30298) (xy 115.551966 -402.30298) (xy 115.541808 -402.302495)
			(xy 115.523042 -402.294713) (xy 115.508678 -402.280345) (xy 115.500902 -402.261576) (xy 115.500404 -402.251418)
			(xy 115.500404 -402.09343) (xy 115.499978 -402.084244) (xy 115.493475 -402.06706) (xy 115.487704 -402.059902)
			(xy 115.465896 -402.034267) (xy 115.42795 -401.978677) (xy 115.396919 -401.918951) (xy 115.373249 -401.855944)
			(xy 115.357279 -401.79056) (xy 115.349237 -401.723737) (xy 87.820954 -401.723737) (xy 87.792056 -401.779212)
			(xy 87.75397 -401.834847) (xy 87.732108 -401.860512) (xy 87.726325 -401.867667) (xy 87.719802 -401.88485)
			(xy 87.719408 -401.89404) (xy 87.719408 -402.386292) (xy 87.71982 -402.395479) (xy 87.726332 -402.412663)
			(xy 87.732108 -402.41982) (xy 87.753925 -402.445524) (xy 87.792014 -402.501153) (xy 87.823166 -402.560944)
			(xy 87.846933 -402.624036) (xy 87.862972 -402.68952) (xy 87.871051 -402.756454) (xy 87.871055 -402.823874)
			(xy 87.871055 -402.823878) (xy 117.548826 -402.823878) (xy 117.548831 -402.75645) (xy 117.556912 -402.689507)
			(xy 117.572954 -402.624015) (xy 117.596726 -402.560916) (xy 117.627885 -402.501119) (xy 117.665983 -402.445484)
			(xy 117.687852 -402.41982) (xy 117.693671 -402.412691) (xy 117.700171 -402.395488) (xy 117.700552 -402.386292)
			(xy 117.700552 -401.89404) (xy 117.700111 -401.884856) (xy 117.693618 -401.867672) (xy 117.687852 -401.860512)
			(xy 117.665967 -401.834864) (xy 117.627875 -401.779228) (xy 117.596722 -401.71943) (xy 117.572957 -401.656331)
			(xy 117.556921 -401.590839) (xy 117.548846 -401.523898) (xy 117.548848 -401.456472) (xy 117.556927 -401.389531)
			(xy 117.572966 -401.32404) (xy 117.596735 -401.260943) (xy 117.627891 -401.201146) (xy 117.665985 -401.145512)
			(xy 117.687852 -401.119848) (xy 117.69366 -401.112711) (xy 117.700166 -401.095514) (xy 117.700552 -401.08632)
			(xy 117.700552 -400.92884) (xy 117.701117 -400.91874) (xy 117.708832 -400.900072) (xy 117.723105 -400.885777)
			(xy 117.741761 -400.878033) (xy 117.75186 -400.877532) (xy 118.46814 -400.877532) (xy 118.478255 -400.877953)
			(xy 118.49694 -400.88571) (xy 118.511235 -400.900027) (xy 118.518963 -400.918724) (xy 118.519448 -400.92884)
			(xy 118.519448 -401.08632) (xy 118.51986 -401.095507) (xy 118.526374 -401.11269) (xy 118.532148 -401.119848)
			(xy 118.553994 -401.145529) (xy 118.592087 -401.20116) (xy 118.623241 -401.260953) (xy 118.647009 -401.324048)
			(xy 118.663047 -401.389536) (xy 118.671126 -401.456473) (xy 118.671127 -401.523897) (xy 118.663053 -401.590834)
			(xy 118.647018 -401.656323) (xy 118.623254 -401.719419) (xy 118.620974 -401.723796) (xy 119.749006 -401.723796)
			(xy 119.749008 -401.656371) (xy 119.757086 -401.589431) (xy 119.773123 -401.523941) (xy 119.79689 -401.460843)
			(xy 119.828043 -401.401046) (xy 119.866135 -401.345411) (xy 119.888 -401.319746) (xy 119.893802 -401.312605)
			(xy 119.900313 -401.295411) (xy 119.9007 -401.286218) (xy 119.9007 -400.793966) (xy 119.900306 -400.784777)
			(xy 119.893781 -400.767593) (xy 119.888 -400.760438) (xy 119.866142 -400.734768) (xy 119.828053 -400.679134)
			(xy 119.796902 -400.619339) (xy 119.773138 -400.556242) (xy 119.757102 -400.490754) (xy 119.749025 -400.423816)
			(xy 119.749025 -400.356393) (xy 119.7571 -400.289455) (xy 119.773135 -400.223966) (xy 119.796898 -400.16087)
			(xy 119.828048 -400.101074) (xy 119.866136 -400.045439) (xy 119.888 -400.019774) (xy 119.89379 -400.012624)
			(xy 119.900309 -399.995437) (xy 119.9007 -399.986246) (xy 119.9007 -399.828766) (xy 119.901197 -399.818642)
			(xy 119.908929 -399.799928) (xy 119.923211 -399.785574) (xy 119.941887 -399.777749) (xy 119.952008 -399.777204)
			(xy 120.668288 -399.777204) (xy 120.67841 -399.777626) (xy 120.697114 -399.785371) (xy 120.711429 -399.799686)
			(xy 120.719174 -399.81839) (xy 120.719596 -399.828512) (xy 120.719596 -399.986246) (xy 120.720033 -399.99543)
			(xy 120.726528 -400.012615) (xy 120.732296 -400.019774) (xy 120.754166 -400.045434) (xy 120.792255 -400.101069)
			(xy 120.823405 -400.160866) (xy 120.847169 -400.223964) (xy 120.863205 -400.289454) (xy 120.87128 -400.356392)
			(xy 120.87128 -400.423817) (xy 120.863203 -400.490755) (xy 120.847167 -400.556245) (xy 120.823402 -400.619342)
			(xy 120.79225 -400.679138) (xy 120.75416 -400.734773) (xy 120.732296 -400.760438) (xy 120.7265 -400.767584)
			(xy 120.719985 -400.784774) (xy 120.719596 -400.793966) (xy 120.719596 -401.286218) (xy 120.719998 -401.295406)
			(xy 120.726517 -401.31259) (xy 120.732296 -401.319746) (xy 120.754138 -401.345429) (xy 120.792228 -401.401061)
			(xy 120.82338 -401.460855) (xy 120.847146 -401.523949) (xy 120.863183 -401.589436) (xy 120.87126 -401.656372)
			(xy 120.871262 -401.723794) (xy 120.863189 -401.790731) (xy 120.847155 -401.856219) (xy 120.823394 -401.919315)
			(xy 120.792245 -401.979111) (xy 120.754159 -402.034745) (xy 120.732296 -402.06041) (xy 120.726512 -402.067564)
			(xy 120.71999 -402.084748) (xy 120.719596 -402.093938) (xy 120.719596 -402.251418) (xy 120.719089 -402.261541)
			(xy 120.711362 -402.280256) (xy 120.697083 -402.294611) (xy 120.678409 -402.302436) (xy 120.668288 -402.30298)
			(xy 119.952008 -402.30298) (xy 119.941884 -402.302577) (xy 119.923176 -402.294828) (xy 119.908861 -402.280507)
			(xy 119.901119 -402.261797) (xy 119.9007 -402.251672) (xy 119.9007 -402.093938) (xy 119.900272 -402.084753)
			(xy 119.893771 -402.067568) (xy 119.888 -402.06041) (xy 119.866114 -402.034763) (xy 119.828026 -401.979126)
			(xy 119.796877 -401.919327) (xy 119.773114 -401.856228) (xy 119.75708 -401.790736) (xy 119.749006 -401.723796)
			(xy 118.620974 -401.723796) (xy 118.592102 -401.779215) (xy 118.554013 -401.834848) (xy 118.532148 -401.860512)
			(xy 118.526357 -401.867661) (xy 118.519841 -401.884849) (xy 118.519448 -401.89404) (xy 118.519448 -402.386292)
			(xy 118.519874 -402.395477) (xy 118.526378 -402.412661) (xy 118.532148 -402.41982) (xy 118.553967 -402.445523)
			(xy 118.59206 -402.501151) (xy 118.623216 -402.560942) (xy 118.646985 -402.624034) (xy 118.663025 -402.689519)
			(xy 118.671106 -402.756454) (xy 118.67111 -402.823818) (xy 121.949146 -402.823818) (xy 121.94915 -402.756509)
			(xy 121.957199 -402.689684) (xy 121.973177 -402.624299) (xy 121.996856 -402.561292) (xy 122.027895 -402.501567)
			(xy 122.065849 -402.44598) (xy 122.08764 -402.420328) (xy 122.093455 -402.413196) (xy 122.099958 -402.395995)
			(xy 122.10034 -402.3868) (xy 122.10034 -401.893532) (xy 122.099905 -401.884348) (xy 122.093408 -401.867164)
			(xy 122.08764 -401.860004) (xy 122.065832 -401.834368) (xy 122.027884 -401.778779) (xy 121.996852 -401.719054)
			(xy 121.97318 -401.656047) (xy 121.957208 -401.590663) (xy 121.949166 -401.523838) (xy 121.949168 -401.456532)
			(xy 121.957214 -401.389708) (xy 121.973189 -401.324324) (xy 121.996864 -401.261319) (xy 122.0279 -401.201595)
			(xy 122.065851 -401.146008) (xy 122.08764 -401.120356) (xy 122.093443 -401.113215) (xy 122.099953 -401.096021)
			(xy 122.10034 -401.086828) (xy 122.10034 -400.92884) (xy 122.10075 -400.918715) (xy 122.108492 -400.900005)
			(xy 122.122812 -400.885688) (xy 122.141523 -400.877948) (xy 122.151648 -400.877532) (xy 122.868182 -400.877532)
			(xy 122.878307 -400.878041) (xy 122.897026 -400.885761) (xy 122.911383 -400.900041) (xy 122.919204 -400.918718)
			(xy 122.919744 -400.92884) (xy 122.919744 -401.086828) (xy 122.920153 -401.096015) (xy 122.926669 -401.113199)
			(xy 122.932444 -401.120356) (xy 122.954212 -401.146024) (xy 122.992163 -401.201608) (xy 123.023198 -401.261329)
			(xy 123.046873 -401.324332) (xy 123.062848 -401.389712) (xy 123.070894 -401.456533) (xy 123.070895 -401.523837)
			(xy 123.062853 -401.590658) (xy 123.046882 -401.65604) (xy 123.02321 -401.719043) (xy 123.020771 -401.723737)
			(xy 124.149301 -401.723737) (xy 124.149303 -401.65643) (xy 124.15735 -401.589605) (xy 124.173327 -401.524221)
			(xy 124.197004 -401.461215) (xy 124.228043 -401.401491) (xy 124.265997 -401.345906) (xy 124.287788 -401.320254)
			(xy 124.293585 -401.313109) (xy 124.3001 -401.295918) (xy 124.300488 -401.286726) (xy 124.300488 -400.793458)
			(xy 124.300101 -400.784268) (xy 124.293572 -400.767084) (xy 124.287788 -400.75993) (xy 124.266005 -400.734274)
			(xy 124.228052 -400.678689) (xy 124.197016 -400.618966) (xy 124.173341 -400.555962) (xy 124.157366 -400.49058)
			(xy 124.149321 -400.423757) (xy 124.14932 -400.356452) (xy 124.157365 -400.289629) (xy 124.173338 -400.224246)
			(xy 124.197013 -400.161242) (xy 124.228048 -400.101519) (xy 124.265999 -400.045933) (xy 124.287788 -400.020282)
			(xy 124.293573 -400.013129) (xy 124.300095 -399.995944) (xy 124.300488 -399.986754) (xy 124.300488 -399.828766)
			(xy 124.300837 -399.818586) (xy 124.308643 -399.799781) (xy 124.323052 -399.785395) (xy 124.341869 -399.777621)
			(xy 124.35205 -399.777204) (xy 125.06833 -399.777204) (xy 125.078486 -399.777708) (xy 125.097249 -399.785486)
			(xy 125.111612 -399.799848) (xy 125.119391 -399.818611) (xy 125.119892 -399.828766) (xy 125.119892 -399.986754)
			(xy 125.120326 -399.995939) (xy 125.126823 -400.013123) (xy 125.132592 -400.020282) (xy 125.154385 -400.04593)
			(xy 125.192331 -400.101518) (xy 125.223363 -400.161242) (xy 125.247034 -400.224247) (xy 125.263005 -400.289629)
			(xy 125.271049 -400.356452) (xy 125.271048 -400.423757) (xy 125.263004 -400.490579) (xy 125.247031 -400.555962)
			(xy 125.223359 -400.618966) (xy 125.192327 -400.67869) (xy 125.154379 -400.734277) (xy 125.132592 -400.75993)
			(xy 125.126799 -400.767078) (xy 125.120283 -400.784266) (xy 125.119892 -400.793458) (xy 125.119892 -401.286726)
			(xy 125.120291 -401.295914) (xy 125.126813 -401.313099) (xy 125.132592 -401.320254) (xy 125.154357 -401.345924)
			(xy 125.192305 -401.401509) (xy 125.223337 -401.46123) (xy 125.24701 -401.524232) (xy 125.262983 -401.589612)
			(xy 125.271029 -401.656432) (xy 125.271031 -401.723735) (xy 125.262989 -401.790555) (xy 125.24702 -401.855936)
			(xy 125.223351 -401.918939) (xy 125.192322 -401.978663) (xy 125.154377 -402.034249) (xy 125.132592 -402.059902)
			(xy 125.126811 -402.067058) (xy 125.120287 -402.08424) (xy 125.119892 -402.09343) (xy 125.119892 -402.251418)
			(xy 125.119382 -402.261573) (xy 125.111608 -402.280337) (xy 125.097247 -402.294701) (xy 125.078485 -402.30248)
			(xy 125.06833 -402.30298) (xy 124.35205 -402.30298) (xy 124.341884 -402.302496) (xy 124.323094 -402.29473)
			(xy 124.308708 -402.280363) (xy 124.300918 -402.261584) (xy 124.300488 -402.251418) (xy 124.300488 -402.09343)
			(xy 124.300066 -402.084244) (xy 124.293561 -402.067059) (xy 124.287788 -402.059902) (xy 124.265977 -402.034268)
			(xy 124.228026 -401.97868) (xy 124.196991 -401.918955) (xy 124.173317 -401.855948) (xy 124.157344 -401.790563)
			(xy 124.149301 -401.723737) (xy 123.020771 -401.723737) (xy 122.992178 -401.778766) (xy 122.954231 -401.834352)
			(xy 122.932444 -401.860004) (xy 122.926656 -401.867155) (xy 122.920138 -401.884341) (xy 122.919744 -401.893532)
			(xy 122.919744 -402.3868) (xy 122.920167 -402.395986) (xy 122.926673 -402.413169) (xy 122.932444 -402.420328)
			(xy 122.954185 -402.446019) (xy 122.992136 -402.501599) (xy 123.023173 -402.561317) (xy 123.046849 -402.624317)
			(xy 123.062826 -402.689695) (xy 123.070874 -402.756513) (xy 123.070878 -402.823815) (xy 123.07087 -402.823878)
			(xy 126.348914 -402.823878) (xy 126.348919 -402.75645) (xy 126.357 -402.689508) (xy 126.373042 -402.624016)
			(xy 126.396813 -402.560916) (xy 126.427971 -402.501119) (xy 126.466068 -402.445485) (xy 126.487936 -402.41982)
			(xy 126.493754 -402.41269) (xy 126.500255 -402.395488) (xy 126.500636 -402.386292) (xy 126.500636 -401.89404)
			(xy 126.500198 -401.884856) (xy 126.493703 -401.867672) (xy 126.487936 -401.860512) (xy 126.466051 -401.834864)
			(xy 126.427961 -401.779227) (xy 126.396809 -401.719429) (xy 126.373044 -401.65633) (xy 126.357009 -401.590839)
			(xy 126.348934 -401.523898) (xy 126.348936 -401.456472) (xy 126.357014 -401.389532) (xy 126.373053 -401.324041)
			(xy 126.396821 -401.260943) (xy 126.427976 -401.201147) (xy 126.46607 -401.145513) (xy 126.487936 -401.119848)
			(xy 126.493742 -401.112709) (xy 126.50025 -401.095514) (xy 126.500636 -401.08632) (xy 126.500636 -400.92884)
			(xy 126.50105 -400.918716) (xy 126.508791 -400.900006) (xy 126.523109 -400.885689) (xy 126.54182 -400.877949)
			(xy 126.551944 -400.877532) (xy 127.268224 -400.877532) (xy 127.278352 -400.877897) (xy 127.297062 -400.885659)
			(xy 127.311377 -400.899991) (xy 127.319116 -400.918711) (xy 127.319532 -400.92884) (xy 127.319532 -401.08632)
			(xy 127.319948 -401.095506) (xy 127.326459 -401.11269) (xy 127.332232 -401.119848) (xy 127.354075 -401.14553)
			(xy 127.392162 -401.201163) (xy 127.423312 -401.260957) (xy 127.447076 -401.324052) (xy 127.463112 -401.389538)
			(xy 127.471189 -401.456474) (xy 127.471191 -401.523896) (xy 127.463117 -401.590832) (xy 127.447085 -401.65632)
			(xy 127.423324 -401.719415) (xy 127.421073 -401.723737) (xy 128.549092 -401.723737) (xy 128.549094 -401.65643)
			(xy 128.557141 -401.589605) (xy 128.573117 -401.524221) (xy 128.596794 -401.461216) (xy 128.627832 -401.401492)
			(xy 128.665786 -401.345906) (xy 128.687576 -401.320254) (xy 128.693372 -401.313108) (xy 128.699888 -401.295918)
			(xy 128.700276 -401.286726) (xy 128.700276 -400.793458) (xy 128.699891 -400.784268) (xy 128.69336 -400.767084)
			(xy 128.687576 -400.75993) (xy 128.665793 -400.734273) (xy 128.627842 -400.678688) (xy 128.596806 -400.618966)
			(xy 128.573131 -400.555962) (xy 128.557157 -400.49058) (xy 128.549112 -400.423757) (xy 128.549111 -400.356452)
			(xy 128.557155 -400.289629) (xy 128.573129 -400.224247) (xy 128.596802 -400.161242) (xy 128.627837 -400.101519)
			(xy 128.665788 -400.045934) (xy 128.687576 -400.020282) (xy 128.69336 -400.013128) (xy 128.699883 -399.995944)
			(xy 128.700276 -399.986754) (xy 128.700276 -399.828766) (xy 128.700637 -399.818587) (xy 128.70844 -399.799785)
			(xy 128.722845 -399.7854) (xy 128.741659 -399.777623) (xy 128.751838 -399.777204) (xy 129.468118 -399.777204)
			(xy 129.478273 -399.777718) (xy 129.497036 -399.785492) (xy 129.511399 -399.799851) (xy 129.519179 -399.818611)
			(xy 129.51968 -399.828766) (xy 129.51968 -399.986754) (xy 129.520117 -399.995938) (xy 129.526612 -400.013123)
			(xy 129.53238 -400.020282) (xy 129.554173 -400.045929) (xy 129.592121 -400.101517) (xy 129.623152 -400.161241)
			(xy 129.646824 -400.224247) (xy 129.662796 -400.289629) (xy 129.670839 -400.356452) (xy 129.670839 -400.423757)
			(xy 129.662794 -400.49058) (xy 129.646821 -400.555962) (xy 129.623149 -400.618967) (xy 129.592116 -400.678691)
			(xy 129.554168 -400.734278) (xy 129.53238 -400.75993) (xy 129.526586 -400.767077) (xy 129.52007 -400.784266)
			(xy 129.51968 -400.793458) (xy 129.51968 -401.286726) (xy 129.520082 -401.295914) (xy 129.526602 -401.313098)
			(xy 129.53238 -401.320254) (xy 129.554146 -401.345924) (xy 129.592094 -401.401508) (xy 129.623127 -401.46123)
			(xy 129.6468 -401.524232) (xy 129.662774 -401.589612) (xy 129.67082 -401.656432) (xy 129.670822 -401.723735)
			(xy 129.66278 -401.790556) (xy 129.64681 -401.855937) (xy 129.623141 -401.91894) (xy 129.592111 -401.978663)
			(xy 129.554166 -402.03425) (xy 129.53238 -402.059902) (xy 129.526598 -402.067057) (xy 129.520075 -402.08424)
			(xy 129.51968 -402.09343) (xy 129.51968 -402.251418) (xy 129.519182 -402.261575) (xy 129.511405 -402.280341)
			(xy 129.497041 -402.294705) (xy 129.478275 -402.302482) (xy 129.468118 -402.30298) (xy 128.751838 -402.30298)
			(xy 128.741671 -402.302505) (xy 128.722881 -402.294736) (xy 128.708495 -402.280366) (xy 128.700706 -402.261584)
			(xy 128.700276 -402.251418) (xy 128.700276 -402.09343) (xy 128.699857 -402.084244) (xy 128.69335 -402.067059)
			(xy 128.687576 -402.059902) (xy 128.665766 -402.034268) (xy 128.627815 -401.97868) (xy 128.596781 -401.918954)
			(xy 128.573108 -401.855947) (xy 128.557135 -401.790562) (xy 128.549092 -401.723737) (xy 127.421073 -401.723737)
			(xy 127.392178 -401.779211) (xy 127.354094 -401.834846) (xy 127.332232 -401.860512) (xy 127.32644 -401.86766)
			(xy 127.319924 -401.884849) (xy 127.319532 -401.89404) (xy 127.319532 -402.386292) (xy 127.319961 -402.395477)
			(xy 127.326463 -402.412661) (xy 127.332232 -402.41982) (xy 127.354048 -402.445525) (xy 127.392136 -402.501154)
			(xy 127.423287 -402.560945) (xy 127.447052 -402.624037) (xy 127.46309 -402.689521) (xy 127.471169 -402.756454)
			(xy 127.471174 -402.823818) (xy 130.749234 -402.823818) (xy 130.749238 -402.75651) (xy 130.757287 -402.689684)
			(xy 130.773265 -402.624299) (xy 130.796942 -402.561293) (xy 130.82798 -402.501568) (xy 130.865934 -402.44598)
			(xy 130.887724 -402.420328) (xy 130.893536 -402.413194) (xy 130.900041 -402.395995) (xy 130.900424 -402.3868)
			(xy 130.900424 -401.893532) (xy 130.899993 -401.884347) (xy 130.893493 -401.867163) (xy 130.887724 -401.860004)
			(xy 130.865917 -401.834368) (xy 130.82797 -401.778779) (xy 130.796938 -401.719053) (xy 130.773267 -401.656046)
			(xy 130.757296 -401.590662) (xy 130.749254 -401.523838) (xy 130.749256 -401.456532) (xy 130.757301 -401.389708)
			(xy 130.773276 -401.324325) (xy 130.79695 -401.26132) (xy 130.827985 -401.201595) (xy 130.865935 -401.146008)
			(xy 130.887724 -401.120356) (xy 130.893525 -401.113214) (xy 130.900036 -401.096021) (xy 130.900424 -401.086828)
			(xy 130.900424 -400.92884) (xy 130.900855 -400.918686) (xy 130.908642 -400.899929) (xy 130.923036 -400.885604)
			(xy 130.94183 -400.877907) (xy 130.951986 -400.877532) (xy 131.668266 -400.877532) (xy 131.67839 -400.878054)
			(xy 131.697108 -400.88577) (xy 131.711465 -400.900045) (xy 131.719287 -400.918719) (xy 131.719828 -400.92884)
			(xy 131.719828 -401.086828) (xy 131.720218 -401.096017) (xy 131.726745 -401.113202) (xy 131.732528 -401.120356)
			(xy 131.754297 -401.146024) (xy 131.792249 -401.201607) (xy 131.823285 -401.261328) (xy 131.84696 -401.324331)
			(xy 131.862935 -401.389712) (xy 131.870981 -401.456533) (xy 131.870983 -401.523837) (xy 131.862941 -401.590659)
			(xy 131.846969 -401.65604) (xy 131.823297 -401.719044) (xy 131.792264 -401.778767) (xy 131.754315 -401.834352)
			(xy 131.732528 -401.860004) (xy 131.726738 -401.867154) (xy 131.720222 -401.884341) (xy 131.719828 -401.893532)
			(xy 131.719828 -402.3868) (xy 131.720232 -402.395988) (xy 131.726749 -402.413173) (xy 131.732528 -402.420328)
			(xy 131.75427 -402.446019) (xy 131.792222 -402.501599) (xy 131.823259 -402.561317) (xy 131.846936 -402.624316)
			(xy 131.862913 -402.689694) (xy 131.870962 -402.756513) (xy 131.870966 -402.823815) (xy 131.862926 -402.890635)
			(xy 131.846957 -402.956015) (xy 131.823289 -403.019017) (xy 131.792259 -403.078739) (xy 131.754314 -403.134324)
			(xy 131.732528 -403.159976) (xy 131.726708 -403.167104) (xy 131.720209 -403.184308) (xy 131.719828 -403.193504)
			(xy 131.719828 -403.351492) (xy 131.719372 -403.361642) (xy 131.711585 -403.380389) (xy 131.697199 -403.394712)
			(xy 131.678418 -403.402417) (xy 131.668266 -403.4028) (xy 130.951986 -403.4028) (xy 130.941863 -403.402286)
			(xy 130.92315 -403.394561) (xy 130.908795 -403.380284) (xy 130.90097 -403.361612) (xy 130.900424 -403.351492)
			(xy 130.900424 -403.193504) (xy 130.900007 -403.184318) (xy 130.893498 -403.167133) (xy 130.887724 -403.159976)
			(xy 130.86589 -403.134362) (xy 130.827943 -403.07877) (xy 130.796913 -403.019041) (xy 130.773243 -402.956032)
			(xy 130.757274 -402.890645) (xy 130.749234 -402.823818) (xy 127.471174 -402.823818) (xy 127.471174 -402.823874)
			(xy 127.463103 -402.890808) (xy 127.447074 -402.956294) (xy 127.423316 -403.019389) (xy 127.392173 -403.079184)
			(xy 127.354092 -403.134818) (xy 127.332232 -403.160484) (xy 127.326409 -403.16761) (xy 127.319912 -403.184816)
			(xy 127.319532 -403.194012) (xy 127.319532 -403.351492) (xy 127.319009 -403.361596) (xy 127.31128 -403.380268)
			(xy 127.296995 -403.394562) (xy 127.278328 -403.402303) (xy 127.268224 -403.4028) (xy 126.551944 -403.4028)
			(xy 126.541824 -403.402348) (xy 126.523122 -403.394614) (xy 126.508806 -403.380308) (xy 126.501059 -403.361611)
			(xy 126.500636 -403.351492) (xy 126.500636 -403.194012) (xy 126.500212 -403.184826) (xy 126.493707 -403.167642)
			(xy 126.487936 -403.160484) (xy 126.466024 -403.134858) (xy 126.427934 -403.079219) (xy 126.396783 -403.019418)
			(xy 126.37302 -402.956315) (xy 126.356987 -402.890821) (xy 126.348914 -402.823878) (xy 123.07087 -402.823878)
			(xy 123.062839 -402.890634) (xy 123.04687 -402.956014) (xy 123.023202 -403.019017) (xy 122.992173 -403.078739)
			(xy 122.954229 -403.134324) (xy 122.932444 -403.159976) (xy 122.926626 -403.167106) (xy 122.920126 -403.184308)
			(xy 122.919744 -403.193504) (xy 122.919744 -403.351492) (xy 122.919209 -403.361595) (xy 122.911483 -403.380264)
			(xy 122.897201 -403.394558) (xy 122.878538 -403.402301) (xy 122.868436 -403.4028) (xy 122.151902 -403.4028)
			(xy 122.14178 -403.402273) (xy 122.123067 -403.394553) (xy 122.108712 -403.38028) (xy 122.100886 -403.361611)
			(xy 122.10034 -403.351492) (xy 122.10034 -403.193504) (xy 122.099919 -403.184318) (xy 122.093412 -403.167134)
			(xy 122.08764 -403.159976) (xy 122.065805 -403.134363) (xy 122.027857 -403.078771) (xy 121.996826 -403.019042)
			(xy 121.973156 -402.956032) (xy 121.957186 -402.890645) (xy 121.949146 -402.823818) (xy 118.67111 -402.823818)
			(xy 118.67111 -402.823874) (xy 118.663038 -402.89081) (xy 118.647006 -402.956297) (xy 118.623245 -403.019392)
			(xy 118.592097 -403.079187) (xy 118.554011 -403.13482) (xy 118.532148 -403.160484) (xy 118.526327 -403.167612)
			(xy 118.519828 -403.184816) (xy 118.519448 -403.194012) (xy 118.519448 -403.351492) (xy 118.51891 -403.361594)
			(xy 118.511183 -403.380263) (xy 118.496903 -403.394557) (xy 118.478242 -403.4023) (xy 118.46814 -403.4028)
			(xy 117.75186 -403.4028) (xy 117.741749 -403.402348) (xy 117.72307 -403.394597) (xy 117.708776 -403.38029)
			(xy 117.701043 -403.361604) (xy 117.700552 -403.351492) (xy 117.700552 -403.194012) (xy 117.700125 -403.184827)
			(xy 117.693622 -403.167643) (xy 117.687852 -403.160484) (xy 117.665939 -403.134859) (xy 117.627848 -403.07922)
			(xy 117.596697 -403.019418) (xy 117.572933 -402.956316) (xy 117.556899 -402.890822) (xy 117.548826 -402.823878)
			(xy 87.871055 -402.823878) (xy 87.862984 -402.890809) (xy 87.846954 -402.956295) (xy 87.823196 -403.01939)
			(xy 87.792051 -403.079185) (xy 87.753969 -403.134819) (xy 87.732108 -403.160484) (xy 87.726294 -403.167617)
			(xy 87.71979 -403.184817) (xy 87.719408 -403.194012) (xy 87.719408 -403.351492) (xy 87.718978 -403.361613)
			(xy 87.711234 -403.380315) (xy 87.696922 -403.394629) (xy 87.678221 -403.402376) (xy 87.6681 -403.4028)
			(xy 86.95182 -403.4028) (xy 86.941699 -403.402368) (xy 86.922996 -403.394626) (xy 86.908681 -403.380315)
			(xy 86.900935 -403.361613) (xy 86.900512 -403.351492) (xy 86.900512 -403.194012) (xy 86.900093 -403.184826)
			(xy 86.893585 -403.167642) (xy 86.887812 -403.160484) (xy 86.8659 -403.134858) (xy 86.827812 -403.079218)
			(xy 86.796663 -403.019417) (xy 86.772901 -402.956315) (xy 86.756869 -402.890821) (xy 86.748796 -402.823878)
			(xy 83.470752 -402.823878) (xy 83.46272 -402.890635) (xy 83.446751 -402.956015) (xy 83.423082 -403.019018)
			(xy 83.392052 -403.07874) (xy 83.354106 -403.134324) (xy 83.33232 -403.159976) (xy 83.326511 -403.167113)
			(xy 83.320003 -403.18431) (xy 83.31962 -403.193504) (xy 83.31962 -403.351492) (xy 83.319172 -403.361643)
			(xy 83.311383 -403.380391) (xy 83.296995 -403.394714) (xy 83.278211 -403.402418) (xy 83.268058 -403.4028)
			(xy 82.551778 -403.4028) (xy 82.541655 -403.402293) (xy 82.522941 -403.394565) (xy 82.508586 -403.380286)
			(xy 82.500761 -403.361613) (xy 82.500216 -403.351492) (xy 82.500216 -403.193504) (xy 82.4998 -403.184318)
			(xy 82.49329 -403.167133) (xy 82.487516 -403.159976) (xy 82.465682 -403.134362) (xy 82.427736 -403.07877)
			(xy 82.396706 -403.019041) (xy 82.373037 -402.956031) (xy 82.357068 -402.890645) (xy 82.349028 -402.823818)
			(xy 79.070968 -402.823818) (xy 79.070968 -402.823874) (xy 79.062897 -402.890808) (xy 79.046867 -402.956294)
			(xy 79.023109 -403.019389) (xy 78.991966 -403.079184) (xy 78.953884 -403.134818) (xy 78.932024 -403.160484)
			(xy 78.926212 -403.167618) (xy 78.919706 -403.184817) (xy 78.919324 -403.194012) (xy 78.919324 -403.351492)
			(xy 78.918809 -403.361597) (xy 78.911078 -403.380271) (xy 78.896791 -403.394565) (xy 78.878121 -403.402304)
			(xy 78.868016 -403.4028) (xy 78.151736 -403.4028) (xy 78.141616 -403.402354) (xy 78.122913 -403.394618)
			(xy 78.108598 -403.38031) (xy 78.100851 -403.361612) (xy 78.100428 -403.351492) (xy 78.100428 -403.194012)
			(xy 78.100006 -403.184826) (xy 78.0935 -403.167642) (xy 78.087728 -403.160484) (xy 78.065816 -403.134858)
			(xy 78.027727 -403.079219) (xy 77.996577 -403.019417) (xy 77.972814 -402.956315) (xy 77.956781 -402.890821)
			(xy 77.948708 -402.823878) (xy 74.670664 -402.823878) (xy 74.662632 -402.890635) (xy 74.646664 -402.956014)
			(xy 74.622995 -403.019017) (xy 74.591966 -403.078739) (xy 74.554022 -403.134324) (xy 74.532236 -403.159976)
			(xy 74.526417 -403.167105) (xy 74.519917 -403.184308) (xy 74.519536 -403.193504) (xy 74.519536 -403.351492)
			(xy 74.519073 -403.361641) (xy 74.511286 -403.380386) (xy 74.496903 -403.394709) (xy 74.478125 -403.402415)
			(xy 74.467974 -403.4028) (xy 73.751694 -403.4028) (xy 73.741572 -403.402279) (xy 73.722858 -403.394557)
			(xy 73.708504 -403.380282) (xy 73.700678 -403.361611) (xy 73.700132 -403.351492) (xy 73.700132 -403.193504)
			(xy 73.699713 -403.184318) (xy 73.693205 -403.167134) (xy 73.687432 -403.159976) (xy 73.665597 -403.134363)
			(xy 73.62765 -403.07877) (xy 73.59662 -403.019041) (xy 73.57295 -402.956032) (xy 73.55698 -402.890645)
			(xy 73.54894 -402.823818) (xy 66.525648 -402.823818) (xy 66.525648 -405.623707) (xy 71.348811 -405.623707)
			(xy 71.348811 -405.556283) (xy 71.356888 -405.489345) (xy 71.372924 -405.423856) (xy 71.396688 -405.360759)
			(xy 71.427839 -405.300962) (xy 71.465928 -405.245327) (xy 71.487792 -405.219662) (xy 71.493586 -405.212515)
			(xy 71.500103 -405.195326) (xy 71.500492 -405.186134) (xy 71.500492 -404.693882) (xy 71.500092 -404.684694)
			(xy 71.493571 -404.667509) (xy 71.487792 -404.660354) (xy 71.46595 -404.634671) (xy 71.427861 -404.579039)
			(xy 71.39671 -404.519245) (xy 71.372945 -404.45615) (xy 71.356908 -404.390664) (xy 71.348831 -404.323727)
			(xy 71.348829 -404.256306) (xy 71.356902 -404.189369) (xy 71.372935 -404.123881) (xy 71.396696 -404.060785)
			(xy 71.427844 -404.00099) (xy 71.46593 -403.945355) (xy 71.487792 -403.91969) (xy 71.493574 -403.912535)
			(xy 71.500098 -403.895352) (xy 71.500492 -403.886162) (xy 71.500492 -403.728682) (xy 71.50101 -403.71856)
			(xy 71.508735 -403.699847) (xy 71.523011 -403.685493) (xy 71.541681 -403.677666) (xy 71.5518 -403.67712)
			(xy 72.26808 -403.67712) (xy 72.278235 -403.677538) (xy 72.296991 -403.685331) (xy 72.311316 -403.699729)
			(xy 72.319013 -403.718525) (xy 72.319388 -403.728682) (xy 72.319388 -403.886162) (xy 72.319819 -403.895347)
			(xy 72.326319 -403.912531) (xy 72.332088 -403.91969) (xy 72.353974 -403.945337) (xy 72.392063 -404.000974)
			(xy 72.423213 -404.060773) (xy 72.446977 -404.123872) (xy 72.463011 -404.189363) (xy 72.471085 -404.256304)
			(xy 72.471083 -404.323729) (xy 72.463005 -404.390669) (xy 72.446967 -404.45616) (xy 72.4232 -404.519258)
			(xy 72.392046 -404.579054) (xy 72.353954 -404.634689) (xy 72.332088 -404.660354) (xy 72.326285 -404.667494)
			(xy 72.319774 -404.684689) (xy 72.319388 -404.693882) (xy 72.319388 -405.186134) (xy 72.319784 -405.195323)
			(xy 72.326308 -405.212507) (xy 72.332088 -405.219662) (xy 72.353946 -405.245332) (xy 72.392036 -405.300965)
			(xy 72.423188 -405.360761) (xy 72.446953 -405.423857) (xy 72.462989 -405.489346) (xy 72.471066 -405.556284)
			(xy 72.471066 -405.623707) (xy 72.462991 -405.690645) (xy 72.446956 -405.756134) (xy 72.423191 -405.819231)
			(xy 72.392041 -405.879027) (xy 72.353952 -405.934661) (xy 72.332088 -405.960326) (xy 72.326297 -405.967475)
			(xy 72.319779 -405.984663) (xy 72.319388 -405.993854) (xy 72.319388 -406.151334) (xy 72.318902 -406.161459)
			(xy 72.311168 -406.180176) (xy 72.296883 -406.19453) (xy 72.278203 -406.202353) (xy 72.26808 -406.202896)
			(xy 71.5518 -406.202896) (xy 71.541645 -406.202478) (xy 71.522892 -406.194682) (xy 71.508569 -406.180284)
			(xy 71.50087 -406.161491) (xy 71.500492 -406.151334) (xy 71.500492 -405.993854) (xy 71.500058 -405.984669)
			(xy 71.493561 -405.967485) (xy 71.487792 -405.960326) (xy 71.465922 -405.934665) (xy 71.427834 -405.87903)
			(xy 71.396684 -405.819233) (xy 71.372921 -405.756136) (xy 71.356886 -405.690646) (xy 71.348811 -405.623707)
			(xy 66.525648 -405.623707) (xy 66.525648 -406.72373) (xy 73.548951 -406.72373) (xy 73.548954 -406.656422)
			(xy 73.557001 -406.589598) (xy 73.572978 -406.524214) (xy 73.596654 -406.461208) (xy 73.62769 -406.401483)
			(xy 73.665642 -406.345896) (xy 73.687432 -406.320244) (xy 73.693239 -406.313106) (xy 73.699747 -406.29591)
			(xy 73.700132 -406.286716) (xy 73.700132 -405.793448) (xy 73.699691 -405.784264) (xy 73.693198 -405.76708)
			(xy 73.687432 -405.75992) (xy 73.66564 -405.734271) (xy 73.627692 -405.678684) (xy 73.596659 -405.61896)
			(xy 73.572987 -405.555955) (xy 73.557015 -405.490572) (xy 73.548971 -405.42375) (xy 73.548971 -405.356444)
			(xy 73.557016 -405.289622) (xy 73.572989 -405.224239) (xy 73.596662 -405.161235) (xy 73.627695 -405.101511)
			(xy 73.665644 -405.045924) (xy 73.687432 -405.020272) (xy 73.693227 -405.013126) (xy 73.699742 -404.995936)
			(xy 73.700132 -404.986744) (xy 73.700132 -404.828756) (xy 73.700486 -404.818595) (xy 73.708302 -404.799836)
			(xy 73.72272 -404.785513) (xy 73.74153 -404.77782) (xy 73.751694 -404.777448) (xy 74.467974 -404.777448)
			(xy 74.4781 -404.777948) (xy 74.496822 -404.785669) (xy 74.51118 -404.799951) (xy 74.518998 -404.818633)
			(xy 74.519536 -404.828756) (xy 74.519536 -404.986744) (xy 74.519939 -404.995932) (xy 74.526459 -405.013115)
			(xy 74.532236 -405.020272) (xy 74.55402 -405.045927) (xy 74.591971 -405.101513) (xy 74.623006 -405.161235)
			(xy 74.64668 -405.22424) (xy 74.662654 -405.289622) (xy 74.670699 -405.356444) (xy 74.670699 -405.42375)
			(xy 74.662655 -405.490572) (xy 74.646682 -405.555955) (xy 74.623008 -405.618959) (xy 74.620571 -405.623649)
			(xy 75.749106 -405.623649) (xy 75.749107 -405.556342) (xy 75.757152 -405.489519) (xy 75.773127 -405.424136)
			(xy 75.796802 -405.361131) (xy 75.827839 -405.301407) (xy 75.865791 -405.245822) (xy 75.88758 -405.22017)
			(xy 75.893369 -405.21302) (xy 75.899889 -405.195833) (xy 75.90028 -405.186642) (xy 75.90028 -404.693374)
			(xy 75.899887 -404.684185) (xy 75.893362 -404.667001) (xy 75.88758 -404.659846) (xy 75.865813 -404.634177)
			(xy 75.827861 -404.578594) (xy 75.796824 -404.518873) (xy 75.773148 -404.45587) (xy 75.757173 -404.39049)
			(xy 75.749126 -404.323669) (xy 75.749124 -404.256365) (xy 75.757167 -404.189543) (xy 75.773138 -404.124161)
			(xy 75.796811 -404.061157) (xy 75.827844 -404.001435) (xy 75.865792 -403.94585) (xy 75.88758 -403.920198)
			(xy 75.893358 -403.913039) (xy 75.899884 -403.895859) (xy 75.90028 -403.88667) (xy 75.90028 -403.728682)
			(xy 75.90065 -403.718504) (xy 75.908449 -403.699701) (xy 75.922851 -403.685315) (xy 75.941664 -403.677538)
			(xy 75.951842 -403.67712) (xy 76.668122 -403.67712) (xy 76.678279 -403.677615) (xy 76.697045 -403.685393)
			(xy 76.711409 -403.699758) (xy 76.719186 -403.718525) (xy 76.719684 -403.728682) (xy 76.719684 -403.88667)
			(xy 76.720112 -403.895855) (xy 76.726614 -403.91304) (xy 76.732384 -403.920198) (xy 76.754193 -403.945833)
			(xy 76.792139 -404.001422) (xy 76.82317 -404.061148) (xy 76.846841 -404.124155) (xy 76.862812 -404.189539)
			(xy 76.870854 -404.256363) (xy 76.870852 -404.32367) (xy 76.862806 -404.390493) (xy 76.846831 -404.455877)
			(xy 76.823157 -404.518882) (xy 76.792122 -404.578606) (xy 76.754172 -404.634194) (xy 76.732384 -404.659846)
			(xy 76.726584 -404.666988) (xy 76.720072 -404.684181) (xy 76.719684 -404.693374) (xy 76.719684 -405.186642)
			(xy 76.720077 -405.195831) (xy 76.726603 -405.213015) (xy 76.732384 -405.22017) (xy 76.754165 -405.245827)
			(xy 76.792113 -405.301414) (xy 76.823145 -405.361137) (xy 76.846817 -405.42414) (xy 76.86279 -405.489522)
			(xy 76.870834 -405.556343) (xy 76.870835 -405.623648) (xy 76.862791 -405.690469) (xy 76.84682 -405.755851)
			(xy 76.823149 -405.818855) (xy 76.792117 -405.878579) (xy 76.754171 -405.934166) (xy 76.732384 -405.959818)
			(xy 76.726595 -405.966969) (xy 76.720077 -405.984155) (xy 76.719684 -405.993346) (xy 76.719684 -406.151334)
			(xy 76.719195 -406.161491) (xy 76.711414 -406.180257) (xy 76.697047 -406.19462) (xy 76.678279 -406.202397)
			(xy 76.668122 -406.202896) (xy 75.951842 -406.202896) (xy 75.941677 -406.202403) (xy 75.92289 -406.194638)
			(xy 75.908505 -406.180274) (xy 75.900712 -406.161498) (xy 75.90028 -406.151334) (xy 75.90028 -405.993346)
			(xy 75.899852 -405.984161) (xy 75.893351 -405.966976) (xy 75.88758 -405.959818) (xy 75.865785 -405.934171)
			(xy 75.827834 -405.878585) (xy 75.796799 -405.818861) (xy 75.773124 -405.755856) (xy 75.757151 -405.690472)
			(xy 75.749106 -405.623649) (xy 74.620571 -405.623649) (xy 74.591974 -405.678682) (xy 74.554024 -405.734268)
			(xy 74.532236 -405.75992) (xy 74.526441 -405.767066) (xy 74.519927 -405.784256) (xy 74.519536 -405.793448)
			(xy 74.519536 -406.286716) (xy 74.519953 -406.295902) (xy 74.526464 -406.313086) (xy 74.532236 -406.320244)
			(xy 74.553993 -406.345922) (xy 74.591944 -406.401504) (xy 74.62298 -406.461224) (xy 74.646656 -406.524225)
			(xy 74.662632 -406.589604) (xy 74.670679 -406.656424) (xy 74.670682 -406.723727) (xy 74.670675 -406.723789)
			(xy 77.94872 -406.723789) (xy 77.948723 -406.656363) (xy 77.956802 -406.589422) (xy 77.972842 -406.52393)
			(xy 77.996611 -406.460832) (xy 78.027767 -406.401035) (xy 78.065861 -406.345401) (xy 78.087728 -406.319736)
			(xy 78.093538 -406.3126) (xy 78.100044 -406.295402) (xy 78.100428 -406.286208) (xy 78.100428 -405.793956)
			(xy 78.100033 -405.784767) (xy 78.093508 -405.767584) (xy 78.087728 -405.760428) (xy 78.065859 -405.734766)
			(xy 78.027769 -405.679132) (xy 77.996617 -405.619336) (xy 77.972851 -405.556238) (xy 77.956815 -405.490748)
			(xy 77.948739 -405.423809) (xy 77.94874 -405.356385) (xy 77.956816 -405.289446) (xy 77.972853 -405.223956)
			(xy 77.996619 -405.160859) (xy 78.027772 -405.101063) (xy 78.065863 -405.045429) (xy 78.087728 -405.019764)
			(xy 78.093526 -405.01262) (xy 78.100039 -404.995428) (xy 78.100428 -404.986236) (xy 78.100428 -404.828756)
			(xy 78.10085 -404.818641) (xy 78.108607 -404.799956) (xy 78.122924 -404.785662) (xy 78.14162 -404.777934)
			(xy 78.151736 -404.777448) (xy 78.868016 -404.777448) (xy 78.878119 -404.777971) (xy 78.896788 -404.785704)
			(xy 78.91108 -404.799989) (xy 78.918823 -404.818653) (xy 78.919324 -404.828756) (xy 78.919324 -404.986236)
			(xy 78.919712 -404.995426) (xy 78.92624 -405.01261) (xy 78.932024 -405.019764) (xy 78.953883 -405.045433)
			(xy 78.99197 -405.101067) (xy 79.02312 -405.160863) (xy 79.046883 -405.22396) (xy 79.062918 -405.289448)
			(xy 79.070994 -405.356386) (xy 79.070995 -405.423808) (xy 79.062919 -405.490746) (xy 79.046885 -405.556235)
			(xy 79.023122 -405.619331) (xy 79.020843 -405.623707) (xy 80.148899 -405.623707) (xy 80.148899 -405.556284)
			(xy 80.156975 -405.489345) (xy 80.173011 -405.423856) (xy 80.196775 -405.360759) (xy 80.227925 -405.300963)
			(xy 80.266013 -405.245328) (xy 80.287876 -405.219662) (xy 80.293668 -405.212514) (xy 80.300186 -405.195326)
			(xy 80.300576 -405.186134) (xy 80.300576 -404.693882) (xy 80.30018 -404.684693) (xy 80.293657 -404.667509)
			(xy 80.287876 -404.660354) (xy 80.266034 -404.634671) (xy 80.227947 -404.579038) (xy 80.196796 -404.519244)
			(xy 80.173032 -404.45615) (xy 80.156996 -404.390663) (xy 80.148918 -404.323727) (xy 80.148917 -404.256306)
			(xy 80.15699 -404.189369) (xy 80.173022 -404.123882) (xy 80.196783 -404.060786) (xy 80.22793 -404.00099)
			(xy 80.266014 -403.945356) (xy 80.287876 -403.91969) (xy 80.293657 -403.912533) (xy 80.300182 -403.895352)
			(xy 80.300576 -403.886162) (xy 80.300576 -403.728682) (xy 80.301013 -403.71855) (xy 80.308753 -403.699821)
			(xy 80.323055 -403.685464) (xy 80.341754 -403.677652) (xy 80.351884 -403.67712) (xy 81.068164 -403.67712)
			(xy 81.078318 -403.677552) (xy 81.097074 -403.685339) (xy 81.111399 -403.699733) (xy 81.119096 -403.718526)
			(xy 81.119472 -403.728682) (xy 81.119472 -403.886162) (xy 81.119907 -403.895346) (xy 81.126404 -403.912531)
			(xy 81.132172 -403.91969) (xy 81.154059 -403.945337) (xy 81.192148 -404.000973) (xy 81.2233 -404.060772)
			(xy 81.247064 -404.123871) (xy 81.263099 -404.189363) (xy 81.271173 -404.256304) (xy 81.271171 -404.32373)
			(xy 81.263093 -404.39067) (xy 81.247054 -404.45616) (xy 81.223286 -404.519258) (xy 81.192131 -404.579055)
			(xy 81.154038 -404.634689) (xy 81.132172 -404.660354) (xy 81.126366 -404.667493) (xy 81.119858 -404.684688)
			(xy 81.119472 -404.693882) (xy 81.119472 -405.186134) (xy 81.119872 -405.195322) (xy 81.126393 -405.212506)
			(xy 81.132172 -405.219662) (xy 81.154031 -405.245332) (xy 81.192122 -405.300965) (xy 81.223274 -405.36076)
			(xy 81.24704 -405.423857) (xy 81.263077 -405.489345) (xy 81.271154 -405.556284) (xy 81.271154 -405.623707)
			(xy 81.263078 -405.690646) (xy 81.247043 -405.756135) (xy 81.223278 -405.819232) (xy 81.192126 -405.879027)
			(xy 81.154037 -405.934661) (xy 81.132172 -405.960326) (xy 81.126378 -405.967473) (xy 81.119862 -405.984662)
			(xy 81.119472 -405.993854) (xy 81.119472 -406.151334) (xy 81.119002 -406.161461) (xy 81.111265 -406.180181)
			(xy 81.096974 -406.194536) (xy 81.078289 -406.202356) (xy 81.068164 -406.202896) (xy 80.351884 -406.202896)
			(xy 80.341728 -406.202492) (xy 80.322975 -406.19469) (xy 80.308652 -406.180288) (xy 80.300953 -406.161492)
			(xy 80.300576 -406.151334) (xy 80.300576 -405.993854) (xy 80.300145 -405.984669) (xy 80.293646 -405.967484)
			(xy 80.287876 -405.960326) (xy 80.266007 -405.934665) (xy 80.22792 -405.879029) (xy 80.196771 -405.819232)
			(xy 80.173008 -405.756135) (xy 80.156974 -405.690646) (xy 80.148899 -405.623707) (xy 79.020843 -405.623707)
			(xy 78.991974 -405.679127) (xy 78.953887 -405.734762) (xy 78.932024 -405.760428) (xy 78.926236 -405.767579)
			(xy 78.919715 -405.784765) (xy 78.919324 -405.793956) (xy 78.919324 -406.286208) (xy 78.919725 -406.295396)
			(xy 78.926244 -406.312581) (xy 78.932024 -406.319736) (xy 78.953856 -406.345428) (xy 78.991944 -406.401059)
			(xy 79.023095 -406.460852) (xy 79.046859 -406.523945) (xy 79.062896 -406.589431) (xy 79.070974 -406.656366)
			(xy 79.070977 -406.72373) (xy 82.349039 -406.72373) (xy 82.349042 -406.656422) (xy 82.357089 -406.589598)
			(xy 82.373065 -406.524214) (xy 82.39674 -406.461209) (xy 82.427776 -406.401484) (xy 82.465727 -406.345896)
			(xy 82.487516 -406.320244) (xy 82.493321 -406.313105) (xy 82.49983 -406.29591) (xy 82.500216 -406.286716)
			(xy 82.500216 -405.793448) (xy 82.499779 -405.784264) (xy 82.493284 -405.767079) (xy 82.487516 -405.75992)
			(xy 82.465725 -405.734271) (xy 82.427778 -405.678683) (xy 82.396746 -405.618959) (xy 82.373074 -405.555954)
			(xy 82.357102 -405.490572) (xy 82.349059 -405.423749) (xy 82.349059 -405.356445) (xy 82.357103 -405.289622)
			(xy 82.373076 -405.22424) (xy 82.396748 -405.161235) (xy 82.427781 -405.101511) (xy 82.465729 -405.045924)
			(xy 82.487516 -405.020272) (xy 82.493309 -405.013124) (xy 82.499825 -404.995936) (xy 82.500216 -404.986744)
			(xy 82.500216 -404.828756) (xy 82.500586 -404.818597) (xy 82.508399 -404.799841) (xy 82.522811 -404.785518)
			(xy 82.541617 -404.777823) (xy 82.551778 -404.777448) (xy 83.268058 -404.777448) (xy 83.278183 -404.777961)
			(xy 83.296905 -404.785677) (xy 83.311263 -404.799955) (xy 83.319082 -404.818634) (xy 83.31962 -404.828756)
			(xy 83.31962 -404.986744) (xy 83.320004 -404.995934) (xy 83.326535 -405.013118) (xy 83.33232 -405.020272)
			(xy 83.354105 -405.045927) (xy 83.392057 -405.101512) (xy 83.423092 -405.161235) (xy 83.446767 -405.224239)
			(xy 83.462742 -405.289621) (xy 83.470787 -405.356444) (xy 83.470787 -405.42375) (xy 83.462743 -405.490573)
			(xy 83.446769 -405.555955) (xy 83.423095 -405.61896) (xy 83.420628 -405.623707) (xy 84.54869 -405.623707)
			(xy 84.54869 -405.556284) (xy 84.556766 -405.489346) (xy 84.572801 -405.423857) (xy 84.596564 -405.36076)
			(xy 84.627714 -405.300963) (xy 84.665801 -405.245328) (xy 84.687664 -405.219662) (xy 84.693467 -405.212522)
			(xy 84.699976 -405.195327) (xy 84.700364 -405.186134) (xy 84.700364 -404.693882) (xy 84.699948 -404.684696)
			(xy 84.693437 -404.667512) (xy 84.687664 -404.660354) (xy 84.665823 -404.63467) (xy 84.627736 -404.579038)
			(xy 84.596586 -404.519244) (xy 84.572822 -404.456149) (xy 84.556787 -404.390663) (xy 84.548709 -404.323727)
			(xy 84.548707 -404.256306) (xy 84.556781 -404.18937) (xy 84.572813 -404.123882) (xy 84.596573 -404.060787)
			(xy 84.627719 -404.000991) (xy 84.665803 -403.945356) (xy 84.687664 -403.91969) (xy 84.693455 -403.912541)
			(xy 84.699971 -403.895353) (xy 84.700364 -403.886162) (xy 84.700364 -403.728682) (xy 84.700812 -403.718551)
			(xy 84.70855 -403.699825) (xy 84.722849 -403.685468) (xy 84.741543 -403.677654) (xy 84.751672 -403.67712)
			(xy 85.467952 -403.67712) (xy 85.478105 -403.677561) (xy 85.496861 -403.685345) (xy 85.511186 -403.699736)
			(xy 85.518884 -403.718527) (xy 85.51926 -403.728682) (xy 85.51926 -403.886162) (xy 85.519698 -403.895346)
			(xy 85.526193 -403.91253) (xy 85.53196 -403.91969) (xy 85.553847 -403.945337) (xy 85.591938 -404.000973)
			(xy 85.62309 -404.060771) (xy 85.646854 -404.123871) (xy 85.66289 -404.189362) (xy 85.670964 -404.256303)
			(xy 85.670962 -404.32373) (xy 85.662884 -404.39067) (xy 85.646845 -404.456161) (xy 85.623076 -404.519259)
			(xy 85.591921 -404.579055) (xy 85.553827 -404.634689) (xy 85.53196 -404.660354) (xy 85.526153 -404.667492)
			(xy 85.519646 -404.684688) (xy 85.51926 -404.693882) (xy 85.51926 -405.186134) (xy 85.519663 -405.195322)
			(xy 85.526183 -405.212506) (xy 85.53196 -405.219662) (xy 85.553819 -405.245331) (xy 85.591911 -405.300964)
			(xy 85.623064 -405.36076) (xy 85.64683 -405.423856) (xy 85.662868 -405.489345) (xy 85.670945 -405.556284)
			(xy 85.670945 -405.623707) (xy 85.662869 -405.690646) (xy 85.646833 -405.756135) (xy 85.623068 -405.819232)
			(xy 85.591916 -405.879028) (xy 85.553825 -405.934661) (xy 85.53196 -405.960326) (xy 85.526165 -405.967472)
			(xy 85.51965 -405.984662) (xy 85.51926 -405.993854) (xy 85.51926 -406.151334) (xy 85.518801 -406.161463)
			(xy 85.511062 -406.180185) (xy 85.496768 -406.19454) (xy 85.478079 -406.202358) (xy 85.467952 -406.202896)
			(xy 84.751672 -406.202896) (xy 84.741516 -406.202501) (xy 84.722762 -406.194696) (xy 84.708439 -406.180291)
			(xy 84.700741 -406.161493) (xy 84.700364 -406.151334) (xy 84.700364 -405.993854) (xy 84.699914 -405.984671)
			(xy 84.693426 -405.967487) (xy 84.687664 -405.960326) (xy 84.665795 -405.934665) (xy 84.627709 -405.879029)
			(xy 84.596561 -405.819232) (xy 84.572799 -405.756135) (xy 84.556765 -405.690645) (xy 84.54869 -405.623707)
			(xy 83.420628 -405.623707) (xy 83.39206 -405.678683) (xy 83.354109 -405.734268) (xy 83.33232 -405.75992)
			(xy 83.326535 -405.767073) (xy 83.320013 -405.784258) (xy 83.31962 -405.793448) (xy 83.31962 -406.286716)
			(xy 83.320018 -406.295905) (xy 83.32654 -406.313089) (xy 83.33232 -406.320244) (xy 83.354077 -406.345921)
			(xy 83.39203 -406.401503) (xy 83.423067 -406.461223) (xy 83.446743 -406.524224) (xy 83.46272 -406.589604)
			(xy 83.470767 -406.656424) (xy 83.47077 -406.723728) (xy 83.470763 -406.723789) (xy 86.748808 -406.723789)
			(xy 86.748811 -406.656363) (xy 86.75689 -406.589422) (xy 86.772929 -406.523931) (xy 86.796697 -406.460833)
			(xy 86.827852 -406.401036) (xy 86.865946 -406.345401) (xy 86.887812 -406.319736) (xy 86.89362 -406.312599)
			(xy 86.900127 -406.295402) (xy 86.900512 -406.286208) (xy 86.900512 -405.793956) (xy 86.90012 -405.784767)
			(xy 86.893594 -405.767583) (xy 86.887812 -405.760428) (xy 86.865944 -405.734766) (xy 86.827854 -405.679131)
			(xy 86.796703 -405.619335) (xy 86.772939 -405.556238) (xy 86.756903 -405.490748) (xy 86.748827 -405.423809)
			(xy 86.748828 -405.356385) (xy 86.756904 -405.289446) (xy 86.77294 -405.223957) (xy 86.796706 -405.16086)
			(xy 86.827857 -405.101063) (xy 86.865947 -405.045429) (xy 86.887812 -405.019764) (xy 86.893608 -405.012618)
			(xy 86.900123 -404.995428) (xy 86.900512 -404.986236) (xy 86.900512 -404.828756) (xy 86.900949 -404.818643)
			(xy 86.908704 -404.799961) (xy 86.923015 -404.785668) (xy 86.941706 -404.777937) (xy 86.95182 -404.777448)
			(xy 87.6681 -404.777448) (xy 87.678202 -404.777984) (xy 87.696871 -404.785712) (xy 87.711163 -404.799993)
			(xy 87.718907 -404.818654) (xy 87.719408 -404.828756) (xy 87.719408 -404.986236) (xy 87.719799 -404.995425)
			(xy 87.726326 -405.01261) (xy 87.732108 -405.019764) (xy 87.753968 -405.045433) (xy 87.792056 -405.101067)
			(xy 87.823206 -405.160863) (xy 87.846971 -405.223959) (xy 87.863006 -405.289448) (xy 87.871082 -405.356385)
			(xy 87.871082 -405.423809) (xy 87.863007 -405.490746) (xy 87.846972 -405.556235) (xy 87.823209 -405.619332)
			(xy 87.792059 -405.679128) (xy 87.753971 -405.734763) (xy 87.732108 -405.760428) (xy 87.726318 -405.767578)
			(xy 87.719799 -405.784765) (xy 87.719408 -405.793956) (xy 87.719408 -406.286208) (xy 87.719813 -406.295396)
			(xy 87.72633 -406.31258) (xy 87.732108 -406.319736) (xy 87.75394 -406.345427) (xy 87.792029 -406.401058)
			(xy 87.823181 -406.460851) (xy 87.846947 -406.523944) (xy 87.862984 -406.58943) (xy 87.871062 -406.656365)
			(xy 87.871065 -406.723729) (xy 91.149127 -406.723729) (xy 91.14913 -406.656423) (xy 91.157177 -406.589598)
			(xy 91.173152 -406.524215) (xy 91.196827 -406.461209) (xy 91.227861 -406.401484) (xy 91.265812 -406.345897)
			(xy 91.2876 -406.320244) (xy 91.293403 -406.313103) (xy 91.299914 -406.295909) (xy 91.3003 -406.286716)
			(xy 91.3003 -405.793448) (xy 91.299867 -405.784263) (xy 91.293369 -405.767079) (xy 91.2876 -405.75992)
			(xy 91.26581 -405.734271) (xy 91.227863 -405.678683) (xy 91.196832 -405.618958) (xy 91.173162 -405.555954)
			(xy 91.15719 -405.490572) (xy 91.149147 -405.423749) (xy 91.149147 -405.356445) (xy 91.157191 -405.289622)
			(xy 91.173163 -405.224241) (xy 91.196835 -405.161236) (xy 91.227866 -405.101512) (xy 91.265813 -405.045925)
			(xy 91.2876 -405.020272) (xy 91.293391 -405.013123) (xy 91.299909 -404.995935) (xy 91.3003 -404.986744)
			(xy 91.3003 -404.828756) (xy 91.300686 -404.818599) (xy 91.308496 -404.799846) (xy 91.322903 -404.785524)
			(xy 91.341703 -404.777826) (xy 91.351862 -404.777448) (xy 92.068142 -404.777448) (xy 92.078272 -404.777892)
			(xy 92.096996 -404.785635) (xy 92.111351 -404.799934) (xy 92.119167 -404.818628) (xy 92.119704 -404.828756)
			(xy 92.119704 -404.986744) (xy 92.120092 -404.995934) (xy 92.126621 -405.013118) (xy 92.132404 -405.020272)
			(xy 92.154186 -405.045928) (xy 92.192133 -405.101515) (xy 92.223164 -405.161238) (xy 92.246835 -405.224242)
			(xy 92.262807 -405.289624) (xy 92.270851 -405.356445) (xy 92.270851 -405.423749) (xy 92.262808 -405.490571)
			(xy 92.246837 -405.555952) (xy 92.223166 -405.618956) (xy 92.220728 -405.623648) (xy 115.349248 -405.623648)
			(xy 115.349249 -405.556343) (xy 115.357293 -405.489521) (xy 115.373266 -405.424139) (xy 115.396938 -405.361134)
			(xy 115.42797 -405.30141) (xy 115.465917 -405.245823) (xy 115.487704 -405.22017) (xy 115.493496 -405.213022)
			(xy 115.500013 -405.195834) (xy 115.500404 -405.186642) (xy 115.500404 -404.693374) (xy 115.500006 -404.684186)
			(xy 115.493484 -404.667001) (xy 115.487704 -404.659846) (xy 115.465939 -404.634176) (xy 115.427992 -404.578591)
			(xy 115.396959 -404.51887) (xy 115.373287 -404.455868) (xy 115.357314 -404.390488) (xy 115.349268 -404.323668)
			(xy 115.349266 -404.256365) (xy 115.357308 -404.189545) (xy 115.373277 -404.124164) (xy 115.396946 -404.061161)
			(xy 115.427975 -404.001437) (xy 115.465919 -403.945851) (xy 115.487704 -403.920198) (xy 115.493484 -403.913041)
			(xy 115.500009 -403.89586) (xy 115.500404 -403.88667) (xy 115.500404 -403.728682) (xy 115.500918 -403.718527)
			(xy 115.508692 -403.699764) (xy 115.523051 -403.685401) (xy 115.541811 -403.677621) (xy 115.551966 -403.67712)
			(xy 116.268246 -403.67712) (xy 116.278404 -403.677595) (xy 116.297171 -403.685382) (xy 116.311534 -403.699752)
			(xy 116.31931 -403.718523) (xy 116.319808 -403.728682) (xy 116.319808 -403.88667) (xy 116.320231 -403.895856)
			(xy 116.326735 -403.91304) (xy 116.332508 -403.920198) (xy 116.354319 -403.945832) (xy 116.392271 -404.00142)
			(xy 116.423306 -404.061145) (xy 116.44698 -404.124152) (xy 116.462953 -404.189537) (xy 116.470996 -404.256363)
			(xy 116.470994 -404.32367) (xy 116.462947 -404.390495) (xy 116.44697 -404.455879) (xy 116.423292 -404.518885)
			(xy 116.392254 -404.578609) (xy 116.354299 -404.634195) (xy 116.332508 -404.659846) (xy 116.32671 -404.66699)
			(xy 116.320196 -404.684181) (xy 116.319808 -404.693374) (xy 116.319808 -405.186642) (xy 116.320196 -405.195832)
			(xy 116.326725 -405.213016) (xy 116.332508 -405.22017) (xy 116.354291 -405.245826) (xy 116.392244 -405.301411)
			(xy 116.42328 -405.361133) (xy 116.446956 -405.424137) (xy 116.462931 -405.48952) (xy 116.470976 -405.556343)
			(xy 116.470977 -405.623648) (xy 116.462932 -405.690471) (xy 116.446958 -405.755854) (xy 116.423284 -405.818858)
			(xy 116.392249 -405.878581) (xy 116.354297 -405.934167) (xy 116.332508 -405.959818) (xy 116.326722 -405.966971)
			(xy 116.320201 -405.984155) (xy 116.319808 -405.993346) (xy 116.319808 -406.151334) (xy 116.319296 -406.161488)
			(xy 116.311519 -406.180249) (xy 116.297159 -406.194612) (xy 116.2784 -406.202393) (xy 116.268246 -406.202896)
			(xy 115.551966 -406.202896) (xy 115.54181 -406.202395) (xy 115.523047 -406.194616) (xy 115.508684 -406.180253)
			(xy 115.500905 -406.16149) (xy 115.500404 -406.151334) (xy 115.500404 -405.993346) (xy 115.499971 -405.984161)
			(xy 115.493473 -405.966977) (xy 115.487704 -405.959818) (xy 115.465911 -405.93417) (xy 115.427965 -405.878582)
			(xy 115.396934 -405.818858) (xy 115.373263 -405.755853) (xy 115.357292 -405.69047) (xy 115.349248 -405.623648)
			(xy 92.220728 -405.623648) (xy 92.192136 -405.67868) (xy 92.15419 -405.734267) (xy 92.132404 -405.75992)
			(xy 92.126617 -405.767072) (xy 92.120096 -405.784257) (xy 92.119704 -405.793448) (xy 92.119704 -406.286716)
			(xy 92.120106 -406.295904) (xy 92.126625 -406.313088) (xy 92.132404 -406.320244) (xy 92.154159 -406.345923)
			(xy 92.192106 -406.401506) (xy 92.223138 -406.461227) (xy 92.246811 -406.524228) (xy 92.262785 -406.589606)
			(xy 92.270831 -406.656425) (xy 92.270834 -406.723727) (xy 92.270826 -406.72379) (xy 117.548838 -406.72379)
			(xy 117.548841 -406.656362) (xy 117.55692 -406.589421) (xy 117.572961 -406.523929) (xy 117.596731 -406.460831)
			(xy 117.627888 -406.401034) (xy 117.665984 -406.3454) (xy 117.687852 -406.319736) (xy 117.693665 -406.312602)
			(xy 117.700168 -406.295403) (xy 117.700552 -406.286208) (xy 117.700552 -405.793956) (xy 117.700151 -405.784768)
			(xy 117.69363 -405.767585) (xy 117.687852 -405.760428) (xy 117.665982 -405.734767) (xy 117.62789 -405.679133)
			(xy 117.596737 -405.619337) (xy 117.572971 -405.556239) (xy 117.556934 -405.490749) (xy 117.548857 -405.42381)
			(xy 117.548858 -405.356384) (xy 117.556935 -405.289445) (xy 117.572972 -405.223955) (xy 117.596739 -405.160858)
			(xy 117.627893 -405.101062) (xy 117.665986 -405.045428) (xy 117.687852 -405.019764) (xy 117.693653 -405.012622)
			(xy 117.700164 -404.995429) (xy 117.700552 -404.986236) (xy 117.700552 -404.828756) (xy 117.701048 -404.81865)
			(xy 117.708791 -404.79998) (xy 117.723084 -404.785689) (xy 117.741754 -404.777947) (xy 117.75186 -404.777448)
			(xy 118.46814 -404.777448) (xy 118.478245 -404.777951) (xy 118.496914 -404.785692) (xy 118.511206 -404.799983)
			(xy 118.518948 -404.818651) (xy 118.519448 -404.828756) (xy 118.519448 -404.986236) (xy 118.519853 -404.995424)
			(xy 118.526372 -405.012607) (xy 118.532148 -405.019764) (xy 118.55401 -405.045432) (xy 118.592102 -405.101065)
			(xy 118.623256 -405.16086) (xy 118.647023 -405.223957) (xy 118.66306 -405.289446) (xy 118.671137 -405.356385)
			(xy 118.671137 -405.423809) (xy 118.663061 -405.490748) (xy 118.647024 -405.556238) (xy 118.623258 -405.619335)
			(xy 118.62098 -405.623708) (xy 119.749017 -405.623708) (xy 119.749017 -405.556283) (xy 119.757094 -405.489345)
			(xy 119.77313 -405.423855) (xy 119.796895 -405.360758) (xy 119.828046 -405.300962) (xy 119.866136 -405.245327)
			(xy 119.888 -405.219662) (xy 119.893795 -405.212516) (xy 119.900311 -405.195326) (xy 119.9007 -405.186134)
			(xy 119.9007 -404.693882) (xy 119.900298 -404.684694) (xy 119.893779 -404.66751) (xy 119.888 -404.660354)
			(xy 119.866158 -404.634671) (xy 119.828068 -404.579039) (xy 119.796917 -404.519245) (xy 119.773151 -404.456151)
			(xy 119.757114 -404.390664) (xy 119.749037 -404.323727) (xy 119.749035 -404.256306) (xy 119.757108 -404.189369)
			(xy 119.773141 -404.123881) (xy 119.796903 -404.060785) (xy 119.828051 -404.000989) (xy 119.866137 -403.945355)
			(xy 119.888 -403.91969) (xy 119.893783 -403.912535) (xy 119.900306 -403.895352) (xy 119.9007 -403.886162)
			(xy 119.9007 -403.728682) (xy 119.90121 -403.718559) (xy 119.908937 -403.699845) (xy 119.923215 -403.685491)
			(xy 119.941888 -403.677665) (xy 119.952008 -403.67712) (xy 120.668288 -403.67712) (xy 120.678412 -403.677526)
			(xy 120.697119 -403.685274) (xy 120.711435 -403.699594) (xy 120.719177 -403.718304) (xy 120.719596 -403.728428)
			(xy 120.719596 -403.886162) (xy 120.720025 -403.895347) (xy 120.726526 -403.912532) (xy 120.732296 -403.91969)
			(xy 120.754182 -403.945337) (xy 120.79227 -404.000974) (xy 120.82342 -404.060773) (xy 120.847183 -404.123872)
			(xy 120.863217 -404.189363) (xy 120.871291 -404.256304) (xy 120.871289 -404.323729) (xy 120.863211 -404.390669)
			(xy 120.847173 -404.456159) (xy 120.823407 -404.519257) (xy 120.792253 -404.579054) (xy 120.754161 -404.634689)
			(xy 120.732296 -404.660354) (xy 120.726494 -404.667495) (xy 120.719983 -404.684689) (xy 120.719596 -404.693882)
			(xy 120.719596 -405.186134) (xy 120.719991 -405.195323) (xy 120.726515 -405.212507) (xy 120.732296 -405.219662)
			(xy 120.754154 -405.245332) (xy 120.792243 -405.300966) (xy 120.823395 -405.360761) (xy 120.847159 -405.423858)
			(xy 120.863195 -405.489346) (xy 120.871272 -405.556284) (xy 120.871272 -405.623707) (xy 120.863197 -405.690645)
			(xy 120.847162 -405.756134) (xy 120.823398 -405.81923) (xy 120.792248 -405.879026) (xy 120.75416 -405.934661)
			(xy 120.732296 -405.960326) (xy 120.726505 -405.967475) (xy 120.719987 -405.984663) (xy 120.719596 -405.993854)
			(xy 120.719596 -406.151334) (xy 120.719102 -406.161458) (xy 120.71137 -406.180174) (xy 120.697087 -406.194527)
			(xy 120.67841 -406.202352) (xy 120.668288 -406.202896) (xy 119.952008 -406.202896) (xy 119.941886 -406.202477)
			(xy 119.923181 -406.194731) (xy 119.908867 -406.180415) (xy 119.901122 -406.16171) (xy 119.9007 -406.151588)
			(xy 119.9007 -405.993854) (xy 119.900264 -405.98467) (xy 119.893768 -405.967485) (xy 119.888 -405.960326)
			(xy 119.86613 -405.934666) (xy 119.828042 -405.87903) (xy 119.796891 -405.819234) (xy 119.773127 -405.756136)
			(xy 119.757092 -405.690646) (xy 119.749017 -405.623708) (xy 118.62098 -405.623708) (xy 118.592105 -405.67913)
			(xy 118.554014 -405.734764) (xy 118.532148 -405.760428) (xy 118.526351 -405.767572) (xy 118.519838 -405.784764)
			(xy 118.519448 -405.793956) (xy 118.519448 -406.286208) (xy 118.519866 -406.295394) (xy 118.526375 -406.312578)
			(xy 118.532148 -406.319736) (xy 118.553982 -406.345426) (xy 118.592075 -406.401056) (xy 118.62323 -406.460848)
			(xy 118.646999 -406.523942) (xy 118.663038 -406.589429) (xy 118.671117 -406.656365) (xy 118.67112 -406.72373)
			(xy 121.949157 -406.72373) (xy 121.94916 -406.656422) (xy 121.957208 -406.589597) (xy 121.973184 -406.524213)
			(xy 121.99686 -406.461207) (xy 122.027897 -406.401483) (xy 122.06585 -406.345896) (xy 122.08764 -406.320244)
			(xy 122.093448 -406.313107) (xy 122.099955 -406.29591) (xy 122.10034 -406.286716) (xy 122.10034 -405.793448)
			(xy 122.099898 -405.784264) (xy 122.093405 -405.76708) (xy 122.08764 -405.75992) (xy 122.065848 -405.734271)
			(xy 122.027899 -405.678684) (xy 121.996866 -405.61896) (xy 121.973194 -405.555955) (xy 121.957221 -405.490573)
			(xy 121.949177 -405.42375) (xy 121.949177 -405.356444) (xy 121.957222 -405.289621) (xy 121.973195 -405.224239)
			(xy 121.996869 -405.161234) (xy 122.027902 -405.101511) (xy 122.065852 -405.045924) (xy 122.08764 -405.020272)
			(xy 122.093436 -405.013127) (xy 122.09995 -404.995936) (xy 122.10034 -404.986744) (xy 122.10034 -404.828756)
			(xy 122.100681 -404.818626) (xy 122.108451 -404.799913) (xy 122.122791 -404.785599) (xy 122.141517 -404.777863)
			(xy 122.151648 -404.777448) (xy 122.868182 -404.777448) (xy 122.878309 -404.777941) (xy 122.897031 -404.785665)
			(xy 122.911388 -404.799949) (xy 122.919207 -404.818632) (xy 122.919744 -404.828756) (xy 122.919744 -404.986744)
			(xy 122.920145 -404.995932) (xy 122.926666 -405.013116) (xy 122.932444 -405.020272) (xy 122.954228 -405.045927)
			(xy 122.992178 -405.101513) (xy 123.023213 -405.161236) (xy 123.046886 -405.22424) (xy 123.06286 -405.289622)
			(xy 123.070905 -405.356444) (xy 123.070905 -405.42375) (xy 123.062861 -405.490572) (xy 123.046888 -405.555954)
			(xy 123.023215 -405.618959) (xy 123.020778 -405.623649) (xy 124.149312 -405.623649) (xy 124.149313 -405.556342)
			(xy 124.157358 -405.489518) (xy 124.173333 -405.424135) (xy 124.197009 -405.36113) (xy 124.228046 -405.301407)
			(xy 124.265998 -405.245822) (xy 124.287788 -405.22017) (xy 124.293578 -405.21302) (xy 124.300097 -405.195833)
			(xy 124.300488 -405.186642) (xy 124.300488 -404.693374) (xy 124.300093 -404.684185) (xy 124.293569 -404.667001)
			(xy 124.287788 -404.659846) (xy 124.26602 -404.634177) (xy 124.228068 -404.578594) (xy 124.197031 -404.518873)
			(xy 124.173355 -404.455871) (xy 124.157379 -404.39049) (xy 124.149332 -404.323669) (xy 124.14933 -404.256364)
			(xy 124.157373 -404.189542) (xy 124.173345 -404.124161) (xy 124.197017 -404.061157) (xy 124.228051 -404.001435)
			(xy 124.266 -403.945849) (xy 124.287788 -403.920198) (xy 124.293567 -403.91304) (xy 124.300092 -403.895859)
			(xy 124.300488 -403.88667) (xy 124.300488 -403.728682) (xy 124.30085 -403.718503) (xy 124.308651 -403.699698)
			(xy 124.323056 -403.685313) (xy 124.34187 -403.677537) (xy 124.35205 -403.67712) (xy 125.06833 -403.67712)
			(xy 125.078487 -403.677608) (xy 125.097254 -403.685389) (xy 125.111617 -403.699756) (xy 125.119394 -403.718524)
			(xy 125.119892 -403.728682) (xy 125.119892 -403.88667) (xy 125.120318 -403.895855) (xy 125.126821 -403.91304)
			(xy 125.132592 -403.920198) (xy 125.1544 -403.945833) (xy 125.192347 -404.001422) (xy 125.223377 -404.061149)
			(xy 125.247047 -404.124155) (xy 125.263018 -404.189539) (xy 125.27106 -404.256363) (xy 125.271058 -404.32367)
			(xy 125.263012 -404.390493) (xy 125.247038 -404.455876) (xy 125.223364 -404.518882) (xy 125.19233 -404.578606)
			(xy 125.15438 -404.634193) (xy 125.132592 -404.659846) (xy 125.126792 -404.666989) (xy 125.12028 -404.684181)
			(xy 125.119892 -404.693374) (xy 125.119892 -405.186642) (xy 125.120284 -405.195831) (xy 125.12681 -405.213015)
			(xy 125.132592 -405.22017) (xy 125.154373 -405.245827) (xy 125.19232 -405.301414) (xy 125.223352 -405.361137)
			(xy 125.247023 -405.424141) (xy 125.262996 -405.489522) (xy 125.27104 -405.556343) (xy 125.271041 -405.623647)
			(xy 125.262998 -405.690469) (xy 125.247026 -405.755851) (xy 125.223355 -405.818855) (xy 125.192325 -405.878578)
			(xy 125.154378 -405.934165) (xy 125.132592 -405.959818) (xy 125.126804 -405.96697) (xy 125.120285 -405.984155)
			(xy 125.119892 -405.993346) (xy 125.119892 -406.151334) (xy 125.119395 -406.16149) (xy 125.111615 -406.180254)
			(xy 125.097251 -406.194617) (xy 125.078486 -406.202396) (xy 125.06833 -406.202896) (xy 124.35205 -406.202896)
			(xy 124.341886 -406.202396) (xy 124.323099 -406.194634) (xy 124.308713 -406.180272) (xy 124.30092 -406.161497)
			(xy 124.300488 -406.151334) (xy 124.300488 -405.993346) (xy 124.300059 -405.984161) (xy 124.293559 -405.966976)
			(xy 124.287788 -405.959818) (xy 124.265993 -405.934171) (xy 124.228041 -405.878585) (xy 124.197005 -405.818861)
			(xy 124.173331 -405.755856) (xy 124.157357 -405.690473) (xy 124.149312 -405.623649) (xy 123.020778 -405.623649)
			(xy 122.992181 -405.678682) (xy 122.954232 -405.734268) (xy 122.932444 -405.75992) (xy 122.92665 -405.767066)
			(xy 122.920135 -405.784256) (xy 122.919744 -405.793448) (xy 122.919744 -406.286716) (xy 122.920159 -406.295902)
			(xy 122.926671 -406.313086) (xy 122.932444 -406.320244) (xy 122.954201 -406.345922) (xy 122.992152 -406.401504)
			(xy 123.023187 -406.461224) (xy 123.046862 -406.524225) (xy 123.062838 -406.589605) (xy 123.070885 -406.656425)
			(xy 123.070888 -406.723727) (xy 123.070881 -406.723789) (xy 126.348926 -406.723789) (xy 126.348929 -406.656363)
			(xy 126.357008 -406.589421) (xy 126.373048 -406.52393) (xy 126.396818 -406.460832) (xy 126.427974 -406.401035)
			(xy 126.466069 -406.345401) (xy 126.487936 -406.319736) (xy 126.493747 -406.312601) (xy 126.500252 -406.295403)
			(xy 126.500636 -406.286208) (xy 126.500636 -405.793956) (xy 126.500239 -405.784768) (xy 126.493715 -405.767584)
			(xy 126.487936 -405.760428) (xy 126.466067 -405.734767) (xy 126.427976 -405.679132) (xy 126.396823 -405.619336)
			(xy 126.373058 -405.556239) (xy 126.357022 -405.490749) (xy 126.348945 -405.423809) (xy 126.348946 -405.356385)
			(xy 126.357023 -405.289445) (xy 126.37306 -405.223956) (xy 126.396826 -405.160859) (xy 126.427979 -405.101062)
			(xy 126.466071 -405.045429) (xy 126.487936 -405.019764) (xy 126.493735 -405.012621) (xy 126.500247 -404.995429)
			(xy 126.500636 -404.986236) (xy 126.500636 -404.828756) (xy 126.50105 -404.81864) (xy 126.508809 -404.799954)
			(xy 126.523128 -404.785659) (xy 126.541827 -404.777933) (xy 126.551944 -404.777448) (xy 127.268224 -404.777448)
			(xy 127.278328 -404.777964) (xy 127.296997 -404.7857) (xy 127.311289 -404.799986) (xy 127.319032 -404.818652)
			(xy 127.319532 -404.828756) (xy 127.319532 -404.986236) (xy 127.31994 -404.995423) (xy 127.326457 -405.012607)
			(xy 127.332232 -405.019764) (xy 127.354091 -405.045433) (xy 127.392178 -405.101068) (xy 127.423327 -405.160864)
			(xy 127.44709 -405.22396) (xy 127.463125 -405.289448) (xy 127.4712 -405.356386) (xy 127.471201 -405.423808)
			(xy 127.463126 -405.490746) (xy 127.447092 -405.556234) (xy 127.423329 -405.619331) (xy 127.42108 -405.623649)
			(xy 128.549103 -405.623649) (xy 128.549104 -405.556342) (xy 128.557149 -405.489519) (xy 128.573124 -405.424136)
			(xy 128.596799 -405.361131) (xy 128.627835 -405.301407) (xy 128.665787 -405.245822) (xy 128.687576 -405.22017)
			(xy 128.693365 -405.213019) (xy 128.699885 -405.195833) (xy 128.700276 -405.186642) (xy 128.700276 -404.693374)
			(xy 128.699884 -404.684185) (xy 128.693358 -404.667) (xy 128.687576 -404.659846) (xy 128.665809 -404.634177)
			(xy 128.627857 -404.578593) (xy 128.596821 -404.518873) (xy 128.573145 -404.45587) (xy 128.557169 -404.39049)
			(xy 128.549123 -404.323669) (xy 128.549121 -404.256365) (xy 128.557164 -404.189543) (xy 128.573135 -404.124161)
			(xy 128.596807 -404.061158) (xy 128.62784 -404.001435) (xy 128.665789 -403.94585) (xy 128.687576 -403.920198)
			(xy 128.693353 -403.913039) (xy 128.69988 -403.895859) (xy 128.700276 -403.88667) (xy 128.700276 -403.728682)
			(xy 128.70065 -403.718505) (xy 128.708448 -403.699702) (xy 128.722849 -403.685317) (xy 128.74166 -403.677539)
			(xy 128.751838 -403.67712) (xy 129.468118 -403.67712) (xy 129.478275 -403.677618) (xy 129.497041 -403.685395)
			(xy 129.511405 -403.699759) (xy 129.519182 -403.718525) (xy 129.51968 -403.728682) (xy 129.51968 -403.88667)
			(xy 129.520109 -403.895855) (xy 129.52661 -403.913039) (xy 129.53238 -403.920198) (xy 129.554189 -403.945833)
			(xy 129.592136 -404.001422) (xy 129.623167 -404.061148) (xy 129.646838 -404.124155) (xy 129.662809 -404.189539)
			(xy 129.670851 -404.256363) (xy 129.670849 -404.32367) (xy 129.662803 -404.390494) (xy 129.646828 -404.455877)
			(xy 129.623154 -404.518882) (xy 129.592119 -404.578606) (xy 129.554169 -404.634194) (xy 129.53238 -404.659846)
			(xy 129.526579 -404.666988) (xy 129.520068 -404.684181) (xy 129.51968 -404.693374) (xy 129.51968 -405.186642)
			(xy 129.520074 -405.195831) (xy 129.5266 -405.213015) (xy 129.53238 -405.22017) (xy 129.554161 -405.245827)
			(xy 129.592109 -405.301413) (xy 129.623142 -405.361136) (xy 129.646814 -405.42414) (xy 129.662787 -405.489522)
			(xy 129.670831 -405.556343) (xy 129.670832 -405.623648) (xy 129.662788 -405.690469) (xy 129.646817 -405.755851)
			(xy 129.623145 -405.818855) (xy 129.592114 -405.878579) (xy 129.554167 -405.934166) (xy 129.53238 -405.959818)
			(xy 129.526591 -405.966968) (xy 129.520072 -405.984155) (xy 129.51968 -405.993346) (xy 129.51968 -406.151334)
			(xy 129.519195 -406.161492) (xy 129.511413 -406.180258) (xy 129.497045 -406.194622) (xy 129.478276 -406.202398)
			(xy 129.468118 -406.202896) (xy 128.751838 -406.202896) (xy 128.741673 -406.202406) (xy 128.722886 -406.19464)
			(xy 128.708501 -406.180275) (xy 128.700708 -406.161498) (xy 128.700276 -406.151334) (xy 128.700276 -405.993346)
			(xy 128.699849 -405.984161) (xy 128.693347 -405.966976) (xy 128.687576 -405.959818) (xy 128.665781 -405.934171)
			(xy 128.62783 -405.878585) (xy 128.596795 -405.818861) (xy 128.573121 -405.755856) (xy 128.557148 -405.690472)
			(xy 128.549103 -405.623649) (xy 127.42108 -405.623649) (xy 127.392181 -405.679127) (xy 127.354095 -405.734762)
			(xy 127.332232 -405.760428) (xy 127.326433 -405.767571) (xy 127.319922 -405.784763) (xy 127.319532 -405.793956)
			(xy 127.319532 -406.286208) (xy 127.319954 -406.295394) (xy 127.326461 -406.312577) (xy 127.332232 -406.319736)
			(xy 127.354063 -406.345428) (xy 127.392151 -406.401059) (xy 127.423301 -406.460852) (xy 127.447066 -406.523945)
			(xy 127.463103 -406.589431) (xy 127.471181 -406.656366) (xy 127.471183 -406.72373) (xy 130.749245 -406.72373)
			(xy 130.749248 -406.656422) (xy 130.757295 -406.589598) (xy 130.773271 -406.524214) (xy 130.796947 -406.461208)
			(xy 130.827983 -406.401484) (xy 130.865935 -406.345896) (xy 130.887724 -406.320244) (xy 130.89353 -406.313105)
			(xy 130.900038 -406.29591) (xy 130.900424 -406.286716) (xy 130.900424 -405.793448) (xy 130.899985 -405.784264)
			(xy 130.893491 -405.76708) (xy 130.887724 -405.75992) (xy 130.865933 -405.734271) (xy 130.827985 -405.678684)
			(xy 130.796953 -405.61896) (xy 130.773281 -405.555955) (xy 130.757309 -405.490572) (xy 130.749265 -405.42375)
			(xy 130.749265 -405.356444) (xy 130.75731 -405.289622) (xy 130.773283 -405.22424) (xy 130.796955 -405.161235)
			(xy 130.827988 -405.101511) (xy 130.865936 -405.045924) (xy 130.887724 -405.020272) (xy 130.893518 -405.013125)
			(xy 130.900033 -404.995936) (xy 130.900424 -404.986744) (xy 130.900424 -404.828756) (xy 130.900786 -404.818596)
			(xy 130.908601 -404.799838) (xy 130.923016 -404.785515) (xy 130.941823 -404.777822) (xy 130.951986 -404.777448)
			(xy 131.668266 -404.777448) (xy 131.678391 -404.777955) (xy 131.697113 -404.785673) (xy 131.711471 -404.799953)
			(xy 131.71929 -404.818633) (xy 131.719828 -404.828756) (xy 131.719828 -404.986744) (xy 131.720211 -404.995934)
			(xy 131.726743 -405.013119) (xy 131.732528 -405.020272) (xy 131.754313 -405.045927) (xy 131.792264 -405.101512)
			(xy 131.823299 -405.161235) (xy 131.846974 -405.224239) (xy 131.862948 -405.289622) (xy 131.870993 -405.356444)
			(xy 131.870993 -405.42375) (xy 131.862949 -405.490573) (xy 131.846975 -405.555955) (xy 131.823302 -405.618959)
			(xy 131.792267 -405.678683) (xy 131.754316 -405.734268) (xy 131.732528 -405.75992) (xy 131.726732 -405.767065)
			(xy 131.720219 -405.784256) (xy 131.719828 -405.793448) (xy 131.719828 -406.286716) (xy 131.720224 -406.295905)
			(xy 131.726747 -406.313089) (xy 131.732528 -406.320244) (xy 131.754285 -406.345922) (xy 131.792237 -406.401504)
			(xy 131.823274 -406.461223) (xy 131.84695 -406.524225) (xy 131.862926 -406.589604) (xy 131.870973 -406.656424)
			(xy 131.870976 -406.723728) (xy 131.862934 -406.790548) (xy 131.846964 -406.855929) (xy 131.823293 -406.918933)
			(xy 131.792262 -406.978655) (xy 131.754315 -407.03424) (xy 131.732528 -407.059892) (xy 131.726744 -407.067045)
			(xy 131.720224 -407.08423) (xy 131.719828 -407.09342) (xy 131.719828 -407.251408) (xy 131.719385 -407.261559)
			(xy 131.711592 -407.280306) (xy 131.697203 -407.294628) (xy 131.678419 -407.302333) (xy 131.668266 -407.302716)
			(xy 130.951986 -407.302716) (xy 130.941853 -407.302283) (xy 130.923123 -407.294543) (xy 130.908766 -407.28024)
			(xy 130.900955 -407.261539) (xy 130.900424 -407.251408) (xy 130.900424 -407.09342) (xy 130.899999 -407.084235)
			(xy 130.893495 -407.06705) (xy 130.887724 -407.059892) (xy 130.865905 -407.034266) (xy 130.827958 -406.978675)
			(xy 130.796927 -406.918948) (xy 130.773257 -406.85594) (xy 130.757287 -406.790555) (xy 130.749245 -406.72373)
			(xy 127.471183 -406.72373) (xy 127.471183 -406.723786) (xy 127.463111 -406.790722) (xy 127.44708 -406.856209)
			(xy 127.423321 -406.919304) (xy 127.392176 -406.9791) (xy 127.354093 -407.034734) (xy 127.332232 -407.0604)
			(xy 127.326445 -407.067551) (xy 127.319926 -407.084737) (xy 127.319532 -407.093928) (xy 127.319532 -407.251408)
			(xy 127.319022 -407.261513) (xy 127.311288 -407.280185) (xy 127.296999 -407.294479) (xy 127.278329 -407.302219)
			(xy 127.268224 -407.302716) (xy 126.551944 -407.302716) (xy 126.541826 -407.302248) (xy 126.523127 -407.294518)
			(xy 126.508812 -407.280217) (xy 126.501062 -407.261525) (xy 126.500636 -407.251408) (xy 126.500636 -407.093928)
			(xy 126.500204 -407.084743) (xy 126.493705 -407.067559) (xy 126.487936 -407.0604) (xy 126.466039 -407.034761)
			(xy 126.427949 -406.979124) (xy 126.396798 -406.919324) (xy 126.373034 -406.856224) (xy 126.357 -406.790731)
			(xy 126.348926 -406.723789) (xy 123.070881 -406.723789) (xy 123.062847 -406.790548) (xy 123.046877 -406.855929)
			(xy 123.023207 -406.918932) (xy 122.992176 -406.978654) (xy 122.95423 -407.03424) (xy 122.932444 -407.059892)
			(xy 122.926661 -407.067047) (xy 122.92014 -407.08423) (xy 122.919744 -407.09342) (xy 122.919744 -407.251408)
			(xy 122.919222 -407.261512) (xy 122.91149 -407.280182) (xy 122.897205 -407.294475) (xy 122.878539 -407.302217)
			(xy 122.868436 -407.302716) (xy 122.151902 -407.302716) (xy 122.14177 -407.30227) (xy 122.123041 -407.294535)
			(xy 122.108683 -407.280236) (xy 122.100871 -407.261538) (xy 122.10034 -407.251408) (xy 122.10034 -407.09342)
			(xy 122.099911 -407.084235) (xy 122.09341 -407.067051) (xy 122.08764 -407.059892) (xy 122.065821 -407.034266)
			(xy 122.027873 -406.978676) (xy 121.996841 -406.918949) (xy 121.97317 -406.855941) (xy 121.957199 -406.790555)
			(xy 121.949157 -406.72373) (xy 118.67112 -406.72373) (xy 118.67112 -406.723787) (xy 118.663047 -406.790724)
			(xy 118.647013 -406.856212) (xy 118.62325 -406.919308) (xy 118.5921 -406.979103) (xy 118.554012 -407.034736)
			(xy 118.532148 -407.0604) (xy 118.526362 -407.067553) (xy 118.519843 -407.084738) (xy 118.519448 -407.093928)
			(xy 118.519448 -407.251408) (xy 118.518922 -407.261511) (xy 118.511191 -407.28018) (xy 118.496907 -407.294473)
			(xy 118.478243 -407.302216) (xy 118.46814 -407.302716) (xy 117.75186 -407.302716) (xy 117.741751 -407.302248)
			(xy 117.723075 -407.2945) (xy 117.708782 -407.280198) (xy 117.701046 -407.261518) (xy 117.700552 -407.251408)
			(xy 117.700552 -407.093928) (xy 117.700117 -407.084744) (xy 117.693619 -407.06756) (xy 117.687852 -407.0604)
			(xy 117.665955 -407.034762) (xy 117.627864 -406.979124) (xy 117.596711 -406.919325) (xy 117.572947 -406.856225)
			(xy 117.556912 -406.790732) (xy 117.548838 -406.72379) (xy 92.270826 -406.72379) (xy 92.262793 -406.790546)
			(xy 92.246825 -406.855926) (xy 92.223158 -406.918929) (xy 92.192131 -406.978652) (xy 92.154188 -407.034239)
			(xy 92.132404 -407.059892) (xy 92.126629 -407.067052) (xy 92.120101 -407.084231) (xy 92.119704 -407.09342)
			(xy 92.119704 -407.251408) (xy 92.119285 -407.261562) (xy 92.111487 -407.280314) (xy 92.09709 -407.294637)
			(xy 92.078298 -407.302337) (xy 92.068142 -407.302716) (xy 91.351862 -407.302716) (xy 91.341727 -407.302303)
			(xy 91.322997 -407.294555) (xy 91.308641 -407.280246) (xy 91.30083 -407.261541) (xy 91.3003 -407.251408)
			(xy 91.3003 -407.09342) (xy 91.29988 -407.084234) (xy 91.293373 -407.067049) (xy 91.2876 -407.059892)
			(xy 91.265782 -407.034265) (xy 91.227837 -406.978674) (xy 91.196807 -406.918947) (xy 91.173138 -406.855939)
			(xy 91.157168 -406.790554) (xy 91.149127 -406.723729) (xy 87.871065 -406.723729) (xy 87.871065 -406.723786)
			(xy 87.862993 -406.790722) (xy 87.846961 -406.85621) (xy 87.823201 -406.919305) (xy 87.792054 -406.9791)
			(xy 87.75397 -407.034735) (xy 87.732108 -407.0604) (xy 87.72633 -407.067558) (xy 87.719804 -407.084739)
			(xy 87.719408 -407.093928) (xy 87.719408 -407.251408) (xy 87.718921 -407.261516) (xy 87.711183 -407.280193)
			(xy 87.696886 -407.294487) (xy 87.678208 -407.302223) (xy 87.6681 -407.302716) (xy 86.95182 -407.302716)
			(xy 86.941701 -407.302268) (xy 86.923001 -407.29453) (xy 86.908686 -407.280223) (xy 86.900937 -407.261527)
			(xy 86.900512 -407.251408) (xy 86.900512 -407.093928) (xy 86.900086 -407.084743) (xy 86.893583 -407.067558)
			(xy 86.887812 -407.0604) (xy 86.865916 -407.034761) (xy 86.827828 -406.979123) (xy 86.796678 -406.919323)
			(xy 86.772915 -406.856223) (xy 86.756881 -406.790731) (xy 86.748808 -406.723789) (xy 83.470763 -406.723789)
			(xy 83.462728 -406.790549) (xy 83.446757 -406.85593) (xy 83.423086 -406.918933) (xy 83.392055 -406.978655)
			(xy 83.354107 -407.03424) (xy 83.33232 -407.059892) (xy 83.326547 -407.067054) (xy 83.320017 -407.084231)
			(xy 83.31962 -407.09342) (xy 83.31962 -407.251408) (xy 83.319185 -407.26156) (xy 83.311391 -407.280309)
			(xy 83.296998 -407.294631) (xy 83.278212 -407.302334) (xy 83.268058 -407.302716) (xy 82.551778 -407.302716)
			(xy 82.541644 -407.30229) (xy 82.522914 -407.294547) (xy 82.508557 -407.280242) (xy 82.500747 -407.26154)
			(xy 82.500216 -407.251408) (xy 82.500216 -407.09342) (xy 82.499792 -407.084234) (xy 82.493288 -407.06705)
			(xy 82.487516 -407.059892) (xy 82.465698 -407.034265) (xy 82.427751 -406.978675) (xy 82.396721 -406.918947)
			(xy 82.373051 -406.85594) (xy 82.35708 -406.790555) (xy 82.349039 -406.72373) (xy 79.070977 -406.72373)
			(xy 79.070977 -406.723786) (xy 79.062905 -406.790722) (xy 79.046874 -406.856209) (xy 79.023114 -406.919304)
			(xy 78.991969 -406.9791) (xy 78.953885 -407.034734) (xy 78.932024 -407.0604) (xy 78.926248 -407.06756)
			(xy 78.91972 -407.084739) (xy 78.919324 -407.093928) (xy 78.919324 -407.251408) (xy 78.918822 -407.261514)
			(xy 78.911086 -407.280188) (xy 78.896795 -407.294482) (xy 78.878122 -407.30222) (xy 78.868016 -407.302716)
			(xy 78.151736 -407.302716) (xy 78.141618 -407.302255) (xy 78.122918 -407.294521) (xy 78.108603 -407.280219)
			(xy 78.100854 -407.261526) (xy 78.100428 -407.251408) (xy 78.100428 -407.093928) (xy 78.099998 -407.084743)
			(xy 78.093497 -407.067559) (xy 78.087728 -407.0604) (xy 78.065832 -407.034761) (xy 78.027742 -406.979124)
			(xy 77.996591 -406.919324) (xy 77.972828 -406.856224) (xy 77.956793 -406.790731) (xy 77.94872 -406.723789)
			(xy 74.670675 -406.723789) (xy 74.662641 -406.790548) (xy 74.64667 -406.855929) (xy 74.623 -406.918932)
			(xy 74.591969 -406.978655) (xy 74.554022 -407.03424) (xy 74.532236 -407.059892) (xy 74.526453 -407.067046)
			(xy 74.519932 -407.08423) (xy 74.519536 -407.09342) (xy 74.519536 -407.251408) (xy 74.519085 -407.261558)
			(xy 74.511294 -407.280304) (xy 74.496907 -407.294625) (xy 74.478126 -407.302331) (xy 74.467974 -407.302716)
			(xy 73.751694 -407.302716) (xy 73.741562 -407.302277) (xy 73.722832 -407.294539) (xy 73.708474 -407.280238)
			(xy 73.700663 -407.261538) (xy 73.700132 -407.251408) (xy 73.700132 -407.09342) (xy 73.699705 -407.084235)
			(xy 73.693202 -407.067051) (xy 73.687432 -407.059892) (xy 73.665613 -407.034266) (xy 73.627666 -406.978675)
			(xy 73.596634 -406.918948) (xy 73.572963 -406.85594) (xy 73.556993 -406.790555) (xy 73.548951 -406.72373)
			(xy 66.525648 -406.72373) (xy 66.525648 -409.523886) (xy 71.34879 -409.523886) (xy 71.348793 -409.45646)
			(xy 71.356872 -409.389519) (xy 71.372911 -409.324028) (xy 71.396679 -409.26093) (xy 71.427834 -409.201133)
			(xy 71.465926 -409.145497) (xy 71.487792 -409.119832) (xy 71.493599 -409.112694) (xy 71.500108 -409.095498)
			(xy 71.500492 -409.086304) (xy 71.500492 -408.594052) (xy 71.500059 -408.584867) (xy 71.493561 -408.567682)
			(xy 71.487792 -408.560524) (xy 71.46592 -408.534865) (xy 71.427833 -408.479229) (xy 71.396683 -408.419432)
			(xy 71.372919 -408.356335) (xy 71.356885 -408.290845) (xy 71.348809 -408.223906) (xy 71.34881 -408.156482)
			(xy 71.356887 -408.089543) (xy 71.372923 -408.024054) (xy 71.396688 -407.960957) (xy 71.427839 -407.90116)
			(xy 71.465928 -407.845525) (xy 71.487792 -407.81986) (xy 71.493587 -407.812714) (xy 71.500103 -407.795524)
			(xy 71.500492 -407.786332) (xy 71.500492 -407.628852) (xy 71.500946 -407.618741) (xy 71.508698 -407.600063)
			(xy 71.523004 -407.585771) (xy 71.541689 -407.578036) (xy 71.5518 -407.577544) (xy 72.26808 -407.577544)
			(xy 72.278181 -407.5781) (xy 72.296848 -407.585821) (xy 72.311141 -407.600095) (xy 72.318887 -407.618752)
			(xy 72.319388 -407.628852) (xy 72.319388 -407.786332) (xy 72.319785 -407.795521) (xy 72.326308 -407.812705)
			(xy 72.332088 -407.81986) (xy 72.353945 -407.845532) (xy 72.392034 -407.901165) (xy 72.423186 -407.96096)
			(xy 72.446951 -408.024056) (xy 72.462988 -408.089545) (xy 72.471064 -408.156482) (xy 72.471065 -408.223906)
			(xy 72.46299 -408.290844) (xy 72.446955 -408.356332) (xy 72.423191 -408.419429) (xy 72.39204 -408.479225)
			(xy 72.353952 -408.534859) (xy 72.332088 -408.560524) (xy 72.326297 -408.567673) (xy 72.31978 -408.584861)
			(xy 72.319388 -408.594052) (xy 72.319388 -409.086304) (xy 72.319799 -409.095491) (xy 72.326313 -409.112675)
			(xy 72.332088 -409.119832) (xy 72.353917 -409.145526) (xy 72.392008 -409.201156) (xy 72.423161 -409.260948)
			(xy 72.446927 -409.324042) (xy 72.462966 -409.389527) (xy 72.471045 -409.456462) (xy 72.471048 -409.523884)
			(xy 72.462975 -409.59082) (xy 72.446943 -409.656307) (xy 72.423183 -409.719402) (xy 72.392035 -409.779197)
			(xy 72.35395 -409.834831) (xy 72.332088 -409.860496) (xy 72.326309 -409.867654) (xy 72.319784 -409.884835)
			(xy 72.319388 -409.894024) (xy 72.319388 -410.051504) (xy 72.318987 -410.061628) (xy 72.311235 -410.080334)
			(xy 72.296914 -410.094649) (xy 72.278204 -410.102392) (xy 72.26808 -410.102812) (xy 71.5518 -410.102812)
			(xy 71.541693 -410.102315) (xy 71.523017 -410.09458) (xy 71.508723 -410.080286) (xy 71.500986 -410.061611)
			(xy 71.500492 -410.051504) (xy 71.500492 -409.894024) (xy 71.500072 -409.884838) (xy 71.493565 -409.867653)
			(xy 71.487792 -409.860496) (xy 71.465893 -409.83486) (xy 71.427806 -409.779221) (xy 71.396657 -409.719421)
			(xy 71.372895 -409.65632) (xy 71.356863 -409.590827) (xy 71.34879 -409.523886) (xy 66.525648 -409.523886)
			(xy 66.525648 -410.623641) (xy 73.548963 -410.623641) (xy 73.548964 -410.556335) (xy 73.55701 -410.489511)
			(xy 73.572984 -410.424128) (xy 73.596658 -410.361123) (xy 73.627693 -410.301399) (xy 73.665643 -410.245812)
			(xy 73.687432 -410.22016) (xy 73.693232 -410.213017) (xy 73.699744 -410.195825) (xy 73.700132 -410.186632)
			(xy 73.700132 -409.693364) (xy 73.699732 -409.684176) (xy 73.69321 -409.666992) (xy 73.687432 -409.659836)
			(xy 73.665656 -409.634174) (xy 73.627707 -409.578589) (xy 73.596674 -409.518867) (xy 73.573001 -409.455863)
			(xy 73.557027 -409.390482) (xy 73.548982 -409.323661) (xy 73.548981 -409.256357) (xy 73.557024 -409.189535)
			(xy 73.572995 -409.124154) (xy 73.596667 -409.06115) (xy 73.627698 -409.001427) (xy 73.665645 -408.94584)
			(xy 73.687432 -408.920188) (xy 73.69322 -408.913037) (xy 73.699739 -408.895851) (xy 73.700132 -408.88666)
			(xy 73.700132 -408.728672) (xy 73.700499 -408.718512) (xy 73.70831 -408.699753) (xy 73.722724 -408.685429)
			(xy 73.741532 -408.677736) (xy 73.751694 -408.677364) (xy 74.467974 -408.677364) (xy 74.478102 -408.677848)
			(xy 74.496827 -408.685572) (xy 74.511185 -408.69986) (xy 74.519001 -408.718546) (xy 74.519536 -408.728672)
			(xy 74.519536 -408.88666) (xy 74.51998 -408.895843) (xy 74.526472 -408.913027) (xy 74.532236 -408.920188)
			(xy 74.554036 -408.94583) (xy 74.591986 -409.001418) (xy 74.62302 -409.061142) (xy 74.646694 -409.124148)
			(xy 74.662666 -409.189532) (xy 74.67071 -409.256356) (xy 74.670709 -409.323662) (xy 74.662663 -409.390486)
			(xy 74.646688 -409.455869) (xy 74.623013 -409.518874) (xy 74.620439 -409.523827) (xy 75.749085 -409.523827)
			(xy 75.749088 -409.456519) (xy 75.757137 -409.389693) (xy 75.773115 -409.324308) (xy 75.796793 -409.261302)
			(xy 75.827833 -409.201578) (xy 75.865789 -409.145992) (xy 75.88758 -409.12034) (xy 75.893382 -409.113199)
			(xy 75.899894 -409.096005) (xy 75.90028 -409.086812) (xy 75.90028 -408.593544) (xy 75.899853 -408.584358)
			(xy 75.893352 -408.567174) (xy 75.88758 -408.560016) (xy 75.865783 -408.534371) (xy 75.827832 -408.478784)
			(xy 75.796797 -408.41906) (xy 75.773123 -408.356055) (xy 75.757149 -408.290671) (xy 75.749105 -408.223847)
			(xy 75.749106 -408.156541) (xy 75.757151 -408.089717) (xy 75.773126 -408.024334) (xy 75.796802 -407.961329)
			(xy 75.827838 -407.901605) (xy 75.865791 -407.84602) (xy 75.88758 -407.820368) (xy 75.89337 -407.813218)
			(xy 75.899889 -407.796031) (xy 75.90028 -407.78684) (xy 75.90028 -407.628852) (xy 75.900682 -407.618697)
			(xy 75.90849 -407.599948) (xy 75.922892 -407.585627) (xy 75.941685 -407.577925) (xy 75.951842 -407.577544)
			(xy 76.668122 -407.577544) (xy 76.678251 -407.578008) (xy 76.696973 -407.585744) (xy 76.711329 -407.600037)
			(xy 76.719147 -407.618726) (xy 76.719684 -407.628852) (xy 76.719684 -407.78684) (xy 76.720078 -407.796029)
			(xy 76.726603 -407.813213) (xy 76.732384 -407.820368) (xy 76.754163 -407.846027) (xy 76.792111 -407.901613)
			(xy 76.823143 -407.961336) (xy 76.846815 -408.024339) (xy 76.862788 -408.08972) (xy 76.870833 -408.156542)
			(xy 76.870833 -408.223846) (xy 76.86279 -408.290668) (xy 76.846819 -408.356049) (xy 76.823148 -408.419053)
			(xy 76.792117 -408.478777) (xy 76.754171 -408.534364) (xy 76.732384 -408.560016) (xy 76.726596 -408.567167)
			(xy 76.720077 -408.584353) (xy 76.719684 -408.593544) (xy 76.719684 -409.086812) (xy 76.720092 -409.095999)
			(xy 76.726607 -409.113184) (xy 76.732384 -409.12034) (xy 76.754135 -409.146022) (xy 76.792084 -409.201605)
			(xy 76.823117 -409.261324) (xy 76.846791 -409.324325) (xy 76.862766 -409.389703) (xy 76.870812 -409.456522)
			(xy 76.870816 -409.523824) (xy 76.862775 -409.590644) (xy 76.846807 -409.656023) (xy 76.823139 -409.719026)
			(xy 76.792112 -409.778749) (xy 76.754169 -409.834335) (xy 76.732384 -409.859988) (xy 76.726566 -409.867118)
			(xy 76.720065 -409.88432) (xy 76.719684 -409.893516) (xy 76.719684 -410.051504) (xy 76.719281 -410.06166)
			(xy 76.711481 -410.080416) (xy 76.697079 -410.09474) (xy 76.678281 -410.102436) (xy 76.668122 -410.102812)
			(xy 75.951842 -410.102812) (xy 75.941724 -410.10224) (xy 75.923014 -410.094536) (xy 75.908658 -410.080276)
			(xy 75.900828 -410.061618) (xy 75.90028 -410.051504) (xy 75.90028 -409.893516) (xy 75.899867 -409.884329)
			(xy 75.893356 -409.867144) (xy 75.88758 -409.859988) (xy 75.865756 -409.834365) (xy 75.827805 -409.778776)
			(xy 75.796771 -409.719048) (xy 75.773099 -409.65604) (xy 75.757127 -409.590654) (xy 75.749085 -409.523827)
			(xy 74.620439 -409.523827) (xy 74.591977 -409.578598) (xy 74.554025 -409.634184) (xy 74.532236 -409.659836)
			(xy 74.526434 -409.666977) (xy 74.519924 -409.684171) (xy 74.519536 -409.693364) (xy 74.519536 -410.186632)
			(xy 74.519945 -410.195819) (xy 74.526461 -410.213002) (xy 74.532236 -410.22016) (xy 74.554009 -410.245825)
			(xy 74.59196 -410.301409) (xy 74.622995 -410.36113) (xy 74.64667 -410.424133) (xy 74.662644 -410.489514)
			(xy 74.67069 -410.556336) (xy 74.670692 -410.62364) (xy 74.670685 -410.623701) (xy 77.948731 -410.623701)
			(xy 77.948732 -410.556275) (xy 77.95681 -410.489335) (xy 77.972848 -410.423845) (xy 77.996615 -410.360747)
			(xy 78.02777 -410.300951) (xy 78.065862 -410.245317) (xy 78.087728 -410.219652) (xy 78.093531 -410.212512)
			(xy 78.100041 -410.195317) (xy 78.100428 -410.186124) (xy 78.100428 -409.693872) (xy 78.100025 -409.684684)
			(xy 78.093506 -409.6675) (xy 78.087728 -409.660344) (xy 78.065875 -409.63467) (xy 78.027784 -409.579037)
			(xy 77.996631 -409.519242) (xy 77.972865 -409.456147) (xy 77.956828 -409.390658) (xy 77.948751 -409.323721)
			(xy 77.94875 -409.256297) (xy 77.956825 -409.189359) (xy 77.97286 -409.123871) (xy 77.996624 -409.060774)
			(xy 78.027775 -409.000979) (xy 78.065864 -408.945345) (xy 78.087728 -408.91968) (xy 78.093519 -408.912531)
			(xy 78.100036 -408.895343) (xy 78.100428 -408.886152) (xy 78.100428 -408.728672) (xy 78.100794 -408.718544)
			(xy 78.108556 -408.699835) (xy 78.122888 -408.68552) (xy 78.141608 -408.677781) (xy 78.151736 -408.677364)
			(xy 78.868016 -408.677364) (xy 78.878121 -408.677871) (xy 78.896793 -408.685608) (xy 78.911086 -408.699897)
			(xy 78.918826 -408.718567) (xy 78.919324 -408.728672) (xy 78.919324 -408.886152) (xy 78.919752 -408.895337)
			(xy 78.926253 -408.912522) (xy 78.932024 -408.91968) (xy 78.953899 -408.945336) (xy 78.991986 -409.000972)
			(xy 79.023135 -409.06077) (xy 79.046897 -409.123868) (xy 79.062931 -409.189358) (xy 79.071005 -409.256297)
			(xy 79.071004 -409.323721) (xy 79.062928 -409.39066) (xy 79.046892 -409.456149) (xy 79.023127 -409.519246)
			(xy 79.02071 -409.523886) (xy 80.148878 -409.523886) (xy 80.148881 -409.45646) (xy 80.15696 -409.38952)
			(xy 80.172999 -409.324029) (xy 80.196766 -409.260931) (xy 80.227919 -409.201133) (xy 80.266011 -409.145498)
			(xy 80.287876 -409.119832) (xy 80.293681 -409.112693) (xy 80.300191 -409.095498) (xy 80.300576 -409.086304)
			(xy 80.300576 -408.594052) (xy 80.300146 -408.584867) (xy 80.293647 -408.567682) (xy 80.287876 -408.560524)
			(xy 80.266005 -408.534865) (xy 80.227918 -408.479229) (xy 80.196769 -408.419432) (xy 80.173006 -408.356334)
			(xy 80.156972 -408.290844) (xy 80.148897 -408.223906) (xy 80.148898 -408.156482) (xy 80.156974 -408.089544)
			(xy 80.17301 -408.024055) (xy 80.196774 -407.960957) (xy 80.227924 -407.901161) (xy 80.266012 -407.845526)
			(xy 80.287876 -407.81986) (xy 80.293669 -407.812712) (xy 80.300187 -407.795524) (xy 80.300576 -407.786332)
			(xy 80.300576 -407.628852) (xy 80.301045 -407.618743) (xy 80.308794 -407.600069) (xy 80.323095 -407.585776)
			(xy 80.341775 -407.578039) (xy 80.351884 -407.577544) (xy 81.068164 -407.577544) (xy 81.078264 -407.578113)
			(xy 81.09693 -407.585829) (xy 81.111224 -407.600099) (xy 81.11897 -407.618753) (xy 81.119472 -407.628852)
			(xy 81.119472 -407.786332) (xy 81.119873 -407.79552) (xy 81.126394 -407.812704) (xy 81.132172 -407.81986)
			(xy 81.154029 -407.845531) (xy 81.19212 -407.901164) (xy 81.223273 -407.960959) (xy 81.247038 -408.024056)
			(xy 81.263075 -408.089544) (xy 81.271152 -408.156482) (xy 81.271153 -408.223906) (xy 81.263077 -408.290844)
			(xy 81.247042 -408.356333) (xy 81.223277 -408.41943) (xy 81.192126 -408.479225) (xy 81.154036 -408.534859)
			(xy 81.132172 -408.560524) (xy 81.126379 -408.567672) (xy 81.119863 -408.58486) (xy 81.119472 -408.594052)
			(xy 81.119472 -409.086304) (xy 81.119886 -409.095491) (xy 81.126398 -409.112675) (xy 81.132172 -409.119832)
			(xy 81.154002 -409.145526) (xy 81.192093 -409.201156) (xy 81.223247 -409.260948) (xy 81.247014 -409.324041)
			(xy 81.263053 -409.389527) (xy 81.271132 -409.456462) (xy 81.271136 -409.523884) (xy 81.263063 -409.59082)
			(xy 81.247031 -409.656307) (xy 81.223269 -409.719403) (xy 81.192121 -409.779198) (xy 81.154035 -409.834831)
			(xy 81.132172 -409.860496) (xy 81.126391 -409.867652) (xy 81.119868 -409.884834) (xy 81.119472 -409.894024)
			(xy 81.119472 -410.051504) (xy 81.119086 -410.06163) (xy 81.111332 -410.080339) (xy 81.097006 -410.094654)
			(xy 81.078291 -410.102394) (xy 81.068164 -410.102812) (xy 80.351884 -410.102812) (xy 80.341776 -410.102328)
			(xy 80.3231 -410.094587) (xy 80.308806 -410.08029) (xy 80.30107 -410.061612) (xy 80.300576 -410.051504)
			(xy 80.300576 -409.894024) (xy 80.30016 -409.884837) (xy 80.293651 -409.867653) (xy 80.287876 -409.860496)
			(xy 80.265978 -409.83486) (xy 80.227891 -409.77922) (xy 80.196744 -409.71942) (xy 80.172983 -409.656319)
			(xy 80.15695 -409.590827) (xy 80.148878 -409.523886) (xy 79.02071 -409.523886) (xy 78.991976 -409.579043)
			(xy 78.953888 -409.634678) (xy 78.932024 -409.660344) (xy 78.926229 -409.667491) (xy 78.919713 -409.68468)
			(xy 78.919324 -409.693872) (xy 78.919324 -410.186124) (xy 78.919717 -410.195313) (xy 78.926242 -410.212497)
			(xy 78.932024 -410.219652) (xy 78.953871 -410.245331) (xy 78.991959 -410.300964) (xy 79.023109 -410.360758)
			(xy 79.046873 -410.423853) (xy 79.062909 -410.489341) (xy 79.070986 -410.556277) (xy 79.070987 -410.623641)
			(xy 82.349051 -410.623641) (xy 82.349052 -410.556335) (xy 82.357097 -410.489512) (xy 82.373071 -410.424129)
			(xy 82.396745 -410.361124) (xy 82.427779 -410.3014) (xy 82.465728 -410.245812) (xy 82.487516 -410.22016)
			(xy 82.493314 -410.213016) (xy 82.499827 -410.195824) (xy 82.500216 -410.186632) (xy 82.500216 -409.693364)
			(xy 82.49982 -409.684175) (xy 82.493296 -409.666991) (xy 82.487516 -409.659836) (xy 82.465741 -409.634174)
			(xy 82.427793 -409.578588) (xy 82.39676 -409.518866) (xy 82.373088 -409.455863) (xy 82.357115 -409.390482)
			(xy 82.34907 -409.323661) (xy 82.349069 -409.256357) (xy 82.357112 -409.189536) (xy 82.373083 -409.124155)
			(xy 82.396753 -409.061151) (xy 82.427784 -409.001427) (xy 82.46573 -408.94584) (xy 82.487516 -408.920188)
			(xy 82.493302 -408.913035) (xy 82.499822 -408.89585) (xy 82.500216 -408.88666) (xy 82.500216 -408.728672)
			(xy 82.500599 -408.718514) (xy 82.508407 -408.699758) (xy 82.522815 -408.685435) (xy 82.541618 -408.677739)
			(xy 82.551778 -408.677364) (xy 83.268058 -408.677364) (xy 83.278185 -408.677862) (xy 83.29691 -408.68558)
			(xy 83.311268 -408.699864) (xy 83.319085 -408.718548) (xy 83.31962 -408.728672) (xy 83.31962 -408.88666)
			(xy 83.320045 -408.895846) (xy 83.326548 -408.913031) (xy 83.33232 -408.920188) (xy 83.354121 -408.94583)
			(xy 83.392072 -409.001417) (xy 83.423107 -409.061141) (xy 83.446781 -409.124147) (xy 83.462754 -409.189531)
			(xy 83.470798 -409.256356) (xy 83.470797 -409.323662) (xy 83.462751 -409.390487) (xy 83.446775 -409.45587)
			(xy 83.423099 -409.518875) (xy 83.420495 -409.523886) (xy 84.548669 -409.523886) (xy 84.548672 -409.45646)
			(xy 84.556751 -409.38952) (xy 84.572789 -409.324029) (xy 84.596556 -409.260931) (xy 84.627709 -409.201134)
			(xy 84.665799 -409.145498) (xy 84.687664 -409.119832) (xy 84.69348 -409.112701) (xy 84.699981 -409.095499)
			(xy 84.700364 -409.086304) (xy 84.700364 -408.594052) (xy 84.699915 -408.584869) (xy 84.693427 -408.567685)
			(xy 84.687664 -408.560524) (xy 84.665793 -408.534865) (xy 84.627707 -408.479228) (xy 84.596559 -408.419431)
			(xy 84.572797 -408.356334) (xy 84.556763 -408.290844) (xy 84.548688 -408.223906) (xy 84.548689 -408.156482)
			(xy 84.556765 -408.089544) (xy 84.5728 -408.024055) (xy 84.596564 -407.960958) (xy 84.627714 -407.901161)
			(xy 84.665801 -407.845526) (xy 84.687664 -407.81986) (xy 84.693468 -407.81272) (xy 84.699976 -407.795525)
			(xy 84.700364 -407.786332) (xy 84.700364 -407.628852) (xy 84.700845 -407.618745) (xy 84.708592 -407.600072)
			(xy 84.722889 -407.585781) (xy 84.741564 -407.578041) (xy 84.751672 -407.577544) (xy 85.467952 -407.577544)
			(xy 85.478051 -407.578123) (xy 85.496717 -407.585835) (xy 85.511012 -407.600102) (xy 85.518758 -407.618754)
			(xy 85.51926 -407.628852) (xy 85.51926 -407.786332) (xy 85.519664 -407.79552) (xy 85.526183 -407.812703)
			(xy 85.53196 -407.81986) (xy 85.553818 -407.845531) (xy 85.591909 -407.901164) (xy 85.623062 -407.960959)
			(xy 85.646829 -408.024055) (xy 85.662866 -408.089544) (xy 85.670943 -408.156482) (xy 85.670944 -408.223906)
			(xy 85.662868 -408.290844) (xy 85.646832 -408.356333) (xy 85.623067 -408.41943) (xy 85.591915 -408.479226)
			(xy 85.553825 -408.534859) (xy 85.53196 -408.560524) (xy 85.526166 -408.567671) (xy 85.519651 -408.58486)
			(xy 85.51926 -408.594052) (xy 85.51926 -409.086304) (xy 85.519677 -409.09549) (xy 85.526187 -409.112674)
			(xy 85.53196 -409.119832) (xy 85.55379 -409.145526) (xy 85.591882 -409.201155) (xy 85.623037 -409.260947)
			(xy 85.646805 -409.32404) (xy 85.662844 -409.389526) (xy 85.670923 -409.456462) (xy 85.670927 -409.523884)
			(xy 85.662854 -409.59082) (xy 85.646821 -409.656308) (xy 85.623059 -409.719403) (xy 85.59191 -409.779198)
			(xy 85.553823 -409.834831) (xy 85.53196 -409.860496) (xy 85.526178 -409.867651) (xy 85.519655 -409.884834)
			(xy 85.51926 -409.894024) (xy 85.51926 -410.051504) (xy 85.518886 -410.061632) (xy 85.511129 -410.080343)
			(xy 85.496799 -410.094659) (xy 85.47808 -410.102396) (xy 85.467952 -410.102812) (xy 84.751672 -410.102812)
			(xy 84.741563 -410.102338) (xy 84.722886 -410.094594) (xy 84.708593 -410.080293) (xy 84.700857 -410.061613)
			(xy 84.700364 -410.051504) (xy 84.700364 -409.894024) (xy 84.699928 -409.88484) (xy 84.693431 -409.867656)
			(xy 84.687664 -409.860496) (xy 84.665766 -409.834859) (xy 84.627681 -409.77922) (xy 84.596534 -409.719419)
			(xy 84.572773 -409.656319) (xy 84.556741 -409.590827) (xy 84.548669 -409.523886) (xy 83.420495 -409.523886)
			(xy 83.392063 -409.578599) (xy 83.35411 -409.634184) (xy 83.33232 -409.659836) (xy 83.326528 -409.666985)
			(xy 83.32001 -409.684172) (xy 83.31962 -409.693364) (xy 83.31962 -410.186632) (xy 83.32001 -410.195821)
			(xy 83.326537 -410.213006) (xy 83.33232 -410.22016) (xy 83.354093 -410.245825) (xy 83.392045 -410.301408)
			(xy 83.423081 -410.36113) (xy 83.446757 -410.424133) (xy 83.462732 -410.489514) (xy 83.470778 -410.556336)
			(xy 83.47078 -410.62364) (xy 83.470773 -410.623701) (xy 86.748819 -410.623701) (xy 86.74882 -410.556275)
			(xy 86.756898 -410.489336) (xy 86.772936 -410.423846) (xy 86.796702 -410.360748) (xy 86.827855 -410.300952)
			(xy 86.865947 -410.245317) (xy 86.887812 -410.219652) (xy 86.893613 -410.21251) (xy 86.900125 -410.195317)
			(xy 86.900512 -410.186124) (xy 86.900512 -409.693872) (xy 86.900113 -409.684684) (xy 86.893591 -409.6675)
			(xy 86.887812 -409.660344) (xy 86.865959 -409.634669) (xy 86.82787 -409.579036) (xy 86.796718 -409.519242)
			(xy 86.772952 -409.456146) (xy 86.756916 -409.390658) (xy 86.748839 -409.32372) (xy 86.748837 -409.256298)
			(xy 86.756912 -409.18936) (xy 86.772947 -409.123871) (xy 86.79671 -409.060775) (xy 86.82786 -409.000979)
			(xy 86.865948 -408.945345) (xy 86.887812 -408.91968) (xy 86.893601 -408.912529) (xy 86.90012 -408.895343)
			(xy 86.900512 -408.886152) (xy 86.900512 -408.728672) (xy 86.900962 -408.71856) (xy 86.908711 -408.699879)
			(xy 86.923019 -408.685585) (xy 86.941708 -408.677853) (xy 86.95182 -408.677364) (xy 87.6681 -408.677364)
			(xy 87.678204 -408.677884) (xy 87.696876 -408.685615) (xy 87.711169 -408.699901) (xy 87.71891 -408.718568)
			(xy 87.719408 -408.728672) (xy 87.719408 -408.886152) (xy 87.719839 -408.895337) (xy 87.726338 -408.912522)
			(xy 87.732108 -408.91968) (xy 87.753983 -408.945336) (xy 87.792071 -409.000972) (xy 87.823221 -409.060769)
			(xy 87.846984 -409.123867) (xy 87.863019 -409.189358) (xy 87.871093 -409.256297) (xy 87.871092 -409.323721)
			(xy 87.863015 -409.39066) (xy 87.846979 -409.45615) (xy 87.823214 -409.519247) (xy 87.792062 -409.579044)
			(xy 87.753972 -409.634679) (xy 87.732108 -409.660344) (xy 87.726311 -409.667489) (xy 87.719796 -409.68468)
			(xy 87.719408 -409.693872) (xy 87.719408 -410.186124) (xy 87.719805 -410.195313) (xy 87.726328 -410.212497)
			(xy 87.732108 -410.219652) (xy 87.753956 -410.24533) (xy 87.792045 -410.300963) (xy 87.823196 -410.360758)
			(xy 87.84696 -410.423853) (xy 87.862997 -410.48934) (xy 87.871074 -410.556277) (xy 87.871075 -410.623641)
			(xy 91.149138 -410.623641) (xy 91.14914 -410.556335) (xy 91.157185 -410.489512) (xy 91.173158 -410.42413)
			(xy 91.196831 -410.361125) (xy 91.227864 -410.3014) (xy 91.265813 -410.245813) (xy 91.2876 -410.22016)
			(xy 91.293396 -410.213014) (xy 91.299911 -410.195824) (xy 91.3003 -410.186632) (xy 91.3003 -409.693364)
			(xy 91.299907 -409.684175) (xy 91.293382 -409.666991) (xy 91.2876 -409.659836) (xy 91.265825 -409.634174)
			(xy 91.227879 -409.578588) (xy 91.196847 -409.518865) (xy 91.173175 -409.455862) (xy 91.157203 -409.390482)
			(xy 91.149158 -409.323661) (xy 91.149157 -409.256357) (xy 91.157199 -409.189536) (xy 91.17317 -409.124155)
			(xy 91.19684 -409.061151) (xy 91.227869 -409.001428) (xy 91.265814 -408.945841) (xy 91.2876 -408.920188)
			(xy 91.293384 -408.913034) (xy 91.299906 -408.89585) (xy 91.3003 -408.88666) (xy 91.3003 -408.728672)
			(xy 91.300699 -408.718516) (xy 91.308503 -408.699763) (xy 91.322907 -408.685441) (xy 91.341704 -408.677742)
			(xy 91.351862 -408.677364) (xy 92.068142 -408.677364) (xy 92.078274 -408.677793) (xy 92.097001 -408.685539)
			(xy 92.111357 -408.699843) (xy 92.11917 -408.718542) (xy 92.119704 -408.728672) (xy 92.119704 -408.88666)
			(xy 92.120132 -408.895845) (xy 92.126633 -408.91303) (xy 92.132404 -408.920188) (xy 92.154202 -408.945831)
			(xy 92.192148 -409.00142) (xy 92.223178 -409.061145) (xy 92.246848 -409.124151) (xy 92.262819 -409.189534)
			(xy 92.270862 -409.256356) (xy 92.270861 -409.323662) (xy 92.262816 -409.390484) (xy 92.246843 -409.455867)
			(xy 92.223171 -409.518871) (xy 92.220596 -409.523827) (xy 115.349227 -409.523827) (xy 115.349231 -409.456519)
			(xy 115.357278 -409.389695) (xy 115.373254 -409.324311) (xy 115.396929 -409.261305) (xy 115.427964 -409.20158)
			(xy 115.465915 -409.145993) (xy 115.487704 -409.12034) (xy 115.493509 -409.113201) (xy 115.500019 -409.096006)
			(xy 115.500404 -409.086812) (xy 115.500404 -408.593544) (xy 115.499972 -408.584359) (xy 115.493473 -408.567175)
			(xy 115.487704 -408.560016) (xy 115.465909 -408.53437) (xy 115.427963 -408.478782) (xy 115.396932 -408.419057)
			(xy 115.373261 -408.356052) (xy 115.35729 -408.290669) (xy 115.349247 -408.223846) (xy 115.349248 -408.156541)
			(xy 115.357292 -408.089719) (xy 115.373265 -408.024337) (xy 115.396937 -407.961332) (xy 115.427969 -407.901608)
			(xy 115.465917 -407.846021) (xy 115.487704 -407.820368) (xy 115.493497 -407.81322) (xy 115.500014 -407.796032)
			(xy 115.500404 -407.78684) (xy 115.500404 -407.628852) (xy 115.500846 -407.61874) (xy 115.5086 -407.60006)
			(xy 115.52291 -407.585767) (xy 115.541599 -407.578034) (xy 115.551712 -407.577544) (xy 116.268246 -407.577544)
			(xy 116.278376 -407.577989) (xy 116.297099 -407.585733) (xy 116.311454 -407.600031) (xy 116.319271 -407.618724)
			(xy 116.319808 -407.628852) (xy 116.319808 -407.78684) (xy 116.320197 -407.79603) (xy 116.326725 -407.813214)
			(xy 116.332508 -407.820368) (xy 116.354289 -407.846026) (xy 116.392242 -407.90161) (xy 116.423279 -407.961333)
			(xy 116.446954 -408.024336) (xy 116.462929 -408.089718) (xy 116.470975 -408.156541) (xy 116.470976 -408.223847)
			(xy 116.462931 -408.29067) (xy 116.446958 -408.356052) (xy 116.423283 -408.419056) (xy 116.392248 -408.478779)
			(xy 116.354297 -408.534365) (xy 116.332508 -408.560016) (xy 116.326723 -408.56717) (xy 116.320201 -408.584354)
			(xy 116.319808 -408.593544) (xy 116.319808 -409.086812) (xy 116.320211 -409.096) (xy 116.326729 -409.113184)
			(xy 116.332508 -409.12034) (xy 116.354262 -409.146021) (xy 116.392215 -409.201602) (xy 116.423253 -409.261321)
			(xy 116.44693 -409.324322) (xy 116.462907 -409.389701) (xy 116.470955 -409.456521) (xy 116.470958 -409.523825)
			(xy 116.462917 -409.590646) (xy 116.446946 -409.656026) (xy 116.423275 -409.71903) (xy 116.392243 -409.778752)
			(xy 116.354295 -409.834337) (xy 116.332508 -409.859988) (xy 116.326692 -409.86712) (xy 116.320189 -409.884321)
			(xy 116.319808 -409.893516) (xy 116.319808 -410.051504) (xy 116.319318 -410.061612) (xy 116.311581 -410.080289)
			(xy 116.297285 -410.094583) (xy 116.278608 -410.102319) (xy 116.2685 -410.102812) (xy 115.551966 -410.102812)
			(xy 115.541844 -410.102303) (xy 115.523131 -410.094574) (xy 115.508778 -410.080295) (xy 115.500951 -410.061624)
			(xy 115.500404 -410.051504) (xy 115.500404 -409.893516) (xy 115.499985 -409.88433) (xy 115.493477 -409.867145)
			(xy 115.487704 -409.859988) (xy 115.465882 -409.834364) (xy 115.427937 -409.778773) (xy 115.396907 -409.719045)
			(xy 115.373238 -409.656037) (xy 115.357268 -409.590652) (xy 115.349227 -409.523827) (xy 92.220596 -409.523827)
			(xy 92.192139 -409.578596) (xy 92.154191 -409.634183) (xy 92.132404 -409.659836) (xy 92.12661 -409.666983)
			(xy 92.120094 -409.684172) (xy 92.119704 -409.693364) (xy 92.119704 -410.186632) (xy 92.120098 -410.195821)
			(xy 92.126623 -410.213005) (xy 92.132404 -410.22016) (xy 92.154175 -410.245826) (xy 92.192121 -410.301411)
			(xy 92.223153 -410.361133) (xy 92.246825 -410.424136) (xy 92.262797 -410.489516) (xy 92.270842 -410.556336)
			(xy 92.270844 -410.623639) (xy 92.270837 -410.623701) (xy 117.548849 -410.623701) (xy 117.54885 -410.556275)
			(xy 117.556929 -410.489335) (xy 117.572967 -410.423844) (xy 117.596736 -410.360746) (xy 117.627891 -410.30095)
			(xy 117.665985 -410.245316) (xy 117.687852 -410.219652) (xy 117.693658 -410.212514) (xy 117.700166 -410.195318)
			(xy 117.700552 -410.186124) (xy 117.700552 -409.693872) (xy 117.700144 -409.684685) (xy 117.693627 -409.667501)
			(xy 117.687852 -409.660344) (xy 117.665998 -409.63467) (xy 117.627906 -409.579038) (xy 117.596751 -409.519243)
			(xy 117.572984 -409.456148) (xy 117.556946 -409.390659) (xy 117.548869 -409.323721) (xy 117.548868 -409.256297)
			(xy 117.556943 -409.189359) (xy 117.572979 -409.12387) (xy 117.596744 -409.060773) (xy 117.627896 -409.000978)
			(xy 117.665987 -408.945344) (xy 117.687852 -408.91968) (xy 117.693646 -408.912533) (xy 117.700161 -408.895344)
			(xy 117.700552 -408.886152) (xy 117.700552 -408.728672) (xy 117.701061 -408.718567) (xy 117.708799 -408.699898)
			(xy 117.723088 -408.685606) (xy 117.741756 -408.677863) (xy 117.75186 -408.677364) (xy 118.46814 -408.677364)
			(xy 118.478247 -408.677852) (xy 118.496919 -408.685596) (xy 118.511211 -408.699891) (xy 118.518951 -408.718565)
			(xy 118.519448 -408.728672) (xy 118.519448 -408.886152) (xy 118.519893 -408.895335) (xy 118.526384 -408.912519)
			(xy 118.532148 -408.91968) (xy 118.554026 -408.945335) (xy 118.592117 -409.000969) (xy 118.62327 -409.060767)
			(xy 118.647036 -409.123865) (xy 118.663072 -409.189356) (xy 118.671148 -409.256296) (xy 118.671147 -409.323722)
			(xy 118.663069 -409.390662) (xy 118.647031 -409.456152) (xy 118.623263 -409.51925) (xy 118.620848 -409.523886)
			(xy 119.748996 -409.523886) (xy 119.748999 -409.45646) (xy 119.757078 -409.389519) (xy 119.773118 -409.324028)
			(xy 119.796886 -409.26093) (xy 119.828041 -409.201132) (xy 119.866134 -409.145497) (xy 119.888 -409.119832)
			(xy 119.893808 -409.112695) (xy 119.900316 -409.095498) (xy 119.9007 -409.086304) (xy 119.9007 -408.594052)
			(xy 119.900265 -408.584867) (xy 119.893769 -408.567683) (xy 119.888 -408.560524) (xy 119.866128 -408.534865)
			(xy 119.82804 -408.47923) (xy 119.796889 -408.419433) (xy 119.773126 -408.356335) (xy 119.757091 -408.290845)
			(xy 119.749015 -408.223906) (xy 119.749016 -408.156482) (xy 119.757093 -408.089543) (xy 119.773129 -408.024054)
			(xy 119.796894 -407.960956) (xy 119.828046 -407.90116) (xy 119.866136 -407.845525) (xy 119.888 -407.81986)
			(xy 119.893796 -407.812714) (xy 119.900311 -407.795524) (xy 119.9007 -407.786332) (xy 119.9007 -407.628852)
			(xy 119.901146 -407.61874) (xy 119.908899 -407.600061) (xy 119.923208 -407.585768) (xy 119.941896 -407.578035)
			(xy 119.952008 -407.577544) (xy 120.668288 -407.577544) (xy 120.678389 -407.578094) (xy 120.697056 -407.585817)
			(xy 120.71135 -407.600093) (xy 120.719095 -407.618752) (xy 120.719596 -407.628852) (xy 120.719596 -407.786332)
			(xy 120.719991 -407.795521) (xy 120.726515 -407.812705) (xy 120.732296 -407.81986) (xy 120.754152 -407.845532)
			(xy 120.792241 -407.901165) (xy 120.823393 -407.96096) (xy 120.847158 -408.024056) (xy 120.863194 -408.089545)
			(xy 120.87127 -408.156482) (xy 120.871271 -408.223906) (xy 120.863196 -408.290843) (xy 120.847161 -408.356332)
			(xy 120.823398 -408.419429) (xy 120.792248 -408.479225) (xy 120.75416 -408.534859) (xy 120.732296 -408.560524)
			(xy 120.726506 -408.567674) (xy 120.719988 -408.584861) (xy 120.719596 -408.594052) (xy 120.719596 -409.086304)
			(xy 120.720005 -409.095491) (xy 120.72652 -409.112675) (xy 120.732296 -409.119832) (xy 120.754125 -409.145526)
			(xy 120.792215 -409.201157) (xy 120.823367 -409.260949) (xy 120.847134 -409.324042) (xy 120.863172 -409.389527)
			(xy 120.871251 -409.456463) (xy 120.871254 -409.523883) (xy 120.863181 -409.590819) (xy 120.84715 -409.656306)
			(xy 120.823389 -409.719402) (xy 120.792243 -409.779197) (xy 120.754158 -409.834831) (xy 120.732296 -409.860496)
			(xy 120.726518 -409.867654) (xy 120.719992 -409.884835) (xy 120.719596 -409.894024) (xy 120.719596 -410.051504)
			(xy 120.719187 -410.061627) (xy 120.711437 -410.080332) (xy 120.697118 -410.094646) (xy 120.678411 -410.10239)
			(xy 120.668288 -410.102812) (xy 119.952008 -410.102812) (xy 119.941888 -410.102378) (xy 119.923186 -410.094634)
			(xy 119.908872 -410.080324) (xy 119.901125 -410.061624) (xy 119.9007 -410.051504) (xy 119.9007 -409.894024)
			(xy 119.900278 -409.884838) (xy 119.893773 -409.867654) (xy 119.888 -409.860496) (xy 119.866101 -409.83486)
			(xy 119.828013 -409.779221) (xy 119.796864 -409.719421) (xy 119.773102 -409.65632) (xy 119.757069 -409.590828)
			(xy 119.748996 -409.523886) (xy 118.620848 -409.523886) (xy 118.592108 -409.579046) (xy 118.554015 -409.63468)
			(xy 118.532148 -409.660344) (xy 118.526344 -409.667484) (xy 118.519835 -409.684679) (xy 118.519448 -409.693872)
			(xy 118.519448 -410.186124) (xy 118.519858 -410.195311) (xy 118.526373 -410.212495) (xy 118.532148 -410.219652)
			(xy 118.553998 -410.245329) (xy 118.592091 -410.300961) (xy 118.623245 -410.360755) (xy 118.647012 -410.42385)
			(xy 118.663051 -410.489338) (xy 118.671128 -410.556276) (xy 118.67113 -410.623641) (xy 121.949169 -410.623641)
			(xy 121.94917 -410.556335) (xy 121.957216 -410.489511) (xy 121.97319 -410.424128) (xy 121.996865 -410.361123)
			(xy 122.0279 -410.301399) (xy 122.065851 -410.245812) (xy 122.08764 -410.22016) (xy 122.093441 -410.213018)
			(xy 122.099952 -410.195825) (xy 122.10034 -410.186632) (xy 122.10034 -409.693364) (xy 122.099938 -409.684176)
			(xy 122.093418 -409.666992) (xy 122.08764 -409.659836) (xy 122.065864 -409.634174) (xy 122.027915 -409.578589)
			(xy 121.996881 -409.518867) (xy 121.973208 -409.455864) (xy 121.957234 -409.390483) (xy 121.949189 -409.323661)
			(xy 121.949188 -409.256357) (xy 121.957231 -409.189535) (xy 121.973202 -409.124154) (xy 121.996874 -409.06115)
			(xy 122.027906 -409.001427) (xy 122.065853 -408.94584) (xy 122.08764 -408.920188) (xy 122.093429 -408.913038)
			(xy 122.099947 -408.895851) (xy 122.10034 -408.88666) (xy 122.10034 -408.728672) (xy 122.100694 -408.718543)
			(xy 122.108459 -408.699831) (xy 122.122795 -408.685516) (xy 122.141518 -408.677779) (xy 122.151648 -408.677364)
			(xy 122.868182 -408.677364) (xy 122.878311 -408.677842) (xy 122.897036 -408.685568) (xy 122.911394 -408.699858)
			(xy 122.919209 -408.718546) (xy 122.919744 -408.728672) (xy 122.919744 -408.88666) (xy 122.920186 -408.895844)
			(xy 122.926679 -408.913028) (xy 122.932444 -408.920188) (xy 122.954244 -408.94583) (xy 122.992193 -409.001418)
			(xy 123.023227 -409.061143) (xy 123.0469 -409.124148) (xy 123.062873 -409.189532) (xy 123.070916 -409.256356)
			(xy 123.070915 -409.323662) (xy 123.062869 -409.390486) (xy 123.046895 -409.455869) (xy 123.02322 -409.518874)
			(xy 123.020646 -409.523827) (xy 124.149291 -409.523827) (xy 124.149295 -409.456519) (xy 124.157343 -409.389693)
			(xy 124.173321 -409.324308) (xy 124.197 -409.261302) (xy 124.22804 -409.201577) (xy 124.265997 -409.145992)
			(xy 124.287788 -409.12034) (xy 124.293591 -409.113199) (xy 124.300102 -409.096005) (xy 124.300488 -409.086812)
			(xy 124.300488 -408.593544) (xy 124.300059 -408.584359) (xy 124.293559 -408.567174) (xy 124.287788 -408.560016)
			(xy 124.265991 -408.534371) (xy 124.228039 -408.478785) (xy 124.197004 -408.419061) (xy 124.173329 -408.356055)
			(xy 124.157355 -408.290671) (xy 124.149311 -408.223847) (xy 124.149312 -408.156541) (xy 124.157357 -408.089717)
			(xy 124.173333 -408.024333) (xy 124.197008 -407.961328) (xy 124.228045 -407.901605) (xy 124.265998 -407.84602)
			(xy 124.287788 -407.820368) (xy 124.293579 -407.813219) (xy 124.300097 -407.796031) (xy 124.300488 -407.78684)
			(xy 124.300488 -407.628852) (xy 124.300946 -407.618742) (xy 124.308697 -407.600065) (xy 124.323002 -407.585772)
			(xy 124.341685 -407.578037) (xy 124.351796 -407.577544) (xy 125.06833 -407.577544) (xy 125.078459 -407.578002)
			(xy 125.097182 -407.58574) (xy 125.111537 -407.600035) (xy 125.119355 -407.618725) (xy 125.119892 -407.628852)
			(xy 125.119892 -407.78684) (xy 125.120285 -407.796029) (xy 125.126811 -407.813213) (xy 125.132592 -407.820368)
			(xy 125.154371 -407.846027) (xy 125.192318 -407.901613) (xy 125.22335 -407.961336) (xy 125.247022 -408.02434)
			(xy 125.262994 -408.089721) (xy 125.271039 -408.156542) (xy 125.271039 -408.223846) (xy 125.262997 -408.290667)
			(xy 125.247025 -408.356049) (xy 125.223355 -408.419053) (xy 125.192324 -408.478776) (xy 125.154378 -408.534363)
			(xy 125.132592 -408.560016) (xy 125.126805 -408.567168) (xy 125.120285 -408.584353) (xy 125.119892 -408.593544)
			(xy 125.119892 -409.086812) (xy 125.120298 -409.096) (xy 125.126815 -409.113184) (xy 125.132592 -409.12034)
			(xy 125.154343 -409.146022) (xy 125.192291 -409.201605) (xy 125.223324 -409.261324) (xy 125.246998 -409.324325)
			(xy 125.262972 -409.389703) (xy 125.271019 -409.456522) (xy 125.271022 -409.523824) (xy 125.262982 -409.590643)
			(xy 125.247014 -409.656023) (xy 125.223347 -409.719026) (xy 125.192319 -409.778749) (xy 125.154377 -409.834336)
			(xy 125.132592 -409.859988) (xy 125.126775 -409.867118) (xy 125.120273 -409.88432) (xy 125.119892 -409.893516)
			(xy 125.119892 -410.051504) (xy 125.119487 -410.061628) (xy 125.111736 -410.080333) (xy 125.097416 -410.094647)
			(xy 125.078708 -410.102391) (xy 125.068584 -410.102812) (xy 124.35205 -410.102812) (xy 124.341933 -410.102234)
			(xy 124.323223 -410.094532) (xy 124.308867 -410.080274) (xy 124.301036 -410.061618) (xy 124.300488 -410.051504)
			(xy 124.300488 -409.893516) (xy 124.300073 -409.884329) (xy 124.293563 -409.867145) (xy 124.287788 -409.859988)
			(xy 124.265963 -409.834366) (xy 124.228013 -409.778776) (xy 124.196978 -409.719049) (xy 124.173305 -409.65604)
			(xy 124.157333 -409.590654) (xy 124.149291 -409.523827) (xy 123.020646 -409.523827) (xy 122.992184 -409.578598)
			(xy 122.954233 -409.634184) (xy 122.932444 -409.659836) (xy 122.926643 -409.666978) (xy 122.920132 -409.684171)
			(xy 122.919744 -409.693364) (xy 122.919744 -410.186632) (xy 122.920151 -410.195819) (xy 122.926668 -410.213003)
			(xy 122.932444 -410.22016) (xy 122.954216 -410.245825) (xy 122.992167 -410.301409) (xy 123.023202 -410.361131)
			(xy 123.046876 -410.424134) (xy 123.062851 -410.489514) (xy 123.070896 -410.556336) (xy 123.070898 -410.62364)
			(xy 123.070891 -410.623701) (xy 126.348937 -410.623701) (xy 126.348938 -410.556275) (xy 126.357016 -410.489335)
			(xy 126.373055 -410.423845) (xy 126.396822 -410.360747) (xy 126.427977 -410.300951) (xy 126.46607 -410.245317)
			(xy 126.487936 -410.219652) (xy 126.49374 -410.212512) (xy 126.500249 -410.195317) (xy 126.500636 -410.186124)
			(xy 126.500636 -409.693872) (xy 126.500231 -409.684684) (xy 126.493713 -409.667501) (xy 126.487936 -409.660344)
			(xy 126.466083 -409.63467) (xy 126.427991 -409.579037) (xy 126.396838 -409.519243) (xy 126.373071 -409.456147)
			(xy 126.357034 -409.390659) (xy 126.348957 -409.323721) (xy 126.348956 -409.256297) (xy 126.357031 -409.189359)
			(xy 126.373066 -409.12387) (xy 126.396831 -409.060774) (xy 126.427982 -409.000978) (xy 126.466071 -408.945345)
			(xy 126.487936 -408.91968) (xy 126.493728 -408.912532) (xy 126.500245 -408.895343) (xy 126.500636 -408.886152)
			(xy 126.500636 -408.728672) (xy 126.500994 -408.718543) (xy 126.508758 -408.699832) (xy 126.523093 -408.685517)
			(xy 126.541815 -408.67778) (xy 126.551944 -408.677364) (xy 127.268224 -408.677364) (xy 127.27833 -408.677864)
			(xy 127.297002 -408.685603) (xy 127.311294 -408.699895) (xy 127.319035 -408.718566) (xy 127.319532 -408.728672)
			(xy 127.319532 -408.886152) (xy 127.31998 -408.895335) (xy 127.326469 -408.912519) (xy 127.332232 -408.91968)
			(xy 127.354107 -408.945336) (xy 127.392193 -409.000973) (xy 127.423341 -409.06077) (xy 127.447103 -409.123868)
			(xy 127.463137 -409.189358) (xy 127.471211 -409.256297) (xy 127.47121 -409.323721) (xy 127.463134 -409.39066)
			(xy 127.447098 -409.456149) (xy 127.423334 -409.519246) (xy 127.420948 -409.523827) (xy 128.549082 -409.523827)
			(xy 128.549085 -409.456519) (xy 128.557133 -409.389693) (xy 128.573111 -409.324308) (xy 128.59679 -409.261302)
			(xy 128.627829 -409.201578) (xy 128.665785 -409.145991) (xy 128.687576 -409.12034) (xy 128.693378 -409.113198)
			(xy 128.69989 -409.096005) (xy 128.700276 -409.086812) (xy 128.700276 -408.593544) (xy 128.69985 -408.584358)
			(xy 128.693348 -408.567174) (xy 128.687576 -408.560016) (xy 128.665779 -408.534371) (xy 128.627828 -408.478784)
			(xy 128.596793 -408.41906) (xy 128.573119 -408.356055) (xy 128.557146 -408.290671) (xy 128.549102 -408.223847)
			(xy 128.549103 -408.156541) (xy 128.557148 -408.089717) (xy 128.573123 -408.024334) (xy 128.596798 -407.961329)
			(xy 128.627835 -407.901605) (xy 128.665787 -407.84602) (xy 128.687576 -407.820368) (xy 128.693366 -407.813218)
			(xy 128.699885 -407.796031) (xy 128.700276 -407.78684) (xy 128.700276 -407.628852) (xy 128.700745 -407.618743)
			(xy 128.708494 -407.600069) (xy 128.722795 -407.585776) (xy 128.741475 -407.578039) (xy 128.751584 -407.577544)
			(xy 129.468118 -407.577544) (xy 129.478246 -407.578012) (xy 129.496969 -407.585746) (xy 129.511325 -407.600038)
			(xy 129.519143 -407.618726) (xy 129.51968 -407.628852) (xy 129.51968 -407.78684) (xy 129.520075 -407.796029)
			(xy 129.5266 -407.813213) (xy 129.53238 -407.820368) (xy 129.554159 -407.846027) (xy 129.592107 -407.901613)
			(xy 129.62314 -407.961336) (xy 129.646812 -408.024339) (xy 129.662785 -408.08972) (xy 129.67083 -408.156542)
			(xy 129.67083 -408.223846) (xy 129.662787 -408.290668) (xy 129.646816 -408.356049) (xy 129.623145 -408.419053)
			(xy 129.592113 -408.478777) (xy 129.554167 -408.534364) (xy 129.53238 -408.560016) (xy 129.526592 -408.567167)
			(xy 129.520073 -408.584353) (xy 129.51968 -408.593544) (xy 129.51968 -409.086812) (xy 129.520089 -409.095999)
			(xy 129.526604 -409.113183) (xy 129.53238 -409.12034) (xy 129.554131 -409.146022) (xy 129.59208 -409.201604)
			(xy 129.623114 -409.261324) (xy 129.646788 -409.324325) (xy 129.662763 -409.389703) (xy 129.670809 -409.456522)
			(xy 129.670813 -409.523824) (xy 129.662772 -409.590644) (xy 129.646804 -409.656024) (xy 129.623136 -409.719026)
			(xy 129.592108 -409.778749) (xy 129.554165 -409.834335) (xy 129.53238 -409.859988) (xy 129.526561 -409.867117)
			(xy 129.52006 -409.88432) (xy 129.51968 -409.893516) (xy 129.51968 -410.051504) (xy 129.519287 -410.061629)
			(xy 129.511534 -410.080337) (xy 129.49721 -410.094651) (xy 129.478497 -410.102393) (xy 129.468372 -410.102812)
			(xy 128.751838 -410.102812) (xy 128.74172 -410.102244) (xy 128.72301 -410.094538) (xy 128.708654 -410.080277)
			(xy 128.700824 -410.061618) (xy 128.700276 -410.051504) (xy 128.700276 -409.893516) (xy 128.699864 -409.884329)
			(xy 128.693352 -409.867144) (xy 128.687576 -409.859988) (xy 128.665751 -409.834366) (xy 128.627801 -409.778776)
			(xy 128.596768 -409.719048) (xy 128.573095 -409.65604) (xy 128.557124 -409.590654) (xy 128.549082 -409.523827)
			(xy 127.420948 -409.523827) (xy 127.392184 -409.579043) (xy 127.354096 -409.634678) (xy 127.332232 -409.660344)
			(xy 127.326426 -409.667482) (xy 127.319919 -409.684678) (xy 127.319532 -409.693872) (xy 127.319532 -410.186124)
			(xy 127.319946 -410.19531) (xy 127.326459 -410.212494) (xy 127.332232 -410.219652) (xy 127.354079 -410.245331)
			(xy 127.392166 -410.300964) (xy 127.423316 -410.360759) (xy 127.44708 -410.423854) (xy 127.463115 -410.489341)
			(xy 127.471192 -410.556277) (xy 127.471193 -410.623641) (xy 130.749257 -410.623641) (xy 130.749258 -410.556335)
			(xy 130.757303 -410.489512) (xy 130.773278 -410.424129) (xy 130.796952 -410.361123) (xy 130.827986 -410.301399)
			(xy 130.865936 -410.245812) (xy 130.887724 -410.22016) (xy 130.893523 -410.213017) (xy 130.900035 -410.195825)
			(xy 130.900424 -410.186632) (xy 130.900424 -409.693364) (xy 130.900026 -409.684176) (xy 130.893503 -409.666992)
			(xy 130.887724 -409.659836) (xy 130.865948 -409.634174) (xy 130.828 -409.578589) (xy 130.796967 -409.518866)
			(xy 130.773294 -409.455863) (xy 130.757321 -409.390482) (xy 130.749276 -409.323661) (xy 130.749275 -409.256357)
			(xy 130.757318 -409.189536) (xy 130.773289 -409.124154) (xy 130.79696 -409.06115) (xy 130.827991 -409.001427)
			(xy 130.865937 -408.94584) (xy 130.887724 -408.920188) (xy 130.893511 -408.913036) (xy 130.900031 -408.895851)
			(xy 130.900424 -408.88666) (xy 130.900424 -408.728672) (xy 130.900799 -408.718513) (xy 130.908608 -408.699755)
			(xy 130.92302 -408.685432) (xy 130.941825 -408.677738) (xy 130.951986 -408.677364) (xy 131.668266 -408.677364)
			(xy 131.678393 -408.677855) (xy 131.697118 -408.685576) (xy 131.711477 -408.699862) (xy 131.719293 -408.718547)
			(xy 131.719828 -408.728672) (xy 131.719828 -408.88666) (xy 131.720251 -408.895846) (xy 131.726755 -408.913031)
			(xy 131.732528 -408.920188) (xy 131.754328 -408.94583) (xy 131.792279 -409.001417) (xy 131.823314 -409.061142)
			(xy 131.846987 -409.124148) (xy 131.86296 -409.189532) (xy 131.871004 -409.256356) (xy 131.871003 -409.323662)
			(xy 131.862957 -409.390486) (xy 131.846982 -409.45587) (xy 131.823306 -409.518875) (xy 131.79227 -409.578598)
			(xy 131.754317 -409.634184) (xy 131.732528 -409.659836) (xy 131.726725 -409.666976) (xy 131.720216 -409.684171)
			(xy 131.719828 -409.693364) (xy 131.719828 -410.186632) (xy 131.720217 -410.195822) (xy 131.726745 -410.213006)
			(xy 131.732528 -410.22016) (xy 131.754301 -410.245825) (xy 131.792252 -410.301409) (xy 131.823288 -410.36113)
			(xy 131.846963 -410.424133) (xy 131.862938 -410.489514) (xy 131.870984 -410.556336) (xy 131.870986 -410.62364)
			(xy 131.862943 -410.690462) (xy 131.84697 -410.755844) (xy 131.823298 -410.818848) (xy 131.792265 -410.878571)
			(xy 131.754316 -410.934156) (xy 131.732528 -410.959808) (xy 131.726737 -410.966957) (xy 131.720221 -410.984145)
			(xy 131.719828 -410.993336) (xy 131.719828 -411.151324) (xy 131.719399 -411.161476) (xy 131.7116 -411.180224)
			(xy 131.697207 -411.194545) (xy 131.67842 -411.202249) (xy 131.668266 -411.202632) (xy 130.951986 -411.202632)
			(xy 130.941855 -411.202184) (xy 130.923128 -411.194446) (xy 130.908772 -411.180148) (xy 130.900958 -411.161453)
			(xy 130.900424 -411.151324) (xy 130.900424 -410.993336) (xy 130.899991 -410.984151) (xy 130.893493 -410.966967)
			(xy 130.887724 -410.959808) (xy 130.865921 -410.934169) (xy 130.827974 -410.87858) (xy 130.796942 -410.818855)
			(xy 130.773271 -410.755848) (xy 130.757299 -410.690465) (xy 130.749257 -410.623641) (xy 127.471193 -410.623641)
			(xy 127.471193 -410.623699) (xy 127.463119 -410.690635) (xy 127.447087 -410.756123) (xy 127.423326 -410.819219)
			(xy 127.392179 -410.879015) (xy 127.354094 -410.93465) (xy 127.332232 -410.960316) (xy 127.326438 -410.967463)
			(xy 127.319924 -410.984652) (xy 127.319532 -410.993844) (xy 127.319532 -411.151324) (xy 127.319035 -411.16143)
			(xy 127.311296 -411.180103) (xy 127.297003 -411.194396) (xy 127.27833 -411.202135) (xy 127.268224 -411.202632)
			(xy 126.551944 -411.202632) (xy 126.541828 -411.202149) (xy 126.523132 -411.194421) (xy 126.508817 -411.180125)
			(xy 126.501065 -411.161439) (xy 126.500636 -411.151324) (xy 126.500636 -410.993844) (xy 126.500196 -410.98466)
			(xy 126.493702 -410.967476) (xy 126.487936 -410.960316) (xy 126.466055 -410.934664) (xy 126.427964 -410.879029)
			(xy 126.396812 -410.819231) (xy 126.373048 -410.756132) (xy 126.357012 -410.690641) (xy 126.348937 -410.623701)
			(xy 123.070891 -410.623701) (xy 123.062855 -410.690462) (xy 123.046883 -410.755843) (xy 123.023211 -410.818847)
			(xy 122.992179 -410.87857) (xy 122.954231 -410.934156) (xy 122.932444 -410.959808) (xy 122.926655 -410.966958)
			(xy 122.920137 -410.984145) (xy 122.919744 -410.993336) (xy 122.919744 -411.151324) (xy 122.919236 -411.161429)
			(xy 122.911498 -411.180099) (xy 122.897209 -411.194392) (xy 122.878541 -411.202133) (xy 122.868436 -411.202632)
			(xy 122.151902 -411.202632) (xy 122.141772 -411.202171) (xy 122.123046 -411.194439) (xy 122.108688 -411.180144)
			(xy 122.100874 -411.161452) (xy 122.10034 -411.151324) (xy 122.10034 -410.993336) (xy 122.099903 -410.984152)
			(xy 122.093407 -410.966968) (xy 122.08764 -410.959808) (xy 122.065836 -410.934169) (xy 122.027888 -410.878581)
			(xy 121.996855 -410.818855) (xy 121.973183 -410.755849) (xy 121.957211 -410.690465) (xy 121.949169 -410.623641)
			(xy 118.67113 -410.623641) (xy 118.67113 -410.6237) (xy 118.663055 -410.690638) (xy 118.647019 -410.756127)
			(xy 118.623255 -410.819223) (xy 118.592103 -410.879018) (xy 118.554013 -410.934652) (xy 118.532148 -410.960316)
			(xy 118.526356 -410.967464) (xy 118.51984 -410.984653) (xy 118.519448 -410.993844) (xy 118.519448 -411.151324)
			(xy 118.518936 -411.161428) (xy 118.511199 -411.180098) (xy 118.496911 -411.19439) (xy 118.478244 -411.202133)
			(xy 118.46814 -411.202632) (xy 117.75186 -411.202632) (xy 117.741753 -411.202148) (xy 117.72308 -411.194404)
			(xy 117.708787 -411.180107) (xy 117.701048 -411.161431) (xy 117.700552 -411.151324) (xy 117.700552 -410.993844)
			(xy 117.700109 -410.984661) (xy 117.693617 -410.967477) (xy 117.687852 -410.960316) (xy 117.66597 -410.934665)
			(xy 117.627879 -410.879029) (xy 117.596726 -410.819232) (xy 117.57296 -410.756133) (xy 117.556924 -410.690642)
			(xy 117.548849 -410.623701) (xy 92.270837 -410.623701) (xy 92.262802 -410.69046) (xy 92.246832 -410.755841)
			(xy 92.223163 -410.818845) (xy 92.192134 -410.878568) (xy 92.154189 -410.934155) (xy 92.132404 -410.959808)
			(xy 92.126622 -410.966964) (xy 92.120098 -410.984146) (xy 92.119704 -410.993336) (xy 92.119704 -411.151324)
			(xy 92.119298 -411.161479) (xy 92.111495 -411.180231) (xy 92.097094 -411.194554) (xy 92.078299 -411.202253)
			(xy 92.068142 -411.202632) (xy 91.351862 -411.202632) (xy 91.341729 -411.202204) (xy 91.323002 -411.194458)
			(xy 91.308646 -411.180154) (xy 91.300833 -411.161455) (xy 91.3003 -411.151324) (xy 91.3003 -410.993336)
			(xy 91.299873 -410.984151) (xy 91.293371 -410.966966) (xy 91.2876 -410.959808) (xy 91.265798 -410.934168)
			(xy 91.227852 -410.878579) (xy 91.196822 -410.818853) (xy 91.173151 -410.755847) (xy 91.157181 -410.690464)
			(xy 91.149138 -410.623641) (xy 87.871075 -410.623641) (xy 87.871075 -410.623699) (xy 87.863001 -410.690636)
			(xy 87.846967 -410.756124) (xy 87.823205 -410.81922) (xy 87.792057 -410.879016) (xy 87.753971 -410.934651)
			(xy 87.732108 -410.960316) (xy 87.726323 -410.96747) (xy 87.719801 -410.984654) (xy 87.719408 -410.993844)
			(xy 87.719408 -411.151324) (xy 87.718935 -411.161433) (xy 87.711191 -411.180111) (xy 87.69689 -411.194404)
			(xy 87.67821 -411.20214) (xy 87.6681 -411.202632) (xy 86.95182 -411.202632) (xy 86.941716 -411.202099)
			(xy 86.923045 -411.194374) (xy 86.90875 -411.180092) (xy 86.901009 -411.161427) (xy 86.900512 -411.151324)
			(xy 86.900512 -410.993844) (xy 86.900078 -410.984659) (xy 86.893581 -410.967475) (xy 86.887812 -410.960316)
			(xy 86.865932 -410.934664) (xy 86.827843 -410.879028) (xy 86.796692 -410.81923) (xy 86.772928 -410.756131)
			(xy 86.756894 -410.69064) (xy 86.748819 -410.623701) (xy 83.470773 -410.623701) (xy 83.462736 -410.690462)
			(xy 83.446764 -410.755844) (xy 83.423091 -410.818848) (xy 83.392058 -410.878571) (xy 83.354108 -410.934156)
			(xy 83.33232 -410.959808) (xy 83.32654 -410.966965) (xy 83.320015 -410.984146) (xy 83.31962 -410.993336)
			(xy 83.31962 -411.151324) (xy 83.319199 -411.161477) (xy 83.311399 -411.180226) (xy 83.297003 -411.194548)
			(xy 83.278213 -411.202251) (xy 83.268058 -411.202632) (xy 82.551778 -411.202632) (xy 82.541646 -411.202191)
			(xy 82.522919 -411.194451) (xy 82.508563 -411.18015) (xy 82.500749 -411.161454) (xy 82.500216 -411.151324)
			(xy 82.500216 -410.993336) (xy 82.499785 -410.984151) (xy 82.493285 -410.966967) (xy 82.487516 -410.959808)
			(xy 82.465713 -410.934169) (xy 82.427766 -410.87858) (xy 82.396735 -410.818854) (xy 82.373064 -410.755848)
			(xy 82.357093 -410.690465) (xy 82.349051 -410.623641) (xy 79.070987 -410.623641) (xy 79.070987 -410.623699)
			(xy 79.062913 -410.690636) (xy 79.04688 -410.756124) (xy 79.023119 -410.81922) (xy 78.991971 -410.879016)
			(xy 78.953886 -410.93465) (xy 78.932024 -410.960316) (xy 78.926241 -410.967471) (xy 78.919717 -410.984654)
			(xy 78.919324 -410.993844) (xy 78.919324 -411.151324) (xy 78.918835 -411.161431) (xy 78.911094 -411.180106)
			(xy 78.896799 -411.194399) (xy 78.878123 -411.202137) (xy 78.868016 -411.202632) (xy 78.151736 -411.202632)
			(xy 78.14162 -411.202155) (xy 78.122923 -411.194425) (xy 78.108609 -411.180127) (xy 78.100857 -411.16144)
			(xy 78.100428 -411.151324) (xy 78.100428 -410.993844) (xy 78.09999 -410.98466) (xy 78.093495 -410.967476)
			(xy 78.087728 -410.960316) (xy 78.065847 -410.934664) (xy 78.027757 -410.879028) (xy 77.996606 -410.819231)
			(xy 77.972841 -410.756132) (xy 77.956806 -410.690641) (xy 77.948731 -410.623701) (xy 74.670685 -410.623701)
			(xy 74.662649 -410.690462) (xy 74.646677 -410.755844) (xy 74.623005 -410.818848) (xy 74.591972 -410.87857)
			(xy 74.554023 -410.934156) (xy 74.532236 -410.959808) (xy 74.526446 -410.966957) (xy 74.519929 -410.984145)
			(xy 74.519536 -410.993336) (xy 74.519536 -411.151324) (xy 74.519099 -411.161475) (xy 74.511302 -411.180221)
			(xy 74.496911 -411.194542) (xy 74.478127 -411.202248) (xy 74.467974 -411.202632) (xy 73.751694 -411.202632)
			(xy 73.741563 -411.202177) (xy 73.722837 -411.194442) (xy 73.70848 -411.180146) (xy 73.700666 -411.161452)
			(xy 73.700132 -411.151324) (xy 73.700132 -410.993336) (xy 73.699697 -410.984152) (xy 73.6932 -410.966967)
			(xy 73.687432 -410.959808) (xy 73.665629 -410.934169) (xy 73.627681 -410.87858) (xy 73.596649 -410.818855)
			(xy 73.572977 -410.755849) (xy 73.557005 -410.690465) (xy 73.548963 -410.623641) (xy 66.525648 -410.623641)
			(xy 66.525648 -417.289488) (xy 66.525648 -417.371276) (xy 141.02334 -417.371276) (xy 141.02334 -394.305282)
			(xy 141.023796 -394.293166) (xy 141.031289 -394.270122) (xy 141.045535 -394.25052) (xy 141.06514 -394.23628)
			(xy 141.088186 -394.228793) (xy 141.100302 -394.22832) (xy 154.426158 -394.22832) (xy 154.57678 -394.378688)
			(xy 154.57678 -397.823825) (xy 159.349135 -397.823825) (xy 159.349138 -397.756518) (xy 159.357186 -397.689693)
			(xy 159.373162 -397.624309) (xy 159.396838 -397.561303) (xy 159.427875 -397.501578) (xy 159.465827 -397.44599)
			(xy 159.487616 -397.420338) (xy 159.493423 -397.4132) (xy 159.499931 -397.396004) (xy 159.500316 -397.38681)
			(xy 159.500316 -396.893542) (xy 159.499882 -396.884357) (xy 159.493384 -396.867173) (xy 159.487616 -396.860014)
			(xy 159.465819 -396.83437) (xy 159.427872 -396.778782) (xy 159.396841 -396.719057) (xy 159.373169 -396.656051)
			(xy 159.357198 -396.590668) (xy 159.349155 -396.523845) (xy 159.349156 -396.45654) (xy 159.3572 -396.389717)
			(xy 159.373174 -396.324334) (xy 159.396847 -396.26133) (xy 159.42788 -396.201606) (xy 159.465828 -396.146018)
			(xy 159.487616 -396.120366) (xy 159.493411 -396.11322) (xy 159.499926 -396.09603) (xy 159.500316 -396.086838)
			(xy 159.500316 -395.92885) (xy 159.500804 -395.918684) (xy 159.508569 -395.899895) (xy 159.522934 -395.885509)
			(xy 159.541713 -395.877718) (xy 159.551878 -395.877288) (xy 160.268158 -395.877288) (xy 160.278333 -395.877699)
			(xy 160.297136 -395.88548) (xy 160.311525 -395.89987) (xy 160.319302 -395.918675) (xy 160.31972 -395.92885)
			(xy 160.31972 -396.086838) (xy 160.320108 -396.096028) (xy 160.326637 -396.113212) (xy 160.33242 -396.120366)
			(xy 160.354199 -396.146026) (xy 160.392151 -396.20161) (xy 160.423187 -396.261332) (xy 160.446862 -396.324336)
			(xy 160.462837 -396.389718) (xy 160.470882 -396.45654) (xy 160.470883 -396.523845) (xy 160.46284 -396.590668)
			(xy 160.446866 -396.65605) (xy 160.423193 -396.719054) (xy 160.392159 -396.778777) (xy 160.354208 -396.834362)
			(xy 160.33242 -396.860014) (xy 160.326637 -396.867169) (xy 160.320114 -396.884352) (xy 160.31972 -396.893542)
			(xy 160.31972 -397.38681) (xy 160.320121 -397.395998) (xy 160.326641 -397.413183) (xy 160.33242 -397.420338)
			(xy 160.354172 -397.44602) (xy 160.392124 -397.501601) (xy 160.420549 -397.556296) (xy 161.5488 -397.556296)
			(xy 161.556874 -397.489359) (xy 161.572908 -397.423871) (xy 161.596669 -397.360775) (xy 161.627817 -397.300979)
			(xy 161.665902 -397.245344) (xy 161.687764 -397.219678) (xy 161.69356 -397.212533) (xy 161.700073 -397.195342)
			(xy 161.700464 -397.18615) (xy 161.700464 -397.028924) (xy 161.701004 -397.018821) (xy 161.708727 -397.00015)
			(xy 161.723007 -396.985856) (xy 161.74167 -396.978114) (xy 161.751772 -396.977616) (xy 162.468052 -396.977616)
			(xy 162.478173 -396.978056) (xy 162.496879 -396.985791) (xy 162.511195 -397.000101) (xy 162.51894 -397.018803)
			(xy 162.51936 -397.028924) (xy 162.51936 -397.18615) (xy 162.519803 -397.195333) (xy 162.526295 -397.212518)
			(xy 162.53206 -397.219678) (xy 162.553935 -397.245334) (xy 162.592026 -397.300969) (xy 162.623179 -397.360766)
			(xy 162.646944 -397.423864) (xy 162.66298 -397.489355) (xy 162.671056 -397.556295) (xy 162.671055 -397.62372)
			(xy 162.662977 -397.69066) (xy 162.64694 -397.75615) (xy 162.623173 -397.819247) (xy 162.620757 -397.823885)
			(xy 163.748903 -397.823885) (xy 163.748907 -397.756458) (xy 163.756987 -397.689517) (xy 163.773027 -397.624026)
			(xy 163.796796 -397.560927) (xy 163.827951 -397.50113) (xy 163.866045 -397.445495) (xy 163.887912 -397.41983)
			(xy 163.893722 -397.412694) (xy 163.900228 -397.395497) (xy 163.900612 -397.386302) (xy 163.900612 -396.89405)
			(xy 163.900175 -396.884866) (xy 163.89368 -396.867681) (xy 163.887912 -396.860522) (xy 163.866038 -396.834865)
			(xy 163.827949 -396.77923) (xy 163.796798 -396.719432) (xy 163.773034 -396.656334) (xy 163.756998 -396.590844)
			(xy 163.748923 -396.523905) (xy 163.748924 -396.45648) (xy 163.757001 -396.389541) (xy 163.773038 -396.324051)
			(xy 163.796804 -396.260954) (xy 163.827956 -396.201157) (xy 163.866047 -396.145523) (xy 163.887912 -396.119858)
			(xy 163.89371 -396.112714) (xy 163.900224 -396.095523) (xy 163.900612 -396.08633) (xy 163.900612 -395.92885)
			(xy 163.901167 -395.91873) (xy 163.908873 -395.900015) (xy 163.923138 -395.885658) (xy 163.941803 -395.877832)
			(xy 163.95192 -395.877288) (xy 164.6682 -395.877288) (xy 164.678353 -395.877721) (xy 164.697103 -395.885515)
			(xy 164.711426 -395.899908) (xy 164.719127 -395.918695) (xy 164.719508 -395.92885) (xy 164.719508 -396.08633)
			(xy 164.719902 -396.095519) (xy 164.726426 -396.112703) (xy 164.732208 -396.119858) (xy 164.754062 -396.145531)
			(xy 164.79215 -396.201165) (xy 164.823301 -396.26096) (xy 164.847065 -396.324056) (xy 164.863101 -396.389544)
			(xy 164.871178 -396.456481) (xy 164.871179 -396.523904) (xy 164.863104 -396.590841) (xy 164.84707 -396.65633)
			(xy 164.823307 -396.719426) (xy 164.792158 -396.779222) (xy 164.754071 -396.834857) (xy 164.732208 -396.860522)
			(xy 164.726421 -396.867674) (xy 164.7199 -396.884859) (xy 164.719508 -396.89405) (xy 164.719508 -397.386302)
			(xy 164.719915 -397.395489) (xy 164.726431 -397.412674) (xy 164.732208 -397.41983) (xy 164.754034 -397.445526)
			(xy 164.792124 -397.501156) (xy 164.823276 -397.560948) (xy 164.846898 -397.62366) (xy 165.949096 -397.62366)
			(xy 165.949096 -397.556355) (xy 165.957139 -397.489533) (xy 165.973111 -397.424151) (xy 165.996783 -397.361147)
			(xy 166.027816 -397.301424) (xy 166.065765 -397.245838) (xy 166.087552 -397.220186) (xy 166.093343 -397.213037)
			(xy 166.09986 -397.195849) (xy 166.100252 -397.186658) (xy 166.100252 -397.028924) (xy 166.10074 -397.018777)
			(xy 166.108519 -397.000035) (xy 166.122895 -396.985712) (xy 166.141666 -396.978003) (xy 166.151814 -396.977616)
			(xy 166.868094 -396.977616) (xy 166.878217 -396.978131) (xy 166.896934 -396.985852) (xy 166.911289 -397.000129)
			(xy 166.919113 -397.018803) (xy 166.919656 -397.028924) (xy 166.919656 -397.186658) (xy 166.920096 -397.195842)
			(xy 166.92659 -397.213026) (xy 166.932356 -397.220186) (xy 166.954154 -397.24583) (xy 166.992103 -397.301417)
			(xy 167.023136 -397.361142) (xy 167.046808 -397.424148) (xy 167.062781 -397.489531) (xy 167.070824 -397.556355)
			(xy 167.070823 -397.62366) (xy 167.062778 -397.690484) (xy 167.046804 -397.755867) (xy 167.02313 -397.818872)
			(xy 167.020556 -397.823825) (xy 168.149223 -397.823825) (xy 168.149226 -397.756518) (xy 168.157274 -397.689693)
			(xy 168.17325 -397.624309) (xy 168.196925 -397.561304) (xy 168.22796 -397.501579) (xy 168.265911 -397.445991)
			(xy 168.2877 -397.420338) (xy 168.293505 -397.413199) (xy 168.300015 -397.396004) (xy 168.3004 -397.38681)
			(xy 168.3004 -396.893542) (xy 168.29997 -396.884357) (xy 168.29347 -396.867172) (xy 168.2877 -396.860014)
			(xy 168.265904 -396.834369) (xy 168.227958 -396.778781) (xy 168.196927 -396.719056) (xy 168.173256 -396.656051)
			(xy 168.157285 -396.590668) (xy 168.149243 -396.523845) (xy 168.149244 -396.45654) (xy 168.157288 -396.389717)
			(xy 168.173261 -396.324335) (xy 168.196933 -396.26133) (xy 168.227965 -396.201606) (xy 168.265913 -396.146019)
			(xy 168.2877 -396.120366) (xy 168.293494 -396.113219) (xy 168.30001 -396.09603) (xy 168.3004 -396.086838)
			(xy 168.3004 -395.92885) (xy 168.300904 -395.918686) (xy 168.308665 -395.8999) (xy 168.323026 -395.885515)
			(xy 168.341799 -395.877721) (xy 168.351962 -395.877288) (xy 169.068242 -395.877288) (xy 169.078423 -395.877631)
			(xy 169.097228 -395.885439) (xy 169.111613 -395.89985) (xy 169.119388 -395.918669) (xy 169.119804 -395.92885)
			(xy 169.119804 -396.086838) (xy 169.120195 -396.096027) (xy 169.126722 -396.113212) (xy 169.132504 -396.120366)
			(xy 169.154281 -396.146027) (xy 169.192227 -396.201613) (xy 169.223258 -396.261336) (xy 169.24693 -396.324339)
			(xy 169.262902 -396.38972) (xy 169.270946 -396.456541) (xy 169.270947 -396.523844) (xy 169.262905 -396.590665)
			(xy 169.246934 -396.656047) (xy 169.223264 -396.71905) (xy 169.192235 -396.778774) (xy 169.15429 -396.834361)
			(xy 169.132504 -396.860014) (xy 169.126719 -396.867168) (xy 169.120197 -396.884352) (xy 169.119804 -396.893542)
			(xy 169.119804 -397.38681) (xy 169.120209 -397.395998) (xy 169.126726 -397.413182) (xy 169.132504 -397.420338)
			(xy 169.154253 -397.446021) (xy 169.1922 -397.501604) (xy 169.22062 -397.556296) (xy 170.348863 -397.556296)
			(xy 170.356939 -397.489357) (xy 170.372975 -397.423868) (xy 170.39674 -397.360771) (xy 170.427892 -397.300976)
			(xy 170.465983 -397.245342) (xy 170.487848 -397.219678) (xy 170.493642 -397.212531) (xy 170.500157 -397.195342)
			(xy 170.500548 -397.18615) (xy 170.500548 -397.028924) (xy 170.501103 -397.018823) (xy 170.508823 -397.000155)
			(xy 170.523098 -396.985862) (xy 170.541756 -396.978117) (xy 170.551856 -396.977616) (xy 171.268136 -396.977616)
			(xy 171.278249 -396.978056) (xy 171.296931 -396.985808) (xy 171.311225 -397.000119) (xy 171.318956 -397.01881)
			(xy 171.319444 -397.028924) (xy 171.319444 -397.18615) (xy 171.319891 -397.195333) (xy 171.326381 -397.212517)
			(xy 171.332144 -397.219678) (xy 171.35402 -397.245334) (xy 171.392112 -397.300969) (xy 171.423265 -397.360766)
			(xy 171.447031 -397.423864) (xy 171.463068 -397.489355) (xy 171.471144 -397.556295) (xy 171.471143 -397.62372)
			(xy 171.463065 -397.69066) (xy 171.447027 -397.756151) (xy 171.423259 -397.819248) (xy 171.420874 -397.823826)
			(xy 172.54899 -397.823826) (xy 172.548993 -397.756517) (xy 172.557042 -397.689691) (xy 172.57302 -397.624306)
			(xy 172.5967 -397.5613) (xy 172.62774 -397.501575) (xy 172.665697 -397.44599) (xy 172.687488 -397.420338)
			(xy 172.693292 -397.413198) (xy 172.699803 -397.396004) (xy 172.700188 -397.38681) (xy 172.700188 -396.893542)
			(xy 172.69976 -396.884357) (xy 172.693259 -396.867172) (xy 172.687488 -396.860014) (xy 172.665689 -396.834371)
			(xy 172.627737 -396.778784) (xy 172.596702 -396.71906) (xy 172.573027 -396.656054) (xy 172.557054 -396.59067)
			(xy 172.54901 -396.523846) (xy 172.54901 -396.456539) (xy 172.557056 -396.389715) (xy 172.573032 -396.324332)
			(xy 172.596708 -396.261327) (xy 172.627745 -396.201603) (xy 172.665698 -396.146018) (xy 172.687488 -396.120366)
			(xy 172.69328 -396.113218) (xy 172.699798 -396.09603) (xy 172.700188 -396.086838) (xy 172.700188 -395.92885)
			(xy 172.700606 -395.918675) (xy 172.708384 -395.899872) (xy 172.722772 -395.885484) (xy 172.741575 -395.877706)
			(xy 172.75175 -395.877288) (xy 173.46803 -395.877288) (xy 173.47821 -395.87764) (xy 173.497015 -395.885445)
			(xy 173.5114 -395.899852) (xy 173.519175 -395.91867) (xy 173.519592 -395.92885) (xy 173.519592 -396.086838)
			(xy 173.519986 -396.096027) (xy 173.526511 -396.113211) (xy 173.532292 -396.120366) (xy 173.554069 -396.146027)
			(xy 173.592016 -396.201613) (xy 173.623048 -396.261335) (xy 173.64672 -396.324339) (xy 173.662693 -396.389719)
			(xy 173.670737 -396.456541) (xy 173.670738 -396.523844) (xy 173.662695 -396.590666) (xy 173.646725 -396.656047)
			(xy 173.623054 -396.719051) (xy 173.592024 -396.778774) (xy 173.554078 -396.834361) (xy 173.532292 -396.860014)
			(xy 173.526506 -396.867167) (xy 173.519985 -396.884351) (xy 173.519592 -396.893542) (xy 173.519592 -397.38681)
			(xy 173.519999 -397.395998) (xy 173.526515 -397.413182) (xy 173.532292 -397.420338) (xy 173.554041 -397.446021)
			(xy 173.591989 -397.501604) (xy 173.620441 -397.556355) (xy 174.749183 -397.556355) (xy 174.757226 -397.489534)
			(xy 174.773198 -397.424152) (xy 174.796869 -397.361148) (xy 174.827901 -397.301424) (xy 174.865849 -397.245838)
			(xy 174.887636 -397.220186) (xy 174.893426 -397.213036) (xy 174.899944 -397.195849) (xy 174.900336 -397.186658)
			(xy 174.900336 -397.028924) (xy 174.900742 -397.018767) (xy 174.908536 -397.000008) (xy 174.922939 -396.985682)
			(xy 174.941739 -396.977988) (xy 174.951898 -396.977616) (xy 175.668178 -396.977616) (xy 175.6783 -396.978144)
			(xy 175.697017 -396.98586) (xy 175.711373 -397.000133) (xy 175.719197 -397.018805) (xy 175.71974 -397.028924)
			(xy 175.71974 -397.186658) (xy 175.720184 -397.195841) (xy 175.726675 -397.213025) (xy 175.73244 -397.220186)
			(xy 175.754238 -397.24583) (xy 175.792188 -397.301417) (xy 175.823222 -397.361142) (xy 175.846895 -397.424147)
			(xy 175.862868 -397.489531) (xy 175.870912 -397.556354) (xy 175.870911 -397.623661) (xy 175.862865 -397.690484)
			(xy 175.846891 -397.755867) (xy 175.823216 -397.818872) (xy 175.79218 -397.878596) (xy 175.754229 -397.934182)
			(xy 175.73244 -397.959834) (xy 175.726639 -397.966976) (xy 175.720129 -397.984169) (xy 175.71974 -397.993362)
			(xy 175.71974 -398.486884) (xy 175.720171 -398.496069) (xy 175.726672 -398.513253) (xy 175.73244 -398.520412)
			(xy 175.754264 -398.546035) (xy 175.792213 -398.601625) (xy 175.823246 -398.661352) (xy 175.846918 -398.724361)
			(xy 175.862889 -398.789747) (xy 175.87093 -398.856573) (xy 175.870927 -398.923881) (xy 175.862879 -398.990707)
			(xy 175.846902 -399.056091) (xy 175.823224 -399.119097) (xy 175.792185 -399.178822) (xy 175.754231 -399.234408)
			(xy 175.73244 -399.26006) (xy 175.726628 -399.267194) (xy 175.720124 -399.284393) (xy 175.71974 -399.293588)
			(xy 175.71974 -399.451576) (xy 175.71926 -399.461724) (xy 175.71148 -399.480468) (xy 175.697101 -399.494791)
			(xy 175.678327 -399.502498) (xy 175.668178 -399.502884) (xy 174.951898 -399.502884) (xy 174.941774 -399.502376)
			(xy 174.923058 -399.494652) (xy 174.908702 -399.480372) (xy 174.900879 -399.461697) (xy 174.900336 -399.451576)
			(xy 174.900336 -399.293588) (xy 174.899924 -399.284401) (xy 174.893411 -399.267217) (xy 174.887636 -399.26006)
			(xy 174.865884 -399.234379) (xy 174.827934 -399.178796) (xy 174.7969 -399.119077) (xy 174.773225 -399.056076)
			(xy 174.75725 -398.990697) (xy 174.749203 -398.923878) (xy 174.749199 -398.856576) (xy 174.75724 -398.789756)
			(xy 174.773209 -398.724376) (xy 174.796878 -398.661373) (xy 174.827906 -398.60165) (xy 174.865851 -398.546064)
			(xy 174.887636 -398.520412) (xy 174.893457 -398.513284) (xy 174.899956 -398.49608) (xy 174.900336 -398.486884)
			(xy 174.900336 -397.993362) (xy 174.899936 -397.984174) (xy 174.893414 -397.96699) (xy 174.887636 -397.959834)
			(xy 174.865858 -397.934174) (xy 174.827909 -397.878588) (xy 174.796876 -397.818866) (xy 174.773202 -397.755863)
			(xy 174.757229 -397.690481) (xy 174.749184 -397.62366) (xy 174.749183 -397.556355) (xy 173.620441 -397.556355)
			(xy 173.623023 -397.561324) (xy 173.646696 -397.624324) (xy 173.662671 -397.689702) (xy 173.670718 -397.756521)
			(xy 173.670721 -397.823822) (xy 173.662681 -397.890642) (xy 173.646713 -397.956021) (xy 173.623046 -398.019024)
			(xy 173.592019 -398.078747) (xy 173.554077 -398.134334) (xy 173.532292 -398.159986) (xy 173.526475 -398.167117)
			(xy 173.519973 -398.184318) (xy 173.519592 -398.193514) (xy 173.519592 -398.351502) (xy 173.519069 -398.361656)
			(xy 173.511299 -398.38042) (xy 173.496943 -398.394784) (xy 173.478184 -398.402563) (xy 173.46803 -398.403064)
			(xy 172.75175 -398.403064) (xy 172.741582 -398.402595) (xy 172.722789 -398.394827) (xy 172.708402 -398.380455)
			(xy 172.700615 -398.36167) (xy 172.700188 -398.351502) (xy 172.700188 -398.193514) (xy 172.699774 -398.184327)
			(xy 172.693263 -398.167143) (xy 172.687488 -398.159986) (xy 172.665661 -398.134365) (xy 172.627711 -398.078775)
			(xy 172.596676 -398.019048) (xy 172.573004 -397.956039) (xy 172.557032 -397.890653) (xy 172.54899 -397.823826)
			(xy 171.420874 -397.823826) (xy 171.392104 -397.879044) (xy 171.354011 -397.934678) (xy 171.332144 -397.960342)
			(xy 171.32634 -397.967482) (xy 171.319831 -397.984677) (xy 171.319444 -397.99387) (xy 171.319444 -398.486376)
			(xy 171.319878 -398.49556) (xy 171.326376 -398.512744) (xy 171.332144 -398.519904) (xy 171.354045 -398.545539)
			(xy 171.392137 -398.601177) (xy 171.423289 -398.660976) (xy 171.447054 -398.724077) (xy 171.463088 -398.789571)
			(xy 171.471162 -398.856513) (xy 171.471159 -398.923941) (xy 171.463078 -398.990883) (xy 171.447037 -399.056374)
			(xy 171.423267 -399.119473) (xy 171.392109 -399.17927) (xy 171.354012 -399.234904) (xy 171.332144 -399.260568)
			(xy 171.326329 -399.2677) (xy 171.319827 -399.284901) (xy 171.319444 -399.294096) (xy 171.319444 -399.451576)
			(xy 171.318896 -399.461678) (xy 171.311175 -399.480347) (xy 171.296897 -399.494641) (xy 171.278237 -399.502385)
			(xy 171.268136 -399.502884) (xy 170.551856 -399.502884) (xy 170.541742 -399.50245) (xy 170.52306 -399.494695)
			(xy 170.508766 -399.480383) (xy 170.501036 -399.46169) (xy 170.500548 -399.451576) (xy 170.500548 -399.294096)
			(xy 170.500129 -399.28491) (xy 170.49362 -399.267726) (xy 170.487848 -399.260568) (xy 170.466018 -399.234874)
			(xy 170.427925 -399.179245) (xy 170.39677 -399.119453) (xy 170.373001 -399.05636) (xy 170.356962 -398.990874)
			(xy 170.348883 -398.923938) (xy 170.348879 -398.856516) (xy 170.356952 -398.789579) (xy 170.372985 -398.724092)
			(xy 170.396748 -398.660996) (xy 170.427897 -398.601201) (xy 170.465984 -398.545568) (xy 170.487848 -398.519904)
			(xy 170.493631 -398.51275) (xy 170.500153 -398.495566) (xy 170.500548 -398.486376) (xy 170.500548 -397.99387)
			(xy 170.500141 -397.984683) (xy 170.493624 -397.967499) (xy 170.487848 -397.960342) (xy 170.465992 -397.934669)
			(xy 170.4279 -397.879037) (xy 170.396746 -397.819242) (xy 170.372979 -397.756146) (xy 170.356942 -397.690658)
			(xy 170.348864 -397.623719) (xy 170.348863 -397.556296) (xy 169.22062 -397.556296) (xy 169.223233 -397.561324)
			(xy 169.246906 -397.624324) (xy 169.26288 -397.689702) (xy 169.270927 -397.756521) (xy 169.27093 -397.823822)
			(xy 169.26289 -397.890641) (xy 169.246923 -397.956021) (xy 169.223256 -398.019024) (xy 169.19223 -398.078746)
			(xy 169.154288 -398.134333) (xy 169.132504 -398.159986) (xy 169.126689 -398.167118) (xy 169.120185 -398.184319)
			(xy 169.119804 -398.193514) (xy 169.119804 -398.351502) (xy 169.119269 -398.361655) (xy 169.111502 -398.380416)
			(xy 169.097149 -398.394779) (xy 169.078394 -398.402561) (xy 169.068242 -398.403064) (xy 168.351962 -398.403064)
			(xy 168.341802 -398.402598) (xy 168.323032 -398.394811) (xy 168.308669 -398.380437) (xy 168.300895 -398.361662)
			(xy 168.3004 -398.351502) (xy 168.3004 -398.193514) (xy 168.299983 -398.184328) (xy 168.293474 -398.167143)
			(xy 168.2877 -398.159986) (xy 168.265876 -398.134364) (xy 168.227931 -398.078772) (xy 168.196902 -398.019044)
			(xy 168.173233 -397.956036) (xy 168.157263 -397.89065) (xy 168.149223 -397.823825) (xy 167.020556 -397.823825)
			(xy 166.992095 -397.878596) (xy 166.954145 -397.934182) (xy 166.932356 -397.959834) (xy 166.926557 -397.966977)
			(xy 166.920045 -397.984169) (xy 166.919656 -397.993362) (xy 166.919656 -398.486884) (xy 166.920084 -398.496069)
			(xy 166.926586 -398.513253) (xy 166.932356 -398.520412) (xy 166.954179 -398.546035) (xy 166.992127 -398.601625)
			(xy 167.023159 -398.661353) (xy 167.04683 -398.724361) (xy 167.062801 -398.789747) (xy 167.070842 -398.856573)
			(xy 167.070839 -398.923881) (xy 167.062791 -398.990706) (xy 167.046814 -399.05609) (xy 167.023137 -399.119097)
			(xy 166.9921 -399.178821) (xy 166.954146 -399.234408) (xy 166.932356 -399.26006) (xy 166.926546 -399.267195)
			(xy 166.92004 -399.284394) (xy 166.919656 -399.293588) (xy 166.919656 -399.451576) (xy 166.91916 -399.461722)
			(xy 166.911383 -399.480463) (xy 166.89701 -399.494785) (xy 166.878241 -399.502496) (xy 166.868094 -399.502884)
			(xy 166.151814 -399.502884) (xy 166.141691 -399.502363) (xy 166.122975 -399.494644) (xy 166.108619 -399.480369)
			(xy 166.100795 -399.461696) (xy 166.100252 -399.451576) (xy 166.100252 -399.293588) (xy 166.099836 -399.284402)
			(xy 166.093325 -399.267218) (xy 166.087552 -399.26006) (xy 166.065799 -399.234379) (xy 166.027849 -399.178797)
			(xy 165.996813 -399.119077) (xy 165.973138 -399.056077) (xy 165.957162 -398.990698) (xy 165.949115 -398.923878)
			(xy 165.949111 -398.856576) (xy 165.957152 -398.789755) (xy 165.973122 -398.724375) (xy 165.996791 -398.661372)
			(xy 166.027821 -398.60165) (xy 166.065766 -398.546064) (xy 166.087552 -398.520412) (xy 166.093375 -398.513286)
			(xy 166.099872 -398.49608) (xy 166.100252 -398.486884) (xy 166.100252 -397.993362) (xy 166.099848 -397.984174)
			(xy 166.093329 -397.966991) (xy 166.087552 -397.959834) (xy 166.065774 -397.934174) (xy 166.027824 -397.878589)
			(xy 165.99679 -397.818866) (xy 165.973116 -397.755863) (xy 165.957142 -397.690482) (xy 165.949096 -397.62366)
			(xy 164.846898 -397.62366) (xy 164.847042 -397.624041) (xy 164.863079 -397.689526) (xy 164.871158 -397.756461)
			(xy 164.871162 -397.823882) (xy 164.86309 -397.890817) (xy 164.847058 -397.956304) (xy 164.823299 -398.019399)
			(xy 164.792153 -398.079195) (xy 164.754069 -398.134829) (xy 164.732208 -398.160494) (xy 164.726432 -398.167654)
			(xy 164.719905 -398.184833) (xy 164.719508 -398.194022) (xy 164.719508 -398.351502) (xy 164.718976 -398.361623)
			(xy 164.711257 -398.380335) (xy 164.696985 -398.394689) (xy 164.678318 -398.402517) (xy 164.6682 -398.403064)
			(xy 163.95192 -398.403064) (xy 163.941763 -398.402661) (xy 163.923004 -398.394866) (xy 163.908678 -398.380462)
			(xy 163.900984 -398.361662) (xy 163.900612 -398.351502) (xy 163.900612 -398.194022) (xy 163.900188 -398.184836)
			(xy 163.893684 -398.167652) (xy 163.887912 -398.160494) (xy 163.86601 -398.13486) (xy 163.827922 -398.079221)
			(xy 163.796772 -398.019421) (xy 163.77301 -397.95632) (xy 163.756976 -397.890827) (xy 163.748903 -397.823885)
			(xy 162.620757 -397.823885) (xy 162.592019 -397.879044) (xy 162.553926 -397.934677) (xy 162.53206 -397.960342)
			(xy 162.526258 -397.967483) (xy 162.519748 -397.984677) (xy 162.51936 -397.99387) (xy 162.51936 -398.486376)
			(xy 162.51979 -398.495561) (xy 162.526291 -398.512745) (xy 162.53206 -398.519904) (xy 162.553961 -398.545539)
			(xy 162.592051 -398.601177) (xy 162.623202 -398.660977) (xy 162.646966 -398.724078) (xy 162.663 -398.789571)
			(xy 162.671074 -398.856513) (xy 162.671071 -398.923941) (xy 162.662991 -398.990882) (xy 162.64695 -399.056374)
			(xy 162.62318 -399.119472) (xy 162.592023 -399.179269) (xy 162.553928 -399.234903) (xy 162.53206 -399.260568)
			(xy 162.526247 -399.267701) (xy 162.519743 -399.284901) (xy 162.51936 -399.294096) (xy 162.51936 -399.451576)
			(xy 162.518964 -399.461702) (xy 162.511216 -399.480413) (xy 162.496893 -399.494729) (xy 162.478178 -399.502468)
			(xy 162.468052 -399.502884) (xy 161.751772 -399.502884) (xy 161.741659 -399.502438) (xy 161.722978 -399.494688)
			(xy 161.708683 -399.480379) (xy 161.700952 -399.461689) (xy 161.700464 -399.451576) (xy 161.700464 -399.294096)
			(xy 161.700041 -399.28491) (xy 161.693535 -399.267727) (xy 161.687764 -399.260568) (xy 161.665937 -399.234873)
			(xy 161.627849 -399.179242) (xy 161.596699 -399.119449) (xy 161.572934 -399.056357) (xy 161.556897 -398.990871)
			(xy 161.548819 -398.923937) (xy 161.548816 -398.856517) (xy 161.556888 -398.789582) (xy 161.572918 -398.724095)
			(xy 161.596677 -398.661) (xy 161.627821 -398.601205) (xy 161.665903 -398.54557) (xy 161.687764 -398.519904)
			(xy 161.693549 -398.512751) (xy 161.700069 -398.495566) (xy 161.700464 -398.486376) (xy 161.700464 -397.99387)
			(xy 161.700054 -397.984683) (xy 161.693538 -397.9675) (xy 161.687764 -397.960342) (xy 161.665911 -397.934668)
			(xy 161.627824 -397.879034) (xy 161.596675 -397.819239) (xy 161.572912 -397.756143) (xy 161.556877 -397.690655)
			(xy 161.548801 -397.623719) (xy 161.5488 -397.556296) (xy 160.420549 -397.556296) (xy 160.423161 -397.561321)
			(xy 160.446838 -397.624321) (xy 160.462815 -397.6897) (xy 160.470863 -397.75652) (xy 160.470866 -397.823823)
			(xy 160.462825 -397.890644) (xy 160.446855 -397.956024) (xy 160.423185 -398.019027) (xy 160.392154 -398.078749)
			(xy 160.354207 -398.134334) (xy 160.33242 -398.159986) (xy 160.326607 -398.16712) (xy 160.320101 -398.184319)
			(xy 160.31972 -398.193514) (xy 160.31972 -398.351502) (xy 160.319337 -398.361679) (xy 160.311543 -398.380482)
			(xy 160.297145 -398.394868) (xy 160.278335 -398.402645) (xy 160.268158 -398.403064) (xy 159.551878 -398.403064)
			(xy 159.541719 -398.402585) (xy 159.52295 -398.394804) (xy 159.508585 -398.380433) (xy 159.500811 -398.361661)
			(xy 159.500316 -398.351502) (xy 159.500316 -398.193514) (xy 159.499895 -398.184328) (xy 159.493388 -398.167144)
			(xy 159.487616 -398.159986) (xy 159.465792 -398.134364) (xy 159.427845 -398.078773) (xy 159.396815 -398.019045)
			(xy 159.373145 -397.956036) (xy 159.357176 -397.890651) (xy 159.349135 -397.823825) (xy 154.57678 -397.823825)
			(xy 154.57678 -401.723737) (xy 159.349146 -401.723737) (xy 159.349148 -401.65643) (xy 159.357194 -401.589607)
			(xy 159.373169 -401.524223) (xy 159.396843 -401.461218) (xy 159.427878 -401.401494) (xy 159.465828 -401.345906)
			(xy 159.487616 -401.320254) (xy 159.493416 -401.313112) (xy 159.499928 -401.295919) (xy 159.500316 -401.286726)
			(xy 159.500316 -400.793458) (xy 159.499923 -400.784269) (xy 159.493397 -400.767085) (xy 159.487616 -400.75993)
			(xy 159.465835 -400.734273) (xy 159.427887 -400.678686) (xy 159.396855 -400.618963) (xy 159.373183 -400.55596)
			(xy 159.35721 -400.490578) (xy 159.349166 -400.423757) (xy 159.349165 -400.356452) (xy 159.357209 -400.289631)
			(xy 159.37318 -400.224249) (xy 159.396851 -400.161245) (xy 159.427883 -400.101521) (xy 159.465829 -400.045934)
			(xy 159.487616 -400.020282) (xy 159.493405 -400.013131) (xy 159.499923 -399.995945) (xy 159.500316 -399.986754)
			(xy 159.500316 -399.828766) (xy 159.500805 -399.818609) (xy 159.508586 -399.799843) (xy 159.522953 -399.78548)
			(xy 159.541721 -399.777703) (xy 159.551878 -399.777204) (xy 160.268158 -399.777204) (xy 160.278323 -399.777697)
			(xy 160.29711 -399.785462) (xy 160.311495 -399.799826) (xy 160.319288 -399.818602) (xy 160.31972 -399.828766)
			(xy 160.31972 -399.986754) (xy 160.320148 -399.995939) (xy 160.326649 -400.013124) (xy 160.33242 -400.020282)
			(xy 160.354215 -400.045929) (xy 160.392166 -400.101515) (xy 160.423201 -400.161239) (xy 160.446876 -400.224244)
			(xy 160.462849 -400.289628) (xy 160.470894 -400.356451) (xy 160.470893 -400.423758) (xy 160.462848 -400.490581)
			(xy 160.446873 -400.555964) (xy 160.423198 -400.618969) (xy 160.392161 -400.678693) (xy 160.354209 -400.734278)
			(xy 160.33242 -400.75993) (xy 160.326631 -400.76708) (xy 160.320111 -400.784267) (xy 160.31972 -400.793458)
			(xy 160.31972 -401.286726) (xy 160.320113 -401.295915) (xy 160.326638 -401.313099) (xy 160.33242 -401.320254)
			(xy 160.354187 -401.345923) (xy 160.392139 -401.401506) (xy 160.423176 -401.461227) (xy 160.446852 -401.52423)
			(xy 160.462827 -401.58961) (xy 160.470874 -401.656431) (xy 160.470876 -401.723735) (xy 160.462833 -401.790557)
			(xy 160.446862 -401.855939) (xy 160.423189 -401.918943) (xy 160.392156 -401.978665) (xy 160.354208 -402.03425)
			(xy 160.33242 -402.059902) (xy 160.326642 -402.067061) (xy 160.320116 -402.084241) (xy 160.31972 -402.09343)
			(xy 160.31972 -402.251418) (xy 160.31935 -402.261596) (xy 160.311551 -402.280399) (xy 160.297149 -402.294785)
			(xy 160.278336 -402.302562) (xy 160.268158 -402.30298) (xy 159.551878 -402.30298) (xy 159.541721 -402.302485)
			(xy 159.522955 -402.294707) (xy 159.508591 -402.280342) (xy 159.500814 -402.261575) (xy 159.500316 -402.251418)
			(xy 159.500316 -402.09343) (xy 159.499888 -402.084245) (xy 159.493386 -402.06706) (xy 159.487616 -402.059902)
			(xy 159.465807 -402.034267) (xy 159.427861 -401.978678) (xy 159.39683 -401.918952) (xy 159.373159 -401.855945)
			(xy 159.357188 -401.790561) (xy 159.349146 -401.723737) (xy 154.57678 -401.723737) (xy 154.57678 -402.823877)
			(xy 161.54876 -402.823877) (xy 161.548765 -402.756451) (xy 161.556845 -402.68951) (xy 161.572884 -402.624018)
			(xy 161.596652 -402.56092) (xy 161.627806 -402.501122) (xy 161.665898 -402.445486) (xy 161.687764 -402.41982)
			(xy 161.693585 -402.412692) (xy 161.700083 -402.395488) (xy 161.700464 -402.386292) (xy 161.700464 -401.89404)
			(xy 161.70002 -401.884857) (xy 161.693528 -401.867673) (xy 161.687764 -401.860512) (xy 161.665882 -401.834862)
			(xy 161.627796 -401.779225) (xy 161.596648 -401.719426) (xy 161.572887 -401.656327) (xy 161.556854 -401.590837)
			(xy 161.54878 -401.523897) (xy 161.548782 -401.456473) (xy 161.556859 -401.389534) (xy 161.572896 -401.324044)
			(xy 161.59666 -401.260946) (xy 161.627811 -401.201149) (xy 161.6659 -401.145514) (xy 161.687764 -401.119848)
			(xy 161.693573 -401.112712) (xy 161.700078 -401.095514) (xy 161.700464 -401.08632) (xy 161.700464 -400.92884)
			(xy 161.700948 -400.918725) (xy 161.708676 -400.900029) (xy 161.722972 -400.885714) (xy 161.741657 -400.877961)
			(xy 161.751772 -400.877532) (xy 162.468052 -400.877532) (xy 162.478175 -400.877956) (xy 162.496884 -400.885694)
			(xy 162.511201 -400.900009) (xy 162.518942 -400.918717) (xy 162.51936 -400.92884) (xy 162.51936 -401.08632)
			(xy 162.519769 -401.095507) (xy 162.526285 -401.112691) (xy 162.53206 -401.119848) (xy 162.553906 -401.145529)
			(xy 162.591998 -401.20116) (xy 162.623151 -401.260954) (xy 162.646919 -401.324049) (xy 162.662957 -401.389536)
			(xy 162.671035 -401.456474) (xy 162.671037 -401.523896) (xy 162.662962 -401.590834) (xy 162.646927 -401.656323)
			(xy 162.623164 -401.719419) (xy 162.620884 -401.723796) (xy 163.748915 -401.723796) (xy 163.748917 -401.656371)
			(xy 163.756995 -401.589431) (xy 163.773033 -401.52394) (xy 163.7968 -401.460842) (xy 163.827954 -401.401046)
			(xy 163.866046 -401.345411) (xy 163.887912 -401.319746) (xy 163.893715 -401.312606) (xy 163.900226 -401.295411)
			(xy 163.900612 -401.286218) (xy 163.900612 -400.793966) (xy 163.900216 -400.784777) (xy 163.893692 -400.767593)
			(xy 163.887912 -400.760438) (xy 163.866054 -400.734768) (xy 163.827964 -400.679135) (xy 163.796812 -400.619339)
			(xy 163.773047 -400.556243) (xy 163.757011 -400.490754) (xy 163.748934 -400.423816) (xy 163.748934 -400.356393)
			(xy 163.757009 -400.289455) (xy 163.773044 -400.223966) (xy 163.796809 -400.160869) (xy 163.827959 -400.101073)
			(xy 163.866048 -400.045439) (xy 163.887912 -400.019774) (xy 163.893703 -400.012625) (xy 163.900221 -399.995437)
			(xy 163.900612 -399.986246) (xy 163.900612 -399.828766) (xy 163.901098 -399.818641) (xy 163.908832 -399.799924)
			(xy 163.923117 -399.78557) (xy 163.941797 -399.777747) (xy 163.95192 -399.777204) (xy 164.6682 -399.777204)
			(xy 164.678355 -399.777622) (xy 164.697108 -399.785418) (xy 164.711431 -399.799816) (xy 164.71913 -399.818609)
			(xy 164.719508 -399.828766) (xy 164.719508 -399.986246) (xy 164.719942 -399.995431) (xy 164.726439 -400.012615)
			(xy 164.732208 -400.019774) (xy 164.754078 -400.045435) (xy 164.792166 -400.10107) (xy 164.823316 -400.160867)
			(xy 164.847079 -400.223964) (xy 164.863114 -400.289454) (xy 164.871189 -400.356393) (xy 164.871189 -400.423817)
			(xy 164.863112 -400.490755) (xy 164.847076 -400.556244) (xy 164.823312 -400.619341) (xy 164.792161 -400.679138)
			(xy 164.754072 -400.734773) (xy 164.732208 -400.760438) (xy 164.726414 -400.767585) (xy 164.719897 -400.784774)
			(xy 164.719508 -400.793966) (xy 164.719508 -401.286218) (xy 164.719908 -401.295406) (xy 164.726429 -401.312591)
			(xy 164.732208 -401.319746) (xy 164.75405 -401.345429) (xy 164.792139 -401.401061) (xy 164.82329 -401.460855)
			(xy 164.847055 -401.52395) (xy 164.863092 -401.589436) (xy 164.871169 -401.656373) (xy 164.871171 -401.723794)
			(xy 164.863098 -401.790731) (xy 164.847065 -401.856219) (xy 164.823304 -401.919315) (xy 164.792156 -401.97911)
			(xy 164.75407 -402.034745) (xy 164.732208 -402.06041) (xy 164.726426 -402.067565) (xy 164.719902 -402.084748)
			(xy 164.719508 -402.093938) (xy 164.719508 -402.251418) (xy 164.71899 -402.26154) (xy 164.711265 -402.280253)
			(xy 164.696989 -402.294607) (xy 164.678319 -402.302434) (xy 164.6682 -402.30298) (xy 163.95192 -402.30298)
			(xy 163.941765 -402.302562) (xy 163.923009 -402.294769) (xy 163.908684 -402.280371) (xy 163.900987 -402.261575)
			(xy 163.900612 -402.251418) (xy 163.900612 -402.093938) (xy 163.900181 -402.084753) (xy 163.893681 -402.067569)
			(xy 163.887912 -402.06041) (xy 163.866026 -402.034763) (xy 163.827937 -401.979126) (xy 163.796787 -401.919327)
			(xy 163.773023 -401.856228) (xy 163.756989 -401.790737) (xy 163.748915 -401.723796) (xy 162.620884 -401.723796)
			(xy 162.592013 -401.779214) (xy 162.553924 -401.834847) (xy 162.53206 -401.860512) (xy 162.526271 -401.867662)
			(xy 162.519753 -401.884849) (xy 162.51936 -401.89404) (xy 162.51936 -402.386292) (xy 162.519783 -402.395478)
			(xy 162.526289 -402.412662) (xy 162.53206 -402.41982) (xy 162.553878 -402.445523) (xy 162.591971 -402.501152)
			(xy 162.623126 -402.560942) (xy 162.646895 -402.624034) (xy 162.662935 -402.689519) (xy 162.671015 -402.756454)
			(xy 162.671019 -402.823818) (xy 165.949055 -402.823818) (xy 165.94906 -402.756509) (xy 165.957109 -402.689683)
			(xy 165.973087 -402.624298) (xy 165.996766 -402.561292) (xy 166.027805 -402.501567) (xy 166.065761 -402.44598)
			(xy 166.087552 -402.420328) (xy 166.093368 -402.413197) (xy 166.09987 -402.395995) (xy 166.100252 -402.3868)
			(xy 166.100252 -401.893532) (xy 166.099815 -401.884348) (xy 166.093319 -401.867164) (xy 166.087552 -401.860004)
			(xy 166.065744 -401.834368) (xy 166.027795 -401.77878) (xy 165.996762 -401.719054) (xy 165.97309 -401.656047)
			(xy 165.957118 -401.590663) (xy 165.949075 -401.523838) (xy 165.949077 -401.456532) (xy 165.957123 -401.389707)
			(xy 165.973098 -401.324324) (xy 165.996774 -401.261318) (xy 166.02781 -401.201594) (xy 166.065762 -401.146008)
			(xy 166.087552 -401.120356) (xy 166.093356 -401.113216) (xy 166.099865 -401.096021) (xy 166.100252 -401.086828)
			(xy 166.100252 -400.92884) (xy 166.100754 -400.918694) (xy 166.108527 -400.899952) (xy 166.122899 -400.885629)
			(xy 166.141667 -400.87792) (xy 166.151814 -400.877532) (xy 166.868094 -400.877532) (xy 166.878219 -400.878031)
			(xy 166.896939 -400.885756) (xy 166.911295 -400.900038) (xy 166.919116 -400.918717) (xy 166.919656 -400.92884)
			(xy 166.919656 -401.086828) (xy 166.920063 -401.096015) (xy 166.92658 -401.113199) (xy 166.932356 -401.120356)
			(xy 166.954124 -401.146024) (xy 166.992074 -401.201608) (xy 167.023108 -401.26133) (xy 167.046782 -401.324332)
			(xy 167.062757 -401.389712) (xy 167.070803 -401.456533) (xy 167.070804 -401.523837) (xy 167.062762 -401.590658)
			(xy 167.046791 -401.656039) (xy 167.02312 -401.719043) (xy 167.020682 -401.723736) (xy 168.149234 -401.723736)
			(xy 168.149236 -401.65643) (xy 168.157282 -401.589607) (xy 168.173256 -401.524224) (xy 168.19693 -401.461219)
			(xy 168.227963 -401.401494) (xy 168.265912 -401.345907) (xy 168.2877 -401.320254) (xy 168.293499 -401.31311)
			(xy 168.300012 -401.295919) (xy 168.3004 -401.286726) (xy 168.3004 -400.793458) (xy 168.30001 -400.784269)
			(xy 168.293482 -400.767084) (xy 168.2877 -400.75993) (xy 168.265919 -400.734272) (xy 168.227973 -400.678686)
			(xy 168.196942 -400.618963) (xy 168.17327 -400.555959) (xy 168.157298 -400.490578) (xy 168.149254 -400.423756)
			(xy 168.149253 -400.356453) (xy 168.157296 -400.289631) (xy 168.173267 -400.22425) (xy 168.196938 -400.161246)
			(xy 168.227968 -400.101522) (xy 168.265914 -400.045935) (xy 168.2877 -400.020282) (xy 168.293487 -400.01313)
			(xy 168.300007 -399.995945) (xy 168.3004 -399.986754) (xy 168.3004 -399.828766) (xy 168.300905 -399.818611)
			(xy 168.308683 -399.799848) (xy 168.323045 -399.785485) (xy 168.341807 -399.777705) (xy 168.351962 -399.777204)
			(xy 169.068242 -399.777204) (xy 169.078398 -399.777698) (xy 169.097162 -399.78548) (xy 169.111524 -399.799845)
			(xy 169.119303 -399.81861) (xy 169.119804 -399.828766) (xy 169.119804 -399.986754) (xy 169.120235 -399.995939)
			(xy 169.126734 -400.013124) (xy 169.132504 -400.020282) (xy 169.154296 -400.04593) (xy 169.192242 -400.101518)
			(xy 169.223273 -400.161243) (xy 169.246943 -400.224248) (xy 169.262915 -400.28963) (xy 169.270958 -400.356452)
			(xy 169.270957 -400.423757) (xy 169.262913 -400.490579) (xy 169.246941 -400.555961) (xy 169.223269 -400.618966)
			(xy 169.192237 -400.67869) (xy 169.154291 -400.734277) (xy 169.132504 -400.75993) (xy 169.126713 -400.767079)
			(xy 169.120195 -400.784267) (xy 169.119804 -400.793458) (xy 169.119804 -401.286726) (xy 169.1202 -401.295915)
			(xy 169.126723 -401.313099) (xy 169.132504 -401.320254) (xy 169.154269 -401.345925) (xy 169.192215 -401.401509)
			(xy 169.223247 -401.461231) (xy 169.246919 -401.524233) (xy 169.262893 -401.589612) (xy 169.270938 -401.656432)
			(xy 169.27094 -401.723735) (xy 169.262899 -401.790555) (xy 169.246929 -401.855936) (xy 169.223261 -401.918939)
			(xy 169.192232 -401.978662) (xy 169.154289 -402.034249) (xy 169.132504 -402.059902) (xy 169.126725 -402.067059)
			(xy 169.1202 -402.084241) (xy 169.119804 -402.09343) (xy 169.119804 -402.251418) (xy 169.119283 -402.261572)
			(xy 169.11151 -402.280333) (xy 169.097154 -402.294697) (xy 169.078396 -402.302478) (xy 169.068242 -402.30298)
			(xy 168.351962 -402.30298) (xy 168.341804 -402.302498) (xy 168.323037 -402.294715) (xy 168.308674 -402.280346)
			(xy 168.300898 -402.261576) (xy 168.3004 -402.251418) (xy 168.3004 -402.09343) (xy 168.299975 -402.084244)
			(xy 168.293472 -402.06706) (xy 168.2877 -402.059902) (xy 168.265892 -402.034267) (xy 168.227946 -401.978677)
			(xy 168.196916 -401.918951) (xy 168.173246 -401.855944) (xy 168.157276 -401.79056) (xy 168.149234 -401.723736)
			(xy 167.020682 -401.723736) (xy 166.992089 -401.778766) (xy 166.954142 -401.834352) (xy 166.932356 -401.860004)
			(xy 166.92657 -401.867156) (xy 166.92005 -401.884342) (xy 166.919656 -401.893532) (xy 166.919656 -402.3868)
			(xy 166.920076 -402.395986) (xy 166.926584 -402.41317) (xy 166.932356 -402.420328) (xy 166.954097 -402.446019)
			(xy 166.992047 -402.5016) (xy 167.023083 -402.561318) (xy 167.046758 -402.624317) (xy 167.062735 -402.689695)
			(xy 167.070783 -402.756513) (xy 167.070787 -402.823815) (xy 167.070779 -402.823878) (xy 170.348823 -402.823878)
			(xy 170.348828 -402.75645) (xy 170.356909 -402.689507) (xy 170.372951 -402.624015) (xy 170.396723 -402.560916)
			(xy 170.427882 -402.501119) (xy 170.465979 -402.445484) (xy 170.487848 -402.41982) (xy 170.493667 -402.412691)
			(xy 170.500167 -402.395488) (xy 170.500548 -402.386292) (xy 170.500548 -401.89404) (xy 170.500108 -401.884856)
			(xy 170.493614 -401.867672) (xy 170.487848 -401.860512) (xy 170.465963 -401.834864) (xy 170.427871 -401.779228)
			(xy 170.396719 -401.71943) (xy 170.372954 -401.656331) (xy 170.356918 -401.590839) (xy 170.348843 -401.523898)
			(xy 170.348845 -401.456472) (xy 170.356924 -401.389531) (xy 170.372963 -401.324041) (xy 170.396731 -401.260943)
			(xy 170.427887 -401.201146) (xy 170.465981 -401.145512) (xy 170.487848 -401.119848) (xy 170.493655 -401.112711)
			(xy 170.500162 -401.095514) (xy 170.500548 -401.08632) (xy 170.500548 -400.92884) (xy 170.501117 -400.91874)
			(xy 170.508832 -400.900073) (xy 170.523102 -400.885779) (xy 170.541757 -400.878033) (xy 170.551856 -400.877532)
			(xy 171.268136 -400.877532) (xy 171.278265 -400.877887) (xy 171.296975 -400.885653) (xy 171.311289 -400.899989)
			(xy 171.319028 -400.918711) (xy 171.319444 -400.92884) (xy 171.319444 -401.08632) (xy 171.319857 -401.095507)
			(xy 171.32637 -401.11269) (xy 171.332144 -401.119848) (xy 171.35399 -401.145528) (xy 171.392083 -401.20116)
			(xy 171.423238 -401.260953) (xy 171.447006 -401.324048) (xy 171.463044 -401.389536) (xy 171.471123 -401.456473)
			(xy 171.471124 -401.523897) (xy 171.46305 -401.590834) (xy 171.447015 -401.656323) (xy 171.42325 -401.719419)
			(xy 171.421001 -401.723737) (xy 172.549001 -401.723737) (xy 172.549003 -401.65643) (xy 172.55705 -401.589605)
			(xy 172.573027 -401.524221) (xy 172.596704 -401.461215) (xy 172.627743 -401.401491) (xy 172.665697 -401.345906)
			(xy 172.687488 -401.320254) (xy 172.693285 -401.313109) (xy 172.6998 -401.295918) (xy 172.700188 -401.286726)
			(xy 172.700188 -400.793458) (xy 172.699801 -400.784268) (xy 172.693272 -400.767084) (xy 172.687488 -400.75993)
			(xy 172.665705 -400.734274) (xy 172.627752 -400.678689) (xy 172.596716 -400.618966) (xy 172.573041 -400.555962)
			(xy 172.557066 -400.49058) (xy 172.549021 -400.423757) (xy 172.54902 -400.356452) (xy 172.557065 -400.289629)
			(xy 172.573038 -400.224246) (xy 172.596713 -400.161242) (xy 172.627748 -400.101519) (xy 172.665699 -400.045933)
			(xy 172.687488 -400.020282) (xy 172.693273 -400.013129) (xy 172.699795 -399.995944) (xy 172.700188 -399.986754)
			(xy 172.700188 -399.828766) (xy 172.700537 -399.818586) (xy 172.708343 -399.799781) (xy 172.722752 -399.785395)
			(xy 172.741569 -399.777621) (xy 172.75175 -399.777204) (xy 173.46803 -399.777204) (xy 173.478186 -399.777708)
			(xy 173.496949 -399.785486) (xy 173.511312 -399.799848) (xy 173.519091 -399.818611) (xy 173.519592 -399.828766)
			(xy 173.519592 -399.986754) (xy 173.520026 -399.995939) (xy 173.526523 -400.013123) (xy 173.532292 -400.020282)
			(xy 173.554085 -400.04593) (xy 173.592031 -400.101518) (xy 173.623063 -400.161242) (xy 173.646734 -400.224247)
			(xy 173.662705 -400.289629) (xy 173.670749 -400.356452) (xy 173.670748 -400.423757) (xy 173.662704 -400.490579)
			(xy 173.646731 -400.555962) (xy 173.623059 -400.618966) (xy 173.592027 -400.67869) (xy 173.554079 -400.734277)
			(xy 173.532292 -400.75993) (xy 173.526499 -400.767078) (xy 173.519983 -400.784266) (xy 173.519592 -400.793458)
			(xy 173.519592 -401.286726) (xy 173.519991 -401.295914) (xy 173.526513 -401.313099) (xy 173.532292 -401.320254)
			(xy 173.554057 -401.345924) (xy 173.592005 -401.401509) (xy 173.623037 -401.46123) (xy 173.64671 -401.524232)
			(xy 173.662683 -401.589612) (xy 173.670729 -401.656432) (xy 173.670731 -401.723735) (xy 173.662689 -401.790555)
			(xy 173.64672 -401.855936) (xy 173.623051 -401.918939) (xy 173.592022 -401.978663) (xy 173.554077 -402.034249)
			(xy 173.532292 -402.059902) (xy 173.526511 -402.067058) (xy 173.519987 -402.08424) (xy 173.519592 -402.09343)
			(xy 173.519592 -402.251418) (xy 173.519082 -402.261573) (xy 173.511308 -402.280337) (xy 173.496947 -402.294701)
			(xy 173.478185 -402.30248) (xy 173.46803 -402.30298) (xy 172.75175 -402.30298) (xy 172.741584 -402.302496)
			(xy 172.722794 -402.29473) (xy 172.708408 -402.280363) (xy 172.700618 -402.261584) (xy 172.700188 -402.251418)
			(xy 172.700188 -402.09343) (xy 172.699766 -402.084244) (xy 172.693261 -402.067059) (xy 172.687488 -402.059902)
			(xy 172.665677 -402.034268) (xy 172.627726 -401.97868) (xy 172.596691 -401.918955) (xy 172.573017 -401.855948)
			(xy 172.557044 -401.790563) (xy 172.549001 -401.723737) (xy 171.421001 -401.723737) (xy 171.392099 -401.779215)
			(xy 171.354009 -401.834848) (xy 171.332144 -401.860512) (xy 171.326353 -401.867661) (xy 171.319836 -401.884849)
			(xy 171.319444 -401.89404) (xy 171.319444 -402.386292) (xy 171.31987 -402.395477) (xy 171.326374 -402.412661)
			(xy 171.332144 -402.41982) (xy 171.353963 -402.445523) (xy 171.392057 -402.501151) (xy 171.423213 -402.560941)
			(xy 171.446982 -402.624033) (xy 171.463022 -402.689518) (xy 171.471103 -402.756453) (xy 171.471107 -402.823818)
			(xy 174.749143 -402.823818) (xy 174.749147 -402.75651) (xy 174.757196 -402.689684) (xy 174.773174 -402.624299)
			(xy 174.796852 -402.561292) (xy 174.827891 -402.501567) (xy 174.865845 -402.44598) (xy 174.887636 -402.420328)
			(xy 174.89345 -402.413195) (xy 174.899953 -402.395995) (xy 174.900336 -402.3868) (xy 174.900336 -401.893532)
			(xy 174.899902 -401.884348) (xy 174.893404 -401.867163) (xy 174.887636 -401.860004) (xy 174.865829 -401.834368)
			(xy 174.827881 -401.778779) (xy 174.796848 -401.719053) (xy 174.773177 -401.656047) (xy 174.757205 -401.590663)
			(xy 174.749163 -401.523838) (xy 174.749165 -401.456532) (xy 174.757211 -401.389708) (xy 174.773186 -401.324324)
			(xy 174.796861 -401.261319) (xy 174.827896 -401.201595) (xy 174.865847 -401.146008) (xy 174.887636 -401.120356)
			(xy 174.893438 -401.113215) (xy 174.899949 -401.096021) (xy 174.900336 -401.086828) (xy 174.900336 -400.92884)
			(xy 174.900755 -400.918684) (xy 174.908544 -400.899926) (xy 174.922943 -400.8856) (xy 174.94174 -400.877905)
			(xy 174.951898 -400.877532) (xy 175.668178 -400.877532) (xy 175.678302 -400.878044) (xy 175.697022 -400.885763)
			(xy 175.711378 -400.900042) (xy 175.7192 -400.918718) (xy 175.71974 -400.92884) (xy 175.71974 -401.086828)
			(xy 175.72015 -401.096015) (xy 175.726665 -401.113198) (xy 175.73244 -401.120356) (xy 175.754209 -401.146024)
			(xy 175.792159 -401.201608) (xy 175.823195 -401.261329) (xy 175.846869 -401.324331) (xy 175.862844 -401.389712)
			(xy 175.870891 -401.456533) (xy 175.870892 -401.523837) (xy 175.86285 -401.590658) (xy 175.846878 -401.65604)
			(xy 175.823207 -401.719044) (xy 175.792175 -401.778766) (xy 175.754227 -401.834352) (xy 175.73244 -401.860004)
			(xy 175.726652 -401.867155) (xy 175.720134 -401.884341) (xy 175.71974 -401.893532) (xy 175.71974 -402.3868)
			(xy 175.720164 -402.395985) (xy 175.726669 -402.413169) (xy 175.73244 -402.420328) (xy 175.754181 -402.446019)
			(xy 175.792133 -402.501599) (xy 175.823169 -402.561317) (xy 175.846846 -402.624317) (xy 175.862823 -402.689694)
			(xy 175.870871 -402.756513) (xy 175.870875 -402.823815) (xy 175.862835 -402.890634) (xy 175.846867 -402.956014)
			(xy 175.823199 -403.019017) (xy 175.79217 -403.078739) (xy 175.754225 -403.134324) (xy 175.73244 -403.159976)
			(xy 175.726621 -403.167105) (xy 175.720122 -403.184308) (xy 175.71974 -403.193504) (xy 175.71974 -403.351492)
			(xy 175.719273 -403.361641) (xy 175.711487 -403.380385) (xy 175.697105 -403.394707) (xy 175.678328 -403.402415)
			(xy 175.668178 -403.4028) (xy 174.951898 -403.4028) (xy 174.941776 -403.402276) (xy 174.923063 -403.394555)
			(xy 174.908708 -403.380281) (xy 174.900882 -403.361611) (xy 174.900336 -403.351492) (xy 174.900336 -403.193504)
			(xy 174.899916 -403.184318) (xy 174.893408 -403.167134) (xy 174.887636 -403.159976) (xy 174.865801 -403.134363)
			(xy 174.827854 -403.078771) (xy 174.796823 -403.019042) (xy 174.773153 -402.956032) (xy 174.757183 -402.890645)
			(xy 174.749143 -402.823818) (xy 171.471107 -402.823818) (xy 171.471107 -402.823874) (xy 171.463035 -402.89081)
			(xy 171.447003 -402.956298) (xy 171.423242 -403.019393) (xy 171.392094 -403.079187) (xy 171.354007 -403.13482)
			(xy 171.332144 -403.160484) (xy 171.326322 -403.167611) (xy 171.319824 -403.184816) (xy 171.319444 -403.194012)
			(xy 171.319444 -403.351492) (xy 171.318909 -403.361595) (xy 171.311183 -403.380264) (xy 171.296901 -403.394558)
			(xy 171.278238 -403.402301) (xy 171.268136 -403.4028) (xy 170.551856 -403.4028) (xy 170.541744 -403.402351)
			(xy 170.523065 -403.394599) (xy 170.508772 -403.380291) (xy 170.501039 -403.361604) (xy 170.500548 -403.351492)
			(xy 170.500548 -403.194012) (xy 170.500121 -403.184827) (xy 170.493618 -403.167643) (xy 170.487848 -403.160484)
			(xy 170.465935 -403.134858) (xy 170.427845 -403.079219) (xy 170.396693 -403.019418) (xy 170.37293 -402.956316)
			(xy 170.356896 -402.890822) (xy 170.348823 -402.823878) (xy 167.070779 -402.823878) (xy 167.062748 -402.890634)
			(xy 167.04678 -402.956014) (xy 167.023112 -403.019016) (xy 166.992084 -403.078738) (xy 166.954141 -403.134324)
			(xy 166.932356 -403.159976) (xy 166.926539 -403.167107) (xy 166.920038 -403.184308) (xy 166.919656 -403.193504)
			(xy 166.919656 -403.351492) (xy 166.919173 -403.361639) (xy 166.911391 -403.38038) (xy 166.897014 -403.394702)
			(xy 166.878242 -403.402412) (xy 166.868094 -403.4028) (xy 166.151814 -403.4028) (xy 166.141693 -403.402263)
			(xy 166.12298 -403.394547) (xy 166.108624 -403.380277) (xy 166.100798 -403.36161) (xy 166.100252 -403.351492)
			(xy 166.100252 -403.193504) (xy 166.099828 -403.184318) (xy 166.093323 -403.167135) (xy 166.087552 -403.159976)
			(xy 166.065717 -403.134363) (xy 166.027768 -403.078771) (xy 165.996736 -403.019042) (xy 165.973066 -402.956033)
			(xy 165.957096 -402.890646) (xy 165.949055 -402.823818) (xy 162.671019 -402.823818) (xy 162.671019 -402.823874)
			(xy 162.662948 -402.89081) (xy 162.646916 -402.956297) (xy 162.623155 -403.019392) (xy 162.592008 -403.079187)
			(xy 162.553923 -403.13482) (xy 162.53206 -403.160484) (xy 162.52624 -403.167613) (xy 162.51974 -403.184816)
			(xy 162.51936 -403.194012) (xy 162.51936 -403.351492) (xy 162.518976 -403.361619) (xy 162.511224 -403.38033)
			(xy 162.496896 -403.394646) (xy 162.478179 -403.402384) (xy 162.468052 -403.4028) (xy 161.751772 -403.4028)
			(xy 161.741661 -403.402338) (xy 161.722983 -403.394591) (xy 161.708689 -403.380287) (xy 161.700955 -403.361603)
			(xy 161.700464 -403.351492) (xy 161.700464 -403.194012) (xy 161.700034 -403.184827) (xy 161.693532 -403.167643)
			(xy 161.687764 -403.160484) (xy 161.665854 -403.134857) (xy 161.627769 -403.079216) (xy 161.596623 -403.019414)
			(xy 161.572863 -402.956313) (xy 161.556832 -402.890819) (xy 161.54876 -402.823877) (xy 154.57678 -402.823877)
			(xy 154.57678 -405.623648) (xy 159.349158 -405.623648) (xy 159.349158 -405.556343) (xy 159.357202 -405.48952)
			(xy 159.373175 -405.424138) (xy 159.396848 -405.361133) (xy 159.427881 -405.301409) (xy 159.465829 -405.245822)
			(xy 159.487616 -405.22017) (xy 159.49341 -405.213023) (xy 159.499926 -405.195834) (xy 159.500316 -405.186642)
			(xy 159.500316 -404.693374) (xy 159.499915 -404.684186) (xy 159.493395 -404.667002) (xy 159.487616 -404.659846)
			(xy 159.465851 -404.634176) (xy 159.427903 -404.578591) (xy 159.39687 -404.51887) (xy 159.373197 -404.455868)
			(xy 159.357223 -404.390488) (xy 159.349177 -404.323668) (xy 159.349175 -404.256365) (xy 159.357217 -404.189544)
			(xy 159.373187 -404.124164) (xy 159.396856 -404.06116) (xy 159.427886 -404.001437) (xy 159.46583 -403.94585)
			(xy 159.487616 -403.920198) (xy 159.493398 -403.913042) (xy 159.499921 -403.89586) (xy 159.500316 -403.88667)
			(xy 159.500316 -403.728682) (xy 159.500818 -403.718526) (xy 159.508594 -403.69976) (xy 159.522957 -403.685396)
			(xy 159.541722 -403.677619) (xy 159.551878 -403.67712) (xy 160.268158 -403.67712) (xy 160.278325 -403.677598)
			(xy 160.297115 -403.685366) (xy 160.311501 -403.699735) (xy 160.31929 -403.718516) (xy 160.31972 -403.728682)
			(xy 160.31972 -403.88667) (xy 160.32014 -403.895856) (xy 160.326646 -403.913041) (xy 160.33242 -403.920198)
			(xy 160.354231 -403.945832) (xy 160.392181 -404.00142) (xy 160.423216 -404.061146) (xy 160.446889 -404.124153)
			(xy 160.462862 -404.189538) (xy 160.470905 -404.256363) (xy 160.470903 -404.32367) (xy 160.462856 -404.390495)
			(xy 160.446879 -404.455879) (xy 160.423202 -404.518885) (xy 160.392164 -404.578608) (xy 160.35421 -404.634194)
			(xy 160.33242 -404.659846) (xy 160.326624 -404.666992) (xy 160.320108 -404.684182) (xy 160.31972 -404.693374)
			(xy 160.31972 -405.186642) (xy 160.320105 -405.195832) (xy 160.326636 -405.213016) (xy 160.33242 -405.22017)
			(xy 160.354203 -405.245826) (xy 160.392155 -405.301411) (xy 160.42319 -405.361134) (xy 160.446865 -405.424138)
			(xy 160.46284 -405.48952) (xy 160.470885 -405.556343) (xy 160.470886 -405.623648) (xy 160.462842 -405.690471)
			(xy 160.446868 -405.755853) (xy 160.423194 -405.818858) (xy 160.392159 -405.878581) (xy 160.354209 -405.934166)
			(xy 160.33242 -405.959818) (xy 160.326636 -405.966972) (xy 160.320113 -405.984156) (xy 160.31972 -405.993346)
			(xy 160.31972 -406.151334) (xy 160.319363 -406.161513) (xy 160.311559 -406.180317) (xy 160.297153 -406.194702)
			(xy 160.278338 -406.202478) (xy 160.268158 -406.202896) (xy 159.551878 -406.202896) (xy 159.541723 -406.202386)
			(xy 159.52296 -406.19461) (xy 159.508596 -406.18025) (xy 159.500817 -406.161489) (xy 159.500316 -406.151334)
			(xy 159.500316 -405.993346) (xy 159.49988 -405.984162) (xy 159.493384 -405.966977) (xy 159.487616 -405.959818)
			(xy 159.465823 -405.93417) (xy 159.427876 -405.878583) (xy 159.396844 -405.818858) (xy 159.373173 -405.755853)
			(xy 159.357201 -405.690471) (xy 159.349158 -405.623648) (xy 154.57678 -405.623648) (xy 154.57678 -406.723789)
			(xy 161.548771 -406.723789) (xy 161.548774 -406.656363) (xy 161.556853 -406.589423) (xy 161.572891 -406.523933)
			(xy 161.596657 -406.460835) (xy 161.627809 -406.401038) (xy 161.665899 -406.345402) (xy 161.687764 -406.319736)
			(xy 161.693578 -406.312604) (xy 161.70008 -406.295403) (xy 161.700464 -406.286208) (xy 161.700464 -405.793956)
			(xy 161.700061 -405.784768) (xy 161.693541 -405.767585) (xy 161.687764 -405.760428) (xy 161.665897 -405.734765)
			(xy 161.627811 -405.67913) (xy 161.596663 -405.619333) (xy 161.5729 -405.556236) (xy 161.556866 -405.490747)
			(xy 161.548791 -405.423809) (xy 161.548792 -405.356385) (xy 161.556867 -405.289447) (xy 161.572902 -405.223959)
			(xy 161.596665 -405.160862) (xy 161.627814 -405.101065) (xy 161.665901 -405.04543) (xy 161.687764 -405.019764)
			(xy 161.693566 -405.012623) (xy 161.700076 -404.995429) (xy 161.700464 -404.986236) (xy 161.700464 -404.828756)
			(xy 161.700948 -404.818649) (xy 161.708694 -404.799977) (xy 161.72299 -404.785685) (xy 161.741665 -404.777945)
			(xy 161.751772 -404.777448) (xy 162.468052 -404.777448) (xy 162.478165 -404.777954) (xy 162.496858 -404.785677)
			(xy 162.511172 -404.799965) (xy 162.518928 -404.818644) (xy 162.51936 -404.828756) (xy 162.51936 -404.986236)
			(xy 162.519762 -404.995424) (xy 162.526282 -405.012608) (xy 162.53206 -405.019764) (xy 162.553921 -405.045432)
			(xy 162.592013 -405.101065) (xy 162.623166 -405.16086) (xy 162.646932 -405.223957) (xy 162.662969 -405.289446)
			(xy 162.671046 -405.356385) (xy 162.671046 -405.423809) (xy 162.66297 -405.490748) (xy 162.646934 -405.556237)
			(xy 162.623168 -405.619334) (xy 162.620889 -405.623708) (xy 163.748926 -405.623708) (xy 163.748926 -405.556283)
			(xy 163.757003 -405.489344) (xy 163.77304 -405.423855) (xy 163.796805 -405.360758) (xy 163.827957 -405.300961)
			(xy 163.866047 -405.245327) (xy 163.887912 -405.219662) (xy 163.893709 -405.212517) (xy 163.900223 -405.195326)
			(xy 163.900612 -405.186134) (xy 163.900612 -404.693882) (xy 163.900208 -404.684694) (xy 163.89369 -404.66751)
			(xy 163.887912 -404.660354) (xy 163.866069 -404.634671) (xy 163.827979 -404.579039) (xy 163.796827 -404.519246)
			(xy 163.773061 -404.456151) (xy 163.757023 -404.390664) (xy 163.748946 -404.323728) (xy 163.748944 -404.256305)
			(xy 163.757018 -404.189368) (xy 163.773051 -404.12388) (xy 163.796813 -404.060784) (xy 163.827962 -404.000989)
			(xy 163.866049 -403.945355) (xy 163.887912 -403.91969) (xy 163.893697 -403.912536) (xy 163.900218 -403.895352)
			(xy 163.900612 -403.886162) (xy 163.900612 -403.728682) (xy 163.901111 -403.718558) (xy 163.908839 -403.699841)
			(xy 163.923121 -403.685486) (xy 163.941798 -403.677663) (xy 163.95192 -403.67712) (xy 164.6682 -403.67712)
			(xy 164.678357 -403.677522) (xy 164.697113 -403.685321) (xy 164.711437 -403.699724) (xy 164.719133 -403.718523)
			(xy 164.719508 -403.728682) (xy 164.719508 -403.886162) (xy 164.719935 -403.895347) (xy 164.726437 -403.912532)
			(xy 164.732208 -403.91969) (xy 164.754093 -403.945338) (xy 164.792181 -404.000975) (xy 164.82333 -404.060774)
			(xy 164.847093 -404.123873) (xy 164.863126 -404.189364) (xy 164.8712 -404.256304) (xy 164.871198 -404.323729)
			(xy 164.86312 -404.390669) (xy 164.847083 -404.456159) (xy 164.823317 -404.519257) (xy 164.792164 -404.579054)
			(xy 164.754073 -404.634689) (xy 164.732208 -404.660354) (xy 164.726407 -404.667496) (xy 164.719895 -404.684689)
			(xy 164.719508 -404.693882) (xy 164.719508 -405.186134) (xy 164.7199 -405.195323) (xy 164.726426 -405.212508)
			(xy 164.732208 -405.219662) (xy 164.754066 -405.245332) (xy 164.792154 -405.300966) (xy 164.823305 -405.360762)
			(xy 164.847069 -405.423858) (xy 164.863104 -405.489346) (xy 164.871181 -405.556284) (xy 164.871181 -405.623707)
			(xy 164.863106 -405.690645) (xy 164.847072 -405.756133) (xy 164.823308 -405.81923) (xy 164.792159 -405.879026)
			(xy 164.754071 -405.934661) (xy 164.732208 -405.960326) (xy 164.726419 -405.967477) (xy 164.719899 -405.984663)
			(xy 164.719508 -405.993854) (xy 164.719508 -406.151334) (xy 164.719003 -406.161457) (xy 164.711273 -406.18017)
			(xy 164.696993 -406.194523) (xy 164.67832 -406.20235) (xy 164.6682 -406.202896) (xy 163.95192 -406.202896)
			(xy 163.941767 -406.202462) (xy 163.923014 -406.194672) (xy 163.90869 -406.180279) (xy 163.90099 -406.161489)
			(xy 163.900612 -406.151334) (xy 163.900612 -405.993854) (xy 163.900173 -405.98467) (xy 163.893679 -405.967485)
			(xy 163.887912 -405.960326) (xy 163.866042 -405.934666) (xy 163.827952 -405.879031) (xy 163.796801 -405.819234)
			(xy 163.773037 -405.756137) (xy 163.757001 -405.690647) (xy 163.748926 -405.623708) (xy 162.620889 -405.623708)
			(xy 162.592016 -405.67913) (xy 162.553925 -405.734763) (xy 162.53206 -405.760428) (xy 162.526264 -405.767573)
			(xy 162.51975 -405.784764) (xy 162.51936 -405.793956) (xy 162.51936 -406.286208) (xy 162.519775 -406.295394)
			(xy 162.526286 -406.312578) (xy 162.53206 -406.319736) (xy 162.553894 -406.345426) (xy 162.591986 -406.401056)
			(xy 162.623141 -406.460849) (xy 162.646908 -406.523942) (xy 162.662947 -406.589429) (xy 162.671026 -406.656365)
			(xy 162.671029 -406.72373) (xy 165.949066 -406.72373) (xy 165.949069 -406.656422) (xy 165.957117 -406.589597)
			(xy 165.973094 -406.524213) (xy 165.996771 -406.461207) (xy 166.027808 -406.401483) (xy 166.065762 -406.345896)
			(xy 166.087552 -406.320244) (xy 166.093361 -406.313108) (xy 166.099867 -406.29591) (xy 166.100252 -406.286716)
			(xy 166.100252 -405.793448) (xy 166.099807 -405.784265) (xy 166.093316 -405.767081) (xy 166.087552 -405.75992)
			(xy 166.06576 -405.734271) (xy 166.027811 -405.678685) (xy 165.996777 -405.618961) (xy 165.973104 -405.555956)
			(xy 165.957131 -405.490573) (xy 165.949087 -405.42375) (xy 165.949087 -405.356444) (xy 165.957132 -405.289621)
			(xy 165.973105 -405.224239) (xy 165.996779 -405.161234) (xy 166.027814 -405.10151) (xy 166.065764 -405.045924)
			(xy 166.087552 -405.020272) (xy 166.093349 -405.013128) (xy 166.099862 -404.995936) (xy 166.100252 -404.986744)
			(xy 166.100252 -404.828756) (xy 166.100685 -404.818605) (xy 166.108486 -404.799861) (xy 166.122878 -404.785541)
			(xy 166.141661 -404.777834) (xy 166.151814 -404.777448) (xy 166.868094 -404.777448) (xy 166.878221 -404.777932)
			(xy 166.896944 -404.785659) (xy 166.911301 -404.799946) (xy 166.919119 -404.818631) (xy 166.919656 -404.828756)
			(xy 166.919656 -404.986744) (xy 166.920055 -404.995932) (xy 166.926578 -405.013116) (xy 166.932356 -405.020272)
			(xy 166.95414 -405.045927) (xy 166.992089 -405.101513) (xy 167.023123 -405.161236) (xy 167.046796 -405.22424)
			(xy 167.062769 -405.289622) (xy 167.070814 -405.356445) (xy 167.070814 -405.423749) (xy 167.06277 -405.490572)
			(xy 167.046798 -405.555954) (xy 167.023125 -405.618958) (xy 167.020688 -405.623648) (xy 168.149245 -405.623648)
			(xy 168.149246 -405.556343) (xy 168.15729 -405.489521) (xy 168.173263 -405.424139) (xy 168.196934 -405.361134)
			(xy 168.227966 -405.30141) (xy 168.265913 -405.245823) (xy 168.2877 -405.22017) (xy 168.293492 -405.213021)
			(xy 168.300009 -405.195834) (xy 168.3004 -405.186642) (xy 168.3004 -404.693374) (xy 168.300003 -404.684185)
			(xy 168.29348 -404.667001) (xy 168.2877 -404.659846) (xy 168.265935 -404.634176) (xy 168.227988 -404.578591)
			(xy 168.196956 -404.518869) (xy 168.173284 -404.455867) (xy 168.15731 -404.390488) (xy 168.149265 -404.323668)
			(xy 168.149263 -404.256365) (xy 168.157305 -404.189545) (xy 168.173274 -404.124164) (xy 168.196943 -404.061161)
			(xy 168.227971 -404.001438) (xy 168.265915 -403.945851) (xy 168.2877 -403.920198) (xy 168.29348 -403.913041)
			(xy 168.300005 -403.89586) (xy 168.3004 -403.88667) (xy 168.3004 -403.728682) (xy 168.300917 -403.718528)
			(xy 168.308691 -403.699765) (xy 168.323049 -403.685402) (xy 168.341808 -403.677621) (xy 168.351962 -403.67712)
			(xy 169.068242 -403.67712) (xy 169.0784 -403.677599) (xy 169.097167 -403.685383) (xy 169.11153 -403.699753)
			(xy 169.119306 -403.718524) (xy 169.119804 -403.728682) (xy 169.119804 -403.88667) (xy 169.120228 -403.895856)
			(xy 169.126732 -403.91304) (xy 169.132504 -403.920198) (xy 169.154312 -403.945833) (xy 169.192257 -404.001423)
			(xy 169.223287 -404.061149) (xy 169.246957 -404.124156) (xy 169.262927 -404.18954) (xy 169.270969 -404.256364)
			(xy 169.270967 -404.32367) (xy 169.262921 -404.390493) (xy 169.246947 -404.455876) (xy 169.223274 -404.518881)
			(xy 169.19224 -404.578606) (xy 169.154292 -404.634193) (xy 169.132504 -404.659846) (xy 169.126706 -404.66699)
			(xy 169.120192 -404.684181) (xy 169.119804 -404.693374) (xy 169.119804 -405.186642) (xy 169.120193 -405.195832)
			(xy 169.126721 -405.213016) (xy 169.132504 -405.22017) (xy 169.154284 -405.245828) (xy 169.192231 -405.301414)
			(xy 169.223262 -405.361137) (xy 169.246933 -405.424141) (xy 169.262905 -405.489522) (xy 169.270949 -405.556344)
			(xy 169.27095 -405.623647) (xy 169.262907 -405.690469) (xy 169.246936 -405.75585) (xy 169.223266 -405.818854)
			(xy 169.192235 -405.878578) (xy 169.15429 -405.934165) (xy 169.132504 -405.959818) (xy 169.126718 -405.966971)
			(xy 169.120197 -405.984155) (xy 169.119804 -405.993346) (xy 169.119804 -406.151334) (xy 169.119296 -406.161489)
			(xy 169.111518 -406.180251) (xy 169.097157 -406.194613) (xy 169.078397 -406.202394) (xy 169.068242 -406.202896)
			(xy 168.351962 -406.202896) (xy 168.341806 -406.202399) (xy 168.323042 -406.194618) (xy 168.30868 -406.180254)
			(xy 168.300901 -406.16149) (xy 168.3004 -406.151334) (xy 168.3004 -405.993346) (xy 168.299968 -405.984161)
			(xy 168.293469 -405.966977) (xy 168.2877 -405.959818) (xy 168.265908 -405.93417) (xy 168.227961 -405.878582)
			(xy 168.196931 -405.818858) (xy 168.17326 -405.755853) (xy 168.157289 -405.69047) (xy 168.149245 -405.623648)
			(xy 167.020688 -405.623648) (xy 166.992092 -405.678681) (xy 166.954143 -405.734268) (xy 166.932356 -405.75992)
			(xy 166.926563 -405.767067) (xy 166.920047 -405.784256) (xy 166.919656 -405.793448) (xy 166.919656 -406.286716)
			(xy 166.920068 -406.295903) (xy 166.926582 -406.313087) (xy 166.932356 -406.320244) (xy 166.954112 -406.345922)
			(xy 166.992062 -406.401505) (xy 167.023097 -406.461225) (xy 167.046772 -406.524226) (xy 167.062747 -406.589605)
			(xy 167.070794 -406.656425) (xy 167.070797 -406.723727) (xy 167.070789 -406.72379) (xy 170.348835 -406.72379)
			(xy 170.348838 -406.656362) (xy 170.356917 -406.589421) (xy 170.372958 -406.52393) (xy 170.396728 -406.460831)
			(xy 170.427885 -406.401034) (xy 170.46598 -406.3454) (xy 170.487848 -406.319736) (xy 170.49366 -406.312602)
			(xy 170.500164 -406.295403) (xy 170.500548 -406.286208) (xy 170.500548 -405.793956) (xy 170.500148 -405.784768)
			(xy 170.493626 -405.767584) (xy 170.487848 -405.760428) (xy 170.465978 -405.734767) (xy 170.427887 -405.679133)
			(xy 170.396733 -405.619337) (xy 170.372967 -405.556239) (xy 170.356931 -405.490749) (xy 170.348854 -405.423809)
			(xy 170.348855 -405.356385) (xy 170.356932 -405.289445) (xy 170.372969 -405.223955) (xy 170.396736 -405.160858)
			(xy 170.42789 -405.101062) (xy 170.465982 -405.045428) (xy 170.487848 -405.019764) (xy 170.493648 -405.012622)
			(xy 170.500159 -404.995429) (xy 170.500548 -404.986236) (xy 170.500548 -404.828756) (xy 170.501048 -404.818651)
			(xy 170.50879 -404.799982) (xy 170.523082 -404.78569) (xy 170.541751 -404.777948) (xy 170.551856 -404.777448)
			(xy 171.268136 -404.777448) (xy 171.278241 -404.777954) (xy 171.29691 -404.785694) (xy 171.311201 -404.799984)
			(xy 171.318944 -404.818651) (xy 171.319444 -404.828756) (xy 171.319444 -404.986236) (xy 171.31985 -404.995423)
			(xy 171.326368 -405.012607) (xy 171.332144 -405.019764) (xy 171.354006 -405.045432) (xy 171.392099 -405.101064)
			(xy 171.423253 -405.16086) (xy 171.447019 -405.223956) (xy 171.463057 -405.289446) (xy 171.471134 -405.356385)
			(xy 171.471134 -405.423809) (xy 171.463058 -405.490748) (xy 171.447021 -405.556238) (xy 171.423255 -405.619335)
			(xy 171.421007 -405.623649) (xy 172.549012 -405.623649) (xy 172.549013 -405.556342) (xy 172.557058 -405.489518)
			(xy 172.573033 -405.424135) (xy 172.596709 -405.36113) (xy 172.627746 -405.301407) (xy 172.665698 -405.245822)
			(xy 172.687488 -405.22017) (xy 172.693278 -405.21302) (xy 172.699797 -405.195833) (xy 172.700188 -405.186642)
			(xy 172.700188 -404.693374) (xy 172.699793 -404.684185) (xy 172.693269 -404.667001) (xy 172.687488 -404.659846)
			(xy 172.66572 -404.634177) (xy 172.627768 -404.578594) (xy 172.596731 -404.518873) (xy 172.573055 -404.455871)
			(xy 172.557079 -404.39049) (xy 172.549032 -404.323669) (xy 172.54903 -404.256364) (xy 172.557073 -404.189542)
			(xy 172.573045 -404.124161) (xy 172.596717 -404.061157) (xy 172.627751 -404.001435) (xy 172.6657 -403.945849)
			(xy 172.687488 -403.920198) (xy 172.693267 -403.91304) (xy 172.699792 -403.895859) (xy 172.700188 -403.88667)
			(xy 172.700188 -403.728682) (xy 172.70055 -403.718503) (xy 172.708351 -403.699698) (xy 172.722756 -403.685313)
			(xy 172.74157 -403.677537) (xy 172.75175 -403.67712) (xy 173.46803 -403.67712) (xy 173.478187 -403.677608)
			(xy 173.496954 -403.685389) (xy 173.511317 -403.699756) (xy 173.519094 -403.718524) (xy 173.519592 -403.728682)
			(xy 173.519592 -403.88667) (xy 173.520018 -403.895855) (xy 173.526521 -403.91304) (xy 173.532292 -403.920198)
			(xy 173.5541 -403.945833) (xy 173.592047 -404.001422) (xy 173.623077 -404.061149) (xy 173.646747 -404.124155)
			(xy 173.662718 -404.189539) (xy 173.67076 -404.256363) (xy 173.670758 -404.32367) (xy 173.662712 -404.390493)
			(xy 173.646738 -404.455876) (xy 173.623064 -404.518882) (xy 173.59203 -404.578606) (xy 173.55408 -404.634193)
			(xy 173.532292 -404.659846) (xy 173.526492 -404.666989) (xy 173.51998 -404.684181) (xy 173.519592 -404.693374)
			(xy 173.519592 -405.186642) (xy 173.519984 -405.195831) (xy 173.52651 -405.213015) (xy 173.532292 -405.22017)
			(xy 173.554073 -405.245827) (xy 173.59202 -405.301414) (xy 173.623052 -405.361137) (xy 173.646723 -405.424141)
			(xy 173.662696 -405.489522) (xy 173.67074 -405.556343) (xy 173.670741 -405.623647) (xy 173.662698 -405.690469)
			(xy 173.646726 -405.755851) (xy 173.623055 -405.818855) (xy 173.592025 -405.878578) (xy 173.554078 -405.934165)
			(xy 173.532292 -405.959818) (xy 173.526504 -405.96697) (xy 173.519985 -405.984155) (xy 173.519592 -405.993346)
			(xy 173.519592 -406.151334) (xy 173.519095 -406.16149) (xy 173.511315 -406.180254) (xy 173.496951 -406.194617)
			(xy 173.478186 -406.202396) (xy 173.46803 -406.202896) (xy 172.75175 -406.202896) (xy 172.741586 -406.202396)
			(xy 172.722799 -406.194634) (xy 172.708413 -406.180272) (xy 172.70062 -406.161497) (xy 172.700188 -406.151334)
			(xy 172.700188 -405.993346) (xy 172.699759 -405.984161) (xy 172.693259 -405.966976) (xy 172.687488 -405.959818)
			(xy 172.665693 -405.934171) (xy 172.627741 -405.878585) (xy 172.596705 -405.818861) (xy 172.573031 -405.755856)
			(xy 172.557057 -405.690473) (xy 172.549012 -405.623649) (xy 171.421007 -405.623649) (xy 171.392102 -405.67913)
			(xy 171.35401 -405.734764) (xy 171.332144 -405.760428) (xy 171.326346 -405.767572) (xy 171.319834 -405.784764)
			(xy 171.319444 -405.793956) (xy 171.319444 -406.286208) (xy 171.319863 -406.295394) (xy 171.326372 -406.312578)
			(xy 171.332144 -406.319736) (xy 171.353978 -406.345426) (xy 171.392072 -406.401056) (xy 171.423227 -406.460848)
			(xy 171.446996 -406.523942) (xy 171.463035 -406.589428) (xy 171.471114 -406.656365) (xy 171.471117 -406.72373)
			(xy 174.749154 -406.72373) (xy 174.749157 -406.656422) (xy 174.757205 -406.589597) (xy 174.773181 -406.524213)
			(xy 174.796857 -406.461208) (xy 174.827894 -406.401483) (xy 174.865846 -406.345896) (xy 174.887636 -406.320244)
			(xy 174.893443 -406.313107) (xy 174.899951 -406.29591) (xy 174.900336 -406.286716) (xy 174.900336 -405.793448)
			(xy 174.899895 -405.784264) (xy 174.893402 -405.76708) (xy 174.887636 -405.75992) (xy 174.865844 -405.734271)
			(xy 174.827896 -405.678684) (xy 174.796863 -405.61896) (xy 174.77319 -405.555955) (xy 174.757218 -405.490573)
			(xy 174.749174 -405.42375) (xy 174.749174 -405.356444) (xy 174.757219 -405.289621) (xy 174.773192 -405.224239)
			(xy 174.796865 -405.161234) (xy 174.827899 -405.101511) (xy 174.865848 -405.045924) (xy 174.887636 -405.020272)
			(xy 174.893432 -405.013126) (xy 174.899946 -404.995936) (xy 174.900336 -404.986744) (xy 174.900336 -404.828756)
			(xy 174.900686 -404.818594) (xy 174.908503 -404.799834) (xy 174.922922 -404.785511) (xy 174.941734 -404.77782)
			(xy 174.951898 -404.777448) (xy 175.668178 -404.777448) (xy 175.678304 -404.777945) (xy 175.697027 -404.785667)
			(xy 175.711384 -404.79995) (xy 175.719202 -404.818632) (xy 175.71974 -404.828756) (xy 175.71974 -404.986744)
			(xy 175.720142 -404.995932) (xy 175.726663 -405.013115) (xy 175.73244 -405.020272) (xy 175.754224 -405.045927)
			(xy 175.792175 -405.101513) (xy 175.823209 -405.161236) (xy 175.846883 -405.22424) (xy 175.862857 -405.289622)
			(xy 175.870902 -405.356444) (xy 175.870902 -405.42375) (xy 175.862858 -405.490572) (xy 175.846885 -405.555954)
			(xy 175.823212 -405.618959) (xy 175.792178 -405.678682) (xy 175.754228 -405.734268) (xy 175.73244 -405.75992)
			(xy 175.726645 -405.767066) (xy 175.720131 -405.784256) (xy 175.71974 -405.793448) (xy 175.71974 -406.286716)
			(xy 175.720156 -406.295902) (xy 175.726667 -406.313086) (xy 175.73244 -406.320244) (xy 175.754197 -406.345922)
			(xy 175.792148 -406.401504) (xy 175.823184 -406.461224) (xy 175.846859 -406.524225) (xy 175.862835 -406.589604)
			(xy 175.870882 -406.656424) (xy 175.870885 -406.723727) (xy 175.862844 -406.790548) (xy 175.846873 -406.855929)
			(xy 175.823203 -406.918932) (xy 175.792173 -406.978655) (xy 175.754226 -407.03424) (xy 175.73244 -407.059892)
			(xy 175.726657 -407.067046) (xy 175.720136 -407.08423) (xy 175.71974 -407.09342) (xy 175.71974 -407.251408)
			(xy 175.719286 -407.261558) (xy 175.711495 -407.280302) (xy 175.697109 -407.294624) (xy 175.678329 -407.302331)
			(xy 175.668178 -407.302716) (xy 174.951898 -407.302716) (xy 174.941766 -407.302274) (xy 174.923036 -407.294537)
			(xy 174.908679 -407.280237) (xy 174.900867 -407.261538) (xy 174.900336 -407.251408) (xy 174.900336 -407.09342)
			(xy 174.899908 -407.084235) (xy 174.893406 -407.067051) (xy 174.887636 -407.059892) (xy 174.865817 -407.034266)
			(xy 174.827869 -406.978676) (xy 174.796837 -406.918948) (xy 174.773167 -406.85594) (xy 174.757196 -406.790555)
			(xy 174.749154 -406.72373) (xy 171.471117 -406.72373) (xy 171.471117 -406.723787) (xy 171.463044 -406.790724)
			(xy 171.44701 -406.856212) (xy 171.423247 -406.919308) (xy 171.392097 -406.979103) (xy 171.354008 -407.034736)
			(xy 171.332144 -407.0604) (xy 171.326358 -407.067552) (xy 171.319839 -407.084738) (xy 171.319444 -407.093928)
			(xy 171.319444 -407.251408) (xy 171.318922 -407.261512) (xy 171.31119 -407.280182) (xy 171.296905 -407.294475)
			(xy 171.278239 -407.302217) (xy 171.268136 -407.302716) (xy 170.551856 -407.302716) (xy 170.541746 -407.302251)
			(xy 170.52307 -407.294502) (xy 170.508778 -407.280199) (xy 170.501042 -407.261518) (xy 170.500548 -407.251408)
			(xy 170.500548 -407.093928) (xy 170.500114 -407.084744) (xy 170.493616 -407.067559) (xy 170.487848 -407.0604)
			(xy 170.465951 -407.034762) (xy 170.42786 -406.979124) (xy 170.396708 -406.919325) (xy 170.372944 -406.856224)
			(xy 170.356909 -406.790732) (xy 170.348835 -406.72379) (xy 167.070789 -406.72379) (xy 167.062756 -406.790548)
			(xy 167.046786 -406.855928) (xy 167.023117 -406.918931) (xy 166.992087 -406.978654) (xy 166.954142 -407.03424)
			(xy 166.932356 -407.059892) (xy 166.926575 -407.067048) (xy 166.920052 -407.08423) (xy 166.919656 -407.09342)
			(xy 166.919656 -407.251408) (xy 166.919186 -407.261556) (xy 166.911398 -407.280297) (xy 166.897017 -407.294618)
			(xy 166.878243 -407.302328) (xy 166.868094 -407.302716) (xy 166.151814 -407.302716) (xy 166.141683 -407.302261)
			(xy 166.122954 -407.294529) (xy 166.108595 -407.280233) (xy 166.100783 -407.261537) (xy 166.100252 -407.251408)
			(xy 166.100252 -407.09342) (xy 166.099821 -407.084235) (xy 166.093321 -407.067051) (xy 166.087552 -407.059892)
			(xy 166.065732 -407.034266) (xy 166.027784 -406.978676) (xy 165.996751 -406.918949) (xy 165.973079 -406.855941)
			(xy 165.957108 -406.790556) (xy 165.949066 -406.72373) (xy 162.671029 -406.72373) (xy 162.671029 -406.723787)
			(xy 162.662956 -406.790724) (xy 162.646923 -406.856212) (xy 162.62316 -406.919307) (xy 162.592011 -406.979102)
			(xy 162.553923 -407.034735) (xy 162.53206 -407.0604) (xy 162.526276 -407.067554) (xy 162.519755 -407.084738)
			(xy 162.51936 -407.093928) (xy 162.51936 -407.251408) (xy 162.518989 -407.261536) (xy 162.511231 -407.280247)
			(xy 162.4969 -407.294563) (xy 162.47818 -407.3023) (xy 162.468052 -407.302716) (xy 161.751772 -407.302716)
			(xy 161.741663 -407.302238) (xy 161.722988 -407.294494) (xy 161.708694 -407.280196) (xy 161.700958 -407.261517)
			(xy 161.700464 -407.251408) (xy 161.700464 -407.093928) (xy 161.700026 -407.084744) (xy 161.69353 -407.06756)
			(xy 161.687764 -407.0604) (xy 161.66587 -407.03476) (xy 161.627784 -406.979121) (xy 161.596637 -406.919321)
			(xy 161.572876 -406.856221) (xy 161.556844 -406.790729) (xy 161.548771 -406.723789) (xy 154.57678 -406.723789)
			(xy 154.57678 -409.523827) (xy 159.349136 -409.523827) (xy 159.34914 -409.456519) (xy 159.357187 -409.389695)
			(xy 159.373163 -409.324311) (xy 159.396839 -409.261305) (xy 159.427875 -409.20158) (xy 159.465827 -409.145992)
			(xy 159.487616 -409.12034) (xy 159.493422 -409.113202) (xy 159.499931 -409.096006) (xy 159.500316 -409.086812)
			(xy 159.500316 -408.593544) (xy 159.499881 -408.58436) (xy 159.493384 -408.567175) (xy 159.487616 -408.560016)
			(xy 159.465821 -408.53437) (xy 159.427874 -408.478782) (xy 159.396842 -408.419058) (xy 159.373171 -408.356052)
			(xy 159.357199 -408.29067) (xy 159.349156 -408.223847) (xy 159.349157 -408.156541) (xy 159.357201 -408.089719)
			(xy 159.373175 -408.024336) (xy 159.396847 -407.961331) (xy 159.42788 -407.901607) (xy 159.465828 -407.84602)
			(xy 159.487616 -407.820368) (xy 159.49341 -407.813221) (xy 159.499926 -407.796032) (xy 159.500316 -407.78684)
			(xy 159.500316 -407.628852) (xy 159.500683 -407.618693) (xy 159.508497 -407.599936) (xy 159.522911 -407.585614)
			(xy 159.541716 -407.577919) (xy 159.551878 -407.577544) (xy 160.268158 -407.577544) (xy 160.278283 -407.578061)
			(xy 160.297003 -407.585776) (xy 160.311361 -407.600053) (xy 160.319181 -407.61873) (xy 160.31972 -407.628852)
			(xy 160.31972 -407.78684) (xy 160.320107 -407.79603) (xy 160.326636 -407.813214) (xy 160.33242 -407.820368)
			(xy 160.354201 -407.846026) (xy 160.392153 -407.901611) (xy 160.423189 -407.961333) (xy 160.446864 -408.024337)
			(xy 160.462838 -408.089719) (xy 160.470884 -408.156541) (xy 160.470885 -408.223847) (xy 160.462841 -408.290669)
			(xy 160.446867 -408.356052) (xy 160.423194 -408.419056) (xy 160.392159 -408.478779) (xy 160.354208 -408.534364)
			(xy 160.33242 -408.560016) (xy 160.326636 -408.567171) (xy 160.320113 -408.584354) (xy 160.31972 -408.593544)
			(xy 160.31972 -409.086812) (xy 160.32012 -409.096) (xy 160.32664 -409.113185) (xy 160.33242 -409.12034)
			(xy 160.354174 -409.146021) (xy 160.392126 -409.201602) (xy 160.423163 -409.261321) (xy 160.44684 -409.324322)
			(xy 160.462817 -409.389701) (xy 160.470864 -409.456521) (xy 160.470867 -409.523824) (xy 160.462826 -409.590645)
			(xy 160.446856 -409.656026) (xy 160.423185 -409.719029) (xy 160.392154 -409.778751) (xy 160.354207 -409.834336)
			(xy 160.33242 -409.859988) (xy 160.326606 -409.867121) (xy 160.320101 -409.884321) (xy 160.31972 -409.893516)
			(xy 160.31972 -410.051504) (xy 160.319282 -410.061656) (xy 160.311489 -410.080404) (xy 160.297098 -410.094727)
			(xy 160.278312 -410.10243) (xy 160.268158 -410.102812) (xy 159.551878 -410.102812) (xy 159.541756 -410.102293)
			(xy 159.523044 -410.094568) (xy 159.508691 -410.080292) (xy 159.500863 -410.061623) (xy 159.500316 -410.051504)
			(xy 159.500316 -409.893516) (xy 159.499894 -409.88433) (xy 159.493388 -409.867146) (xy 159.487616 -409.859988)
			(xy 159.465794 -409.834365) (xy 159.427847 -409.778774) (xy 159.396817 -409.719046) (xy 159.373147 -409.656038)
			(xy 159.357177 -409.590652) (xy 159.349136 -409.523827) (xy 154.57678 -409.523827) (xy 154.57678 -410.6237)
			(xy 161.548783 -410.6237) (xy 161.548784 -410.556276) (xy 161.556861 -410.489337) (xy 161.572897 -410.423848)
			(xy 161.596662 -410.36075) (xy 161.627812 -410.300953) (xy 161.6659 -410.245318) (xy 161.687764 -410.219652)
			(xy 161.693571 -410.212515) (xy 161.700078 -410.195318) (xy 161.700464 -410.186124) (xy 161.700464 -409.693872)
			(xy 161.700053 -409.684685) (xy 161.693538 -409.667502) (xy 161.687764 -409.660344) (xy 161.665913 -409.634668)
			(xy 161.627826 -409.579035) (xy 161.596677 -409.519239) (xy 161.572914 -409.456144) (xy 161.556879 -409.390657)
			(xy 161.548802 -409.32372) (xy 161.548801 -409.256298) (xy 161.556875 -409.189361) (xy 161.572909 -409.123873)
			(xy 161.59667 -409.060777) (xy 161.627817 -409.000981) (xy 161.665902 -408.945346) (xy 161.687764 -408.91968)
			(xy 161.693559 -408.912534) (xy 161.700073 -408.895344) (xy 161.700464 -408.886152) (xy 161.700464 -408.728672)
			(xy 161.700961 -408.718566) (xy 161.708701 -408.699894) (xy 161.722994 -408.685601) (xy 161.741666 -408.677861)
			(xy 161.751772 -408.677364) (xy 162.468052 -408.677364) (xy 162.478167 -408.677854) (xy 162.496863 -408.68558)
			(xy 162.511177 -408.699874) (xy 162.518931 -408.718558) (xy 162.51936 -408.728672) (xy 162.51936 -408.886152)
			(xy 162.519802 -408.895336) (xy 162.526295 -408.91252) (xy 162.53206 -408.91968) (xy 162.553937 -408.945335)
			(xy 162.592028 -409.00097) (xy 162.623181 -409.060767) (xy 162.646946 -409.123866) (xy 162.662982 -409.189356)
			(xy 162.671057 -409.256296) (xy 162.671056 -409.323722) (xy 162.662978 -409.390662) (xy 162.64694 -409.456152)
			(xy 162.623173 -409.519249) (xy 162.620757 -409.523886) (xy 163.748905 -409.523886) (xy 163.748908 -409.45646)
			(xy 163.756988 -409.389519) (xy 163.773027 -409.324027) (xy 163.796796 -409.260929) (xy 163.827952 -409.201132)
			(xy 163.866045 -409.145497) (xy 163.887912 -409.119832) (xy 163.893721 -409.112696) (xy 163.900228 -409.095498)
			(xy 163.900612 -409.086304) (xy 163.900612 -408.594052) (xy 163.900174 -408.584868) (xy 163.893679 -408.567683)
			(xy 163.887912 -408.560524) (xy 163.86604 -408.534865) (xy 163.82795 -408.47923) (xy 163.796799 -408.419433)
			(xy 163.773035 -408.356335) (xy 163.757 -408.290845) (xy 163.748925 -408.223906) (xy 163.748925 -408.156482)
			(xy 163.757002 -408.089543) (xy 163.773039 -408.024053) (xy 163.796804 -407.960956) (xy 163.827957 -407.901159)
			(xy 163.866047 -407.845525) (xy 163.887912 -407.81986) (xy 163.893709 -407.812715) (xy 163.900223 -407.795524)
			(xy 163.900612 -407.786332) (xy 163.900612 -407.628852) (xy 163.901046 -407.618739) (xy 163.908802 -407.600057)
			(xy 163.923114 -407.585764) (xy 163.941806 -407.578033) (xy 163.95192 -407.577544) (xy 164.6682 -407.577544)
			(xy 164.678302 -407.578084) (xy 164.696969 -407.585811) (xy 164.711262 -407.60009) (xy 164.719007 -407.618751)
			(xy 164.719508 -407.628852) (xy 164.719508 -407.786332) (xy 164.719901 -407.795521) (xy 164.726426 -407.812705)
			(xy 164.732208 -407.81986) (xy 164.754064 -407.845532) (xy 164.792152 -407.901166) (xy 164.823303 -407.960961)
			(xy 164.847067 -408.024057) (xy 164.863103 -408.089545) (xy 164.871179 -408.156483) (xy 164.87118 -408.223905)
			(xy 164.863105 -408.290843) (xy 164.847071 -408.356332) (xy 164.823308 -408.419428) (xy 164.792158 -408.479224)
			(xy 164.754071 -408.534859) (xy 164.732208 -408.560524) (xy 164.72642 -408.567675) (xy 164.7199 -408.584861)
			(xy 164.719508 -408.594052) (xy 164.719508 -409.086304) (xy 164.719915 -409.095492) (xy 164.726431 -409.112676)
			(xy 164.732208 -409.119832) (xy 164.754036 -409.145527) (xy 164.792126 -409.201157) (xy 164.823277 -409.260949)
			(xy 164.847043 -409.324042) (xy 164.863081 -409.389528) (xy 164.87116 -409.456463) (xy 164.871163 -409.523883)
			(xy 164.863091 -409.590819) (xy 164.847059 -409.656306) (xy 164.8233 -409.719401) (xy 164.792153 -409.779196)
			(xy 164.75407 -409.834831) (xy 164.732208 -409.860496) (xy 164.726432 -409.867656) (xy 164.719905 -409.884835)
			(xy 164.719508 -409.894024) (xy 164.719508 -410.051504) (xy 164.719018 -410.061612) (xy 164.711281 -410.080289)
			(xy 164.696985 -410.094583) (xy 164.678308 -410.102319) (xy 164.6682 -410.102812) (xy 163.95192 -410.102812)
			(xy 163.9418 -410.102368) (xy 163.923099 -410.094629) (xy 163.908785 -410.080321) (xy 163.901037 -410.061624)
			(xy 163.900612 -410.051504) (xy 163.900612 -409.894024) (xy 163.900188 -409.884838) (xy 163.893683 -409.867654)
			(xy 163.887912 -409.860496) (xy 163.866012 -409.83486) (xy 163.827924 -409.779222) (xy 163.796774 -409.719422)
			(xy 163.773011 -409.656321) (xy 163.756978 -409.590828) (xy 163.748905 -409.523886) (xy 162.620757 -409.523886)
			(xy 162.592019 -409.579046) (xy 162.553926 -409.634679) (xy 162.53206 -409.660344) (xy 162.526257 -409.667485)
			(xy 162.519747 -409.684679) (xy 162.51936 -409.693872) (xy 162.51936 -410.186124) (xy 162.519768 -410.195311)
			(xy 162.526284 -410.212495) (xy 162.53206 -410.219652) (xy 162.55391 -410.24533) (xy 162.592001 -410.300961)
			(xy 162.623155 -410.360755) (xy 162.646922 -410.423851) (xy 162.66296 -410.489339) (xy 162.671038 -410.556276)
			(xy 162.671039 -410.623641) (xy 165.949078 -410.623641) (xy 165.949079 -410.556335) (xy 165.957125 -410.489511)
			(xy 165.9731 -410.424127) (xy 165.996775 -410.361122) (xy 166.027811 -410.301398) (xy 166.065763 -410.245812)
			(xy 166.087552 -410.22016) (xy 166.093354 -410.213019) (xy 166.099864 -410.195825) (xy 166.100252 -410.186632)
			(xy 166.100252 -409.693364) (xy 166.099847 -409.684176) (xy 166.093328 -409.666993) (xy 166.087552 -409.659836)
			(xy 166.065776 -409.634174) (xy 166.027826 -409.578589) (xy 165.996791 -409.518867) (xy 165.973117 -409.455864)
			(xy 165.957143 -409.390483) (xy 165.949098 -409.323661) (xy 165.949097 -409.256357) (xy 165.95714 -409.189535)
			(xy 165.973112 -409.124153) (xy 165.996784 -409.061149) (xy 166.027817 -409.001426) (xy 166.065765 -408.94584)
			(xy 166.087552 -408.920188) (xy 166.093343 -408.913039) (xy 166.099859 -408.895851) (xy 166.100252 -408.88666)
			(xy 166.100252 -408.728672) (xy 166.100698 -408.718522) (xy 166.108493 -408.699778) (xy 166.122882 -408.685458)
			(xy 166.141662 -408.67775) (xy 166.151814 -408.677364) (xy 166.868094 -408.677364) (xy 166.878223 -408.677832)
			(xy 166.896949 -408.685562) (xy 166.911306 -408.699855) (xy 166.919121 -408.718545) (xy 166.919656 -408.728672)
			(xy 166.919656 -408.88666) (xy 166.920095 -408.895844) (xy 166.92659 -408.913028) (xy 166.932356 -408.920188)
			(xy 166.954156 -408.94583) (xy 166.992105 -409.001418) (xy 167.023138 -409.061143) (xy 167.04681 -409.124149)
			(xy 167.062782 -409.189532) (xy 167.070826 -409.256356) (xy 167.070824 -409.323662) (xy 167.062779 -409.390486)
			(xy 167.046805 -409.455869) (xy 167.02313 -409.518874) (xy 167.020557 -409.523826) (xy 168.149224 -409.523826)
			(xy 168.149228 -409.456519) (xy 168.157275 -409.389695) (xy 168.17325 -409.324311) (xy 168.196925 -409.261305)
			(xy 168.227961 -409.201581) (xy 168.265911 -409.145993) (xy 168.2877 -409.12034) (xy 168.293505 -409.1132)
			(xy 168.300014 -409.096006) (xy 168.3004 -409.086812) (xy 168.3004 -408.593544) (xy 168.299969 -408.584359)
			(xy 168.29347 -408.567174) (xy 168.2877 -408.560016) (xy 168.265906 -408.53437) (xy 168.22796 -408.478782)
			(xy 168.196929 -408.419057) (xy 168.173258 -408.356052) (xy 168.157287 -408.290669) (xy 168.149244 -408.223846)
			(xy 168.149245 -408.156542) (xy 168.157289 -408.089719) (xy 168.173262 -408.024337) (xy 168.196934 -407.961332)
			(xy 168.227966 -407.901608) (xy 168.265913 -407.846021) (xy 168.2877 -407.820368) (xy 168.293493 -407.81322)
			(xy 168.30001 -407.796032) (xy 168.3004 -407.78684) (xy 168.3004 -407.628852) (xy 168.300782 -407.618695)
			(xy 168.308594 -407.599941) (xy 168.323002 -407.58562) (xy 168.341802 -407.577922) (xy 168.351962 -407.577544)
			(xy 169.068242 -407.577544) (xy 169.078372 -407.577992) (xy 169.097095 -407.585735) (xy 169.11145 -407.600032)
			(xy 169.119267 -407.618724) (xy 169.119804 -407.628852) (xy 169.119804 -407.78684) (xy 169.120194 -407.796029)
			(xy 169.126721 -407.813214) (xy 169.132504 -407.820368) (xy 169.154283 -407.846027) (xy 169.192229 -407.901614)
			(xy 169.22326 -407.961337) (xy 169.246931 -408.02434) (xy 169.262904 -408.089721) (xy 169.270948 -408.156542)
			(xy 169.270948 -408.223846) (xy 169.262906 -408.290667) (xy 169.246935 -408.356048) (xy 169.223265 -408.419052)
			(xy 169.192235 -408.478776) (xy 169.15429 -408.534363) (xy 169.132504 -408.560016) (xy 169.126719 -408.567169)
			(xy 169.120197 -408.584354) (xy 169.119804 -408.593544) (xy 169.119804 -409.086812) (xy 169.120208 -409.096)
			(xy 169.126726 -409.113184) (xy 169.132504 -409.12034) (xy 169.154255 -409.146022) (xy 169.192202 -409.201605)
			(xy 169.223235 -409.261325) (xy 169.246908 -409.324325) (xy 169.262882 -409.389704) (xy 169.270928 -409.456522)
			(xy 169.270931 -409.523824) (xy 169.262891 -409.590643) (xy 169.246924 -409.656023) (xy 169.223257 -409.719026)
			(xy 169.19223 -409.778748) (xy 169.154288 -409.834335) (xy 169.132504 -409.859988) (xy 169.126688 -409.86712)
			(xy 169.120185 -409.88432) (xy 169.119804 -409.893516) (xy 169.119804 -410.051504) (xy 169.119382 -410.061658)
			(xy 169.111586 -410.08041) (xy 169.097189 -410.094733) (xy 169.078398 -410.102433) (xy 169.068242 -410.102812)
			(xy 168.351962 -410.102812) (xy 168.341839 -410.102306) (xy 168.323127 -410.094575) (xy 168.308774 -410.080296)
			(xy 168.300947 -410.061624) (xy 168.3004 -410.051504) (xy 168.3004 -409.893516) (xy 168.299982 -409.88433)
			(xy 168.293474 -409.867145) (xy 168.2877 -409.859988) (xy 168.265878 -409.834364) (xy 168.227933 -409.778773)
			(xy 168.196903 -409.719045) (xy 168.173234 -409.656037) (xy 168.157265 -409.590652) (xy 168.149224 -409.523826)
			(xy 167.020557 -409.523826) (xy 166.992095 -409.578598) (xy 166.954145 -409.634184) (xy 166.932356 -409.659836)
			(xy 166.926556 -409.666979) (xy 166.920045 -409.684171) (xy 166.919656 -409.693364) (xy 166.919656 -410.186632)
			(xy 166.920061 -410.19582) (xy 166.926579 -410.213003) (xy 166.932356 -410.22016) (xy 166.954128 -410.245825)
			(xy 166.992078 -410.30141) (xy 167.023112 -410.361131) (xy 167.046786 -410.424134) (xy 167.06276 -410.489515)
			(xy 167.070805 -410.556336) (xy 167.070807 -410.62364) (xy 167.0708 -410.623701) (xy 170.348846 -410.623701)
			(xy 170.348847 -410.556275) (xy 170.356926 -410.489335) (xy 170.372964 -410.423844) (xy 170.396732 -410.360747)
			(xy 170.427888 -410.30095) (xy 170.465981 -410.245316) (xy 170.487848 -410.219652) (xy 170.493653 -410.212513)
			(xy 170.500162 -410.195318) (xy 170.500548 -410.186124) (xy 170.500548 -409.693872) (xy 170.50014 -409.684685)
			(xy 170.493624 -409.667501) (xy 170.487848 -409.660344) (xy 170.465994 -409.63467) (xy 170.427902 -409.579038)
			(xy 170.396748 -409.519243) (xy 170.372981 -409.456147) (xy 170.356943 -409.390659) (xy 170.348866 -409.323721)
			(xy 170.348865 -409.256297) (xy 170.35694 -409.189359) (xy 170.372976 -409.12387) (xy 170.396741 -409.060773)
			(xy 170.427893 -409.000978) (xy 170.465983 -408.945344) (xy 170.487848 -408.91968) (xy 170.493642 -408.912533)
			(xy 170.500157 -408.895344) (xy 170.500548 -408.886152) (xy 170.500548 -408.728672) (xy 170.501061 -408.718568)
			(xy 170.508798 -408.699899) (xy 170.523086 -408.685607) (xy 170.541752 -408.677864) (xy 170.551856 -408.677364)
			(xy 171.268136 -408.677364) (xy 171.278243 -408.677855) (xy 171.296915 -408.685598) (xy 171.311207 -408.699892)
			(xy 171.318947 -408.718565) (xy 171.319444 -408.728672) (xy 171.319444 -408.886152) (xy 171.31989 -408.895335)
			(xy 171.32638 -408.912519) (xy 171.332144 -408.91968) (xy 171.354022 -408.945335) (xy 171.392114 -409.000969)
			(xy 171.423267 -409.060766) (xy 171.447033 -409.123865) (xy 171.463069 -409.189356) (xy 171.471145 -409.256296)
			(xy 171.471144 -409.323722) (xy 171.463066 -409.390662) (xy 171.447028 -409.456152) (xy 171.42326 -409.51925)
			(xy 171.420875 -409.523827) (xy 172.548991 -409.523827) (xy 172.548995 -409.456519) (xy 172.557043 -409.389693)
			(xy 172.573021 -409.324308) (xy 172.5967 -409.261302) (xy 172.62774 -409.201577) (xy 172.665697 -409.145992)
			(xy 172.687488 -409.12034) (xy 172.693291 -409.113199) (xy 172.699802 -409.096005) (xy 172.700188 -409.086812)
			(xy 172.700188 -408.593544) (xy 172.699759 -408.584359) (xy 172.693259 -408.567174) (xy 172.687488 -408.560016)
			(xy 172.665691 -408.534371) (xy 172.627739 -408.478785) (xy 172.596704 -408.419061) (xy 172.573029 -408.356055)
			(xy 172.557055 -408.290671) (xy 172.549011 -408.223847) (xy 172.549012 -408.156541) (xy 172.557057 -408.089717)
			(xy 172.573033 -408.024333) (xy 172.596708 -407.961328) (xy 172.627745 -407.901605) (xy 172.665698 -407.84602)
			(xy 172.687488 -407.820368) (xy 172.693279 -407.813219) (xy 172.699797 -407.796031) (xy 172.700188 -407.78684)
			(xy 172.700188 -407.628852) (xy 172.700582 -407.618696) (xy 172.708391 -407.599945) (xy 172.722796 -407.585624)
			(xy 172.741592 -407.577924) (xy 172.75175 -407.577544) (xy 173.46803 -407.577544) (xy 173.478159 -407.578002)
			(xy 173.496882 -407.58574) (xy 173.511237 -407.600035) (xy 173.519055 -407.618725) (xy 173.519592 -407.628852)
			(xy 173.519592 -407.78684) (xy 173.519985 -407.796029) (xy 173.526511 -407.813213) (xy 173.532292 -407.820368)
			(xy 173.554071 -407.846027) (xy 173.592018 -407.901613) (xy 173.62305 -407.961336) (xy 173.646722 -408.02434)
			(xy 173.662694 -408.089721) (xy 173.670739 -408.156542) (xy 173.670739 -408.223846) (xy 173.662697 -408.290667)
			(xy 173.646725 -408.356049) (xy 173.623055 -408.419053) (xy 173.592024 -408.478776) (xy 173.554078 -408.534363)
			(xy 173.532292 -408.560016) (xy 173.526505 -408.567168) (xy 173.519985 -408.584353) (xy 173.519592 -408.593544)
			(xy 173.519592 -409.086812) (xy 173.519998 -409.096) (xy 173.526515 -409.113184) (xy 173.532292 -409.12034)
			(xy 173.554043 -409.146022) (xy 173.591991 -409.201605) (xy 173.623024 -409.261324) (xy 173.646698 -409.324325)
			(xy 173.662672 -409.389703) (xy 173.670719 -409.456522) (xy 173.670722 -409.523824) (xy 173.662682 -409.590643)
			(xy 173.646714 -409.656023) (xy 173.623047 -409.719026) (xy 173.592019 -409.778749) (xy 173.554077 -409.834336)
			(xy 173.532292 -409.859988) (xy 173.526475 -409.867118) (xy 173.519973 -409.88432) (xy 173.519592 -409.893516)
			(xy 173.519592 -410.051504) (xy 173.519181 -410.061659) (xy 173.511383 -410.080413) (xy 173.496983 -410.094737)
			(xy 173.478187 -410.102435) (xy 173.46803 -410.102812) (xy 172.75175 -410.102812) (xy 172.741633 -410.102234)
			(xy 172.722923 -410.094532) (xy 172.708567 -410.080274) (xy 172.700736 -410.061618) (xy 172.700188 -410.051504)
			(xy 172.700188 -409.893516) (xy 172.699773 -409.884329) (xy 172.693263 -409.867145) (xy 172.687488 -409.859988)
			(xy 172.665663 -409.834366) (xy 172.627713 -409.778776) (xy 172.596678 -409.719049) (xy 172.573005 -409.65604)
			(xy 172.557033 -409.590654) (xy 172.548991 -409.523827) (xy 171.420875 -409.523827) (xy 171.392104 -409.579046)
			(xy 171.354011 -409.63468) (xy 171.332144 -409.660344) (xy 171.326339 -409.667483) (xy 171.319831 -409.684679)
			(xy 171.319444 -409.693872) (xy 171.319444 -410.186124) (xy 171.319855 -410.195311) (xy 171.32637 -410.212494)
			(xy 171.332144 -410.219652) (xy 171.353994 -410.245329) (xy 171.392087 -410.300961) (xy 171.423242 -410.360755)
			(xy 171.447009 -410.42385) (xy 171.463047 -410.489338) (xy 171.471125 -410.556276) (xy 171.471127 -410.623641)
			(xy 174.749166 -410.623641) (xy 174.749167 -410.556335) (xy 174.757213 -410.489511) (xy 174.773187 -410.424128)
			(xy 174.796862 -410.361123) (xy 174.827897 -410.301399) (xy 174.865847 -410.245812) (xy 174.887636 -410.22016)
			(xy 174.893437 -410.213018) (xy 174.899948 -410.195825) (xy 174.900336 -410.186632) (xy 174.900336 -409.693364)
			(xy 174.899935 -409.684176) (xy 174.893414 -409.666992) (xy 174.887636 -409.659836) (xy 174.86586 -409.634174)
			(xy 174.827911 -409.578589) (xy 174.796878 -409.518867) (xy 174.773205 -409.455863) (xy 174.757231 -409.390482)
			(xy 174.749186 -409.323661) (xy 174.749185 -409.256357) (xy 174.757228 -409.189535) (xy 174.773199 -409.124154)
			(xy 174.79687 -409.06115) (xy 174.827902 -409.001427) (xy 174.865849 -408.94584) (xy 174.887636 -408.920188)
			(xy 174.893425 -408.913037) (xy 174.899943 -408.895851) (xy 174.900336 -408.88666) (xy 174.900336 -408.728672)
			(xy 174.900699 -408.718512) (xy 174.908511 -408.699752) (xy 174.922926 -408.685428) (xy 174.941735 -408.677736)
			(xy 174.951898 -408.677364) (xy 175.668178 -408.677364) (xy 175.678306 -408.677845) (xy 175.697032 -408.68557)
			(xy 175.711389 -408.699859) (xy 175.719205 -408.718546) (xy 175.71974 -408.728672) (xy 175.71974 -408.88666)
			(xy 175.720183 -408.895843) (xy 175.726675 -408.913028) (xy 175.73244 -408.920188) (xy 175.75424 -408.94583)
			(xy 175.79219 -409.001418) (xy 175.823224 -409.061142) (xy 175.846897 -409.124148) (xy 175.862869 -409.189532)
			(xy 175.870913 -409.256356) (xy 175.870912 -409.323662) (xy 175.862866 -409.390486) (xy 175.846891 -409.455869)
			(xy 175.823216 -409.518874) (xy 175.792181 -409.578598) (xy 175.754229 -409.634184) (xy 175.73244 -409.659836)
			(xy 175.726638 -409.666977) (xy 175.720128 -409.684171) (xy 175.71974 -409.693364) (xy 175.71974 -410.186632)
			(xy 175.720148 -410.195819) (xy 175.726665 -410.213003) (xy 175.73244 -410.22016) (xy 175.754213 -410.245825)
			(xy 175.792163 -410.301409) (xy 175.823198 -410.361131) (xy 175.846873 -410.424134) (xy 175.862848 -410.489514)
			(xy 175.870893 -410.556336) (xy 175.870895 -410.62364) (xy 175.862852 -410.690462) (xy 175.84688 -410.755843)
			(xy 175.823208 -410.818847) (xy 175.792176 -410.87857) (xy 175.754227 -410.934156) (xy 175.73244 -410.959808)
			(xy 175.72665 -410.966958) (xy 175.720133 -410.984145) (xy 175.71974 -410.993336) (xy 175.71974 -411.151324)
			(xy 175.719299 -411.161475) (xy 175.711503 -411.18022) (xy 175.697113 -411.194541) (xy 175.678331 -411.202247)
			(xy 175.668178 -411.202632) (xy 174.951898 -411.202632) (xy 174.941768 -411.202174) (xy 174.923041 -411.194441)
			(xy 174.908684 -411.180145) (xy 174.90087 -411.161452) (xy 174.900336 -411.151324) (xy 174.900336 -410.993336)
			(xy 174.8999 -410.984152) (xy 174.893403 -410.966968) (xy 174.887636 -410.959808) (xy 174.865833 -410.934169)
			(xy 174.827884 -410.87858) (xy 174.796852 -410.818855) (xy 174.77318 -410.755849) (xy 174.757208 -410.690465)
			(xy 174.749166 -410.623641) (xy 171.471127 -410.623641) (xy 171.471127 -410.6237) (xy 171.463052 -410.690638)
			(xy 171.447016 -410.756127) (xy 171.423251 -410.819223) (xy 171.392099 -410.879019) (xy 171.354009 -410.934652)
			(xy 171.332144 -410.960316) (xy 171.326351 -410.967464) (xy 171.319836 -410.984653) (xy 171.319444 -410.993844)
			(xy 171.319444 -411.151324) (xy 171.318936 -411.161429) (xy 171.311198 -411.180099) (xy 171.296909 -411.194392)
			(xy 171.278241 -411.202133) (xy 171.268136 -411.202632) (xy 170.551856 -411.202632) (xy 170.541748 -411.202152)
			(xy 170.523075 -411.194405) (xy 170.508783 -411.180108) (xy 170.501044 -411.161432) (xy 170.500548 -411.151324)
			(xy 170.500548 -410.993844) (xy 170.500106 -410.98466) (xy 170.493613 -410.967476) (xy 170.487848 -410.960316)
			(xy 170.465967 -410.934665) (xy 170.427875 -410.879029) (xy 170.396723 -410.819232) (xy 170.372957 -410.756133)
			(xy 170.356921 -410.690641) (xy 170.348846 -410.623701) (xy 167.0708 -410.623701) (xy 167.062764 -410.690461)
			(xy 167.046793 -410.755843) (xy 167.023122 -410.818847) (xy 166.99209 -410.87857) (xy 166.954143 -410.934156)
			(xy 166.932356 -410.959808) (xy 166.926568 -410.966959) (xy 166.920049 -410.984145) (xy 166.919656 -410.993336)
			(xy 166.919656 -411.151324) (xy 166.919199 -411.161473) (xy 166.911406 -411.180215) (xy 166.897021 -411.194535)
			(xy 166.878245 -411.202244) (xy 166.868094 -411.202632) (xy 166.151814 -411.202632) (xy 166.141685 -411.202161)
			(xy 166.122959 -411.194433) (xy 166.108601 -411.180141) (xy 166.100786 -411.161451) (xy 166.100252 -411.151324)
			(xy 166.100252 -410.993336) (xy 166.099813 -410.984152) (xy 166.093318 -410.966968) (xy 166.087552 -410.959808)
			(xy 166.065748 -410.934169) (xy 166.027799 -410.878581) (xy 165.996765 -410.818856) (xy 165.973093 -410.75585)
			(xy 165.957121 -410.690466) (xy 165.949078 -410.623641) (xy 162.671039 -410.623641) (xy 162.671039 -410.6237)
			(xy 162.662964 -410.690637) (xy 162.646929 -410.756126) (xy 162.623165 -410.819223) (xy 162.592014 -410.879018)
			(xy 162.553924 -410.934651) (xy 162.53206 -410.960316) (xy 162.526269 -410.967465) (xy 162.519752 -410.984653)
			(xy 162.51936 -410.993844) (xy 162.51936 -411.151324) (xy 162.519003 -411.161453) (xy 162.511239 -411.180165)
			(xy 162.496904 -411.19448) (xy 162.478182 -411.202217) (xy 162.468052 -411.202632) (xy 161.751772 -411.202632)
			(xy 161.741665 -411.202139) (xy 161.722993 -411.194398) (xy 161.7087 -411.180104) (xy 161.700961 -411.161431)
			(xy 161.700464 -411.151324) (xy 161.700464 -410.993844) (xy 161.700019 -410.984661) (xy 161.693528 -410.967477)
			(xy 161.687764 -410.960316) (xy 161.665886 -410.934663) (xy 161.6278 -410.879026) (xy 161.596652 -410.819228)
			(xy 161.57289 -410.756129) (xy 161.556857 -410.690639) (xy 161.548783 -410.6237) (xy 154.57678 -410.6237)
			(xy 154.57678 -417.371276) (xy 154.576371 -417.383441) (xy 154.568857 -417.406581) (xy 154.554556 -417.426265)
			(xy 154.53487 -417.440562) (xy 154.511729 -417.448073) (xy 154.499564 -417.448492) (xy 141.100302 -417.448492)
			(xy 141.088157 -417.448035) (xy 141.06506 -417.440516) (xy 141.045426 -417.426216) (xy 141.031183 -417.406541)
			(xy 141.02373 -417.383422) (xy 141.02334 -417.371276) (xy 66.525648 -417.371276) (xy 66.525648 -417.533836)
			(xy 66.525172 -417.545883) (xy 66.517735 -417.568802) (xy 66.503597 -417.588313) (xy 66.484133 -417.602517)
			(xy 66.46124 -417.610031) (xy 66.449194 -417.610544) (xy 53.151024 -417.610544) (xy 53.138954 -417.610016)
			(xy 53.115994 -417.602564) (xy 53.09646 -417.588383) (xy 53.082263 -417.56886) (xy 53.074793 -417.545905)
			(xy 53.074316 -417.533836) (xy 53.074316 -417.289488) (xy 53.073808 -417.289488) (xy 0.681656 -417.289488)
			(xy 0.736245 -417.384039) (xy 0.79912 -417.476259) (xy 0.86871 -417.563523) (xy 0.944627 -417.645342)
			(xy 1.026446 -417.721259) (xy 1.113709 -417.790849) (xy 1.205929 -417.853724) (xy 1.302589 -417.909531)
			(xy 1.40315 -417.957958) (xy 1.507049 -417.998736) (xy 1.613704 -418.031635) (xy 1.72252 -418.056471)
			(xy 1.832887 -418.073107) (xy 1.944189 -418.081448) (xy 1.999996 -418.081968)
		)
		(stroke
			(width 0)
			(type solid)
		)
		(fill yes)
		(layer "In10.Cu")
		(net "GND")
	)
	(gr_line
		(start 20.365466 -130.829304)
		(end 20.365466 -132.988304)
		(stroke
			(width 0.1016)
			(type default)
		)
		(layer "In10.Cu")
	)
	(gr_line
		(start 21.142198 -130.82905)
		(end 20.365466 -130.829304)
		(stroke
			(width 0.1016)
			(type default)
		)
		(layer "In10.Cu")
	)
	(gr_line
		(start 21.142706 -132.988304)
		(end 21.142198 -130.82905)
		(stroke
			(width 0.1016)
			(type default)
		)
		(layer "In10.Cu")
	)
	(gr_line
		(start 24.040592 -156.489146)
		(end 24.41194 -158.615888)
		(stroke
			(width 0.1016)
			(type default)
		)
		(layer "In10.Cu")
	)
	(gr_line
		(start 24.805894 -156.355034)
		(end 24.040592 -156.489146)
		(stroke
			(width 0.1016)
			(type default)
		)
		(layer "In10.Cu")
	)
	(gr_line
		(start 25.177496 -158.48203)
		(end 24.805894 -156.355034)
		(stroke
			(width 0.1016)
			(type default)
		)
		(layer "In10.Cu")
	)
	(gr_line
		(start 26.52268 -115.836446)
		(end 25.896062 -117.902482)
		(stroke
			(width 0.1016)
			(type default)
		)
		(layer "In10.Cu")
	)
	(gr_line
		(start 26.640028 -118.128034)
		(end 27.266392 -116.061998)
		(stroke
			(width 0.1016)
			(type default)
		)
		(layer "In10.Cu")
	)
	(gr_line
		(start 27.266392 -116.061998)
		(end 26.52268 -115.836446)
		(stroke
			(width 0.1016)
			(type default)
		)
		(layer "In10.Cu")
	)
	(gr_line
		(start 28.043886 -117.404642)
		(end 27.417268 -119.470678)
		(stroke
			(width 0.1016)
			(type default)
		)
		(layer "In10.Cu")
	)
	(gr_line
		(start 28.161234 -119.69623)
		(end 28.787598 -117.630194)
		(stroke
			(width 0.1016)
			(type default)
		)
		(layer "In10.Cu")
	)
	(gr_line
		(start 28.787598 -117.630194)
		(end 28.043886 -117.404642)
		(stroke
			(width 0.1016)
			(type default)
		)
		(layer "In10.Cu")
	)
	(gr_line
		(start 30.445456 -110.673642)
		(end 31.271464 -108.678726)
		(stroke
			(width 0.1016)
			(type default)
		)
		(layer "In10.Cu")
	)
	(gr_line
		(start 30.55366 -108.381546)
		(end 29.727398 -110.376208)
		(stroke
			(width 0.1016)
			(type default)
		)
		(layer "In10.Cu")
	)
	(gr_line
		(start 31.271464 -108.678726)
		(end 30.55366 -108.381546)
		(stroke
			(width 0.1016)
			(type default)
		)
		(layer "In10.Cu")
	)
	(gr_line
		(start 31.494222 -167.626792)
		(end 32.186372 -169.671746)
		(stroke
			(width 0.1016)
			(type default)
		)
		(layer "In10.Cu")
	)
	(gr_line
		(start 32.230314 -167.377618)
		(end 31.494222 -167.626792)
		(stroke
			(width 0.1016)
			(type default)
		)
		(layer "In10.Cu")
	)
	(gr_line
		(start 32.922718 -169.422572)
		(end 32.230314 -167.377618)
		(stroke
			(width 0.1016)
			(type default)
		)
		(layer "In10.Cu")
	)
	(gr_circle
		(center 43.499786 -312.049922)
		(end 43.753786 -312.049922)
		(stroke
			(width 0.1016)
			(type default)
		)
		(fill no)
		(layer "In10.Cu")
	)
	(gr_circle
		(center 43.499786 -311.099962)
		(end 43.753786 -311.099962)
		(stroke
			(width 0.1016)
			(type default)
		)
		(fill no)
		(layer "In10.Cu")
	)
	(gr_circle
		(center 44.449746 -313.949842)
		(end 44.703746 -313.949842)
		(stroke
			(width 0.1016)
			(type default)
		)
		(fill no)
		(layer "In10.Cu")
	)
	(gr_circle
		(center 44.449746 -312.999882)
		(end 44.703746 -312.999882)
		(stroke
			(width 0.1016)
			(type default)
		)
		(fill no)
		(layer "In10.Cu")
	)
	(gr_circle
		(center 44.449746 -278.799798)
		(end 44.703746 -278.799798)
		(stroke
			(width 0.1016)
			(type default)
		)
		(fill no)
		(layer "In10.Cu")
	)
	(gr_circle
		(center 44.449746 -277.849838)
		(end 44.703746 -277.849838)
		(stroke
			(width 0.1016)
			(type default)
		)
		(fill no)
		(layer "In10.Cu")
	)
	(gr_circle
		(center 45.39996 -312.049922)
		(end 45.65396 -312.049922)
		(stroke
			(width 0.1016)
			(type default)
		)
		(fill no)
		(layer "In10.Cu")
	)
	(gr_circle
		(center 45.39996 -311.099962)
		(end 45.65396 -311.099962)
		(stroke
			(width 0.1016)
			(type default)
		)
		(fill no)
		(layer "In10.Cu")
	)
	(gr_circle
		(center 45.39996 -280.699464)
		(end 45.65396 -280.699464)
		(stroke
			(width 0.1016)
			(type default)
		)
		(fill no)
		(layer "In10.Cu")
	)
	(gr_circle
		(center 45.39996 -279.749504)
		(end 45.65396 -279.749504)
		(stroke
			(width 0.1016)
			(type default)
		)
		(fill no)
		(layer "In10.Cu")
	)
	(gr_circle
		(center 46.34992 -313.949842)
		(end 46.60392 -313.949842)
		(stroke
			(width 0.1016)
			(type default)
		)
		(fill no)
		(layer "In10.Cu")
	)
	(gr_circle
		(center 46.34992 -312.999882)
		(end 46.60392 -312.999882)
		(stroke
			(width 0.1016)
			(type default)
		)
		(fill no)
		(layer "In10.Cu")
	)
	(gr_circle
		(center 46.34992 -278.799798)
		(end 46.60392 -278.799798)
		(stroke
			(width 0.1016)
			(type default)
		)
		(fill no)
		(layer "In10.Cu")
	)
	(gr_circle
		(center 46.34992 -277.849838)
		(end 46.60392 -277.849838)
		(stroke
			(width 0.1016)
			(type default)
		)
		(fill no)
		(layer "In10.Cu")
	)
	(gr_circle
		(center 47.29988 -312.049922)
		(end 47.55388 -312.049922)
		(stroke
			(width 0.1016)
			(type default)
		)
		(fill no)
		(layer "In10.Cu")
	)
	(gr_circle
		(center 47.29988 -311.099962)
		(end 47.55388 -311.099962)
		(stroke
			(width 0.1016)
			(type default)
		)
		(fill no)
		(layer "In10.Cu")
	)
	(gr_circle
		(center 47.29988 -280.699464)
		(end 47.55388 -280.699464)
		(stroke
			(width 0.1016)
			(type default)
		)
		(fill no)
		(layer "In10.Cu")
	)
	(gr_circle
		(center 47.29988 -279.749504)
		(end 47.55388 -279.749504)
		(stroke
			(width 0.1016)
			(type default)
		)
		(fill no)
		(layer "In10.Cu")
	)
	(gr_circle
		(center 48.24984 -313.949842)
		(end 48.50384 -313.949842)
		(stroke
			(width 0.1016)
			(type default)
		)
		(fill no)
		(layer "In10.Cu")
	)
	(gr_circle
		(center 48.24984 -312.999882)
		(end 48.50384 -312.999882)
		(stroke
			(width 0.1016)
			(type default)
		)
		(fill no)
		(layer "In10.Cu")
	)
	(gr_circle
		(center 48.24984 -278.799798)
		(end 48.50384 -278.799798)
		(stroke
			(width 0.1016)
			(type default)
		)
		(fill no)
		(layer "In10.Cu")
	)
	(gr_circle
		(center 48.24984 -277.849838)
		(end 48.50384 -277.849838)
		(stroke
			(width 0.1016)
			(type default)
		)
		(fill no)
		(layer "In10.Cu")
	)
	(gr_circle
		(center 49.1998 -312.049922)
		(end 49.4538 -312.049922)
		(stroke
			(width 0.1016)
			(type default)
		)
		(fill no)
		(layer "In10.Cu")
	)
	(gr_circle
		(center 49.1998 -311.099962)
		(end 49.4538 -311.099962)
		(stroke
			(width 0.1016)
			(type default)
		)
		(fill no)
		(layer "In10.Cu")
	)
	(gr_circle
		(center 49.1998 -280.699464)
		(end 49.4538 -280.699464)
		(stroke
			(width 0.1016)
			(type default)
		)
		(fill no)
		(layer "In10.Cu")
	)
	(gr_circle
		(center 49.1998 -279.749504)
		(end 49.4538 -279.749504)
		(stroke
			(width 0.1016)
			(type default)
		)
		(fill no)
		(layer "In10.Cu")
	)
	(gr_circle
		(center 50.14976 -313.949842)
		(end 50.40376 -313.949842)
		(stroke
			(width 0.1016)
			(type default)
		)
		(fill no)
		(layer "In10.Cu")
	)
	(gr_circle
		(center 50.14976 -312.999882)
		(end 50.40376 -312.999882)
		(stroke
			(width 0.1016)
			(type default)
		)
		(fill no)
		(layer "In10.Cu")
	)
	(gr_circle
		(center 50.14976 -278.799798)
		(end 50.40376 -278.799798)
		(stroke
			(width 0.1016)
			(type default)
		)
		(fill no)
		(layer "In10.Cu")
	)
	(gr_circle
		(center 50.14976 -277.849838)
		(end 50.40376 -277.849838)
		(stroke
			(width 0.1016)
			(type default)
		)
		(fill no)
		(layer "In10.Cu")
	)
	(gr_circle
		(center 51.099974 -312.049922)
		(end 51.353974 -312.049922)
		(stroke
			(width 0.1016)
			(type default)
		)
		(fill no)
		(layer "In10.Cu")
	)
	(gr_circle
		(center 51.099974 -311.099962)
		(end 51.353974 -311.099962)
		(stroke
			(width 0.1016)
			(type default)
		)
		(fill no)
		(layer "In10.Cu")
	)
	(gr_circle
		(center 51.099974 -280.699464)
		(end 51.353974 -280.699464)
		(stroke
			(width 0.1016)
			(type default)
		)
		(fill no)
		(layer "In10.Cu")
	)
	(gr_circle
		(center 51.099974 -279.749504)
		(end 51.353974 -279.749504)
		(stroke
			(width 0.1016)
			(type default)
		)
		(fill no)
		(layer "In10.Cu")
	)
	(gr_circle
		(center 52.049934 -313.949842)
		(end 52.303934 -313.949842)
		(stroke
			(width 0.1016)
			(type default)
		)
		(fill no)
		(layer "In10.Cu")
	)
	(gr_circle
		(center 52.049934 -312.999882)
		(end 52.303934 -312.999882)
		(stroke
			(width 0.1016)
			(type default)
		)
		(fill no)
		(layer "In10.Cu")
	)
	(gr_circle
		(center 52.049934 -278.799798)
		(end 52.303934 -278.799798)
		(stroke
			(width 0.1016)
			(type default)
		)
		(fill no)
		(layer "In10.Cu")
	)
	(gr_circle
		(center 52.049934 -277.849838)
		(end 52.303934 -277.849838)
		(stroke
			(width 0.1016)
			(type default)
		)
		(fill no)
		(layer "In10.Cu")
	)
	(gr_circle
		(center 52.999894 -312.049922)
		(end 53.253894 -312.049922)
		(stroke
			(width 0.1016)
			(type default)
		)
		(fill no)
		(layer "In10.Cu")
	)
	(gr_circle
		(center 52.999894 -311.099962)
		(end 53.253894 -311.099962)
		(stroke
			(width 0.1016)
			(type default)
		)
		(fill no)
		(layer "In10.Cu")
	)
	(gr_circle
		(center 52.999894 -280.699464)
		(end 53.253894 -280.699464)
		(stroke
			(width 0.1016)
			(type default)
		)
		(fill no)
		(layer "In10.Cu")
	)
	(gr_circle
		(center 52.999894 -279.749504)
		(end 53.253894 -279.749504)
		(stroke
			(width 0.1016)
			(type default)
		)
		(fill no)
		(layer "In10.Cu")
	)
	(gr_circle
		(center 53.949854 -313.949842)
		(end 54.203854 -313.949842)
		(stroke
			(width 0.1016)
			(type default)
		)
		(fill no)
		(layer "In10.Cu")
	)
	(gr_circle
		(center 53.949854 -312.999882)
		(end 54.203854 -312.999882)
		(stroke
			(width 0.1016)
			(type default)
		)
		(fill no)
		(layer "In10.Cu")
	)
	(gr_circle
		(center 53.949854 -278.799798)
		(end 54.203854 -278.799798)
		(stroke
			(width 0.1016)
			(type default)
		)
		(fill no)
		(layer "In10.Cu")
	)
	(gr_circle
		(center 53.949854 -277.849838)
		(end 54.203854 -277.849838)
		(stroke
			(width 0.1016)
			(type default)
		)
		(fill no)
		(layer "In10.Cu")
	)
	(gr_circle
		(center 54.899814 -312.049922)
		(end 55.153814 -312.049922)
		(stroke
			(width 0.1016)
			(type default)
		)
		(fill no)
		(layer "In10.Cu")
	)
	(gr_circle
		(center 54.899814 -311.099962)
		(end 55.153814 -311.099962)
		(stroke
			(width 0.1016)
			(type default)
		)
		(fill no)
		(layer "In10.Cu")
	)
	(gr_circle
		(center 54.899814 -280.699464)
		(end 55.153814 -280.699464)
		(stroke
			(width 0.1016)
			(type default)
		)
		(fill no)
		(layer "In10.Cu")
	)
	(gr_circle
		(center 54.899814 -279.749504)
		(end 55.153814 -279.749504)
		(stroke
			(width 0.1016)
			(type default)
		)
		(fill no)
		(layer "In10.Cu")
	)
	(gr_circle
		(center 55.849774 -313.949842)
		(end 56.103774 -313.949842)
		(stroke
			(width 0.1016)
			(type default)
		)
		(fill no)
		(layer "In10.Cu")
	)
	(gr_circle
		(center 55.849774 -312.999882)
		(end 56.103774 -312.999882)
		(stroke
			(width 0.1016)
			(type default)
		)
		(fill no)
		(layer "In10.Cu")
	)
	(gr_circle
		(center 55.849774 -278.799798)
		(end 56.103774 -278.799798)
		(stroke
			(width 0.1016)
			(type default)
		)
		(fill no)
		(layer "In10.Cu")
	)
	(gr_circle
		(center 55.849774 -277.849838)
		(end 56.103774 -277.849838)
		(stroke
			(width 0.1016)
			(type default)
		)
		(fill no)
		(layer "In10.Cu")
	)
	(gr_circle
		(center 56.799734 -280.699464)
		(end 57.053734 -280.699464)
		(stroke
			(width 0.1016)
			(type default)
		)
		(fill no)
		(layer "In10.Cu")
	)
	(gr_circle
		(center 56.799734 -279.749504)
		(end 57.053734 -279.749504)
		(stroke
			(width 0.1016)
			(type default)
		)
		(fill no)
		(layer "In10.Cu")
	)
	(gr_circle
		(center 56.799988 -312.049922)
		(end 57.053988 -312.049922)
		(stroke
			(width 0.1016)
			(type default)
		)
		(fill no)
		(layer "In10.Cu")
	)
	(gr_circle
		(center 56.799988 -311.099962)
		(end 57.053988 -311.099962)
		(stroke
			(width 0.1016)
			(type default)
		)
		(fill no)
		(layer "In10.Cu")
	)
	(gr_circle
		(center 57.749948 -313.949842)
		(end 58.003948 -313.949842)
		(stroke
			(width 0.1016)
			(type default)
		)
		(fill no)
		(layer "In10.Cu")
	)
	(gr_circle
		(center 57.749948 -312.999882)
		(end 58.003948 -312.999882)
		(stroke
			(width 0.1016)
			(type default)
		)
		(fill no)
		(layer "In10.Cu")
	)
	(gr_circle
		(center 57.749948 -278.799798)
		(end 58.003948 -278.799798)
		(stroke
			(width 0.1016)
			(type default)
		)
		(fill no)
		(layer "In10.Cu")
	)
	(gr_circle
		(center 57.749948 -277.849838)
		(end 58.003948 -277.849838)
		(stroke
			(width 0.1016)
			(type default)
		)
		(fill no)
		(layer "In10.Cu")
	)
	(gr_circle
		(center 58.699908 -280.699464)
		(end 58.953908 -280.699464)
		(stroke
			(width 0.1016)
			(type default)
		)
		(fill no)
		(layer "In10.Cu")
	)
	(gr_circle
		(center 58.699908 -279.749504)
		(end 58.953908 -279.749504)
		(stroke
			(width 0.1016)
			(type default)
		)
		(fill no)
		(layer "In10.Cu")
	)
	(gr_line
		(start 61.530992 -259.328666)
		(end 62.223142 -261.37362)
		(stroke
			(width 0.1016)
			(type default)
		)
		(layer "In10.Cu")
	)
	(gr_line
		(start 61.749432 -251.115068)
		(end 62.441582 -253.160022)
		(stroke
			(width 0.0254)
			(type default)
		)
		(layer "In10.Cu")
	)
	(gr_line
		(start 61.759592 -251.115068)
		(end 62.451742 -253.160022)
		(stroke
			(width 0.1016)
			(type default)
		)
		(layer "In10.Cu")
	)
	(gr_line
		(start 62.267084 -259.079492)
		(end 61.530992 -259.328666)
		(stroke
			(width 0.1016)
			(type default)
		)
		(layer "In10.Cu")
	)
	(gr_line
		(start 62.485524 -250.865894)
		(end 61.749432 -251.115068)
		(stroke
			(width 0.0254)
			(type default)
		)
		(layer "In10.Cu")
	)
	(gr_line
		(start 62.495684 -250.865894)
		(end 61.759592 -251.115068)
		(stroke
			(width 0.1016)
			(type default)
		)
		(layer "In10.Cu")
	)
	(gr_line
		(start 62.618366 -247.723406)
		(end 63.310516 -249.76836)
		(stroke
			(width 0.1016)
			(type default)
		)
		(layer "In10.Cu")
	)
	(gr_line
		(start 62.959488 -261.124446)
		(end 62.267084 -259.079492)
		(stroke
			(width 0.1016)
			(type default)
		)
		(layer "In10.Cu")
	)
	(gr_line
		(start 63.177928 -252.910848)
		(end 62.485524 -250.865894)
		(stroke
			(width 0.0254)
			(type default)
		)
		(layer "In10.Cu")
	)
	(gr_line
		(start 63.188088 -252.910848)
		(end 62.495684 -250.865894)
		(stroke
			(width 0.1016)
			(type default)
		)
		(layer "In10.Cu")
	)
	(gr_line
		(start 63.354458 -247.474232)
		(end 62.618366 -247.723406)
		(stroke
			(width 0.1016)
			(type default)
		)
		(layer "In10.Cu")
	)
	(gr_line
		(start 63.430912 -259.014722)
		(end 64.123062 -261.059676)
		(stroke
			(width 0.1016)
			(type default)
		)
		(layer "In10.Cu")
	)
	(gr_line
		(start 64.046862 -249.519186)
		(end 63.354458 -247.474232)
		(stroke
			(width 0.1016)
			(type default)
		)
		(layer "In10.Cu")
	)
	(gr_line
		(start 64.167004 -258.765548)
		(end 63.430912 -259.014722)
		(stroke
			(width 0.1016)
			(type default)
		)
		(layer "In10.Cu")
	)
	(gr_line
		(start 64.532764 -247.453404)
		(end 65.224914 -249.498358)
		(stroke
			(width 0.1016)
			(type default)
		)
		(layer "In10.Cu")
	)
	(gr_line
		(start 64.859408 -260.810502)
		(end 64.167004 -258.765548)
		(stroke
			(width 0.1016)
			(type default)
		)
		(layer "In10.Cu")
	)
	(gr_line
		(start 65.268856 -247.20423)
		(end 64.532764 -247.453404)
		(stroke
			(width 0.1016)
			(type default)
		)
		(layer "In10.Cu")
	)
	(gr_line
		(start 65.330832 -258.703064)
		(end 66.022982 -260.748018)
		(stroke
			(width 0.1016)
			(type default)
		)
		(layer "In10.Cu")
	)
	(gr_line
		(start 65.96126 -249.249184)
		(end 65.268856 -247.20423)
		(stroke
			(width 0.1016)
			(type default)
		)
		(layer "In10.Cu")
	)
	(gr_line
		(start 66.066924 -258.45389)
		(end 65.330832 -258.703064)
		(stroke
			(width 0.1016)
			(type default)
		)
		(layer "In10.Cu")
	)
	(gr_line
		(start 66.41719 -247.098566)
		(end 67.10934 -249.14352)
		(stroke
			(width 0.1016)
			(type default)
		)
		(layer "In10.Cu")
	)
	(gr_line
		(start 66.759328 -260.498844)
		(end 66.066924 -258.45389)
		(stroke
			(width 0.1016)
			(type default)
		)
		(layer "In10.Cu")
	)
	(gr_line
		(start 67.03314 -257.804412)
		(end 67.72529 -259.849366)
		(stroke
			(width 0.1016)
			(type default)
		)
		(layer "In10.Cu")
	)
	(gr_line
		(start 67.153282 -246.849392)
		(end 66.41719 -247.098566)
		(stroke
			(width 0.1016)
			(type default)
		)
		(layer "In10.Cu")
	)
	(gr_line
		(start 67.769232 -257.555238)
		(end 67.03314 -257.804412)
		(stroke
			(width 0.1016)
			(type default)
		)
		(layer "In10.Cu")
	)
	(gr_line
		(start 67.845686 -248.894346)
		(end 67.153282 -246.849392)
		(stroke
			(width 0.1016)
			(type default)
		)
		(layer "In10.Cu")
	)
	(gr_line
		(start 68.461636 -259.600192)
		(end 67.769232 -257.555238)
		(stroke
			(width 0.1016)
			(type default)
		)
		(layer "In10.Cu")
	)
	(gr_line
		(start 68.947538 -257.53441)
		(end 69.639688 -259.579364)
		(stroke
			(width 0.1016)
			(type default)
		)
		(layer "In10.Cu")
	)
	(gr_line
		(start 69.68363 -257.285236)
		(end 68.947538 -257.53441)
		(stroke
			(width 0.1016)
			(type default)
		)
		(layer "In10.Cu")
	)
	(gr_line
		(start 70.376034 -259.33019)
		(end 69.68363 -257.285236)
		(stroke
			(width 0.1016)
			(type default)
		)
		(layer "In10.Cu")
	)
	(gr_line
		(start 70.83298 -257.179572)
		(end 71.52513 -259.224526)
		(stroke
			(width 0.1016)
			(type default)
		)
		(layer "In10.Cu")
	)
	(gr_line
		(start 71.569072 -256.930398)
		(end 70.83298 -257.179572)
		(stroke
			(width 0.1016)
			(type default)
		)
		(layer "In10.Cu")
	)
	(gr_line
		(start 72.068944 -230.902256)
		(end 72.408542 -233.034332)
		(stroke
			(width 0.1016)
			(type default)
		)
		(layer "In10.Cu")
	)
	(gr_line
		(start 72.261476 -258.975352)
		(end 71.569072 -256.930398)
		(stroke
			(width 0.1016)
			(type default)
		)
		(layer "In10.Cu")
	)
	(gr_line
		(start 72.836024 -230.779828)
		(end 72.068944 -230.902256)
		(stroke
			(width 0.1016)
			(type default)
		)
		(layer "In10.Cu")
	)
	(gr_line
		(start 73.176384 -232.912158)
		(end 72.836024 -230.779828)
		(stroke
			(width 0.1016)
			(type default)
		)
		(layer "In10.Cu")
	)
	(gr_line
		(start 73.543414 -246.090948)
		(end 73.883012 -248.223024)
		(stroke
			(width 0.1016)
			(type default)
		)
		(layer "In10.Cu")
	)
	(gr_circle
		(center 73.899776 -316.799722)
		(end 74.153776 -316.799722)
		(stroke
			(width 0.1016)
			(type default)
		)
		(fill no)
		(layer "In10.Cu")
	)
	(gr_circle
		(center 73.899776 -315.849762)
		(end 74.153776 -315.849762)
		(stroke
			(width 0.1016)
			(type default)
		)
		(fill no)
		(layer "In10.Cu")
	)
	(gr_circle
		(center 73.899776 -312.049922)
		(end 74.153776 -312.049922)
		(stroke
			(width 0.1016)
			(type default)
		)
		(fill no)
		(layer "In10.Cu")
	)
	(gr_circle
		(center 73.899776 -311.099962)
		(end 74.153776 -311.099962)
		(stroke
			(width 0.1016)
			(type default)
		)
		(fill no)
		(layer "In10.Cu")
	)
	(gr_line
		(start 73.942702 -230.828596)
		(end 74.2823 -232.960672)
		(stroke
			(width 0.1016)
			(type default)
		)
		(layer "In10.Cu")
	)
	(gr_line
		(start 74.310494 -245.96852)
		(end 73.543414 -246.090948)
		(stroke
			(width 0.1016)
			(type default)
		)
		(layer "In10.Cu")
	)
	(gr_line
		(start 74.650854 -248.10085)
		(end 74.310494 -245.96852)
		(stroke
			(width 0.1016)
			(type default)
		)
		(layer "In10.Cu")
	)
	(gr_line
		(start 74.709782 -230.706168)
		(end 73.942702 -230.828596)
		(stroke
			(width 0.1016)
			(type default)
		)
		(layer "In10.Cu")
	)
	(gr_circle
		(center 74.84999 -318.699896)
		(end 75.10399 -318.699896)
		(stroke
			(width 0.1016)
			(type default)
		)
		(fill no)
		(layer "In10.Cu")
	)
	(gr_circle
		(center 74.84999 -317.749936)
		(end 75.10399 -317.749936)
		(stroke
			(width 0.1016)
			(type default)
		)
		(fill no)
		(layer "In10.Cu")
	)
	(gr_circle
		(center 74.84999 -313.949842)
		(end 75.10399 -313.949842)
		(stroke
			(width 0.1016)
			(type default)
		)
		(fill no)
		(layer "In10.Cu")
	)
	(gr_circle
		(center 74.84999 -312.999882)
		(end 75.10399 -312.999882)
		(stroke
			(width 0.1016)
			(type default)
		)
		(fill no)
		(layer "In10.Cu")
	)
	(gr_circle
		(center 74.84999 -308.249828)
		(end 75.10399 -308.249828)
		(stroke
			(width 0.1016)
			(type default)
		)
		(fill no)
		(layer "In10.Cu")
	)
	(gr_circle
		(center 74.84999 -306.349908)
		(end 75.10399 -306.349908)
		(stroke
			(width 0.1016)
			(type default)
		)
		(fill no)
		(layer "In10.Cu")
	)
	(gr_circle
		(center 74.84999 -304.449734)
		(end 75.10399 -304.449734)
		(stroke
			(width 0.1016)
			(type default)
		)
		(fill no)
		(layer "In10.Cu")
	)
	(gr_line
		(start 75.050142 -232.838498)
		(end 74.709782 -230.706168)
		(stroke
			(width 0.1016)
			(type default)
		)
		(layer "In10.Cu")
	)
	(gr_line
		(start 75.419712 -246.017288)
		(end 75.75931 -248.149364)
		(stroke
			(width 0.1016)
			(type default)
		)
		(layer "In10.Cu")
	)
	(gr_circle
		(center 75.79995 -316.799722)
		(end 76.05395 -316.799722)
		(stroke
			(width 0.1016)
			(type default)
		)
		(fill no)
		(layer "In10.Cu")
	)
	(gr_circle
		(center 75.79995 -315.849762)
		(end 76.05395 -315.849762)
		(stroke
			(width 0.1016)
			(type default)
		)
		(fill no)
		(layer "In10.Cu")
	)
	(gr_circle
		(center 75.79995 -312.049922)
		(end 76.05395 -312.049922)
		(stroke
			(width 0.1016)
			(type default)
		)
		(fill no)
		(layer "In10.Cu")
	)
	(gr_circle
		(center 75.79995 -311.099962)
		(end 76.05395 -311.099962)
		(stroke
			(width 0.1016)
			(type default)
		)
		(fill no)
		(layer "In10.Cu")
	)
	(gr_circle
		(center 75.79995 -308.249828)
		(end 76.05395 -308.249828)
		(stroke
			(width 0.1016)
			(type default)
		)
		(fill no)
		(layer "In10.Cu")
	)
	(gr_circle
		(center 75.79995 -306.349908)
		(end 76.05395 -306.349908)
		(stroke
			(width 0.1016)
			(type default)
		)
		(fill no)
		(layer "In10.Cu")
	)
	(gr_circle
		(center 75.79995 -304.449734)
		(end 76.05395 -304.449734)
		(stroke
			(width 0.1016)
			(type default)
		)
		(fill no)
		(layer "In10.Cu")
	)
	(gr_line
		(start 75.836526 -230.838756)
		(end 76.176124 -232.970832)
		(stroke
			(width 0.1016)
			(type default)
		)
		(layer "In10.Cu")
	)
	(gr_line
		(start 76.186792 -245.89486)
		(end 75.419712 -246.017288)
		(stroke
			(width 0.1016)
			(type default)
		)
		(layer "In10.Cu")
	)
	(gr_line
		(start 76.527152 -248.02719)
		(end 76.186792 -245.89486)
		(stroke
			(width 0.1016)
			(type default)
		)
		(layer "In10.Cu")
	)
	(gr_line
		(start 76.603606 -230.716328)
		(end 75.836526 -230.838756)
		(stroke
			(width 0.1016)
			(type default)
		)
		(layer "In10.Cu")
	)
	(gr_circle
		(center 76.74991 -318.699896)
		(end 77.00391 -318.699896)
		(stroke
			(width 0.1016)
			(type default)
		)
		(fill no)
		(layer "In10.Cu")
	)
	(gr_circle
		(center 76.74991 -317.749936)
		(end 77.00391 -317.749936)
		(stroke
			(width 0.1016)
			(type default)
		)
		(fill no)
		(layer "In10.Cu")
	)
	(gr_circle
		(center 76.74991 -313.949842)
		(end 77.00391 -313.949842)
		(stroke
			(width 0.1016)
			(type default)
		)
		(fill no)
		(layer "In10.Cu")
	)
	(gr_circle
		(center 76.74991 -312.999882)
		(end 77.00391 -312.999882)
		(stroke
			(width 0.1016)
			(type default)
		)
		(fill no)
		(layer "In10.Cu")
	)
	(gr_circle
		(center 76.74991 -309.199788)
		(end 77.00391 -309.199788)
		(stroke
			(width 0.1016)
			(type default)
		)
		(fill no)
		(layer "In10.Cu")
	)
	(gr_circle
		(center 76.74991 -307.299868)
		(end 77.00391 -307.299868)
		(stroke
			(width 0.1016)
			(type default)
		)
		(fill no)
		(layer "In10.Cu")
	)
	(gr_circle
		(center 76.74991 -305.399948)
		(end 77.00391 -305.399948)
		(stroke
			(width 0.1016)
			(type default)
		)
		(fill no)
		(layer "In10.Cu")
	)
	(gr_line
		(start 76.943966 -232.848658)
		(end 76.603606 -230.716328)
		(stroke
			(width 0.1016)
			(type default)
		)
		(layer "In10.Cu")
	)
	(gr_circle
		(center 77.69987 -316.799722)
		(end 77.95387 -316.799722)
		(stroke
			(width 0.1016)
			(type default)
		)
		(fill no)
		(layer "In10.Cu")
	)
	(gr_circle
		(center 77.69987 -315.849762)
		(end 77.95387 -315.849762)
		(stroke
			(width 0.1016)
			(type default)
		)
		(fill no)
		(layer "In10.Cu")
	)
	(gr_circle
		(center 77.69987 -312.049922)
		(end 77.95387 -312.049922)
		(stroke
			(width 0.1016)
			(type default)
		)
		(fill no)
		(layer "In10.Cu")
	)
	(gr_circle
		(center 77.69987 -311.099962)
		(end 77.95387 -311.099962)
		(stroke
			(width 0.1016)
			(type default)
		)
		(fill no)
		(layer "In10.Cu")
	)
	(gr_circle
		(center 77.69987 -309.199788)
		(end 77.95387 -309.199788)
		(stroke
			(width 0.1016)
			(type default)
		)
		(fill no)
		(layer "In10.Cu")
	)
	(gr_circle
		(center 77.69987 -307.299868)
		(end 77.95387 -307.299868)
		(stroke
			(width 0.1016)
			(type default)
		)
		(fill no)
		(layer "In10.Cu")
	)
	(gr_circle
		(center 77.69987 -305.399948)
		(end 77.95387 -305.399948)
		(stroke
			(width 0.1016)
			(type default)
		)
		(fill no)
		(layer "In10.Cu")
	)
	(gr_circle
		(center 78.64983 -318.699896)
		(end 78.90383 -318.699896)
		(stroke
			(width 0.1016)
			(type default)
		)
		(fill no)
		(layer "In10.Cu")
	)
	(gr_circle
		(center 78.64983 -317.749936)
		(end 78.90383 -317.749936)
		(stroke
			(width 0.1016)
			(type default)
		)
		(fill no)
		(layer "In10.Cu")
	)
	(gr_circle
		(center 78.64983 -313.949842)
		(end 78.90383 -313.949842)
		(stroke
			(width 0.1016)
			(type default)
		)
		(fill no)
		(layer "In10.Cu")
	)
	(gr_circle
		(center 78.64983 -312.999882)
		(end 78.90383 -312.999882)
		(stroke
			(width 0.1016)
			(type default)
		)
		(fill no)
		(layer "In10.Cu")
	)
	(gr_line
		(start 78.653894 -260.17601)
		(end 78.653894 -262.33501)
		(stroke
			(width 0.1016)
			(type default)
		)
		(layer "In10.Cu")
	)
	(gr_line
		(start 79.298038 -246.597678)
		(end 79.637636 -248.729754)
		(stroke
			(width 0.1016)
			(type default)
		)
		(layer "In10.Cu")
	)
	(gr_line
		(start 79.430626 -260.175756)
		(end 78.653894 -260.17601)
		(stroke
			(width 0.1016)
			(type default)
		)
		(layer "In10.Cu")
	)
	(gr_line
		(start 79.431134 -262.33501)
		(end 79.430626 -260.175756)
		(stroke
			(width 0.1016)
			(type default)
		)
		(layer "In10.Cu")
	)
	(gr_circle
		(center 79.59979 -316.799722)
		(end 79.85379 -316.799722)
		(stroke
			(width 0.1016)
			(type default)
		)
		(fill no)
		(layer "In10.Cu")
	)
	(gr_circle
		(center 79.59979 -315.849762)
		(end 79.85379 -315.849762)
		(stroke
			(width 0.1016)
			(type default)
		)
		(fill no)
		(layer "In10.Cu")
	)
	(gr_circle
		(center 79.59979 -312.049922)
		(end 79.85379 -312.049922)
		(stroke
			(width 0.1016)
			(type default)
		)
		(fill no)
		(layer "In10.Cu")
	)
	(gr_circle
		(center 79.59979 -311.099962)
		(end 79.85379 -311.099962)
		(stroke
			(width 0.1016)
			(type default)
		)
		(fill no)
		(layer "In10.Cu")
	)
	(gr_circle
		(center 79.59979 -309.199788)
		(end 79.85379 -309.199788)
		(stroke
			(width 0.1016)
			(type default)
		)
		(fill no)
		(layer "In10.Cu")
	)
	(gr_circle
		(center 79.59979 -307.299868)
		(end 79.85379 -307.299868)
		(stroke
			(width 0.1016)
			(type default)
		)
		(fill no)
		(layer "In10.Cu")
	)
	(gr_circle
		(center 79.59979 -305.399948)
		(end 79.85379 -305.399948)
		(stroke
			(width 0.1016)
			(type default)
		)
		(fill no)
		(layer "In10.Cu")
	)
	(gr_line
		(start 79.64932 -230.969058)
		(end 79.988918 -233.101134)
		(stroke
			(width 0.1016)
			(type default)
		)
		(layer "In10.Cu")
	)
	(gr_line
		(start 80.065118 -246.47525)
		(end 79.298038 -246.597678)
		(stroke
			(width 0.1016)
			(type default)
		)
		(layer "In10.Cu")
	)
	(gr_line
		(start 80.405478 -248.60758)
		(end 80.065118 -246.47525)
		(stroke
			(width 0.1016)
			(type default)
		)
		(layer "In10.Cu")
	)
	(gr_line
		(start 80.4164 -230.84663)
		(end 79.64932 -230.969058)
		(stroke
			(width 0.1016)
			(type default)
		)
		(layer "In10.Cu")
	)
	(gr_circle
		(center 80.54975 -318.699896)
		(end 80.80375 -318.699896)
		(stroke
			(width 0.1016)
			(type default)
		)
		(fill no)
		(layer "In10.Cu")
	)
	(gr_circle
		(center 80.54975 -317.749936)
		(end 80.80375 -317.749936)
		(stroke
			(width 0.1016)
			(type default)
		)
		(fill no)
		(layer "In10.Cu")
	)
	(gr_circle
		(center 80.54975 -313.949842)
		(end 80.80375 -313.949842)
		(stroke
			(width 0.1016)
			(type default)
		)
		(fill no)
		(layer "In10.Cu")
	)
	(gr_circle
		(center 80.54975 -312.999882)
		(end 80.80375 -312.999882)
		(stroke
			(width 0.1016)
			(type default)
		)
		(fill no)
		(layer "In10.Cu")
	)
	(gr_circle
		(center 80.54975 -309.199788)
		(end 80.80375 -309.199788)
		(stroke
			(width 0.1016)
			(type default)
		)
		(fill no)
		(layer "In10.Cu")
	)
	(gr_circle
		(center 80.54975 -307.299868)
		(end 80.80375 -307.299868)
		(stroke
			(width 0.1016)
			(type default)
		)
		(fill no)
		(layer "In10.Cu")
	)
	(gr_circle
		(center 80.54975 -305.399948)
		(end 80.80375 -305.399948)
		(stroke
			(width 0.1016)
			(type default)
		)
		(fill no)
		(layer "In10.Cu")
	)
	(gr_line
		(start 80.75676 -232.97896)
		(end 80.4164 -230.84663)
		(stroke
			(width 0.1016)
			(type default)
		)
		(layer "In10.Cu")
	)
	(gr_line
		(start 81.111344 -246.11457)
		(end 81.450942 -248.246646)
		(stroke
			(width 0.1016)
			(type default)
		)
		(layer "In10.Cu")
	)
	(gr_circle
		(center 81.499964 -316.799722)
		(end 81.753964 -316.799722)
		(stroke
			(width 0.1016)
			(type default)
		)
		(fill no)
		(layer "In10.Cu")
	)
	(gr_circle
		(center 81.499964 -314.899802)
		(end 81.753964 -314.899802)
		(stroke
			(width 0.1016)
			(type default)
		)
		(fill no)
		(layer "In10.Cu")
	)
	(gr_circle
		(center 81.499964 -312.049922)
		(end 81.753964 -312.049922)
		(stroke
			(width 0.1016)
			(type default)
		)
		(fill no)
		(layer "In10.Cu")
	)
	(gr_circle
		(center 81.499964 -310.149748)
		(end 81.753964 -310.149748)
		(stroke
			(width 0.1016)
			(type default)
		)
		(fill no)
		(layer "In10.Cu")
	)
	(gr_circle
		(center 81.499964 -308.249828)
		(end 81.753964 -308.249828)
		(stroke
			(width 0.1016)
			(type default)
		)
		(fill no)
		(layer "In10.Cu")
	)
	(gr_circle
		(center 81.499964 -306.349908)
		(end 81.753964 -306.349908)
		(stroke
			(width 0.1016)
			(type default)
		)
		(fill no)
		(layer "In10.Cu")
	)
	(gr_circle
		(center 81.499964 -304.449734)
		(end 81.753964 -304.449734)
		(stroke
			(width 0.1016)
			(type default)
		)
		(fill no)
		(layer "In10.Cu")
	)
	(gr_line
		(start 81.500472 -260.491224)
		(end 81.500472 -262.650224)
		(stroke
			(width 0.1016)
			(type default)
		)
		(layer "In10.Cu")
	)
	(gr_line
		(start 81.534 -230.750872)
		(end 81.873598 -232.882948)
		(stroke
			(width 0.1016)
			(type default)
		)
		(layer "In10.Cu")
	)
	(gr_line
		(start 81.878424 -245.992142)
		(end 81.111344 -246.11457)
		(stroke
			(width 0.1016)
			(type default)
		)
		(layer "In10.Cu")
	)
	(gr_line
		(start 82.218784 -248.124472)
		(end 81.878424 -245.992142)
		(stroke
			(width 0.1016)
			(type default)
		)
		(layer "In10.Cu")
	)
	(gr_line
		(start 82.277204 -260.49097)
		(end 81.500472 -260.491224)
		(stroke
			(width 0.1016)
			(type default)
		)
		(layer "In10.Cu")
	)
	(gr_line
		(start 82.277712 -262.650224)
		(end 82.277204 -260.49097)
		(stroke
			(width 0.1016)
			(type default)
		)
		(layer "In10.Cu")
	)
	(gr_line
		(start 82.30108 -230.628444)
		(end 81.534 -230.750872)
		(stroke
			(width 0.1016)
			(type default)
		)
		(layer "In10.Cu")
	)
	(gr_line
		(start 82.370676 -242.091464)
		(end 82.710274 -244.22354)
		(stroke
			(width 0.1016)
			(type default)
		)
		(layer "In10.Cu")
	)
	(gr_circle
		(center 82.449924 -316.799722)
		(end 82.703924 -316.799722)
		(stroke
			(width 0.1016)
			(type default)
		)
		(fill no)
		(layer "In10.Cu")
	)
	(gr_circle
		(center 82.449924 -314.899802)
		(end 82.703924 -314.899802)
		(stroke
			(width 0.1016)
			(type default)
		)
		(fill no)
		(layer "In10.Cu")
	)
	(gr_circle
		(center 82.449924 -312.049922)
		(end 82.703924 -312.049922)
		(stroke
			(width 0.1016)
			(type default)
		)
		(fill no)
		(layer "In10.Cu")
	)
	(gr_circle
		(center 82.449924 -310.149748)
		(end 82.703924 -310.149748)
		(stroke
			(width 0.1016)
			(type default)
		)
		(fill no)
		(layer "In10.Cu")
	)
	(gr_circle
		(center 82.449924 -308.249828)
		(end 82.703924 -308.249828)
		(stroke
			(width 0.1016)
			(type default)
		)
		(fill no)
		(layer "In10.Cu")
	)
	(gr_circle
		(center 82.449924 -306.349908)
		(end 82.703924 -306.349908)
		(stroke
			(width 0.1016)
			(type default)
		)
		(fill no)
		(layer "In10.Cu")
	)
	(gr_circle
		(center 82.449924 -304.449734)
		(end 82.703924 -304.449734)
		(stroke
			(width 0.1016)
			(type default)
		)
		(fill no)
		(layer "In10.Cu")
	)
	(gr_line
		(start 82.64144 -232.760774)
		(end 82.30108 -230.628444)
		(stroke
			(width 0.1016)
			(type default)
		)
		(layer "In10.Cu")
	)
	(gr_line
		(start 83.137756 -241.969036)
		(end 82.370676 -242.091464)
		(stroke
			(width 0.1016)
			(type default)
		)
		(layer "In10.Cu")
	)
	(gr_line
		(start 83.432142 -230.563674)
		(end 83.77174 -232.69575)
		(stroke
			(width 0.1016)
			(type default)
		)
		(layer "In10.Cu")
	)
	(gr_line
		(start 83.478116 -244.101366)
		(end 83.137756 -241.969036)
		(stroke
			(width 0.1016)
			(type default)
		)
		(layer "In10.Cu")
	)
	(gr_line
		(start 84.199222 -230.441246)
		(end 83.432142 -230.563674)
		(stroke
			(width 0.1016)
			(type default)
		)
		(layer "In10.Cu")
	)
	(gr_line
		(start 84.303616 -242.091464)
		(end 84.643214 -244.22354)
		(stroke
			(width 0.1016)
			(type default)
		)
		(layer "In10.Cu")
	)
	(gr_line
		(start 84.539582 -232.573576)
		(end 84.199222 -230.441246)
		(stroke
			(width 0.1016)
			(type default)
		)
		(layer "In10.Cu")
	)
	(gr_line
		(start 85.070696 -241.969036)
		(end 84.303616 -242.091464)
		(stroke
			(width 0.1016)
			(type default)
		)
		(layer "In10.Cu")
	)
	(gr_line
		(start 85.336126 -230.313992)
		(end 85.675724 -232.446068)
		(stroke
			(width 0.1016)
			(type default)
		)
		(layer "In10.Cu")
	)
	(gr_line
		(start 85.411056 -244.101366)
		(end 85.070696 -241.969036)
		(stroke
			(width 0.1016)
			(type default)
		)
		(layer "In10.Cu")
	)
	(gr_line
		(start 86.103206 -230.191564)
		(end 85.336126 -230.313992)
		(stroke
			(width 0.1016)
			(type default)
		)
		(layer "In10.Cu")
	)
	(gr_line
		(start 86.18855 -241.730784)
		(end 86.528148 -243.86286)
		(stroke
			(width 0.1016)
			(type default)
		)
		(layer "In10.Cu")
	)
	(gr_line
		(start 86.443566 -232.323894)
		(end 86.103206 -230.191564)
		(stroke
			(width 0.1016)
			(type default)
		)
		(layer "In10.Cu")
	)
	(gr_line
		(start 86.95563 -241.608356)
		(end 86.18855 -241.730784)
		(stroke
			(width 0.1016)
			(type default)
		)
		(layer "In10.Cu")
	)
	(gr_line
		(start 87.29599 -243.740686)
		(end 86.95563 -241.608356)
		(stroke
			(width 0.1016)
			(type default)
		)
		(layer "In10.Cu")
	)
	(gr_line
		(start 136.465564 -130.829304)
		(end 136.465564 -132.988304)
		(stroke
			(width 0.1016)
			(type default)
		)
		(layer "In10.Cu")
	)
	(gr_line
		(start 137.242296 -130.82905)
		(end 136.465564 -130.829304)
		(stroke
			(width 0.1016)
			(type default)
		)
		(layer "In10.Cu")
	)
	(gr_line
		(start 137.242804 -132.988304)
		(end 137.242296 -130.82905)
		(stroke
			(width 0.1016)
			(type default)
		)
		(layer "In10.Cu")
	)
	(gr_line
		(start 140.14069 -156.489146)
		(end 140.512038 -158.615888)
		(stroke
			(width 0.1016)
			(type default)
		)
		(layer "In10.Cu")
	)
	(gr_line
		(start 140.905992 -156.355034)
		(end 140.14069 -156.489146)
		(stroke
			(width 0.1016)
			(type default)
		)
		(layer "In10.Cu")
	)
	(gr_line
		(start 141.277594 -158.48203)
		(end 140.905992 -156.355034)
		(stroke
			(width 0.1016)
			(type default)
		)
		(layer "In10.Cu")
	)
	(gr_line
		(start 142.622778 -115.836446)
		(end 141.99616 -117.902482)
		(stroke
			(width 0.1016)
			(type default)
		)
		(layer "In10.Cu")
	)
	(gr_line
		(start 142.740126 -118.128034)
		(end 143.36649 -116.061998)
		(stroke
			(width 0.1016)
			(type default)
		)
		(layer "In10.Cu")
	)
	(gr_line
		(start 143.36649 -116.061998)
		(end 142.622778 -115.836446)
		(stroke
			(width 0.1016)
			(type default)
		)
		(layer "In10.Cu")
	)
	(gr_line
		(start 144.143984 -117.404642)
		(end 143.517366 -119.470678)
		(stroke
			(width 0.1016)
			(type default)
		)
		(layer "In10.Cu")
	)
	(gr_line
		(start 144.261332 -119.69623)
		(end 144.887696 -117.630194)
		(stroke
			(width 0.1016)
			(type default)
		)
		(layer "In10.Cu")
	)
	(gr_line
		(start 144.887696 -117.630194)
		(end 144.143984 -117.404642)
		(stroke
			(width 0.1016)
			(type default)
		)
		(layer "In10.Cu")
	)
	(gr_line
		(start 146.545554 -110.673642)
		(end 147.371562 -108.678726)
		(stroke
			(width 0.1016)
			(type default)
		)
		(layer "In10.Cu")
	)
	(gr_line
		(start 146.653758 -108.381546)
		(end 145.827496 -110.376208)
		(stroke
			(width 0.1016)
			(type default)
		)
		(layer "In10.Cu")
	)
	(gr_line
		(start 147.371562 -108.678726)
		(end 146.653758 -108.381546)
		(stroke
			(width 0.1016)
			(type default)
		)
		(layer "In10.Cu")
	)
	(gr_line
		(start 147.59432 -167.626792)
		(end 148.28647 -169.671746)
		(stroke
			(width 0.1016)
			(type default)
		)
		(layer "In10.Cu")
	)
	(gr_line
		(start 148.330412 -167.377618)
		(end 147.59432 -167.626792)
		(stroke
			(width 0.1016)
			(type default)
		)
		(layer "In10.Cu")
	)
	(gr_line
		(start 149.022816 -169.422572)
		(end 148.330412 -167.377618)
		(stroke
			(width 0.1016)
			(type default)
		)
		(layer "In10.Cu")
	)
	(gr_circle
		(center 152.94991 -314.899802)
		(end 153.20391 -314.899802)
		(stroke
			(width 0.1016)
			(type default)
		)
		(fill no)
		(layer "In10.Cu")
	)
	(gr_circle
		(center 152.94991 -312.049922)
		(end 153.20391 -312.049922)
		(stroke
			(width 0.1016)
			(type default)
		)
		(fill no)
		(layer "In10.Cu")
	)
	(gr_circle
		(center 153.89987 -314.899802)
		(end 154.15387 -314.899802)
		(stroke
			(width 0.1016)
			(type default)
		)
		(fill no)
		(layer "In10.Cu")
	)
	(gr_circle
		(center 153.89987 -312.049922)
		(end 154.15387 -312.049922)
		(stroke
			(width 0.1016)
			(type default)
		)
		(fill no)
		(layer "In10.Cu")
	)
	(gr_circle
		(center 154.850084 -313.949842)
		(end 155.104084 -313.949842)
		(stroke
			(width 0.1016)
			(type default)
		)
		(fill no)
		(layer "In10.Cu")
	)
	(gr_circle
		(center 154.850084 -312.999882)
		(end 155.104084 -312.999882)
		(stroke
			(width 0.1016)
			(type default)
		)
		(fill no)
		(layer "In10.Cu")
	)
	(gr_circle
		(center 155.800044 -312.049922)
		(end 156.054044 -312.049922)
		(stroke
			(width 0.1016)
			(type default)
		)
		(fill no)
		(layer "In10.Cu")
	)
	(gr_circle
		(center 155.800044 -311.099962)
		(end 156.054044 -311.099962)
		(stroke
			(width 0.1016)
			(type default)
		)
		(fill no)
		(layer "In10.Cu")
	)
	(gr_circle
		(center 156.750004 -313.949842)
		(end 157.004004 -313.949842)
		(stroke
			(width 0.1016)
			(type default)
		)
		(fill no)
		(layer "In10.Cu")
	)
	(gr_circle
		(center 156.750004 -312.999882)
		(end 157.004004 -312.999882)
		(stroke
			(width 0.1016)
			(type default)
		)
		(fill no)
		(layer "In10.Cu")
	)
	(gr_circle
		(center 157.699964 -312.049922)
		(end 157.953964 -312.049922)
		(stroke
			(width 0.1016)
			(type default)
		)
		(fill no)
		(layer "In10.Cu")
	)
	(gr_circle
		(center 157.699964 -311.099962)
		(end 157.953964 -311.099962)
		(stroke
			(width 0.1016)
			(type default)
		)
		(fill no)
		(layer "In10.Cu")
	)
	(gr_circle
		(center 157.699964 -309.199788)
		(end 157.953964 -309.199788)
		(stroke
			(width 0.1016)
			(type default)
		)
		(fill no)
		(layer "In10.Cu")
	)
	(gr_circle
		(center 157.699964 -307.299868)
		(end 157.953964 -307.299868)
		(stroke
			(width 0.1016)
			(type default)
		)
		(fill no)
		(layer "In10.Cu")
	)
	(gr_circle
		(center 157.699964 -305.399948)
		(end 157.953964 -305.399948)
		(stroke
			(width 0.1016)
			(type default)
		)
		(fill no)
		(layer "In10.Cu")
	)
	(gr_circle
		(center 157.699964 -303.499774)
		(end 157.953964 -303.499774)
		(stroke
			(width 0.1016)
			(type default)
		)
		(fill no)
		(layer "In10.Cu")
	)
	(gr_circle
		(center 157.699964 -301.599854)
		(end 157.953964 -301.599854)
		(stroke
			(width 0.1016)
			(type default)
		)
		(fill no)
		(layer "In10.Cu")
	)
	(gr_circle
		(center 158.649924 -313.949842)
		(end 158.903924 -313.949842)
		(stroke
			(width 0.1016)
			(type default)
		)
		(fill no)
		(layer "In10.Cu")
	)
	(gr_circle
		(center 158.649924 -312.999882)
		(end 158.903924 -312.999882)
		(stroke
			(width 0.1016)
			(type default)
		)
		(fill no)
		(layer "In10.Cu")
	)
	(gr_circle
		(center 158.649924 -309.199788)
		(end 158.903924 -309.199788)
		(stroke
			(width 0.1016)
			(type default)
		)
		(fill no)
		(layer "In10.Cu")
	)
	(gr_circle
		(center 158.649924 -307.299868)
		(end 158.903924 -307.299868)
		(stroke
			(width 0.1016)
			(type default)
		)
		(fill no)
		(layer "In10.Cu")
	)
	(gr_circle
		(center 158.649924 -305.399948)
		(end 158.903924 -305.399948)
		(stroke
			(width 0.1016)
			(type default)
		)
		(fill no)
		(layer "In10.Cu")
	)
	(gr_circle
		(center 158.649924 -303.499774)
		(end 158.903924 -303.499774)
		(stroke
			(width 0.1016)
			(type default)
		)
		(fill no)
		(layer "In10.Cu")
	)
	(gr_circle
		(center 158.649924 -301.599854)
		(end 158.903924 -301.599854)
		(stroke
			(width 0.1016)
			(type default)
		)
		(fill no)
		(layer "In10.Cu")
	)
	(gr_circle
		(center 159.599884 -316.799722)
		(end 159.853884 -316.799722)
		(stroke
			(width 0.1016)
			(type default)
		)
		(fill no)
		(layer "In10.Cu")
	)
	(gr_circle
		(center 159.599884 -315.849762)
		(end 159.853884 -315.849762)
		(stroke
			(width 0.1016)
			(type default)
		)
		(fill no)
		(layer "In10.Cu")
	)
	(gr_circle
		(center 159.599884 -312.049922)
		(end 159.853884 -312.049922)
		(stroke
			(width 0.1016)
			(type default)
		)
		(fill no)
		(layer "In10.Cu")
	)
	(gr_circle
		(center 159.599884 -311.099962)
		(end 159.853884 -311.099962)
		(stroke
			(width 0.1016)
			(type default)
		)
		(fill no)
		(layer "In10.Cu")
	)
	(gr_circle
		(center 159.599884 -308.249828)
		(end 159.853884 -308.249828)
		(stroke
			(width 0.1016)
			(type default)
		)
		(fill no)
		(layer "In10.Cu")
	)
	(gr_circle
		(center 159.599884 -306.349908)
		(end 159.853884 -306.349908)
		(stroke
			(width 0.1016)
			(type default)
		)
		(fill no)
		(layer "In10.Cu")
	)
	(gr_circle
		(center 159.599884 -304.449734)
		(end 159.853884 -304.449734)
		(stroke
			(width 0.1016)
			(type default)
		)
		(fill no)
		(layer "In10.Cu")
	)
	(gr_circle
		(center 159.599884 -302.549814)
		(end 159.853884 -302.549814)
		(stroke
			(width 0.1016)
			(type default)
		)
		(fill no)
		(layer "In10.Cu")
	)
	(gr_circle
		(center 160.549844 -318.699896)
		(end 160.803844 -318.699896)
		(stroke
			(width 0.1016)
			(type default)
		)
		(fill no)
		(layer "In10.Cu")
	)
	(gr_circle
		(center 160.549844 -317.749936)
		(end 160.803844 -317.749936)
		(stroke
			(width 0.1016)
			(type default)
		)
		(fill no)
		(layer "In10.Cu")
	)
	(gr_circle
		(center 160.549844 -313.949842)
		(end 160.803844 -313.949842)
		(stroke
			(width 0.1016)
			(type default)
		)
		(fill no)
		(layer "In10.Cu")
	)
	(gr_circle
		(center 160.549844 -312.999882)
		(end 160.803844 -312.999882)
		(stroke
			(width 0.1016)
			(type default)
		)
		(fill no)
		(layer "In10.Cu")
	)
	(gr_circle
		(center 160.549844 -308.249828)
		(end 160.803844 -308.249828)
		(stroke
			(width 0.1016)
			(type default)
		)
		(fill no)
		(layer "In10.Cu")
	)
	(gr_circle
		(center 160.549844 -306.349908)
		(end 160.803844 -306.349908)
		(stroke
			(width 0.1016)
			(type default)
		)
		(fill no)
		(layer "In10.Cu")
	)
	(gr_circle
		(center 160.549844 -304.449734)
		(end 160.803844 -304.449734)
		(stroke
			(width 0.1016)
			(type default)
		)
		(fill no)
		(layer "In10.Cu")
	)
	(gr_circle
		(center 160.549844 -302.549814)
		(end 160.803844 -302.549814)
		(stroke
			(width 0.1016)
			(type default)
		)
		(fill no)
		(layer "In10.Cu")
	)
	(gr_circle
		(center 160.549844 -278.799798)
		(end 160.803844 -278.799798)
		(stroke
			(width 0.1016)
			(type default)
		)
		(fill no)
		(layer "In10.Cu")
	)
	(gr_circle
		(center 160.549844 -277.849838)
		(end 160.803844 -277.849838)
		(stroke
			(width 0.1016)
			(type default)
		)
		(fill no)
		(layer "In10.Cu")
	)
	(gr_circle
		(center 161.500058 -316.799722)
		(end 161.754058 -316.799722)
		(stroke
			(width 0.1016)
			(type default)
		)
		(fill no)
		(layer "In10.Cu")
	)
	(gr_circle
		(center 161.500058 -315.849762)
		(end 161.754058 -315.849762)
		(stroke
			(width 0.1016)
			(type default)
		)
		(fill no)
		(layer "In10.Cu")
	)
	(gr_circle
		(center 161.500058 -312.049922)
		(end 161.754058 -312.049922)
		(stroke
			(width 0.1016)
			(type default)
		)
		(fill no)
		(layer "In10.Cu")
	)
	(gr_circle
		(center 161.500058 -311.099962)
		(end 161.754058 -311.099962)
		(stroke
			(width 0.1016)
			(type default)
		)
		(fill no)
		(layer "In10.Cu")
	)
	(gr_circle
		(center 161.500058 -280.699464)
		(end 161.754058 -280.699464)
		(stroke
			(width 0.1016)
			(type default)
		)
		(fill no)
		(layer "In10.Cu")
	)
	(gr_circle
		(center 161.500058 -279.749504)
		(end 161.754058 -279.749504)
		(stroke
			(width 0.1016)
			(type default)
		)
		(fill no)
		(layer "In10.Cu")
	)
	(gr_circle
		(center 162.450018 -318.699896)
		(end 162.704018 -318.699896)
		(stroke
			(width 0.1016)
			(type default)
		)
		(fill no)
		(layer "In10.Cu")
	)
	(gr_circle
		(center 162.450018 -317.749936)
		(end 162.704018 -317.749936)
		(stroke
			(width 0.1016)
			(type default)
		)
		(fill no)
		(layer "In10.Cu")
	)
	(gr_circle
		(center 162.450018 -313.949842)
		(end 162.704018 -313.949842)
		(stroke
			(width 0.1016)
			(type default)
		)
		(fill no)
		(layer "In10.Cu")
	)
	(gr_circle
		(center 162.450018 -312.999882)
		(end 162.704018 -312.999882)
		(stroke
			(width 0.1016)
			(type default)
		)
		(fill no)
		(layer "In10.Cu")
	)
	(gr_circle
		(center 162.450018 -278.799798)
		(end 162.704018 -278.799798)
		(stroke
			(width 0.1016)
			(type default)
		)
		(fill no)
		(layer "In10.Cu")
	)
	(gr_circle
		(center 162.450018 -277.849838)
		(end 162.704018 -277.849838)
		(stroke
			(width 0.1016)
			(type default)
		)
		(fill no)
		(layer "In10.Cu")
	)
	(gr_circle
		(center 163.399978 -316.799722)
		(end 163.653978 -316.799722)
		(stroke
			(width 0.1016)
			(type default)
		)
		(fill no)
		(layer "In10.Cu")
	)
	(gr_circle
		(center 163.399978 -315.849762)
		(end 163.653978 -315.849762)
		(stroke
			(width 0.1016)
			(type default)
		)
		(fill no)
		(layer "In10.Cu")
	)
	(gr_circle
		(center 163.399978 -312.049922)
		(end 163.653978 -312.049922)
		(stroke
			(width 0.1016)
			(type default)
		)
		(fill no)
		(layer "In10.Cu")
	)
	(gr_circle
		(center 163.399978 -311.099962)
		(end 163.653978 -311.099962)
		(stroke
			(width 0.1016)
			(type default)
		)
		(fill no)
		(layer "In10.Cu")
	)
	(gr_circle
		(center 163.399978 -280.699464)
		(end 163.653978 -280.699464)
		(stroke
			(width 0.1016)
			(type default)
		)
		(fill no)
		(layer "In10.Cu")
	)
	(gr_circle
		(center 163.399978 -279.749504)
		(end 163.653978 -279.749504)
		(stroke
			(width 0.1016)
			(type default)
		)
		(fill no)
		(layer "In10.Cu")
	)
	(gr_circle
		(center 164.349938 -318.699896)
		(end 164.603938 -318.699896)
		(stroke
			(width 0.1016)
			(type default)
		)
		(fill no)
		(layer "In10.Cu")
	)
	(gr_circle
		(center 164.349938 -317.749936)
		(end 164.603938 -317.749936)
		(stroke
			(width 0.1016)
			(type default)
		)
		(fill no)
		(layer "In10.Cu")
	)
	(gr_circle
		(center 164.349938 -313.949842)
		(end 164.603938 -313.949842)
		(stroke
			(width 0.1016)
			(type default)
		)
		(fill no)
		(layer "In10.Cu")
	)
	(gr_circle
		(center 164.349938 -312.999882)
		(end 164.603938 -312.999882)
		(stroke
			(width 0.1016)
			(type default)
		)
		(fill no)
		(layer "In10.Cu")
	)
	(gr_circle
		(center 164.349938 -278.799798)
		(end 164.603938 -278.799798)
		(stroke
			(width 0.1016)
			(type default)
		)
		(fill no)
		(layer "In10.Cu")
	)
	(gr_circle
		(center 164.349938 -277.849838)
		(end 164.603938 -277.849838)
		(stroke
			(width 0.1016)
			(type default)
		)
		(fill no)
		(layer "In10.Cu")
	)
	(gr_circle
		(center 165.299898 -316.799722)
		(end 165.553898 -316.799722)
		(stroke
			(width 0.1016)
			(type default)
		)
		(fill no)
		(layer "In10.Cu")
	)
	(gr_circle
		(center 165.299898 -315.849762)
		(end 165.553898 -315.849762)
		(stroke
			(width 0.1016)
			(type default)
		)
		(fill no)
		(layer "In10.Cu")
	)
	(gr_circle
		(center 165.299898 -312.049922)
		(end 165.553898 -312.049922)
		(stroke
			(width 0.1016)
			(type default)
		)
		(fill no)
		(layer "In10.Cu")
	)
	(gr_circle
		(center 165.299898 -311.099962)
		(end 165.553898 -311.099962)
		(stroke
			(width 0.1016)
			(type default)
		)
		(fill no)
		(layer "In10.Cu")
	)
	(gr_circle
		(center 165.299898 -280.699464)
		(end 165.553898 -280.699464)
		(stroke
			(width 0.1016)
			(type default)
		)
		(fill no)
		(layer "In10.Cu")
	)
	(gr_circle
		(center 165.299898 -279.749504)
		(end 165.553898 -279.749504)
		(stroke
			(width 0.1016)
			(type default)
		)
		(fill no)
		(layer "In10.Cu")
	)
	(gr_circle
		(center 166.249858 -318.699896)
		(end 166.503858 -318.699896)
		(stroke
			(width 0.1016)
			(type default)
		)
		(fill no)
		(layer "In10.Cu")
	)
	(gr_circle
		(center 166.249858 -317.749936)
		(end 166.503858 -317.749936)
		(stroke
			(width 0.1016)
			(type default)
		)
		(fill no)
		(layer "In10.Cu")
	)
	(gr_circle
		(center 166.249858 -313.949842)
		(end 166.503858 -313.949842)
		(stroke
			(width 0.1016)
			(type default)
		)
		(fill no)
		(layer "In10.Cu")
	)
	(gr_circle
		(center 166.249858 -312.999882)
		(end 166.503858 -312.999882)
		(stroke
			(width 0.1016)
			(type default)
		)
		(fill no)
		(layer "In10.Cu")
	)
	(gr_circle
		(center 166.249858 -278.799798)
		(end 166.503858 -278.799798)
		(stroke
			(width 0.1016)
			(type default)
		)
		(fill no)
		(layer "In10.Cu")
	)
	(gr_circle
		(center 166.249858 -277.849838)
		(end 166.503858 -277.849838)
		(stroke
			(width 0.1016)
			(type default)
		)
		(fill no)
		(layer "In10.Cu")
	)
	(gr_circle
		(center 167.200072 -280.699464)
		(end 167.454072 -280.699464)
		(stroke
			(width 0.1016)
			(type default)
		)
		(fill no)
		(layer "In10.Cu")
	)
	(gr_circle
		(center 167.200072 -279.749504)
		(end 167.454072 -279.749504)
		(stroke
			(width 0.1016)
			(type default)
		)
		(fill no)
		(layer "In10.Cu")
	)
	(gr_circle
		(center 168.150032 -278.799798)
		(end 168.404032 -278.799798)
		(stroke
			(width 0.1016)
			(type default)
		)
		(fill no)
		(layer "In10.Cu")
	)
	(gr_circle
		(center 168.150032 -277.849838)
		(end 168.404032 -277.849838)
		(stroke
			(width 0.1016)
			(type default)
		)
		(fill no)
		(layer "In10.Cu")
	)
	(gr_circle
		(center 169.099992 -280.699464)
		(end 169.353992 -280.699464)
		(stroke
			(width 0.1016)
			(type default)
		)
		(fill no)
		(layer "In10.Cu")
	)
	(gr_circle
		(center 169.099992 -279.749504)
		(end 169.353992 -279.749504)
		(stroke
			(width 0.1016)
			(type default)
		)
		(fill no)
		(layer "In10.Cu")
	)
	(gr_circle
		(center 170.049952 -278.799798)
		(end 170.303952 -278.799798)
		(stroke
			(width 0.1016)
			(type default)
		)
		(fill no)
		(layer "In10.Cu")
	)
	(gr_circle
		(center 170.049952 -277.849838)
		(end 170.303952 -277.849838)
		(stroke
			(width 0.1016)
			(type default)
		)
		(fill no)
		(layer "In10.Cu")
	)
	(gr_circle
		(center 170.999912 -280.699464)
		(end 171.253912 -280.699464)
		(stroke
			(width 0.1016)
			(type default)
		)
		(fill no)
		(layer "In10.Cu")
	)
	(gr_circle
		(center 170.999912 -279.749504)
		(end 171.253912 -279.749504)
		(stroke
			(width 0.1016)
			(type default)
		)
		(fill no)
		(layer "In10.Cu")
	)
	(gr_circle
		(center 171.949872 -278.799798)
		(end 172.203872 -278.799798)
		(stroke
			(width 0.1016)
			(type default)
		)
		(fill no)
		(layer "In10.Cu")
	)
	(gr_circle
		(center 171.949872 -277.849838)
		(end 172.203872 -277.849838)
		(stroke
			(width 0.1016)
			(type default)
		)
		(fill no)
		(layer "In10.Cu")
	)
	(gr_circle
		(center 172.899832 -280.699464)
		(end 173.153832 -280.699464)
		(stroke
			(width 0.1016)
			(type default)
		)
		(fill no)
		(layer "In10.Cu")
	)
	(gr_circle
		(center 172.899832 -279.749504)
		(end 173.153832 -279.749504)
		(stroke
			(width 0.1016)
			(type default)
		)
		(fill no)
		(layer "In10.Cu")
	)
	(gr_circle
		(center 173.850046 -278.799798)
		(end 174.104046 -278.799798)
		(stroke
			(width 0.1016)
			(type default)
		)
		(fill no)
		(layer "In10.Cu")
	)
	(gr_circle
		(center 173.850046 -277.849838)
		(end 174.104046 -277.849838)
		(stroke
			(width 0.1016)
			(type default)
		)
		(fill no)
		(layer "In10.Cu")
	)
	(gr_circle
		(center 174.800006 -280.699464)
		(end 175.054006 -280.699464)
		(stroke
			(width 0.1016)
			(type default)
		)
		(fill no)
		(layer "In10.Cu")
	)
	(gr_circle
		(center 174.800006 -279.749504)
		(end 175.054006 -279.749504)
		(stroke
			(width 0.1016)
			(type default)
		)
		(fill no)
		(layer "In10.Cu")
	)
	(gr_line
		(start 177.63109 -259.328666)
		(end 178.32324 -261.37362)
		(stroke
			(width 0.1016)
			(type default)
		)
		(layer "In10.Cu")
	)
	(gr_line
		(start 177.85969 -251.115068)
		(end 178.55184 -253.160022)
		(stroke
			(width 0.1016)
			(type default)
		)
		(layer "In10.Cu")
	)
	(gr_line
		(start 178.367182 -259.079492)
		(end 177.63109 -259.328666)
		(stroke
			(width 0.1016)
			(type default)
		)
		(layer "In10.Cu")
	)
	(gr_line
		(start 178.595782 -250.865894)
		(end 177.85969 -251.115068)
		(stroke
			(width 0.1016)
			(type default)
		)
		(layer "In10.Cu")
	)
	(gr_line
		(start 178.718464 -247.723406)
		(end 179.410614 -249.76836)
		(stroke
			(width 0.1016)
			(type default)
		)
		(layer "In10.Cu")
	)
	(gr_line
		(start 179.059586 -261.124446)
		(end 178.367182 -259.079492)
		(stroke
			(width 0.1016)
			(type default)
		)
		(layer "In10.Cu")
	)
	(gr_line
		(start 179.288186 -252.910848)
		(end 178.595782 -250.865894)
		(stroke
			(width 0.1016)
			(type default)
		)
		(layer "In10.Cu")
	)
	(gr_line
		(start 179.454556 -247.474232)
		(end 178.718464 -247.723406)
		(stroke
			(width 0.1016)
			(type default)
		)
		(layer "In10.Cu")
	)
	(gr_line
		(start 179.53101 -259.014722)
		(end 180.22316 -261.059676)
		(stroke
			(width 0.1016)
			(type default)
		)
		(layer "In10.Cu")
	)
	(gr_line
		(start 180.14696 -249.519186)
		(end 179.454556 -247.474232)
		(stroke
			(width 0.1016)
			(type default)
		)
		(layer "In10.Cu")
	)
	(gr_line
		(start 180.267102 -258.765548)
		(end 179.53101 -259.014722)
		(stroke
			(width 0.1016)
			(type default)
		)
		(layer "In10.Cu")
	)
	(gr_line
		(start 180.632862 -247.453404)
		(end 181.325012 -249.498358)
		(stroke
			(width 0.1016)
			(type default)
		)
		(layer "In10.Cu")
	)
	(gr_line
		(start 180.959506 -260.810502)
		(end 180.267102 -258.765548)
		(stroke
			(width 0.1016)
			(type default)
		)
		(layer "In10.Cu")
	)
	(gr_line
		(start 181.368954 -247.20423)
		(end 180.632862 -247.453404)
		(stroke
			(width 0.1016)
			(type default)
		)
		(layer "In10.Cu")
	)
	(gr_line
		(start 181.43093 -258.703064)
		(end 182.12308 -260.748018)
		(stroke
			(width 0.1016)
			(type default)
		)
		(layer "In10.Cu")
	)
	(gr_line
		(start 182.061358 -249.249184)
		(end 181.368954 -247.20423)
		(stroke
			(width 0.1016)
			(type default)
		)
		(layer "In10.Cu")
	)
	(gr_line
		(start 182.167022 -258.45389)
		(end 181.43093 -258.703064)
		(stroke
			(width 0.1016)
			(type default)
		)
		(layer "In10.Cu")
	)
	(gr_circle
		(center 182.39994 -316.799722)
		(end 182.65394 -316.799722)
		(stroke
			(width 0.1016)
			(type default)
		)
		(fill no)
		(layer "In10.Cu")
	)
	(gr_circle
		(center 182.39994 -315.849762)
		(end 182.65394 -315.849762)
		(stroke
			(width 0.1016)
			(type default)
		)
		(fill no)
		(layer "In10.Cu")
	)
	(gr_circle
		(center 182.39994 -312.049922)
		(end 182.65394 -312.049922)
		(stroke
			(width 0.1016)
			(type default)
		)
		(fill no)
		(layer "In10.Cu")
	)
	(gr_circle
		(center 182.39994 -311.099962)
		(end 182.65394 -311.099962)
		(stroke
			(width 0.1016)
			(type default)
		)
		(fill no)
		(layer "In10.Cu")
	)
	(gr_line
		(start 182.517288 -247.098566)
		(end 183.209438 -249.14352)
		(stroke
			(width 0.1016)
			(type default)
		)
		(layer "In10.Cu")
	)
	(gr_line
		(start 182.859426 -260.498844)
		(end 182.167022 -258.45389)
		(stroke
			(width 0.1016)
			(type default)
		)
		(layer "In10.Cu")
	)
	(gr_line
		(start 183.133238 -257.804412)
		(end 183.825388 -259.849366)
		(stroke
			(width 0.1016)
			(type default)
		)
		(layer "In10.Cu")
	)
	(gr_line
		(start 183.25338 -246.849392)
		(end 182.517288 -247.098566)
		(stroke
			(width 0.1016)
			(type default)
		)
		(layer "In10.Cu")
	)
	(gr_circle
		(center 183.3499 -318.699896)
		(end 183.6039 -318.699896)
		(stroke
			(width 0.1016)
			(type default)
		)
		(fill no)
		(layer "In10.Cu")
	)
	(gr_circle
		(center 183.3499 -317.749936)
		(end 183.6039 -317.749936)
		(stroke
			(width 0.1016)
			(type default)
		)
		(fill no)
		(layer "In10.Cu")
	)
	(gr_circle
		(center 183.3499 -313.949842)
		(end 183.6039 -313.949842)
		(stroke
			(width 0.1016)
			(type default)
		)
		(fill no)
		(layer "In10.Cu")
	)
	(gr_circle
		(center 183.3499 -312.999882)
		(end 183.6039 -312.999882)
		(stroke
			(width 0.1016)
			(type default)
		)
		(fill no)
		(layer "In10.Cu")
	)
	(gr_line
		(start 183.86933 -257.555238)
		(end 183.133238 -257.804412)
		(stroke
			(width 0.1016)
			(type default)
		)
		(layer "In10.Cu")
	)
	(gr_line
		(start 183.945784 -248.894346)
		(end 183.25338 -246.849392)
		(stroke
			(width 0.1016)
			(type default)
		)
		(layer "In10.Cu")
	)
	(gr_circle
		(center 184.29986 -316.799722)
		(end 184.55386 -316.799722)
		(stroke
			(width 0.1016)
			(type default)
		)
		(fill no)
		(layer "In10.Cu")
	)
	(gr_circle
		(center 184.29986 -315.849762)
		(end 184.55386 -315.849762)
		(stroke
			(width 0.1016)
			(type default)
		)
		(fill no)
		(layer "In10.Cu")
	)
	(gr_circle
		(center 184.29986 -312.049922)
		(end 184.55386 -312.049922)
		(stroke
			(width 0.1016)
			(type default)
		)
		(fill no)
		(layer "In10.Cu")
	)
	(gr_circle
		(center 184.29986 -311.099962)
		(end 184.55386 -311.099962)
		(stroke
			(width 0.1016)
			(type default)
		)
		(fill no)
		(layer "In10.Cu")
	)
	(gr_line
		(start 184.561734 -259.600192)
		(end 183.86933 -257.555238)
		(stroke
			(width 0.1016)
			(type default)
		)
		(layer "In10.Cu")
	)
	(gr_line
		(start 185.047636 -257.53441)
		(end 185.739786 -259.579364)
		(stroke
			(width 0.1016)
			(type default)
		)
		(layer "In10.Cu")
	)
	(gr_circle
		(center 185.250074 -318.699896)
		(end 185.504074 -318.699896)
		(stroke
			(width 0.1016)
			(type default)
		)
		(fill no)
		(layer "In10.Cu")
	)
	(gr_circle
		(center 185.250074 -317.749936)
		(end 185.504074 -317.749936)
		(stroke
			(width 0.1016)
			(type default)
		)
		(fill no)
		(layer "In10.Cu")
	)
	(gr_circle
		(center 185.250074 -313.949842)
		(end 185.504074 -313.949842)
		(stroke
			(width 0.1016)
			(type default)
		)
		(fill no)
		(layer "In10.Cu")
	)
	(gr_circle
		(center 185.250074 -312.999882)
		(end 185.504074 -312.999882)
		(stroke
			(width 0.1016)
			(type default)
		)
		(fill no)
		(layer "In10.Cu")
	)
	(gr_line
		(start 185.783728 -257.285236)
		(end 185.047636 -257.53441)
		(stroke
			(width 0.1016)
			(type default)
		)
		(layer "In10.Cu")
	)
	(gr_circle
		(center 186.200034 -316.799722)
		(end 186.454034 -316.799722)
		(stroke
			(width 0.1016)
			(type default)
		)
		(fill no)
		(layer "In10.Cu")
	)
	(gr_circle
		(center 186.200034 -315.849762)
		(end 186.454034 -315.849762)
		(stroke
			(width 0.1016)
			(type default)
		)
		(fill no)
		(layer "In10.Cu")
	)
	(gr_circle
		(center 186.200034 -312.049922)
		(end 186.454034 -312.049922)
		(stroke
			(width 0.1016)
			(type default)
		)
		(fill no)
		(layer "In10.Cu")
	)
	(gr_circle
		(center 186.200034 -311.099962)
		(end 186.454034 -311.099962)
		(stroke
			(width 0.1016)
			(type default)
		)
		(fill no)
		(layer "In10.Cu")
	)
	(gr_line
		(start 186.476132 -259.33019)
		(end 185.783728 -257.285236)
		(stroke
			(width 0.1016)
			(type default)
		)
		(layer "In10.Cu")
	)
	(gr_line
		(start 186.933078 -257.179572)
		(end 187.625228 -259.224526)
		(stroke
			(width 0.1016)
			(type default)
		)
		(layer "In10.Cu")
	)
	(gr_circle
		(center 187.149994 -318.699896)
		(end 187.403994 -318.699896)
		(stroke
			(width 0.1016)
			(type default)
		)
		(fill no)
		(layer "In10.Cu")
	)
	(gr_circle
		(center 187.149994 -317.749936)
		(end 187.403994 -317.749936)
		(stroke
			(width 0.1016)
			(type default)
		)
		(fill no)
		(layer "In10.Cu")
	)
	(gr_circle
		(center 187.149994 -313.949842)
		(end 187.403994 -313.949842)
		(stroke
			(width 0.1016)
			(type default)
		)
		(fill no)
		(layer "In10.Cu")
	)
	(gr_circle
		(center 187.149994 -312.999882)
		(end 187.403994 -312.999882)
		(stroke
			(width 0.1016)
			(type default)
		)
		(fill no)
		(layer "In10.Cu")
	)
	(gr_line
		(start 187.66917 -256.930398)
		(end 186.933078 -257.179572)
		(stroke
			(width 0.1016)
			(type default)
		)
		(layer "In10.Cu")
	)
	(gr_circle
		(center 188.099954 -316.799722)
		(end 188.353954 -316.799722)
		(stroke
			(width 0.1016)
			(type default)
		)
		(fill no)
		(layer "In10.Cu")
	)
	(gr_circle
		(center 188.099954 -315.849762)
		(end 188.353954 -315.849762)
		(stroke
			(width 0.1016)
			(type default)
		)
		(fill no)
		(layer "In10.Cu")
	)
	(gr_circle
		(center 188.099954 -312.049922)
		(end 188.353954 -312.049922)
		(stroke
			(width 0.1016)
			(type default)
		)
		(fill no)
		(layer "In10.Cu")
	)
	(gr_circle
		(center 188.099954 -311.099962)
		(end 188.353954 -311.099962)
		(stroke
			(width 0.1016)
			(type default)
		)
		(fill no)
		(layer "In10.Cu")
	)
	(gr_line
		(start 188.169042 -230.902256)
		(end 188.50864 -233.034332)
		(stroke
			(width 0.1016)
			(type default)
		)
		(layer "In10.Cu")
	)
	(gr_line
		(start 188.361574 -258.975352)
		(end 187.66917 -256.930398)
		(stroke
			(width 0.1016)
			(type default)
		)
		(layer "In10.Cu")
	)
	(gr_line
		(start 188.936122 -230.779828)
		(end 188.169042 -230.902256)
		(stroke
			(width 0.1016)
			(type default)
		)
		(layer "In10.Cu")
	)
	(gr_circle
		(center 189.049914 -318.699896)
		(end 189.303914 -318.699896)
		(stroke
			(width 0.1016)
			(type default)
		)
		(fill no)
		(layer "In10.Cu")
	)
	(gr_circle
		(center 189.049914 -317.749936)
		(end 189.303914 -317.749936)
		(stroke
			(width 0.1016)
			(type default)
		)
		(fill no)
		(layer "In10.Cu")
	)
	(gr_circle
		(center 189.049914 -313.949842)
		(end 189.303914 -313.949842)
		(stroke
			(width 0.1016)
			(type default)
		)
		(fill no)
		(layer "In10.Cu")
	)
	(gr_circle
		(center 189.049914 -312.999882)
		(end 189.303914 -312.999882)
		(stroke
			(width 0.1016)
			(type default)
		)
		(fill no)
		(layer "In10.Cu")
	)
	(gr_line
		(start 189.276482 -232.912158)
		(end 188.936122 -230.779828)
		(stroke
			(width 0.1016)
			(type default)
		)
		(layer "In10.Cu")
	)
	(gr_line
		(start 189.643512 -246.090948)
		(end 189.98311 -248.223024)
		(stroke
			(width 0.1016)
			(type default)
		)
		(layer "In10.Cu")
	)
	(gr_line
		(start 190.0428 -230.828596)
		(end 190.382398 -232.960672)
		(stroke
			(width 0.1016)
			(type default)
		)
		(layer "In10.Cu")
	)
	(gr_line
		(start 190.410592 -245.96852)
		(end 189.643512 -246.090948)
		(stroke
			(width 0.1016)
			(type default)
		)
		(layer "In10.Cu")
	)
	(gr_line
		(start 190.750952 -248.10085)
		(end 190.410592 -245.96852)
		(stroke
			(width 0.1016)
			(type default)
		)
		(layer "In10.Cu")
	)
	(gr_line
		(start 190.80988 -230.706168)
		(end 190.0428 -230.828596)
		(stroke
			(width 0.1016)
			(type default)
		)
		(layer "In10.Cu")
	)
	(gr_line
		(start 191.15024 -232.838498)
		(end 190.80988 -230.706168)
		(stroke
			(width 0.1016)
			(type default)
		)
		(layer "In10.Cu")
	)
	(gr_line
		(start 191.51981 -246.017288)
		(end 191.859408 -248.149364)
		(stroke
			(width 0.1016)
			(type default)
		)
		(layer "In10.Cu")
	)
	(gr_line
		(start 191.936624 -230.838756)
		(end 192.276222 -232.970832)
		(stroke
			(width 0.1016)
			(type default)
		)
		(layer "In10.Cu")
	)
	(gr_line
		(start 192.28689 -245.89486)
		(end 191.51981 -246.017288)
		(stroke
			(width 0.1016)
			(type default)
		)
		(layer "In10.Cu")
	)
	(gr_line
		(start 192.62725 -248.02719)
		(end 192.28689 -245.89486)
		(stroke
			(width 0.1016)
			(type default)
		)
		(layer "In10.Cu")
	)
	(gr_line
		(start 192.703704 -230.716328)
		(end 191.936624 -230.838756)
		(stroke
			(width 0.1016)
			(type default)
		)
		(layer "In10.Cu")
	)
	(gr_line
		(start 193.044064 -232.848658)
		(end 192.703704 -230.716328)
		(stroke
			(width 0.1016)
			(type default)
		)
		(layer "In10.Cu")
	)
	(gr_line
		(start 194.753992 -260.17601)
		(end 194.753992 -262.33501)
		(stroke
			(width 0.1016)
			(type default)
		)
		(layer "In10.Cu")
	)
	(gr_line
		(start 195.398136 -246.597678)
		(end 195.737734 -248.729754)
		(stroke
			(width 0.1016)
			(type default)
		)
		(layer "In10.Cu")
	)
	(gr_line
		(start 195.530724 -260.175756)
		(end 194.753992 -260.17601)
		(stroke
			(width 0.1016)
			(type default)
		)
		(layer "In10.Cu")
	)
	(gr_line
		(start 195.531232 -262.33501)
		(end 195.530724 -260.175756)
		(stroke
			(width 0.1016)
			(type default)
		)
		(layer "In10.Cu")
	)
	(gr_line
		(start 195.749418 -230.969058)
		(end 196.089016 -233.101134)
		(stroke
			(width 0.1016)
			(type default)
		)
		(layer "In10.Cu")
	)
	(gr_line
		(start 196.165216 -246.47525)
		(end 195.398136 -246.597678)
		(stroke
			(width 0.1016)
			(type default)
		)
		(layer "In10.Cu")
	)
	(gr_line
		(start 196.505576 -248.60758)
		(end 196.165216 -246.47525)
		(stroke
			(width 0.1016)
			(type default)
		)
		(layer "In10.Cu")
	)
	(gr_line
		(start 196.516498 -230.84663)
		(end 195.749418 -230.969058)
		(stroke
			(width 0.1016)
			(type default)
		)
		(layer "In10.Cu")
	)
	(gr_line
		(start 196.856858 -232.97896)
		(end 196.516498 -230.84663)
		(stroke
			(width 0.1016)
			(type default)
		)
		(layer "In10.Cu")
	)
	(gr_line
		(start 197.211442 -246.11457)
		(end 197.55104 -248.246646)
		(stroke
			(width 0.1016)
			(type default)
		)
		(layer "In10.Cu")
	)
	(gr_line
		(start 197.60057 -260.491224)
		(end 197.60057 -262.650224)
		(stroke
			(width 0.1016)
			(type default)
		)
		(layer "In10.Cu")
	)
	(gr_line
		(start 197.634098 -230.750872)
		(end 197.973696 -232.882948)
		(stroke
			(width 0.1016)
			(type default)
		)
		(layer "In10.Cu")
	)
	(gr_line
		(start 197.978522 -245.992142)
		(end 197.211442 -246.11457)
		(stroke
			(width 0.1016)
			(type default)
		)
		(layer "In10.Cu")
	)
	(gr_line
		(start 198.318882 -248.124472)
		(end 197.978522 -245.992142)
		(stroke
			(width 0.1016)
			(type default)
		)
		(layer "In10.Cu")
	)
	(gr_line
		(start 198.377302 -260.49097)
		(end 197.60057 -260.491224)
		(stroke
			(width 0.1016)
			(type default)
		)
		(layer "In10.Cu")
	)
	(gr_line
		(start 198.37781 -262.650224)
		(end 198.377302 -260.49097)
		(stroke
			(width 0.1016)
			(type default)
		)
		(layer "In10.Cu")
	)
	(gr_line
		(start 198.401178 -230.628444)
		(end 197.634098 -230.750872)
		(stroke
			(width 0.1016)
			(type default)
		)
		(layer "In10.Cu")
	)
	(gr_line
		(start 198.470774 -242.091464)
		(end 198.810372 -244.22354)
		(stroke
			(width 0.1016)
			(type default)
		)
		(layer "In10.Cu")
	)
	(gr_line
		(start 198.741538 -232.760774)
		(end 198.401178 -230.628444)
		(stroke
			(width 0.1016)
			(type default)
		)
		(layer "In10.Cu")
	)
	(gr_line
		(start 199.237854 -241.969036)
		(end 198.470774 -242.091464)
		(stroke
			(width 0.1016)
			(type default)
		)
		(layer "In10.Cu")
	)
	(gr_line
		(start 199.53224 -230.563674)
		(end 199.871838 -232.69575)
		(stroke
			(width 0.1016)
			(type default)
		)
		(layer "In10.Cu")
	)
	(gr_line
		(start 199.578214 -244.101366)
		(end 199.237854 -241.969036)
		(stroke
			(width 0.1016)
			(type default)
		)
		(layer "In10.Cu")
	)
	(gr_line
		(start 200.29932 -230.441246)
		(end 199.53224 -230.563674)
		(stroke
			(width 0.1016)
			(type default)
		)
		(layer "In10.Cu")
	)
	(gr_line
		(start 200.403714 -242.091464)
		(end 200.743312 -244.22354)
		(stroke
			(width 0.1016)
			(type default)
		)
		(layer "In10.Cu")
	)
	(gr_line
		(start 200.63968 -232.573576)
		(end 200.29932 -230.441246)
		(stroke
			(width 0.1016)
			(type default)
		)
		(layer "In10.Cu")
	)
	(gr_line
		(start 201.170794 -241.969036)
		(end 200.403714 -242.091464)
		(stroke
			(width 0.1016)
			(type default)
		)
		(layer "In10.Cu")
	)
	(gr_line
		(start 201.436224 -230.313992)
		(end 201.775822 -232.446068)
		(stroke
			(width 0.1016)
			(type default)
		)
		(layer "In10.Cu")
	)
	(gr_line
		(start 201.511154 -244.101366)
		(end 201.170794 -241.969036)
		(stroke
			(width 0.1016)
			(type default)
		)
		(layer "In10.Cu")
	)
	(gr_line
		(start 202.203304 -230.191564)
		(end 201.436224 -230.313992)
		(stroke
			(width 0.1016)
			(type default)
		)
		(layer "In10.Cu")
	)
	(gr_line
		(start 202.288648 -241.730784)
		(end 202.628246 -243.86286)
		(stroke
			(width 0.1016)
			(type default)
		)
		(layer "In10.Cu")
	)
	(gr_line
		(start 202.543664 -232.323894)
		(end 202.203304 -230.191564)
		(stroke
			(width 0.1016)
			(type default)
		)
		(layer "In10.Cu")
	)
	(gr_line
		(start 203.055728 -241.608356)
		(end 202.288648 -241.730784)
		(stroke
			(width 0.1016)
			(type default)
		)
		(layer "In10.Cu")
	)
	(gr_line
		(start 203.396088 -243.740686)
		(end 203.055728 -241.608356)
		(stroke
			(width 0.1016)
			(type default)
		)
		(layer "In10.Cu")
	)
	(gr_line
		(start 252.565408 -130.829304)
		(end 252.565408 -132.988304)
		(stroke
			(width 0.1016)
			(type default)
		)
		(layer "In10.Cu")
	)
	(gr_line
		(start 253.34214 -130.82905)
		(end 252.565408 -130.829304)
		(stroke
			(width 0.1016)
			(type default)
		)
		(layer "In10.Cu")
	)
	(gr_line
		(start 253.342648 -132.988304)
		(end 253.34214 -130.82905)
		(stroke
			(width 0.1016)
			(type default)
		)
		(layer "In10.Cu")
	)
	(gr_line
		(start 256.240534 -156.489146)
		(end 256.611882 -158.615888)
		(stroke
			(width 0.1016)
			(type default)
		)
		(layer "In10.Cu")
	)
	(gr_line
		(start 257.005836 -156.355034)
		(end 256.240534 -156.489146)
		(stroke
			(width 0.1016)
			(type default)
		)
		(layer "In10.Cu")
	)
	(gr_line
		(start 257.377438 -158.48203)
		(end 257.005836 -156.355034)
		(stroke
			(width 0.1016)
			(type default)
		)
		(layer "In10.Cu")
	)
	(gr_line
		(start 258.722622 -115.836446)
		(end 258.096004 -117.902482)
		(stroke
			(width 0.1016)
			(type default)
		)
		(layer "In10.Cu")
	)
	(gr_line
		(start 258.83997 -118.128034)
		(end 259.466334 -116.061998)
		(stroke
			(width 0.1016)
			(type default)
		)
		(layer "In10.Cu")
	)
	(gr_line
		(start 259.466334 -116.061998)
		(end 258.722622 -115.836446)
		(stroke
			(width 0.1016)
			(type default)
		)
		(layer "In10.Cu")
	)
	(gr_line
		(start 260.243828 -117.404642)
		(end 259.61721 -119.470678)
		(stroke
			(width 0.1016)
			(type default)
		)
		(layer "In10.Cu")
	)
	(gr_line
		(start 260.361176 -119.69623)
		(end 260.98754 -117.630194)
		(stroke
			(width 0.1016)
			(type default)
		)
		(layer "In10.Cu")
	)
	(gr_line
		(start 260.98754 -117.630194)
		(end 260.243828 -117.404642)
		(stroke
			(width 0.1016)
			(type default)
		)
		(layer "In10.Cu")
	)
	(gr_line
		(start 262.645398 -110.673642)
		(end 263.471406 -108.678726)
		(stroke
			(width 0.1016)
			(type default)
		)
		(layer "In10.Cu")
	)
	(gr_line
		(start 262.753602 -108.381546)
		(end 261.92734 -110.376208)
		(stroke
			(width 0.1016)
			(type default)
		)
		(layer "In10.Cu")
	)
	(gr_line
		(start 263.471406 -108.678726)
		(end 262.753602 -108.381546)
		(stroke
			(width 0.1016)
			(type default)
		)
		(layer "In10.Cu")
	)
	(gr_line
		(start 263.694164 -167.626792)
		(end 264.386314 -169.671746)
		(stroke
			(width 0.1016)
			(type default)
		)
		(layer "In10.Cu")
	)
	(gr_line
		(start 264.430256 -167.377618)
		(end 263.694164 -167.626792)
		(stroke
			(width 0.1016)
			(type default)
		)
		(layer "In10.Cu")
	)
	(gr_line
		(start 265.12266 -169.422572)
		(end 264.430256 -167.377618)
		(stroke
			(width 0.1016)
			(type default)
		)
		(layer "In10.Cu")
	)
	(gr_circle
		(center 275.699728 -312.049922)
		(end 275.953728 -312.049922)
		(stroke
			(width 0.1016)
			(type default)
		)
		(fill no)
		(layer "In10.Cu")
	)
	(gr_circle
		(center 275.699728 -311.099962)
		(end 275.953728 -311.099962)
		(stroke
			(width 0.1016)
			(type default)
		)
		(fill no)
		(layer "In10.Cu")
	)
	(gr_circle
		(center 276.649688 -313.949842)
		(end 276.903688 -313.949842)
		(stroke
			(width 0.1016)
			(type default)
		)
		(fill no)
		(layer "In10.Cu")
	)
	(gr_circle
		(center 276.649688 -312.999882)
		(end 276.903688 -312.999882)
		(stroke
			(width 0.1016)
			(type default)
		)
		(fill no)
		(layer "In10.Cu")
	)
	(gr_circle
		(center 276.649688 -278.799798)
		(end 276.903688 -278.799798)
		(stroke
			(width 0.1016)
			(type default)
		)
		(fill no)
		(layer "In10.Cu")
	)
	(gr_circle
		(center 276.649688 -277.849838)
		(end 276.903688 -277.849838)
		(stroke
			(width 0.1016)
			(type default)
		)
		(fill no)
		(layer "In10.Cu")
	)
	(gr_circle
		(center 277.599902 -312.049922)
		(end 277.853902 -312.049922)
		(stroke
			(width 0.1016)
			(type default)
		)
		(fill no)
		(layer "In10.Cu")
	)
	(gr_circle
		(center 277.599902 -311.099962)
		(end 277.853902 -311.099962)
		(stroke
			(width 0.1016)
			(type default)
		)
		(fill no)
		(layer "In10.Cu")
	)
	(gr_circle
		(center 277.599902 -280.699464)
		(end 277.853902 -280.699464)
		(stroke
			(width 0.1016)
			(type default)
		)
		(fill no)
		(layer "In10.Cu")
	)
	(gr_circle
		(center 277.599902 -279.749504)
		(end 277.853902 -279.749504)
		(stroke
			(width 0.1016)
			(type default)
		)
		(fill no)
		(layer "In10.Cu")
	)
	(gr_circle
		(center 278.549862 -313.949842)
		(end 278.803862 -313.949842)
		(stroke
			(width 0.1016)
			(type default)
		)
		(fill no)
		(layer "In10.Cu")
	)
	(gr_circle
		(center 278.549862 -312.999882)
		(end 278.803862 -312.999882)
		(stroke
			(width 0.1016)
			(type default)
		)
		(fill no)
		(layer "In10.Cu")
	)
	(gr_circle
		(center 278.549862 -278.799798)
		(end 278.803862 -278.799798)
		(stroke
			(width 0.1016)
			(type default)
		)
		(fill no)
		(layer "In10.Cu")
	)
	(gr_circle
		(center 278.549862 -277.849838)
		(end 278.803862 -277.849838)
		(stroke
			(width 0.1016)
			(type default)
		)
		(fill no)
		(layer "In10.Cu")
	)
	(gr_circle
		(center 279.499822 -312.049922)
		(end 279.753822 -312.049922)
		(stroke
			(width 0.1016)
			(type default)
		)
		(fill no)
		(layer "In10.Cu")
	)
	(gr_circle
		(center 279.499822 -311.099962)
		(end 279.753822 -311.099962)
		(stroke
			(width 0.1016)
			(type default)
		)
		(fill no)
		(layer "In10.Cu")
	)
	(gr_circle
		(center 279.499822 -280.699464)
		(end 279.753822 -280.699464)
		(stroke
			(width 0.1016)
			(type default)
		)
		(fill no)
		(layer "In10.Cu")
	)
	(gr_circle
		(center 279.499822 -279.749504)
		(end 279.753822 -279.749504)
		(stroke
			(width 0.1016)
			(type default)
		)
		(fill no)
		(layer "In10.Cu")
	)
	(gr_circle
		(center 280.449782 -313.949842)
		(end 280.703782 -313.949842)
		(stroke
			(width 0.1016)
			(type default)
		)
		(fill no)
		(layer "In10.Cu")
	)
	(gr_circle
		(center 280.449782 -312.999882)
		(end 280.703782 -312.999882)
		(stroke
			(width 0.1016)
			(type default)
		)
		(fill no)
		(layer "In10.Cu")
	)
	(gr_circle
		(center 280.449782 -278.799798)
		(end 280.703782 -278.799798)
		(stroke
			(width 0.1016)
			(type default)
		)
		(fill no)
		(layer "In10.Cu")
	)
	(gr_circle
		(center 280.449782 -277.849838)
		(end 280.703782 -277.849838)
		(stroke
			(width 0.1016)
			(type default)
		)
		(fill no)
		(layer "In10.Cu")
	)
	(gr_circle
		(center 281.399742 -312.049922)
		(end 281.653742 -312.049922)
		(stroke
			(width 0.1016)
			(type default)
		)
		(fill no)
		(layer "In10.Cu")
	)
	(gr_circle
		(center 281.399742 -311.099962)
		(end 281.653742 -311.099962)
		(stroke
			(width 0.1016)
			(type default)
		)
		(fill no)
		(layer "In10.Cu")
	)
	(gr_circle
		(center 281.399742 -280.699464)
		(end 281.653742 -280.699464)
		(stroke
			(width 0.1016)
			(type default)
		)
		(fill no)
		(layer "In10.Cu")
	)
	(gr_circle
		(center 281.399742 -279.749504)
		(end 281.653742 -279.749504)
		(stroke
			(width 0.1016)
			(type default)
		)
		(fill no)
		(layer "In10.Cu")
	)
	(gr_circle
		(center 282.349702 -313.949842)
		(end 282.603702 -313.949842)
		(stroke
			(width 0.1016)
			(type default)
		)
		(fill no)
		(layer "In10.Cu")
	)
	(gr_circle
		(center 282.349702 -312.999882)
		(end 282.603702 -312.999882)
		(stroke
			(width 0.1016)
			(type default)
		)
		(fill no)
		(layer "In10.Cu")
	)
	(gr_circle
		(center 282.349702 -278.799798)
		(end 282.603702 -278.799798)
		(stroke
			(width 0.1016)
			(type default)
		)
		(fill no)
		(layer "In10.Cu")
	)
	(gr_circle
		(center 282.349702 -277.849838)
		(end 282.603702 -277.849838)
		(stroke
			(width 0.1016)
			(type default)
		)
		(fill no)
		(layer "In10.Cu")
	)
	(gr_circle
		(center 283.299916 -312.049922)
		(end 283.553916 -312.049922)
		(stroke
			(width 0.1016)
			(type default)
		)
		(fill no)
		(layer "In10.Cu")
	)
	(gr_circle
		(center 283.299916 -311.099962)
		(end 283.553916 -311.099962)
		(stroke
			(width 0.1016)
			(type default)
		)
		(fill no)
		(layer "In10.Cu")
	)
	(gr_circle
		(center 283.299916 -280.699464)
		(end 283.553916 -280.699464)
		(stroke
			(width 0.1016)
			(type default)
		)
		(fill no)
		(layer "In10.Cu")
	)
	(gr_circle
		(center 283.299916 -279.749504)
		(end 283.553916 -279.749504)
		(stroke
			(width 0.1016)
			(type default)
		)
		(fill no)
		(layer "In10.Cu")
	)
	(gr_circle
		(center 284.249876 -313.949842)
		(end 284.503876 -313.949842)
		(stroke
			(width 0.1016)
			(type default)
		)
		(fill no)
		(layer "In10.Cu")
	)
	(gr_circle
		(center 284.249876 -312.999882)
		(end 284.503876 -312.999882)
		(stroke
			(width 0.1016)
			(type default)
		)
		(fill no)
		(layer "In10.Cu")
	)
	(gr_circle
		(center 284.249876 -278.799798)
		(end 284.503876 -278.799798)
		(stroke
			(width 0.1016)
			(type default)
		)
		(fill no)
		(layer "In10.Cu")
	)
	(gr_circle
		(center 284.249876 -277.849838)
		(end 284.503876 -277.849838)
		(stroke
			(width 0.1016)
			(type default)
		)
		(fill no)
		(layer "In10.Cu")
	)
	(gr_circle
		(center 285.199836 -312.049922)
		(end 285.453836 -312.049922)
		(stroke
			(width 0.1016)
			(type default)
		)
		(fill no)
		(layer "In10.Cu")
	)
	(gr_circle
		(center 285.199836 -311.099962)
		(end 285.453836 -311.099962)
		(stroke
			(width 0.1016)
			(type default)
		)
		(fill no)
		(layer "In10.Cu")
	)
	(gr_circle
		(center 285.199836 -280.699464)
		(end 285.453836 -280.699464)
		(stroke
			(width 0.1016)
			(type default)
		)
		(fill no)
		(layer "In10.Cu")
	)
	(gr_circle
		(center 285.199836 -279.749504)
		(end 285.453836 -279.749504)
		(stroke
			(width 0.1016)
			(type default)
		)
		(fill no)
		(layer "In10.Cu")
	)
	(gr_circle
		(center 286.149796 -313.949842)
		(end 286.403796 -313.949842)
		(stroke
			(width 0.1016)
			(type default)
		)
		(fill no)
		(layer "In10.Cu")
	)
	(gr_circle
		(center 286.149796 -312.999882)
		(end 286.403796 -312.999882)
		(stroke
			(width 0.1016)
			(type default)
		)
		(fill no)
		(layer "In10.Cu")
	)
	(gr_circle
		(center 286.149796 -278.799798)
		(end 286.403796 -278.799798)
		(stroke
			(width 0.1016)
			(type default)
		)
		(fill no)
		(layer "In10.Cu")
	)
	(gr_circle
		(center 286.149796 -277.849838)
		(end 286.403796 -277.849838)
		(stroke
			(width 0.1016)
			(type default)
		)
		(fill no)
		(layer "In10.Cu")
	)
	(gr_circle
		(center 287.099756 -312.049922)
		(end 287.353756 -312.049922)
		(stroke
			(width 0.1016)
			(type default)
		)
		(fill no)
		(layer "In10.Cu")
	)
	(gr_circle
		(center 287.099756 -311.099962)
		(end 287.353756 -311.099962)
		(stroke
			(width 0.1016)
			(type default)
		)
		(fill no)
		(layer "In10.Cu")
	)
	(gr_circle
		(center 287.099756 -280.699464)
		(end 287.353756 -280.699464)
		(stroke
			(width 0.1016)
			(type default)
		)
		(fill no)
		(layer "In10.Cu")
	)
	(gr_circle
		(center 287.099756 -279.749504)
		(end 287.353756 -279.749504)
		(stroke
			(width 0.1016)
			(type default)
		)
		(fill no)
		(layer "In10.Cu")
	)
	(gr_circle
		(center 288.049716 -313.949842)
		(end 288.303716 -313.949842)
		(stroke
			(width 0.1016)
			(type default)
		)
		(fill no)
		(layer "In10.Cu")
	)
	(gr_circle
		(center 288.049716 -312.999882)
		(end 288.303716 -312.999882)
		(stroke
			(width 0.1016)
			(type default)
		)
		(fill no)
		(layer "In10.Cu")
	)
	(gr_circle
		(center 288.049716 -278.799798)
		(end 288.303716 -278.799798)
		(stroke
			(width 0.1016)
			(type default)
		)
		(fill no)
		(layer "In10.Cu")
	)
	(gr_circle
		(center 288.049716 -277.849838)
		(end 288.303716 -277.849838)
		(stroke
			(width 0.1016)
			(type default)
		)
		(fill no)
		(layer "In10.Cu")
	)
	(gr_circle
		(center 288.999676 -280.699464)
		(end 289.253676 -280.699464)
		(stroke
			(width 0.1016)
			(type default)
		)
		(fill no)
		(layer "In10.Cu")
	)
	(gr_circle
		(center 288.999676 -279.749504)
		(end 289.253676 -279.749504)
		(stroke
			(width 0.1016)
			(type default)
		)
		(fill no)
		(layer "In10.Cu")
	)
	(gr_circle
		(center 288.99993 -312.049922)
		(end 289.25393 -312.049922)
		(stroke
			(width 0.1016)
			(type default)
		)
		(fill no)
		(layer "In10.Cu")
	)
	(gr_circle
		(center 288.99993 -311.099962)
		(end 289.25393 -311.099962)
		(stroke
			(width 0.1016)
			(type default)
		)
		(fill no)
		(layer "In10.Cu")
	)
	(gr_circle
		(center 289.94989 -313.949842)
		(end 290.20389 -313.949842)
		(stroke
			(width 0.1016)
			(type default)
		)
		(fill no)
		(layer "In10.Cu")
	)
	(gr_circle
		(center 289.94989 -312.999882)
		(end 290.20389 -312.999882)
		(stroke
			(width 0.1016)
			(type default)
		)
		(fill no)
		(layer "In10.Cu")
	)
	(gr_circle
		(center 289.94989 -278.799798)
		(end 290.20389 -278.799798)
		(stroke
			(width 0.1016)
			(type default)
		)
		(fill no)
		(layer "In10.Cu")
	)
	(gr_circle
		(center 289.94989 -277.849838)
		(end 290.20389 -277.849838)
		(stroke
			(width 0.1016)
			(type default)
		)
		(fill no)
		(layer "In10.Cu")
	)
	(gr_circle
		(center 290.89985 -280.699464)
		(end 291.15385 -280.699464)
		(stroke
			(width 0.1016)
			(type default)
		)
		(fill no)
		(layer "In10.Cu")
	)
	(gr_circle
		(center 290.89985 -279.749504)
		(end 291.15385 -279.749504)
		(stroke
			(width 0.1016)
			(type default)
		)
		(fill no)
		(layer "In10.Cu")
	)
	(gr_line
		(start 293.730934 -259.328666)
		(end 294.423084 -261.37362)
		(stroke
			(width 0.1016)
			(type default)
		)
		(layer "In10.Cu")
	)
	(gr_line
		(start 293.959534 -251.115068)
		(end 294.651684 -253.160022)
		(stroke
			(width 0.1016)
			(type default)
		)
		(layer "In10.Cu")
	)
	(gr_line
		(start 294.467026 -259.079492)
		(end 293.730934 -259.328666)
		(stroke
			(width 0.1016)
			(type default)
		)
		(layer "In10.Cu")
	)
	(gr_line
		(start 294.695626 -250.865894)
		(end 293.959534 -251.115068)
		(stroke
			(width 0.1016)
			(type default)
		)
		(layer "In10.Cu")
	)
	(gr_line
		(start 294.818308 -247.723406)
		(end 295.510458 -249.76836)
		(stroke
			(width 0.1016)
			(type default)
		)
		(layer "In10.Cu")
	)
	(gr_line
		(start 295.15943 -261.124446)
		(end 294.467026 -259.079492)
		(stroke
			(width 0.1016)
			(type default)
		)
		(layer "In10.Cu")
	)
	(gr_line
		(start 295.38803 -252.910848)
		(end 294.695626 -250.865894)
		(stroke
			(width 0.1016)
			(type default)
		)
		(layer "In10.Cu")
	)
	(gr_line
		(start 295.5544 -247.474232)
		(end 294.818308 -247.723406)
		(stroke
			(width 0.1016)
			(type default)
		)
		(layer "In10.Cu")
	)
	(gr_line
		(start 295.630854 -259.014722)
		(end 296.323004 -261.059676)
		(stroke
			(width 0.1016)
			(type default)
		)
		(layer "In10.Cu")
	)
	(gr_line
		(start 296.246804 -249.519186)
		(end 295.5544 -247.474232)
		(stroke
			(width 0.1016)
			(type default)
		)
		(layer "In10.Cu")
	)
	(gr_line
		(start 296.366946 -258.765548)
		(end 295.630854 -259.014722)
		(stroke
			(width 0.1016)
			(type default)
		)
		(layer "In10.Cu")
	)
	(gr_line
		(start 296.732706 -247.453404)
		(end 297.424856 -249.498358)
		(stroke
			(width 0.1016)
			(type default)
		)
		(layer "In10.Cu")
	)
	(gr_line
		(start 297.05935 -260.810502)
		(end 296.366946 -258.765548)
		(stroke
			(width 0.1016)
			(type default)
		)
		(layer "In10.Cu")
	)
	(gr_line
		(start 297.468798 -247.20423)
		(end 296.732706 -247.453404)
		(stroke
			(width 0.1016)
			(type default)
		)
		(layer "In10.Cu")
	)
	(gr_line
		(start 297.530774 -258.703064)
		(end 298.222924 -260.748018)
		(stroke
			(width 0.1016)
			(type default)
		)
		(layer "In10.Cu")
	)
	(gr_line
		(start 298.161202 -249.249184)
		(end 297.468798 -247.20423)
		(stroke
			(width 0.1016)
			(type default)
		)
		(layer "In10.Cu")
	)
	(gr_line
		(start 298.266866 -258.45389)
		(end 297.530774 -258.703064)
		(stroke
			(width 0.1016)
			(type default)
		)
		(layer "In10.Cu")
	)
	(gr_line
		(start 298.617132 -247.098566)
		(end 299.309282 -249.14352)
		(stroke
			(width 0.1016)
			(type default)
		)
		(layer "In10.Cu")
	)
	(gr_line
		(start 298.95927 -260.498844)
		(end 298.266866 -258.45389)
		(stroke
			(width 0.1016)
			(type default)
		)
		(layer "In10.Cu")
	)
	(gr_line
		(start 299.233082 -257.804412)
		(end 299.925232 -259.849366)
		(stroke
			(width 0.1016)
			(type default)
		)
		(layer "In10.Cu")
	)
	(gr_line
		(start 299.353224 -246.849392)
		(end 298.617132 -247.098566)
		(stroke
			(width 0.1016)
			(type default)
		)
		(layer "In10.Cu")
	)
	(gr_line
		(start 299.969174 -257.555238)
		(end 299.233082 -257.804412)
		(stroke
			(width 0.1016)
			(type default)
		)
		(layer "In10.Cu")
	)
	(gr_line
		(start 300.045628 -248.894346)
		(end 299.353224 -246.849392)
		(stroke
			(width 0.1016)
			(type default)
		)
		(layer "In10.Cu")
	)
	(gr_line
		(start 300.661578 -259.600192)
		(end 299.969174 -257.555238)
		(stroke
			(width 0.1016)
			(type default)
		)
		(layer "In10.Cu")
	)
	(gr_line
		(start 301.14748 -257.53441)
		(end 301.83963 -259.579364)
		(stroke
			(width 0.1016)
			(type default)
		)
		(layer "In10.Cu")
	)
	(gr_line
		(start 301.883572 -257.285236)
		(end 301.14748 -257.53441)
		(stroke
			(width 0.1016)
			(type default)
		)
		(layer "In10.Cu")
	)
	(gr_line
		(start 302.575976 -259.33019)
		(end 301.883572 -257.285236)
		(stroke
			(width 0.1016)
			(type default)
		)
		(layer "In10.Cu")
	)
	(gr_line
		(start 303.032922 -257.179572)
		(end 303.725072 -259.224526)
		(stroke
			(width 0.1016)
			(type default)
		)
		(layer "In10.Cu")
	)
	(gr_line
		(start 303.769014 -256.930398)
		(end 303.032922 -257.179572)
		(stroke
			(width 0.1016)
			(type default)
		)
		(layer "In10.Cu")
	)
	(gr_line
		(start 304.268886 -230.902256)
		(end 304.608484 -233.034332)
		(stroke
			(width 0.1016)
			(type default)
		)
		(layer "In10.Cu")
	)
	(gr_line
		(start 304.461418 -258.975352)
		(end 303.769014 -256.930398)
		(stroke
			(width 0.1016)
			(type default)
		)
		(layer "In10.Cu")
	)
	(gr_line
		(start 305.035966 -230.779828)
		(end 304.268886 -230.902256)
		(stroke
			(width 0.1016)
			(type default)
		)
		(layer "In10.Cu")
	)
	(gr_line
		(start 305.376326 -232.912158)
		(end 305.035966 -230.779828)
		(stroke
			(width 0.1016)
			(type default)
		)
		(layer "In10.Cu")
	)
	(gr_line
		(start 305.743356 -246.090948)
		(end 306.082954 -248.223024)
		(stroke
			(width 0.1016)
			(type default)
		)
		(layer "In10.Cu")
	)
	(gr_circle
		(center 306.099718 -316.799722)
		(end 306.353718 -316.799722)
		(stroke
			(width 0.1016)
			(type default)
		)
		(fill no)
		(layer "In10.Cu")
	)
	(gr_circle
		(center 306.099718 -315.849762)
		(end 306.353718 -315.849762)
		(stroke
			(width 0.1016)
			(type default)
		)
		(fill no)
		(layer "In10.Cu")
	)
	(gr_circle
		(center 306.099718 -312.049922)
		(end 306.353718 -312.049922)
		(stroke
			(width 0.1016)
			(type default)
		)
		(fill no)
		(layer "In10.Cu")
	)
	(gr_circle
		(center 306.099718 -311.099962)
		(end 306.353718 -311.099962)
		(stroke
			(width 0.1016)
			(type default)
		)
		(fill no)
		(layer "In10.Cu")
	)
	(gr_line
		(start 306.142644 -230.828596)
		(end 306.482242 -232.960672)
		(stroke
			(width 0.1016)
			(type default)
		)
		(layer "In10.Cu")
	)
	(gr_line
		(start 306.510436 -245.96852)
		(end 305.743356 -246.090948)
		(stroke
			(width 0.1016)
			(type default)
		)
		(layer "In10.Cu")
	)
	(gr_line
		(start 306.850796 -248.10085)
		(end 306.510436 -245.96852)
		(stroke
			(width 0.1016)
			(type default)
		)
		(layer "In10.Cu")
	)
	(gr_line
		(start 306.909724 -230.706168)
		(end 306.142644 -230.828596)
		(stroke
			(width 0.1016)
			(type default)
		)
		(layer "In10.Cu")
	)
	(gr_circle
		(center 307.049932 -318.699896)
		(end 307.303932 -318.699896)
		(stroke
			(width 0.1016)
			(type default)
		)
		(fill no)
		(layer "In10.Cu")
	)
	(gr_circle
		(center 307.049932 -317.749936)
		(end 307.303932 -317.749936)
		(stroke
			(width 0.1016)
			(type default)
		)
		(fill no)
		(layer "In10.Cu")
	)
	(gr_circle
		(center 307.049932 -313.949842)
		(end 307.303932 -313.949842)
		(stroke
			(width 0.1016)
			(type default)
		)
		(fill no)
		(layer "In10.Cu")
	)
	(gr_circle
		(center 307.049932 -312.999882)
		(end 307.303932 -312.999882)
		(stroke
			(width 0.1016)
			(type default)
		)
		(fill no)
		(layer "In10.Cu")
	)
	(gr_circle
		(center 307.049932 -308.249828)
		(end 307.303932 -308.249828)
		(stroke
			(width 0.1016)
			(type default)
		)
		(fill no)
		(layer "In10.Cu")
	)
	(gr_circle
		(center 307.049932 -306.349908)
		(end 307.303932 -306.349908)
		(stroke
			(width 0.1016)
			(type default)
		)
		(fill no)
		(layer "In10.Cu")
	)
	(gr_circle
		(center 307.049932 -304.449734)
		(end 307.303932 -304.449734)
		(stroke
			(width 0.1016)
			(type default)
		)
		(fill no)
		(layer "In10.Cu")
	)
	(gr_line
		(start 307.250084 -232.838498)
		(end 306.909724 -230.706168)
		(stroke
			(width 0.1016)
			(type default)
		)
		(layer "In10.Cu")
	)
	(gr_line
		(start 307.619654 -246.017288)
		(end 307.959252 -248.149364)
		(stroke
			(width 0.1016)
			(type default)
		)
		(layer "In10.Cu")
	)
	(gr_circle
		(center 307.999892 -316.799722)
		(end 308.253892 -316.799722)
		(stroke
			(width 0.1016)
			(type default)
		)
		(fill no)
		(layer "In10.Cu")
	)
	(gr_circle
		(center 307.999892 -315.849762)
		(end 308.253892 -315.849762)
		(stroke
			(width 0.1016)
			(type default)
		)
		(fill no)
		(layer "In10.Cu")
	)
	(gr_circle
		(center 307.999892 -312.049922)
		(end 308.253892 -312.049922)
		(stroke
			(width 0.1016)
			(type default)
		)
		(fill no)
		(layer "In10.Cu")
	)
	(gr_circle
		(center 307.999892 -311.099962)
		(end 308.253892 -311.099962)
		(stroke
			(width 0.1016)
			(type default)
		)
		(fill no)
		(layer "In10.Cu")
	)
	(gr_circle
		(center 307.999892 -308.249828)
		(end 308.253892 -308.249828)
		(stroke
			(width 0.1016)
			(type default)
		)
		(fill no)
		(layer "In10.Cu")
	)
	(gr_circle
		(center 307.999892 -306.349908)
		(end 308.253892 -306.349908)
		(stroke
			(width 0.1016)
			(type default)
		)
		(fill no)
		(layer "In10.Cu")
	)
	(gr_circle
		(center 307.999892 -304.449734)
		(end 308.253892 -304.449734)
		(stroke
			(width 0.1016)
			(type default)
		)
		(fill no)
		(layer "In10.Cu")
	)
	(gr_line
		(start 308.036468 -230.838756)
		(end 308.376066 -232.970832)
		(stroke
			(width 0.1016)
			(type default)
		)
		(layer "In10.Cu")
	)
	(gr_line
		(start 308.386734 -245.89486)
		(end 307.619654 -246.017288)
		(stroke
			(width 0.1016)
			(type default)
		)
		(layer "In10.Cu")
	)
	(gr_line
		(start 308.727094 -248.02719)
		(end 308.386734 -245.89486)
		(stroke
			(width 0.1016)
			(type default)
		)
		(layer "In10.Cu")
	)
	(gr_line
		(start 308.803548 -230.716328)
		(end 308.036468 -230.838756)
		(stroke
			(width 0.1016)
			(type default)
		)
		(layer "In10.Cu")
	)
	(gr_circle
		(center 308.949852 -318.699896)
		(end 309.203852 -318.699896)
		(stroke
			(width 0.1016)
			(type default)
		)
		(fill no)
		(layer "In10.Cu")
	)
	(gr_circle
		(center 308.949852 -317.749936)
		(end 309.203852 -317.749936)
		(stroke
			(width 0.1016)
			(type default)
		)
		(fill no)
		(layer "In10.Cu")
	)
	(gr_circle
		(center 308.949852 -313.949842)
		(end 309.203852 -313.949842)
		(stroke
			(width 0.1016)
			(type default)
		)
		(fill no)
		(layer "In10.Cu")
	)
	(gr_circle
		(center 308.949852 -312.999882)
		(end 309.203852 -312.999882)
		(stroke
			(width 0.1016)
			(type default)
		)
		(fill no)
		(layer "In10.Cu")
	)
	(gr_circle
		(center 308.949852 -309.199788)
		(end 309.203852 -309.199788)
		(stroke
			(width 0.1016)
			(type default)
		)
		(fill no)
		(layer "In10.Cu")
	)
	(gr_circle
		(center 308.949852 -307.299868)
		(end 309.203852 -307.299868)
		(stroke
			(width 0.1016)
			(type default)
		)
		(fill no)
		(layer "In10.Cu")
	)
	(gr_circle
		(center 308.949852 -305.399948)
		(end 309.203852 -305.399948)
		(stroke
			(width 0.1016)
			(type default)
		)
		(fill no)
		(layer "In10.Cu")
	)
	(gr_line
		(start 309.143908 -232.848658)
		(end 308.803548 -230.716328)
		(stroke
			(width 0.1016)
			(type default)
		)
		(layer "In10.Cu")
	)
	(gr_circle
		(center 309.899812 -316.799722)
		(end 310.153812 -316.799722)
		(stroke
			(width 0.1016)
			(type default)
		)
		(fill no)
		(layer "In10.Cu")
	)
	(gr_circle
		(center 309.899812 -315.849762)
		(end 310.153812 -315.849762)
		(stroke
			(width 0.1016)
			(type default)
		)
		(fill no)
		(layer "In10.Cu")
	)
	(gr_circle
		(center 309.899812 -312.049922)
		(end 310.153812 -312.049922)
		(stroke
			(width 0.1016)
			(type default)
		)
		(fill no)
		(layer "In10.Cu")
	)
	(gr_circle
		(center 309.899812 -311.099962)
		(end 310.153812 -311.099962)
		(stroke
			(width 0.1016)
			(type default)
		)
		(fill no)
		(layer "In10.Cu")
	)
	(gr_circle
		(center 309.899812 -309.199788)
		(end 310.153812 -309.199788)
		(stroke
			(width 0.1016)
			(type default)
		)
		(fill no)
		(layer "In10.Cu")
	)
	(gr_circle
		(center 309.899812 -307.299868)
		(end 310.153812 -307.299868)
		(stroke
			(width 0.1016)
			(type default)
		)
		(fill no)
		(layer "In10.Cu")
	)
	(gr_circle
		(center 309.899812 -305.399948)
		(end 310.153812 -305.399948)
		(stroke
			(width 0.1016)
			(type default)
		)
		(fill no)
		(layer "In10.Cu")
	)
	(gr_circle
		(center 310.849772 -318.699896)
		(end 311.103772 -318.699896)
		(stroke
			(width 0.1016)
			(type default)
		)
		(fill no)
		(layer "In10.Cu")
	)
	(gr_circle
		(center 310.849772 -317.749936)
		(end 311.103772 -317.749936)
		(stroke
			(width 0.1016)
			(type default)
		)
		(fill no)
		(layer "In10.Cu")
	)
	(gr_circle
		(center 310.849772 -313.949842)
		(end 311.103772 -313.949842)
		(stroke
			(width 0.1016)
			(type default)
		)
		(fill no)
		(layer "In10.Cu")
	)
	(gr_circle
		(center 310.849772 -312.999882)
		(end 311.103772 -312.999882)
		(stroke
			(width 0.1016)
			(type default)
		)
		(fill no)
		(layer "In10.Cu")
	)
	(gr_line
		(start 310.853836 -260.17601)
		(end 310.853836 -262.33501)
		(stroke
			(width 0.1016)
			(type default)
		)
		(layer "In10.Cu")
	)
	(gr_line
		(start 311.49798 -246.597678)
		(end 311.837578 -248.729754)
		(stroke
			(width 0.1016)
			(type default)
		)
		(layer "In10.Cu")
	)
	(gr_line
		(start 311.630568 -260.175756)
		(end 310.853836 -260.17601)
		(stroke
			(width 0.1016)
			(type default)
		)
		(layer "In10.Cu")
	)
	(gr_line
		(start 311.631076 -262.33501)
		(end 311.630568 -260.175756)
		(stroke
			(width 0.1016)
			(type default)
		)
		(layer "In10.Cu")
	)
	(gr_circle
		(center 311.799732 -316.799722)
		(end 312.053732 -316.799722)
		(stroke
			(width 0.1016)
			(type default)
		)
		(fill no)
		(layer "In10.Cu")
	)
	(gr_circle
		(center 311.799732 -315.849762)
		(end 312.053732 -315.849762)
		(stroke
			(width 0.1016)
			(type default)
		)
		(fill no)
		(layer "In10.Cu")
	)
	(gr_circle
		(center 311.799732 -312.049922)
		(end 312.053732 -312.049922)
		(stroke
			(width 0.1016)
			(type default)
		)
		(fill no)
		(layer "In10.Cu")
	)
	(gr_circle
		(center 311.799732 -311.099962)
		(end 312.053732 -311.099962)
		(stroke
			(width 0.1016)
			(type default)
		)
		(fill no)
		(layer "In10.Cu")
	)
	(gr_circle
		(center 311.799732 -309.199788)
		(end 312.053732 -309.199788)
		(stroke
			(width 0.1016)
			(type default)
		)
		(fill no)
		(layer "In10.Cu")
	)
	(gr_circle
		(center 311.799732 -307.299868)
		(end 312.053732 -307.299868)
		(stroke
			(width 0.1016)
			(type default)
		)
		(fill no)
		(layer "In10.Cu")
	)
	(gr_circle
		(center 311.799732 -305.399948)
		(end 312.053732 -305.399948)
		(stroke
			(width 0.1016)
			(type default)
		)
		(fill no)
		(layer "In10.Cu")
	)
	(gr_line
		(start 311.849262 -230.969058)
		(end 312.18886 -233.101134)
		(stroke
			(width 0.1016)
			(type default)
		)
		(layer "In10.Cu")
	)
	(gr_line
		(start 312.26506 -246.47525)
		(end 311.49798 -246.597678)
		(stroke
			(width 0.1016)
			(type default)
		)
		(layer "In10.Cu")
	)
	(gr_line
		(start 312.60542 -248.60758)
		(end 312.26506 -246.47525)
		(stroke
			(width 0.1016)
			(type default)
		)
		(layer "In10.Cu")
	)
	(gr_line
		(start 312.616342 -230.84663)
		(end 311.849262 -230.969058)
		(stroke
			(width 0.1016)
			(type default)
		)
		(layer "In10.Cu")
	)
	(gr_circle
		(center 312.749692 -318.699896)
		(end 313.003692 -318.699896)
		(stroke
			(width 0.1016)
			(type default)
		)
		(fill no)
		(layer "In10.Cu")
	)
	(gr_circle
		(center 312.749692 -317.749936)
		(end 313.003692 -317.749936)
		(stroke
			(width 0.1016)
			(type default)
		)
		(fill no)
		(layer "In10.Cu")
	)
	(gr_circle
		(center 312.749692 -313.949842)
		(end 313.003692 -313.949842)
		(stroke
			(width 0.1016)
			(type default)
		)
		(fill no)
		(layer "In10.Cu")
	)
	(gr_circle
		(center 312.749692 -312.999882)
		(end 313.003692 -312.999882)
		(stroke
			(width 0.1016)
			(type default)
		)
		(fill no)
		(layer "In10.Cu")
	)
	(gr_circle
		(center 312.749692 -309.199788)
		(end 313.003692 -309.199788)
		(stroke
			(width 0.1016)
			(type default)
		)
		(fill no)
		(layer "In10.Cu")
	)
	(gr_circle
		(center 312.749692 -307.299868)
		(end 313.003692 -307.299868)
		(stroke
			(width 0.1016)
			(type default)
		)
		(fill no)
		(layer "In10.Cu")
	)
	(gr_circle
		(center 312.749692 -305.399948)
		(end 313.003692 -305.399948)
		(stroke
			(width 0.1016)
			(type default)
		)
		(fill no)
		(layer "In10.Cu")
	)
	(gr_line
		(start 312.956702 -232.97896)
		(end 312.616342 -230.84663)
		(stroke
			(width 0.1016)
			(type default)
		)
		(layer "In10.Cu")
	)
	(gr_line
		(start 313.311286 -246.11457)
		(end 313.650884 -248.246646)
		(stroke
			(width 0.1016)
			(type default)
		)
		(layer "In10.Cu")
	)
	(gr_circle
		(center 313.699906 -316.799722)
		(end 313.953906 -316.799722)
		(stroke
			(width 0.1016)
			(type default)
		)
		(fill no)
		(layer "In10.Cu")
	)
	(gr_circle
		(center 313.699906 -314.899802)
		(end 313.953906 -314.899802)
		(stroke
			(width 0.1016)
			(type default)
		)
		(fill no)
		(layer "In10.Cu")
	)
	(gr_circle
		(center 313.699906 -312.049922)
		(end 313.953906 -312.049922)
		(stroke
			(width 0.1016)
			(type default)
		)
		(fill no)
		(layer "In10.Cu")
	)
	(gr_circle
		(center 313.699906 -310.149748)
		(end 313.953906 -310.149748)
		(stroke
			(width 0.1016)
			(type default)
		)
		(fill no)
		(layer "In10.Cu")
	)
	(gr_circle
		(center 313.699906 -308.249828)
		(end 313.953906 -308.249828)
		(stroke
			(width 0.1016)
			(type default)
		)
		(fill no)
		(layer "In10.Cu")
	)
	(gr_circle
		(center 313.699906 -306.349908)
		(end 313.953906 -306.349908)
		(stroke
			(width 0.1016)
			(type default)
		)
		(fill no)
		(layer "In10.Cu")
	)
	(gr_circle
		(center 313.699906 -304.449734)
		(end 313.953906 -304.449734)
		(stroke
			(width 0.1016)
			(type default)
		)
		(fill no)
		(layer "In10.Cu")
	)
	(gr_line
		(start 313.700414 -260.491224)
		(end 313.700414 -262.650224)
		(stroke
			(width 0.1016)
			(type default)
		)
		(layer "In10.Cu")
	)
	(gr_line
		(start 313.733942 -230.750872)
		(end 314.07354 -232.882948)
		(stroke
			(width 0.1016)
			(type default)
		)
		(layer "In10.Cu")
	)
	(gr_line
		(start 314.078366 -245.992142)
		(end 313.311286 -246.11457)
		(stroke
			(width 0.1016)
			(type default)
		)
		(layer "In10.Cu")
	)
	(gr_line
		(start 314.418726 -248.124472)
		(end 314.078366 -245.992142)
		(stroke
			(width 0.1016)
			(type default)
		)
		(layer "In10.Cu")
	)
	(gr_line
		(start 314.477146 -260.49097)
		(end 313.700414 -260.491224)
		(stroke
			(width 0.1016)
			(type default)
		)
		(layer "In10.Cu")
	)
	(gr_line
		(start 314.477654 -262.650224)
		(end 314.477146 -260.49097)
		(stroke
			(width 0.1016)
			(type default)
		)
		(layer "In10.Cu")
	)
	(gr_line
		(start 314.501022 -230.628444)
		(end 313.733942 -230.750872)
		(stroke
			(width 0.1016)
			(type default)
		)
		(layer "In10.Cu")
	)
	(gr_line
		(start 314.570618 -242.091464)
		(end 314.910216 -244.22354)
		(stroke
			(width 0.1016)
			(type default)
		)
		(layer "In10.Cu")
	)
	(gr_circle
		(center 314.649866 -316.799722)
		(end 314.903866 -316.799722)
		(stroke
			(width 0.1016)
			(type default)
		)
		(fill no)
		(layer "In10.Cu")
	)
	(gr_circle
		(center 314.649866 -314.899802)
		(end 314.903866 -314.899802)
		(stroke
			(width 0.1016)
			(type default)
		)
		(fill no)
		(layer "In10.Cu")
	)
	(gr_circle
		(center 314.649866 -312.049922)
		(end 314.903866 -312.049922)
		(stroke
			(width 0.1016)
			(type default)
		)
		(fill no)
		(layer "In10.Cu")
	)
	(gr_circle
		(center 314.649866 -310.149748)
		(end 314.903866 -310.149748)
		(stroke
			(width 0.1016)
			(type default)
		)
		(fill no)
		(layer "In10.Cu")
	)
	(gr_circle
		(center 314.649866 -308.249828)
		(end 314.903866 -308.249828)
		(stroke
			(width 0.1016)
			(type default)
		)
		(fill no)
		(layer "In10.Cu")
	)
	(gr_circle
		(center 314.649866 -306.349908)
		(end 314.903866 -306.349908)
		(stroke
			(width 0.1016)
			(type default)
		)
		(fill no)
		(layer "In10.Cu")
	)
	(gr_circle
		(center 314.649866 -304.449734)
		(end 314.903866 -304.449734)
		(stroke
			(width 0.1016)
			(type default)
		)
		(fill no)
		(layer "In10.Cu")
	)
	(gr_line
		(start 314.841382 -232.760774)
		(end 314.501022 -230.628444)
		(stroke
			(width 0.1016)
			(type default)
		)
		(layer "In10.Cu")
	)
	(gr_line
		(start 315.337698 -241.969036)
		(end 314.570618 -242.091464)
		(stroke
			(width 0.1016)
			(type default)
		)
		(layer "In10.Cu")
	)
	(gr_line
		(start 315.632084 -230.563674)
		(end 315.971682 -232.69575)
		(stroke
			(width 0.1016)
			(type default)
		)
		(layer "In10.Cu")
	)
	(gr_line
		(start 315.678058 -244.101366)
		(end 315.337698 -241.969036)
		(stroke
			(width 0.1016)
			(type default)
		)
		(layer "In10.Cu")
	)
	(gr_line
		(start 316.399164 -230.441246)
		(end 315.632084 -230.563674)
		(stroke
			(width 0.1016)
			(type default)
		)
		(layer "In10.Cu")
	)
	(gr_line
		(start 316.503558 -242.091464)
		(end 316.843156 -244.22354)
		(stroke
			(width 0.1016)
			(type default)
		)
		(layer "In10.Cu")
	)
	(gr_line
		(start 316.739524 -232.573576)
		(end 316.399164 -230.441246)
		(stroke
			(width 0.1016)
			(type default)
		)
		(layer "In10.Cu")
	)
	(gr_line
		(start 317.270638 -241.969036)
		(end 316.503558 -242.091464)
		(stroke
			(width 0.1016)
			(type default)
		)
		(layer "In10.Cu")
	)
	(gr_line
		(start 317.536068 -230.313992)
		(end 317.875666 -232.446068)
		(stroke
			(width 0.1016)
			(type default)
		)
		(layer "In10.Cu")
	)
	(gr_line
		(start 317.610998 -244.101366)
		(end 317.270638 -241.969036)
		(stroke
			(width 0.1016)
			(type default)
		)
		(layer "In10.Cu")
	)
	(gr_line
		(start 318.303148 -230.191564)
		(end 317.536068 -230.313992)
		(stroke
			(width 0.1016)
			(type default)
		)
		(layer "In10.Cu")
	)
	(gr_line
		(start 318.388492 -241.730784)
		(end 318.72809 -243.86286)
		(stroke
			(width 0.1016)
			(type default)
		)
		(layer "In10.Cu")
	)
	(gr_line
		(start 318.643508 -232.323894)
		(end 318.303148 -230.191564)
		(stroke
			(width 0.1016)
			(type default)
		)
		(layer "In10.Cu")
	)
	(gr_line
		(start 319.155572 -241.608356)
		(end 318.388492 -241.730784)
		(stroke
			(width 0.1016)
			(type default)
		)
		(layer "In10.Cu")
	)
	(gr_line
		(start 319.495932 -243.740686)
		(end 319.155572 -241.608356)
		(stroke
			(width 0.1016)
			(type default)
		)
		(layer "In10.Cu")
	)
	(gr_line
		(start 368.665506 -130.829304)
		(end 368.665506 -132.988304)
		(stroke
			(width 0.1016)
			(type default)
		)
		(layer "In10.Cu")
	)
	(gr_line
		(start 369.442238 -130.82905)
		(end 368.665506 -130.829304)
		(stroke
			(width 0.1016)
			(type default)
		)
		(layer "In10.Cu")
	)
	(gr_line
		(start 369.442746 -132.988304)
		(end 369.442238 -130.82905)
		(stroke
			(width 0.1016)
			(type default)
		)
		(layer "In10.Cu")
	)
	(gr_line
		(start 372.340632 -156.489146)
		(end 372.71198 -158.615888)
		(stroke
			(width 0.1016)
			(type default)
		)
		(layer "In10.Cu")
	)
	(gr_line
		(start 373.105934 -156.355034)
		(end 372.340632 -156.489146)
		(stroke
			(width 0.1016)
			(type default)
		)
		(layer "In10.Cu")
	)
	(gr_line
		(start 373.477536 -158.48203)
		(end 373.105934 -156.355034)
		(stroke
			(width 0.1016)
			(type default)
		)
		(layer "In10.Cu")
	)
	(gr_line
		(start 374.82272 -115.836446)
		(end 374.196102 -117.902482)
		(stroke
			(width 0.1016)
			(type default)
		)
		(layer "In10.Cu")
	)
	(gr_line
		(start 374.940068 -118.128034)
		(end 375.566432 -116.061998)
		(stroke
			(width 0.1016)
			(type default)
		)
		(layer "In10.Cu")
	)
	(gr_line
		(start 375.566432 -116.061998)
		(end 374.82272 -115.836446)
		(stroke
			(width 0.1016)
			(type default)
		)
		(layer "In10.Cu")
	)
	(gr_line
		(start 376.343926 -117.404642)
		(end 375.717308 -119.470678)
		(stroke
			(width 0.1016)
			(type default)
		)
		(layer "In10.Cu")
	)
	(gr_line
		(start 376.461274 -119.69623)
		(end 377.087638 -117.630194)
		(stroke
			(width 0.1016)
			(type default)
		)
		(layer "In10.Cu")
	)
	(gr_line
		(start 377.087638 -117.630194)
		(end 376.343926 -117.404642)
		(stroke
			(width 0.1016)
			(type default)
		)
		(layer "In10.Cu")
	)
	(gr_line
		(start 378.745496 -110.673642)
		(end 379.571504 -108.678726)
		(stroke
			(width 0.1016)
			(type default)
		)
		(layer "In10.Cu")
	)
	(gr_line
		(start 378.8537 -108.381546)
		(end 378.027438 -110.376208)
		(stroke
			(width 0.1016)
			(type default)
		)
		(layer "In10.Cu")
	)
	(gr_line
		(start 379.571504 -108.678726)
		(end 378.8537 -108.381546)
		(stroke
			(width 0.1016)
			(type default)
		)
		(layer "In10.Cu")
	)
	(gr_line
		(start 379.794262 -167.626792)
		(end 380.486412 -169.671746)
		(stroke
			(width 0.1016)
			(type default)
		)
		(layer "In10.Cu")
	)
	(gr_line
		(start 380.530354 -167.377618)
		(end 379.794262 -167.626792)
		(stroke
			(width 0.1016)
			(type default)
		)
		(layer "In10.Cu")
	)
	(gr_line
		(start 381.222758 -169.422572)
		(end 380.530354 -167.377618)
		(stroke
			(width 0.1016)
			(type default)
		)
		(layer "In10.Cu")
	)
	(gr_circle
		(center 385.149852 -314.899802)
		(end 385.403852 -314.899802)
		(stroke
			(width 0.1016)
			(type default)
		)
		(fill no)
		(layer "In10.Cu")
	)
	(gr_circle
		(center 385.149852 -312.049922)
		(end 385.403852 -312.049922)
		(stroke
			(width 0.1016)
			(type default)
		)
		(fill no)
		(layer "In10.Cu")
	)
	(gr_circle
		(center 386.099812 -314.899802)
		(end 386.353812 -314.899802)
		(stroke
			(width 0.1016)
			(type default)
		)
		(fill no)
		(layer "In10.Cu")
	)
	(gr_circle
		(center 386.099812 -312.049922)
		(end 386.353812 -312.049922)
		(stroke
			(width 0.1016)
			(type default)
		)
		(fill no)
		(layer "In10.Cu")
	)
	(gr_circle
		(center 387.050026 -313.949842)
		(end 387.304026 -313.949842)
		(stroke
			(width 0.1016)
			(type default)
		)
		(fill no)
		(layer "In10.Cu")
	)
	(gr_circle
		(center 387.050026 -312.999882)
		(end 387.304026 -312.999882)
		(stroke
			(width 0.1016)
			(type default)
		)
		(fill no)
		(layer "In10.Cu")
	)
	(gr_circle
		(center 387.999986 -312.049922)
		(end 388.253986 -312.049922)
		(stroke
			(width 0.1016)
			(type default)
		)
		(fill no)
		(layer "In10.Cu")
	)
	(gr_circle
		(center 387.999986 -311.099962)
		(end 388.253986 -311.099962)
		(stroke
			(width 0.1016)
			(type default)
		)
		(fill no)
		(layer "In10.Cu")
	)
	(gr_circle
		(center 388.949946 -313.949842)
		(end 389.203946 -313.949842)
		(stroke
			(width 0.1016)
			(type default)
		)
		(fill no)
		(layer "In10.Cu")
	)
	(gr_circle
		(center 388.949946 -312.999882)
		(end 389.203946 -312.999882)
		(stroke
			(width 0.1016)
			(type default)
		)
		(fill no)
		(layer "In10.Cu")
	)
	(gr_circle
		(center 389.899906 -312.049922)
		(end 390.153906 -312.049922)
		(stroke
			(width 0.1016)
			(type default)
		)
		(fill no)
		(layer "In10.Cu")
	)
	(gr_circle
		(center 389.899906 -311.099962)
		(end 390.153906 -311.099962)
		(stroke
			(width 0.1016)
			(type default)
		)
		(fill no)
		(layer "In10.Cu")
	)
	(gr_circle
		(center 389.899906 -309.199788)
		(end 390.153906 -309.199788)
		(stroke
			(width 0.1016)
			(type default)
		)
		(fill no)
		(layer "In10.Cu")
	)
	(gr_circle
		(center 389.899906 -307.299868)
		(end 390.153906 -307.299868)
		(stroke
			(width 0.1016)
			(type default)
		)
		(fill no)
		(layer "In10.Cu")
	)
	(gr_circle
		(center 389.899906 -305.399948)
		(end 390.153906 -305.399948)
		(stroke
			(width 0.1016)
			(type default)
		)
		(fill no)
		(layer "In10.Cu")
	)
	(gr_circle
		(center 389.899906 -303.499774)
		(end 390.153906 -303.499774)
		(stroke
			(width 0.1016)
			(type default)
		)
		(fill no)
		(layer "In10.Cu")
	)
	(gr_circle
		(center 389.899906 -301.599854)
		(end 390.153906 -301.599854)
		(stroke
			(width 0.1016)
			(type default)
		)
		(fill no)
		(layer "In10.Cu")
	)
	(gr_circle
		(center 390.849866 -313.949842)
		(end 391.103866 -313.949842)
		(stroke
			(width 0.1016)
			(type default)
		)
		(fill no)
		(layer "In10.Cu")
	)
	(gr_circle
		(center 390.849866 -312.999882)
		(end 391.103866 -312.999882)
		(stroke
			(width 0.1016)
			(type default)
		)
		(fill no)
		(layer "In10.Cu")
	)
	(gr_circle
		(center 390.849866 -309.199788)
		(end 391.103866 -309.199788)
		(stroke
			(width 0.1016)
			(type default)
		)
		(fill no)
		(layer "In10.Cu")
	)
	(gr_circle
		(center 390.849866 -307.299868)
		(end 391.103866 -307.299868)
		(stroke
			(width 0.1016)
			(type default)
		)
		(fill no)
		(layer "In10.Cu")
	)
	(gr_circle
		(center 390.849866 -305.399948)
		(end 391.103866 -305.399948)
		(stroke
			(width 0.1016)
			(type default)
		)
		(fill no)
		(layer "In10.Cu")
	)
	(gr_circle
		(center 390.849866 -303.499774)
		(end 391.103866 -303.499774)
		(stroke
			(width 0.1016)
			(type default)
		)
		(fill no)
		(layer "In10.Cu")
	)
	(gr_circle
		(center 390.849866 -301.599854)
		(end 391.103866 -301.599854)
		(stroke
			(width 0.1016)
			(type default)
		)
		(fill no)
		(layer "In10.Cu")
	)
	(gr_circle
		(center 391.799826 -316.799722)
		(end 392.053826 -316.799722)
		(stroke
			(width 0.1016)
			(type default)
		)
		(fill no)
		(layer "In10.Cu")
	)
	(gr_circle
		(center 391.799826 -315.849762)
		(end 392.053826 -315.849762)
		(stroke
			(width 0.1016)
			(type default)
		)
		(fill no)
		(layer "In10.Cu")
	)
	(gr_circle
		(center 391.799826 -312.049922)
		(end 392.053826 -312.049922)
		(stroke
			(width 0.1016)
			(type default)
		)
		(fill no)
		(layer "In10.Cu")
	)
	(gr_circle
		(center 391.799826 -311.099962)
		(end 392.053826 -311.099962)
		(stroke
			(width 0.1016)
			(type default)
		)
		(fill no)
		(layer "In10.Cu")
	)
	(gr_circle
		(center 391.799826 -308.249828)
		(end 392.053826 -308.249828)
		(stroke
			(width 0.1016)
			(type default)
		)
		(fill no)
		(layer "In10.Cu")
	)
	(gr_circle
		(center 391.799826 -306.349908)
		(end 392.053826 -306.349908)
		(stroke
			(width 0.1016)
			(type default)
		)
		(fill no)
		(layer "In10.Cu")
	)
	(gr_circle
		(center 391.799826 -304.449734)
		(end 392.053826 -304.449734)
		(stroke
			(width 0.1016)
			(type default)
		)
		(fill no)
		(layer "In10.Cu")
	)
	(gr_circle
		(center 391.799826 -302.549814)
		(end 392.053826 -302.549814)
		(stroke
			(width 0.1016)
			(type default)
		)
		(fill no)
		(layer "In10.Cu")
	)
	(gr_circle
		(center 392.749786 -318.699896)
		(end 393.003786 -318.699896)
		(stroke
			(width 0.1016)
			(type default)
		)
		(fill no)
		(layer "In10.Cu")
	)
	(gr_circle
		(center 392.749786 -317.749936)
		(end 393.003786 -317.749936)
		(stroke
			(width 0.1016)
			(type default)
		)
		(fill no)
		(layer "In10.Cu")
	)
	(gr_circle
		(center 392.749786 -313.949842)
		(end 393.003786 -313.949842)
		(stroke
			(width 0.1016)
			(type default)
		)
		(fill no)
		(layer "In10.Cu")
	)
	(gr_circle
		(center 392.749786 -312.999882)
		(end 393.003786 -312.999882)
		(stroke
			(width 0.1016)
			(type default)
		)
		(fill no)
		(layer "In10.Cu")
	)
	(gr_circle
		(center 392.749786 -308.249828)
		(end 393.003786 -308.249828)
		(stroke
			(width 0.1016)
			(type default)
		)
		(fill no)
		(layer "In10.Cu")
	)
	(gr_circle
		(center 392.749786 -306.349908)
		(end 393.003786 -306.349908)
		(stroke
			(width 0.1016)
			(type default)
		)
		(fill no)
		(layer "In10.Cu")
	)
	(gr_circle
		(center 392.749786 -304.449734)
		(end 393.003786 -304.449734)
		(stroke
			(width 0.1016)
			(type default)
		)
		(fill no)
		(layer "In10.Cu")
	)
	(gr_circle
		(center 392.749786 -302.549814)
		(end 393.003786 -302.549814)
		(stroke
			(width 0.1016)
			(type default)
		)
		(fill no)
		(layer "In10.Cu")
	)
	(gr_circle
		(center 392.749786 -278.799798)
		(end 393.003786 -278.799798)
		(stroke
			(width 0.1016)
			(type default)
		)
		(fill no)
		(layer "In10.Cu")
	)
	(gr_circle
		(center 392.749786 -277.849838)
		(end 393.003786 -277.849838)
		(stroke
			(width 0.1016)
			(type default)
		)
		(fill no)
		(layer "In10.Cu")
	)
	(gr_circle
		(center 393.7 -316.799722)
		(end 393.954 -316.799722)
		(stroke
			(width 0.1016)
			(type default)
		)
		(fill no)
		(layer "In10.Cu")
	)
	(gr_circle
		(center 393.7 -315.849762)
		(end 393.954 -315.849762)
		(stroke
			(width 0.1016)
			(type default)
		)
		(fill no)
		(layer "In10.Cu")
	)
	(gr_circle
		(center 393.7 -312.049922)
		(end 393.954 -312.049922)
		(stroke
			(width 0.1016)
			(type default)
		)
		(fill no)
		(layer "In10.Cu")
	)
	(gr_circle
		(center 393.7 -311.099962)
		(end 393.954 -311.099962)
		(stroke
			(width 0.1016)
			(type default)
		)
		(fill no)
		(layer "In10.Cu")
	)
	(gr_circle
		(center 393.7 -280.699464)
		(end 393.954 -280.699464)
		(stroke
			(width 0.1016)
			(type default)
		)
		(fill no)
		(layer "In10.Cu")
	)
	(gr_circle
		(center 393.7 -279.749504)
		(end 393.954 -279.749504)
		(stroke
			(width 0.1016)
			(type default)
		)
		(fill no)
		(layer "In10.Cu")
	)
	(gr_circle
		(center 394.64996 -318.699896)
		(end 394.90396 -318.699896)
		(stroke
			(width 0.1016)
			(type default)
		)
		(fill no)
		(layer "In10.Cu")
	)
	(gr_circle
		(center 394.64996 -317.749936)
		(end 394.90396 -317.749936)
		(stroke
			(width 0.1016)
			(type default)
		)
		(fill no)
		(layer "In10.Cu")
	)
	(gr_circle
		(center 394.64996 -313.949842)
		(end 394.90396 -313.949842)
		(stroke
			(width 0.1016)
			(type default)
		)
		(fill no)
		(layer "In10.Cu")
	)
	(gr_circle
		(center 394.64996 -312.999882)
		(end 394.90396 -312.999882)
		(stroke
			(width 0.1016)
			(type default)
		)
		(fill no)
		(layer "In10.Cu")
	)
	(gr_circle
		(center 394.64996 -278.799798)
		(end 394.90396 -278.799798)
		(stroke
			(width 0.1016)
			(type default)
		)
		(fill no)
		(layer "In10.Cu")
	)
	(gr_circle
		(center 394.64996 -277.849838)
		(end 394.90396 -277.849838)
		(stroke
			(width 0.1016)
			(type default)
		)
		(fill no)
		(layer "In10.Cu")
	)
	(gr_circle
		(center 395.59992 -316.799722)
		(end 395.85392 -316.799722)
		(stroke
			(width 0.1016)
			(type default)
		)
		(fill no)
		(layer "In10.Cu")
	)
	(gr_circle
		(center 395.59992 -315.849762)
		(end 395.85392 -315.849762)
		(stroke
			(width 0.1016)
			(type default)
		)
		(fill no)
		(layer "In10.Cu")
	)
	(gr_circle
		(center 395.59992 -312.049922)
		(end 395.85392 -312.049922)
		(stroke
			(width 0.1016)
			(type default)
		)
		(fill no)
		(layer "In10.Cu")
	)
	(gr_circle
		(center 395.59992 -311.099962)
		(end 395.85392 -311.099962)
		(stroke
			(width 0.1016)
			(type default)
		)
		(fill no)
		(layer "In10.Cu")
	)
	(gr_circle
		(center 395.59992 -280.699464)
		(end 395.85392 -280.699464)
		(stroke
			(width 0.1016)
			(type default)
		)
		(fill no)
		(layer "In10.Cu")
	)
	(gr_circle
		(center 395.59992 -279.749504)
		(end 395.85392 -279.749504)
		(stroke
			(width 0.1016)
			(type default)
		)
		(fill no)
		(layer "In10.Cu")
	)
	(gr_circle
		(center 396.54988 -318.699896)
		(end 396.80388 -318.699896)
		(stroke
			(width 0.1016)
			(type default)
		)
		(fill no)
		(layer "In10.Cu")
	)
	(gr_circle
		(center 396.54988 -317.749936)
		(end 396.80388 -317.749936)
		(stroke
			(width 0.1016)
			(type default)
		)
		(fill no)
		(layer "In10.Cu")
	)
	(gr_circle
		(center 396.54988 -313.949842)
		(end 396.80388 -313.949842)
		(stroke
			(width 0.1016)
			(type default)
		)
		(fill no)
		(layer "In10.Cu")
	)
	(gr_circle
		(center 396.54988 -312.999882)
		(end 396.80388 -312.999882)
		(stroke
			(width 0.1016)
			(type default)
		)
		(fill no)
		(layer "In10.Cu")
	)
	(gr_circle
		(center 396.54988 -278.799798)
		(end 396.80388 -278.799798)
		(stroke
			(width 0.1016)
			(type default)
		)
		(fill no)
		(layer "In10.Cu")
	)
	(gr_circle
		(center 396.54988 -277.849838)
		(end 396.80388 -277.849838)
		(stroke
			(width 0.1016)
			(type default)
		)
		(fill no)
		(layer "In10.Cu")
	)
	(gr_circle
		(center 397.49984 -316.799722)
		(end 397.75384 -316.799722)
		(stroke
			(width 0.1016)
			(type default)
		)
		(fill no)
		(layer "In10.Cu")
	)
	(gr_circle
		(center 397.49984 -315.849762)
		(end 397.75384 -315.849762)
		(stroke
			(width 0.1016)
			(type default)
		)
		(fill no)
		(layer "In10.Cu")
	)
	(gr_circle
		(center 397.49984 -312.049922)
		(end 397.75384 -312.049922)
		(stroke
			(width 0.1016)
			(type default)
		)
		(fill no)
		(layer "In10.Cu")
	)
	(gr_circle
		(center 397.49984 -311.099962)
		(end 397.75384 -311.099962)
		(stroke
			(width 0.1016)
			(type default)
		)
		(fill no)
		(layer "In10.Cu")
	)
	(gr_circle
		(center 397.49984 -280.699464)
		(end 397.75384 -280.699464)
		(stroke
			(width 0.1016)
			(type default)
		)
		(fill no)
		(layer "In10.Cu")
	)
	(gr_circle
		(center 397.49984 -279.749504)
		(end 397.75384 -279.749504)
		(stroke
			(width 0.1016)
			(type default)
		)
		(fill no)
		(layer "In10.Cu")
	)
	(gr_circle
		(center 398.4498 -318.699896)
		(end 398.7038 -318.699896)
		(stroke
			(width 0.1016)
			(type default)
		)
		(fill no)
		(layer "In10.Cu")
	)
	(gr_circle
		(center 398.4498 -317.749936)
		(end 398.7038 -317.749936)
		(stroke
			(width 0.1016)
			(type default)
		)
		(fill no)
		(layer "In10.Cu")
	)
	(gr_circle
		(center 398.4498 -313.949842)
		(end 398.7038 -313.949842)
		(stroke
			(width 0.1016)
			(type default)
		)
		(fill no)
		(layer "In10.Cu")
	)
	(gr_circle
		(center 398.4498 -312.999882)
		(end 398.7038 -312.999882)
		(stroke
			(width 0.1016)
			(type default)
		)
		(fill no)
		(layer "In10.Cu")
	)
	(gr_circle
		(center 398.4498 -278.799798)
		(end 398.7038 -278.799798)
		(stroke
			(width 0.1016)
			(type default)
		)
		(fill no)
		(layer "In10.Cu")
	)
	(gr_circle
		(center 398.4498 -277.849838)
		(end 398.7038 -277.849838)
		(stroke
			(width 0.1016)
			(type default)
		)
		(fill no)
		(layer "In10.Cu")
	)
	(gr_circle
		(center 399.400014 -280.699464)
		(end 399.654014 -280.699464)
		(stroke
			(width 0.1016)
			(type default)
		)
		(fill no)
		(layer "In10.Cu")
	)
	(gr_circle
		(center 399.400014 -279.749504)
		(end 399.654014 -279.749504)
		(stroke
			(width 0.1016)
			(type default)
		)
		(fill no)
		(layer "In10.Cu")
	)
	(gr_circle
		(center 400.349974 -278.799798)
		(end 400.603974 -278.799798)
		(stroke
			(width 0.1016)
			(type default)
		)
		(fill no)
		(layer "In10.Cu")
	)
	(gr_circle
		(center 400.349974 -277.849838)
		(end 400.603974 -277.849838)
		(stroke
			(width 0.1016)
			(type default)
		)
		(fill no)
		(layer "In10.Cu")
	)
	(gr_circle
		(center 401.299934 -280.699464)
		(end 401.553934 -280.699464)
		(stroke
			(width 0.1016)
			(type default)
		)
		(fill no)
		(layer "In10.Cu")
	)
	(gr_circle
		(center 401.299934 -279.749504)
		(end 401.553934 -279.749504)
		(stroke
			(width 0.1016)
			(type default)
		)
		(fill no)
		(layer "In10.Cu")
	)
	(gr_circle
		(center 402.249894 -278.799798)
		(end 402.503894 -278.799798)
		(stroke
			(width 0.1016)
			(type default)
		)
		(fill no)
		(layer "In10.Cu")
	)
	(gr_circle
		(center 402.249894 -277.849838)
		(end 402.503894 -277.849838)
		(stroke
			(width 0.1016)
			(type default)
		)
		(fill no)
		(layer "In10.Cu")
	)
	(gr_circle
		(center 403.199854 -280.699464)
		(end 403.453854 -280.699464)
		(stroke
			(width 0.1016)
			(type default)
		)
		(fill no)
		(layer "In10.Cu")
	)
	(gr_circle
		(center 403.199854 -279.749504)
		(end 403.453854 -279.749504)
		(stroke
			(width 0.1016)
			(type default)
		)
		(fill no)
		(layer "In10.Cu")
	)
	(gr_circle
		(center 404.149814 -278.799798)
		(end 404.403814 -278.799798)
		(stroke
			(width 0.1016)
			(type default)
		)
		(fill no)
		(layer "In10.Cu")
	)
	(gr_circle
		(center 404.149814 -277.849838)
		(end 404.403814 -277.849838)
		(stroke
			(width 0.1016)
			(type default)
		)
		(fill no)
		(layer "In10.Cu")
	)
	(gr_circle
		(center 405.099774 -280.699464)
		(end 405.353774 -280.699464)
		(stroke
			(width 0.1016)
			(type default)
		)
		(fill no)
		(layer "In10.Cu")
	)
	(gr_circle
		(center 405.099774 -279.749504)
		(end 405.353774 -279.749504)
		(stroke
			(width 0.1016)
			(type default)
		)
		(fill no)
		(layer "In10.Cu")
	)
	(gr_circle
		(center 406.049988 -278.799798)
		(end 406.303988 -278.799798)
		(stroke
			(width 0.1016)
			(type default)
		)
		(fill no)
		(layer "In10.Cu")
	)
	(gr_circle
		(center 406.049988 -277.849838)
		(end 406.303988 -277.849838)
		(stroke
			(width 0.1016)
			(type default)
		)
		(fill no)
		(layer "In10.Cu")
	)
	(gr_circle
		(center 406.999948 -280.699464)
		(end 407.253948 -280.699464)
		(stroke
			(width 0.1016)
			(type default)
		)
		(fill no)
		(layer "In10.Cu")
	)
	(gr_circle
		(center 406.999948 -279.749504)
		(end 407.253948 -279.749504)
		(stroke
			(width 0.1016)
			(type default)
		)
		(fill no)
		(layer "In10.Cu")
	)
	(gr_line
		(start 409.831032 -259.328666)
		(end 410.523182 -261.37362)
		(stroke
			(width 0.1016)
			(type default)
		)
		(layer "In10.Cu")
	)
	(gr_line
		(start 410.059632 -251.115068)
		(end 410.751782 -253.160022)
		(stroke
			(width 0.1016)
			(type default)
		)
		(layer "In10.Cu")
	)
	(gr_line
		(start 410.567124 -259.079492)
		(end 409.831032 -259.328666)
		(stroke
			(width 0.1016)
			(type default)
		)
		(layer "In10.Cu")
	)
	(gr_line
		(start 410.795724 -250.865894)
		(end 410.059632 -251.115068)
		(stroke
			(width 0.1016)
			(type default)
		)
		(layer "In10.Cu")
	)
	(gr_line
		(start 410.918406 -247.723406)
		(end 411.610556 -249.76836)
		(stroke
			(width 0.1016)
			(type default)
		)
		(layer "In10.Cu")
	)
	(gr_line
		(start 411.259528 -261.124446)
		(end 410.567124 -259.079492)
		(stroke
			(width 0.1016)
			(type default)
		)
		(layer "In10.Cu")
	)
	(gr_line
		(start 411.488128 -252.910848)
		(end 410.795724 -250.865894)
		(stroke
			(width 0.1016)
			(type default)
		)
		(layer "In10.Cu")
	)
	(gr_line
		(start 411.654498 -247.474232)
		(end 410.918406 -247.723406)
		(stroke
			(width 0.1016)
			(type default)
		)
		(layer "In10.Cu")
	)
	(gr_line
		(start 411.730952 -259.014722)
		(end 412.423102 -261.059676)
		(stroke
			(width 0.1016)
			(type default)
		)
		(layer "In10.Cu")
	)
	(gr_line
		(start 412.346902 -249.519186)
		(end 411.654498 -247.474232)
		(stroke
			(width 0.1016)
			(type default)
		)
		(layer "In10.Cu")
	)
	(gr_line
		(start 412.467044 -258.765548)
		(end 411.730952 -259.014722)
		(stroke
			(width 0.1016)
			(type default)
		)
		(layer "In10.Cu")
	)
	(gr_line
		(start 412.832804 -247.453404)
		(end 413.524954 -249.498358)
		(stroke
			(width 0.1016)
			(type default)
		)
		(layer "In10.Cu")
	)
	(gr_line
		(start 413.159448 -260.810502)
		(end 412.467044 -258.765548)
		(stroke
			(width 0.1016)
			(type default)
		)
		(layer "In10.Cu")
	)
	(gr_line
		(start 413.568896 -247.20423)
		(end 412.832804 -247.453404)
		(stroke
			(width 0.1016)
			(type default)
		)
		(layer "In10.Cu")
	)
	(gr_line
		(start 413.630872 -258.703064)
		(end 414.323022 -260.748018)
		(stroke
			(width 0.1016)
			(type default)
		)
		(layer "In10.Cu")
	)
	(gr_line
		(start 414.2613 -249.249184)
		(end 413.568896 -247.20423)
		(stroke
			(width 0.1016)
			(type default)
		)
		(layer "In10.Cu")
	)
	(gr_line
		(start 414.366964 -258.45389)
		(end 413.630872 -258.703064)
		(stroke
			(width 0.1016)
			(type default)
		)
		(layer "In10.Cu")
	)
	(gr_circle
		(center 414.599882 -316.799722)
		(end 414.853882 -316.799722)
		(stroke
			(width 0.1016)
			(type default)
		)
		(fill no)
		(layer "In10.Cu")
	)
	(gr_circle
		(center 414.599882 -315.849762)
		(end 414.853882 -315.849762)
		(stroke
			(width 0.1016)
			(type default)
		)
		(fill no)
		(layer "In10.Cu")
	)
	(gr_circle
		(center 414.599882 -312.049922)
		(end 414.853882 -312.049922)
		(stroke
			(width 0.1016)
			(type default)
		)
		(fill no)
		(layer "In10.Cu")
	)
	(gr_circle
		(center 414.599882 -311.099962)
		(end 414.853882 -311.099962)
		(stroke
			(width 0.1016)
			(type default)
		)
		(fill no)
		(layer "In10.Cu")
	)
	(gr_line
		(start 414.71723 -247.098566)
		(end 415.40938 -249.14352)
		(stroke
			(width 0.1016)
			(type default)
		)
		(layer "In10.Cu")
	)
	(gr_line
		(start 415.059368 -260.498844)
		(end 414.366964 -258.45389)
		(stroke
			(width 0.1016)
			(type default)
		)
		(layer "In10.Cu")
	)
	(gr_line
		(start 415.33318 -257.804412)
		(end 416.02533 -259.849366)
		(stroke
			(width 0.1016)
			(type default)
		)
		(layer "In10.Cu")
	)
	(gr_line
		(start 415.453322 -246.849392)
		(end 414.71723 -247.098566)
		(stroke
			(width 0.1016)
			(type default)
		)
		(layer "In10.Cu")
	)
	(gr_circle
		(center 415.549842 -318.699896)
		(end 415.803842 -318.699896)
		(stroke
			(width 0.1016)
			(type default)
		)
		(fill no)
		(layer "In10.Cu")
	)
	(gr_circle
		(center 415.549842 -317.749936)
		(end 415.803842 -317.749936)
		(stroke
			(width 0.1016)
			(type default)
		)
		(fill no)
		(layer "In10.Cu")
	)
	(gr_circle
		(center 415.549842 -313.949842)
		(end 415.803842 -313.949842)
		(stroke
			(width 0.1016)
			(type default)
		)
		(fill no)
		(layer "In10.Cu")
	)
	(gr_circle
		(center 415.549842 -312.999882)
		(end 415.803842 -312.999882)
		(stroke
			(width 0.1016)
			(type default)
		)
		(fill no)
		(layer "In10.Cu")
	)
	(gr_line
		(start 416.069272 -257.555238)
		(end 415.33318 -257.804412)
		(stroke
			(width 0.1016)
			(type default)
		)
		(layer "In10.Cu")
	)
	(gr_line
		(start 416.145726 -248.894346)
		(end 415.453322 -246.849392)
		(stroke
			(width 0.1016)
			(type default)
		)
		(layer "In10.Cu")
	)
	(gr_circle
		(center 416.499802 -316.799722)
		(end 416.753802 -316.799722)
		(stroke
			(width 0.1016)
			(type default)
		)
		(fill no)
		(layer "In10.Cu")
	)
	(gr_circle
		(center 416.499802 -315.849762)
		(end 416.753802 -315.849762)
		(stroke
			(width 0.1016)
			(type default)
		)
		(fill no)
		(layer "In10.Cu")
	)
	(gr_circle
		(center 416.499802 -312.049922)
		(end 416.753802 -312.049922)
		(stroke
			(width 0.1016)
			(type default)
		)
		(fill no)
		(layer "In10.Cu")
	)
	(gr_circle
		(center 416.499802 -311.099962)
		(end 416.753802 -311.099962)
		(stroke
			(width 0.1016)
			(type default)
		)
		(fill no)
		(layer "In10.Cu")
	)
	(gr_line
		(start 416.761676 -259.600192)
		(end 416.069272 -257.555238)
		(stroke
			(width 0.1016)
			(type default)
		)
		(layer "In10.Cu")
	)
	(gr_line
		(start 417.247578 -257.53441)
		(end 417.939728 -259.579364)
		(stroke
			(width 0.1016)
			(type default)
		)
		(layer "In10.Cu")
	)
	(gr_circle
		(center 417.450016 -318.699896)
		(end 417.704016 -318.699896)
		(stroke
			(width 0.1016)
			(type default)
		)
		(fill no)
		(layer "In10.Cu")
	)
	(gr_circle
		(center 417.450016 -317.749936)
		(end 417.704016 -317.749936)
		(stroke
			(width 0.1016)
			(type default)
		)
		(fill no)
		(layer "In10.Cu")
	)
	(gr_circle
		(center 417.450016 -313.949842)
		(end 417.704016 -313.949842)
		(stroke
			(width 0.1016)
			(type default)
		)
		(fill no)
		(layer "In10.Cu")
	)
	(gr_circle
		(center 417.450016 -312.999882)
		(end 417.704016 -312.999882)
		(stroke
			(width 0.1016)
			(type default)
		)
		(fill no)
		(layer "In10.Cu")
	)
	(gr_line
		(start 417.98367 -257.285236)
		(end 417.247578 -257.53441)
		(stroke
			(width 0.1016)
			(type default)
		)
		(layer "In10.Cu")
	)
	(gr_circle
		(center 418.399976 -316.799722)
		(end 418.653976 -316.799722)
		(stroke
			(width 0.1016)
			(type default)
		)
		(fill no)
		(layer "In10.Cu")
	)
	(gr_circle
		(center 418.399976 -315.849762)
		(end 418.653976 -315.849762)
		(stroke
			(width 0.1016)
			(type default)
		)
		(fill no)
		(layer "In10.Cu")
	)
	(gr_circle
		(center 418.399976 -312.049922)
		(end 418.653976 -312.049922)
		(stroke
			(width 0.1016)
			(type default)
		)
		(fill no)
		(layer "In10.Cu")
	)
	(gr_circle
		(center 418.399976 -311.099962)
		(end 418.653976 -311.099962)
		(stroke
			(width 0.1016)
			(type default)
		)
		(fill no)
		(layer "In10.Cu")
	)
	(gr_line
		(start 418.676074 -259.33019)
		(end 417.98367 -257.285236)
		(stroke
			(width 0.1016)
			(type default)
		)
		(layer "In10.Cu")
	)
	(gr_line
		(start 419.13302 -257.179572)
		(end 419.82517 -259.224526)
		(stroke
			(width 0.1016)
			(type default)
		)
		(layer "In10.Cu")
	)
	(gr_circle
		(center 419.349936 -318.699896)
		(end 419.603936 -318.699896)
		(stroke
			(width 0.1016)
			(type default)
		)
		(fill no)
		(layer "In10.Cu")
	)
	(gr_circle
		(center 419.349936 -317.749936)
		(end 419.603936 -317.749936)
		(stroke
			(width 0.1016)
			(type default)
		)
		(fill no)
		(layer "In10.Cu")
	)
	(gr_circle
		(center 419.349936 -313.949842)
		(end 419.603936 -313.949842)
		(stroke
			(width 0.1016)
			(type default)
		)
		(fill no)
		(layer "In10.Cu")
	)
	(gr_circle
		(center 419.349936 -312.999882)
		(end 419.603936 -312.999882)
		(stroke
			(width 0.1016)
			(type default)
		)
		(fill no)
		(layer "In10.Cu")
	)
	(gr_line
		(start 419.869112 -256.930398)
		(end 419.13302 -257.179572)
		(stroke
			(width 0.1016)
			(type default)
		)
		(layer "In10.Cu")
	)
	(gr_circle
		(center 420.299896 -316.799722)
		(end 420.553896 -316.799722)
		(stroke
			(width 0.1016)
			(type default)
		)
		(fill no)
		(layer "In10.Cu")
	)
	(gr_circle
		(center 420.299896 -315.849762)
		(end 420.553896 -315.849762)
		(stroke
			(width 0.1016)
			(type default)
		)
		(fill no)
		(layer "In10.Cu")
	)
	(gr_circle
		(center 420.299896 -312.049922)
		(end 420.553896 -312.049922)
		(stroke
			(width 0.1016)
			(type default)
		)
		(fill no)
		(layer "In10.Cu")
	)
	(gr_circle
		(center 420.299896 -311.099962)
		(end 420.553896 -311.099962)
		(stroke
			(width 0.1016)
			(type default)
		)
		(fill no)
		(layer "In10.Cu")
	)
	(gr_line
		(start 420.368984 -230.902256)
		(end 420.708582 -233.034332)
		(stroke
			(width 0.1016)
			(type default)
		)
		(layer "In10.Cu")
	)
	(gr_line
		(start 420.561516 -258.975352)
		(end 419.869112 -256.930398)
		(stroke
			(width 0.1016)
			(type default)
		)
		(layer "In10.Cu")
	)
	(gr_line
		(start 421.136064 -230.779828)
		(end 420.368984 -230.902256)
		(stroke
			(width 0.1016)
			(type default)
		)
		(layer "In10.Cu")
	)
	(gr_circle
		(center 421.249856 -318.699896)
		(end 421.503856 -318.699896)
		(stroke
			(width 0.1016)
			(type default)
		)
		(fill no)
		(layer "In10.Cu")
	)
	(gr_circle
		(center 421.249856 -317.749936)
		(end 421.503856 -317.749936)
		(stroke
			(width 0.1016)
			(type default)
		)
		(fill no)
		(layer "In10.Cu")
	)
	(gr_circle
		(center 421.249856 -313.949842)
		(end 421.503856 -313.949842)
		(stroke
			(width 0.1016)
			(type default)
		)
		(fill no)
		(layer "In10.Cu")
	)
	(gr_circle
		(center 421.249856 -312.999882)
		(end 421.503856 -312.999882)
		(stroke
			(width 0.1016)
			(type default)
		)
		(fill no)
		(layer "In10.Cu")
	)
	(gr_line
		(start 421.476424 -232.912158)
		(end 421.136064 -230.779828)
		(stroke
			(width 0.1016)
			(type default)
		)
		(layer "In10.Cu")
	)
	(gr_line
		(start 421.843454 -246.090948)
		(end 422.183052 -248.223024)
		(stroke
			(width 0.1016)
			(type default)
		)
		(layer "In10.Cu")
	)
	(gr_line
		(start 422.242742 -230.828596)
		(end 422.58234 -232.960672)
		(stroke
			(width 0.1016)
			(type default)
		)
		(layer "In10.Cu")
	)
	(gr_line
		(start 422.610534 -245.96852)
		(end 421.843454 -246.090948)
		(stroke
			(width 0.1016)
			(type default)
		)
		(layer "In10.Cu")
	)
	(gr_line
		(start 422.950894 -248.10085)
		(end 422.610534 -245.96852)
		(stroke
			(width 0.1016)
			(type default)
		)
		(layer "In10.Cu")
	)
	(gr_line
		(start 423.009822 -230.706168)
		(end 422.242742 -230.828596)
		(stroke
			(width 0.1016)
			(type default)
		)
		(layer "In10.Cu")
	)
	(gr_line
		(start 423.350182 -232.838498)
		(end 423.009822 -230.706168)
		(stroke
			(width 0.1016)
			(type default)
		)
		(layer "In10.Cu")
	)
	(gr_line
		(start 423.719752 -246.017288)
		(end 424.05935 -248.149364)
		(stroke
			(width 0.1016)
			(type default)
		)
		(layer "In10.Cu")
	)
	(gr_line
		(start 424.136566 -230.838756)
		(end 424.476164 -232.970832)
		(stroke
			(width 0.1016)
			(type default)
		)
		(layer "In10.Cu")
	)
	(gr_line
		(start 424.486832 -245.89486)
		(end 423.719752 -246.017288)
		(stroke
			(width 0.1016)
			(type default)
		)
		(layer "In10.Cu")
	)
	(gr_line
		(start 424.827192 -248.02719)
		(end 424.486832 -245.89486)
		(stroke
			(width 0.1016)
			(type default)
		)
		(layer "In10.Cu")
	)
	(gr_line
		(start 424.903646 -230.716328)
		(end 424.136566 -230.838756)
		(stroke
			(width 0.1016)
			(type default)
		)
		(layer "In10.Cu")
	)
	(gr_line
		(start 425.244006 -232.848658)
		(end 424.903646 -230.716328)
		(stroke
			(width 0.1016)
			(type default)
		)
		(layer "In10.Cu")
	)
	(gr_line
		(start 426.953934 -260.17601)
		(end 426.953934 -262.33501)
		(stroke
			(width 0.1016)
			(type default)
		)
		(layer "In10.Cu")
	)
	(gr_line
		(start 427.598078 -246.597678)
		(end 427.937676 -248.729754)
		(stroke
			(width 0.1016)
			(type default)
		)
		(layer "In10.Cu")
	)
	(gr_line
		(start 427.730666 -260.175756)
		(end 426.953934 -260.17601)
		(stroke
			(width 0.1016)
			(type default)
		)
		(layer "In10.Cu")
	)
	(gr_line
		(start 427.731174 -262.33501)
		(end 427.730666 -260.175756)
		(stroke
			(width 0.1016)
			(type default)
		)
		(layer "In10.Cu")
	)
	(gr_line
		(start 427.94936 -230.969058)
		(end 428.288958 -233.101134)
		(stroke
			(width 0.1016)
			(type default)
		)
		(layer "In10.Cu")
	)
	(gr_line
		(start 428.365158 -246.47525)
		(end 427.598078 -246.597678)
		(stroke
			(width 0.1016)
			(type default)
		)
		(layer "In10.Cu")
	)
	(gr_line
		(start 428.705518 -248.60758)
		(end 428.365158 -246.47525)
		(stroke
			(width 0.1016)
			(type default)
		)
		(layer "In10.Cu")
	)
	(gr_line
		(start 428.71644 -230.84663)
		(end 427.94936 -230.969058)
		(stroke
			(width 0.1016)
			(type default)
		)
		(layer "In10.Cu")
	)
	(gr_line
		(start 429.0568 -232.97896)
		(end 428.71644 -230.84663)
		(stroke
			(width 0.1016)
			(type default)
		)
		(layer "In10.Cu")
	)
	(gr_line
		(start 429.411384 -246.11457)
		(end 429.750982 -248.246646)
		(stroke
			(width 0.1016)
			(type default)
		)
		(layer "In10.Cu")
	)
	(gr_line
		(start 429.800512 -260.491224)
		(end 429.800512 -262.650224)
		(stroke
			(width 0.1016)
			(type default)
		)
		(layer "In10.Cu")
	)
	(gr_line
		(start 429.83404 -230.750872)
		(end 430.173638 -232.882948)
		(stroke
			(width 0.1016)
			(type default)
		)
		(layer "In10.Cu")
	)
	(gr_line
		(start 430.178464 -245.992142)
		(end 429.411384 -246.11457)
		(stroke
			(width 0.1016)
			(type default)
		)
		(layer "In10.Cu")
	)
	(gr_line
		(start 430.518824 -248.124472)
		(end 430.178464 -245.992142)
		(stroke
			(width 0.1016)
			(type default)
		)
		(layer "In10.Cu")
	)
	(gr_line
		(start 430.577244 -260.49097)
		(end 429.800512 -260.491224)
		(stroke
			(width 0.1016)
			(type default)
		)
		(layer "In10.Cu")
	)
	(gr_line
		(start 430.577752 -262.650224)
		(end 430.577244 -260.49097)
		(stroke
			(width 0.1016)
			(type default)
		)
		(layer "In10.Cu")
	)
	(gr_line
		(start 430.60112 -230.628444)
		(end 429.83404 -230.750872)
		(stroke
			(width 0.1016)
			(type default)
		)
		(layer "In10.Cu")
	)
	(gr_line
		(start 430.670716 -242.091464)
		(end 431.010314 -244.22354)
		(stroke
			(width 0.1016)
			(type default)
		)
		(layer "In10.Cu")
	)
	(gr_line
		(start 430.94148 -232.760774)
		(end 430.60112 -230.628444)
		(stroke
			(width 0.1016)
			(type default)
		)
		(layer "In10.Cu")
	)
	(gr_line
		(start 431.437796 -241.969036)
		(end 430.670716 -242.091464)
		(stroke
			(width 0.1016)
			(type default)
		)
		(layer "In10.Cu")
	)
	(gr_line
		(start 431.732182 -230.563674)
		(end 432.07178 -232.69575)
		(stroke
			(width 0.1016)
			(type default)
		)
		(layer "In10.Cu")
	)
	(gr_line
		(start 431.778156 -244.101366)
		(end 431.437796 -241.969036)
		(stroke
			(width 0.1016)
			(type default)
		)
		(layer "In10.Cu")
	)
	(gr_line
		(start 432.499262 -230.441246)
		(end 431.732182 -230.563674)
		(stroke
			(width 0.1016)
			(type default)
		)
		(layer "In10.Cu")
	)
	(gr_line
		(start 432.603656 -242.091464)
		(end 432.943254 -244.22354)
		(stroke
			(width 0.1016)
			(type default)
		)
		(layer "In10.Cu")
	)
	(gr_line
		(start 432.839622 -232.573576)
		(end 432.499262 -230.441246)
		(stroke
			(width 0.1016)
			(type default)
		)
		(layer "In10.Cu")
	)
	(gr_line
		(start 433.370736 -241.969036)
		(end 432.603656 -242.091464)
		(stroke
			(width 0.1016)
			(type default)
		)
		(layer "In10.Cu")
	)
	(gr_line
		(start 433.636166 -230.313992)
		(end 433.975764 -232.446068)
		(stroke
			(width 0.1016)
			(type default)
		)
		(layer "In10.Cu")
	)
	(gr_line
		(start 433.711096 -244.101366)
		(end 433.370736 -241.969036)
		(stroke
			(width 0.1016)
			(type default)
		)
		(layer "In10.Cu")
	)
	(gr_line
		(start 434.403246 -230.191564)
		(end 433.636166 -230.313992)
		(stroke
			(width 0.1016)
			(type default)
		)
		(layer "In10.Cu")
	)
	(gr_line
		(start 434.48859 -241.730784)
		(end 434.828188 -243.86286)
		(stroke
			(width 0.1016)
			(type default)
		)
		(layer "In10.Cu")
	)
	(gr_line
		(start 434.743606 -232.323894)
		(end 434.403246 -230.191564)
		(stroke
			(width 0.1016)
			(type default)
		)
		(layer "In10.Cu")
	)
	(gr_line
		(start 435.25567 -241.608356)
		(end 434.48859 -241.730784)
		(stroke
			(width 0.1016)
			(type default)
		)
		(layer "In10.Cu")
	)
	(gr_line
		(start 435.59603 -243.740686)
		(end 435.25567 -241.608356)
		(stroke
			(width 0.1016)
			(type default)
		)
		(layer "In10.Cu")
	)
	(gr_poly
		(pts
			(arc
				(start 64.102996 -209.328512)
				(mid 63.81242 -209.328512)
				(end 64.102996 -209.328512)
			)
		)
		(stroke
			(width 0)
			(type solid)
		)
		(fill yes)
		(layer "In11.Cu")
		(net "GND")
	)
	(gr_poly
		(pts
			(arc
				(start 93.68663 -235.7374)
				(mid 93.396054 -235.7374)
				(end 93.68663 -235.7374)
			)
		)
		(stroke
			(width 0)
			(type solid)
		)
		(fill yes)
		(layer "In11.Cu")
		(net "GND")
	)
	(gr_poly
		(pts
			(arc
				(start 93.742002 -207.033368)
				(mid 93.451426 -207.033368)
				(end 93.742002 -207.033368)
			)
		)
		(stroke
			(width 0)
			(type solid)
		)
		(fill yes)
		(layer "In11.Cu")
		(net "GND")
	)
	(gr_poly
		(pts
			(arc
				(start 94.486984 -238.04499)
				(mid 94.196408 -238.04499)
				(end 94.486984 -238.04499)
			)
		)
		(stroke
			(width 0)
			(type solid)
		)
		(fill yes)
		(layer "In11.Cu")
		(net "GND")
	)
	(gr_poly
		(pts
			(arc
				(start 95.405448 -236.971586)
				(mid 95.114872 -236.971586)
				(end 95.405448 -236.971586)
			)
		)
		(stroke
			(width 0)
			(type solid)
		)
		(fill yes)
		(layer "In11.Cu")
		(net "GND")
	)
	(gr_poly
		(pts
			(arc
				(start 95.908368 -198.76389)
				(mid 95.617792 -198.76389)
				(end 95.908368 -198.76389)
			)
		)
		(stroke
			(width 0)
			(type solid)
		)
		(fill yes)
		(layer "In11.Cu")
		(net "GND")
	)
	(gr_poly
		(pts
			(arc
				(start 109.164628 -199.347582)
				(mid 108.874052 -199.347582)
				(end 109.164628 -199.347582)
			)
		)
		(stroke
			(width 0)
			(type solid)
		)
		(fill yes)
		(layer "In11.Cu")
		(net "GND")
	)
	(gr_poly
		(pts
			(arc
				(start 123.167902 -179.192936)
				(mid 122.877326 -179.192936)
				(end 123.167902 -179.192936)
			)
		)
		(stroke
			(width 0)
			(type solid)
		)
		(fill yes)
		(layer "In11.Cu")
		(net "GND")
	)
	(gr_poly
		(pts
			(arc
				(start 123.167902 -177.934112)
				(mid 122.877326 -177.934112)
				(end 123.167902 -177.934112)
			)
		)
		(stroke
			(width 0)
			(type solid)
		)
		(fill yes)
		(layer "In11.Cu")
		(net "GND")
	)
	(gr_poly
		(pts
			(arc
				(start 127.327406 -195.062094)
				(mid 127.03683 -195.062094)
				(end 127.327406 -195.062094)
			)
		)
		(stroke
			(width 0)
			(type solid)
		)
		(fill yes)
		(layer "In11.Cu")
		(net "GND")
	)
	(gr_poly
		(pts
			(arc
				(start 128.58623 -195.062094)
				(mid 128.295654 -195.062094)
				(end 128.58623 -195.062094)
			)
		)
		(stroke
			(width 0)
			(type solid)
		)
		(fill yes)
		(layer "In11.Cu")
		(net "GND")
	)
	(gr_poly
		(pts
			(arc
				(start 129.061972 -187.588906)
				(mid 128.771396 -187.588906)
				(end 129.061972 -187.588906)
			)
		)
		(stroke
			(width 0)
			(type solid)
		)
		(fill yes)
		(layer "In11.Cu")
		(net "GND")
	)
	(gr_poly
		(pts
			(arc
				(start 129.550922 -249.328432)
				(mid 129.260346 -249.328432)
				(end 129.550922 -249.328432)
			)
		)
		(stroke
			(width 0)
			(type solid)
		)
		(fill yes)
		(layer "In11.Cu")
		(net "GND")
	)
	(gr_poly
		(pts
			(arc
				(start 130.320796 -187.588906)
				(mid 130.03022 -187.588906)
				(end 130.320796 -187.588906)
			)
		)
		(stroke
			(width 0)
			(type solid)
		)
		(fill yes)
		(layer "In11.Cu")
		(net "GND")
	)
	(gr_poly
		(pts
			(arc
				(start 131.45135 -187.59805)
				(mid 131.160774 -187.59805)
				(end 131.45135 -187.59805)
			)
		)
		(stroke
			(width 0)
			(type solid)
		)
		(fill yes)
		(layer "In11.Cu")
		(net "GND")
	)
	(gr_poly
		(pts
			(arc
				(start 132.710174 -187.59805)
				(mid 132.419598 -187.59805)
				(end 132.710174 -187.59805)
			)
		)
		(stroke
			(width 0)
			(type solid)
		)
		(fill yes)
		(layer "In11.Cu")
		(net "GND")
	)
	(gr_poly
		(pts
			(arc
				(start 133.361938 -241.88166)
				(mid 133.071362 -241.88166)
				(end 133.361938 -241.88166)
			)
		)
		(stroke
			(width 0)
			(type solid)
		)
		(fill yes)
		(layer "In11.Cu")
		(net "GND")
	)
	(gr_poly
		(pts
			(arc
				(start 133.480302 -167.992298)
				(mid 133.189726 -167.992298)
				(end 133.480302 -167.992298)
			)
		)
		(stroke
			(width 0)
			(type solid)
		)
		(fill yes)
		(layer "In11.Cu")
		(net "GND")
	)
	(gr_poly
		(pts
			(arc
				(start 133.954266 -187.730638)
				(mid 133.66369 -187.730638)
				(end 133.954266 -187.730638)
			)
		)
		(stroke
			(width 0)
			(type solid)
		)
		(fill yes)
		(layer "In11.Cu")
		(net "GND")
	)
	(gr_poly
		(pts
			(arc
				(start 134.967472 -167.992298)
				(mid 134.676896 -167.992298)
				(end 134.967472 -167.992298)
			)
		)
		(stroke
			(width 0)
			(type solid)
		)
		(fill yes)
		(layer "In11.Cu")
		(net "GND")
	)
	(gr_poly
		(pts
			(arc
				(start 135.21309 -187.730638)
				(mid 134.922514 -187.730638)
				(end 135.21309 -187.730638)
			)
		)
		(stroke
			(width 0)
			(type solid)
		)
		(fill yes)
		(layer "In11.Cu")
		(net "GND")
	)
	(gr_poly
		(pts
			(arc
				(start 135.650732 -168.669208)
				(mid 135.360156 -168.669208)
				(end 135.650732 -168.669208)
			)
		)
		(stroke
			(width 0)
			(type solid)
		)
		(fill yes)
		(layer "In11.Cu")
		(net "GND")
	)
	(gr_poly
		(pts
			(arc
				(start 135.986266 -186.460638)
				(mid 135.69569 -186.460638)
				(end 135.986266 -186.460638)
			)
		)
		(stroke
			(width 0)
			(type solid)
		)
		(fill yes)
		(layer "In11.Cu")
		(net "GND")
	)
	(gr_poly
		(pts
			(arc
				(start 136.909556 -168.669208)
				(mid 136.61898 -168.669208)
				(end 136.909556 -168.669208)
			)
		)
		(stroke
			(width 0)
			(type solid)
		)
		(fill yes)
		(layer "In11.Cu")
		(net "GND")
	)
	(gr_poly
		(pts
			(arc
				(start 137.24509 -186.460638)
				(mid 136.954514 -186.460638)
				(end 137.24509 -186.460638)
			)
		)
		(stroke
			(width 0)
			(type solid)
		)
		(fill yes)
		(layer "In11.Cu")
		(net "GND")
	)
	(gr_poly
		(pts
			(arc
				(start 141.515084 -183.130698)
				(mid 141.224508 -183.130698)
				(end 141.515084 -183.130698)
			)
		)
		(stroke
			(width 0)
			(type solid)
		)
		(fill yes)
		(layer "In11.Cu")
		(net "GND")
	)
	(gr_poly
		(pts
			(arc
				(start 141.515084 -181.871874)
				(mid 141.224508 -181.871874)
				(end 141.515084 -181.871874)
			)
		)
		(stroke
			(width 0)
			(type solid)
		)
		(fill yes)
		(layer "In11.Cu")
		(net "GND")
	)
	(gr_poly
		(pts
			(arc
				(start 141.515084 -179.066698)
				(mid 141.224508 -179.066698)
				(end 141.515084 -179.066698)
			)
		)
		(stroke
			(width 0)
			(type solid)
		)
		(fill yes)
		(layer "In11.Cu")
		(net "GND")
	)
	(gr_poly
		(pts
			(arc
				(start 141.515084 -177.807874)
				(mid 141.224508 -177.807874)
				(end 141.515084 -177.807874)
			)
		)
		(stroke
			(width 0)
			(type solid)
		)
		(fill yes)
		(layer "In11.Cu")
		(net "GND")
	)
	(gr_poly
		(pts
			(arc
				(start 141.515084 -175.002698)
				(mid 141.224508 -175.002698)
				(end 141.515084 -175.002698)
			)
		)
		(stroke
			(width 0)
			(type solid)
		)
		(fill yes)
		(layer "In11.Cu")
		(net "GND")
	)
	(gr_poly
		(pts
			(arc
				(start 141.515084 -173.743874)
				(mid 141.224508 -173.743874)
				(end 141.515084 -173.743874)
			)
		)
		(stroke
			(width 0)
			(type solid)
		)
		(fill yes)
		(layer "In11.Cu")
		(net "GND")
	)
	(gr_poly
		(pts
			(arc
				(start 142.150084 -181.098698)
				(mid 141.859508 -181.098698)
				(end 142.150084 -181.098698)
			)
		)
		(stroke
			(width 0)
			(type solid)
		)
		(fill yes)
		(layer "In11.Cu")
		(net "GND")
	)
	(gr_poly
		(pts
			(arc
				(start 142.150084 -179.839874)
				(mid 141.859508 -179.839874)
				(end 142.150084 -179.839874)
			)
		)
		(stroke
			(width 0)
			(type solid)
		)
		(fill yes)
		(layer "In11.Cu")
		(net "GND")
	)
	(gr_poly
		(pts
			(arc
				(start 142.150084 -177.034698)
				(mid 141.859508 -177.034698)
				(end 142.150084 -177.034698)
			)
		)
		(stroke
			(width 0)
			(type solid)
		)
		(fill yes)
		(layer "In11.Cu")
		(net "GND")
	)
	(gr_poly
		(pts
			(arc
				(start 142.150084 -175.775874)
				(mid 141.859508 -175.775874)
				(end 142.150084 -175.775874)
			)
		)
		(stroke
			(width 0)
			(type solid)
		)
		(fill yes)
		(layer "In11.Cu")
		(net "GND")
	)
	(gr_poly
		(pts
			(arc
				(start 146.766534 -245.22303)
				(mid 146.475958 -245.22303)
				(end 146.766534 -245.22303)
			)
		)
		(stroke
			(width 0)
			(type solid)
		)
		(fill yes)
		(layer "In11.Cu")
		(net "GND")
	)
	(gr_poly
		(pts
			(arc
				(start 154.105356 -245.27891)
				(mid 153.81478 -245.27891)
				(end 154.105356 -245.27891)
			)
		)
		(stroke
			(width 0)
			(type solid)
		)
		(fill yes)
		(layer "In11.Cu")
		(net "GND")
	)
	(gr_poly
		(pts
			(arc
				(start 184.37606 -226.149916)
				(mid 184.085484 -226.149916)
				(end 184.37606 -226.149916)
			)
		)
		(stroke
			(width 0)
			(type solid)
		)
		(fill yes)
		(layer "In11.Cu")
		(net "GND")
	)
	(gr_poly
		(pts
			(arc
				(start 206.791052 -189.023498)
				(mid 206.500476 -189.023498)
				(end 206.791052 -189.023498)
			)
		)
		(stroke
			(width 0)
			(type solid)
		)
		(fill yes)
		(layer "In11.Cu")
		(net "GND")
	)
	(gr_poly
		(pts
			(arc
				(start 207.280256 -186.160918)
				(mid 206.98968 -186.160918)
				(end 207.280256 -186.160918)
			)
		)
		(stroke
			(width 0)
			(type solid)
		)
		(fill yes)
		(layer "In11.Cu")
		(net "GND")
	)
	(gr_poly
		(pts
			(arc
				(start 207.790288 -193.04)
				(mid 207.499712 -193.04)
				(end 207.790288 -193.04)
			)
		)
		(stroke
			(width 0)
			(type solid)
		)
		(fill yes)
		(layer "In11.Cu")
		(net "GND")
	)
	(gr_poly
		(pts
			(arc
				(start 208.397348 -187.178696)
				(mid 208.106772 -187.178696)
				(end 208.397348 -187.178696)
			)
		)
		(stroke
			(width 0)
			(type solid)
		)
		(fill yes)
		(layer "In11.Cu")
		(net "GND")
	)
	(gr_poly
		(pts
			(arc
				(start 208.535016 -203.334366)
				(mid 208.24444 -203.334366)
				(end 208.535016 -203.334366)
			)
		)
		(stroke
			(width 0)
			(type solid)
		)
		(fill yes)
		(layer "In11.Cu")
		(net "GND")
	)
	(gr_poly
		(pts
			(arc
				(start 208.552288 -201.168)
				(mid 208.261712 -201.168)
				(end 208.552288 -201.168)
			)
		)
		(stroke
			(width 0)
			(type solid)
		)
		(fill yes)
		(layer "In11.Cu")
		(net "GND")
	)
	(gr_poly
		(pts
			(arc
				(start 208.552288 -197.485)
				(mid 208.261712 -197.485)
				(end 208.552288 -197.485)
			)
		)
		(stroke
			(width 0)
			(type solid)
		)
		(fill yes)
		(layer "In11.Cu")
		(net "GND")
	)
	(gr_poly
		(pts
			(arc
				(start 208.564226 -198.199756)
				(mid 208.27365 -198.199756)
				(end 208.564226 -198.199756)
			)
		)
		(stroke
			(width 0)
			(type solid)
		)
		(fill yes)
		(layer "In11.Cu")
		(net "GND")
	)
	(gr_poly
		(pts
			(arc
				(start 209.387948 -181.19725)
				(mid 209.097372 -181.19725)
				(end 209.387948 -181.19725)
			)
		)
		(stroke
			(width 0)
			(type solid)
		)
		(fill yes)
		(layer "In11.Cu")
		(net "GND")
	)
	(gr_poly
		(pts
			(arc
				(start 209.40141 -185.955686)
				(mid 209.110834 -185.955686)
				(end 209.40141 -185.955686)
			)
		)
		(stroke
			(width 0)
			(type solid)
		)
		(fill yes)
		(layer "In11.Cu")
		(net "GND")
	)
	(gr_poly
		(pts
			(arc
				(start 211.04606 -171.237656)
				(mid 210.755484 -171.237656)
				(end 211.04606 -171.237656)
			)
		)
		(stroke
			(width 0)
			(type solid)
		)
		(fill yes)
		(layer "In11.Cu")
		(net "GND")
	)
	(gr_poly
		(pts
			(arc
				(start 212.295232 -135.426196)
				(mid 212.004656 -135.426196)
				(end 212.295232 -135.426196)
			)
		)
		(stroke
			(width 0)
			(type solid)
		)
		(fill yes)
		(layer "In11.Cu")
		(net "GND")
	)
	(gr_poly
		(pts
			(arc
				(start 212.61705 -169.63263)
				(mid 212.326474 -169.63263)
				(end 212.61705 -169.63263)
			)
		)
		(stroke
			(width 0)
			(type solid)
		)
		(fill yes)
		(layer "In11.Cu")
		(net "GND")
	)
	(gr_poly
		(pts
			(arc
				(start 214.453724 -256.229612)
				(mid 214.163148 -256.229612)
				(end 214.453724 -256.229612)
			)
		)
		(stroke
			(width 0)
			(type solid)
		)
		(fill yes)
		(layer "In11.Cu")
		(net "GND")
	)
	(gr_poly
		(pts
			(arc
				(start 214.960454 -167.960802)
				(mid 214.669878 -167.960802)
				(end 214.960454 -167.960802)
			)
		)
		(stroke
			(width 0)
			(type solid)
		)
		(fill yes)
		(layer "In11.Cu")
		(net "GND")
	)
	(gr_poly
		(pts
			(arc
				(start 215.669368 -258.28117)
				(mid 215.378792 -258.28117)
				(end 215.669368 -258.28117)
			)
		)
		(stroke
			(width 0)
			(type solid)
		)
		(fill yes)
		(layer "In11.Cu")
		(net "GND")
	)
	(gr_poly
		(pts
			(arc
				(start 216.616026 -256.420366)
				(mid 216.32545 -256.420366)
				(end 216.616026 -256.420366)
			)
		)
		(stroke
			(width 0)
			(type solid)
		)
		(fill yes)
		(layer "In11.Cu")
		(net "GND")
	)
	(gr_poly
		(pts
			(arc
				(start 217.606118 -172.183298)
				(mid 217.315542 -172.183298)
				(end 217.606118 -172.183298)
			)
		)
		(stroke
			(width 0)
			(type solid)
		)
		(fill yes)
		(layer "In11.Cu")
		(net "GND")
	)
	(gr_poly
		(pts
			(arc
				(start 220.95079 -174.875444)
				(mid 220.660214 -174.875444)
				(end 220.95079 -174.875444)
			)
		)
		(stroke
			(width 0)
			(type solid)
		)
		(fill yes)
		(layer "In11.Cu")
		(net "GND")
	)
	(gr_poly
		(pts
			(arc
				(start 221.160086 -170.043094)
				(mid 220.86951 -170.043094)
				(end 221.160086 -170.043094)
			)
		)
		(stroke
			(width 0)
			(type solid)
		)
		(fill yes)
		(layer "In11.Cu")
		(net "GND")
	)
	(gr_poly
		(pts
			(arc
				(start 224.399602 -136.174988)
				(mid 224.109026 -136.174988)
				(end 224.399602 -136.174988)
			)
		)
		(stroke
			(width 0)
			(type solid)
		)
		(fill yes)
		(layer "In11.Cu")
		(net "GND")
	)
	(gr_poly
		(pts
			(arc
				(start 229.369874 -134.81177)
				(mid 229.079298 -134.81177)
				(end 229.369874 -134.81177)
			)
		)
		(stroke
			(width 0)
			(type solid)
		)
		(fill yes)
		(layer "In11.Cu")
		(net "GND")
	)
	(gr_poly
		(pts
			(arc
				(start 230.027988 -182.948072)
				(mid 229.737412 -182.948072)
				(end 230.027988 -182.948072)
			)
		)
		(stroke
			(width 0)
			(type solid)
		)
		(fill yes)
		(layer "In11.Cu")
		(net "GND")
	)
	(gr_poly
		(pts
			(arc
				(start 230.09479 -180.151786)
				(mid 229.804214 -180.151786)
				(end 230.09479 -180.151786)
			)
		)
		(stroke
			(width 0)
			(type solid)
		)
		(fill yes)
		(layer "In11.Cu")
		(net "GND")
	)
	(gr_poly
		(pts
			(arc
				(start 236.681264 -182.999634)
				(mid 236.390688 -182.999634)
				(end 236.681264 -182.999634)
			)
		)
		(stroke
			(width 0)
			(type solid)
		)
		(fill yes)
		(layer "In11.Cu")
		(net "GND")
	)
	(gr_poly
		(pts
			(arc
				(start 246.815864 -230.878888)
				(mid 246.525288 -230.878888)
				(end 246.815864 -230.878888)
			)
		)
		(stroke
			(width 0)
			(type solid)
		)
		(fill yes)
		(layer "In11.Cu")
		(net "GND")
	)
	(gr_poly
		(pts
			(arc
				(start 260.478016 -182.335424)
				(mid 260.18744 -182.335424)
				(end 260.478016 -182.335424)
			)
		)
		(stroke
			(width 0)
			(type solid)
		)
		(fill yes)
		(layer "In11.Cu")
		(net "GND")
	)
	(gr_poly
		(pts
			(arc
				(start 260.524752 -177.376328)
				(mid 260.234176 -177.376328)
				(end 260.524752 -177.376328)
			)
		)
		(stroke
			(width 0)
			(type solid)
		)
		(fill yes)
		(layer "In11.Cu")
		(net "GND")
	)
	(gr_poly
		(pts
			(arc
				(start 260.835648 -233.111294)
				(mid 260.545072 -233.111294)
				(end 260.835648 -233.111294)
			)
		)
		(stroke
			(width 0)
			(type solid)
		)
		(fill yes)
		(layer "In11.Cu")
		(net "GND")
	)
	(gr_poly
		(pts
			(arc
				(start 297.138852 -203.402946)
				(mid 296.848276 -203.402946)
				(end 297.138852 -203.402946)
			)
		)
		(stroke
			(width 0)
			(type solid)
		)
		(fill yes)
		(layer "In11.Cu")
		(net "GND")
	)
	(gr_poly
		(pts
			(arc
				(start 350.94926 -161.044382)
				(mid 350.658684 -161.044382)
				(end 350.94926 -161.044382)
			)
		)
		(stroke
			(width 0)
			(type solid)
		)
		(fill yes)
		(layer "In11.Cu")
		(net "GND")
	)
	(gr_poly
		(pts
			(arc
				(start 221.811088 -366.373918)
				(mid 221.830611 -366.370017)
				(end 221.847156 -366.358932)
			)
			(arc
				(start 221.990666 -366.215422)
				(mid 222.001777 -366.198888)
				(end 222.005652 -366.179354)
			)
			(arc
				(start 222.005652 -362.216954)
				(mid 222.001751 -362.197431)
				(end 221.990666 -362.180886)
			)
			(arc
				(start 221.862904 -362.053124)
				(mid 221.84637 -362.042013)
				(end 221.826836 -362.038138)
			)
			(arc
				(start 217.80119 -362.038138)
				(mid 217.781667 -362.042039)
				(end 217.765122 -362.053124)
			)
			(arc
				(start 217.676984 -362.141262)
				(mid 217.665873 -362.157796)
				(end 217.661998 -362.17733)
			)
			(arc
				(start 217.661998 -366.195102)
				(mid 217.665899 -366.214625)
				(end 217.676984 -366.23117)
			)
			(arc
				(start 217.804746 -366.358932)
				(mid 217.82128 -366.370043)
				(end 217.840814 -366.373918)
			)
		)
		(stroke
			(width 0)
			(type solid)
		)
		(fill yes)
		(layer "In11.Cu")
		(net "P12V_AUX")
	)
	(gr_poly
		(pts
			(arc
				(start 241.82197 -376.463306)
				(mid 241.841493 -376.459405)
				(end 241.858038 -376.44832)
			)
			(arc
				(start 242.310666 -375.995692)
				(mid 242.321777 -375.979158)
				(end 242.325652 -375.959624)
			)
			(arc
				(start 242.325652 -368.584988)
				(mid 242.321751 -368.565465)
				(end 242.310666 -368.54892)
			)
			(arc
				(start 242.213638 -368.451892)
				(mid 242.197104 -368.440781)
				(end 242.17757 -368.436906)
			)
			(arc
				(start 236.28731 -368.436906)
				(mid 236.267787 -368.440807)
				(end 236.251242 -368.451892)
			)
			(arc
				(start 236.083856 -368.619278)
				(mid 236.072745 -368.635812)
				(end 236.06887 -368.655346)
			)
			(arc
				(start 236.06887 -376.112532)
				(mid 236.072771 -376.132055)
				(end 236.083856 -376.1486)
			)
			(arc
				(start 236.383576 -376.44832)
				(mid 236.40011 -376.459431)
				(end 236.419644 -376.463306)
			)
		)
		(stroke
			(width 0)
			(type solid)
		)
		(fill yes)
		(layer "In11.Cu")
		(net "P12V_STBY_R1")
	)
	(gr_poly
		(pts
			(arc
				(start 252.431042 -397.963136)
				(mid 252.450565 -397.959235)
				(end 252.46711 -397.94815)
			)
			(arc
				(start 252.932438 -397.482822)
				(mid 252.943549 -397.466288)
				(end 252.947424 -397.446754)
			)
			(arc
				(start 252.947424 -392.961114)
				(mid 252.943523 -392.941591)
				(end 252.932438 -392.925046)
			)
			(arc
				(start 252.451362 -392.44397)
				(mid 252.434828 -392.432859)
				(end 252.415294 -392.428984)
			)
			(arc
				(start 245.184422 -392.428984)
				(mid 245.164899 -392.432885)
				(end 245.148354 -392.44397)
			)
			(arc
				(start 244.746526 -392.845798)
				(mid 244.735415 -392.862332)
				(end 244.73154 -392.881866)
			)
			(arc
				(start 244.73154 -397.594328)
				(mid 244.735441 -397.613851)
				(end 244.746526 -397.630396)
			)
			(arc
				(start 245.06428 -397.94815)
				(mid 245.080814 -397.959261)
				(end 245.100348 -397.963136)
			)
		)
		(stroke
			(width 0)
			(type solid)
		)
		(fill yes)
		(layer "In11.Cu")
		(net "P12V_STBY_FUSE")
	)
	(gr_poly
		(pts
			(arc
				(start 208.882742 -366.397794)
				(mid 208.902265 -366.393893)
				(end 208.91881 -366.382808)
			)
			(arc
				(start 209.038698 -366.26292)
				(mid 209.049809 -366.246386)
				(end 209.053684 -366.226852)
			)
			(arc
				(start 209.053684 -365.023654)
				(mid 209.057585 -365.004131)
				(end 209.06867 -364.987586)
			)
			(arc
				(start 209.157062 -364.899194)
				(mid 209.173596 -364.888083)
				(end 209.19313 -364.884208)
			)
			(arc
				(start 210.447382 -364.884208)
				(mid 210.466905 -364.880307)
				(end 210.48345 -364.869222)
			)
			(arc
				(start 211.30895 -364.043722)
				(mid 211.320061 -364.027188)
				(end 211.323936 -364.007654)
			)
			(arc
				(start 211.323936 -363.150912)
				(mid 211.320035 -363.131389)
				(end 211.30895 -363.114844)
			)
			(arc
				(start 210.499452 -362.305346)
				(mid 210.482918 -362.294235)
				(end 210.463384 -362.29036)
			)
			(arc
				(start 208.570322 -362.29036)
				(mid 208.550799 -362.294261)
				(end 208.534254 -362.305346)
			)
			(arc
				(start 207.172814 -363.666786)
				(mid 207.15628 -363.677897)
				(end 207.136746 -363.681772)
			)
			(arc
				(start 205.665578 -363.681772)
				(mid 205.646055 -363.685673)
				(end 205.62951 -363.696758)
			)
			(arc
				(start 205.48219 -363.844078)
				(mid 205.471079 -363.860612)
				(end 205.467204 -363.880146)
			)
			(arc
				(start 205.467204 -366.230662)
				(mid 205.471105 -366.250185)
				(end 205.48219 -366.26673)
			)
			(arc
				(start 205.598268 -366.382808)
				(mid 205.614802 -366.393919)
				(end 205.634336 -366.397794)
			)
		)
		(stroke
			(width 0)
			(type solid)
		)
		(fill yes)
		(layer "In11.Cu")
		(net "P12V_AUX")
	)
	(gr_poly
		(pts
			(arc
				(start 263.911842 -377.74626)
				(mid 263.94545 -377.733554)
				(end 263.962388 -377.70181)
			)
			(arc
				(start 263.962388 -377.70181)
				(mid 264.830834 -374.954473)
				(end 266.61618 -372.69293)
			)
			(arc
				(start 266.61618 -372.69293)
				(mid 266.62895 -372.67562)
				(end 266.633452 -372.654576)
			)
			(arc
				(start 266.633452 -368.922046)
				(mid 266.629551 -368.902523)
				(end 266.618466 -368.885978)
			)
			(arc
				(start 266.291568 -368.55908)
				(mid 266.275034 -368.547969)
				(end 266.2555 -368.544094)
			)
			(xy 243.539264 -368.544094) (xy 243.533676 -368.538506)
			(arc
				(start 242.778534 -368.538506)
				(mid 242.759011 -368.542407)
				(end 242.742466 -368.553492)
			)
			(arc
				(start 242.620038 -368.67592)
				(mid 242.608927 -368.692454)
				(end 242.605052 -368.711988)
			)
			(arc
				(start 242.605052 -377.229624)
				(mid 242.608953 -377.249147)
				(end 242.620038 -377.265692)
			)
			(arc
				(start 243.08562 -377.731274)
				(mid 243.102154 -377.742385)
				(end 243.121688 -377.74626)
			)
		)
		(stroke
			(width 0)
			(type solid)
		)
		(fill yes)
		(layer "In11.Cu")
		(net "P12V_STBY_R2")
	)
	(gr_poly
		(pts
			(arc
				(start 266.737846 -366.389666)
				(mid 266.757369 -366.385765)
				(end 266.773914 -366.37468)
			)
			(arc
				(start 267.181838 -365.966756)
				(mid 267.192949 -365.950222)
				(end 267.196824 -365.930688)
			)
			(arc
				(start 267.196824 -360.117898)
				(mid 267.192923 -360.098375)
				(end 267.181838 -360.08183)
			)
			(arc
				(start 264.009632 -356.909624)
				(mid 263.993098 -356.898513)
				(end 263.973564 -356.894638)
			)
			(arc
				(start 253.270258 -356.894638)
				(mid 253.250735 -356.898539)
				(end 253.23419 -356.909624)
			)
			(arc
				(start 250.382786 -359.761028)
				(mid 250.366252 -359.772139)
				(end 250.346718 -359.776014)
			)
			(arc
				(start 246.79783 -359.776014)
				(mid 246.778307 -359.779915)
				(end 246.761762 -359.791)
			)
			(arc
				(start 245.756938 -360.795824)
				(mid 245.740404 -360.806935)
				(end 245.72087 -360.81081)
			)
			(xy 237.667292 -360.81081) (xy 237.667546 -360.811064)
			(arc
				(start 237.559596 -360.811064)
				(mid 237.540073 -360.814965)
				(end 237.523528 -360.82605)
			)
			(arc
				(start 236.372654 -361.976924)
				(mid 236.35612 -361.988035)
				(end 236.336586 -361.99191)
			)
			(xy 232.506774 -361.99191) (xy 232.505758 -361.990894)
			(arc
				(start 228.506528 -361.990894)
				(mid 228.487005 -361.994795)
				(end 228.47046 -362.00588)
			)
			(arc
				(start 228.311202 -362.165138)
				(mid 228.300091 -362.181672)
				(end 228.296216 -362.201206)
			)
			(arc
				(start 228.296216 -366.147604)
				(mid 228.300117 -366.167127)
				(end 228.311202 -366.183672)
			)
			(arc
				(start 228.50221 -366.37468)
				(mid 228.518744 -366.385791)
				(end 228.538278 -366.389666)
			)
		)
		(stroke
			(width 0)
			(type solid)
		)
		(fill yes)
		(layer "In11.Cu")
		(net "P12V_AUX")
	)
	(gr_poly
		(pts
			(arc
				(start 319.445894 -161.858198)
				(mid 319.465417 -161.854297)
				(end 319.481962 -161.843212)
			)
			(arc
				(start 325.820532 -155.504642)
				(mid 325.831643 -155.488108)
				(end 325.835518 -155.468574)
			)
			(arc
				(start 325.835518 -139.892024)
				(mid 325.839419 -139.872501)
				(end 325.850504 -139.855956)
			)
			(arc
				(start 331.380846 -134.325614)
				(mid 331.39738 -134.314503)
				(end 331.416914 -134.310628)
			)
			(arc
				(start 335.299812 -134.310628)
				(mid 335.319335 -134.306727)
				(end 335.33588 -134.295642)
			)
			(arc
				(start 336.28711 -133.344412)
				(mid 336.298221 -133.327878)
				(end 336.302096 -133.308344)
			)
			(arc
				(start 336.302096 -132.15112)
				(mid 336.298195 -132.131597)
				(end 336.28711 -132.115052)
			)
			(arc
				(start 335.844642 -131.672584)
				(mid 335.828108 -131.661473)
				(end 335.808574 -131.657598)
			)
			(arc
				(start 330.544678 -131.657598)
				(mid 330.525155 -131.661499)
				(end 330.50861 -131.672584)
			)
			(arc
				(start 323.488304 -138.69289)
				(mid 323.477193 -138.709424)
				(end 323.473318 -138.728958)
			)
			(arc
				(start 323.473318 -153.441654)
				(mid 323.469417 -153.461177)
				(end 323.458332 -153.477722)
			)
			(arc
				(start 318.218312 -158.717742)
				(mid 318.201778 -158.728853)
				(end 318.182244 -158.732728)
			)
			(arc
				(start 314.881006 -158.732728)
				(mid 314.861483 -158.736629)
				(end 314.844938 -158.747714)
			)
			(arc
				(start 313.16676 -160.425892)
				(mid 313.155649 -160.442426)
				(end 313.151774 -160.46196)
			)
			(arc
				(start 313.151774 -161.400998)
				(mid 313.155675 -161.420521)
				(end 313.16676 -161.437066)
			)
			(arc
				(start 313.572906 -161.843212)
				(mid 313.58944 -161.854323)
				(end 313.608974 -161.858198)
			)
		)
		(stroke
			(width 0)
			(type solid)
		)
		(fill yes)
		(layer "In11.Cu")
		(net "P5V_AUX")
	)
	(gr_poly
		(pts
			(xy 42.390314 -13.820648) (xy 42.390314 -13.401548) (xy 42.34688 -13.358114)
			(arc
				(start 34.964878 -13.358114)
				(mid 33.898562 -12.916432)
				(end 33.45688 -11.850116)
			)
			(arc
				(start 33.45688 -1.999996)
				(mid 33.019884 -0.944996)
				(end 31.964884 -0.508)
			)
			(arc
				(start 19.964908 -0.508)
				(mid 18.909908 -0.944996)
				(end 18.472912 -1.999996)
			)
			(xy 18.472912 -11.631422) (xy 18.980404 -11.631422)
			(arc
				(start 18.980404 -1.999996)
				(mid 19.268759 -1.303847)
				(end 19.964908 -1.015492)
			)
			(arc
				(start 31.964884 -1.015492)
				(mid 32.661033 -1.303847)
				(end 32.949388 -1.999996)
			)
			(arc
				(start 32.949388 -11.850116)
				(mid 33.539801 -13.275118)
				(end 34.964878 -13.865352)
			)
			(xy 42.34561 -13.865352)
		)
		(stroke
			(width 0)
			(type solid)
		)
		(fill yes)
		(layer "In11.Cu")
		(net "GND")
	)
	(gr_poly
		(pts
			(xy 68.431156 -13.728954) (xy 68.431156 -13.494512) (xy 68.294758 -13.358114)
			(arc
				(start 60.96508 -13.358114)
				(mid 59.898764 -12.916432)
				(end 59.457082 -11.850116)
			)
			(arc
				(start 59.457082 -1.999996)
				(mid 59.020086 -0.944996)
				(end 57.965086 -0.508)
			)
			(arc
				(start 45.96511 -0.508)
				(mid 44.91011 -0.944996)
				(end 44.473114 -1.999996)
			)
			(xy 44.473114 -11.726418) (xy 44.980352 -11.726418)
			(arc
				(start 44.980352 -1.999996)
				(mid 45.268617 -1.303936)
				(end 45.964602 -1.015492)
			)
			(arc
				(start 57.965086 -1.015492)
				(mid 58.661325 -1.303831)
				(end 58.949844 -1.999996)
			)
			(arc
				(start 58.949844 -11.850116)
				(mid 59.540093 -13.275103)
				(end 60.96508 -13.865352)
			)
			(xy 68.294758 -13.865352)
		)
		(stroke
			(width 0)
			(type solid)
		)
		(fill yes)
		(layer "In11.Cu")
		(net "GND")
	)
	(gr_poly
		(pts
			(xy 94.285816 -13.833856) (xy 94.285816 -13.444728) (xy 94.199202 -13.358114)
			(arc
				(start 86.965028 -13.358114)
				(mid 85.898712 -12.916432)
				(end 85.45703 -11.850116)
			)
			(arc
				(start 85.45703 -1.999996)
				(mid 85.020034 -0.944996)
				(end 83.965034 -0.508)
			)
			(arc
				(start 71.965058 -0.508)
				(mid 70.910058 -0.944996)
				(end 70.473062 -1.999996)
			)
			(xy 70.473062 -11.716004) (xy 70.9803 -11.716004)
			(arc
				(start 70.9803 -1.999996)
				(mid 71.268565 -1.303936)
				(end 71.96455 -1.015492)
			)
			(arc
				(start 83.965034 -1.015492)
				(mid 84.661273 -1.303831)
				(end 84.949792 -1.999996)
			)
			(arc
				(start 84.949792 -11.850116)
				(mid 85.540041 -13.275103)
				(end 86.965028 -13.865352)
			)
			(xy 94.25432 -13.865352)
		)
		(stroke
			(width 0)
			(type solid)
		)
		(fill yes)
		(layer "In11.Cu")
		(net "GND")
	)
	(gr_poly
		(pts
			(xy 132.291582 -13.80998) (xy 132.291582 -13.413486) (xy 132.23621 -13.358114)
			(arc
				(start 125.065028 -13.358114)
				(mid 123.998712 -12.916432)
				(end 123.55703 -11.850116)
			)
			(arc
				(start 123.55703 -1.999996)
				(mid 123.120034 -0.944996)
				(end 122.065034 -0.508)
			)
			(arc
				(start 97.965006 -0.508)
				(mid 96.910006 -0.944996)
				(end 96.47301 -1.999996)
			)
			(xy 96.47301 -11.72464) (xy 96.980248 -11.72464)
			(arc
				(start 96.980248 -1.999996)
				(mid 97.268513 -1.303936)
				(end 97.964498 -1.015492)
			)
			(arc
				(start 122.065034 -1.015492)
				(mid 122.761273 -1.303831)
				(end 123.049792 -1.999996)
			)
			(arc
				(start 123.049792 -11.850116)
				(mid 123.640041 -13.275103)
				(end 125.065028 -13.865352)
			)
			(xy 132.23621 -13.865352)
		)
		(stroke
			(width 0)
			(type solid)
		)
		(fill yes)
		(layer "In11.Cu")
		(net "GND")
	)
	(gr_poly
		(pts
			(xy 158.365444 -13.805662) (xy 158.365444 -13.417804) (xy 158.305754 -13.358114)
			(arc
				(start 151.064976 -13.358114)
				(mid 149.99866 -12.916432)
				(end 149.556978 -11.850116)
			)
			(arc
				(start 149.556978 -1.999996)
				(mid 149.119982 -0.944996)
				(end 148.064982 -0.508)
			)
			(arc
				(start 136.065006 -0.508)
				(mid 135.010006 -0.944996)
				(end 134.57301 -1.999996)
			)
			(xy 134.57301 -11.817604) (xy 135.080248 -11.817604)
			(arc
				(start 135.080248 -1.999996)
				(mid 135.368513 -1.303936)
				(end 136.064498 -1.015492)
			)
			(arc
				(start 148.064982 -1.015492)
				(mid 148.761221 -1.303831)
				(end 149.04974 -1.999996)
			)
			(arc
				(start 149.04974 -11.850116)
				(mid 149.639989 -13.275103)
				(end 151.064976 -13.865352)
			)
			(xy 158.305754 -13.865352)
		)
		(stroke
			(width 0)
			(type solid)
		)
		(fill yes)
		(layer "In11.Cu")
		(net "GND")
	)
	(gr_poly
		(pts
			(xy 184.389268 -13.77569) (xy 184.389268 -13.447776) (xy 184.299606 -13.358114)
			(arc
				(start 177.064924 -13.358114)
				(mid 175.998608 -12.916432)
				(end 175.556926 -11.850116)
			)
			(arc
				(start 175.556926 -1.999996)
				(mid 175.11993 -0.944996)
				(end 174.06493 -0.508)
			)
			(arc
				(start 162.064954 -0.508)
				(mid 161.009954 -0.944996)
				(end 160.572958 -1.999996)
			)
			(xy 160.572958 -11.62304) (xy 161.080196 -11.62304)
			(arc
				(start 161.080196 -1.999996)
				(mid 161.368461 -1.303936)
				(end 162.064446 -1.015492)
			)
			(arc
				(start 174.06493 -1.015492)
				(mid 174.761169 -1.303831)
				(end 175.049688 -1.999996)
			)
			(arc
				(start 175.049688 -11.850116)
				(mid 175.639937 -13.275103)
				(end 177.064924 -13.865352)
			)
			(xy 184.299606 -13.865352)
		)
		(stroke
			(width 0)
			(type solid)
		)
		(fill yes)
		(layer "In11.Cu")
		(net "GND")
	)
	(gr_poly
		(pts
			(xy 210.250024 -13.829284) (xy 210.250024 -13.394182) (xy 210.213956 -13.358114)
			(arc
				(start 203.064872 -13.358114)
				(mid 201.998721 -12.916342)
				(end 201.556874 -11.850116)
			)
			(arc
				(start 201.556874 -1.999996)
				(mid 201.119878 -0.944996)
				(end 200.064878 -0.508)
			)
			(arc
				(start 188.064902 -0.508)
				(mid 187.009902 -0.944996)
				(end 186.572906 -1.999996)
			)
			(xy 186.572906 -11.750294) (xy 187.080144 -11.750294)
			(arc
				(start 187.080144 -1.999996)
				(mid 187.368409 -1.303936)
				(end 188.064394 -1.015492)
			)
			(arc
				(start 200.064878 -1.015492)
				(mid 200.761117 -1.303831)
				(end 201.049636 -1.999996)
			)
			(arc
				(start 201.049636 -11.850116)
				(mid 201.63987 -13.275193)
				(end 203.064872 -13.865352)
			)
			(xy 210.213956 -13.865352)
		)
		(stroke
			(width 0)
			(type solid)
		)
		(fill yes)
		(layer "In11.Cu")
		(net "GND")
	)
	(gr_poly
		(pts
			(xy 300.515782 -13.7541) (xy 300.515782 -13.469366) (xy 300.40453 -13.358114)
			(arc
				(start 293.165022 -13.358114)
				(mid 292.098706 -12.916432)
				(end 291.657024 -11.850116)
			)
			(arc
				(start 291.657024 -1.999996)
				(mid 291.220028 -0.944996)
				(end 290.165028 -0.508)
			)
			(arc
				(start 278.165052 -0.508)
				(mid 277.110052 -0.944996)
				(end 276.673056 -1.999996)
			)
			(xy 276.673056 -11.825732) (xy 277.180548 -11.825732)
			(arc
				(start 277.180548 -1.999996)
				(mid 277.468903 -1.303847)
				(end 278.165052 -1.015492)
			)
			(arc
				(start 290.165028 -1.015492)
				(mid 290.861177 -1.303847)
				(end 291.149532 -1.999996)
			)
			(arc
				(start 291.149532 -11.850116)
				(mid 291.739945 -13.275118)
				(end 293.165022 -13.865352)
			)
			(xy 300.40453 -13.865352)
		)
		(stroke
			(width 0)
			(type solid)
		)
		(fill yes)
		(layer "In11.Cu")
		(net "GND")
	)
	(gr_poly
		(pts
			(xy 442.67882 -13.82903) (xy 442.67882 -13.394436) (xy 442.642498 -13.358114)
			(arc
				(start 435.265068 -13.358114)
				(mid 434.198752 -12.916432)
				(end 433.75707 -11.850116)
			)
			(arc
				(start 433.75707 -1.999996)
				(mid 433.320074 -0.944996)
				(end 432.265074 -0.508)
			)
			(arc
				(start 420.265098 -0.508)
				(mid 419.210098 -0.944996)
				(end 418.773102 -1.999996)
			)
			(xy 418.773102 -11.73734) (xy 419.28034 -11.73734)
			(arc
				(start 419.28034 -1.999996)
				(mid 419.568605 -1.303936)
				(end 420.26459 -1.015492)
			)
			(arc
				(start 432.265074 -1.015492)
				(mid 432.961313 -1.303831)
				(end 433.249832 -1.999996)
			)
			(arc
				(start 433.249832 -11.850116)
				(mid 433.840081 -13.275103)
				(end 435.265068 -13.865352)
			)
			(xy 442.642498 -13.865352)
		)
		(stroke
			(width 0)
			(type solid)
		)
		(fill yes)
		(layer "In11.Cu")
		(net "GND")
	)
	(gr_poly
		(pts
			(xy 248.61139 -13.829538) (xy 248.61139 -13.393928) (xy 248.575576 -13.358114)
			(arc
				(start 241.164872 -13.358114)
				(mid 240.098721 -12.916342)
				(end 239.656874 -11.850116)
			)
			(arc
				(start 239.656874 -1.999996)
				(mid 239.219878 -0.944996)
				(end 238.164878 -0.508)
			)
			(arc
				(start 214.065104 -0.508)
				(mid 213.010104 -0.944996)
				(end 212.573108 -1.999996)
			)
			(xy 212.573108 -11.851132) (xy 212.571584 -11.91895) (xy 213.07933 -11.91895) (xy 213.0806 -11.850116)
			(arc
				(start 213.0806 -1.999996)
				(mid 213.368955 -1.303847)
				(end 214.065104 -1.015492)
			)
			(arc
				(start 238.164878 -1.015492)
				(mid 238.861117 -1.303831)
				(end 239.149636 -1.999996)
			)
			(arc
				(start 239.149636 -11.850116)
				(mid 239.73987 -13.275193)
				(end 241.164872 -13.865352)
			)
			(xy 248.575576 -13.865352)
		)
		(stroke
			(width 0)
			(type solid)
		)
		(fill yes)
		(layer "In11.Cu")
		(net "GND")
	)
	(gr_poly
		(pts
			(xy 274.599654 -13.810742) (xy 274.599654 -13.412724) (xy 274.545044 -13.358114)
			(arc
				(start 267.165074 -13.358114)
				(mid 266.098758 -12.916432)
				(end 265.657076 -11.850116)
			)
			(arc
				(start 265.657076 -1.999996)
				(mid 265.22008 -0.944996)
				(end 264.16508 -0.508)
			)
			(arc
				(start 252.165104 -0.508)
				(mid 251.110104 -0.944996)
				(end 250.673108 -1.999996)
			)
			(xy 250.673108 -11.850116) (xy 250.673108 -11.851386) (xy 251.1806 -11.851386) (xy 251.1806 -11.850116)
			(arc
				(start 251.1806 -1.999996)
				(mid 251.468955 -1.303847)
				(end 252.165104 -1.015492)
			)
			(arc
				(start 264.16508 -1.015492)
				(mid 264.861229 -1.303847)
				(end 265.149584 -1.999996)
			)
			(arc
				(start 265.149584 -11.850116)
				(mid 265.739997 -13.275118)
				(end 267.165074 -13.865352)
			)
			(xy 274.545044 -13.865352)
		)
		(stroke
			(width 0)
			(type solid)
		)
		(fill yes)
		(layer "In11.Cu")
		(net "GND")
	)
	(gr_poly
		(pts
			(xy 416.458146 -13.816076) (xy 416.458146 -13.40739) (xy 416.40887 -13.358114)
			(arc
				(start 409.26512 -13.358114)
				(mid 408.198804 -12.916432)
				(end 407.757122 -11.850116)
			)
			(arc
				(start 407.757122 -1.999996)
				(mid 407.320126 -0.944996)
				(end 406.265126 -0.508)
			)
			(arc
				(start 394.264896 -0.508)
				(mid 393.209896 -0.944996)
				(end 392.7729 -1.999996)
			)
			(arc
				(start 392.7729 -11.850116)
				(mid 392.702216 -12.306469)
				(end 392.496802 -12.720066)
			)
			(xy 392.496802 -12.748514) (xy 392.499088 -12.7508)
			(arc
				(start 393.067794 -12.7508)
				(mid 393.226496 -12.312827)
				(end 393.280392 -11.850116)
			)
			(arc
				(start 393.280392 -1.999996)
				(mid 393.568747 -1.303847)
				(end 394.264896 -1.015492)
			)
			(arc
				(start 406.265126 -1.015492)
				(mid 406.961365 -1.303831)
				(end 407.249884 -1.999996)
			)
			(arc
				(start 407.249884 -11.850116)
				(mid 407.840133 -13.275103)
				(end 409.26512 -13.865352)
			)
			(xy 416.40887 -13.865352)
		)
		(stroke
			(width 0)
			(type solid)
		)
		(fill yes)
		(layer "In11.Cu")
		(net "GND")
	)
	(gr_poly
		(pts
			(xy 364.71606 -13.770102) (xy 364.71606 -13.453364) (xy 364.62081 -13.358114)
			(arc
				(start 357.26497 -13.358114)
				(mid 356.198654 -12.916432)
				(end 355.756972 -11.850116)
			)
			(arc
				(start 355.756972 -1.999996)
				(mid 355.319976 -0.944996)
				(end 354.264976 -0.508)
			)
			(arc
				(start 330.164948 -0.508)
				(mid 329.109948 -0.944996)
				(end 328.672952 -1.999996)
			)
			(arc
				(start 328.672952 -11.850116)
				(mid 328.570197 -12.397292)
				(end 328.27595 -12.869926)
			)
			(xy 328.27595 -12.876784) (xy 328.28738 -12.888214) (xy 328.885042 -12.888214)
			(arc
				(start 328.90333 -12.869926)
				(mid 329.10994 -12.378512)
				(end 329.180444 -11.850116)
			)
			(arc
				(start 329.180444 -1.999996)
				(mid 329.468799 -1.303847)
				(end 330.164948 -1.015492)
			)
			(arc
				(start 354.264976 -1.015492)
				(mid 354.961125 -1.303847)
				(end 355.24948 -1.999996)
			)
			(arc
				(start 355.24948 -11.850116)
				(mid 355.839893 -13.275118)
				(end 357.26497 -13.865352)
			)
			(xy 364.62081 -13.865352)
		)
		(stroke
			(width 0)
			(type solid)
		)
		(fill yes)
		(layer "In11.Cu")
		(net "GND")
	)
	(gr_poly
		(pts
			(xy 390.499092 -13.810996) (xy 390.499092 -13.41247) (xy 390.444736 -13.358114)
			(arc
				(start 383.264918 -13.358114)
				(mid 382.198602 -12.916432)
				(end 381.75692 -11.850116)
			)
			(arc
				(start 381.75692 -1.999996)
				(mid 381.319924 -0.944996)
				(end 380.264924 -0.508)
			)
			(arc
				(start 368.264948 -0.508)
				(mid 367.209948 -0.944996)
				(end 366.772952 -1.999996)
			)
			(arc
				(start 366.772952 -11.850116)
				(mid 366.670132 -12.397459)
				(end 366.375696 -12.87018)
			)
			(xy 366.375696 -12.899644) (xy 366.434878 -12.958826) (xy 366.914684 -12.958826)
			(arc
				(start 367.00333 -12.87018)
				(mid 367.209881 -12.378884)
				(end 367.280444 -11.850624)
			)
			(arc
				(start 367.280444 -1.999996)
				(mid 367.568799 -1.303847)
				(end 368.264948 -1.015492)
			)
			(arc
				(start 380.264924 -1.015492)
				(mid 380.961073 -1.303847)
				(end 381.249428 -1.999996)
			)
			(arc
				(start 381.249428 -11.850116)
				(mid 381.839841 -13.275118)
				(end 383.264918 -13.865352)
			)
			(xy 390.444736 -13.865352)
		)
		(stroke
			(width 0)
			(type solid)
		)
		(fill yes)
		(layer "In11.Cu")
		(net "GND")
	)
	(gr_poly
		(pts
			(xy 326.45985 -13.852906) (xy 326.45985 -13.37945) (xy 326.438514 -13.358114)
			(arc
				(start 319.16497 -13.358114)
				(mid 318.098654 -12.916432)
				(end 317.656972 -11.850116)
			)
			(arc
				(start 317.656972 -1.999996)
				(mid 317.219976 -0.944996)
				(end 316.164976 -0.508)
			)
			(arc
				(start 304.165 -0.508)
				(mid 303.11 -0.944996)
				(end 302.673004 -1.999996)
			)
			(arc
				(start 302.673004 -11.850116)
				(mid 302.577528 -12.378214)
				(end 302.30318 -12.839446)
			)
			(xy 302.30318 -12.884912) (xy 302.304196 -12.885928) (xy 302.874426 -12.885928)
			(arc
				(start 302.920908 -12.839446)
				(mid 303.114524 -12.361527)
				(end 303.180496 -11.850116)
			)
			(arc
				(start 303.180496 -1.999996)
				(mid 303.468851 -1.303847)
				(end 304.165 -1.015492)
			)
			(arc
				(start 316.164976 -1.015492)
				(mid 316.861125 -1.303847)
				(end 317.14948 -1.999996)
			)
			(arc
				(start 317.14948 -11.850116)
				(mid 317.739893 -13.275118)
				(end 319.16497 -13.865352)
			)
			(xy 326.438514 -13.865352) (xy 326.447404 -13.865352)
		)
		(stroke
			(width 0)
			(type solid)
		)
		(fill yes)
		(layer "In11.Cu")
		(net "GND")
	)
	(gr_poly
		(pts
			(arc
				(start 200.481692 -418.081968)
				(mid 201.086106 -417.953924)
				(end 201.586846 -417.592002)
			)
			(arc
				(start 201.586846 -417.592002)
				(mid 202.42889 -416.98332)
				(end 203.445364 -416.768026)
			)
			(arc
				(start 271.794732 -416.768026)
				(mid 272.811071 -416.983322)
				(end 273.652996 -417.592002)
			)
			(arc
				(start 273.652996 -417.592002)
				(mid 274.153727 -417.953921)
				(end 274.75815 -418.081968)
			)
			(arc
				(start 465.600034 -418.081968)
				(mid 466.655034 -417.644972)
				(end 467.09203 -416.589972)
			)
			(xy 467.09203 -317.499746) (xy 466.584792 -317.499746)
			(arc
				(start 466.584792 -416.589972)
				(mid 466.296527 -417.286032)
				(end 465.600542 -417.574476)
			)
			(xy 414.915604 -417.574476) (xy 414.915604 -417.797742) (xy 400.95424 -417.797742) (xy 400.95424 -417.574476)
			(xy 326.621648 -417.574476) (xy 326.621648 -417.747958) (xy 313.065922 -417.747958) (xy 313.065922 -417.574476)
			(arc
				(start 274.757896 -417.574476)
				(mid 274.359217 -417.490052)
				(end 274.028916 -417.251388)
			)
			(arc
				(start 274.028916 -417.251388)
				(mid 273.01669 -416.519565)
				(end 271.794732 -416.260788)
			)
			(arc
				(start 203.445364 -416.260788)
				(mid 202.223266 -416.519531)
				(end 201.210926 -417.251388)
			)
			(arc
				(start 201.210926 -417.251388)
				(mid 200.880626 -417.490098)
				(end 200.481946 -417.574476)
			)
			(xy 154.673554 -417.574476) (xy 154.673554 -417.693856) (xy 141.027912 -417.693856) (xy 141.027912 -417.574476)
			(xy 66.745104 -417.574476) (xy 66.745104 -417.671758) (xy 53.039772 -417.671758) (xy 53.039772 -417.574476)
			(arc
				(start 1.999996 -417.574476)
				(mid 1.303847 -417.286121)
				(end 1.015492 -416.589972)
			)
			(xy 1.015492 -316.13983) (xy 0.508 -316.13983)
			(arc
				(start 0.508 -416.589972)
				(mid 0.944996 -417.644972)
				(end 1.999996 -418.081968)
			)
		)
		(stroke
			(width 0)
			(type solid)
		)
		(fill yes)
		(layer "In11.Cu")
		(net "GND")
	)
	(gr_poly
		(pts
			(arc
				(start 467.09203 -246.488204)
				(mid 466.978493 -245.917325)
				(end 466.65515 -245.433342)
			)
			(arc
				(start 464.026504 -242.80495)
				(mid 463.482885 -241.991412)
				(end 463.291936 -241.031776)
			)
			(arc
				(start 463.291936 -87.588344)
				(mid 463.482826 -86.628673)
				(end 464.026504 -85.81517)
			)
			(arc
				(start 466.65515 -83.186524)
				(mid 466.978483 -82.702667)
				(end 467.09203 -82.131916)
			)
			(arc
				(start 467.09203 -1.999996)
				(mid 466.655034 -0.944996)
				(end 465.600034 -0.508)
			)
			(arc
				(start 446.265046 -0.508)
				(mid 445.210046 -0.944996)
				(end 444.77305 -1.999996)
			)
			(arc
				(start 444.77305 -11.850116)
				(mid 444.676277 -12.381671)
				(end 444.3984 -12.845034)
			)
			(xy 444.3984 -12.869164) (xy 444.399924 -12.870688)
			(arc
				(start 445.002666 -12.870688)
				(mid 445.20965 -12.378943)
				(end 445.280288 -11.850116)
			)
			(arc
				(start 445.280288 -1.999996)
				(mid 445.568553 -1.303936)
				(end 446.264538 -1.015492)
			)
			(arc
				(start 465.600034 -1.015492)
				(mid 466.296273 -1.303831)
				(end 466.584792 -1.999996)
			)
			(arc
				(start 466.584792 -82.131916)
				(mid 466.509885 -82.508586)
				(end 466.296502 -82.827876)
			)
			(arc
				(start 463.667856 -85.456522)
				(mid 463.014235 -86.434595)
				(end 462.784698 -87.588344)
			)
			(xy 462.784444 -87.588344) (xy 462.784444 -241.031776)
			(arc
				(start 462.784698 -241.031776)
				(mid 463.014268 -242.185519)
				(end 463.667856 -243.163598)
			)
			(arc
				(start 466.296502 -245.79199)
				(mid 466.509882 -246.11143)
				(end 466.584792 -246.488204)
			)
			(xy 466.584792 -311.303416) (xy 467.09203 -311.303416)
		)
		(stroke
			(width 0)
			(type solid)
		)
		(fill yes)
		(layer "In11.Cu")
		(net "GND")
	)
	(gr_poly
		(pts
			(arc
				(start 1.015492 -246.48795)
				(mid 1.090466 -246.111319)
				(end 1.303782 -245.79199)
			)
			(arc
				(start 3.93192 -243.163852)
				(mid 4.58575 -242.18556)
				(end 4.815332 -241.031522)
			)
			(arc
				(start 4.815332 -87.588344)
				(mid 4.585694 -86.434435)
				(end 3.93192 -85.456268)
			)
			(arc
				(start 1.303528 -82.827876)
				(mid 1.090411 -82.508641)
				(end 1.015492 -82.13217)
			)
			(arc
				(start 1.015492 -1.999996)
				(mid 1.303847 -1.303847)
				(end 1.999996 -1.015492)
			)
			(arc
				(start 5.964936 -1.015492)
				(mid 6.661085 -1.303847)
				(end 6.94944 -1.999996)
			)
			(arc
				(start 6.94944 -11.850116)
				(mid 7.539853 -13.275118)
				(end 8.96493 -13.865352)
			)
			(xy 16.2814 -13.865352) (xy 16.371316 -13.775436) (xy 16.371316 -13.44803) (xy 16.2814 -13.358114)
			(arc
				(start 8.96493 -13.358114)
				(mid 7.898614 -12.916432)
				(end 7.456932 -11.850116)
			)
			(arc
				(start 7.456932 -1.999996)
				(mid 7.019936 -0.944996)
				(end 5.964936 -0.508)
			)
			(arc
				(start 1.999996 -0.508)
				(mid 0.944996 -0.944996)
				(end 0.508 -1.999996)
			)
			(arc
				(start 0.508 -82.131916)
				(mid 0.621601 -82.702644)
				(end 0.94488 -83.186524)
			)
			(arc
				(start 3.573272 -85.81517)
				(mid 4.117081 -86.628665)
				(end 4.308094 -87.588344)
			)
			(arc
				(start 4.308094 -241.031522)
				(mid 4.117082 -241.991334)
				(end 3.573272 -242.80495)
			)
			(arc
				(start 0.94488 -245.433342)
				(mid 0.621552 -245.917331)
				(end 0.508 -246.488204)
			)
			(xy 0.508 -307.918358) (xy 1.015492 -307.918358)
		)
		(stroke
			(width 0)
			(type solid)
		)
		(fill yes)
		(layer "In11.Cu")
		(net "GND")
	)
	(gr_poly
		(pts
			(xy 96.458532 -287.745424) (xy 96.470065 -287.744876) (xy 96.490828 -287.734828) (xy 96.49841 -287.72612)
			(xy 96.552083 -287.659035) (xy 96.665295 -287.529782) (xy 96.784927 -287.406448) (xy 96.910672 -287.289351)
			(xy 97.042204 -287.178795) (xy 97.179184 -287.075065) (xy 97.321257 -286.978429) (xy 97.468057 -286.889136)
			(xy 97.543366 -286.847788) (xy 97.55122 -286.843108) (xy 97.563221 -286.829331) (xy 97.569626 -286.812219)
			(xy 97.570036 -286.803084) (xy 97.570036 -261.432294) (xy 97.56961 -261.422226) (xy 97.561887 -261.403629)
			(xy 97.55505 -261.396226) (xy 90.548968 -254.390144) (xy 90.542123 -254.382746) (xy 90.534398 -254.364147)
			(xy 90.533982 -254.354076) (xy 90.533982 -189.410086) (xy 90.534407 -189.400016) (xy 90.542123 -189.381414)
			(xy 90.548968 -189.374018) (xy 95.763842 -184.159144) (xy 95.770686 -184.151745) (xy 95.778409 -184.133146)
			(xy 95.778828 -184.123076) (xy 95.778828 -181.229508) (xy 95.778407 -181.219437) (xy 95.770698 -181.200827)
			(xy 95.763842 -181.19344) (xy 94.793308 -180.222906) (xy 94.785963 -180.216093) (xy 94.767501 -180.208357)
			(xy 94.757494 -180.20792) (xy 89.926668 -180.20792) (xy 89.918679 -180.208838) (xy 89.903799 -180.214913)
			(xy 89.897458 -180.219858) (xy 78.92161 -191.195706) (xy 78.914799 -191.203051) (xy 78.907068 -191.221514)
			(xy 78.906624 -191.23152) (xy 78.906624 -252.862842) (xy 78.90717 -252.872826) (xy 78.914896 -252.891244)
			(xy 78.92161 -252.898656) (xy 82.844132 -256.821178) (xy 82.851752 -256.83972) (xy 82.851752 -256.849626)
			(xy 84.360766 -258.35864) (xy 84.369136 -258.366236) (xy 84.39037 -258.373898) (xy 84.40166 -258.373372)
			(xy 84.490814 -258.364736) (xy 84.510118 -258.353306) (xy 84.516468 -258.343908) (xy 84.531765 -258.322171)
			(xy 84.567414 -258.282747) (xy 84.608189 -258.248651) (xy 84.653302 -258.220545) (xy 84.701878 -258.19897)
			(xy 84.752979 -258.184346) (xy 84.805614 -258.176955) (xy 84.83219 -258.176522) (xy 84.859443 -258.176985)
			(xy 84.913393 -258.184741) (xy 84.96569 -258.200096) (xy 85.01527 -258.222738) (xy 85.061122 -258.252207)
			(xy 85.102313 -258.287901) (xy 85.138005 -258.329094) (xy 85.167471 -258.374948) (xy 85.190111 -258.424528)
			(xy 85.205464 -258.476827) (xy 85.213217 -258.530777) (xy 85.213698 -258.55803) (xy 85.213242 -258.584607)
			(xy 85.205871 -258.637248) (xy 85.203176 -258.646676) (xy 85.359238 -258.646676) (xy 85.363309 -258.591054)
			(xy 85.375435 -258.536617) (xy 85.395358 -258.484526) (xy 85.422654 -258.435891) (xy 85.45674 -258.391748)
			(xy 85.496889 -258.353039) (xy 85.542247 -258.320588) (xy 85.591847 -258.295087) (xy 85.644631 -258.27708)
			(xy 85.699474 -258.26695) (xy 85.755208 -258.264913) (xy 85.810645 -258.271013) (xy 85.864602 -258.285119)
			(xy 85.915931 -258.306931) (xy 85.963537 -258.335985) (xy 86.006405 -258.37166) (xy 86.043622 -258.413197)
			(xy 86.074395 -258.45971) (xy 86.098067 -258.510207) (xy 86.114135 -258.563614) (xy 86.117462 -258.586224)
			(xy 86.25154 -258.586224) (xy 86.255611 -258.530602) (xy 86.267737 -258.476165) (xy 86.28766 -258.424074)
			(xy 86.314956 -258.375439) (xy 86.349042 -258.331296) (xy 86.389191 -258.292587) (xy 86.434549 -258.260136)
			(xy 86.484149 -258.234635) (xy 86.536933 -258.216628) (xy 86.591776 -258.206498) (xy 86.64751 -258.204461)
			(xy 86.702947 -258.210561) (xy 86.756904 -258.224667) (xy 86.808233 -258.246479) (xy 86.855839 -258.275533)
			(xy 86.898707 -258.311208) (xy 86.935924 -258.352745) (xy 86.966697 -258.399258) (xy 86.990369 -258.449755)
			(xy 87.006437 -258.503162) (xy 87.014557 -258.558338) (xy 87.015066 -258.586224) (xy 87.014557 -258.61411)
			(xy 87.006437 -258.669286) (xy 86.990369 -258.722693) (xy 86.966697 -258.77319) (xy 86.935924 -258.819703)
			(xy 86.898707 -258.86124) (xy 86.855839 -258.896915) (xy 86.808233 -258.925969) (xy 86.756904 -258.947781)
			(xy 86.702947 -258.961887) (xy 86.64751 -258.967987) (xy 86.591776 -258.96595) (xy 86.536933 -258.95582)
			(xy 86.484149 -258.937813) (xy 86.434549 -258.912312) (xy 86.389191 -258.879861) (xy 86.349042 -258.841152)
			(xy 86.314956 -258.797009) (xy 86.28766 -258.748374) (xy 86.267737 -258.696283) (xy 86.255611 -258.641846)
			(xy 86.25154 -258.586224) (xy 86.117462 -258.586224) (xy 86.122255 -258.61879) (xy 86.122764 -258.646676)
			(xy 86.122255 -258.674562) (xy 86.114135 -258.729738) (xy 86.098067 -258.783145) (xy 86.074395 -258.833642)
			(xy 86.043622 -258.880155) (xy 86.006405 -258.921692) (xy 85.963537 -258.957367) (xy 85.915931 -258.986421)
			(xy 85.864602 -259.008233) (xy 85.810645 -259.022339) (xy 85.755208 -259.028439) (xy 85.699474 -259.026402)
			(xy 85.644631 -259.016272) (xy 85.591847 -258.998265) (xy 85.542247 -258.972764) (xy 85.496889 -258.940313)
			(xy 85.45674 -258.901604) (xy 85.422654 -258.857461) (xy 85.395358 -258.808826) (xy 85.375435 -258.756735)
			(xy 85.363309 -258.702298) (xy 85.359238 -258.646676) (xy 85.203176 -258.646676) (xy 85.191261 -258.688356)
			(xy 85.169696 -258.736939) (xy 85.141594 -258.782057) (xy 85.107499 -258.822836) (xy 85.068071 -258.858486)
			(xy 85.046312 -258.873752) (xy 85.036914 -258.880102) (xy 85.025484 -258.899406) (xy 85.016848 -258.988814)
			(xy 85.016848 -258.98983) (xy 85.016512 -259.000861) (xy 85.02416 -259.021537) (xy 85.03158 -259.029708)
			(xy 94.120208 -268.118082) (xy 94.12704 -268.125486) (xy 94.134744 -268.144084) (xy 94.135194 -268.15415)
			(xy 94.135194 -269.259812) (xy 94.138242 -269.268194) (xy 94.169423 -269.355282) (xy 94.225842 -269.531471)
			(xy 94.275395 -269.709713) (xy 94.318006 -269.889741) (xy 94.353612 -270.071284) (xy 94.382159 -270.25407)
			(xy 94.403605 -270.437824) (xy 94.417917 -270.622272) (xy 94.425073 -270.807135) (xy 94.425516 -270.899636)
			(xy 94.425516 -270.900144) (xy 94.425068 -270.992645) (xy 94.417904 -271.177507) (xy 94.403586 -271.361954)
			(xy 94.382138 -271.545707) (xy 94.353591 -271.728493) (xy 94.317988 -271.910036) (xy 94.275382 -272.090065)
			(xy 94.225837 -272.268308) (xy 94.169429 -272.4445) (xy 94.138242 -272.531586) (xy 94.136836 -272.535765)
			(xy 94.135311 -272.54445) (xy 94.135194 -272.548858) (xy 94.135194 -285.118302) (xy 94.135194 -285.12008)
			(xy 94.135901 -285.129481) (xy 94.143323 -285.146799) (xy 94.156504 -285.160262) (xy 94.164912 -285.16453)
			(xy 94.16923 -285.166308) (xy 94.275148 -285.203138) (xy 94.30639 -285.194248) (xy 94.316296 -285.181548)
			(xy 94.334493 -285.159421) (xy 94.376395 -285.120355) (xy 94.423665 -285.087992) (xy 94.475242 -285.063059)
			(xy 94.529967 -285.046116) (xy 94.58661 -285.037545) (xy 94.615254 -285.037022) (xy 94.642507 -285.037482)
			(xy 94.696459 -285.045233) (xy 94.748758 -285.060584) (xy 94.79834 -285.083222) (xy 94.844195 -285.112687)
			(xy 94.88539 -285.148377) (xy 94.921086 -285.189568) (xy 94.950556 -285.23542) (xy 94.9732 -285.284999)
			(xy 94.988557 -285.337296) (xy 94.996315 -285.391247) (xy 94.996315 -285.445753) (xy 94.988557 -285.499704)
			(xy 94.9732 -285.552001) (xy 94.950556 -285.60158) (xy 94.921086 -285.647432) (xy 94.88539 -285.688623)
			(xy 94.844195 -285.724313) (xy 94.79834 -285.753778) (xy 94.748758 -285.776416) (xy 94.696459 -285.791767)
			(xy 94.642507 -285.799518) (xy 94.615254 -285.800038) (xy 94.586608 -285.799528) (xy 94.529959 -285.790968)
			(xy 94.475227 -285.774031) (xy 94.423644 -285.7491) (xy 94.37637 -285.716734) (xy 94.334468 -285.677662)
			(xy 94.316296 -285.655512) (xy 94.30639 -285.642812) (xy 94.275148 -285.633922) (xy 94.16923 -285.670752)
			(xy 94.164912 -285.67253) (xy 94.156526 -285.676825) (xy 94.143367 -285.690286) (xy 94.135951 -285.707589)
			(xy 94.135194 -285.71698) (xy 94.135194 -286.490664) (xy 94.135628 -286.500729) (xy 94.143358 -286.519317)
			(xy 94.15018 -286.526732) (xy 95.353886 -287.730438) (xy 95.361286 -287.737278) (xy 95.379885 -287.74499)
			(xy 95.389954 -287.745424)
		)
		(stroke
			(width 0)
			(type solid)
		)
		(fill yes)
		(layer "In11.Cu")
		(net "P3V3")
	)
	(gr_poly
		(pts
			(arc
				(start 235.636562 -413.132016)
				(mid 235.656085 -413.128115)
				(end 235.67263 -413.11703)
			)
			(arc
				(start 236.812328 -411.977332)
				(mid 236.823439 -411.960798)
				(end 236.827314 -411.941264)
			)
			(arc
				(start 236.827314 -402.776436)
				(mid 236.831215 -402.756913)
				(end 236.8423 -402.740368)
			)
			(arc
				(start 238.886238 -400.69643)
				(mid 238.902772 -400.685319)
				(end 238.922306 -400.681444)
			)
			(arc
				(start 242.916964 -400.681444)
				(mid 242.936487 -400.677543)
				(end 242.953032 -400.666458)
			)
			(arc
				(start 243.86286 -399.75663)
				(mid 243.873971 -399.740096)
				(end 243.877846 -399.720562)
			)
			(arc
				(start 243.877846 -392.486896)
				(mid 243.881747 -392.467373)
				(end 243.892832 -392.450828)
			)
			(xy 243.896388 -392.447272)
			(arc
				(start 243.896388 -391.97026)
				(mid 243.900289 -391.950737)
				(end 243.911374 -391.934192)
			)
			(arc
				(start 245.02999 -390.815576)
				(mid 245.046524 -390.804465)
				(end 245.066058 -390.80059)
			)
			(arc
				(start 259.092954 -390.80059)
				(mid 259.112477 -390.796689)
				(end 259.129022 -390.785604)
			)
			(arc
				(start 262.060944 -387.853682)
				(mid 262.072055 -387.837148)
				(end 262.07593 -387.817614)
			)
			(arc
				(start 262.07593 -379.165866)
				(mid 262.072029 -379.146343)
				(end 262.060944 -379.129798)
			)
			(arc
				(start 261.987538 -379.056392)
				(mid 261.971004 -379.045281)
				(end 261.95147 -379.041406)
			)
			(xy 243.1415 -379.041406) (xy 243.140484 -379.042422)
			(arc
				(start 240.581688 -379.042422)
				(mid 240.562165 -379.046323)
				(end 240.54562 -379.057408)
			)
			(arc
				(start 239.903 -379.700028)
				(mid 239.886466 -379.711139)
				(end 239.866932 -379.715014)
			)
			(arc
				(start 237.06963 -379.715014)
				(mid 237.050107 -379.711113)
				(end 237.033562 -379.700028)
			)
			(arc
				(start 232.94086 -375.607326)
				(mid 232.929749 -375.590792)
				(end 232.925874 -375.571258)
			)
			(arc
				(start 232.925874 -372.098062)
				(mid 232.921973 -372.078539)
				(end 232.910888 -372.061994)
			)
			(arc
				(start 232.189274 -371.34038)
				(mid 232.178163 -371.323846)
				(end 232.174288 -371.304312)
			)
			(arc
				(start 232.174288 -371.057424)
				(mid 232.170387 -371.037901)
				(end 232.159302 -371.021356)
			)
			(xy 232.119932 -370.981986) (xy 232.118408 -370.981986)
			(arc
				(start 232.015284 -370.878862)
				(mid 232.004173 -370.862328)
				(end 232.000298 -370.842794)
			)
			(arc
				(start 232.000298 -367.379758)
				(mid 231.996397 -367.360235)
				(end 231.985312 -367.34369)
			)
			(arc
				(start 231.905048 -367.263426)
				(mid 231.888514 -367.252315)
				(end 231.86898 -367.24844)
			)
			(arc
				(start 228.707696 -367.24844)
				(mid 228.688173 -367.252341)
				(end 228.671628 -367.263426)
			)
			(arc
				(start 228.614478 -367.320576)
				(mid 228.603367 -367.33711)
				(end 228.599492 -367.356644)
			)
			(arc
				(start 228.599492 -370.828062)
				(mid 228.595591 -370.847585)
				(end 228.584506 -370.86413)
			)
			(arc
				(start 228.431344 -371.017292)
				(mid 228.420233 -371.033826)
				(end 228.416358 -371.05336)
			)
			(arc
				(start 228.416358 -371.446552)
				(mid 228.412457 -371.466075)
				(end 228.401372 -371.48262)
			)
			(arc
				(start 227.137722 -372.74627)
				(mid 227.126611 -372.762804)
				(end 227.122736 -372.782338)
			)
			(arc
				(start 227.122736 -374.248426)
				(mid 227.118835 -374.267949)
				(end 227.10775 -374.284494)
			)
			(arc
				(start 225.693224 -375.69902)
				(mid 225.67669 -375.710131)
				(end 225.657156 -375.714006)
			)
			(arc
				(start 223.582484 -375.714006)
				(mid 223.562961 -375.710105)
				(end 223.546416 -375.69902)
			)
			(arc
				(start 221.539816 -373.69242)
				(mid 221.528705 -373.675886)
				(end 221.52483 -373.656352)
			)
			(arc
				(start 221.52483 -371.070124)
				(mid 221.520929 -371.050601)
				(end 221.509844 -371.034056)
			)
			(arc
				(start 221.337632 -370.861844)
				(mid 221.326521 -370.84531)
				(end 221.322646 -370.825776)
			)
			(arc
				(start 221.322646 -367.359692)
				(mid 221.318745 -367.340169)
				(end 221.30766 -367.323624)
			)
			(arc
				(start 221.24416 -367.260124)
				(mid 221.227626 -367.249013)
				(end 221.208092 -367.245138)
			)
			(arc
				(start 218.078304 -367.245138)
				(mid 218.058781 -367.249039)
				(end 218.042236 -367.260124)
			)
			(arc
				(start 217.916506 -367.385854)
				(mid 217.905395 -367.402388)
				(end 217.90152 -367.421922)
			)
			(arc
				(start 217.90152 -369.007898)
				(mid 217.905421 -369.027421)
				(end 217.916506 -369.043966)
			)
			(arc
				(start 217.938096 -369.065556)
				(mid 218.009962 -369.17325)
				(end 218.035124 -369.300252)
			)
			(arc
				(start 218.035124 -370.6114)
				(mid 218.009956 -370.738399)
				(end 217.938096 -370.846096)
			)
			(arc
				(start 217.404696 -371.379496)
				(mid 217.342304 -371.428483)
				(end 217.270076 -371.461284)
			)
			(xy 217.264234 -371.463062) (xy 217.254074 -371.469158)
			(arc
				(start 216.72931 -371.993922)
				(mid 216.712776 -372.005033)
				(end 216.693242 -372.008908)
			)
			(arc
				(start 210.338924 -372.008908)
				(mid 210.319401 -372.005007)
				(end 210.302856 -371.993922)
			)
			(arc
				(start 210.054698 -371.745764)
				(mid 210.043587 -371.72923)
				(end 210.039712 -371.709696)
			)
			(arc
				(start 210.039712 -371.274086)
				(mid 210.035811 -371.254563)
				(end 210.024726 -371.238018)
			)
			(arc
				(start 209.986626 -371.199918)
				(mid 209.970063 -371.188944)
				(end 209.950558 -371.185186)
			)
			(arc
				(start 209.475324 -371.185186)
				(mid 209.455801 -371.181285)
				(end 209.439256 -371.1702)
			)
			(arc
				(start 208.832196 -370.56314)
				(mid 208.821085 -370.546606)
				(end 208.81721 -370.527072)
			)
			(arc
				(start 208.81721 -370.46027)
				(mid 208.813309 -370.440747)
				(end 208.802224 -370.424202)
			)
			(xy 208.795366 -370.417344)
			(arc
				(start 208.220056 -370.417344)
				(mid 208.200533 -370.413443)
				(end 208.183988 -370.402358)
			)
			(arc
				(start 208.098898 -370.317268)
				(mid 208.087787 -370.300734)
				(end 208.083912 -370.2812)
			)
			(arc
				(start 208.083912 -367.384584)
				(mid 208.080011 -367.365061)
				(end 208.068926 -367.348516)
			)
			(arc
				(start 207.996028 -367.275618)
				(mid 207.979494 -367.264507)
				(end 207.95996 -367.260632)
			)
			(arc
				(start 204.786484 -367.260632)
				(mid 204.766961 -367.264533)
				(end 204.750416 -367.275618)
			)
			(arc
				(start 204.68082 -367.345214)
				(mid 204.669709 -367.361748)
				(end 204.665834 -367.381282)
			)
			(arc
				(start 204.665834 -370.837714)
				(mid 204.669735 -370.857237)
				(end 204.68082 -370.873782)
			)
			(arc
				(start 204.794104 -370.987066)
				(mid 204.805215 -371.0036)
				(end 204.80909 -371.023134)
			)
			(arc
				(start 204.80909 -372.841012)
				(mid 204.815471 -372.865662)
				(end 204.832966 -372.884192)
			)
			(xy 204.917548 -372.93677) (xy 204.94371 -372.93804)
			(arc
				(start 204.955648 -372.932198)
				(mid 205.037716 -372.902845)
				(end 205.124304 -372.892828)
			)
			(arc
				(start 205.124304 -372.892828)
				(mid 205.505812 -373.274336)
				(end 205.124304 -373.655844)
			)
			(arc
				(start 205.124304 -373.655844)
				(mid 205.037702 -373.645885)
				(end 204.955648 -373.616474)
			)
			(xy 204.94371 -373.610632) (xy 204.917548 -373.611902)
			(arc
				(start 204.832966 -373.66448)
				(mid 204.815396 -373.682968)
				(end 204.80909 -373.70766)
			)
			(arc
				(start 204.80909 -374.498616)
				(mid 204.812991 -374.518139)
				(end 204.824076 -374.534684)
			)
			(arc
				(start 204.905102 -374.61571)
				(mid 204.916213 -374.632244)
				(end 204.920088 -374.651778)
			)
			(arc
				(start 204.920088 -387.060948)
				(mid 204.923989 -387.080471)
				(end 204.935074 -387.097016)
			)
			(arc
				(start 207.491838 -389.65378)
				(mid 207.502949 -389.670314)
				(end 207.506824 -389.689848)
			)
			(arc
				(start 207.506824 -411.710124)
				(mid 207.510725 -411.729647)
				(end 207.52181 -411.746192)
			)
			(arc
				(start 208.892648 -413.11703)
				(mid 208.909182 -413.128141)
				(end 208.928716 -413.132016)
			)
		)
		(stroke
			(width 0)
			(type solid)
		)
		(fill yes)
		(layer "In11.Cu")
		(net "P12V_STBY")
	)
	(gr_poly
		(pts
			(arc
				(start 277.246842 -139.670028)
				(mid 277.27121 -139.65134)
				(end 277.28037 -139.622022)
			)
			(arc
				(start 277.241762 -135.792464)
				(mid 277.22915 -135.759468)
				(end 277.198074 -135.74268)
			)
			(arc
				(start 277.198074 -135.74268)
				(mid 276.963594 -135.615065)
				(end 276.87016 -135.364982)
			)
			(arc
				(start 276.87016 -135.364982)
				(mid 276.961077 -135.117881)
				(end 277.190454 -134.988554)
			)
			(arc
				(start 277.190454 -134.988554)
				(mid 277.221184 -134.971072)
				(end 277.233126 -134.937754)
			)
			(arc
				(start 277.223474 -133.989572)
				(mid 277.21145 -133.957506)
				(end 277.181818 -133.940296)
			)
			(arc
				(start 277.181818 -133.940296)
				(mid 276.958174 -133.809031)
				(end 276.87016 -133.565138)
			)
			(arc
				(start 276.87016 -133.565138)
				(mid 276.95586 -133.324211)
				(end 277.174452 -133.191504)
			)
			(arc
				(start 277.174452 -133.191504)
				(mid 277.203673 -133.173594)
				(end 277.214838 -133.141212)
			)
			(arc
				(start 277.20544 -132.185918)
				(mid 277.194238 -132.1546)
				(end 277.16607 -132.136896)
			)
			(arc
				(start 277.16607 -132.136896)
				(mid 276.953116 -132.002676)
				(end 276.87016 -131.76504)
			)
			(arc
				(start 276.87016 -131.76504)
				(mid 276.950731 -131.530463)
				(end 277.15845 -131.394962)
			)
			(arc
				(start 277.15845 -131.394962)
				(mid 277.186257 -131.376714)
				(end 277.196804 -131.345178)
			)
			(arc
				(start 277.187152 -130.380994)
				(mid 277.176598 -130.350499)
				(end 277.149814 -130.33248)
			)
			(arc
				(start 277.149814 -130.33248)
				(mid 276.947976 -130.19588)
				(end 276.87016 -129.964942)
			)
			(arc
				(start 276.87016 -129.964942)
				(mid 276.945782 -129.736861)
				(end 277.142702 -129.599182)
			)
			(arc
				(start 277.142702 -129.599182)
				(mid 277.168849 -129.580661)
				(end 277.17877 -129.55016)
			)
			(xy 277.146512 -126.341886) (xy 277.128986 -126.316486)
			(arc
				(start 277.123652 -126.314454)
				(mid 276.939895 -126.174955)
				(end 276.87016 -125.955044)
			)
			(arc
				(start 276.87016 -125.955044)
				(mid 276.934809 -125.742484)
				(end 277.106888 -125.601984)
			)
			(xy 277.121366 -125.596142) (xy 277.138638 -125.570234) (xy 277.128224 -124.535184) (xy 277.111714 -124.510292)
			(arc
				(start 277.102062 -124.505974)
				(mid 277.029286 -124.465025)
				(end 276.967188 -124.4092)
			)
			(arc
				(start 276.967188 -124.4092)
				(mid 276.879341 -124.238292)
				(end 276.885908 -124.046234)
			)
			(arc
				(start 276.885908 -124.046234)
				(mid 276.904707 -123.996149)
				(end 276.930358 -123.949206)
			)
			(arc
				(start 276.930358 -123.949206)
				(mid 277.003672 -123.865003)
				(end 277.098252 -123.805696)
			)
			(xy 277.099268 -123.805188) (xy 277.10511 -123.802394) (xy 277.120604 -123.777502)
			(arc
				(start 277.11019 -122.74169)
				(mid 277.102501 -122.715322)
				(end 277.08225 -122.696732)
			)
			(arc
				(start 277.081996 -122.696732)
				(mid 276.927461 -122.556074)
				(end 276.87016 -122.355102)
			)
			(arc
				(start 276.87016 -122.355102)
				(mid 276.925397 -122.157305)
				(end 277.075138 -122.016774)
			)
			(xy 277.087838 -122.01017) (xy 277.10257 -121.985786) (xy 277.091902 -120.918224) (xy 277.077932 -120.894856)
			(arc
				(start 277.065994 -120.888252)
				(mid 276.92276 -120.748262)
				(end 276.87016 -120.555004)
			)
			(arc
				(start 276.87016 -120.555004)
				(mid 276.920748 -120.365093)
				(end 277.059136 -120.225566)
			)
			(arc
				(start 277.05939 -120.225566)
				(mid 277.077989 -120.206738)
				(end 277.084536 -120.181116)
			)
			(xy 277.073614 -119.107966) (xy 277.061168 -119.085614)
			(arc
				(start 277.054564 -119.08155)
				(mid 276.919446 -118.942456)
				(end 276.87016 -118.754906)
			)
			(arc
				(start 276.87016 -118.754906)
				(mid 276.916258 -118.573179)
				(end 277.043388 -118.435374)
			)
			(xy 277.05431 -118.428262) (xy 277.066248 -118.405402) (xy 277.042372 -116.006372)
			(arc
				(start 277.042372 -115.996212)
				(mid 277.050817 -115.8662)
				(end 277.076154 -115.738402)
			)
			(arc
				(start 277.292308 -114.930682)
				(mid 277.288442 -114.894268)
				(end 277.261066 -114.869976)
			)
			(arc
				(start 276.857714 -114.719862)
				(mid 276.82437 -114.719094)
				(end 276.79777 -114.739166)
			)
			(xy 276.211284 -115.617244)
			(arc
				(start 276.21103 -115.617498)
				(mid 276.206761 -115.625184)
				(end 276.203918 -115.6335)
			)
			(xy 276.020022 -116.593366) (xy 276.019768 -116.594636) (xy 276.019006 -116.601494) (xy 276.113494 -123.31319)
			(xy 276.307804 -137.120122)
			(arc
				(start 276.308312 -137.12698)
				(mid 276.315953 -137.147077)
				(end 276.331172 -137.162286)
			)
			(xy 276.357334 -137.179304)
			(arc
				(start 276.404324 -137.20953)
				(mid 276.416453 -137.214577)
				(end 276.42947 -137.216388)
			)
			(xy 276.449282 -137.212324)
			(arc
				(start 276.453854 -137.210546)
				(mid 276.540117 -137.184178)
				(end 276.629876 -137.17524)
			)
			(arc
				(start 276.630384 -137.17524)
				(mid 276.954032 -137.3093)
				(end 277.088092 -137.632948)
			)
			(arc
				(start 277.088092 -138.496548)
				(mid 276.954032 -138.820196)
				(end 276.630384 -138.954256)
			)
			(arc
				(start 276.630384 -138.954256)
				(mid 276.549762 -138.94719)
				(end 276.471634 -138.926062)
			)
			(xy 276.47138 -138.926062)
			(arc
				(start 276.471126 -138.925808)
				(mid 276.459591 -138.923164)
				(end 276.447758 -138.923268)
			)
			(xy 276.434804 -138.924792)
			(arc
				(start 276.356318 -138.980418)
				(mid 276.341451 -138.996828)
				(end 276.334982 -139.01801)
			)
			(xy 276.334728 -139.022836)
			(arc
				(start 276.342348 -139.560046)
				(mid 276.344284 -139.572956)
				(end 276.34946 -139.584938)
			)
			(xy 276.352508 -139.590526) (xy 276.361398 -139.599416)
			(arc
				(start 276.36724 -139.602972)
				(mid 276.393116 -139.619988)
				(end 276.417532 -139.63904)
			)
			(xy 276.41804 -139.639548) (xy 276.418802 -139.640056) (xy 276.419818 -139.641072) (xy 276.421596 -139.642596)
			(arc
				(start 276.422866 -139.643866)
				(mid 276.435633 -139.651445)
				(end 276.450044 -139.655042)
			)
			(xy 276.45487 -139.655296) (xy 276.522434 -139.655296)
			(arc
				(start 276.52726 -139.655042)
				(mid 276.541686 -139.651481)
				(end 276.554438 -139.643866)
			)
			(arc
				(start 276.555454 -139.64285)
				(mid 276.67228 -139.573117)
				(end 276.806152 -139.54887)
			)
			(arc
				(start 276.806152 -139.54887)
				(mid 276.972346 -139.586972)
				(end 277.105364 -139.69365)
			)
			(xy 277.106126 -139.694666) (xy 277.110698 -139.700254) (xy 277.141432 -139.708636)
		)
		(stroke
			(width 0)
			(type solid)
		)
		(fill yes)
		(layer "In11.Cu")
		(net "GND")
	)
	(gr_poly
		(pts
			(arc
				(start 393.34694 -139.670028)
				(mid 393.371308 -139.65134)
				(end 393.380468 -139.622022)
			)
			(arc
				(start 393.34186 -135.792464)
				(mid 393.329248 -135.759468)
				(end 393.298172 -135.74268)
			)
			(arc
				(start 393.298172 -135.74268)
				(mid 393.063692 -135.615065)
				(end 392.970258 -135.364982)
			)
			(arc
				(start 392.970258 -135.364982)
				(mid 393.061175 -135.117881)
				(end 393.290552 -134.988554)
			)
			(arc
				(start 393.290552 -134.988554)
				(mid 393.321282 -134.971072)
				(end 393.333224 -134.937754)
			)
			(arc
				(start 393.323572 -133.989572)
				(mid 393.311548 -133.957506)
				(end 393.281916 -133.940296)
			)
			(arc
				(start 393.281916 -133.940296)
				(mid 393.058272 -133.809031)
				(end 392.970258 -133.565138)
			)
			(arc
				(start 392.970258 -133.565138)
				(mid 393.055958 -133.324211)
				(end 393.27455 -133.191504)
			)
			(arc
				(start 393.27455 -133.191504)
				(mid 393.303771 -133.173594)
				(end 393.314936 -133.141212)
			)
			(arc
				(start 393.305538 -132.185918)
				(mid 393.294336 -132.1546)
				(end 393.266168 -132.136896)
			)
			(arc
				(start 393.266168 -132.136896)
				(mid 393.053214 -132.002676)
				(end 392.970258 -131.76504)
			)
			(arc
				(start 392.970258 -131.76504)
				(mid 393.050829 -131.530463)
				(end 393.258548 -131.394962)
			)
			(arc
				(start 393.258548 -131.394962)
				(mid 393.286355 -131.376714)
				(end 393.296902 -131.345178)
			)
			(arc
				(start 393.28725 -130.380994)
				(mid 393.276696 -130.350499)
				(end 393.249912 -130.33248)
			)
			(arc
				(start 393.249912 -130.33248)
				(mid 393.048074 -130.19588)
				(end 392.970258 -129.964942)
			)
			(arc
				(start 392.970258 -129.964942)
				(mid 393.04588 -129.736861)
				(end 393.2428 -129.599182)
			)
			(arc
				(start 393.2428 -129.599182)
				(mid 393.268947 -129.580661)
				(end 393.278868 -129.55016)
			)
			(xy 393.24661 -126.341886) (xy 393.229084 -126.316486)
			(arc
				(start 393.22375 -126.314454)
				(mid 393.039993 -126.174955)
				(end 392.970258 -125.955044)
			)
			(arc
				(start 392.970258 -125.955044)
				(mid 393.034907 -125.742484)
				(end 393.206986 -125.601984)
			)
			(xy 393.221464 -125.596142) (xy 393.238736 -125.570234) (xy 393.228322 -124.535184) (xy 393.211812 -124.510292)
			(arc
				(start 393.20216 -124.505974)
				(mid 393.129384 -124.465025)
				(end 393.067286 -124.4092)
			)
			(arc
				(start 393.067286 -124.4092)
				(mid 392.979439 -124.238292)
				(end 392.986006 -124.046234)
			)
			(arc
				(start 392.986006 -124.046234)
				(mid 393.004805 -123.996149)
				(end 393.030456 -123.949206)
			)
			(arc
				(start 393.030456 -123.949206)
				(mid 393.10377 -123.865003)
				(end 393.19835 -123.805696)
			)
			(xy 393.199366 -123.805188) (xy 393.205208 -123.802394) (xy 393.220702 -123.777502)
			(arc
				(start 393.210288 -122.74169)
				(mid 393.202599 -122.715322)
				(end 393.182348 -122.696732)
			)
			(arc
				(start 393.182094 -122.696732)
				(mid 393.027559 -122.556074)
				(end 392.970258 -122.355102)
			)
			(arc
				(start 392.970258 -122.355102)
				(mid 393.025495 -122.157305)
				(end 393.175236 -122.016774)
			)
			(xy 393.187936 -122.01017) (xy 393.202668 -121.985786) (xy 393.192 -120.918224) (xy 393.17803 -120.894856)
			(arc
				(start 393.166092 -120.888252)
				(mid 393.022858 -120.748262)
				(end 392.970258 -120.555004)
			)
			(arc
				(start 392.970258 -120.555004)
				(mid 393.020846 -120.365093)
				(end 393.159234 -120.225566)
			)
			(arc
				(start 393.159488 -120.225566)
				(mid 393.178087 -120.206738)
				(end 393.184634 -120.181116)
			)
			(xy 393.173712 -119.107966) (xy 393.161266 -119.085614)
			(arc
				(start 393.154662 -119.08155)
				(mid 393.019544 -118.942456)
				(end 392.970258 -118.754906)
			)
			(arc
				(start 392.970258 -118.754906)
				(mid 393.016356 -118.573179)
				(end 393.143486 -118.435374)
			)
			(xy 393.154408 -118.428262) (xy 393.166346 -118.405402) (xy 393.14247 -116.006372) (xy 393.142216 -115.99672)
			(arc
				(start 393.142216 -115.995704)
				(mid 393.150826 -115.865941)
				(end 393.176252 -115.738402)
			)
			(arc
				(start 393.367006 -115.025678)
				(mid 393.363269 -114.989516)
				(end 393.336272 -114.965226)
			)
			(arc
				(start 392.907266 -114.797332)
				(mid 392.873546 -114.796146)
				(end 392.84656 -114.816382)
			)
			(xy 392.311382 -115.617244)
			(arc
				(start 392.311128 -115.617498)
				(mid 392.306859 -115.625184)
				(end 392.304016 -115.6335)
			)
			(xy 392.12012 -116.593366) (xy 392.119866 -116.594636) (xy 392.119104 -116.601494) (xy 392.213592 -123.31319)
			(xy 392.407902 -137.12063)
			(arc
				(start 392.40841 -137.127488)
				(mid 392.416051 -137.147585)
				(end 392.43127 -137.162794)
			)
			(xy 392.457432 -137.179812)
			(arc
				(start 392.504422 -137.210038)
				(mid 392.516551 -137.215085)
				(end 392.529568 -137.216896)
			)
			(xy 392.54938 -137.212832)
			(arc
				(start 392.553952 -137.211054)
				(mid 392.640464 -137.184636)
				(end 392.730482 -137.175748)
			)
			(arc
				(start 392.74115 -137.175494)
				(mid 393.058059 -137.313243)
				(end 393.188444 -137.633202)
			)
			(arc
				(start 393.188444 -138.497056)
				(mid 393.054295 -138.820794)
				(end 392.730482 -138.954764)
			)
			(arc
				(start 392.730482 -138.954764)
				(mid 392.64986 -138.947698)
				(end 392.571732 -138.92657)
			)
			(xy 392.571478 -138.92657)
			(arc
				(start 392.571224 -138.926316)
				(mid 392.559689 -138.923672)
				(end 392.547856 -138.923776)
			)
			(xy 392.534902 -138.9253)
			(arc
				(start 392.456416 -138.980926)
				(mid 392.441549 -138.997336)
				(end 392.43508 -139.018518)
			)
			(xy 392.434826 -139.023344)
			(arc
				(start 392.442446 -139.560046)
				(mid 392.444382 -139.572956)
				(end 392.449558 -139.584938)
			)
			(xy 392.452606 -139.590526) (xy 392.461496 -139.599416)
			(arc
				(start 392.467338 -139.602972)
				(mid 392.493214 -139.619988)
				(end 392.51763 -139.63904)
			)
			(xy 392.518138 -139.639548) (xy 392.5189 -139.640056) (xy 392.519916 -139.641072) (xy 392.521694 -139.642596)
			(arc
				(start 392.522964 -139.643866)
				(mid 392.535731 -139.651445)
				(end 392.550142 -139.655042)
			)
			(xy 392.554968 -139.655296) (xy 392.622532 -139.655296)
			(arc
				(start 392.627358 -139.655042)
				(mid 392.641784 -139.651481)
				(end 392.654536 -139.643866)
			)
			(arc
				(start 392.655552 -139.64285)
				(mid 392.772378 -139.573117)
				(end 392.90625 -139.54887)
			)
			(arc
				(start 392.90625 -139.54887)
				(mid 393.072444 -139.586972)
				(end 393.205462 -139.69365)
			)
			(xy 393.206224 -139.694666) (xy 393.210796 -139.700254) (xy 393.24153 -139.708636)
		)
		(stroke
			(width 0)
			(type solid)
		)
		(fill yes)
		(layer "In11.Cu")
		(net "GND")
	)
	(gr_poly
		(pts
			(arc
				(start 45.0469 -139.670028)
				(mid 45.071268 -139.65134)
				(end 45.080428 -139.622022)
			)
			(arc
				(start 45.04182 -135.792464)
				(mid 45.029208 -135.759468)
				(end 44.998132 -135.74268)
			)
			(arc
				(start 44.998132 -135.74268)
				(mid 44.763652 -135.615065)
				(end 44.670218 -135.364982)
			)
			(arc
				(start 44.670218 -135.364982)
				(mid 44.761135 -135.117881)
				(end 44.990512 -134.988554)
			)
			(arc
				(start 44.990512 -134.988554)
				(mid 45.021242 -134.971072)
				(end 45.033184 -134.937754)
			)
			(arc
				(start 45.023532 -133.989572)
				(mid 45.011508 -133.957506)
				(end 44.981876 -133.940296)
			)
			(arc
				(start 44.981876 -133.940296)
				(mid 44.758232 -133.809031)
				(end 44.670218 -133.565138)
			)
			(arc
				(start 44.670218 -133.565138)
				(mid 44.755918 -133.324211)
				(end 44.97451 -133.191504)
			)
			(arc
				(start 44.97451 -133.191504)
				(mid 45.003731 -133.173594)
				(end 45.014896 -133.141212)
			)
			(arc
				(start 45.005498 -132.185918)
				(mid 44.994296 -132.1546)
				(end 44.966128 -132.136896)
			)
			(arc
				(start 44.966128 -132.136896)
				(mid 44.753174 -132.002676)
				(end 44.670218 -131.76504)
			)
			(arc
				(start 44.670218 -131.76504)
				(mid 44.750789 -131.530463)
				(end 44.958508 -131.394962)
			)
			(arc
				(start 44.958508 -131.394962)
				(mid 44.986315 -131.376714)
				(end 44.996862 -131.345178)
			)
			(arc
				(start 44.98721 -130.380994)
				(mid 44.976656 -130.350499)
				(end 44.949872 -130.33248)
			)
			(arc
				(start 44.949872 -130.33248)
				(mid 44.748034 -130.19588)
				(end 44.670218 -129.964942)
			)
			(arc
				(start 44.670218 -129.964942)
				(mid 44.74584 -129.736861)
				(end 44.94276 -129.599182)
			)
			(arc
				(start 44.94276 -129.599182)
				(mid 44.968907 -129.580661)
				(end 44.978828 -129.55016)
			)
			(xy 44.94657 -126.341886) (xy 44.929044 -126.316486)
			(arc
				(start 44.92371 -126.314454)
				(mid 44.739953 -126.174955)
				(end 44.670218 -125.955044)
			)
			(arc
				(start 44.670218 -125.951234)
				(mid 44.679295 -125.872229)
				(end 44.704508 -125.796802)
			)
			(arc
				(start 44.704508 -125.796802)
				(mid 44.787149 -125.68009)
				(end 44.906946 -125.601984)
			)
			(xy 44.921424 -125.596142) (xy 44.938696 -125.570234) (xy 44.928282 -124.535184) (xy 44.911772 -124.510292)
			(arc
				(start 44.90212 -124.505974)
				(mid 44.829344 -124.465025)
				(end 44.767246 -124.4092)
			)
			(arc
				(start 44.767246 -124.4092)
				(mid 44.679399 -124.238292)
				(end 44.685966 -124.046234)
			)
			(arc
				(start 44.685966 -124.046234)
				(mid 44.704765 -123.996149)
				(end 44.730416 -123.949206)
			)
			(arc
				(start 44.730416 -123.949206)
				(mid 44.80373 -123.865003)
				(end 44.89831 -123.805696)
			)
			(xy 44.899326 -123.805188) (xy 44.905168 -123.802394) (xy 44.920662 -123.777502)
			(arc
				(start 44.910248 -122.74169)
				(mid 44.902559 -122.715322)
				(end 44.882308 -122.696732)
			)
			(arc
				(start 44.882054 -122.696732)
				(mid 44.727519 -122.556074)
				(end 44.670218 -122.355102)
			)
			(arc
				(start 44.670218 -122.355102)
				(mid 44.725455 -122.157305)
				(end 44.875196 -122.016774)
			)
			(xy 44.887896 -122.01017) (xy 44.902628 -121.985786) (xy 44.89196 -120.918224) (xy 44.87799 -120.894856)
			(arc
				(start 44.866052 -120.888252)
				(mid 44.722818 -120.748262)
				(end 44.670218 -120.555004)
			)
			(arc
				(start 44.670218 -120.555004)
				(mid 44.671017 -120.529549)
				(end 44.67352 -120.504204)
			)
			(arc
				(start 44.67352 -120.504204)
				(mid 44.734152 -120.343421)
				(end 44.859194 -120.225566)
			)
			(arc
				(start 44.859448 -120.225566)
				(mid 44.878047 -120.206738)
				(end 44.884594 -120.181116)
			)
			(xy 44.873672 -119.107966) (xy 44.861226 -119.085614)
			(arc
				(start 44.854622 -119.08155)
				(mid 44.719504 -118.942456)
				(end 44.670218 -118.754906)
			)
			(arc
				(start 44.670218 -118.754906)
				(mid 44.716316 -118.573179)
				(end 44.843446 -118.435374)
			)
			(xy 44.854368 -118.428262) (xy 44.866306 -118.405402) (xy 44.84243 -116.006372) (xy 44.842176 -115.99672)
			(arc
				(start 44.842176 -115.995704)
				(mid 44.850786 -115.865941)
				(end 44.876212 -115.738402)
			)
			(arc
				(start 45.038772 -115.130326)
				(mid 45.038681 -115.104078)
				(end 45.025564 -115.081304)
			)
			(arc
				(start 44.848272 -114.904012)
				(mid 44.831738 -114.892901)
				(end 44.812204 -114.889026)
			)
			(arc
				(start 44.525184 -114.889026)
				(mid 44.501245 -114.89502)
				(end 44.48302 -114.911632)
			)
			(xy 44.011342 -115.617244)
			(arc
				(start 44.011088 -115.617498)
				(mid 44.006819 -115.625184)
				(end 44.003976 -115.6335)
			)
			(xy 43.82008 -116.593366) (xy 43.819826 -116.594636) (xy 43.819064 -116.601494) (xy 43.913552 -123.31319)
			(xy 44.107862 -137.120122)
			(arc
				(start 44.10837 -137.12698)
				(mid 44.116011 -137.147077)
				(end 44.13123 -137.162286)
			)
			(xy 44.157392 -137.179304)
			(arc
				(start 44.204382 -137.20953)
				(mid 44.216511 -137.214577)
				(end 44.229528 -137.216388)
			)
			(xy 44.24934 -137.212324)
			(arc
				(start 44.253912 -137.210546)
				(mid 44.340424 -137.184128)
				(end 44.430442 -137.17524)
			)
			(arc
				(start 44.44111 -137.174986)
				(mid 44.758019 -137.312735)
				(end 44.888404 -137.632694)
			)
			(arc
				(start 44.888404 -138.496548)
				(mid 44.754255 -138.820286)
				(end 44.430442 -138.954256)
			)
			(arc
				(start 44.430442 -138.954256)
				(mid 44.34982 -138.94719)
				(end 44.271692 -138.926062)
			)
			(xy 44.271438 -138.926062)
			(arc
				(start 44.271184 -138.925808)
				(mid 44.259649 -138.923164)
				(end 44.247816 -138.923268)
			)
			(xy 44.234862 -138.924792)
			(arc
				(start 44.156376 -138.980418)
				(mid 44.141509 -138.996828)
				(end 44.13504 -139.01801)
			)
			(xy 44.134786 -139.022836)
			(arc
				(start 44.142406 -139.560046)
				(mid 44.144342 -139.572956)
				(end 44.149518 -139.584938)
			)
			(xy 44.152566 -139.590526) (xy 44.161456 -139.599416)
			(arc
				(start 44.167298 -139.602972)
				(mid 44.193174 -139.619988)
				(end 44.21759 -139.63904)
			)
			(xy 44.218098 -139.639548) (xy 44.21886 -139.640056) (xy 44.219876 -139.641072) (xy 44.221654 -139.642596)
			(arc
				(start 44.222924 -139.643866)
				(mid 44.235691 -139.651445)
				(end 44.250102 -139.655042)
			)
			(xy 44.254928 -139.655296) (xy 44.322492 -139.655296)
			(arc
				(start 44.327318 -139.655042)
				(mid 44.341744 -139.651481)
				(end 44.354496 -139.643866)
			)
			(arc
				(start 44.355512 -139.64285)
				(mid 44.472338 -139.573117)
				(end 44.60621 -139.54887)
			)
			(arc
				(start 44.60621 -139.54887)
				(mid 44.772404 -139.586972)
				(end 44.905422 -139.69365)
			)
			(xy 44.906184 -139.694666) (xy 44.910756 -139.700254) (xy 44.94149 -139.708636)
		)
		(stroke
			(width 0)
			(type solid)
		)
		(fill yes)
		(layer "In11.Cu")
		(net "GND")
	)
	(gr_poly
		(pts
			(arc
				(start 161.146998 -139.670282)
				(mid 161.171366 -139.651594)
				(end 161.180526 -139.622276)
			)
			(arc
				(start 161.141918 -135.792464)
				(mid 161.129306 -135.759468)
				(end 161.09823 -135.74268)
			)
			(arc
				(start 161.09823 -135.74268)
				(mid 160.863605 -135.615137)
				(end 160.770062 -135.364982)
			)
			(arc
				(start 160.770062 -135.364982)
				(mid 160.86106 -135.117785)
				(end 161.09061 -134.988554)
			)
			(arc
				(start 161.09061 -134.988554)
				(mid 161.12134 -134.971072)
				(end 161.133282 -134.937754)
			)
			(arc
				(start 161.12363 -133.989826)
				(mid 161.111685 -133.957605)
				(end 161.081974 -133.940296)
			)
			(arc
				(start 161.081974 -133.940296)
				(mid 160.858191 -133.809097)
				(end 160.770062 -133.565138)
			)
			(arc
				(start 160.770062 -133.565138)
				(mid 160.85584 -133.324115)
				(end 161.074608 -133.191504)
			)
			(arc
				(start 161.074608 -133.191504)
				(mid 161.103829 -133.173594)
				(end 161.114994 -133.141212)
			)
			(arc
				(start 161.105596 -132.185918)
				(mid 161.094317 -132.154504)
				(end 161.065972 -132.136896)
			)
			(arc
				(start 161.065972 -132.136896)
				(mid 160.853018 -132.002676)
				(end 160.770062 -131.76504)
			)
			(arc
				(start 160.770062 -131.76504)
				(mid 160.850731 -131.530425)
				(end 161.058606 -131.394962)
			)
			(arc
				(start 161.058606 -131.394962)
				(mid 161.086413 -131.376714)
				(end 161.09696 -131.345178)
			)
			(arc
				(start 161.087308 -130.380994)
				(mid 161.076679 -130.350651)
				(end 161.04997 -130.332734)
			)
			(arc
				(start 161.04997 -130.332734)
				(mid 160.847958 -130.196055)
				(end 160.770062 -129.964942)
			)
			(arc
				(start 160.770062 -129.964942)
				(mid 160.845684 -129.736861)
				(end 161.042604 -129.599182)
			)
			(arc
				(start 161.042604 -129.599182)
				(mid 161.068874 -129.580715)
				(end 161.078926 -129.55016)
			)
			(arc
				(start 161.046668 -126.358142)
				(mid 161.037606 -126.329687)
				(end 161.014156 -126.311152)
			)
			(arc
				(start 161.014156 -126.311152)
				(mid 160.836922 -126.17092)
				(end 160.770062 -125.955044)
			)
			(arc
				(start 160.770062 -125.955044)
				(mid 160.835567 -125.741213)
				(end 161.009584 -125.600714)
			)
			(xy 161.010092 -125.600714) (xy 161.021776 -125.595888) (xy 161.038794 -125.56998) (xy 161.02838 -124.535438)
			(xy 161.01187 -124.510546)
			(arc
				(start 160.998154 -124.50445)
				(mid 160.832107 -124.363629)
				(end 160.770062 -124.154946)
			)
			(arc
				(start 160.770062 -124.154946)
				(mid 160.830093 -123.949518)
				(end 160.991296 -123.808744)
			)
			(xy 161.004758 -123.802394) (xy 161.02076 -123.777248) (xy 161.010346 -122.727466) (xy 160.995106 -122.703336)
			(arc
				(start 160.982152 -122.696986)
				(mid 160.839718 -122.574956)
				(end 160.772602 -122.399806)
			)
			(xy 160.771078 -122.38609)
			(arc
				(start 160.769808 -122.355102)
				(mid 160.825192 -122.157062)
				(end 160.975294 -122.01652)
			)
			(arc
				(start 160.975294 -122.01652)
				(mid 160.995463 -121.997665)
				(end 161.002726 -121.971054)
			)
			(arc
				(start 160.992058 -120.932194)
				(mid 160.985052 -120.906704)
				(end 160.96615 -120.888252)
			)
			(arc
				(start 160.965896 -120.888252)
				(mid 160.822662 -120.748262)
				(end 160.770062 -120.555004)
			)
			(arc
				(start 160.770062 -120.555004)
				(mid 160.821969 -120.362742)
				(end 160.96361 -120.222772)
			)
			(xy 160.964118 -120.222772) (xy 160.97123 -120.218454) (xy 160.984692 -120.194832) (xy 160.97377 -119.10822)
			(xy 160.96107 -119.085614)
			(arc
				(start 160.949894 -119.078756)
				(mid 160.818033 -118.940122)
				(end 160.770062 -118.754906)
			)
			(arc
				(start 160.770062 -118.754906)
				(mid 160.770861 -118.729451)
				(end 160.773364 -118.704106)
			)
			(arc
				(start 160.773364 -118.704106)
				(mid 160.828969 -118.551071)
				(end 160.94329 -118.43512)
			)
			(arc
				(start 160.94329 -118.43512)
				(mid 160.960422 -118.416505)
				(end 160.966404 -118.39194)
			)
			(xy 160.942528 -116.006372)
			(arc
				(start 160.942528 -115.996212)
				(mid 160.950973 -115.8662)
				(end 160.97631 -115.738402)
			)
			(arc
				(start 161.192972 -114.927888)
				(mid 161.194029 -114.906332)
				(end 161.186114 -114.886232)
			)
			(xy 161.179764 -114.877088) (xy 161.161222 -114.865658)
			(arc
				(start 160.68548 -114.808254)
				(mid 160.658247 -114.812506)
				(end 160.63722 -114.830352)
			)
			(xy 160.11144 -115.617244)
			(arc
				(start 160.111186 -115.617498)
				(mid 160.106917 -115.625184)
				(end 160.104074 -115.6335)
			)
			(xy 159.920178 -116.593366) (xy 159.919924 -116.594636) (xy 159.919162 -116.601494) (xy 160.01365 -123.31319)
			(arc
				(start 160.208214 -137.12317)
				(mid 160.209509 -137.131733)
				(end 160.212278 -137.139934)
			)
			(xy 160.214564 -137.144252)
			(arc
				(start 160.21939 -137.151364)
				(mid 160.224914 -137.157312)
				(end 160.231328 -137.162286)
			)
			(xy 160.272476 -137.188956)
			(arc
				(start 160.303464 -137.209022)
				(mid 160.316163 -137.214539)
				(end 160.32988 -137.216388)
			)
			(xy 160.345374 -137.213086)
			(arc
				(start 160.35401 -137.210292)
				(mid 160.440035 -137.184084)
				(end 160.529524 -137.17524)
			)
			(xy 160.529778 -137.17524) (xy 160.537398 -137.174986)
			(arc
				(start 160.537652 -137.174986)
				(mid 160.856661 -137.311602)
				(end 160.988248 -137.632694)
			)
			(arc
				(start 160.988248 -138.496548)
				(mid 160.854099 -138.820286)
				(end 160.530286 -138.954256)
			)
			(arc
				(start 160.530286 -138.954256)
				(mid 160.449793 -138.947168)
				(end 160.37179 -138.926062)
			)
			(arc
				(start 160.371536 -138.926062)
				(mid 160.348156 -138.923285)
				(end 160.32607 -138.931396)
			)
			(arc
				(start 160.256474 -138.980672)
				(mid 160.241607 -138.997082)
				(end 160.235138 -139.018264)
			)
			(xy 160.234884 -139.02309)
			(arc
				(start 160.242504 -139.5603)
				(mid 160.24444 -139.57321)
				(end 160.249616 -139.585192)
			)
			(arc
				(start 160.249616 -139.585446)
				(mid 160.257189 -139.595253)
				(end 160.266888 -139.602972)
			)
			(arc
				(start 160.267142 -139.603226)
				(mid 160.295327 -139.621826)
				(end 160.321752 -139.64285)
			)
			(arc
				(start 160.322768 -139.643866)
				(mid 160.335535 -139.651445)
				(end 160.349946 -139.655042)
			)
			(xy 160.354772 -139.655296) (xy 160.422336 -139.655296)
			(arc
				(start 160.427162 -139.655042)
				(mid 160.441588 -139.651481)
				(end 160.45434 -139.643866)
			)
			(arc
				(start 160.455356 -139.64285)
				(mid 160.572182 -139.573117)
				(end 160.706054 -139.54887)
			)
			(arc
				(start 160.706054 -139.54887)
				(mid 160.871516 -139.586618)
				(end 161.00425 -139.69238)
			)
			(xy 161.004758 -139.692888) (xy 161.010854 -139.700508) (xy 161.041588 -139.70889)
		)
		(stroke
			(width 0)
			(type solid)
		)
		(fill yes)
		(layer "In11.Cu")
		(net "GND")
	)
	(gr_poly
		(pts
			(xy 248.200164 -321.435222) (xy 248.207276 -321.427856) (xy 248.538238 -321.096894) (xy 248.54509 -321.089498)
			(xy 248.552832 -321.070899) (xy 248.553224 -321.060826) (xy 248.553224 -310.68518) (xy 248.552747 -310.675214)
			(xy 248.545174 -310.656775) (xy 248.538492 -310.649366) (xy 248.480834 -310.5912) (xy 248.462546 -310.58358)
			(xy 248.452386 -310.58358) (xy 248.425254 -310.582923) (xy 248.371582 -310.574878) (xy 248.319593 -310.559307)
			(xy 248.270334 -310.536526) (xy 248.224802 -310.506993) (xy 248.183914 -310.471306) (xy 248.148497 -310.430184)
			(xy 248.119265 -310.384458) (xy 248.096809 -310.33505) (xy 248.081581 -310.282959) (xy 248.07389 -310.229235)
			(xy 248.07389 -310.174964) (xy 248.081581 -310.121241) (xy 248.096809 -310.069149) (xy 248.119265 -310.019742)
			(xy 248.148497 -309.974016) (xy 248.183914 -309.932894) (xy 248.224802 -309.897207) (xy 248.270335 -309.867674)
			(xy 248.319593 -309.844893) (xy 248.371583 -309.829322) (xy 248.425254 -309.821277) (xy 248.452386 -309.820564)
			(xy 248.462546 -309.820564) (xy 248.480834 -309.812944) (xy 248.538492 -309.754778) (xy 248.545173 -309.747368)
			(xy 248.552749 -309.728931) (xy 248.553224 -309.718964) (xy 248.553224 -308.977284) (xy 248.52884 -308.948836)
			(xy 248.510044 -308.946042) (xy 248.483358 -308.941463) (xy 248.431543 -308.925757) (xy 248.382469 -308.902884)
			(xy 248.33712 -308.873304) (xy 248.296409 -308.83761) (xy 248.261151 -308.79652) (xy 248.232056 -308.750859)
			(xy 248.209708 -308.701543) (xy 248.194556 -308.649564) (xy 248.186903 -308.595964) (xy 248.186904 -308.541821)
			(xy 248.194559 -308.488222) (xy 248.209713 -308.436243) (xy 248.232063 -308.386928) (xy 248.26116 -308.341268)
			(xy 248.296419 -308.300179) (xy 248.337132 -308.264487) (xy 248.382482 -308.234909) (xy 248.431557 -308.212038)
			(xy 248.483373 -308.196334) (xy 248.510044 -308.191662) (xy 248.52884 -308.188868) (xy 248.553224 -308.16042)
			(xy 248.553224 -307.892704) (xy 248.52884 -307.864256) (xy 248.510044 -307.861462) (xy 248.483352 -307.856893)
			(xy 248.431522 -307.841202) (xy 248.382434 -307.818337) (xy 248.337073 -307.788758) (xy 248.296353 -307.75306)
			(xy 248.261092 -307.71196) (xy 248.232 -307.666286) (xy 248.209661 -307.616955) (xy 248.194526 -307.564961)
			(xy 248.186897 -307.511349) (xy 248.186448 -307.484272) (xy 248.18697 -307.45487) (xy 248.195953 -307.396757)
			(xy 248.213747 -307.340712) (xy 248.239931 -307.28806) (xy 248.273885 -307.240051) (xy 248.314804 -307.197821)
			(xy 248.361719 -307.16237) (xy 248.387362 -307.147976) (xy 248.39803 -307.142388) (xy 248.412 -307.122576)
			(xy 248.425462 -307.03012) (xy 248.42662 -307.018238) (xy 248.4192 -306.995581) (xy 248.411238 -306.986686)
			(xy 245.784116 -304.359564) (xy 245.776716 -304.352724) (xy 245.758117 -304.34501) (xy 245.748048 -304.344578)
			(xy 235.326174 -304.344578) (xy 235.316105 -304.345005) (xy 235.297506 -304.352724) (xy 235.290106 -304.359564)
			(xy 234.49026 -305.15941) (xy 234.483408 -305.166806) (xy 234.475668 -305.185405) (xy 234.475274 -305.195478)
			(xy 234.475274 -306.744116) (xy 238.199674 -306.744116) (xy 238.203745 -306.688494) (xy 238.215871 -306.634057)
			(xy 238.235794 -306.581966) (xy 238.26309 -306.533331) (xy 238.297176 -306.489188) (xy 238.337325 -306.450479)
			(xy 238.382683 -306.418028) (xy 238.432283 -306.392527) (xy 238.485067 -306.37452) (xy 238.53991 -306.36439)
			(xy 238.595644 -306.362353) (xy 238.651081 -306.368453) (xy 238.705038 -306.382559) (xy 238.756367 -306.404371)
			(xy 238.803973 -306.433425) (xy 238.846841 -306.4691) (xy 238.884058 -306.510637) (xy 238.914831 -306.55715)
			(xy 238.938503 -306.607647) (xy 238.954571 -306.661054) (xy 238.962691 -306.71623) (xy 238.9632 -306.744116)
			(xy 238.962691 -306.772002) (xy 238.960478 -306.787042) (xy 245.473726 -306.787042) (xy 245.477797 -306.73142)
			(xy 245.489923 -306.676983) (xy 245.509846 -306.624892) (xy 245.537142 -306.576257) (xy 245.571228 -306.532114)
			(xy 245.611377 -306.493405) (xy 245.656735 -306.460954) (xy 245.706335 -306.435453) (xy 245.759119 -306.417446)
			(xy 245.813962 -306.407316) (xy 245.869696 -306.405279) (xy 245.925133 -306.411379) (xy 245.97909 -306.425485)
			(xy 246.030419 -306.447297) (xy 246.078025 -306.476351) (xy 246.120893 -306.512026) (xy 246.15811 -306.553563)
			(xy 246.188883 -306.600076) (xy 246.212555 -306.650573) (xy 246.228623 -306.70398) (xy 246.236743 -306.759156)
			(xy 246.237252 -306.787042) (xy 246.236743 -306.814928) (xy 246.228623 -306.870104) (xy 246.212555 -306.923511)
			(xy 246.188883 -306.974008) (xy 246.15811 -307.020521) (xy 246.120893 -307.062058) (xy 246.078025 -307.097733)
			(xy 246.030419 -307.126787) (xy 245.97909 -307.148599) (xy 245.925133 -307.162705) (xy 245.869696 -307.168805)
			(xy 245.813962 -307.166768) (xy 245.759119 -307.156638) (xy 245.706335 -307.138631) (xy 245.656735 -307.11313)
			(xy 245.611377 -307.080679) (xy 245.571228 -307.04197) (xy 245.537142 -306.997827) (xy 245.509846 -306.949192)
			(xy 245.489923 -306.897101) (xy 245.477797 -306.842664) (xy 245.473726 -306.787042) (xy 238.960478 -306.787042)
			(xy 238.954571 -306.827178) (xy 238.938503 -306.880585) (xy 238.914831 -306.931082) (xy 238.884058 -306.977595)
			(xy 238.846841 -307.019132) (xy 238.803973 -307.054807) (xy 238.756367 -307.083861) (xy 238.705038 -307.105673)
			(xy 238.651081 -307.119779) (xy 238.595644 -307.125879) (xy 238.53991 -307.123842) (xy 238.485067 -307.113712)
			(xy 238.432283 -307.095705) (xy 238.382683 -307.070204) (xy 238.337325 -307.037753) (xy 238.297176 -306.999044)
			(xy 238.26309 -306.954901) (xy 238.235794 -306.906266) (xy 238.215871 -306.854175) (xy 238.203745 -306.799738)
			(xy 238.199674 -306.744116) (xy 234.475274 -306.744116) (xy 234.475274 -307.446426) (xy 243.125242 -307.446426)
			(xy 243.129313 -307.390804) (xy 243.141439 -307.336367) (xy 243.161362 -307.284276) (xy 243.188658 -307.235641)
			(xy 243.222744 -307.191498) (xy 243.262893 -307.152789) (xy 243.308251 -307.120338) (xy 243.357851 -307.094837)
			(xy 243.410635 -307.07683) (xy 243.465478 -307.0667) (xy 243.521212 -307.064663) (xy 243.576649 -307.070763)
			(xy 243.630606 -307.084869) (xy 243.681935 -307.106681) (xy 243.729541 -307.135735) (xy 243.772409 -307.17141)
			(xy 243.809626 -307.212947) (xy 243.840399 -307.25946) (xy 243.864071 -307.309957) (xy 243.880139 -307.363364)
			(xy 243.888259 -307.41854) (xy 243.888768 -307.446426) (xy 243.888259 -307.474312) (xy 243.880139 -307.529488)
			(xy 243.864071 -307.582895) (xy 243.840399 -307.633392) (xy 243.809626 -307.679905) (xy 243.772409 -307.721442)
			(xy 243.729541 -307.757117) (xy 243.681935 -307.786171) (xy 243.630606 -307.807983) (xy 243.576649 -307.822089)
			(xy 243.521212 -307.828189) (xy 243.465478 -307.826152) (xy 243.410635 -307.816022) (xy 243.357851 -307.798015)
			(xy 243.308251 -307.772514) (xy 243.262893 -307.740063) (xy 243.222744 -307.701354) (xy 243.188658 -307.657211)
			(xy 243.161362 -307.608576) (xy 243.141439 -307.556485) (xy 243.129313 -307.502048) (xy 243.125242 -307.446426)
			(xy 234.475274 -307.446426) (xy 234.475274 -308.402228) (xy 244.183152 -308.402228) (xy 244.187223 -308.346606)
			(xy 244.199349 -308.292169) (xy 244.219272 -308.240078) (xy 244.246568 -308.191443) (xy 244.280654 -308.1473)
			(xy 244.320803 -308.108591) (xy 244.366161 -308.07614) (xy 244.415761 -308.050639) (xy 244.468545 -308.032632)
			(xy 244.523388 -308.022502) (xy 244.579122 -308.020465) (xy 244.634559 -308.026565) (xy 244.688516 -308.040671)
			(xy 244.739845 -308.062483) (xy 244.787451 -308.091537) (xy 244.830319 -308.127212) (xy 244.867536 -308.168749)
			(xy 244.898309 -308.215262) (xy 244.921981 -308.265759) (xy 244.938049 -308.319166) (xy 244.946169 -308.374342)
			(xy 244.946678 -308.402228) (xy 244.946169 -308.430114) (xy 244.938049 -308.48529) (xy 244.921981 -308.538697)
			(xy 244.898309 -308.589194) (xy 244.867536 -308.635707) (xy 244.830319 -308.677244) (xy 244.787451 -308.712919)
			(xy 244.739845 -308.741973) (xy 244.688516 -308.763785) (xy 244.634559 -308.777891) (xy 244.579122 -308.783991)
			(xy 244.523388 -308.781954) (xy 244.468545 -308.771824) (xy 244.415761 -308.753817) (xy 244.366161 -308.728316)
			(xy 244.320803 -308.695865) (xy 244.280654 -308.657156) (xy 244.246568 -308.613013) (xy 244.219272 -308.564378)
			(xy 244.199349 -308.512287) (xy 244.187223 -308.45785) (xy 244.183152 -308.402228) (xy 234.475274 -308.402228)
			(xy 234.475274 -309.018178) (xy 246.191276 -309.018178) (xy 246.195347 -308.962556) (xy 246.207473 -308.908119)
			(xy 246.227396 -308.856028) (xy 246.254692 -308.807393) (xy 246.288778 -308.76325) (xy 246.328927 -308.724541)
			(xy 246.374285 -308.69209) (xy 246.423885 -308.666589) (xy 246.476669 -308.648582) (xy 246.531512 -308.638452)
			(xy 246.587246 -308.636415) (xy 246.642683 -308.642515) (xy 246.69664 -308.656621) (xy 246.747969 -308.678433)
			(xy 246.795575 -308.707487) (xy 246.838443 -308.743162) (xy 246.87566 -308.784699) (xy 246.906433 -308.831212)
			(xy 246.930105 -308.881709) (xy 246.946173 -308.935116) (xy 246.954293 -308.990292) (xy 246.954802 -309.018178)
			(xy 246.954293 -309.046064) (xy 246.946173 -309.10124) (xy 246.930105 -309.154647) (xy 246.906433 -309.205144)
			(xy 246.87566 -309.251657) (xy 246.838443 -309.293194) (xy 246.795575 -309.328869) (xy 246.747969 -309.357923)
			(xy 246.69664 -309.379735) (xy 246.642683 -309.393841) (xy 246.587246 -309.399941) (xy 246.531512 -309.397904)
			(xy 246.476669 -309.387774) (xy 246.423885 -309.369767) (xy 246.374285 -309.344266) (xy 246.328927 -309.311815)
			(xy 246.288778 -309.273106) (xy 246.254692 -309.228963) (xy 246.227396 -309.180328) (xy 246.207473 -309.128237)
			(xy 246.195347 -309.0738) (xy 246.191276 -309.018178) (xy 234.475274 -309.018178) (xy 234.475274 -309.908448)
			(xy 242.571268 -309.908448) (xy 242.575339 -309.852826) (xy 242.587465 -309.798389) (xy 242.607388 -309.746298)
			(xy 242.634684 -309.697663) (xy 242.66877 -309.65352) (xy 242.708919 -309.614811) (xy 242.754277 -309.58236)
			(xy 242.803877 -309.556859) (xy 242.856661 -309.538852) (xy 242.911504 -309.528722) (xy 242.967238 -309.526685)
			(xy 243.022675 -309.532785) (xy 243.076632 -309.546891) (xy 243.127961 -309.568703) (xy 243.175567 -309.597757)
			(xy 243.218435 -309.633432) (xy 243.255652 -309.674969) (xy 243.286425 -309.721482) (xy 243.297509 -309.745126)
			(xy 244.286784 -309.745126) (xy 244.290855 -309.689504) (xy 244.302981 -309.635067) (xy 244.322904 -309.582976)
			(xy 244.3502 -309.534341) (xy 244.384286 -309.490198) (xy 244.424435 -309.451489) (xy 244.469793 -309.419038)
			(xy 244.519393 -309.393537) (xy 244.572177 -309.37553) (xy 244.62702 -309.3654) (xy 244.682754 -309.363363)
			(xy 244.738191 -309.369463) (xy 244.792148 -309.383569) (xy 244.843477 -309.405381) (xy 244.891083 -309.434435)
			(xy 244.933951 -309.47011) (xy 244.971168 -309.511647) (xy 245.001941 -309.55816) (xy 245.025613 -309.608657)
			(xy 245.041681 -309.662064) (xy 245.049801 -309.71724) (xy 245.05031 -309.745126) (xy 245.049801 -309.773012)
			(xy 245.041681 -309.828188) (xy 245.025613 -309.881595) (xy 245.001941 -309.932092) (xy 244.971168 -309.978605)
			(xy 244.933951 -310.020142) (xy 244.891083 -310.055817) (xy 244.843477 -310.084871) (xy 244.792148 -310.106683)
			(xy 244.738191 -310.120789) (xy 244.682754 -310.126889) (xy 244.62702 -310.124852) (xy 244.572177 -310.114722)
			(xy 244.519393 -310.096715) (xy 244.469793 -310.071214) (xy 244.424435 -310.038763) (xy 244.384286 -310.000054)
			(xy 244.3502 -309.955911) (xy 244.322904 -309.907276) (xy 244.302981 -309.855185) (xy 244.290855 -309.800748)
			(xy 244.286784 -309.745126) (xy 243.297509 -309.745126) (xy 243.310097 -309.771979) (xy 243.326165 -309.825386)
			(xy 243.334285 -309.880562) (xy 243.334794 -309.908448) (xy 243.334285 -309.936334) (xy 243.326165 -309.99151)
			(xy 243.310097 -310.044917) (xy 243.286425 -310.095414) (xy 243.255652 -310.141927) (xy 243.218435 -310.183464)
			(xy 243.175567 -310.219139) (xy 243.127961 -310.248193) (xy 243.076632 -310.270005) (xy 243.022675 -310.284111)
			(xy 242.967238 -310.290211) (xy 242.911504 -310.288174) (xy 242.856661 -310.278044) (xy 242.803877 -310.260037)
			(xy 242.754277 -310.234536) (xy 242.708919 -310.202085) (xy 242.66877 -310.163376) (xy 242.634684 -310.119233)
			(xy 242.607388 -310.070598) (xy 242.587465 -310.018507) (xy 242.575339 -309.96407) (xy 242.571268 -309.908448)
			(xy 234.475274 -309.908448) (xy 234.475274 -311.215786) (xy 243.749066 -311.215786) (xy 243.753137 -311.160164)
			(xy 243.765263 -311.105727) (xy 243.785186 -311.053636) (xy 243.812482 -311.005001) (xy 243.846568 -310.960858)
			(xy 243.886717 -310.922149) (xy 243.932075 -310.889698) (xy 243.981675 -310.864197) (xy 244.034459 -310.84619)
			(xy 244.089302 -310.83606) (xy 244.145036 -310.834023) (xy 244.200473 -310.840123) (xy 244.25443 -310.854229)
			(xy 244.305759 -310.876041) (xy 244.353365 -310.905095) (xy 244.396233 -310.94077) (xy 244.43345 -310.982307)
			(xy 244.464223 -311.02882) (xy 244.487895 -311.079317) (xy 244.503963 -311.132724) (xy 244.512083 -311.1879)
			(xy 244.512592 -311.215786) (xy 244.512083 -311.243672) (xy 244.503963 -311.298848) (xy 244.487895 -311.352255)
			(xy 244.464223 -311.402752) (xy 244.43345 -311.449265) (xy 244.396233 -311.490802) (xy 244.353365 -311.526477)
			(xy 244.305759 -311.555531) (xy 244.25443 -311.577343) (xy 244.200473 -311.591449) (xy 244.145036 -311.597549)
			(xy 244.089302 -311.595512) (xy 244.034459 -311.585382) (xy 243.981675 -311.567375) (xy 243.932075 -311.541874)
			(xy 243.886717 -311.509423) (xy 243.846568 -311.470714) (xy 243.812482 -311.426571) (xy 243.785186 -311.377936)
			(xy 243.765263 -311.325845) (xy 243.753137 -311.271408) (xy 243.749066 -311.215786) (xy 234.475274 -311.215786)
			(xy 234.475274 -320.816732) (xy 241.138202 -320.816732) (xy 241.138686 -320.789362) (xy 241.1465 -320.735184)
			(xy 241.161984 -320.682681) (xy 241.184822 -320.632934) (xy 241.214543 -320.586966) (xy 241.232182 -320.566034)
			(xy 241.238278 -320.558922) (xy 241.244628 -320.541904) (xy 241.244628 -320.45656) (xy 241.238278 -320.439542)
			(xy 241.232182 -320.43243) (xy 241.214541 -320.4115) (xy 241.18483 -320.365526) (xy 241.161995 -320.315778)
			(xy 241.146504 -320.263277) (xy 241.138676 -320.209101) (xy 241.138202 -320.181732) (xy 241.138685 -320.154479)
			(xy 241.146438 -320.100529) (xy 241.16179 -320.048231) (xy 241.18443 -319.99865) (xy 241.213896 -319.952796)
			(xy 241.249587 -319.911603) (xy 241.290779 -319.875909) (xy 241.336631 -319.846441) (xy 241.38621 -319.823798)
			(xy 241.438507 -319.808443) (xy 241.492458 -319.800687) (xy 241.51971 -319.800224) (xy 241.547081 -319.800678)
			(xy 241.601261 -319.808498) (xy 241.653764 -319.82399) (xy 241.703511 -319.846834) (xy 241.749477 -319.876561)
			(xy 241.770408 -319.894204) (xy 241.77752 -319.9003) (xy 241.794538 -319.90665) (xy 241.879882 -319.90665)
			(xy 241.8969 -319.9003) (xy 241.904012 -319.894204) (xy 241.924945 -319.876563) (xy 241.970913 -319.846839)
			(xy 242.020659 -319.823993) (xy 242.073161 -319.808497) (xy 242.127339 -319.800668) (xy 242.182081 -319.800668)
			(xy 242.236259 -319.808497) (xy 242.288761 -319.823993) (xy 242.338507 -319.846839) (xy 242.384475 -319.876563)
			(xy 242.405408 -319.894204) (xy 242.41252 -319.9003) (xy 242.429538 -319.90665) (xy 242.514882 -319.90665)
			(xy 242.5319 -319.9003) (xy 242.539012 -319.894204) (xy 242.559967 -319.876593) (xy 242.605933 -319.846877)
			(xy 242.655675 -319.824036) (xy 242.708171 -319.808538) (xy 242.762342 -319.800702) (xy 242.78971 -319.800224)
			(xy 242.816965 -319.800646) (xy 242.870919 -319.808405) (xy 242.923219 -319.823764) (xy 242.972802 -319.84641)
			(xy 243.018656 -319.875882) (xy 243.05985 -319.91158) (xy 243.095543 -319.952777) (xy 243.12501 -319.998635)
			(xy 243.147651 -320.04822) (xy 243.163004 -320.100522) (xy 243.170757 -320.154477) (xy 243.171218 -320.181732)
			(xy 243.170791 -320.209104) (xy 243.162967 -320.263285) (xy 243.14747 -320.31579) (xy 243.124619 -320.365536)
			(xy 243.094884 -320.4115) (xy 243.077238 -320.43243) (xy 243.071142 -320.439542) (xy 243.064792 -320.45656)
			(xy 243.064792 -320.541904) (xy 243.071142 -320.558922) (xy 243.077238 -320.566034) (xy 243.094866 -320.586975)
			(xy 243.124578 -320.632946) (xy 243.147416 -320.682691) (xy 243.16291 -320.73519) (xy 243.170742 -320.789364)
			(xy 243.171218 -320.816732) (xy 243.170752 -320.843984) (xy 243.162991 -320.897931) (xy 243.147633 -320.950226)
			(xy 243.124989 -320.999803) (xy 243.09552 -321.045652) (xy 243.059826 -321.086842) (xy 243.018635 -321.122533)
			(xy 242.972783 -321.151999) (xy 242.923205 -321.17464) (xy 242.87091 -321.189996) (xy 242.816962 -321.197754)
			(xy 242.78971 -321.19824) (xy 242.762339 -321.197783) (xy 242.708159 -321.189965) (xy 242.655655 -321.174475)
			(xy 242.605909 -321.151631) (xy 242.559943 -321.121903) (xy 242.539012 -321.10426) (xy 242.5319 -321.098164)
			(xy 242.514882 -321.091814) (xy 242.429538 -321.091814) (xy 242.41252 -321.098164) (xy 242.405408 -321.10426)
			(xy 242.384475 -321.121901) (xy 242.338507 -321.151625) (xy 242.288761 -321.174471) (xy 242.236259 -321.189967)
			(xy 242.182081 -321.197796) (xy 242.127339 -321.197796) (xy 242.073161 -321.189967) (xy 242.020659 -321.174471)
			(xy 241.970913 -321.151625) (xy 241.924945 -321.121901) (xy 241.904012 -321.10426) (xy 241.8969 -321.098164)
			(xy 241.879882 -321.091814) (xy 241.794538 -321.091814) (xy 241.77752 -321.098164) (xy 241.770408 -321.10426)
			(xy 241.749479 -321.121903) (xy 241.703506 -321.151615) (xy 241.653758 -321.174451) (xy 241.601256 -321.189941)
			(xy 241.547079 -321.197767) (xy 241.51971 -321.19824) (xy 241.49246 -321.197713) (xy 241.438516 -321.189958)
			(xy 241.386224 -321.174606) (xy 241.336649 -321.151968) (xy 241.2908 -321.122506) (xy 241.249611 -321.086819)
			(xy 241.213919 -321.045634) (xy 241.184452 -320.999788) (xy 241.161809 -320.950215) (xy 241.146451 -320.897925)
			(xy 241.13869 -320.843981) (xy 241.138202 -320.816732) (xy 234.475274 -320.816732) (xy 234.475274 -321.132708)
			(xy 234.482894 -321.151504) (xy 234.49026 -321.158616) (xy 234.7595 -321.427856) (xy 234.766896 -321.434707)
			(xy 234.785495 -321.442449) (xy 234.795568 -321.442842) (xy 248.181368 -321.442842)
		)
		(stroke
			(width 0)
			(type solid)
		)
		(fill yes)
		(layer "In11.Cu")
		(net "GND")
	)
	(gr_poly
		(pts
			(arc
				(start 200.481692 -418.081968)
				(mid 201.086106 -417.953924)
				(end 201.586846 -417.592002)
			)
			(arc
				(start 201.586846 -417.592002)
				(mid 202.42889 -416.98332)
				(end 203.445364 -416.768026)
			)
			(arc
				(start 271.794732 -416.768026)
				(mid 272.811071 -416.983322)
				(end 273.652996 -417.592002)
			)
			(arc
				(start 273.652996 -417.592002)
				(mid 274.153727 -417.953921)
				(end 274.75815 -418.081968)
			)
			(arc
				(start 465.600034 -418.081968)
				(mid 466.655034 -417.644972)
				(end 467.09203 -416.589972)
			)
			(arc
				(start 467.09203 -246.488204)
				(mid 466.978493 -245.917325)
				(end 466.65515 -245.433342)
			)
			(arc
				(start 464.026504 -242.80495)
				(mid 463.482885 -241.991412)
				(end 463.291936 -241.031776)
			)
			(arc
				(start 463.291936 -87.588344)
				(mid 463.482826 -86.628673)
				(end 464.026504 -85.81517)
			)
			(arc
				(start 466.65515 -83.186524)
				(mid 466.978483 -82.702667)
				(end 467.09203 -82.131916)
			)
			(arc
				(start 467.09203 -1.999996)
				(mid 466.655034 -0.944996)
				(end 465.600034 -0.508)
			)
			(arc
				(start 446.265046 -0.508)
				(mid 445.210046 -0.944996)
				(end 444.77305 -1.999996)
			)
			(arc
				(start 444.77305 -11.850116)
				(mid 444.676277 -12.381671)
				(end 444.3984 -12.845034)
			)
			(xy 444.3984 -12.869164) (xy 444.399924 -12.870688)
			(arc
				(start 445.002666 -12.870688)
				(mid 445.20965 -12.378943)
				(end 445.280288 -11.850116)
			)
			(arc
				(start 445.280288 -1.999996)
				(mid 445.568553 -1.303936)
				(end 446.264538 -1.015492)
			)
			(arc
				(start 465.600034 -1.015492)
				(mid 466.296273 -1.303831)
				(end 466.584792 -1.999996)
			)
			(arc
				(start 466.584792 -82.131916)
				(mid 466.509885 -82.508586)
				(end 466.296502 -82.827876)
			)
			(arc
				(start 463.667856 -85.456522)
				(mid 463.014235 -86.434595)
				(end 462.784698 -87.588344)
			)
			(xy 462.784444 -87.588344) (xy 462.784444 -241.031776)
			(arc
				(start 462.784698 -241.031776)
				(mid 463.014268 -242.185519)
				(end 463.667856 -243.163598)
			)
			(arc
				(start 466.296502 -245.79199)
				(mid 466.509882 -246.11143)
				(end 466.584792 -246.488204)
			)
			(arc
				(start 466.584792 -416.589972)
				(mid 466.296527 -417.286032)
				(end 465.600542 -417.574476)
			)
			(xy 414.915604 -417.574476) (xy 414.915604 -417.797742) (xy 400.95424 -417.797742) (xy 400.95424 -417.574476)
			(xy 326.621648 -417.574476) (xy 326.621648 -417.747958) (xy 313.065922 -417.747958) (xy 313.065922 -417.574476)
			(arc
				(start 274.757896 -417.574476)
				(mid 274.359217 -417.490052)
				(end 274.028916 -417.251388)
			)
			(arc
				(start 274.028916 -417.251388)
				(mid 273.01669 -416.519565)
				(end 271.794732 -416.260788)
			)
			(arc
				(start 203.445364 -416.260788)
				(mid 202.223266 -416.519531)
				(end 201.210926 -417.251388)
			)
			(arc
				(start 201.210926 -417.251388)
				(mid 200.880626 -417.490098)
				(end 200.481946 -417.574476)
			)
			(xy 154.673554 -417.574476) (xy 154.673554 -417.693856) (xy 141.027912 -417.693856) (xy 141.027912 -417.574476)
			(xy 66.745104 -417.574476) (xy 66.745104 -417.671758) (xy 53.039772 -417.671758) (xy 53.039772 -417.574476)
			(arc
				(start 1.999996 -417.574476)
				(mid 1.303847 -417.286121)
				(end 1.015492 -416.589972)
			)
			(arc
				(start 1.015492 -246.48795)
				(mid 1.090466 -246.111319)
				(end 1.303782 -245.79199)
			)
			(arc
				(start 3.93192 -243.163852)
				(mid 4.58575 -242.18556)
				(end 4.815332 -241.031522)
			)
			(arc
				(start 4.815332 -87.588344)
				(mid 4.585694 -86.434435)
				(end 3.93192 -85.456268)
			)
			(arc
				(start 1.303528 -82.827876)
				(mid 1.090411 -82.508641)
				(end 1.015492 -82.13217)
			)
			(arc
				(start 1.015492 -1.999996)
				(mid 1.303847 -1.303847)
				(end 1.999996 -1.015492)
			)
			(arc
				(start 5.964936 -1.015492)
				(mid 6.661085 -1.303847)
				(end 6.94944 -1.999996)
			)
			(arc
				(start 6.94944 -11.850116)
				(mid 7.539853 -13.275118)
				(end 8.96493 -13.865352)
			)
			(xy 16.2814 -13.865352) (xy 16.371316 -13.775436) (xy 16.371316 -13.44803) (xy 16.2814 -13.358114)
			(arc
				(start 8.96493 -13.358114)
				(mid 7.898614 -12.916432)
				(end 7.456932 -11.850116)
			)
			(arc
				(start 7.456932 -1.999996)
				(mid 7.019936 -0.944996)
				(end 5.964936 -0.508)
			)
			(arc
				(start 1.999996 -0.508)
				(mid 0.944996 -0.944996)
				(end 0.508 -1.999996)
			)
			(arc
				(start 0.508 -82.131916)
				(mid 0.621601 -82.702644)
				(end 0.94488 -83.186524)
			)
			(arc
				(start 3.573272 -85.81517)
				(mid 4.117081 -86.628665)
				(end 4.308094 -87.588344)
			)
			(arc
				(start 4.308094 -241.031522)
				(mid 4.117082 -241.991334)
				(end 3.573272 -242.80495)
			)
			(arc
				(start 0.94488 -245.433342)
				(mid 0.621552 -245.917331)
				(end 0.508 -246.488204)
			)
			(arc
				(start 0.508 -416.589972)
				(mid 0.944996 -417.644972)
				(end 1.999996 -418.081968)
			)
		)
		(stroke
			(width 0)
			(type solid)
		)
		(fill yes)
		(layer "In11.Cu")
		(net "GND")
	)
	(gr_poly
		(pts
			(xy 118.559834 -266.109704) (xy 118.569819 -266.10916) (xy 118.588242 -266.101439) (xy 118.595648 -266.094718)
			(xy 119.126 -265.564366) (xy 119.147576 -265.54363) (xy 119.195992 -265.508466) (xy 119.24931 -265.481304)
			(xy 119.30622 -265.462813) (xy 119.365321 -265.453448) (xy 119.39524 -265.45286) (xy 119.628412 -265.452606)
			(xy 119.655664 -265.45307) (xy 119.709613 -265.460829) (xy 119.761908 -265.476186) (xy 119.811486 -265.498829)
			(xy 119.857337 -265.528298) (xy 119.898527 -265.563992) (xy 119.934218 -265.605184) (xy 119.963683 -265.651037)
			(xy 119.986323 -265.700616) (xy 120.001677 -265.752913) (xy 120.009432 -265.806862) (xy 120.00992 -265.834114)
			(xy 120.00992 -265.838178) (xy 120.008776 -265.872321) (xy 119.995873 -265.939398) (xy 119.984266 -265.971528)
			(xy 119.980351 -265.983388) (xy 119.983263 -266.008165) (xy 119.989854 -266.018772) (xy 120.037098 -266.087606)
			(xy 120.044624 -266.0975) (xy 120.066592 -266.109076) (xy 120.079008 -266.109704) (xy 120.367044 -266.109704)
			(xy 120.377046 -266.109208) (xy 120.395523 -266.101541) (xy 120.409664 -266.08739) (xy 120.417316 -266.068906)
			(xy 120.417844 -266.058904) (xy 120.417844 -264.93597) (xy 120.41833 -264.908719) (xy 120.426086 -264.854771)
			(xy 120.441441 -264.802476) (xy 120.464083 -264.752899) (xy 120.493549 -264.707049) (xy 120.52924 -264.665858)
			(xy 120.570431 -264.630167) (xy 120.616281 -264.600701) (xy 120.665858 -264.578059) (xy 120.718153 -264.562704)
			(xy 120.772101 -264.554948) (xy 120.826603 -264.554948) (xy 120.880551 -264.562704) (xy 120.932846 -264.578059)
			(xy 120.982423 -264.600701) (xy 121.028273 -264.630167) (xy 121.069464 -264.665858) (xy 121.105155 -264.707049)
			(xy 121.134621 -264.752899) (xy 121.157263 -264.802476) (xy 121.172618 -264.854771) (xy 121.180374 -264.908719)
			(xy 121.18086 -264.93597) (xy 121.18086 -266.058904) (xy 121.181348 -266.068914) (xy 121.189007 -266.087411)
			(xy 121.203158 -266.101573) (xy 121.22165 -266.109245) (xy 121.23166 -266.109704) (xy 122.10542 -266.109704)
			(xy 122.115297 -266.109244) (xy 122.133595 -266.1018) (xy 122.14098 -266.095226) (xy 122.141234 -266.094972)
			(xy 122.1486 -266.087606) (xy 122.155311 -266.080173) (xy 122.162938 -266.061678) (xy 122.162928 -266.041673)
			(xy 122.155283 -266.023185) (xy 122.1486 -266.015724) (xy 121.819162 -265.68654) (xy 121.670572 -265.53795)
			(xy 121.649793 -265.516335) (xy 121.614556 -265.467829) (xy 121.587337 -265.41441) (xy 121.568804 -265.357393)
			(xy 121.559415 -265.298179) (xy 121.558812 -265.268202) (xy 121.558812 -264.650728) (xy 121.55828 -264.640738)
			(xy 121.550575 -264.622298) (xy 121.543826 -264.614914) (xy 121.146316 -264.21715) (xy 121.138916 -264.210311)
			(xy 121.120317 -264.202599) (xy 121.110248 -264.202164) (xy 119.82577 -264.202164) (xy 119.798538 -264.201676)
			(xy 119.744629 -264.193922) (xy 119.692372 -264.178574) (xy 119.642831 -264.155947) (xy 119.597014 -264.126499)
			(xy 119.555854 -264.090832) (xy 119.520189 -264.04967) (xy 119.490744 -264.003851) (xy 119.468119 -263.954309)
			(xy 119.452774 -263.902051) (xy 119.445022 -263.848142) (xy 119.444516 -263.82091) (xy 119.444979 -263.793778)
			(xy 119.452641 -263.740057) (xy 119.46784 -263.687966) (xy 119.490269 -263.638554) (xy 119.50446 -263.615424)
			(xy 119.509009 -263.607701) (xy 119.512925 -263.590221) (xy 119.510603 -263.57246) (xy 119.506746 -263.56437)
			(xy 119.494298 -263.539663) (xy 119.475869 -263.4875) (xy 119.465164 -263.433223) (xy 119.463312 -263.40562)
			(xy 119.462804 -263.395968) (xy 119.455184 -263.37895) (xy 119.345202 -263.268968) (xy 119.33836 -263.261568)
			(xy 119.330637 -263.24297) (xy 119.330216 -263.2329) (xy 119.330216 -262.92937) (xy 119.329562 -262.917396)
			(xy 119.318676 -262.896066) (xy 119.309388 -262.888476) (xy 119.287457 -262.87181) (xy 119.248169 -262.833205)
			(xy 119.214845 -262.789348) (xy 119.188179 -262.741152) (xy 119.168725 -262.689621) (xy 119.15689 -262.635827)
			(xy 119.152918 -262.580889) (xy 119.156893 -262.525952) (xy 119.168732 -262.472158) (xy 119.188188 -262.420628)
			(xy 119.214857 -262.372434) (xy 119.248183 -262.328579) (xy 119.287473 -262.289976) (xy 119.309388 -262.273288)
			(xy 119.318654 -262.265687) (xy 119.329522 -262.244359) (xy 119.330216 -262.232394) (xy 119.330216 -261.176516)
			(xy 119.329731 -261.166505) (xy 119.322075 -261.148005) (xy 119.307922 -261.133843) (xy 119.289427 -261.126175)
			(xy 119.279416 -261.125716) (xy 118.97487 -261.125716) (xy 118.964802 -261.125288) (xy 118.946204 -261.117568)
			(xy 118.938802 -261.11073) (xy 118.440962 -260.61289) (xy 118.43411 -260.605494) (xy 118.42637 -260.586895)
			(xy 118.425976 -260.576822) (xy 118.425976 -253.583948) (xy 118.418356 -253.565152) (xy 118.41099 -253.55804)
			(xy 117.856254 -253.003304) (xy 117.850657 -252.99558) (xy 117.835151 -252.984498) (xy 117.826028 -252.981714)
			(xy 117.822218 -252.98019) (xy 117.815868 -252.98019) (xy 117.810788 -252.98019) (xy 115.70081 -252.98019)
			(xy 115.682014 -252.98781) (xy 115.674902 -252.995176) (xy 115.576096 -253.093982) (xy 115.568376 -253.099582)
			(xy 115.557307 -253.115091) (xy 115.554506 -253.124208) (xy 115.552982 -253.128018) (xy 115.552982 -253.134368)
			(xy 115.552982 -253.139448) (xy 115.552982 -254.276606) (xy 115.557808 -254.28702) (xy 115.569093 -254.312397)
			(xy 115.585035 -254.365596) (xy 115.593112 -254.420542) (xy 115.593622 -254.44831) (xy 115.593622 -254.448818)
			(xy 115.593124 -254.476588) (xy 115.585066 -254.531539) (xy 115.56911 -254.584737) (xy 115.557808 -254.610108)
			(xy 115.552982 -254.620522) (xy 115.552982 -254.759968) (xy 115.553343 -254.768663) (xy 115.559175 -254.785048)
			(xy 115.570144 -254.798543) (xy 115.577366 -254.803402) (xy 115.622578 -254.830834) (xy 115.62334 -254.83058)
			(xy 115.663218 -254.855218) (xy 115.689634 -254.856234) (xy 115.701826 -254.850138) (xy 115.729021 -254.836685)
			(xy 115.786614 -254.81761) (xy 115.846499 -254.807881) (xy 115.876832 -254.807212) (xy 115.882928 -254.807212)
			(xy 115.912536 -254.808202) (xy 115.970924 -254.818207) (xy 116.027062 -254.837119) (xy 116.079602 -254.864483)
			(xy 116.12728 -254.899641) (xy 116.168949 -254.941746) (xy 116.186712 -254.965454) (xy 116.190268 -254.97028)
			(xy 116.199158 -254.978154) (xy 116.224558 -254.991362) (xy 116.230088 -254.994062) (xy 116.242029 -254.997025)
			(xy 116.24818 -254.997204) (xy 116.3066 -254.997204) (xy 116.312752 -254.997031) (xy 116.324696 -254.994073)
			(xy 116.330222 -254.991362) (xy 116.350542 -254.980694) (xy 116.355538 -254.977886) (xy 116.364261 -254.970458)
			(xy 116.367814 -254.965962) (xy 116.368068 -254.965454) (xy 116.368322 -254.9652) (xy 116.383757 -254.944581)
			(xy 116.419281 -254.907286) (xy 116.459498 -254.875106) (xy 116.503676 -254.848627) (xy 116.551014 -254.828329)
			(xy 116.600652 -254.814582) (xy 116.651687 -254.807634) (xy 116.67744 -254.807212) (xy 116.704689 -254.807701)
			(xy 116.758631 -254.815462) (xy 116.81092 -254.830821) (xy 116.860491 -254.853465) (xy 116.906335 -254.882932)
			(xy 116.947518 -254.918624) (xy 116.983204 -254.959814) (xy 117.012664 -255.005662) (xy 117.0353 -255.055236)
			(xy 117.050651 -255.107528) (xy 117.058403 -255.161471) (xy 117.058948 -255.18872) (xy 117.058503 -255.215463)
			(xy 117.05104 -255.268427) (xy 117.03625 -255.319827) (xy 117.014422 -255.368657) (xy 116.985986 -255.413958)
			(xy 116.951498 -255.454841) (xy 116.911636 -255.490504) (xy 116.867182 -255.520246) (xy 116.819008 -255.543485)
			(xy 116.768059 -255.559765) (xy 116.715335 -255.568766) (xy 116.688616 -255.569974) (xy 116.679472 -255.570228)
			(xy 116.67744 -255.570228) (xy 116.651661 -255.569799) (xy 116.600574 -255.562848) (xy 116.550888 -255.54908)
			(xy 116.503509 -255.528746) (xy 116.4593 -255.502217) (xy 116.419066 -255.469976) (xy 116.383541 -255.43261)
			(xy 116.368068 -255.411986) (xy 116.364512 -255.40716) (xy 116.355622 -255.399286) (xy 116.330222 -255.386078)
			(xy 116.324691 -255.383383) (xy 116.31275 -255.380429) (xy 116.3066 -255.380236) (xy 116.24818 -255.380236)
			(xy 116.242029 -255.380412) (xy 116.230088 -255.383376) (xy 116.224558 -255.386078) (xy 116.199158 -255.399286)
			(xy 116.190268 -255.40716) (xy 116.186712 -255.411986) (xy 116.171281 -255.432644) (xy 116.135752 -255.470012)
			(xy 116.095512 -255.502254) (xy 116.051296 -255.52878) (xy 116.003909 -255.549107) (xy 115.954215 -255.562866)
			(xy 115.903122 -255.569804) (xy 115.87734 -255.570228) (xy 115.871244 -255.570228) (xy 115.843662 -255.5693)
			(xy 115.789185 -255.560488) (xy 115.736539 -255.543937) (xy 115.711478 -255.532382) (xy 115.706398 -255.529842)
			(xy 115.695222 -255.527302) (xy 115.668552 -255.527302) (xy 115.6616 -255.527539) (xy 115.648204 -255.531268)
			(xy 115.642136 -255.534668) (xy 115.577366 -255.574038) (xy 115.570111 -255.578859) (xy 115.559127 -255.592362)
			(xy 115.55331 -255.608768) (xy 115.552982 -255.617472) (xy 115.552982 -257.13055) (xy 116.295422 -257.13055)
			(xy 116.299493 -257.074928) (xy 116.311619 -257.020491) (xy 116.331542 -256.9684) (xy 116.358838 -256.919765)
			(xy 116.392924 -256.875622) (xy 116.433073 -256.836913) (xy 116.478431 -256.804462) (xy 116.528031 -256.778961)
			(xy 116.580815 -256.760954) (xy 116.635658 -256.750824) (xy 116.691392 -256.748787) (xy 116.746829 -256.754887)
			(xy 116.800786 -256.768993) (xy 116.852115 -256.790805) (xy 116.899721 -256.819859) (xy 116.942589 -256.855534)
			(xy 116.979806 -256.897071) (xy 117.010579 -256.943584) (xy 117.034251 -256.994081) (xy 117.050319 -257.047488)
			(xy 117.058439 -257.102664) (xy 117.058948 -257.13055) (xy 117.058439 -257.158436) (xy 117.050319 -257.213612)
			(xy 117.034251 -257.267019) (xy 117.010579 -257.317516) (xy 116.979806 -257.364029) (xy 116.942589 -257.405566)
			(xy 116.899721 -257.441241) (xy 116.852115 -257.470295) (xy 116.800786 -257.492107) (xy 116.746829 -257.506213)
			(xy 116.691392 -257.512313) (xy 116.635658 -257.510276) (xy 116.580815 -257.500146) (xy 116.528031 -257.482139)
			(xy 116.478431 -257.456638) (xy 116.433073 -257.424187) (xy 116.392924 -257.385478) (xy 116.358838 -257.341335)
			(xy 116.331542 -257.2927) (xy 116.311619 -257.240609) (xy 116.299493 -257.186172) (xy 116.295422 -257.13055)
			(xy 115.552982 -257.13055) (xy 115.552982 -258.01955) (xy 116.422932 -258.01955) (xy 116.423402 -257.992297)
			(xy 116.431153 -257.938344) (xy 116.446505 -257.886044) (xy 116.469144 -257.836461) (xy 116.498611 -257.790606)
			(xy 116.534304 -257.749411) (xy 116.575498 -257.713717) (xy 116.621352 -257.684249) (xy 116.670934 -257.661608)
			(xy 116.723234 -257.646255) (xy 116.777187 -257.638503) (xy 116.80444 -257.638042) (xy 116.831497 -257.638464)
			(xy 116.885066 -257.646128) (xy 116.937014 -257.661283) (xy 116.986301 -257.683624) (xy 117.031938 -257.712704)
			(xy 117.073009 -257.747939) (xy 117.108691 -257.788623) (xy 117.138267 -257.833939) (xy 117.150134 -257.85826)
			(xy 117.154198 -257.866642) (xy 117.167406 -257.879596) (xy 117.246908 -257.913886) (xy 117.26545 -257.914648)
			(xy 117.27434 -257.9116) (xy 117.30367 -257.902497) (xy 117.364286 -257.892662) (xy 117.39499 -257.892042)
			(xy 117.422247 -257.892404) (xy 117.476206 -257.900161) (xy 117.528512 -257.915518) (xy 117.5781 -257.938163)
			(xy 117.62396 -257.967635) (xy 117.66516 -258.003333) (xy 117.700859 -258.044532) (xy 117.730332 -258.090391)
			(xy 117.752978 -258.139979) (xy 117.768337 -258.192284) (xy 117.776095 -258.246243) (xy 117.776095 -258.300757)
			(xy 117.768337 -258.354716) (xy 117.752978 -258.407021) (xy 117.730332 -258.456609) (xy 117.700859 -258.502468)
			(xy 117.66516 -258.543667) (xy 117.62396 -258.579365) (xy 117.5781 -258.608837) (xy 117.528512 -258.631482)
			(xy 117.476206 -258.646839) (xy 117.422247 -258.654596) (xy 117.39499 -258.655058) (xy 117.374442 -258.654758)
			(xy 117.333586 -258.650305) (xy 117.313456 -258.646168) (xy 117.301518 -258.643628) (xy 117.27815 -258.649724)
			(xy 117.198394 -258.720336) (xy 117.189504 -258.742688) (xy 117.19052 -258.75488) (xy 117.192298 -258.79044)
			(xy 117.191812 -258.817691) (xy 117.184056 -258.871639) (xy 117.168701 -258.923934) (xy 117.146059 -258.973511)
			(xy 117.116593 -259.019361) (xy 117.080902 -259.060552) (xy 117.039711 -259.096243) (xy 116.993861 -259.125709)
			(xy 116.944284 -259.148351) (xy 116.891989 -259.163706) (xy 116.838041 -259.171462) (xy 116.783539 -259.171462)
			(xy 116.729591 -259.163706) (xy 116.677296 -259.148351) (xy 116.627719 -259.125709) (xy 116.581869 -259.096243)
			(xy 116.540678 -259.060552) (xy 116.504987 -259.019361) (xy 116.475521 -258.973511) (xy 116.452879 -258.923934)
			(xy 116.437524 -258.871639) (xy 116.429768 -258.817691) (xy 116.429282 -258.79044) (xy 116.429857 -258.761315)
			(xy 116.438719 -258.703744) (xy 116.456227 -258.648188) (xy 116.481976 -258.595939) (xy 116.515366 -258.548209)
			(xy 116.555622 -258.506109) (xy 116.57838 -258.487926) (xy 116.587778 -258.48056) (xy 116.598192 -258.459224)
			(xy 116.59743 -258.354068) (xy 116.586762 -258.332986) (xy 116.576856 -258.325874) (xy 116.553429 -258.307703)
			(xy 116.511899 -258.265397) (xy 116.477407 -258.21718) (xy 116.450783 -258.16421) (xy 116.432668 -258.107762)
			(xy 116.423496 -258.049192) (xy 116.422932 -258.01955) (xy 115.552982 -258.01955) (xy 115.552982 -258.544822)
			(xy 115.561364 -258.572) (xy 115.565174 -258.577842) (xy 115.579131 -258.600809) (xy 115.60116 -258.64983)
			(xy 115.616091 -258.701458) (xy 115.623628 -258.754671) (xy 115.623622 -258.808414) (xy 115.616073 -258.861625)
			(xy 115.601131 -258.913249) (xy 115.579091 -258.962265) (xy 115.565174 -258.985258) (xy 115.561364 -258.9911)
			(xy 115.552982 -259.018278) (xy 115.552982 -259.43433) (xy 115.552553 -259.444397) (xy 115.544829 -259.462992)
			(xy 115.537996 -259.470398) (xy 114.701574 -260.30682) (xy 114.694178 -260.313671) (xy 114.675579 -260.321409)
			(xy 114.665506 -260.321806) (xy 112.463072 -260.321806) (xy 112.444276 -260.329426) (xy 112.437164 -260.336792)
			(xy 112.281716 -260.49224) (xy 112.27399 -260.497836) (xy 112.262904 -260.51334) (xy 112.260126 -260.522466)
			(xy 112.258602 -260.526276) (xy 112.258602 -260.532626) (xy 112.258602 -260.537706) (xy 112.258602 -261.217664)
			(xy 114.140232 -261.217664) (xy 114.144303 -261.162042) (xy 114.156429 -261.107605) (xy 114.176352 -261.055514)
			(xy 114.203648 -261.006879) (xy 114.237734 -260.962736) (xy 114.277883 -260.924027) (xy 114.323241 -260.891576)
			(xy 114.372841 -260.866075) (xy 114.425625 -260.848068) (xy 114.480468 -260.837938) (xy 114.536202 -260.835901)
			(xy 114.591639 -260.842001) (xy 114.645596 -260.856107) (xy 114.696925 -260.877919) (xy 114.744531 -260.906973)
			(xy 114.787399 -260.942648) (xy 114.824616 -260.984185) (xy 114.855389 -261.030698) (xy 114.879061 -261.081195)
			(xy 114.895129 -261.134602) (xy 114.903249 -261.189778) (xy 114.903758 -261.217664) (xy 114.903249 -261.24555)
			(xy 114.895129 -261.300726) (xy 114.879061 -261.354133) (xy 114.855389 -261.40463) (xy 114.824616 -261.451143)
			(xy 114.787399 -261.49268) (xy 114.744531 -261.528355) (xy 114.696925 -261.557409) (xy 114.645596 -261.579221)
			(xy 114.591639 -261.593327) (xy 114.536202 -261.599427) (xy 114.480468 -261.59739) (xy 114.425625 -261.58726)
			(xy 114.372841 -261.569253) (xy 114.323241 -261.543752) (xy 114.277883 -261.511301) (xy 114.237734 -261.472592)
			(xy 114.203648 -261.428449) (xy 114.176352 -261.379814) (xy 114.156429 -261.327723) (xy 114.144303 -261.273286)
			(xy 114.140232 -261.217664) (xy 112.258602 -261.217664) (xy 112.258602 -261.241286) (xy 112.259241 -261.253844)
			(xy 112.271092 -261.275985) (xy 112.281208 -261.28345) (xy 112.351566 -261.33044) (xy 112.356945 -261.3338)
			(xy 112.368894 -261.338042) (xy 112.375188 -261.338822) (xy 112.387634 -261.339838) (xy 112.399318 -261.335012)
			(xy 112.422282 -261.325938) (xy 112.469965 -261.313116) (xy 112.518903 -261.306553) (xy 112.54359 -261.306056)
			(xy 112.549686 -261.306056) (xy 112.576722 -261.306853) (xy 112.63017 -261.315135) (xy 112.681913 -261.330885)
			(xy 112.730913 -261.353785) (xy 112.776187 -261.383376) (xy 112.816827 -261.419066) (xy 112.852018 -261.460138)
			(xy 112.881056 -261.505769) (xy 112.903357 -261.555044) (xy 112.918474 -261.606975) (xy 112.926105 -261.660521)
			(xy 112.926389 -261.675372) (xy 117.07444 -261.675372) (xy 117.078511 -261.61975) (xy 117.090637 -261.565313)
			(xy 117.11056 -261.513222) (xy 117.137856 -261.464587) (xy 117.171942 -261.420444) (xy 117.212091 -261.381735)
			(xy 117.257449 -261.349284) (xy 117.307049 -261.323783) (xy 117.359833 -261.305776) (xy 117.414676 -261.295646)
			(xy 117.47041 -261.293609) (xy 117.525847 -261.299709) (xy 117.579804 -261.313815) (xy 117.631133 -261.335627)
			(xy 117.678739 -261.364681) (xy 117.721607 -261.400356) (xy 117.758824 -261.441893) (xy 117.789597 -261.488406)
			(xy 117.813269 -261.538903) (xy 117.829337 -261.59231) (xy 117.837457 -261.647486) (xy 117.837966 -261.675372)
			(xy 117.837457 -261.703258) (xy 117.829337 -261.758434) (xy 117.813269 -261.811841) (xy 117.789597 -261.862338)
			(xy 117.758824 -261.908851) (xy 117.721607 -261.950388) (xy 117.678739 -261.986063) (xy 117.631133 -262.015117)
			(xy 117.579804 -262.036929) (xy 117.525847 -262.051035) (xy 117.47041 -262.057135) (xy 117.414676 -262.055098)
			(xy 117.359833 -262.044968) (xy 117.307049 -262.026961) (xy 117.257449 -262.00146) (xy 117.212091 -261.969009)
			(xy 117.171942 -261.9303) (xy 117.137856 -261.886157) (xy 117.11056 -261.837522) (xy 117.090637 -261.785431)
			(xy 117.078511 -261.730994) (xy 117.07444 -261.675372) (xy 112.926389 -261.675372) (xy 112.926622 -261.687564)
			(xy 112.926159 -261.714523) (xy 112.918571 -261.767904) (xy 112.903541 -261.819685) (xy 112.881368 -261.868833)
			(xy 112.852496 -261.914368) (xy 112.817498 -261.955384) (xy 112.79759 -261.973568) (xy 112.789716 -261.980426)
			(xy 112.780826 -261.999476) (xy 112.778286 -262.084058) (xy 112.778458 -262.094429) (xy 112.786059 -262.113706)
			(xy 112.793018 -262.121396) (xy 112.867175 -262.195564) (xy 116.381782 -262.195564) (xy 116.385853 -262.139942)
			(xy 116.397979 -262.085505) (xy 116.417902 -262.033414) (xy 116.445198 -261.984779) (xy 116.479284 -261.940636)
			(xy 116.519433 -261.901927) (xy 116.564791 -261.869476) (xy 116.614391 -261.843975) (xy 116.667175 -261.825968)
			(xy 116.722018 -261.815838) (xy 116.777752 -261.813801) (xy 116.833189 -261.819901) (xy 116.887146 -261.834007)
			(xy 116.938475 -261.855819) (xy 116.986081 -261.884873) (xy 117.028949 -261.920548) (xy 117.066166 -261.962085)
			(xy 117.096939 -262.008598) (xy 117.120611 -262.059095) (xy 117.136679 -262.112502) (xy 117.144799 -262.167678)
			(xy 117.145308 -262.195564) (xy 117.144799 -262.22345) (xy 117.136679 -262.278626) (xy 117.120611 -262.332033)
			(xy 117.096939 -262.38253) (xy 117.066166 -262.429043) (xy 117.028949 -262.47058) (xy 116.986081 -262.506255)
			(xy 116.938475 -262.535309) (xy 116.887146 -262.557121) (xy 116.833189 -262.571227) (xy 116.777752 -262.577327)
			(xy 116.722018 -262.57529) (xy 116.667175 -262.56516) (xy 116.614391 -262.547153) (xy 116.564791 -262.521652)
			(xy 116.519433 -262.489201) (xy 116.479284 -262.450492) (xy 116.445198 -262.406349) (xy 116.417902 -262.357714)
			(xy 116.397979 -262.305623) (xy 116.385853 -262.251186) (xy 116.381782 -262.195564) (xy 112.867175 -262.195564)
			(xy 113.743346 -263.071864) (xy 116.381782 -263.071864) (xy 116.385853 -263.016242) (xy 116.397979 -262.961805)
			(xy 116.417902 -262.909714) (xy 116.445198 -262.861079) (xy 116.479284 -262.816936) (xy 116.519433 -262.778227)
			(xy 116.564791 -262.745776) (xy 116.614391 -262.720275) (xy 116.667175 -262.702268) (xy 116.722018 -262.692138)
			(xy 116.777752 -262.690101) (xy 116.833189 -262.696201) (xy 116.887146 -262.710307) (xy 116.938475 -262.732119)
			(xy 116.986081 -262.761173) (xy 117.028949 -262.796848) (xy 117.066166 -262.838385) (xy 117.096939 -262.884898)
			(xy 117.120611 -262.935395) (xy 117.136679 -262.988802) (xy 117.144799 -263.043978) (xy 117.145308 -263.071864)
			(xy 117.144799 -263.09975) (xy 117.136679 -263.154926) (xy 117.120611 -263.208333) (xy 117.096939 -263.25883)
			(xy 117.066166 -263.305343) (xy 117.028949 -263.34688) (xy 116.986081 -263.382555) (xy 116.938475 -263.411609)
			(xy 116.887146 -263.433421) (xy 116.833189 -263.447527) (xy 116.777752 -263.453627) (xy 116.722018 -263.45159)
			(xy 116.667175 -263.44146) (xy 116.614391 -263.423453) (xy 116.564791 -263.397952) (xy 116.519433 -263.365501)
			(xy 116.479284 -263.326792) (xy 116.445198 -263.282649) (xy 116.417902 -263.234014) (xy 116.397979 -263.181923)
			(xy 116.385853 -263.127486) (xy 116.381782 -263.071864) (xy 113.743346 -263.071864) (xy 114.522504 -263.851136)
			(xy 114.522758 -263.851136) (xy 114.525552 -263.85393) (xy 114.565176 -263.8552) (xy 114.580416 -263.841992)
			(xy 114.601348 -263.824351) (xy 114.647315 -263.794628) (xy 114.697062 -263.771787) (xy 114.749565 -263.756299)
			(xy 114.803744 -263.748483) (xy 114.831114 -263.748012) (xy 114.858366 -263.748476) (xy 114.912314 -263.756235)
			(xy 114.964609 -263.771592) (xy 114.999736 -263.787636) (xy 117.571772 -263.787636) (xy 117.575843 -263.732014)
			(xy 117.587969 -263.677577) (xy 117.607892 -263.625486) (xy 117.635188 -263.576851) (xy 117.669274 -263.532708)
			(xy 117.709423 -263.493999) (xy 117.754781 -263.461548) (xy 117.804381 -263.436047) (xy 117.857165 -263.41804)
			(xy 117.912008 -263.40791) (xy 117.967742 -263.405873) (xy 118.023179 -263.411973) (xy 118.077136 -263.426079)
			(xy 118.128465 -263.447891) (xy 118.176071 -263.476945) (xy 118.218939 -263.51262) (xy 118.256156 -263.554157)
			(xy 118.286929 -263.60067) (xy 118.310601 -263.651167) (xy 118.326669 -263.704574) (xy 118.334789 -263.75975)
			(xy 118.335298 -263.787636) (xy 118.334789 -263.815522) (xy 118.326669 -263.870698) (xy 118.310601 -263.924105)
			(xy 118.286929 -263.974602) (xy 118.256156 -264.021115) (xy 118.218939 -264.062652) (xy 118.176071 -264.098327)
			(xy 118.128465 -264.127381) (xy 118.077136 -264.149193) (xy 118.023179 -264.163299) (xy 117.967742 -264.169399)
			(xy 117.912008 -264.167362) (xy 117.857165 -264.157232) (xy 117.804381 -264.139225) (xy 117.754781 -264.113724)
			(xy 117.709423 -264.081273) (xy 117.669274 -264.042564) (xy 117.635188 -263.998421) (xy 117.607892 -263.949786)
			(xy 117.587969 -263.897695) (xy 117.575843 -263.843258) (xy 117.571772 -263.787636) (xy 114.999736 -263.787636)
			(xy 115.014186 -263.794236) (xy 115.060036 -263.823705) (xy 115.101225 -263.859399) (xy 115.136916 -263.900591)
			(xy 115.16638 -263.946444) (xy 115.189019 -263.996023) (xy 115.204372 -264.048319) (xy 115.212126 -264.102268)
			(xy 115.212622 -264.12952) (xy 115.212149 -264.15689) (xy 115.204323 -264.211067) (xy 115.188835 -264.263569)
			(xy 115.166002 -264.31332) (xy 115.136293 -264.359296) (xy 115.118642 -264.380218) (xy 115.105434 -264.395458)
			(xy 115.106704 -264.435082) (xy 116.371116 -265.699494) (xy 116.371624 -265.700002) (xy 116.379001 -265.706594)
			(xy 116.397301 -265.714063) (xy 116.407184 -265.71448) (xy 118.001288 -265.71448) (xy 118.006243 -265.714363)
			(xy 118.015966 -265.712449) (xy 118.020592 -265.71067) (xy 118.0211 -265.710416) (xy 118.051072 -265.716512)
			(xy 118.429278 -266.094718) (xy 118.429786 -266.095226) (xy 118.437168 -266.101806) (xy 118.455467 -266.109249)
			(xy 118.465346 -266.109704)
		)
		(stroke
			(width 0)
			(type solid)
		)
		(fill yes)
		(layer "In11.Cu")
		(net "P0V8_PEX0_VREF")
	)
	(gr_poly
		(pts
			(xy 350.76003 -266.109704) (xy 350.770015 -266.109161) (xy 350.78844 -266.101441) (xy 350.795844 -266.094718)
			(xy 351.326196 -265.564366) (xy 351.347771 -265.543629) (xy 351.396187 -265.508465) (xy 351.449506 -265.481303)
			(xy 351.506416 -265.462812) (xy 351.565517 -265.453446) (xy 351.595436 -265.45286) (xy 351.828608 -265.452606)
			(xy 351.85586 -265.45307) (xy 351.909809 -265.460828) (xy 351.962105 -265.476185) (xy 352.011684 -265.498828)
			(xy 352.057535 -265.528296) (xy 352.098725 -265.56399) (xy 352.134417 -265.605183) (xy 352.163883 -265.651036)
			(xy 352.186523 -265.700615) (xy 352.201877 -265.752912) (xy 352.209632 -265.806862) (xy 352.210116 -265.834114)
			(xy 352.210116 -265.838178) (xy 352.208972 -265.872321) (xy 352.196069 -265.939398) (xy 352.184462 -265.971528)
			(xy 352.180547 -265.983388) (xy 352.183459 -266.008165) (xy 352.19005 -266.018772) (xy 352.237294 -266.087606)
			(xy 352.24482 -266.0975) (xy 352.266788 -266.109079) (xy 352.279204 -266.109704) (xy 352.56724 -266.109704)
			(xy 352.577243 -266.109209) (xy 352.595721 -266.101542) (xy 352.609863 -266.087391) (xy 352.617516 -266.068907)
			(xy 352.61804 -266.058904) (xy 352.61804 -264.93597) (xy 352.618526 -264.908719) (xy 352.626282 -264.854771)
			(xy 352.641637 -264.802476) (xy 352.664279 -264.752899) (xy 352.693745 -264.707049) (xy 352.729436 -264.665858)
			(xy 352.770627 -264.630167) (xy 352.816477 -264.600701) (xy 352.866054 -264.578059) (xy 352.918349 -264.562704)
			(xy 352.972297 -264.554948) (xy 353.026799 -264.554948) (xy 353.080747 -264.562704) (xy 353.133042 -264.578059)
			(xy 353.182619 -264.600701) (xy 353.228469 -264.630167) (xy 353.26966 -264.665858) (xy 353.305351 -264.707049)
			(xy 353.334817 -264.752899) (xy 353.357459 -264.802476) (xy 353.372814 -264.854771) (xy 353.38057 -264.908719)
			(xy 353.381056 -264.93597) (xy 353.381056 -266.058904) (xy 353.381544 -266.068914) (xy 353.389203 -266.087412)
			(xy 353.403354 -266.101575) (xy 353.421846 -266.109248) (xy 353.431856 -266.109704) (xy 354.305616 -266.109704)
			(xy 354.315493 -266.109244) (xy 354.333793 -266.101802) (xy 354.341176 -266.095226) (xy 354.34143 -266.094972)
			(xy 354.348796 -266.087606) (xy 354.355507 -266.080173) (xy 354.363134 -266.061678) (xy 354.363124 -266.041673)
			(xy 354.355479 -266.023185) (xy 354.348796 -266.015724) (xy 354.019358 -265.68654) (xy 353.870768 -265.53795)
			(xy 353.84999 -265.516335) (xy 353.814753 -265.467829) (xy 353.787534 -265.41441) (xy 353.769001 -265.357393)
			(xy 353.759612 -265.298179) (xy 353.759008 -265.268202) (xy 353.759008 -264.650728) (xy 353.758476 -264.640738)
			(xy 353.75077 -264.622298) (xy 353.744022 -264.614914) (xy 353.346512 -264.21715) (xy 353.339117 -264.210296)
			(xy 353.320518 -264.20255) (xy 353.310444 -264.202164) (xy 352.025966 -264.202164) (xy 351.998734 -264.201676)
			(xy 351.944826 -264.193921) (xy 351.892569 -264.178573) (xy 351.843029 -264.155945) (xy 351.797212 -264.126498)
			(xy 351.756053 -264.09083) (xy 351.720388 -264.049668) (xy 351.690943 -264.00385) (xy 351.668319 -263.954308)
			(xy 351.652974 -263.902051) (xy 351.645222 -263.848142) (xy 351.644712 -263.82091) (xy 351.645175 -263.793778)
			(xy 351.652837 -263.740057) (xy 351.668036 -263.687965) (xy 351.690464 -263.638554) (xy 351.704656 -263.615424)
			(xy 351.709205 -263.607701) (xy 351.713122 -263.590221) (xy 351.710799 -263.57246) (xy 351.706942 -263.56437)
			(xy 351.694494 -263.539663) (xy 351.676065 -263.4875) (xy 351.66536 -263.433223) (xy 351.663508 -263.40562)
			(xy 351.663 -263.395968) (xy 351.65538 -263.37895) (xy 351.545398 -263.268968) (xy 351.538557 -263.261568)
			(xy 351.530834 -263.24297) (xy 351.530412 -263.2329) (xy 351.530412 -262.92937) (xy 351.529758 -262.917396)
			(xy 351.518871 -262.896067) (xy 351.509584 -262.888476) (xy 351.487653 -262.87181) (xy 351.448366 -262.833205)
			(xy 351.415042 -262.789348) (xy 351.388376 -262.741152) (xy 351.368923 -262.689621) (xy 351.357087 -262.635827)
			(xy 351.353115 -262.580889) (xy 351.35709 -262.525952) (xy 351.368929 -262.472159) (xy 351.388385 -262.420629)
			(xy 351.415054 -262.372434) (xy 351.44838 -262.328579) (xy 351.48767 -262.289976) (xy 351.509584 -262.273288)
			(xy 351.518851 -262.265687) (xy 351.529719 -262.244359) (xy 351.530412 -262.232394) (xy 351.530412 -261.176516)
			(xy 351.529995 -261.166492) (xy 351.522329 -261.147967) (xy 351.508156 -261.133787) (xy 351.489636 -261.12611)
			(xy 351.479612 -261.125716) (xy 351.175066 -261.125716) (xy 351.164998 -261.125287) (xy 351.146401 -261.117566)
			(xy 351.138998 -261.11073) (xy 350.641158 -260.61289) (xy 350.634307 -260.605494) (xy 350.626567 -260.586895)
			(xy 350.626172 -260.576822) (xy 350.626172 -253.583948) (xy 350.618552 -253.565152) (xy 350.611186 -253.55804)
			(xy 350.05645 -253.003304) (xy 350.050852 -252.99558) (xy 350.035347 -252.984499) (xy 350.026224 -252.981714)
			(xy 350.022414 -252.98019) (xy 350.016064 -252.98019) (xy 350.010984 -252.98019) (xy 347.901006 -252.98019)
			(xy 347.88221 -252.98781) (xy 347.875098 -252.995176) (xy 347.776292 -253.093982) (xy 347.768573 -253.099582)
			(xy 347.757504 -253.115091) (xy 347.754702 -253.124208) (xy 347.753178 -253.128018) (xy 347.753178 -253.134368)
			(xy 347.753178 -253.139448) (xy 347.753178 -254.276606) (xy 347.758004 -254.28702) (xy 347.769289 -254.312397)
			(xy 347.785231 -254.365596) (xy 347.793308 -254.420542) (xy 347.793818 -254.44831) (xy 347.793818 -254.448818)
			(xy 347.79332 -254.476588) (xy 347.785262 -254.531539) (xy 347.769305 -254.584737) (xy 347.758004 -254.610108)
			(xy 347.753178 -254.620522) (xy 347.753178 -254.759968) (xy 347.753539 -254.768663) (xy 347.75937 -254.785048)
			(xy 347.770339 -254.798545) (xy 347.777562 -254.803402) (xy 347.822774 -254.830834) (xy 347.823536 -254.83058)
			(xy 347.863414 -254.855218) (xy 347.88983 -254.856234) (xy 347.902022 -254.850138) (xy 347.929217 -254.836685)
			(xy 347.98681 -254.817609) (xy 348.046694 -254.807879) (xy 348.077028 -254.807212) (xy 348.083124 -254.807212)
			(xy 348.112732 -254.808201) (xy 348.17112 -254.818206) (xy 348.227259 -254.837118) (xy 348.279799 -254.864482)
			(xy 348.327478 -254.899639) (xy 348.369147 -254.941744) (xy 348.386908 -254.965454) (xy 348.390464 -254.97028)
			(xy 348.399354 -254.978154) (xy 348.424754 -254.991362) (xy 348.430284 -254.994063) (xy 348.442225 -254.997026)
			(xy 348.448376 -254.997204) (xy 348.506796 -254.997204) (xy 348.512948 -254.997032) (xy 348.524893 -254.994074)
			(xy 348.530418 -254.991362) (xy 348.550738 -254.980694) (xy 348.555734 -254.977887) (xy 348.564458 -254.970458)
			(xy 348.56801 -254.965962) (xy 348.568264 -254.965454) (xy 348.568518 -254.9652) (xy 348.583953 -254.944581)
			(xy 348.619477 -254.907285) (xy 348.659693 -254.875105) (xy 348.703872 -254.848626) (xy 348.75121 -254.828327)
			(xy 348.800847 -254.814579) (xy 348.851883 -254.807631) (xy 348.877636 -254.807212) (xy 348.904885 -254.807701)
			(xy 348.958828 -254.815462) (xy 349.011117 -254.83082) (xy 349.060688 -254.853463) (xy 349.106533 -254.882931)
			(xy 349.147717 -254.918623) (xy 349.183403 -254.959812) (xy 349.212863 -255.005661) (xy 349.2355 -255.055236)
			(xy 349.25085 -255.107527) (xy 349.258603 -255.161471) (xy 349.259144 -255.18872) (xy 349.258699 -255.215463)
			(xy 349.251236 -255.268426) (xy 349.236446 -255.319827) (xy 349.214618 -255.368657) (xy 349.186182 -255.413957)
			(xy 349.151694 -255.45484) (xy 349.111832 -255.490502) (xy 349.067378 -255.520244) (xy 349.019204 -255.543483)
			(xy 348.968255 -255.559762) (xy 348.915531 -255.568762) (xy 348.888812 -255.569974) (xy 348.879668 -255.570228)
			(xy 348.877636 -255.570228) (xy 348.851857 -255.569799) (xy 348.80077 -255.562847) (xy 348.751085 -255.549079)
			(xy 348.703706 -255.528745) (xy 348.659498 -255.502215) (xy 348.619264 -255.469974) (xy 348.58374 -255.432609)
			(xy 348.568264 -255.411986) (xy 348.564708 -255.40716) (xy 348.555818 -255.399286) (xy 348.530418 -255.386078)
			(xy 348.524887 -255.383383) (xy 348.512946 -255.38043) (xy 348.506796 -255.380236) (xy 348.448376 -255.380236)
			(xy 348.442221 -255.3804) (xy 348.43027 -255.383345) (xy 348.424754 -255.386078) (xy 348.399354 -255.399286)
			(xy 348.390464 -255.40716) (xy 348.386908 -255.411986) (xy 348.371477 -255.432644) (xy 348.335948 -255.470012)
			(xy 348.295708 -255.502253) (xy 348.251491 -255.528778) (xy 348.204105 -255.549106) (xy 348.154411 -255.562864)
			(xy 348.103317 -255.569801) (xy 348.077536 -255.570228) (xy 348.07144 -255.570228) (xy 348.043859 -255.5693)
			(xy 347.989381 -255.560488) (xy 347.936736 -255.543936) (xy 347.911674 -255.532382) (xy 347.906594 -255.529842)
			(xy 347.895418 -255.527302) (xy 347.868748 -255.527302) (xy 347.861796 -255.527539) (xy 347.848401 -255.53127)
			(xy 347.842332 -255.534668) (xy 347.777562 -255.574038) (xy 347.770308 -255.578859) (xy 347.759325 -255.592363)
			(xy 347.753508 -255.608768) (xy 347.753178 -255.617472) (xy 347.753178 -257.13055) (xy 348.495618 -257.13055)
			(xy 348.499689 -257.074928) (xy 348.511815 -257.020491) (xy 348.531738 -256.9684) (xy 348.559034 -256.919765)
			(xy 348.59312 -256.875622) (xy 348.633269 -256.836913) (xy 348.678627 -256.804462) (xy 348.728227 -256.778961)
			(xy 348.781011 -256.760954) (xy 348.835854 -256.750824) (xy 348.891588 -256.748787) (xy 348.947025 -256.754887)
			(xy 349.000982 -256.768993) (xy 349.052311 -256.790805) (xy 349.099917 -256.819859) (xy 349.142785 -256.855534)
			(xy 349.180002 -256.897071) (xy 349.210775 -256.943584) (xy 349.234447 -256.994081) (xy 349.250515 -257.047488)
			(xy 349.258635 -257.102664) (xy 349.259144 -257.13055) (xy 349.258635 -257.158436) (xy 349.250515 -257.213612)
			(xy 349.234447 -257.267019) (xy 349.210775 -257.317516) (xy 349.180002 -257.364029) (xy 349.142785 -257.405566)
			(xy 349.099917 -257.441241) (xy 349.052311 -257.470295) (xy 349.000982 -257.492107) (xy 348.947025 -257.506213)
			(xy 348.891588 -257.512313) (xy 348.835854 -257.510276) (xy 348.781011 -257.500146) (xy 348.728227 -257.482139)
			(xy 348.678627 -257.456638) (xy 348.633269 -257.424187) (xy 348.59312 -257.385478) (xy 348.559034 -257.341335)
			(xy 348.531738 -257.2927) (xy 348.511815 -257.240609) (xy 348.499689 -257.186172) (xy 348.495618 -257.13055)
			(xy 347.753178 -257.13055) (xy 347.753178 -258.01955) (xy 348.623128 -258.01955) (xy 348.623602 -257.992297)
			(xy 348.631353 -257.938344) (xy 348.646705 -257.886044) (xy 348.669344 -257.836462) (xy 348.69881 -257.790607)
			(xy 348.734503 -257.749413) (xy 348.775696 -257.713718) (xy 348.82155 -257.684251) (xy 348.871131 -257.661609)
			(xy 348.923431 -257.646256) (xy 348.977383 -257.638503) (xy 349.004636 -257.638042) (xy 349.031693 -257.638468)
			(xy 349.085261 -257.646131) (xy 349.13721 -257.661285) (xy 349.186497 -257.683626) (xy 349.232134 -257.712706)
			(xy 349.273205 -257.74794) (xy 349.308887 -257.788624) (xy 349.338463 -257.83394) (xy 349.35033 -257.85826)
			(xy 349.354394 -257.866642) (xy 349.367602 -257.879596) (xy 349.447104 -257.913886) (xy 349.465646 -257.914648)
			(xy 349.474536 -257.9116) (xy 349.50386 -257.902475) (xy 349.564481 -257.892654) (xy 349.595186 -257.892042)
			(xy 349.622443 -257.892404) (xy 349.676403 -257.90016) (xy 349.728709 -257.915517) (xy 349.778298 -257.938162)
			(xy 349.824158 -257.967633) (xy 349.865358 -258.003332) (xy 349.901058 -258.04453) (xy 349.930531 -258.09039)
			(xy 349.953178 -258.139978) (xy 349.968537 -258.192284) (xy 349.976295 -258.246243) (xy 349.976295 -258.300757)
			(xy 349.968537 -258.354716) (xy 349.953178 -258.407022) (xy 349.930531 -258.45661) (xy 349.901058 -258.50247)
			(xy 349.865358 -258.543668) (xy 349.824158 -258.579367) (xy 349.778298 -258.608838) (xy 349.728709 -258.631483)
			(xy 349.676403 -258.64684) (xy 349.622443 -258.654596) (xy 349.595186 -258.655058) (xy 349.574638 -258.654758)
			(xy 349.533782 -258.650305) (xy 349.513652 -258.646168) (xy 349.501714 -258.643628) (xy 349.478346 -258.649724)
			(xy 349.39859 -258.720336) (xy 349.3897 -258.742688) (xy 349.390716 -258.75488) (xy 349.392494 -258.79044)
			(xy 349.392008 -258.817691) (xy 349.384252 -258.871639) (xy 349.368897 -258.923934) (xy 349.346255 -258.973511)
			(xy 349.316789 -259.019361) (xy 349.281098 -259.060552) (xy 349.239907 -259.096243) (xy 349.194057 -259.125709)
			(xy 349.14448 -259.148351) (xy 349.092185 -259.163706) (xy 349.038237 -259.171462) (xy 348.983735 -259.171462)
			(xy 348.929787 -259.163706) (xy 348.877492 -259.148351) (xy 348.827915 -259.125709) (xy 348.782065 -259.096243)
			(xy 348.740874 -259.060552) (xy 348.705183 -259.019361) (xy 348.675717 -258.973511) (xy 348.653075 -258.923934)
			(xy 348.63772 -258.871639) (xy 348.629964 -258.817691) (xy 348.629478 -258.79044) (xy 348.630055 -258.761315)
			(xy 348.638916 -258.703744) (xy 348.656424 -258.648188) (xy 348.682173 -258.595939) (xy 348.715562 -258.548209)
			(xy 348.755818 -258.506109) (xy 348.778576 -258.487926) (xy 348.787974 -258.48056) (xy 348.798388 -258.459224)
			(xy 348.797626 -258.354068) (xy 348.786958 -258.332986) (xy 348.777052 -258.325874) (xy 348.753624 -258.307704)
			(xy 348.712094 -258.265398) (xy 348.677603 -258.21718) (xy 348.650979 -258.164211) (xy 348.632864 -258.107762)
			(xy 348.623692 -258.049192) (xy 348.623128 -258.01955) (xy 347.753178 -258.01955) (xy 347.753178 -258.544822)
			(xy 347.76156 -258.572) (xy 347.76537 -258.577842) (xy 347.779327 -258.600809) (xy 347.801357 -258.64983)
			(xy 347.816288 -258.701458) (xy 347.823825 -258.75467) (xy 347.823819 -258.808414) (xy 347.81627 -258.861625)
			(xy 347.801327 -258.913249) (xy 347.779287 -258.962265) (xy 347.76537 -258.985258) (xy 347.76156 -258.9911)
			(xy 347.753178 -259.018278) (xy 347.753178 -259.43433) (xy 347.752749 -259.444397) (xy 347.745024 -259.462992)
			(xy 347.738192 -259.470398) (xy 346.90177 -260.30682) (xy 346.894374 -260.31367) (xy 346.875775 -260.321407)
			(xy 346.865702 -260.321806) (xy 344.663268 -260.321806) (xy 344.644472 -260.329426) (xy 344.63736 -260.336792)
			(xy 344.481912 -260.49224) (xy 344.474186 -260.497836) (xy 344.463101 -260.513341) (xy 344.460322 -260.522466)
			(xy 344.458798 -260.526276) (xy 344.458798 -260.532626) (xy 344.458798 -260.537706) (xy 344.458798 -261.217664)
			(xy 346.340428 -261.217664) (xy 346.344499 -261.162042) (xy 346.356625 -261.107605) (xy 346.376548 -261.055514)
			(xy 346.403844 -261.006879) (xy 346.43793 -260.962736) (xy 346.478079 -260.924027) (xy 346.523437 -260.891576)
			(xy 346.573037 -260.866075) (xy 346.625821 -260.848068) (xy 346.680664 -260.837938) (xy 346.736398 -260.835901)
			(xy 346.791835 -260.842001) (xy 346.845792 -260.856107) (xy 346.897121 -260.877919) (xy 346.944727 -260.906973)
			(xy 346.987595 -260.942648) (xy 347.024812 -260.984185) (xy 347.055585 -261.030698) (xy 347.079257 -261.081195)
			(xy 347.095325 -261.134602) (xy 347.103445 -261.189778) (xy 347.103954 -261.217664) (xy 347.103445 -261.24555)
			(xy 347.095325 -261.300726) (xy 347.079257 -261.354133) (xy 347.055585 -261.40463) (xy 347.024812 -261.451143)
			(xy 346.987595 -261.49268) (xy 346.944727 -261.528355) (xy 346.897121 -261.557409) (xy 346.845792 -261.579221)
			(xy 346.791835 -261.593327) (xy 346.736398 -261.599427) (xy 346.680664 -261.59739) (xy 346.625821 -261.58726)
			(xy 346.573037 -261.569253) (xy 346.523437 -261.543752) (xy 346.478079 -261.511301) (xy 346.43793 -261.472592)
			(xy 346.403844 -261.428449) (xy 346.376548 -261.379814) (xy 346.356625 -261.327723) (xy 346.344499 -261.273286)
			(xy 346.340428 -261.217664) (xy 344.458798 -261.217664) (xy 344.458798 -261.241286) (xy 344.459436 -261.253844)
			(xy 344.471286 -261.275987) (xy 344.481404 -261.28345) (xy 344.551762 -261.33044) (xy 344.557141 -261.333801)
			(xy 344.56909 -261.338043) (xy 344.575384 -261.338822) (xy 344.58783 -261.339838) (xy 344.599514 -261.335012)
			(xy 344.622478 -261.325938) (xy 344.670161 -261.313116) (xy 344.719099 -261.306551) (xy 344.743786 -261.306056)
			(xy 344.749882 -261.306056) (xy 344.776918 -261.306852) (xy 344.830367 -261.315135) (xy 344.88211 -261.330884)
			(xy 344.93111 -261.353783) (xy 344.976385 -261.383375) (xy 345.017025 -261.419064) (xy 345.052217 -261.460136)
			(xy 345.081255 -261.505768) (xy 345.103556 -261.555043) (xy 345.118674 -261.606974) (xy 345.126304 -261.66052)
			(xy 345.126586 -261.675372) (xy 349.274636 -261.675372) (xy 349.278707 -261.61975) (xy 349.290833 -261.565313)
			(xy 349.310756 -261.513222) (xy 349.338052 -261.464587) (xy 349.372138 -261.420444) (xy 349.412287 -261.381735)
			(xy 349.457645 -261.349284) (xy 349.507245 -261.323783) (xy 349.560029 -261.305776) (xy 349.614872 -261.295646)
			(xy 349.670606 -261.293609) (xy 349.726043 -261.299709) (xy 349.78 -261.313815) (xy 349.831329 -261.335627)
			(xy 349.878935 -261.364681) (xy 349.921803 -261.400356) (xy 349.95902 -261.441893) (xy 349.989793 -261.488406)
			(xy 350.013465 -261.538903) (xy 350.029533 -261.59231) (xy 350.037653 -261.647486) (xy 350.038162 -261.675372)
			(xy 350.037653 -261.703258) (xy 350.029533 -261.758434) (xy 350.013465 -261.811841) (xy 349.989793 -261.862338)
			(xy 349.95902 -261.908851) (xy 349.921803 -261.950388) (xy 349.878935 -261.986063) (xy 349.831329 -262.015117)
			(xy 349.78 -262.036929) (xy 349.726043 -262.051035) (xy 349.670606 -262.057135) (xy 349.614872 -262.055098)
			(xy 349.560029 -262.044968) (xy 349.507245 -262.026961) (xy 349.457645 -262.00146) (xy 349.412287 -261.969009)
			(xy 349.372138 -261.9303) (xy 349.338052 -261.886157) (xy 349.310756 -261.837522) (xy 349.290833 -261.785431)
			(xy 349.278707 -261.730994) (xy 349.274636 -261.675372) (xy 345.126586 -261.675372) (xy 345.126818 -261.687564)
			(xy 345.126356 -261.714524) (xy 345.118769 -261.767907) (xy 345.103742 -261.81969) (xy 345.081573 -261.868841)
			(xy 345.052705 -261.914382) (xy 345.017713 -261.955404) (xy 344.997786 -261.973568) (xy 344.989912 -261.980426)
			(xy 344.981022 -261.999476) (xy 344.978482 -262.084058) (xy 344.978654 -262.094429) (xy 344.986254 -262.113706)
			(xy 344.993214 -262.121396) (xy 345.067371 -262.195564) (xy 348.581978 -262.195564) (xy 348.586049 -262.139942)
			(xy 348.598175 -262.085505) (xy 348.618098 -262.033414) (xy 348.645394 -261.984779) (xy 348.67948 -261.940636)
			(xy 348.719629 -261.901927) (xy 348.764987 -261.869476) (xy 348.814587 -261.843975) (xy 348.867371 -261.825968)
			(xy 348.922214 -261.815838) (xy 348.977948 -261.813801) (xy 349.033385 -261.819901) (xy 349.087342 -261.834007)
			(xy 349.138671 -261.855819) (xy 349.186277 -261.884873) (xy 349.229145 -261.920548) (xy 349.266362 -261.962085)
			(xy 349.297135 -262.008598) (xy 349.320807 -262.059095) (xy 349.336875 -262.112502) (xy 349.344995 -262.167678)
			(xy 349.345504 -262.195564) (xy 349.344995 -262.22345) (xy 349.336875 -262.278626) (xy 349.320807 -262.332033)
			(xy 349.297135 -262.38253) (xy 349.266362 -262.429043) (xy 349.229145 -262.47058) (xy 349.186277 -262.506255)
			(xy 349.138671 -262.535309) (xy 349.087342 -262.557121) (xy 349.033385 -262.571227) (xy 348.977948 -262.577327)
			(xy 348.922214 -262.57529) (xy 348.867371 -262.56516) (xy 348.814587 -262.547153) (xy 348.764987 -262.521652)
			(xy 348.719629 -262.489201) (xy 348.67948 -262.450492) (xy 348.645394 -262.406349) (xy 348.618098 -262.357714)
			(xy 348.598175 -262.305623) (xy 348.586049 -262.251186) (xy 348.581978 -262.195564) (xy 345.067371 -262.195564)
			(xy 345.943542 -263.071864) (xy 348.581978 -263.071864) (xy 348.586049 -263.016242) (xy 348.598175 -262.961805)
			(xy 348.618098 -262.909714) (xy 348.645394 -262.861079) (xy 348.67948 -262.816936) (xy 348.719629 -262.778227)
			(xy 348.764987 -262.745776) (xy 348.814587 -262.720275) (xy 348.867371 -262.702268) (xy 348.922214 -262.692138)
			(xy 348.977948 -262.690101) (xy 349.033385 -262.696201) (xy 349.087342 -262.710307) (xy 349.138671 -262.732119)
			(xy 349.186277 -262.761173) (xy 349.229145 -262.796848) (xy 349.266362 -262.838385) (xy 349.297135 -262.884898)
			(xy 349.320807 -262.935395) (xy 349.336875 -262.988802) (xy 349.344995 -263.043978) (xy 349.345504 -263.071864)
			(xy 349.344995 -263.09975) (xy 349.336875 -263.154926) (xy 349.320807 -263.208333) (xy 349.297135 -263.25883)
			(xy 349.266362 -263.305343) (xy 349.229145 -263.34688) (xy 349.186277 -263.382555) (xy 349.138671 -263.411609)
			(xy 349.087342 -263.433421) (xy 349.033385 -263.447527) (xy 348.977948 -263.453627) (xy 348.922214 -263.45159)
			(xy 348.867371 -263.44146) (xy 348.814587 -263.423453) (xy 348.764987 -263.397952) (xy 348.719629 -263.365501)
			(xy 348.67948 -263.326792) (xy 348.645394 -263.282649) (xy 348.618098 -263.234014) (xy 348.598175 -263.181923)
			(xy 348.586049 -263.127486) (xy 348.581978 -263.071864) (xy 345.943542 -263.071864) (xy 346.7227 -263.851136)
			(xy 346.722954 -263.851136) (xy 346.725748 -263.85393) (xy 346.765372 -263.8552) (xy 346.780612 -263.841992)
			(xy 346.801544 -263.824351) (xy 346.847511 -263.794627) (xy 346.897258 -263.771786) (xy 346.949761 -263.756298)
			(xy 347.00394 -263.748481) (xy 347.03131 -263.748012) (xy 347.058562 -263.748476) (xy 347.112511 -263.756234)
			(xy 347.164806 -263.771591) (xy 347.199936 -263.787636) (xy 349.771968 -263.787636) (xy 349.776039 -263.732014)
			(xy 349.788165 -263.677577) (xy 349.808088 -263.625486) (xy 349.835384 -263.576851) (xy 349.86947 -263.532708)
			(xy 349.909619 -263.493999) (xy 349.954977 -263.461548) (xy 350.004577 -263.436047) (xy 350.057361 -263.41804)
			(xy 350.112204 -263.40791) (xy 350.167938 -263.405873) (xy 350.223375 -263.411973) (xy 350.277332 -263.426079)
			(xy 350.328661 -263.447891) (xy 350.376267 -263.476945) (xy 350.419135 -263.51262) (xy 350.456352 -263.554157)
			(xy 350.487125 -263.60067) (xy 350.510797 -263.651167) (xy 350.526865 -263.704574) (xy 350.534985 -263.75975)
			(xy 350.535494 -263.787636) (xy 350.534985 -263.815522) (xy 350.526865 -263.870698) (xy 350.510797 -263.924105)
			(xy 350.487125 -263.974602) (xy 350.456352 -264.021115) (xy 350.419135 -264.062652) (xy 350.376267 -264.098327)
			(xy 350.328661 -264.127381) (xy 350.277332 -264.149193) (xy 350.223375 -264.163299) (xy 350.167938 -264.169399)
			(xy 350.112204 -264.167362) (xy 350.057361 -264.157232) (xy 350.004577 -264.139225) (xy 349.954977 -264.113724)
			(xy 349.909619 -264.081273) (xy 349.86947 -264.042564) (xy 349.835384 -263.998421) (xy 349.808088 -263.949786)
			(xy 349.788165 -263.897695) (xy 349.776039 -263.843258) (xy 349.771968 -263.787636) (xy 347.199936 -263.787636)
			(xy 347.214384 -263.794235) (xy 347.260234 -263.823703) (xy 347.301424 -263.859397) (xy 347.337115 -263.90059)
			(xy 347.36658 -263.946443) (xy 347.389219 -263.996022) (xy 347.404572 -264.048319) (xy 347.412326 -264.102268)
			(xy 347.412818 -264.12952) (xy 347.412345 -264.15689) (xy 347.404519 -264.211067) (xy 347.389031 -264.263569)
			(xy 347.366197 -264.313319) (xy 347.336488 -264.359295) (xy 347.318838 -264.380218) (xy 347.30563 -264.395458)
			(xy 347.3069 -264.435082) (xy 348.571312 -265.699494) (xy 348.57182 -265.700002) (xy 348.579197 -265.706595)
			(xy 348.597497 -265.714065) (xy 348.60738 -265.71448) (xy 350.201484 -265.71448) (xy 350.206439 -265.714363)
			(xy 350.216163 -265.71245) (xy 350.220788 -265.71067) (xy 350.221296 -265.710416) (xy 350.251268 -265.716512)
			(xy 350.629474 -266.094718) (xy 350.629982 -266.095226) (xy 350.637363 -266.101807) (xy 350.655663 -266.109251)
			(xy 350.665542 -266.109704)
		)
		(stroke
			(width 0)
			(type solid)
		)
		(fill yes)
		(layer "In11.Cu")
		(net "P0V8_PEX2_VREF")
	)
	(gr_poly
		(pts
			(xy 462.542128 -321.566286) (xy 462.552196 -321.565857) (xy 462.570791 -321.558134) (xy 462.578196 -321.5513)
			(xy 462.909158 -321.220338) (xy 462.915999 -321.212938) (xy 462.923718 -321.194339) (xy 462.924144 -321.18427)
			(xy 462.924144 -317.052706) (xy 462.92367 -317.042473) (xy 462.91568 -317.023629) (xy 462.900993 -317.009372)
			(xy 462.891632 -317.005208) (xy 462.815759 -316.975627) (xy 462.666646 -316.910117) (xy 462.520863 -316.837498)
			(xy 462.378748 -316.75794) (xy 462.240632 -316.671627) (xy 462.106834 -316.57876) (xy 461.977666 -316.479554)
			(xy 461.853428 -316.37424) (xy 461.734408 -316.263062) (xy 461.620884 -316.146279) (xy 461.513117 -316.024162)
			(xy 461.41136 -315.896994) (xy 461.315847 -315.765072) (xy 461.226802 -315.628701) (xy 461.14443 -315.488198)
			(xy 461.068924 -315.343889) (xy 461.000458 -315.19611) (xy 460.939192 -315.045205) (xy 460.885268 -314.891522)
			(xy 460.838811 -314.73542) (xy 460.799929 -314.577261) (xy 460.768712 -314.417412) (xy 460.745233 -314.256244)
			(xy 460.729546 -314.094133) (xy 460.721689 -313.931454) (xy 460.721202 -313.85002) (xy 460.721694 -313.768084)
			(xy 460.729637 -313.604405) (xy 460.745506 -313.441304) (xy 460.769263 -313.279164) (xy 460.800853 -313.118366)
			(xy 460.8402 -312.959289) (xy 460.887213 -312.802306) (xy 460.941781 -312.647787) (xy 461.003776 -312.496095)
			(xy 461.073052 -312.347586) (xy 461.149446 -312.202611) (xy 461.232778 -312.061509) (xy 461.322852 -311.924614)
			(xy 461.419457 -311.792246) (xy 461.522366 -311.664716) (xy 461.631336 -311.542326) (xy 461.746111 -311.425362)
			(xy 461.866421 -311.3141) (xy 461.991984 -311.208801) (xy 462.122504 -311.109713) (xy 462.257674 -311.017069)
			(xy 462.397176 -310.931087) (xy 462.540683 -310.851969) (xy 462.687856 -310.7799) (xy 462.83835 -310.715052)
			(xy 462.991811 -310.657575) (xy 463.069686 -310.632094) (xy 463.075432 -310.630106) (xy 463.085835 -310.623818)
			(xy 463.09026 -310.619648) (xy 465.627974 -308.081934) (xy 465.634578 -308.070504) (xy 465.636356 -308.0639)
			(xy 465.64344 -308.039102) (xy 465.663378 -307.99154) (xy 465.689548 -307.9471) (xy 465.721472 -307.906596)
			(xy 465.739734 -307.888386) (xy 465.746792 -307.880936) (xy 465.7548 -307.862062) (xy 465.755228 -307.85181)
			(xy 465.755228 -305.058826) (xy 465.754723 -305.048775) (xy 465.747004 -305.030213) (xy 465.740242 -305.022758)
			(xy 465.315554 -304.59807) (xy 465.308156 -304.591223) (xy 465.289557 -304.583494) (xy 465.279486 -304.583084)
			(xy 449.617846 -304.583084) (xy 449.60778 -304.583516) (xy 449.589188 -304.591243) (xy 449.581778 -304.59807)
			(xy 448.86118 -305.318668) (xy 448.854336 -305.326066) (xy 448.846613 -305.344666) (xy 448.846194 -305.354736)
			(xy 448.846194 -305.515518) (xy 448.862196 -305.54041) (xy 448.875658 -305.54676) (xy 448.949441 -305.581642)
			(xy 449.093925 -305.657579) (xy 449.234572 -305.740405) (xy 449.371057 -305.829925) (xy 449.503059 -305.925932)
			(xy 449.630272 -306.0282) (xy 449.752398 -306.136492) (xy 449.775075 -306.158646) (xy 459.899002 -306.158646)
			(xy 459.903073 -306.103024) (xy 459.915199 -306.048587) (xy 459.935122 -305.996496) (xy 459.962418 -305.947861)
			(xy 459.996504 -305.903718) (xy 460.036653 -305.865009) (xy 460.082011 -305.832558) (xy 460.131611 -305.807057)
			(xy 460.184395 -305.78905) (xy 460.239238 -305.77892) (xy 460.294972 -305.776883) (xy 460.350409 -305.782983)
			(xy 460.404366 -305.797089) (xy 460.455695 -305.818901) (xy 460.503301 -305.847955) (xy 460.546169 -305.88363)
			(xy 460.583386 -305.925167) (xy 460.614159 -305.97168) (xy 460.637831 -306.022177) (xy 460.653899 -306.075584)
			(xy 460.662019 -306.13076) (xy 460.662528 -306.158646) (xy 460.662019 -306.186532) (xy 460.653899 -306.241708)
			(xy 460.637831 -306.295115) (xy 460.614159 -306.345612) (xy 460.583386 -306.392125) (xy 460.546169 -306.433662)
			(xy 460.503301 -306.469337) (xy 460.455695 -306.498391) (xy 460.404366 -306.520203) (xy 460.350409 -306.534309)
			(xy 460.294972 -306.540409) (xy 460.239238 -306.538372) (xy 460.184395 -306.528242) (xy 460.131611 -306.510235)
			(xy 460.082011 -306.484734) (xy 460.036653 -306.452283) (xy 459.996504 -306.413574) (xy 459.962418 -306.369431)
			(xy 459.935122 -306.320796) (xy 459.915199 -306.268705) (xy 459.903073 -306.214268) (xy 459.899002 -306.158646)
			(xy 449.775075 -306.158646) (xy 449.869152 -306.250555) (xy 449.980262 -306.370123) (xy 450.085469 -306.494917)
			(xy 450.184527 -306.624645) (xy 450.277206 -306.759005) (xy 450.34459 -306.86756) (xy 452.570594 -306.86756)
			(xy 452.574665 -306.811938) (xy 452.586791 -306.757501) (xy 452.606714 -306.70541) (xy 452.63401 -306.656775)
			(xy 452.668096 -306.612632) (xy 452.708245 -306.573923) (xy 452.753603 -306.541472) (xy 452.803203 -306.515971)
			(xy 452.855987 -306.497964) (xy 452.91083 -306.487834) (xy 452.966564 -306.485797) (xy 453.022001 -306.491897)
			(xy 453.075958 -306.506003) (xy 453.127287 -306.527815) (xy 453.174893 -306.556869) (xy 453.217761 -306.592544)
			(xy 453.254978 -306.634081) (xy 453.285751 -306.680594) (xy 453.309423 -306.731091) (xy 453.325491 -306.784498)
			(xy 453.333611 -306.839674) (xy 453.33412 -306.86756) (xy 453.333611 -306.895446) (xy 453.325491 -306.950622)
			(xy 453.309423 -307.004029) (xy 453.285751 -307.054526) (xy 453.254978 -307.101039) (xy 453.217761 -307.142576)
			(xy 453.174893 -307.178251) (xy 453.127287 -307.207305) (xy 453.075958 -307.229117) (xy 453.022001 -307.243223)
			(xy 452.966564 -307.249323) (xy 452.91083 -307.247286) (xy 452.855987 -307.237156) (xy 452.803203 -307.219149)
			(xy 452.753603 -307.193648) (xy 452.708245 -307.161197) (xy 452.668096 -307.122488) (xy 452.63401 -307.078345)
			(xy 452.606714 -307.02971) (xy 452.586791 -306.977619) (xy 452.574665 -306.923182) (xy 452.570594 -306.86756)
			(xy 450.34459 -306.86756) (xy 450.363288 -306.897683) (xy 450.442573 -307.040357) (xy 450.514877 -307.186692)
			(xy 450.58003 -307.336349) (xy 450.63788 -307.488976) (xy 450.664149 -307.56987) (xy 457.496162 -307.56987)
			(xy 457.500233 -307.514248) (xy 457.512359 -307.459811) (xy 457.532282 -307.40772) (xy 457.559578 -307.359085)
			(xy 457.593664 -307.314942) (xy 457.633813 -307.276233) (xy 457.679171 -307.243782) (xy 457.728771 -307.218281)
			(xy 457.781555 -307.200274) (xy 457.836398 -307.190144) (xy 457.892132 -307.188107) (xy 457.947569 -307.194207)
			(xy 458.001526 -307.208313) (xy 458.052855 -307.230125) (xy 458.100461 -307.259179) (xy 458.143329 -307.294854)
			(xy 458.180546 -307.336391) (xy 458.211319 -307.382904) (xy 458.234991 -307.433401) (xy 458.251059 -307.486808)
			(xy 458.259179 -307.541984) (xy 458.259688 -307.56987) (xy 458.259179 -307.597756) (xy 458.257713 -307.607716)
			(xy 462.556604 -307.607716) (xy 462.560677 -307.552057) (xy 462.572812 -307.497584) (xy 462.592748 -307.445458)
			(xy 462.620062 -307.39679) (xy 462.65417 -307.352618) (xy 462.694347 -307.313883) (xy 462.739735 -307.281411)
			(xy 462.789367 -307.255893) (xy 462.842187 -307.237874) (xy 462.897066 -307.227737) (xy 462.952837 -307.225699)
			(xy 463.008311 -307.231802) (xy 463.062304 -307.245918) (xy 463.113667 -307.267745) (xy 463.161305 -307.296818)
			(xy 463.204201 -307.332517) (xy 463.241443 -307.374081) (xy 463.272237 -307.420625) (xy 463.295925 -307.471156)
			(xy 463.312003 -307.524598) (xy 463.320129 -307.579812) (xy 463.320638 -307.607716) (xy 463.320129 -307.63562)
			(xy 463.312003 -307.690834) (xy 463.295925 -307.744276) (xy 463.272237 -307.794807) (xy 463.241443 -307.841351)
			(xy 463.204201 -307.882915) (xy 463.161305 -307.918614) (xy 463.113667 -307.947687) (xy 463.062304 -307.969514)
			(xy 463.008311 -307.98363) (xy 462.952837 -307.989733) (xy 462.897066 -307.987695) (xy 462.842187 -307.977558)
			(xy 462.789367 -307.959539) (xy 462.739735 -307.934021) (xy 462.694347 -307.901549) (xy 462.65417 -307.862814)
			(xy 462.620062 -307.818642) (xy 462.592748 -307.769974) (xy 462.572812 -307.717848) (xy 462.560677 -307.663375)
			(xy 462.556604 -307.607716) (xy 458.257713 -307.607716) (xy 458.251059 -307.652932) (xy 458.234991 -307.706339)
			(xy 458.211319 -307.756836) (xy 458.180546 -307.803349) (xy 458.143329 -307.844886) (xy 458.100461 -307.880561)
			(xy 458.052855 -307.909615) (xy 458.001526 -307.931427) (xy 457.947569 -307.945533) (xy 457.892132 -307.951633)
			(xy 457.836398 -307.949596) (xy 457.781555 -307.939466) (xy 457.728771 -307.921459) (xy 457.679171 -307.895958)
			(xy 457.633813 -307.863507) (xy 457.593664 -307.824798) (xy 457.559578 -307.780655) (xy 457.532282 -307.73202)
			(xy 457.512359 -307.679929) (xy 457.500233 -307.625492) (xy 457.496162 -307.56987) (xy 450.664149 -307.56987)
			(xy 450.688293 -307.64422) (xy 450.731151 -307.801716) (xy 450.766354 -307.961098) (xy 450.793819 -308.121994)
			(xy 450.813483 -308.284029) (xy 450.8253 -308.446824) (xy 450.827205 -308.525672) (xy 458.554072 -308.525672)
			(xy 458.558143 -308.47005) (xy 458.570269 -308.415613) (xy 458.590192 -308.363522) (xy 458.617488 -308.314887)
			(xy 458.651574 -308.270744) (xy 458.691723 -308.232035) (xy 458.737081 -308.199584) (xy 458.786681 -308.174083)
			(xy 458.839465 -308.156076) (xy 458.894308 -308.145946) (xy 458.950042 -308.143909) (xy 459.005479 -308.150009)
			(xy 459.059436 -308.164115) (xy 459.110765 -308.185927) (xy 459.158371 -308.214981) (xy 459.201239 -308.250656)
			(xy 459.238456 -308.292193) (xy 459.269229 -308.338706) (xy 459.292901 -308.389203) (xy 459.308969 -308.44261)
			(xy 459.317089 -308.497786) (xy 459.317598 -308.525672) (xy 459.317089 -308.553558) (xy 459.308969 -308.608734)
			(xy 459.292901 -308.662141) (xy 459.278765 -308.692296) (xy 462.556604 -308.692296) (xy 462.560677 -308.636637)
			(xy 462.572812 -308.582164) (xy 462.592748 -308.530038) (xy 462.620062 -308.48137) (xy 462.65417 -308.437198)
			(xy 462.694347 -308.398463) (xy 462.739735 -308.365991) (xy 462.789367 -308.340473) (xy 462.842187 -308.322454)
			(xy 462.897066 -308.312317) (xy 462.952837 -308.310279) (xy 463.008311 -308.316382) (xy 463.062304 -308.330498)
			(xy 463.113667 -308.352325) (xy 463.161305 -308.381398) (xy 463.204201 -308.417097) (xy 463.241443 -308.458661)
			(xy 463.272237 -308.505205) (xy 463.295925 -308.555736) (xy 463.312003 -308.609178) (xy 463.320129 -308.664392)
			(xy 463.320638 -308.692296) (xy 463.320129 -308.7202) (xy 463.312003 -308.775414) (xy 463.295925 -308.828856)
			(xy 463.272237 -308.879387) (xy 463.241443 -308.925931) (xy 463.204201 -308.967495) (xy 463.161305 -309.003194)
			(xy 463.113667 -309.032267) (xy 463.062304 -309.054094) (xy 463.008311 -309.06821) (xy 462.952837 -309.074313)
			(xy 462.897066 -309.072275) (xy 462.842187 -309.062138) (xy 462.789367 -309.044119) (xy 462.739735 -309.018601)
			(xy 462.694347 -308.986129) (xy 462.65417 -308.947394) (xy 462.620062 -308.903222) (xy 462.592748 -308.854554)
			(xy 462.572812 -308.802428) (xy 462.560677 -308.747955) (xy 462.556604 -308.692296) (xy 459.278765 -308.692296)
			(xy 459.269229 -308.712638) (xy 459.238456 -308.759151) (xy 459.201239 -308.800688) (xy 459.158371 -308.836363)
			(xy 459.110765 -308.865417) (xy 459.059436 -308.887229) (xy 459.005479 -308.901335) (xy 458.950042 -308.907435)
			(xy 458.894308 -308.905398) (xy 458.839465 -308.895268) (xy 458.786681 -308.877261) (xy 458.737081 -308.85176)
			(xy 458.691723 -308.819309) (xy 458.651574 -308.7806) (xy 458.617488 -308.736457) (xy 458.590192 -308.687822)
			(xy 458.570269 -308.635731) (xy 458.558143 -308.581294) (xy 458.554072 -308.525672) (xy 450.827205 -308.525672)
			(xy 450.829242 -308.61) (xy 450.8253 -308.773176) (xy 450.813483 -308.935971) (xy 450.793819 -309.098006)
			(xy 450.786374 -309.141622) (xy 460.562196 -309.141622) (xy 460.566267 -309.086) (xy 460.578393 -309.031563)
			(xy 460.598316 -308.979472) (xy 460.625612 -308.930837) (xy 460.659698 -308.886694) (xy 460.699847 -308.847985)
			(xy 460.745205 -308.815534) (xy 460.794805 -308.790033) (xy 460.847589 -308.772026) (xy 460.902432 -308.761896)
			(xy 460.958166 -308.759859) (xy 461.013603 -308.765959) (xy 461.06756 -308.780065) (xy 461.118889 -308.801877)
			(xy 461.166495 -308.830931) (xy 461.209363 -308.866606) (xy 461.24658 -308.908143) (xy 461.277353 -308.954656)
			(xy 461.301025 -309.005153) (xy 461.317093 -309.05856) (xy 461.325213 -309.113736) (xy 461.325722 -309.141622)
			(xy 461.325213 -309.169508) (xy 461.317093 -309.224684) (xy 461.301025 -309.278091) (xy 461.277353 -309.328588)
			(xy 461.24658 -309.375101) (xy 461.209363 -309.416638) (xy 461.166495 -309.452313) (xy 461.118889 -309.481367)
			(xy 461.06756 -309.503179) (xy 461.013603 -309.517285) (xy 460.958166 -309.523385) (xy 460.902432 -309.521348)
			(xy 460.847589 -309.511218) (xy 460.794805 -309.493211) (xy 460.745205 -309.46771) (xy 460.699847 -309.435259)
			(xy 460.659698 -309.39655) (xy 460.625612 -309.352407) (xy 460.598316 -309.303772) (xy 460.578393 -309.251681)
			(xy 460.566267 -309.197244) (xy 460.562196 -309.141622) (xy 450.786374 -309.141622) (xy 450.766354 -309.258902)
			(xy 450.731151 -309.418284) (xy 450.688293 -309.57578) (xy 450.63788 -309.731024) (xy 450.58003 -309.883651)
			(xy 450.515493 -310.031892) (xy 456.942188 -310.031892) (xy 456.946259 -309.97627) (xy 456.958385 -309.921833)
			(xy 456.978308 -309.869742) (xy 457.005604 -309.821107) (xy 457.03969 -309.776964) (xy 457.079839 -309.738255)
			(xy 457.125197 -309.705804) (xy 457.174797 -309.680303) (xy 457.227581 -309.662296) (xy 457.282424 -309.652166)
			(xy 457.338158 -309.650129) (xy 457.393595 -309.656229) (xy 457.447552 -309.670335) (xy 457.498881 -309.692147)
			(xy 457.546487 -309.721201) (xy 457.589355 -309.756876) (xy 457.626572 -309.798413) (xy 457.657345 -309.844926)
			(xy 457.668429 -309.86857) (xy 458.657704 -309.86857) (xy 458.661775 -309.812948) (xy 458.673901 -309.758511)
			(xy 458.693824 -309.70642) (xy 458.72112 -309.657785) (xy 458.755206 -309.613642) (xy 458.795355 -309.574933)
			(xy 458.840713 -309.542482) (xy 458.890313 -309.516981) (xy 458.943097 -309.498974) (xy 458.99794 -309.488844)
			(xy 459.053674 -309.486807) (xy 459.109111 -309.492907) (xy 459.163068 -309.507013) (xy 459.214397 -309.528825)
			(xy 459.262003 -309.557879) (xy 459.304871 -309.593554) (xy 459.342088 -309.635091) (xy 459.372861 -309.681604)
			(xy 459.396533 -309.732101) (xy 459.412601 -309.785508) (xy 459.420721 -309.840684) (xy 459.42123 -309.86857)
			(xy 459.420721 -309.896456) (xy 459.412601 -309.951632) (xy 459.396533 -310.005039) (xy 459.372861 -310.055536)
			(xy 459.342088 -310.102049) (xy 459.304871 -310.143586) (xy 459.262003 -310.179261) (xy 459.214397 -310.208315)
			(xy 459.163068 -310.230127) (xy 459.109111 -310.244233) (xy 459.053674 -310.250333) (xy 458.99794 -310.248296)
			(xy 458.943097 -310.238166) (xy 458.890313 -310.220159) (xy 458.840713 -310.194658) (xy 458.795355 -310.162207)
			(xy 458.755206 -310.123498) (xy 458.72112 -310.079355) (xy 458.693824 -310.03072) (xy 458.673901 -309.978629)
			(xy 458.661775 -309.924192) (xy 458.657704 -309.86857) (xy 457.668429 -309.86857) (xy 457.681017 -309.895423)
			(xy 457.697085 -309.94883) (xy 457.705205 -310.004006) (xy 457.705714 -310.031892) (xy 457.705205 -310.059778)
			(xy 457.697085 -310.114954) (xy 457.681017 -310.168361) (xy 457.657345 -310.218858) (xy 457.626572 -310.265371)
			(xy 457.589355 -310.306908) (xy 457.546487 -310.342583) (xy 457.498881 -310.371637) (xy 457.447552 -310.393449)
			(xy 457.393595 -310.407555) (xy 457.338158 -310.413655) (xy 457.282424 -310.411618) (xy 457.227581 -310.401488)
			(xy 457.174797 -310.383481) (xy 457.125197 -310.35798) (xy 457.079839 -310.325529) (xy 457.03969 -310.28682)
			(xy 457.005604 -310.242677) (xy 456.978308 -310.194042) (xy 456.958385 -310.141951) (xy 456.946259 -310.087514)
			(xy 456.942188 -310.031892) (xy 450.515493 -310.031892) (xy 450.514877 -310.033308) (xy 450.442573 -310.179643)
			(xy 450.363288 -310.322317) (xy 450.277206 -310.460995) (xy 450.184527 -310.595355) (xy 450.085469 -310.725083)
			(xy 449.980262 -310.849877) (xy 449.869152 -310.969445) (xy 449.752398 -311.083508) (xy 449.630272 -311.1918)
			(xy 449.503059 -311.294068) (xy 449.440965 -311.33923) (xy 458.119986 -311.33923) (xy 458.124057 -311.283608)
			(xy 458.136183 -311.229171) (xy 458.156106 -311.17708) (xy 458.183402 -311.128445) (xy 458.217488 -311.084302)
			(xy 458.257637 -311.045593) (xy 458.302995 -311.013142) (xy 458.352595 -310.987641) (xy 458.405379 -310.969634)
			(xy 458.460222 -310.959504) (xy 458.515956 -310.957467) (xy 458.571393 -310.963567) (xy 458.62535 -310.977673)
			(xy 458.676679 -310.999485) (xy 458.724285 -311.028539) (xy 458.767153 -311.064214) (xy 458.80437 -311.105751)
			(xy 458.835143 -311.152264) (xy 458.858815 -311.202761) (xy 458.874883 -311.256168) (xy 458.883003 -311.311344)
			(xy 458.883512 -311.33923) (xy 458.883003 -311.367116) (xy 458.874883 -311.422292) (xy 458.858815 -311.475699)
			(xy 458.842059 -311.511442) (xy 459.73441 -311.511442) (xy 459.738481 -311.45582) (xy 459.750607 -311.401383)
			(xy 459.77053 -311.349292) (xy 459.797826 -311.300657) (xy 459.831912 -311.256514) (xy 459.872061 -311.217805)
			(xy 459.917419 -311.185354) (xy 459.967019 -311.159853) (xy 460.019803 -311.141846) (xy 460.074646 -311.131716)
			(xy 460.13038 -311.129679) (xy 460.185817 -311.135779) (xy 460.239774 -311.149885) (xy 460.291103 -311.171697)
			(xy 460.338709 -311.200751) (xy 460.381577 -311.236426) (xy 460.418794 -311.277963) (xy 460.449567 -311.324476)
			(xy 460.473239 -311.374973) (xy 460.489307 -311.42838) (xy 460.497427 -311.483556) (xy 460.497936 -311.511442)
			(xy 460.497427 -311.539328) (xy 460.489307 -311.594504) (xy 460.473239 -311.647911) (xy 460.449567 -311.698408)
			(xy 460.418794 -311.744921) (xy 460.381577 -311.786458) (xy 460.338709 -311.822133) (xy 460.291103 -311.851187)
			(xy 460.239774 -311.872999) (xy 460.185817 -311.887105) (xy 460.13038 -311.893205) (xy 460.074646 -311.891168)
			(xy 460.019803 -311.881038) (xy 459.967019 -311.863031) (xy 459.917419 -311.83753) (xy 459.872061 -311.805079)
			(xy 459.831912 -311.76637) (xy 459.797826 -311.722227) (xy 459.77053 -311.673592) (xy 459.750607 -311.621501)
			(xy 459.738481 -311.567064) (xy 459.73441 -311.511442) (xy 458.842059 -311.511442) (xy 458.835143 -311.526196)
			(xy 458.80437 -311.572709) (xy 458.767153 -311.614246) (xy 458.724285 -311.649921) (xy 458.676679 -311.678975)
			(xy 458.62535 -311.700787) (xy 458.571393 -311.714893) (xy 458.515956 -311.720993) (xy 458.460222 -311.718956)
			(xy 458.405379 -311.708826) (xy 458.352595 -311.690819) (xy 458.302995 -311.665318) (xy 458.257637 -311.632867)
			(xy 458.217488 -311.594158) (xy 458.183402 -311.550015) (xy 458.156106 -311.50138) (xy 458.136183 -311.449289)
			(xy 458.124057 -311.394852) (xy 458.119986 -311.33923) (xy 449.440965 -311.33923) (xy 449.371057 -311.390075)
			(xy 449.234572 -311.479595) (xy 449.093925 -311.562421) (xy 448.949441 -311.638358) (xy 448.875658 -311.67324)
			(xy 448.867103 -311.677692) (xy 448.853864 -311.691696) (xy 448.84669 -311.709581) (xy 448.846194 -311.719214)
			(xy 448.846194 -320.940176) (xy 455.509122 -320.940176) (xy 455.509569 -320.912805) (xy 455.51739 -320.858625)
			(xy 455.532884 -320.806121) (xy 455.55573 -320.756375) (xy 455.585459 -320.710409) (xy 455.603102 -320.689478)
			(xy 455.609198 -320.682366) (xy 455.615548 -320.665348) (xy 455.615548 -320.580004) (xy 455.609198 -320.562986)
			(xy 455.603102 -320.555874) (xy 455.585484 -320.534925) (xy 455.555769 -320.488957) (xy 455.532929 -320.439213)
			(xy 455.517433 -320.386717) (xy 455.509599 -320.332544) (xy 455.509122 -320.305176) (xy 455.509533 -320.277921)
			(xy 455.517294 -320.223967) (xy 455.532654 -320.171666) (xy 455.555302 -320.122084) (xy 455.584775 -320.076229)
			(xy 455.620474 -320.035036) (xy 455.661673 -319.999343) (xy 455.707531 -319.969876) (xy 455.757117 -319.947235)
			(xy 455.80942 -319.931882) (xy 455.863375 -319.924129) (xy 455.89063 -319.923668) (xy 455.918002 -319.9241)
			(xy 455.972183 -319.931923) (xy 456.024687 -319.94742) (xy 456.074433 -319.970269) (xy 456.120398 -320.000002)
			(xy 456.141328 -320.017648) (xy 456.14844 -320.023744) (xy 456.165458 -320.030094) (xy 456.250802 -320.030094)
			(xy 456.26782 -320.023744) (xy 456.274932 -320.017648) (xy 456.295865 -320.000007) (xy 456.341833 -319.970283)
			(xy 456.391579 -319.947437) (xy 456.444081 -319.931941) (xy 456.498259 -319.924112) (xy 456.553001 -319.924112)
			(xy 456.607179 -319.931941) (xy 456.659681 -319.947437) (xy 456.709427 -319.970283) (xy 456.755395 -320.000007)
			(xy 456.776328 -320.017648) (xy 456.78344 -320.023744) (xy 456.800458 -320.030094) (xy 456.885802 -320.030094)
			(xy 456.90282 -320.023744) (xy 456.909932 -320.017648) (xy 456.930885 -320.000035) (xy 456.976851 -319.970317)
			(xy 457.026593 -319.947476) (xy 457.07909 -319.931979) (xy 457.133262 -319.924145) (xy 457.16063 -319.923668)
			(xy 457.187881 -319.92415) (xy 457.241828 -319.93191) (xy 457.294121 -319.947268) (xy 457.343697 -319.96991)
			(xy 457.389546 -319.999378) (xy 457.430735 -320.035069) (xy 457.466426 -320.076259) (xy 457.495892 -320.122109)
			(xy 457.518535 -320.171685) (xy 457.533891 -320.223978) (xy 457.541651 -320.277925) (xy 457.542138 -320.305176)
			(xy 457.541673 -320.332546) (xy 457.533857 -320.386726) (xy 457.518369 -320.43923) (xy 457.495526 -320.488977)
			(xy 457.4658 -320.534943) (xy 457.448158 -320.555874) (xy 457.442062 -320.562986) (xy 457.435712 -320.580004)
			(xy 457.435712 -320.665348) (xy 457.442062 -320.682366) (xy 457.448158 -320.689478) (xy 457.465794 -320.710413)
			(xy 457.495507 -320.756384) (xy 457.518345 -320.806131) (xy 457.533836 -320.858631) (xy 457.541664 -320.912807)
			(xy 457.542138 -320.940176) (xy 457.5416 -320.967425) (xy 457.533847 -321.021369) (xy 457.518496 -321.073661)
			(xy 457.49586 -321.123236) (xy 457.466399 -321.169085) (xy 457.430713 -321.210275) (xy 457.389529 -321.245967)
			(xy 457.343684 -321.275434) (xy 457.294112 -321.298078) (xy 457.241822 -321.313436) (xy 457.187879 -321.321196)
			(xy 457.16063 -321.321684) (xy 457.13326 -321.321204) (xy 457.079082 -321.31339) (xy 457.026578 -321.297905)
			(xy 456.976831 -321.275066) (xy 456.930864 -321.245344) (xy 456.909932 -321.227704) (xy 456.90282 -321.221608)
			(xy 456.885802 -321.215258) (xy 456.800458 -321.215258) (xy 456.78344 -321.221608) (xy 456.776328 -321.227704)
			(xy 456.755395 -321.245345) (xy 456.709427 -321.275069) (xy 456.659681 -321.297915) (xy 456.607179 -321.313411)
			(xy 456.553001 -321.32124) (xy 456.498259 -321.32124) (xy 456.444081 -321.313411) (xy 456.391579 -321.297915)
			(xy 456.341833 -321.275069) (xy 456.295865 -321.245345) (xy 456.274932 -321.227704) (xy 456.26782 -321.221608)
			(xy 456.250802 -321.215258) (xy 456.165458 -321.215258) (xy 456.14844 -321.221608) (xy 456.141328 -321.227704)
			(xy 456.120397 -321.245344) (xy 456.074424 -321.275056) (xy 456.024676 -321.297891) (xy 455.972175 -321.313382)
			(xy 455.917999 -321.32121) (xy 455.89063 -321.321684) (xy 455.863377 -321.321217) (xy 455.809425 -321.313463)
			(xy 455.757126 -321.29811) (xy 455.707544 -321.275469) (xy 455.661689 -321.246002) (xy 455.620496 -321.210308)
			(xy 455.584802 -321.169115) (xy 455.555334 -321.123261) (xy 455.532692 -321.07368) (xy 455.517338 -321.021381)
			(xy 455.509584 -320.967429) (xy 455.509122 -320.940176) (xy 448.846194 -320.940176) (xy 448.846194 -321.245992)
			(xy 448.846615 -321.256063) (xy 448.854327 -321.27467) (xy 448.86118 -321.28206) (xy 449.13042 -321.5513)
			(xy 449.13782 -321.558143) (xy 449.156418 -321.56587) (xy 449.166488 -321.566286)
		)
		(stroke
			(width 0)
			(type solid)
		)
		(fill yes)
		(layer "In11.Cu")
		(net "GND")
	)
	(gr_poly
		(pts
			(xy 231.92105 -321.442842) (xy 231.930925 -321.442377) (xy 231.94922 -321.43493) (xy 231.95661 -321.428364)
			(xy 231.956864 -321.42811) (xy 232.28808 -321.096894) (xy 232.288588 -321.096386) (xy 232.295173 -321.089005)
			(xy 232.302632 -321.070707) (xy 232.303066 -321.060826) (xy 232.303066 -310.621172) (xy 232.302616 -310.609749)
			(xy 232.292842 -310.589109) (xy 232.28427 -310.581548) (xy 232.213912 -310.524652) (xy 232.19156 -310.519318)
			(xy 232.180384 -310.521604) (xy 232.160805 -310.525509) (xy 232.121099 -310.529709) (xy 232.101136 -310.529986)
			(xy 232.073882 -310.529525) (xy 232.019928 -310.521772) (xy 231.967627 -310.506419) (xy 231.918044 -310.483778)
			(xy 231.872188 -310.454311) (xy 231.830993 -310.418617) (xy 231.795297 -310.377423) (xy 231.765828 -310.331568)
			(xy 231.743186 -310.281986) (xy 231.727831 -310.229685) (xy 231.720076 -310.175732) (xy 231.719628 -310.148478)
			(xy 231.720189 -310.118881) (xy 231.72934 -310.060399) (xy 231.74742 -310.004034) (xy 231.773994 -309.951141)
			(xy 231.790748 -309.926736) (xy 231.79913 -309.915052) (xy 231.801162 -309.886858) (xy 231.753156 -309.79364)
			(xy 231.748526 -309.785563) (xy 231.734645 -309.773181) (xy 231.717247 -309.7666) (xy 231.707944 -309.766208)
			(xy 231.189784 -309.766208) (xy 231.177084 -309.767732) (xy 231.158542 -309.772812) (xy 231.1527 -309.776114)
			(xy 231.131046 -309.787962) (xy 231.085338 -309.806599) (xy 231.037611 -309.819194) (xy 230.988659 -309.825536)
			(xy 230.963978 -309.825898) (xy 230.935195 -309.825372) (xy 230.878284 -309.81672) (xy 230.823318 -309.799616)
			(xy 230.771546 -309.774447) (xy 230.724144 -309.741786) (xy 230.682186 -309.702374) (xy 230.646626 -309.657105)
			(xy 230.618271 -309.607007) (xy 230.597765 -309.553218) (xy 230.585573 -309.496958) (xy 230.583232 -309.468266)
			(xy 230.58247 -309.456074) (xy 230.570532 -309.435754) (xy 230.483156 -309.377588) (xy 230.459788 -309.37454)
			(xy 230.448358 -309.378604) (xy 230.417993 -309.388448) (xy 230.35505 -309.399047) (xy 230.323136 -309.399686)
			(xy 230.295883 -309.399225) (xy 230.241931 -309.391473) (xy 230.189632 -309.376121) (xy 230.14005 -309.353482)
			(xy 230.094195 -309.324016) (xy 230.053001 -309.288325) (xy 230.017305 -309.247133) (xy 229.987836 -309.201281)
			(xy 229.965192 -309.151702) (xy 229.949835 -309.099404) (xy 229.942077 -309.045453) (xy 229.942077 -308.990947)
			(xy 229.949835 -308.936996) (xy 229.965192 -308.884698) (xy 229.987836 -308.835119) (xy 230.017305 -308.789267)
			(xy 230.053001 -308.748075) (xy 230.094195 -308.712384) (xy 230.14005 -308.682918) (xy 230.189632 -308.660279)
			(xy 230.241931 -308.644927) (xy 230.295883 -308.637175) (xy 230.323136 -308.63667) (xy 230.351919 -308.637197)
			(xy 230.40883 -308.64585) (xy 230.463796 -308.662956) (xy 230.515568 -308.688124) (xy 230.562972 -308.720785)
			(xy 230.60493 -308.760197) (xy 230.640492 -308.805465) (xy 230.668849 -308.855561) (xy 230.689359 -308.90935)
			(xy 230.701555 -308.965609) (xy 230.703882 -308.994302) (xy 230.704644 -309.006494) (xy 230.716582 -309.026814)
			(xy 230.803958 -309.08498) (xy 230.827326 -309.088028) (xy 230.838756 -309.083964) (xy 230.869121 -309.074122)
			(xy 230.932064 -309.063526) (xy 230.963978 -309.062882) (xy 230.98866 -309.06325) (xy 231.037615 -309.069575)
			(xy 231.085346 -309.082162) (xy 231.131055 -309.100799) (xy 231.1527 -309.112666) (xy 231.158542 -309.115968)
			(xy 231.177084 -309.121048) (xy 231.189784 -309.122572) (xy 232.252266 -309.122572) (xy 232.26229 -309.122158)
			(xy 232.280813 -309.114493) (xy 232.294989 -309.100318) (xy 232.302657 -309.081796) (xy 232.303066 -309.071772)
			(xy 232.303066 -308.977284) (xy 232.278682 -308.948836) (xy 232.259886 -308.946042) (xy 232.233183 -308.941483)
			(xy 232.181331 -308.925811) (xy 232.132216 -308.902962) (xy 232.086827 -308.873396) (xy 232.046076 -308.837706)
			(xy 232.010784 -308.796612) (xy 231.981658 -308.750939) (xy 231.959286 -308.701605) (xy 231.944117 -308.649603)
			(xy 231.936456 -308.595978) (xy 231.936457 -308.541808) (xy 231.94412 -308.488183) (xy 231.959291 -308.436182)
			(xy 231.981665 -308.386849) (xy 232.010792 -308.341176) (xy 232.046087 -308.300083) (xy 232.086838 -308.264396)
			(xy 232.132229 -308.234831) (xy 232.181344 -308.211984) (xy 232.233198 -308.196313) (xy 232.259886 -308.191662)
			(xy 232.278682 -308.188868) (xy 232.303066 -308.16042) (xy 232.303066 -307.892704) (xy 232.278682 -307.864256)
			(xy 232.259886 -307.861462) (xy 232.233182 -307.856903) (xy 232.181326 -307.841231) (xy 232.132209 -307.818381)
			(xy 232.086817 -307.788813) (xy 232.046064 -307.753122) (xy 232.010769 -307.712026) (xy 231.981642 -307.666351)
			(xy 231.959269 -307.617014) (xy 231.944098 -307.56501) (xy 231.936437 -307.511382) (xy 231.936437 -307.45721)
			(xy 231.9441 -307.403582) (xy 231.959272 -307.351578) (xy 231.981646 -307.302242) (xy 232.010775 -307.256567)
			(xy 232.04607 -307.215472) (xy 232.086824 -307.179782) (xy 232.132216 -307.150215) (xy 232.181334 -307.127366)
			(xy 232.23319 -307.111695) (xy 232.259886 -307.107082) (xy 232.278682 -307.104288) (xy 232.303066 -307.07584)
			(xy 232.303066 -304.60696) (xy 232.302635 -304.596894) (xy 232.294906 -304.578303) (xy 232.28808 -304.570892)
			(xy 231.958134 -304.240946) (xy 231.950734 -304.234105) (xy 231.932135 -304.226387) (xy 231.922066 -304.22596)
			(xy 221.980506 -304.22596) (xy 221.970437 -304.226384) (xy 221.951836 -304.234103) (xy 221.944438 -304.240946)
			(xy 219.441268 -306.744116) (xy 221.949516 -306.744116) (xy 221.953587 -306.688494) (xy 221.965713 -306.634057)
			(xy 221.985636 -306.581966) (xy 222.012932 -306.533331) (xy 222.047018 -306.489188) (xy 222.087167 -306.450479)
			(xy 222.132525 -306.418028) (xy 222.182125 -306.392527) (xy 222.234909 -306.37452) (xy 222.289752 -306.36439)
			(xy 222.345486 -306.362353) (xy 222.400923 -306.368453) (xy 222.45488 -306.382559) (xy 222.506209 -306.404371)
			(xy 222.553815 -306.433425) (xy 222.596683 -306.4691) (xy 222.6339 -306.510637) (xy 222.664673 -306.55715)
			(xy 222.688345 -306.607647) (xy 222.704413 -306.661054) (xy 222.712533 -306.71623) (xy 222.713042 -306.744116)
			(xy 222.712533 -306.772002) (xy 222.71032 -306.787042) (xy 229.223568 -306.787042) (xy 229.227639 -306.73142)
			(xy 229.239765 -306.676983) (xy 229.259688 -306.624892) (xy 229.286984 -306.576257) (xy 229.32107 -306.532114)
			(xy 229.361219 -306.493405) (xy 229.406577 -306.460954) (xy 229.456177 -306.435453) (xy 229.508961 -306.417446)
			(xy 229.563804 -306.407316) (xy 229.619538 -306.405279) (xy 229.674975 -306.411379) (xy 229.728932 -306.425485)
			(xy 229.780261 -306.447297) (xy 229.827867 -306.476351) (xy 229.870735 -306.512026) (xy 229.907952 -306.553563)
			(xy 229.938725 -306.600076) (xy 229.962397 -306.650573) (xy 229.978465 -306.70398) (xy 229.986585 -306.759156)
			(xy 229.987094 -306.787042) (xy 229.986585 -306.814928) (xy 229.978465 -306.870104) (xy 229.962397 -306.923511)
			(xy 229.938725 -306.974008) (xy 229.907952 -307.020521) (xy 229.870735 -307.062058) (xy 229.827867 -307.097733)
			(xy 229.780261 -307.126787) (xy 229.728932 -307.148599) (xy 229.674975 -307.162705) (xy 229.619538 -307.168805)
			(xy 229.563804 -307.166768) (xy 229.508961 -307.156638) (xy 229.456177 -307.138631) (xy 229.406577 -307.11313)
			(xy 229.361219 -307.080679) (xy 229.32107 -307.04197) (xy 229.286984 -306.997827) (xy 229.259688 -306.949192)
			(xy 229.239765 -306.897101) (xy 229.227639 -306.842664) (xy 229.223568 -306.787042) (xy 222.71032 -306.787042)
			(xy 222.704413 -306.827178) (xy 222.688345 -306.880585) (xy 222.664673 -306.931082) (xy 222.6339 -306.977595)
			(xy 222.596683 -307.019132) (xy 222.553815 -307.054807) (xy 222.506209 -307.083861) (xy 222.45488 -307.105673)
			(xy 222.400923 -307.119779) (xy 222.345486 -307.125879) (xy 222.289752 -307.123842) (xy 222.234909 -307.113712)
			(xy 222.182125 -307.095705) (xy 222.132525 -307.070204) (xy 222.087167 -307.037753) (xy 222.047018 -306.999044)
			(xy 222.012932 -306.954901) (xy 221.985636 -306.906266) (xy 221.965713 -306.854175) (xy 221.953587 -306.799738)
			(xy 221.949516 -306.744116) (xy 219.441268 -306.744116) (xy 218.738958 -307.446426) (xy 226.875084 -307.446426)
			(xy 226.879155 -307.390804) (xy 226.891281 -307.336367) (xy 226.911204 -307.284276) (xy 226.9385 -307.235641)
			(xy 226.972586 -307.191498) (xy 227.012735 -307.152789) (xy 227.058093 -307.120338) (xy 227.107693 -307.094837)
			(xy 227.160477 -307.07683) (xy 227.21532 -307.0667) (xy 227.271054 -307.064663) (xy 227.326491 -307.070763)
			(xy 227.380448 -307.084869) (xy 227.431777 -307.106681) (xy 227.479383 -307.135735) (xy 227.522251 -307.17141)
			(xy 227.559468 -307.212947) (xy 227.590241 -307.25946) (xy 227.613913 -307.309957) (xy 227.629981 -307.363364)
			(xy 227.638101 -307.41854) (xy 227.63861 -307.446426) (xy 227.638101 -307.474312) (xy 227.629981 -307.529488)
			(xy 227.613913 -307.582895) (xy 227.590241 -307.633392) (xy 227.559468 -307.679905) (xy 227.522251 -307.721442)
			(xy 227.479383 -307.757117) (xy 227.431777 -307.786171) (xy 227.380448 -307.807983) (xy 227.326491 -307.822089)
			(xy 227.271054 -307.828189) (xy 227.21532 -307.826152) (xy 227.160477 -307.816022) (xy 227.107693 -307.798015)
			(xy 227.058093 -307.772514) (xy 227.012735 -307.740063) (xy 226.972586 -307.701354) (xy 226.9385 -307.657211)
			(xy 226.911204 -307.608576) (xy 226.891281 -307.556485) (xy 226.879155 -307.502048) (xy 226.875084 -307.446426)
			(xy 218.738958 -307.446426) (xy 218.240102 -307.945282) (xy 218.233268 -307.952685) (xy 218.225564 -307.971283)
			(xy 218.225116 -307.98135) (xy 218.225116 -307.988716) (xy 218.225254 -307.993749) (xy 218.227296 -308.003605)
			(xy 218.22918 -308.008274) (xy 218.234006 -308.017164) (xy 218.2495 -308.040278) (xy 218.26093 -308.049422)
			(xy 218.268042 -308.05247) (xy 218.344927 -308.084434) (xy 218.495791 -308.154939) (xy 218.642998 -308.232791)
			(xy 218.786191 -308.317801) (xy 218.913647 -308.402228) (xy 227.932994 -308.402228) (xy 227.937065 -308.346606)
			(xy 227.949191 -308.292169) (xy 227.969114 -308.240078) (xy 227.99641 -308.191443) (xy 228.030496 -308.1473)
			(xy 228.070645 -308.108591) (xy 228.116003 -308.07614) (xy 228.165603 -308.050639) (xy 228.218387 -308.032632)
			(xy 228.27323 -308.022502) (xy 228.328964 -308.020465) (xy 228.384401 -308.026565) (xy 228.438358 -308.040671)
			(xy 228.489687 -308.062483) (xy 228.537293 -308.091537) (xy 228.580161 -308.127212) (xy 228.617378 -308.168749)
			(xy 228.648151 -308.215262) (xy 228.671823 -308.265759) (xy 228.687891 -308.319166) (xy 228.696011 -308.374342)
			(xy 228.69652 -308.402228) (xy 228.696011 -308.430114) (xy 228.687891 -308.48529) (xy 228.671823 -308.538697)
			(xy 228.648151 -308.589194) (xy 228.617378 -308.635707) (xy 228.580161 -308.677244) (xy 228.537293 -308.712919)
			(xy 228.489687 -308.741973) (xy 228.438358 -308.763785) (xy 228.384401 -308.777891) (xy 228.328964 -308.783991)
			(xy 228.27323 -308.781954) (xy 228.218387 -308.771824) (xy 228.165603 -308.753817) (xy 228.116003 -308.728316)
			(xy 228.070645 -308.695865) (xy 228.030496 -308.657156) (xy 227.99641 -308.613013) (xy 227.969114 -308.564378)
			(xy 227.949191 -308.512287) (xy 227.937065 -308.45785) (xy 227.932994 -308.402228) (xy 218.913647 -308.402228)
			(xy 218.925022 -308.409763) (xy 219.059153 -308.508454) (xy 219.188259 -308.613632) (xy 219.312026 -308.725044)
			(xy 219.430154 -308.842419) (xy 219.542355 -308.965471) (xy 219.648358 -309.093901) (xy 219.747904 -309.227399)
			(xy 219.840752 -309.365638) (xy 219.926676 -309.508284) (xy 220.005468 -309.654991) (xy 220.076937 -309.805401)
			(xy 220.119812 -309.908448) (xy 226.32111 -309.908448) (xy 226.325181 -309.852826) (xy 226.337307 -309.798389)
			(xy 226.35723 -309.746298) (xy 226.384526 -309.697663) (xy 226.418612 -309.65352) (xy 226.458761 -309.614811)
			(xy 226.504119 -309.58236) (xy 226.553719 -309.556859) (xy 226.606503 -309.538852) (xy 226.661346 -309.528722)
			(xy 226.71708 -309.526685) (xy 226.772517 -309.532785) (xy 226.826474 -309.546891) (xy 226.877803 -309.568703)
			(xy 226.925409 -309.597757) (xy 226.968277 -309.633432) (xy 227.005494 -309.674969) (xy 227.036267 -309.721482)
			(xy 227.047351 -309.745126) (xy 228.036626 -309.745126) (xy 228.040697 -309.689504) (xy 228.052823 -309.635067)
			(xy 228.072746 -309.582976) (xy 228.100042 -309.534341) (xy 228.134128 -309.490198) (xy 228.174277 -309.451489)
			(xy 228.219635 -309.419038) (xy 228.269235 -309.393537) (xy 228.322019 -309.37553) (xy 228.376862 -309.3654)
			(xy 228.432596 -309.363363) (xy 228.488033 -309.369463) (xy 228.54199 -309.383569) (xy 228.593319 -309.405381)
			(xy 228.640925 -309.434435) (xy 228.683793 -309.47011) (xy 228.72101 -309.511647) (xy 228.751783 -309.55816)
			(xy 228.775455 -309.608657) (xy 228.791523 -309.662064) (xy 228.799643 -309.71724) (xy 228.800152 -309.745126)
			(xy 228.799643 -309.773012) (xy 228.791523 -309.828188) (xy 228.775455 -309.881595) (xy 228.751783 -309.932092)
			(xy 228.72101 -309.978605) (xy 228.683793 -310.020142) (xy 228.640925 -310.055817) (xy 228.593319 -310.084871)
			(xy 228.54199 -310.106683) (xy 228.488033 -310.120789) (xy 228.432596 -310.126889) (xy 228.376862 -310.124852)
			(xy 228.322019 -310.114722) (xy 228.269235 -310.096715) (xy 228.219635 -310.071214) (xy 228.174277 -310.038763)
			(xy 228.134128 -310.000054) (xy 228.100042 -309.955911) (xy 228.072746 -309.907276) (xy 228.052823 -309.855185)
			(xy 228.040697 -309.800748) (xy 228.036626 -309.745126) (xy 227.047351 -309.745126) (xy 227.059939 -309.771979)
			(xy 227.076007 -309.825386) (xy 227.084127 -309.880562) (xy 227.084636 -309.908448) (xy 227.084127 -309.936334)
			(xy 227.076007 -309.99151) (xy 227.059939 -310.044917) (xy 227.036267 -310.095414) (xy 227.005494 -310.141927)
			(xy 226.968277 -310.183464) (xy 226.925409 -310.219139) (xy 226.877803 -310.248193) (xy 226.826474 -310.270005)
			(xy 226.772517 -310.284111) (xy 226.71708 -310.290211) (xy 226.661346 -310.288174) (xy 226.606503 -310.278044)
			(xy 226.553719 -310.260037) (xy 226.504119 -310.234536) (xy 226.458761 -310.202085) (xy 226.418612 -310.163376)
			(xy 226.384526 -310.119233) (xy 226.35723 -310.070598) (xy 226.337307 -310.018507) (xy 226.325181 -309.96407)
			(xy 226.32111 -309.908448) (xy 220.119812 -309.908448) (xy 220.140908 -309.959149) (xy 220.197226 -310.115863)
			(xy 220.245755 -310.275161) (xy 220.286377 -310.436657) (xy 220.317192 -310.590946) (xy 230.918764 -310.590946)
			(xy 230.922835 -310.535324) (xy 230.934961 -310.480887) (xy 230.954884 -310.428796) (xy 230.98218 -310.380161)
			(xy 231.016266 -310.336018) (xy 231.056415 -310.297309) (xy 231.101773 -310.264858) (xy 231.151373 -310.239357)
			(xy 231.204157 -310.22135) (xy 231.259 -310.21122) (xy 231.314734 -310.209183) (xy 231.370171 -310.215283)
			(xy 231.424128 -310.229389) (xy 231.475457 -310.251201) (xy 231.523063 -310.280255) (xy 231.565931 -310.31593)
			(xy 231.603148 -310.357467) (xy 231.633921 -310.40398) (xy 231.657593 -310.454477) (xy 231.673661 -310.507884)
			(xy 231.681781 -310.56306) (xy 231.68229 -310.590946) (xy 231.681781 -310.618832) (xy 231.673661 -310.674008)
			(xy 231.657593 -310.727415) (xy 231.633921 -310.777912) (xy 231.603148 -310.824425) (xy 231.565931 -310.865962)
			(xy 231.523063 -310.901637) (xy 231.475457 -310.930691) (xy 231.424128 -310.952503) (xy 231.370171 -310.966609)
			(xy 231.314734 -310.972709) (xy 231.259 -310.970672) (xy 231.204157 -310.960542) (xy 231.151373 -310.942535)
			(xy 231.101773 -310.917034) (xy 231.056415 -310.884583) (xy 231.016266 -310.845874) (xy 230.98218 -310.801731)
			(xy 230.954884 -310.753096) (xy 230.934961 -310.701005) (xy 230.922835 -310.646568) (xy 230.918764 -310.590946)
			(xy 220.317192 -310.590946) (xy 220.318992 -310.599958) (xy 220.343523 -310.764667) (xy 220.359908 -310.930385)
			(xy 220.368109 -311.096709) (xy 220.368622 -311.179972) (xy 220.36841 -311.215786) (xy 227.498908 -311.215786)
			(xy 227.502979 -311.160164) (xy 227.515105 -311.105727) (xy 227.535028 -311.053636) (xy 227.562324 -311.005001)
			(xy 227.59641 -310.960858) (xy 227.636559 -310.922149) (xy 227.681917 -310.889698) (xy 227.731517 -310.864197)
			(xy 227.784301 -310.84619) (xy 227.839144 -310.83606) (xy 227.894878 -310.834023) (xy 227.950315 -310.840123)
			(xy 228.004272 -310.854229) (xy 228.055601 -310.876041) (xy 228.103207 -310.905095) (xy 228.146075 -310.94077)
			(xy 228.183292 -310.982307) (xy 228.214065 -311.02882) (xy 228.237737 -311.079317) (xy 228.253805 -311.132724)
			(xy 228.261925 -311.1879) (xy 228.262434 -311.215786) (xy 228.261925 -311.243672) (xy 228.253805 -311.298848)
			(xy 228.237737 -311.352255) (xy 228.214065 -311.402752) (xy 228.183292 -311.449265) (xy 228.146075 -311.490802)
			(xy 228.103207 -311.526477) (xy 228.055601 -311.555531) (xy 228.025463 -311.568338) (xy 229.820468 -311.568338)
			(xy 229.824539 -311.512716) (xy 229.836665 -311.458279) (xy 229.856588 -311.406188) (xy 229.883884 -311.357553)
			(xy 229.91797 -311.31341) (xy 229.958119 -311.274701) (xy 230.003477 -311.24225) (xy 230.053077 -311.216749)
			(xy 230.105861 -311.198742) (xy 230.160704 -311.188612) (xy 230.216438 -311.186575) (xy 230.271875 -311.192675)
			(xy 230.325832 -311.206781) (xy 230.377161 -311.228593) (xy 230.424767 -311.257647) (xy 230.467635 -311.293322)
			(xy 230.504852 -311.334859) (xy 230.535625 -311.381372) (xy 230.559297 -311.431869) (xy 230.575365 -311.485276)
			(xy 230.583485 -311.540452) (xy 230.583994 -311.568338) (xy 230.583485 -311.596224) (xy 230.575365 -311.6514)
			(xy 230.559297 -311.704807) (xy 230.535625 -311.755304) (xy 230.504852 -311.801817) (xy 230.467635 -311.843354)
			(xy 230.424767 -311.879029) (xy 230.377161 -311.908083) (xy 230.325832 -311.929895) (xy 230.271875 -311.944001)
			(xy 230.216438 -311.950101) (xy 230.160704 -311.948064) (xy 230.105861 -311.937934) (xy 230.053077 -311.919927)
			(xy 230.003477 -311.894426) (xy 229.958119 -311.861975) (xy 229.91797 -311.823266) (xy 229.883884 -311.779123)
			(xy 229.856588 -311.730488) (xy 229.836665 -311.678397) (xy 229.824539 -311.62396) (xy 229.820468 -311.568338)
			(xy 228.025463 -311.568338) (xy 228.004272 -311.577343) (xy 227.950315 -311.591449) (xy 227.894878 -311.597549)
			(xy 227.839144 -311.595512) (xy 227.784301 -311.585382) (xy 227.731517 -311.567375) (xy 227.681917 -311.541874)
			(xy 227.636559 -311.509423) (xy 227.59641 -311.470714) (xy 227.562324 -311.426571) (xy 227.535028 -311.377936)
			(xy 227.515105 -311.325845) (xy 227.502979 -311.271408) (xy 227.498908 -311.215786) (xy 220.36841 -311.215786)
			(xy 220.368148 -311.260131) (xy 220.360541 -311.420268) (xy 220.345348 -311.579864) (xy 220.322602 -311.73856)
			(xy 220.292356 -311.895999) (xy 220.254676 -312.051826) (xy 220.209649 -312.205691) (xy 220.157374 -312.357246)
			(xy 220.097971 -312.506153) (xy 220.031572 -312.652074) (xy 219.958327 -312.794681) (xy 219.878401 -312.933655)
			(xy 219.791974 -313.068681) (xy 219.76133 -313.111896) (xy 230.52354 -313.111896) (xy 230.527611 -313.056274)
			(xy 230.539737 -313.001837) (xy 230.55966 -312.949746) (xy 230.586956 -312.901111) (xy 230.621042 -312.856968)
			(xy 230.661191 -312.818259) (xy 230.706549 -312.785808) (xy 230.756149 -312.760307) (xy 230.808933 -312.7423)
			(xy 230.863776 -312.73217) (xy 230.91951 -312.730133) (xy 230.974947 -312.736233) (xy 231.028904 -312.750339)
			(xy 231.080233 -312.772151) (xy 231.127839 -312.801205) (xy 231.170707 -312.83688) (xy 231.207924 -312.878417)
			(xy 231.238697 -312.92493) (xy 231.262369 -312.975427) (xy 231.278437 -313.028834) (xy 231.286557 -313.08401)
			(xy 231.287066 -313.111896) (xy 231.286557 -313.139782) (xy 231.278437 -313.194958) (xy 231.262369 -313.248365)
			(xy 231.238697 -313.298862) (xy 231.207924 -313.345375) (xy 231.170707 -313.386912) (xy 231.127839 -313.422587)
			(xy 231.080233 -313.451641) (xy 231.028904 -313.473453) (xy 230.974947 -313.487559) (xy 230.91951 -313.493659)
			(xy 230.863776 -313.491622) (xy 230.808933 -313.481492) (xy 230.756149 -313.463485) (xy 230.706549 -313.437984)
			(xy 230.661191 -313.405533) (xy 230.621042 -313.366824) (xy 230.586956 -313.322681) (xy 230.55966 -313.274046)
			(xy 230.539737 -313.221955) (xy 230.527611 -313.167518) (xy 230.52354 -313.111896) (xy 219.76133 -313.111896)
			(xy 219.69924 -313.199457) (xy 219.600408 -313.325687) (xy 219.4957 -313.447087) (xy 219.385352 -313.563385)
			(xy 219.269613 -313.674319) (xy 219.148743 -313.779638) (xy 219.023014 -313.879106) (xy 218.95816 -313.92622)
			(xy 218.89396 -313.971761) (xy 218.761949 -314.057521) (xy 218.626084 -314.137035) (xy 218.486661 -314.210131)
			(xy 218.343984 -314.276649) (xy 218.271344 -314.306966) (xy 218.27109 -314.30722) (xy 218.263978 -314.310268)
			(xy 218.258644 -314.314586) (xy 218.255677 -314.317018) (xy 218.250453 -314.322635) (xy 218.24823 -314.325762)
			(xy 218.234006 -314.346844) (xy 218.22918 -314.355734) (xy 218.227677 -314.359452) (xy 218.225758 -314.367237)
			(xy 218.22537 -314.371228) (xy 218.225116 -314.375546) (xy 218.225116 -320.816732) (xy 224.888044 -320.816732)
			(xy 224.888518 -320.789362) (xy 224.896332 -320.735183) (xy 224.911819 -320.682679) (xy 224.934659 -320.632932)
			(xy 224.964383 -320.586966) (xy 224.982024 -320.566034) (xy 224.98812 -320.558922) (xy 224.99447 -320.541904)
			(xy 224.99447 -320.45656) (xy 224.98812 -320.439542) (xy 224.982024 -320.43243) (xy 224.964389 -320.411494)
			(xy 224.934676 -320.365523) (xy 224.911839 -320.315776) (xy 224.896347 -320.263276) (xy 224.888518 -320.209101)
			(xy 224.888044 -320.181732) (xy 224.888608 -320.154484) (xy 224.896359 -320.100541) (xy 224.911707 -320.048251)
			(xy 224.934341 -319.998677) (xy 224.9638 -319.952829) (xy 224.999483 -319.91164) (xy 225.040665 -319.875948)
			(xy 225.086507 -319.84648) (xy 225.136076 -319.823835) (xy 225.188363 -319.808476) (xy 225.242304 -319.800714)
			(xy 225.269552 -319.800224) (xy 225.296921 -319.800712) (xy 225.3511 -319.808524) (xy 225.403603 -319.824007)
			(xy 225.45335 -319.846844) (xy 225.499318 -319.876565) (xy 225.52025 -319.894204) (xy 225.527362 -319.9003)
			(xy 225.54438 -319.90665) (xy 225.629724 -319.90665) (xy 225.646742 -319.9003) (xy 225.653854 -319.894204)
			(xy 225.674787 -319.876563) (xy 225.720755 -319.846839) (xy 225.770501 -319.823993) (xy 225.823003 -319.808497)
			(xy 225.877181 -319.800668) (xy 225.931923 -319.800668) (xy 225.986101 -319.808497) (xy 226.038603 -319.823993)
			(xy 226.088349 -319.846839) (xy 226.134317 -319.876563) (xy 226.15525 -319.894204) (xy 226.162362 -319.9003)
			(xy 226.17938 -319.90665) (xy 226.264724 -319.90665) (xy 226.281742 -319.9003) (xy 226.288854 -319.894204)
			(xy 226.309793 -319.876574) (xy 226.355764 -319.84686) (xy 226.40551 -319.824023) (xy 226.458009 -319.80853)
			(xy 226.512183 -319.800699) (xy 226.539552 -319.800224) (xy 226.566805 -319.8007) (xy 226.620757 -319.808451)
			(xy 226.673057 -319.823803) (xy 226.722639 -319.846442) (xy 226.768494 -319.875908) (xy 226.809688 -319.911601)
			(xy 226.845382 -319.952793) (xy 226.87485 -319.998647) (xy 226.897492 -320.048228) (xy 226.912845 -320.100527)
			(xy 226.920599 -320.154479) (xy 226.92106 -320.181732) (xy 226.920622 -320.209103) (xy 226.912799 -320.263284)
			(xy 226.897304 -320.315788) (xy 226.874456 -320.365534) (xy 226.844725 -320.4115) (xy 226.82708 -320.43243)
			(xy 226.820984 -320.439542) (xy 226.814634 -320.45656) (xy 226.814634 -320.541904) (xy 226.820984 -320.558922)
			(xy 226.82708 -320.566034) (xy 226.844699 -320.586983) (xy 226.874414 -320.632951) (xy 226.897254 -320.682694)
			(xy 226.91275 -320.735191) (xy 226.920583 -320.789364) (xy 226.92106 -320.816732) (xy 226.920675 -320.843988)
			(xy 226.912912 -320.897944) (xy 226.89755 -320.950246) (xy 226.8749 -320.99983) (xy 226.845424 -321.045685)
			(xy 226.809722 -321.086879) (xy 226.768521 -321.122572) (xy 226.72266 -321.152038) (xy 226.673071 -321.174678)
			(xy 226.620766 -321.190029) (xy 226.566808 -321.19778) (xy 226.539552 -321.19824) (xy 226.512182 -321.197758)
			(xy 226.458003 -321.189946) (xy 226.4055 -321.174462) (xy 226.355752 -321.151623) (xy 226.309786 -321.121901)
			(xy 226.288854 -321.10426) (xy 226.281742 -321.098164) (xy 226.264724 -321.091814) (xy 226.17938 -321.091814)
			(xy 226.162362 -321.098164) (xy 226.15525 -321.10426) (xy 226.134317 -321.121901) (xy 226.088349 -321.151625)
			(xy 226.038603 -321.174471) (xy 225.986101 -321.189967) (xy 225.931923 -321.197796) (xy 225.877181 -321.197796)
			(xy 225.823003 -321.189967) (xy 225.770501 -321.174471) (xy 225.720755 -321.151625) (xy 225.674787 -321.121901)
			(xy 225.653854 -321.10426) (xy 225.646742 -321.098164) (xy 225.629724 -321.091814) (xy 225.54438 -321.091814)
			(xy 225.527362 -321.098164) (xy 225.52025 -321.10426) (xy 225.499305 -321.121883) (xy 225.453336 -321.151599)
			(xy 225.403592 -321.174438) (xy 225.351094 -321.189933) (xy 225.29692 -321.197764) (xy 225.269552 -321.19824)
			(xy 225.242301 -321.197767) (xy 225.188355 -321.190005) (xy 225.136062 -321.174645) (xy 225.086486 -321.152001)
			(xy 225.040638 -321.122532) (xy 224.999449 -321.08684) (xy 224.963758 -321.04565) (xy 224.934292 -320.9998)
			(xy 224.911649 -320.950223) (xy 224.896292 -320.89793) (xy 224.888532 -320.843983) (xy 224.888044 -320.816732)
			(xy 218.225116 -320.816732) (xy 218.225116 -321.122548) (xy 218.225582 -321.132422) (xy 218.233034 -321.150712)
			(xy 218.239594 -321.158108) (xy 218.239848 -321.158362) (xy 218.509342 -321.427856) (xy 218.50985 -321.428364)
			(xy 218.517232 -321.434946) (xy 218.53553 -321.442395) (xy 218.54541 -321.442842)
		)
		(stroke
			(width 0)
			(type solid)
		)
		(fill yes)
		(layer "In11.Cu")
		(net "GND")
	)
	(gr_poly
		(pts
			(xy 38.686486 -295.88714) (xy 38.813232 -295.88714) (xy 38.820852 -295.887394) (xy 39.62908 -295.887394)
			(xy 39.6367 -295.88714) (xy 39.763192 -295.88714) (xy 39.770812 -295.887394) (xy 40.57904 -295.887394)
			(xy 40.58666 -295.88714) (xy 41.663112 -295.88714) (xy 41.670732 -295.887394) (xy 42.47896 -295.887394)
			(xy 42.48658 -295.88714) (xy 43.563032 -295.88714) (xy 43.570652 -295.887394) (xy 44.37888 -295.887394)
			(xy 44.3865 -295.88714) (xy 44.513246 -295.88714) (xy 44.520866 -295.887394) (xy 45.329094 -295.887394)
			(xy 45.336714 -295.88714) (xy 45.463206 -295.88714) (xy 45.470826 -295.887394) (xy 46.279054 -295.887394)
			(xy 46.286674 -295.88714) (xy 46.413166 -295.88714) (xy 46.420786 -295.887394) (xy 46.421548 -295.887394)
			(xy 46.893988 -295.887394) (xy 46.904059 -295.886973) (xy 46.922666 -295.879261) (xy 46.930056 -295.872408)
			(xy 47.168562 -295.633902) (xy 47.175413 -295.626505) (xy 47.183154 -295.607907) (xy 47.183548 -295.597834)
			(xy 47.183548 -293.995094) (xy 47.183122 -293.985025) (xy 47.175401 -293.966427) (xy 47.168562 -293.959026)
			(xy 47.03699 -293.827454) (xy 47.029056 -293.820215) (xy 47.008998 -293.81259) (xy 46.987575 -293.813836)
			(xy 46.977808 -293.81831) (xy 46.977554 -293.81831) (xy 46.953842 -293.830064) (xy 46.903606 -293.846707)
			(xy 46.85136 -293.855136) (xy 46.8249 -293.855648) (xy 46.824646 -293.855648) (xy 46.801131 -293.855236)
			(xy 46.754576 -293.848571) (xy 46.709437 -293.835368) (xy 46.666628 -293.815895) (xy 46.646592 -293.803578)
			(xy 46.631606 -293.793926) (xy 46.5963 -293.797482) (xy 46.57598 -293.817548) (xy 46.557692 -293.825168)
			(xy 46.549818 -293.825168) (xy 46.152308 -293.825168) (xy 46.142148 -293.825168) (xy 46.12386 -293.817548)
			(xy 46.10354 -293.797482) (xy 46.068234 -293.793926) (xy 46.053248 -293.803578) (xy 46.03321 -293.815888)
			(xy 45.990394 -293.83534) (xy 45.945257 -293.848539) (xy 45.898707 -293.855219) (xy 45.875194 -293.855648)
			(xy 45.874686 -293.855648) (xy 45.85117 -293.855239) (xy 45.804612 -293.848579) (xy 45.759471 -293.83538)
			(xy 45.716658 -293.815912) (xy 45.696632 -293.803578) (xy 45.681646 -293.793926) (xy 45.64634 -293.797482)
			(xy 45.62602 -293.817548) (xy 45.607732 -293.825168) (xy 45.599858 -293.825168) (xy 44.252134 -293.825168)
			(xy 44.241974 -293.825168) (xy 44.223686 -293.817548) (xy 44.203366 -293.797482) (xy 44.16806 -293.793926)
			(xy 44.153074 -293.803578) (xy 44.133036 -293.815889) (xy 44.090221 -293.835345) (xy 44.045084 -293.848547)
			(xy 43.998534 -293.855231) (xy 43.97502 -293.855648) (xy 43.974512 -293.855648) (xy 43.950996 -293.855241)
			(xy 43.904436 -293.848584) (xy 43.859293 -293.835389) (xy 43.816478 -293.815922) (xy 43.796458 -293.803578)
			(xy 43.781472 -293.793926) (xy 43.746166 -293.797482) (xy 43.725846 -293.817548) (xy 43.707558 -293.825168)
			(xy 43.699684 -293.825168) (xy 43.284902 -293.825168) (xy 43.280967 -293.825195) (xy 43.273182 -293.82634)
			(xy 43.269408 -293.827454) (xy 43.247818 -293.834566) (xy 43.241468 -293.838884) (xy 43.217447 -293.854815)
			(xy 43.165624 -293.880042) (xy 43.110601 -293.897201) (xy 43.053624 -293.905902) (xy 43.024806 -293.906448)
			(xy 42.995984 -293.905926) (xy 42.938997 -293.897255) (xy 42.883968 -293.880095) (xy 42.832153 -293.854838)
			(xy 42.808144 -293.838884) (xy 42.801794 -293.834566) (xy 42.780204 -293.827454) (xy 42.776423 -293.826372)
			(xy 42.768642 -293.825229) (xy 42.76471 -293.825168) (xy 42.352214 -293.825168) (xy 42.342054 -293.825168)
			(xy 42.323766 -293.817548) (xy 42.303446 -293.797482) (xy 42.26814 -293.793926) (xy 42.253154 -293.803578)
			(xy 42.233116 -293.815888) (xy 42.190301 -293.835341) (xy 42.145164 -293.848541) (xy 42.098613 -293.855222)
			(xy 42.0751 -293.855648) (xy 42.074592 -293.855648) (xy 42.051076 -293.855239) (xy 42.004518 -293.84858)
			(xy 41.959376 -293.835382) (xy 41.916562 -293.815914) (xy 41.896538 -293.803578) (xy 41.881552 -293.793926)
			(xy 41.846246 -293.797482) (xy 41.825926 -293.817548) (xy 41.807638 -293.825168) (xy 41.799764 -293.825168)
			(xy 41.402254 -293.825168) (xy 41.392094 -293.825168) (xy 41.373806 -293.817548) (xy 41.353486 -293.797482)
			(xy 41.31818 -293.793926) (xy 41.303194 -293.803578) (xy 41.283157 -293.815891) (xy 41.240342 -293.835349)
			(xy 41.195205 -293.848554) (xy 41.148654 -293.855241) (xy 41.12514 -293.855648) (xy 41.124632 -293.855648)
			(xy 41.101117 -293.855235) (xy 41.054563 -293.848568) (xy 41.009425 -293.835364) (xy 40.966617 -293.815889)
			(xy 40.946578 -293.803578) (xy 40.931592 -293.793926) (xy 40.896286 -293.797482) (xy 40.875966 -293.817548)
			(xy 40.857678 -293.825168) (xy 40.849804 -293.825168) (xy 40.452294 -293.825168) (xy 40.442134 -293.825168)
			(xy 40.423846 -293.817548) (xy 40.403526 -293.797482) (xy 40.36822 -293.793926) (xy 40.353234 -293.803578)
			(xy 40.333196 -293.815887) (xy 40.29038 -293.835337) (xy 40.245243 -293.848534) (xy 40.198693 -293.855213)
			(xy 40.17518 -293.855648) (xy 40.174926 -293.855648) (xy 40.147183 -293.855078) (xy 40.092477 -293.845812)
			(xy 40.040082 -293.827554) (xy 39.991466 -293.800813) (xy 39.94799 -293.766339) (xy 39.910871 -293.725097)
			(xy 39.895526 -293.701978) (xy 39.892478 -293.697152) (xy 39.722806 -293.52748) (xy 39.712646 -293.51732)
			(xy 39.685214 -293.510462) (xy 39.57193 -293.546276) (xy 39.553388 -293.567358) (xy 39.550848 -293.581582)
			(xy 39.545966 -293.606834) (xy 39.529424 -293.655531) (xy 39.505542 -293.701079) (xy 39.474895 -293.74238)
			(xy 39.438222 -293.778437) (xy 39.396409 -293.808381) (xy 39.350463 -293.831489) (xy 39.301493 -293.847204)
			(xy 39.250681 -293.855147) (xy 39.224966 -293.855648) (xy 39.198979 -293.855136) (xy 39.147647 -293.847001)
			(xy 39.098218 -293.830938) (xy 39.05191 -293.807341) (xy 39.009864 -293.776791) (xy 38.973113 -293.740041)
			(xy 38.942562 -293.697995) (xy 38.918964 -293.651687) (xy 38.9029 -293.602259) (xy 38.894765 -293.550927)
			(xy 38.894258 -293.52494) (xy 38.89475 -293.499228) (xy 38.902716 -293.448425) (xy 38.918447 -293.399465)
			(xy 38.941563 -293.35353) (xy 38.971509 -293.311724) (xy 39.007562 -293.275055) (xy 39.048855 -293.244406)
			(xy 39.094393 -293.220516) (xy 39.143078 -293.203959) (xy 39.168324 -293.199058) (xy 39.182548 -293.196518)
			(xy 39.20363 -293.177976) (xy 39.235126 -293.078408) (xy 39.237518 -293.069421) (xy 39.236391 -293.050873)
			(xy 39.228719 -293.03395) (xy 39.222426 -293.0271) (xy 39.057834 -292.862508) (xy 39.053516 -292.858698)
			(xy 39.047166 -292.853618) (xy 39.045134 -292.852348) (xy 39.02585 -292.839387) (xy 38.990774 -292.808918)
			(xy 38.960306 -292.773841) (xy 38.947344 -292.754558) (xy 38.946074 -292.752526) (xy 38.940994 -292.746176)
			(xy 38.937184 -292.741858) (xy 38.772846 -292.57752) (xy 38.762686 -292.56736) (xy 38.735254 -292.560502)
			(xy 38.62197 -292.596316) (xy 38.603428 -292.617398) (xy 38.600888 -292.631622) (xy 38.596004 -292.656873)
			(xy 38.579459 -292.705568) (xy 38.555575 -292.751114) (xy 38.524927 -292.792414) (xy 38.488255 -292.82847)
			(xy 38.446443 -292.858415) (xy 38.400499 -292.881525) (xy 38.351531 -292.897243) (xy 38.300721 -292.905191)
			(xy 38.275006 -292.905688) (xy 38.249017 -292.905205) (xy 38.197679 -292.897075) (xy 38.148245 -292.881013)
			(xy 38.101932 -292.857415) (xy 38.059882 -292.826863) (xy 38.023128 -292.790108) (xy 37.992578 -292.748056)
			(xy 37.968982 -292.701742) (xy 37.952922 -292.652307) (xy 37.944794 -292.600969) (xy 37.944298 -292.57498)
			(xy 37.944787 -292.549267) (xy 37.952749 -292.498461) (xy 37.968476 -292.449499) (xy 37.991591 -292.403561)
			(xy 38.021537 -292.361753) (xy 38.057592 -292.325083) (xy 38.098887 -292.294434) (xy 38.144427 -292.270544)
			(xy 38.193116 -292.25399) (xy 38.218364 -292.249098) (xy 38.232588 -292.246558) (xy 38.25367 -292.228016)
			(xy 38.285166 -292.128448) (xy 38.287564 -292.119458) (xy 38.28645 -292.100902) (xy 38.27879 -292.083963)
			(xy 38.272466 -292.07714) (xy 38.107874 -291.912548) (xy 38.103556 -291.908738) (xy 38.097206 -291.903658)
			(xy 38.095174 -291.902388) (xy 38.075891 -291.889427) (xy 38.040815 -291.858957) (xy 38.010349 -291.823878)
			(xy 37.997384 -291.804598) (xy 37.996114 -291.802566) (xy 37.991034 -291.796216) (xy 37.987224 -291.791898)
			(xy 37.822632 -291.627306) (xy 37.812472 -291.617146) (xy 37.78504 -291.610288) (xy 37.671756 -291.646102)
			(xy 37.653214 -291.667184) (xy 37.650674 -291.681408) (xy 37.64579 -291.706659) (xy 37.629247 -291.755355)
			(xy 37.605363 -291.800902) (xy 37.574716 -291.842202) (xy 37.538044 -291.878258) (xy 37.496231 -291.908203)
			(xy 37.450287 -291.931312) (xy 37.401318 -291.947029) (xy 37.350507 -291.954975) (xy 37.324792 -291.955474)
			(xy 37.298804 -291.95499) (xy 37.247469 -291.946858) (xy 37.198037 -291.930794) (xy 37.151728 -291.907196)
			(xy 37.10968 -291.876643) (xy 37.07293 -291.839888) (xy 37.042382 -291.797837) (xy 37.018789 -291.751524)
			(xy 37.002732 -291.702091) (xy 36.994606 -291.650754) (xy 36.994084 -291.624766) (xy 36.994574 -291.599053)
			(xy 37.002537 -291.548248) (xy 37.018266 -291.499287) (xy 37.041381 -291.45335) (xy 37.071327 -291.411543)
			(xy 37.107381 -291.374873) (xy 37.148675 -291.344224) (xy 37.194215 -291.320334) (xy 37.242903 -291.303779)
			(xy 37.26815 -291.298884) (xy 37.282374 -291.296344) (xy 37.303456 -291.277802) (xy 37.334952 -291.178234)
			(xy 37.337348 -291.169245) (xy 37.33623 -291.150692) (xy 37.328565 -291.133758) (xy 37.322252 -291.126926)
			(xy 37.15258 -290.957254) (xy 37.147754 -290.954206) (xy 37.127428 -290.940816) (xy 37.090577 -290.909021)
			(xy 37.058782 -290.872169) (xy 37.045392 -290.851844) (xy 37.042344 -290.847018) (xy 36.872672 -290.677346)
			(xy 36.862512 -290.667186) (xy 36.83508 -290.660328) (xy 36.721796 -290.696142) (xy 36.703254 -290.717224)
			(xy 36.700714 -290.731448) (xy 36.695835 -290.756704) (xy 36.679298 -290.80541) (xy 36.65542 -290.850968)
			(xy 36.624775 -290.892279) (xy 36.588103 -290.928347) (xy 36.546289 -290.958302) (xy 36.500342 -290.981421)
			(xy 36.451368 -290.997148) (xy 36.40055 -291.005102) (xy 36.374832 -291.005514) (xy 36.348841 -291.005033)
			(xy 36.297498 -290.996906) (xy 36.248059 -290.980847) (xy 36.201741 -290.957251) (xy 36.159684 -290.926699)
			(xy 36.122926 -290.889944) (xy 36.092369 -290.847892) (xy 36.068768 -290.801576) (xy 36.052703 -290.752139)
			(xy 36.04457 -290.700797) (xy 36.044124 -290.674806) (xy 36.044619 -290.649095) (xy 36.052589 -290.598294)
			(xy 36.068322 -290.549337) (xy 36.091439 -290.503404) (xy 36.121385 -290.4616) (xy 36.157437 -290.424932)
			(xy 36.198728 -290.394283) (xy 36.244263 -290.370391) (xy 36.292946 -290.353832) (xy 36.31819 -290.348924)
			(xy 36.332414 -290.346384) (xy 36.353496 -290.327842) (xy 36.384992 -290.228274) (xy 36.387398 -290.219284)
			(xy 36.386291 -290.200723) (xy 36.378626 -290.183782) (xy 36.372292 -290.176966) (xy 36.20262 -290.007294)
			(xy 36.197794 -290.004246) (xy 36.1778 -289.991079) (xy 36.141469 -289.959902) (xy 36.110003 -289.923821)
			(xy 36.096702 -289.903916) (xy 36.095432 -289.901884) (xy 36.090352 -289.895534) (xy 36.086542 -289.891216)
			(xy 35.453828 -289.258502) (xy 35.446479 -289.251703) (xy 35.428016 -289.243996) (xy 35.418014 -289.243516)
			(xy 32.176466 -289.243516) (xy 32.163827 -289.244198) (xy 32.141581 -289.256202) (xy 32.134048 -289.266376)
			(xy 32.087312 -289.336734) (xy 32.08087 -289.347565) (xy 32.078489 -289.37262) (xy 32.08274 -289.384486)
			(xy 32.08274 -289.38474) (xy 32.09208 -289.408036) (xy 32.105263 -289.456465) (xy 32.111991 -289.506204)
			(xy 32.112458 -289.531298) (xy 32.112458 -289.536886) (xy 32.111661 -289.563922) (xy 32.103379 -289.617371)
			(xy 32.08763 -289.669115) (xy 32.06473 -289.718116) (xy 32.035139 -289.76339) (xy 31.999449 -289.804032)
			(xy 31.958377 -289.839224) (xy 31.912746 -289.868263) (xy 31.863471 -289.890566) (xy 31.81154 -289.905685)
			(xy 31.757994 -289.913318) (xy 31.73095 -289.913822) (xy 31.702139 -289.913293) (xy 31.645174 -289.904625)
			(xy 31.590158 -289.887493) (xy 31.538342 -289.862287) (xy 31.490904 -289.82958) (xy 31.44892 -289.790114)
			(xy 31.430722 -289.767772) (xy 31.420562 -289.754818) (xy 31.389574 -289.745674) (xy 31.283402 -289.78225)
			(xy 31.273623 -289.786179) (xy 31.258149 -289.800452) (xy 31.249694 -289.819731) (xy 31.249112 -289.830256)
			(xy 31.249112 -290.294314) (xy 33.620962 -290.294314) (xy 33.625033 -290.238692) (xy 33.637159 -290.184255)
			(xy 33.657082 -290.132164) (xy 33.684378 -290.083529) (xy 33.718464 -290.039386) (xy 33.758613 -290.000677)
			(xy 33.803971 -289.968226) (xy 33.853571 -289.942725) (xy 33.906355 -289.924718) (xy 33.961198 -289.914588)
			(xy 34.016932 -289.912551) (xy 34.072369 -289.918651) (xy 34.126326 -289.932757) (xy 34.177655 -289.954569)
			(xy 34.225261 -289.983623) (xy 34.268129 -290.019298) (xy 34.305346 -290.060835) (xy 34.336119 -290.107348)
			(xy 34.359791 -290.157845) (xy 34.375859 -290.211252) (xy 34.383979 -290.266428) (xy 34.384488 -290.294314)
			(xy 34.383979 -290.3222) (xy 34.375859 -290.377376) (xy 34.359791 -290.430783) (xy 34.336119 -290.48128)
			(xy 34.305346 -290.527793) (xy 34.268129 -290.56933) (xy 34.225261 -290.605005) (xy 34.177655 -290.634059)
			(xy 34.126326 -290.655871) (xy 34.072369 -290.669977) (xy 34.016932 -290.676077) (xy 33.961198 -290.67404)
			(xy 33.906355 -290.66391) (xy 33.853571 -290.645903) (xy 33.803971 -290.620402) (xy 33.758613 -290.587951)
			(xy 33.718464 -290.549242) (xy 33.684378 -290.505099) (xy 33.657082 -290.456464) (xy 33.637159 -290.404373)
			(xy 33.625033 -290.349936) (xy 33.620962 -290.294314) (xy 31.249112 -290.294314) (xy 31.249112 -291.624766)
			(xy 36.069028 -291.624766) (xy 36.072988 -291.575712) (xy 36.084765 -291.527928) (xy 36.104056 -291.482652)
			(xy 36.130359 -291.441056) (xy 36.162994 -291.404219) (xy 36.201115 -291.373094) (xy 36.243736 -291.348487)
			(xy 36.289752 -291.331035) (xy 36.337971 -291.321191) (xy 36.387146 -291.31921) (xy 36.436001 -291.325142)
			(xy 36.483272 -291.338834) (xy 36.527734 -291.359932) (xy 36.568237 -291.387888) (xy 36.60373 -291.42198)
			(xy 36.633295 -291.461324) (xy 36.656166 -291.504901) (xy 36.67175 -291.551582) (xy 36.679645 -291.600159)
			(xy 36.68014 -291.624766) (xy 36.679645 -291.649373) (xy 36.67175 -291.69795) (xy 36.656166 -291.744631)
			(xy 36.633295 -291.788208) (xy 36.60373 -291.827552) (xy 36.568237 -291.861644) (xy 36.527734 -291.8896)
			(xy 36.483272 -291.910698) (xy 36.436001 -291.92439) (xy 36.387146 -291.930322) (xy 36.337971 -291.928341)
			(xy 36.289752 -291.918497) (xy 36.243736 -291.901045) (xy 36.201115 -291.876438) (xy 36.162994 -291.845313)
			(xy 36.130359 -291.808476) (xy 36.104056 -291.76688) (xy 36.084765 -291.721604) (xy 36.072988 -291.67382)
			(xy 36.069028 -291.624766) (xy 31.249112 -291.624766) (xy 31.249112 -292.169088) (xy 31.249533 -292.179159)
			(xy 31.257246 -292.197765) (xy 31.264098 -292.205156) (xy 31.332932 -292.27399) (xy 31.340332 -292.280832)
			(xy 31.35893 -292.288557) (xy 31.369 -292.288976) (xy 34.209736 -292.288976) (xy 34.219804 -292.289405)
			(xy 34.238401 -292.297126) (xy 34.245804 -292.303962) (xy 34.516822 -292.57498) (xy 36.069028 -292.57498)
			(xy 36.072988 -292.525926) (xy 36.084765 -292.478142) (xy 36.104056 -292.432866) (xy 36.130359 -292.39127)
			(xy 36.162994 -292.354433) (xy 36.201115 -292.323308) (xy 36.243736 -292.298701) (xy 36.289752 -292.281249)
			(xy 36.337971 -292.271405) (xy 36.387146 -292.269424) (xy 36.436001 -292.275356) (xy 36.483272 -292.289048)
			(xy 36.527734 -292.310146) (xy 36.568237 -292.338102) (xy 36.60373 -292.372194) (xy 36.633295 -292.411538)
			(xy 36.656166 -292.455115) (xy 36.67175 -292.501796) (xy 36.679645 -292.550373) (xy 36.68014 -292.57498)
			(xy 37.018988 -292.57498) (xy 37.022948 -292.525926) (xy 37.034725 -292.478142) (xy 37.054016 -292.432866)
			(xy 37.080319 -292.39127) (xy 37.112954 -292.354433) (xy 37.151075 -292.323308) (xy 37.193696 -292.298701)
			(xy 37.239712 -292.281249) (xy 37.287931 -292.271405) (xy 37.337106 -292.269424) (xy 37.385961 -292.275356)
			(xy 37.433232 -292.289048) (xy 37.477694 -292.310146) (xy 37.518197 -292.338102) (xy 37.55369 -292.372194)
			(xy 37.583255 -292.411538) (xy 37.606126 -292.455115) (xy 37.62171 -292.501796) (xy 37.629605 -292.550373)
			(xy 37.6301 -292.57498) (xy 37.629605 -292.599587) (xy 37.62171 -292.648164) (xy 37.606126 -292.694845)
			(xy 37.583255 -292.738422) (xy 37.55369 -292.777766) (xy 37.518197 -292.811858) (xy 37.477694 -292.839814)
			(xy 37.433232 -292.860912) (xy 37.385961 -292.874604) (xy 37.337106 -292.880536) (xy 37.287931 -292.878555)
			(xy 37.239712 -292.868711) (xy 37.193696 -292.851259) (xy 37.151075 -292.826652) (xy 37.112954 -292.795527)
			(xy 37.080319 -292.75869) (xy 37.054016 -292.717094) (xy 37.034725 -292.671818) (xy 37.022948 -292.624034)
			(xy 37.018988 -292.57498) (xy 36.68014 -292.57498) (xy 36.679645 -292.599587) (xy 36.67175 -292.648164)
			(xy 36.656166 -292.694845) (xy 36.633295 -292.738422) (xy 36.60373 -292.777766) (xy 36.568237 -292.811858)
			(xy 36.527734 -292.839814) (xy 36.483272 -292.860912) (xy 36.436001 -292.874604) (xy 36.387146 -292.880536)
			(xy 36.337971 -292.878555) (xy 36.289752 -292.868711) (xy 36.243736 -292.851259) (xy 36.201115 -292.826652)
			(xy 36.162994 -292.795527) (xy 36.130359 -292.75869) (xy 36.104056 -292.717094) (xy 36.084765 -292.671818)
			(xy 36.072988 -292.624034) (xy 36.069028 -292.57498) (xy 34.516822 -292.57498) (xy 35.466782 -293.52494)
			(xy 37.969202 -293.52494) (xy 37.973162 -293.475886) (xy 37.984939 -293.428102) (xy 38.00423 -293.382826)
			(xy 38.030533 -293.34123) (xy 38.063168 -293.304393) (xy 38.101289 -293.273268) (xy 38.14391 -293.248661)
			(xy 38.189926 -293.231209) (xy 38.238145 -293.221365) (xy 38.28732 -293.219384) (xy 38.336175 -293.225316)
			(xy 38.383446 -293.239008) (xy 38.427908 -293.260106) (xy 38.468411 -293.288062) (xy 38.503904 -293.322154)
			(xy 38.533469 -293.361498) (xy 38.55634 -293.405075) (xy 38.571924 -293.451756) (xy 38.579819 -293.500333)
			(xy 38.580314 -293.52494) (xy 38.579819 -293.549547) (xy 38.571924 -293.598124) (xy 38.55634 -293.644805)
			(xy 38.533469 -293.688382) (xy 38.503904 -293.727726) (xy 38.468411 -293.761818) (xy 38.427908 -293.789774)
			(xy 38.383446 -293.810872) (xy 38.336175 -293.824564) (xy 38.28732 -293.830496) (xy 38.238145 -293.828515)
			(xy 38.189926 -293.818671) (xy 38.14391 -293.801219) (xy 38.101289 -293.776612) (xy 38.063168 -293.745487)
			(xy 38.030533 -293.70865) (xy 38.00423 -293.667054) (xy 37.984939 -293.621778) (xy 37.973162 -293.573994)
			(xy 37.969202 -293.52494) (xy 35.466782 -293.52494) (xy 36.144962 -294.20312) (xy 36.180268 -294.20693)
			(xy 36.195508 -294.197024) (xy 36.215644 -294.184512) (xy 36.258736 -294.164757) (xy 36.304209 -294.151358)
			(xy 36.351129 -294.144592) (xy 36.374832 -294.144192) (xy 36.400818 -294.144704) (xy 36.452148 -294.152838)
			(xy 36.501574 -294.168902) (xy 36.547879 -294.1925) (xy 36.589923 -294.22305) (xy 36.626671 -294.259801)
			(xy 36.657217 -294.301848) (xy 36.68081 -294.348155) (xy 36.696869 -294.397583) (xy 36.704999 -294.448914)
			(xy 36.70554 -294.4749) (xy 37.018988 -294.4749) (xy 37.022948 -294.425846) (xy 37.034725 -294.378062)
			(xy 37.054016 -294.332786) (xy 37.080319 -294.29119) (xy 37.112954 -294.254353) (xy 37.151075 -294.223228)
			(xy 37.193696 -294.198621) (xy 37.239712 -294.181169) (xy 37.287931 -294.171325) (xy 37.337106 -294.169344)
			(xy 37.385961 -294.175276) (xy 37.433232 -294.188968) (xy 37.477694 -294.210066) (xy 37.518197 -294.238022)
			(xy 37.55369 -294.272114) (xy 37.583255 -294.311458) (xy 37.606126 -294.355035) (xy 37.62171 -294.401716)
			(xy 37.629605 -294.450293) (xy 37.6301 -294.4749) (xy 37.969202 -294.4749) (xy 37.973162 -294.425846)
			(xy 37.984939 -294.378062) (xy 38.00423 -294.332786) (xy 38.030533 -294.29119) (xy 38.063168 -294.254353)
			(xy 38.101289 -294.223228) (xy 38.14391 -294.198621) (xy 38.189926 -294.181169) (xy 38.238145 -294.171325)
			(xy 38.28732 -294.169344) (xy 38.336175 -294.175276) (xy 38.383446 -294.188968) (xy 38.427908 -294.210066)
			(xy 38.468411 -294.238022) (xy 38.503904 -294.272114) (xy 38.533469 -294.311458) (xy 38.55634 -294.355035)
			(xy 38.571924 -294.401716) (xy 38.579819 -294.450293) (xy 38.580314 -294.4749) (xy 40.819082 -294.4749)
			(xy 40.823042 -294.425846) (xy 40.834819 -294.378062) (xy 40.85411 -294.332786) (xy 40.880413 -294.29119)
			(xy 40.913048 -294.254353) (xy 40.951169 -294.223228) (xy 40.99379 -294.198621) (xy 41.039806 -294.181169)
			(xy 41.088025 -294.171325) (xy 41.1372 -294.169344) (xy 41.186055 -294.175276) (xy 41.233326 -294.188968)
			(xy 41.277788 -294.210066) (xy 41.318291 -294.238022) (xy 41.353784 -294.272114) (xy 41.383349 -294.311458)
			(xy 41.40622 -294.355035) (xy 41.421804 -294.401716) (xy 41.429699 -294.450293) (xy 41.430194 -294.4749)
			(xy 41.429699 -294.499507) (xy 41.429367 -294.501549) (xy 41.719236 -294.501549) (xy 41.719236 -294.448251)
			(xy 41.727179 -294.395547) (xy 41.742889 -294.344617) (xy 41.766015 -294.296596) (xy 41.796039 -294.252559)
			(xy 41.832291 -294.213488) (xy 41.873962 -294.180257) (xy 41.92012 -294.153608) (xy 41.969734 -294.134136)
			(xy 42.021696 -294.122276) (xy 42.074846 -294.118293) (xy 42.127996 -294.122276) (xy 42.179958 -294.134136)
			(xy 42.229572 -294.153608) (xy 42.27573 -294.180257) (xy 42.317401 -294.213488) (xy 42.353653 -294.252559)
			(xy 42.383677 -294.296596) (xy 42.406803 -294.344617) (xy 42.422513 -294.395547) (xy 42.430456 -294.448251)
			(xy 42.430954 -294.4749) (xy 42.719002 -294.4749) (xy 42.722962 -294.425846) (xy 42.734739 -294.378062)
			(xy 42.75403 -294.332786) (xy 42.780333 -294.29119) (xy 42.812968 -294.254353) (xy 42.851089 -294.223228)
			(xy 42.89371 -294.198621) (xy 42.939726 -294.181169) (xy 42.987945 -294.171325) (xy 43.03712 -294.169344)
			(xy 43.085975 -294.175276) (xy 43.133246 -294.188968) (xy 43.177708 -294.210066) (xy 43.218211 -294.238022)
			(xy 43.253704 -294.272114) (xy 43.283269 -294.311458) (xy 43.30614 -294.355035) (xy 43.321724 -294.401716)
			(xy 43.329619 -294.450293) (xy 43.330114 -294.4749) (xy 43.668962 -294.4749) (xy 43.672922 -294.425846)
			(xy 43.684699 -294.378062) (xy 43.70399 -294.332786) (xy 43.730293 -294.29119) (xy 43.762928 -294.254353)
			(xy 43.801049 -294.223228) (xy 43.84367 -294.198621) (xy 43.889686 -294.181169) (xy 43.937905 -294.171325)
			(xy 43.98708 -294.169344) (xy 44.035935 -294.175276) (xy 44.083206 -294.188968) (xy 44.127668 -294.210066)
			(xy 44.168171 -294.238022) (xy 44.203664 -294.272114) (xy 44.233229 -294.311458) (xy 44.2561 -294.355035)
			(xy 44.271684 -294.401716) (xy 44.279579 -294.450293) (xy 44.280074 -294.4749) (xy 44.619176 -294.4749)
			(xy 44.623136 -294.425846) (xy 44.634913 -294.378062) (xy 44.654204 -294.332786) (xy 44.680507 -294.29119)
			(xy 44.713142 -294.254353) (xy 44.751263 -294.223228) (xy 44.793884 -294.198621) (xy 44.8399 -294.181169)
			(xy 44.888119 -294.171325) (xy 44.937294 -294.169344) (xy 44.986149 -294.175276) (xy 45.03342 -294.188968)
			(xy 45.077882 -294.210066) (xy 45.118385 -294.238022) (xy 45.153878 -294.272114) (xy 45.183443 -294.311458)
			(xy 45.206314 -294.355035) (xy 45.221898 -294.401716) (xy 45.229793 -294.450293) (xy 45.230288 -294.4749)
			(xy 45.569136 -294.4749) (xy 45.573096 -294.425846) (xy 45.584873 -294.378062) (xy 45.604164 -294.332786)
			(xy 45.630467 -294.29119) (xy 45.663102 -294.254353) (xy 45.701223 -294.223228) (xy 45.743844 -294.198621)
			(xy 45.78986 -294.181169) (xy 45.838079 -294.171325) (xy 45.887254 -294.169344) (xy 45.936109 -294.175276)
			(xy 45.98338 -294.188968) (xy 46.027842 -294.210066) (xy 46.068345 -294.238022) (xy 46.103838 -294.272114)
			(xy 46.133403 -294.311458) (xy 46.156274 -294.355035) (xy 46.171858 -294.401716) (xy 46.179753 -294.450293)
			(xy 46.180248 -294.4749) (xy 46.179753 -294.499507) (xy 46.171858 -294.548084) (xy 46.156274 -294.594765)
			(xy 46.133403 -294.638342) (xy 46.103838 -294.677686) (xy 46.068345 -294.711778) (xy 46.027842 -294.739734)
			(xy 45.98338 -294.760832) (xy 45.936109 -294.774524) (xy 45.887254 -294.780456) (xy 45.838079 -294.778475)
			(xy 45.78986 -294.768631) (xy 45.743844 -294.751179) (xy 45.701223 -294.726572) (xy 45.663102 -294.695447)
			(xy 45.630467 -294.65861) (xy 45.604164 -294.617014) (xy 45.584873 -294.571738) (xy 45.573096 -294.523954)
			(xy 45.569136 -294.4749) (xy 45.230288 -294.4749) (xy 45.229793 -294.499507) (xy 45.221898 -294.548084)
			(xy 45.206314 -294.594765) (xy 45.183443 -294.638342) (xy 45.153878 -294.677686) (xy 45.118385 -294.711778)
			(xy 45.077882 -294.739734) (xy 45.03342 -294.760832) (xy 44.986149 -294.774524) (xy 44.937294 -294.780456)
			(xy 44.888119 -294.778475) (xy 44.8399 -294.768631) (xy 44.793884 -294.751179) (xy 44.751263 -294.726572)
			(xy 44.713142 -294.695447) (xy 44.680507 -294.65861) (xy 44.654204 -294.617014) (xy 44.634913 -294.571738)
			(xy 44.623136 -294.523954) (xy 44.619176 -294.4749) (xy 44.280074 -294.4749) (xy 44.279579 -294.499507)
			(xy 44.271684 -294.548084) (xy 44.2561 -294.594765) (xy 44.233229 -294.638342) (xy 44.203664 -294.677686)
			(xy 44.168171 -294.711778) (xy 44.127668 -294.739734) (xy 44.083206 -294.760832) (xy 44.035935 -294.774524)
			(xy 43.98708 -294.780456) (xy 43.937905 -294.778475) (xy 43.889686 -294.768631) (xy 43.84367 -294.751179)
			(xy 43.801049 -294.726572) (xy 43.762928 -294.695447) (xy 43.730293 -294.65861) (xy 43.70399 -294.617014)
			(xy 43.684699 -294.571738) (xy 43.672922 -294.523954) (xy 43.668962 -294.4749) (xy 43.330114 -294.4749)
			(xy 43.329619 -294.499507) (xy 43.321724 -294.548084) (xy 43.30614 -294.594765) (xy 43.283269 -294.638342)
			(xy 43.253704 -294.677686) (xy 43.218211 -294.711778) (xy 43.177708 -294.739734) (xy 43.133246 -294.760832)
			(xy 43.085975 -294.774524) (xy 43.03712 -294.780456) (xy 42.987945 -294.778475) (xy 42.939726 -294.768631)
			(xy 42.89371 -294.751179) (xy 42.851089 -294.726572) (xy 42.812968 -294.695447) (xy 42.780333 -294.65861)
			(xy 42.75403 -294.617014) (xy 42.734739 -294.571738) (xy 42.722962 -294.523954) (xy 42.719002 -294.4749)
			(xy 42.430954 -294.4749) (xy 42.430456 -294.501549) (xy 42.422513 -294.554253) (xy 42.406803 -294.605183)
			(xy 42.383677 -294.653204) (xy 42.353653 -294.697241) (xy 42.317401 -294.736312) (xy 42.27573 -294.769543)
			(xy 42.229572 -294.796192) (xy 42.179958 -294.815664) (xy 42.127996 -294.827524) (xy 42.074846 -294.831508)
			(xy 42.021696 -294.827524) (xy 41.969734 -294.815664) (xy 41.92012 -294.796192) (xy 41.873962 -294.769543)
			(xy 41.832291 -294.736312) (xy 41.796039 -294.697241) (xy 41.766015 -294.653204) (xy 41.742889 -294.605183)
			(xy 41.727179 -294.554253) (xy 41.719236 -294.501549) (xy 41.429367 -294.501549) (xy 41.421804 -294.548084)
			(xy 41.40622 -294.594765) (xy 41.383349 -294.638342) (xy 41.353784 -294.677686) (xy 41.318291 -294.711778)
			(xy 41.277788 -294.739734) (xy 41.233326 -294.760832) (xy 41.186055 -294.774524) (xy 41.1372 -294.780456)
			(xy 41.088025 -294.778475) (xy 41.039806 -294.768631) (xy 40.99379 -294.751179) (xy 40.951169 -294.726572)
			(xy 40.913048 -294.695447) (xy 40.880413 -294.65861) (xy 40.85411 -294.617014) (xy 40.834819 -294.571738)
			(xy 40.823042 -294.523954) (xy 40.819082 -294.4749) (xy 38.580314 -294.4749) (xy 38.579819 -294.499507)
			(xy 38.571924 -294.548084) (xy 38.55634 -294.594765) (xy 38.533469 -294.638342) (xy 38.503904 -294.677686)
			(xy 38.468411 -294.711778) (xy 38.427908 -294.739734) (xy 38.383446 -294.760832) (xy 38.336175 -294.774524)
			(xy 38.28732 -294.780456) (xy 38.238145 -294.778475) (xy 38.189926 -294.768631) (xy 38.14391 -294.751179)
			(xy 38.101289 -294.726572) (xy 38.063168 -294.695447) (xy 38.030533 -294.65861) (xy 38.00423 -294.617014)
			(xy 37.984939 -294.571738) (xy 37.973162 -294.523954) (xy 37.969202 -294.4749) (xy 37.6301 -294.4749)
			(xy 37.629605 -294.499507) (xy 37.62171 -294.548084) (xy 37.606126 -294.594765) (xy 37.583255 -294.638342)
			(xy 37.55369 -294.677686) (xy 37.518197 -294.711778) (xy 37.477694 -294.739734) (xy 37.433232 -294.760832)
			(xy 37.385961 -294.774524) (xy 37.337106 -294.780456) (xy 37.287931 -294.778475) (xy 37.239712 -294.768631)
			(xy 37.193696 -294.751179) (xy 37.151075 -294.726572) (xy 37.112954 -294.695447) (xy 37.080319 -294.65861)
			(xy 37.054016 -294.617014) (xy 37.034725 -294.571738) (xy 37.022948 -294.523954) (xy 37.018988 -294.4749)
			(xy 36.70554 -294.4749) (xy 36.705133 -294.498602) (xy 36.698365 -294.545521) (xy 36.684968 -294.590993)
			(xy 36.665216 -294.634087) (xy 36.652708 -294.654224) (xy 36.642802 -294.669464) (xy 36.646612 -294.70477)
			(xy 37.522404 -295.580562) (xy 37.528001 -295.586559) (xy 37.535378 -295.6012) (xy 37.536882 -295.609264)
			(xy 37.538152 -295.617392) (xy 37.545518 -295.632124) (xy 37.785802 -295.872408) (xy 37.793212 -295.879091)
			(xy 37.811648 -295.886671) (xy 37.821616 -295.88714) (xy 37.863018 -295.88714) (xy 37.870638 -295.887394)
			(xy 38.678866 -295.887394)
		)
		(stroke
			(width 0)
			(type solid)
		)
		(fill yes)
		(layer "In11.Cu")
		(net "PCEPLL4_VDDA18_PEX0")
	)
	(gr_poly
		(pts
			(xy 337.889342 -91.740736) (xy 337.898235 -91.740405) (xy 337.91495 -91.734325) (xy 337.928566 -91.722881)
			(xy 337.933284 -91.715336) (xy 337.984338 -91.627198) (xy 337.984338 -91.600528) (xy 337.97748 -91.58859)
			(xy 337.965417 -91.566798) (xy 337.946417 -91.520755) (xy 337.933562 -91.472633) (xy 337.927071 -91.423249)
			(xy 337.92668 -91.398344) (xy 337.927166 -91.371093) (xy 337.934922 -91.317145) (xy 337.950277 -91.26485)
			(xy 337.972919 -91.215273) (xy 338.002385 -91.169423) (xy 338.038076 -91.128232) (xy 338.079267 -91.092541)
			(xy 338.125117 -91.063075) (xy 338.174694 -91.040433) (xy 338.226989 -91.025078) (xy 338.280937 -91.017322)
			(xy 338.335439 -91.017322) (xy 338.389387 -91.025078) (xy 338.441682 -91.040433) (xy 338.491259 -91.063075)
			(xy 338.537109 -91.092541) (xy 338.5783 -91.128232) (xy 338.613991 -91.169423) (xy 338.643457 -91.215273)
			(xy 338.666099 -91.26485) (xy 338.681454 -91.317145) (xy 338.68921 -91.371093) (xy 338.689696 -91.398344)
			(xy 338.689296 -91.423249) (xy 338.682821 -91.472637) (xy 338.669973 -91.520761) (xy 338.650971 -91.566804)
			(xy 338.638896 -91.58859) (xy 338.632038 -91.600528) (xy 338.632038 -91.627198) (xy 338.683092 -91.715336)
			(xy 338.687871 -91.722831) (xy 338.701474 -91.734252) (xy 338.718154 -91.740357) (xy 338.727034 -91.740736)
			(xy 342.080596 -91.740736) (xy 342.090665 -91.740312) (xy 342.109265 -91.732591) (xy 342.116664 -91.72575)
			(xy 342.579452 -91.262962) (xy 342.586298 -91.255564) (xy 342.594026 -91.236965) (xy 342.594438 -91.226894)
			(xy 342.594438 -86.92134) (xy 342.593874 -86.909671) (xy 342.583555 -86.88874) (xy 342.574626 -86.881208)
			(xy 342.553647 -86.86445) (xy 342.516146 -86.826025) (xy 342.484398 -86.782723) (xy 342.459031 -86.735401)
			(xy 342.440544 -86.684992) (xy 342.429302 -86.632489) (xy 342.425527 -86.578929) (xy 342.429294 -86.525369)
			(xy 342.440527 -86.472865) (xy 342.459007 -86.422452) (xy 342.484367 -86.375126) (xy 342.516108 -86.33182)
			(xy 342.553603 -86.293389) (xy 342.574626 -86.276688) (xy 342.583506 -86.269111) (xy 342.59385 -86.248212)
			(xy 342.594438 -86.236556) (xy 342.594438 -82.894424) (xy 342.593999 -82.884361) (xy 342.586259 -82.865783)
			(xy 342.579452 -82.858356) (xy 341.272368 -81.551272) (xy 341.264971 -81.544423) (xy 341.246372 -81.536689)
			(xy 341.2363 -81.536286) (xy 338.777326 -81.536286) (xy 338.767561 -81.536776) (xy 338.749476 -81.544161)
			(xy 338.735451 -81.557758) (xy 338.731098 -81.566512) (xy 338.687156 -81.665318) (xy 338.691982 -81.694782)
			(xy 338.702142 -81.705958) (xy 338.720604 -81.727117) (xy 338.751756 -81.773837) (xy 338.775725 -81.824618)
			(xy 338.791993 -81.878364) (xy 338.800209 -81.933913) (xy 338.800694 -81.96199) (xy 338.800208 -81.989241)
			(xy 338.792452 -82.043189) (xy 338.777097 -82.095484) (xy 338.754455 -82.145061) (xy 338.724989 -82.190911)
			(xy 338.689298 -82.232102) (xy 338.648107 -82.267793) (xy 338.602257 -82.297259) (xy 338.55268 -82.319901)
			(xy 338.500385 -82.335256) (xy 338.446437 -82.343012) (xy 338.391935 -82.343012) (xy 338.337987 -82.335256)
			(xy 338.285692 -82.319901) (xy 338.236115 -82.297259) (xy 338.190265 -82.267793) (xy 338.149074 -82.232102)
			(xy 338.113383 -82.190911) (xy 338.083917 -82.145061) (xy 338.061275 -82.095484) (xy 338.04592 -82.043189)
			(xy 338.038164 -81.989241) (xy 338.037678 -81.96199) (xy 338.038175 -81.933914) (xy 338.046398 -81.878368)
			(xy 338.062666 -81.824624) (xy 338.086628 -81.773842) (xy 338.117767 -81.727115) (xy 338.13623 -81.705958)
			(xy 338.14639 -81.694782) (xy 338.151216 -81.665318) (xy 338.107274 -81.566512) (xy 338.10292 -81.557756)
			(xy 338.088906 -81.544145) (xy 338.070813 -81.536774) (xy 338.061046 -81.536286) (xy 334.311498 -81.536286)
			(xy 334.301428 -81.536709) (xy 334.282822 -81.544422) (xy 334.27543 -81.551272) (xy 333.041498 -82.785204)
			(xy 340.274908 -82.785204) (xy 340.278979 -82.729582) (xy 340.291105 -82.675145) (xy 340.311028 -82.623054)
			(xy 340.338324 -82.574419) (xy 340.37241 -82.530276) (xy 340.412559 -82.491567) (xy 340.457917 -82.459116)
			(xy 340.507517 -82.433615) (xy 340.560301 -82.415608) (xy 340.615144 -82.405478) (xy 340.670878 -82.403441)
			(xy 340.726315 -82.409541) (xy 340.780272 -82.423647) (xy 340.831601 -82.445459) (xy 340.879207 -82.474513)
			(xy 340.922075 -82.510188) (xy 340.959292 -82.551725) (xy 340.990065 -82.598238) (xy 341.013737 -82.648735)
			(xy 341.029805 -82.702142) (xy 341.037925 -82.757318) (xy 341.038434 -82.785204) (xy 341.037925 -82.81309)
			(xy 341.029805 -82.868266) (xy 341.013737 -82.921673) (xy 340.990065 -82.97217) (xy 340.959292 -83.018683)
			(xy 340.922075 -83.06022) (xy 340.879207 -83.095895) (xy 340.831601 -83.124949) (xy 340.780272 -83.146761)
			(xy 340.726315 -83.160867) (xy 340.670878 -83.166967) (xy 340.615144 -83.16493) (xy 340.560301 -83.1548)
			(xy 340.507517 -83.136793) (xy 340.457917 -83.111292) (xy 340.412559 -83.078841) (xy 340.37241 -83.040132)
			(xy 340.338324 -82.995989) (xy 340.311028 -82.947354) (xy 340.291105 -82.895263) (xy 340.278979 -82.840826)
			(xy 340.274908 -82.785204) (xy 333.041498 -82.785204) (xy 330.790451 -85.036251) (xy 332.927952 -85.036251)
			(xy 332.927952 -84.981749) (xy 332.935708 -84.927801) (xy 332.951062 -84.875506) (xy 332.973702 -84.825928)
			(xy 333.003166 -84.780076) (xy 333.038856 -84.738884) (xy 333.080044 -84.70319) (xy 333.125893 -84.673721)
			(xy 333.175468 -84.651076) (xy 333.227762 -84.635716) (xy 333.281709 -84.627955) (xy 333.30896 -84.627466)
			(xy 333.3377 -84.627962) (xy 333.394528 -84.636593) (xy 333.449419 -84.65365) (xy 333.50113 -84.678747)
			(xy 333.548492 -84.711317) (xy 333.569818 -84.73059) (xy 333.581319 -84.740714) (xy 333.608837 -84.754156)
			(xy 333.639104 -84.758835) (xy 333.669397 -84.754331) (xy 333.696993 -84.741049) (xy 333.719411 -84.720182)
			(xy 333.734634 -84.693607) (xy 333.738474 -84.678774) (xy 333.745269 -84.650944) (xy 333.766005 -84.597544)
			(xy 333.79449 -84.547843) (xy 333.830084 -84.502958) (xy 333.871987 -84.463897) (xy 333.919257 -84.431538)
			(xy 333.970833 -84.406608) (xy 334.025555 -84.389667) (xy 334.082196 -84.381096) (xy 334.110838 -84.380578)
			(xy 334.138086 -84.381095) (xy 334.192028 -84.388855) (xy 334.244316 -84.404213) (xy 334.293887 -84.426856)
			(xy 334.339731 -84.456322) (xy 334.380915 -84.492012) (xy 334.416601 -84.5332) (xy 334.446063 -84.579047)
			(xy 334.4687 -84.628619) (xy 334.484053 -84.680909) (xy 334.491808 -84.734852) (xy 334.491808 -84.789348)
			(xy 334.484053 -84.843291) (xy 334.4687 -84.895581) (xy 334.455659 -84.924138) (xy 335.867246 -84.924138)
			(xy 335.871317 -84.868516) (xy 335.883443 -84.814079) (xy 335.903366 -84.761988) (xy 335.930662 -84.713353)
			(xy 335.964748 -84.66921) (xy 336.004897 -84.630501) (xy 336.050255 -84.59805) (xy 336.099855 -84.572549)
			(xy 336.152639 -84.554542) (xy 336.207482 -84.544412) (xy 336.263216 -84.542375) (xy 336.318653 -84.548475)
			(xy 336.37261 -84.562581) (xy 336.423939 -84.584393) (xy 336.471545 -84.613447) (xy 336.514413 -84.649122)
			(xy 336.55163 -84.690659) (xy 336.582403 -84.737172) (xy 336.606075 -84.787669) (xy 336.622143 -84.841076)
			(xy 336.630263 -84.896252) (xy 336.630772 -84.924138) (xy 337.713572 -84.924138) (xy 337.717643 -84.868516)
			(xy 337.729769 -84.814079) (xy 337.749692 -84.761988) (xy 337.776988 -84.713353) (xy 337.811074 -84.66921)
			(xy 337.851223 -84.630501) (xy 337.896581 -84.59805) (xy 337.946181 -84.572549) (xy 337.998965 -84.554542)
			(xy 338.053808 -84.544412) (xy 338.109542 -84.542375) (xy 338.164979 -84.548475) (xy 338.218936 -84.562581)
			(xy 338.270265 -84.584393) (xy 338.317871 -84.613447) (xy 338.360739 -84.649122) (xy 338.397956 -84.690659)
			(xy 338.428729 -84.737172) (xy 338.452401 -84.787669) (xy 338.468469 -84.841076) (xy 338.476589 -84.896252)
			(xy 338.477098 -84.924138) (xy 339.565994 -84.924138) (xy 339.570065 -84.868516) (xy 339.582191 -84.814079)
			(xy 339.602114 -84.761988) (xy 339.62941 -84.713353) (xy 339.663496 -84.66921) (xy 339.703645 -84.630501)
			(xy 339.749003 -84.59805) (xy 339.798603 -84.572549) (xy 339.851387 -84.554542) (xy 339.90623 -84.544412)
			(xy 339.961964 -84.542375) (xy 340.017401 -84.548475) (xy 340.071358 -84.562581) (xy 340.122687 -84.584393)
			(xy 340.170293 -84.613447) (xy 340.213161 -84.649122) (xy 340.250378 -84.690659) (xy 340.281151 -84.737172)
			(xy 340.304823 -84.787669) (xy 340.320891 -84.841076) (xy 340.329011 -84.896252) (xy 340.32952 -84.924138)
			(xy 340.329011 -84.952024) (xy 340.320891 -85.0072) (xy 340.304823 -85.060607) (xy 340.281151 -85.111104)
			(xy 340.250378 -85.157617) (xy 340.213161 -85.199154) (xy 340.170293 -85.234829) (xy 340.122687 -85.263883)
			(xy 340.071358 -85.285695) (xy 340.017401 -85.299801) (xy 339.961964 -85.305901) (xy 339.90623 -85.303864)
			(xy 339.851387 -85.293734) (xy 339.798603 -85.275727) (xy 339.749003 -85.250226) (xy 339.703645 -85.217775)
			(xy 339.663496 -85.179066) (xy 339.62941 -85.134923) (xy 339.602114 -85.086288) (xy 339.582191 -85.034197)
			(xy 339.570065 -84.97976) (xy 339.565994 -84.924138) (xy 338.477098 -84.924138) (xy 338.476589 -84.952024)
			(xy 338.468469 -85.0072) (xy 338.452401 -85.060607) (xy 338.428729 -85.111104) (xy 338.397956 -85.157617)
			(xy 338.360739 -85.199154) (xy 338.317871 -85.234829) (xy 338.270265 -85.263883) (xy 338.218936 -85.285695)
			(xy 338.164979 -85.299801) (xy 338.109542 -85.305901) (xy 338.053808 -85.303864) (xy 337.998965 -85.293734)
			(xy 337.946181 -85.275727) (xy 337.896581 -85.250226) (xy 337.851223 -85.217775) (xy 337.811074 -85.179066)
			(xy 337.776988 -85.134923) (xy 337.749692 -85.086288) (xy 337.729769 -85.034197) (xy 337.717643 -84.97976)
			(xy 337.713572 -84.924138) (xy 336.630772 -84.924138) (xy 336.630263 -84.952024) (xy 336.622143 -85.0072)
			(xy 336.606075 -85.060607) (xy 336.582403 -85.111104) (xy 336.55163 -85.157617) (xy 336.514413 -85.199154)
			(xy 336.471545 -85.234829) (xy 336.423939 -85.263883) (xy 336.37261 -85.285695) (xy 336.318653 -85.299801)
			(xy 336.263216 -85.305901) (xy 336.207482 -85.303864) (xy 336.152639 -85.293734) (xy 336.099855 -85.275727)
			(xy 336.050255 -85.250226) (xy 336.004897 -85.217775) (xy 335.964748 -85.179066) (xy 335.930662 -85.134923)
			(xy 335.903366 -85.086288) (xy 335.883443 -85.034197) (xy 335.871317 -84.97976) (xy 335.867246 -84.924138)
			(xy 334.455659 -84.924138) (xy 334.446063 -84.945153) (xy 334.416601 -84.991) (xy 334.380915 -85.032188)
			(xy 334.339731 -85.067878) (xy 334.293887 -85.097344) (xy 334.244316 -85.119987) (xy 334.192028 -85.135345)
			(xy 334.138086 -85.143105) (xy 334.110838 -85.143594) (xy 334.082098 -85.14311) (xy 334.025268 -85.134478)
			(xy 333.970377 -85.117418) (xy 333.918666 -85.092318) (xy 333.871305 -85.059745) (xy 333.84998 -85.04047)
			(xy 333.838467 -85.030364) (xy 333.810952 -85.01693) (xy 333.780691 -85.012254) (xy 333.750404 -85.016757)
			(xy 333.722813 -85.030034) (xy 333.700396 -85.050892) (xy 333.685168 -85.077457) (xy 333.681324 -85.092286)
			(xy 333.674572 -85.120127) (xy 333.653828 -85.173527) (xy 333.625335 -85.223227) (xy 333.589735 -85.26811)
			(xy 333.547827 -85.307169) (xy 333.500552 -85.339526) (xy 333.448973 -85.364454) (xy 333.394247 -85.381394)
			(xy 333.337604 -85.389964) (xy 333.30896 -85.390482) (xy 333.281709 -85.390045) (xy 333.227762 -85.382284)
			(xy 333.175468 -85.366924) (xy 333.125893 -85.344279) (xy 333.080044 -85.31481) (xy 333.038856 -85.279116)
			(xy 333.003166 -85.237924) (xy 332.973702 -85.192072) (xy 332.951062 -85.142494) (xy 332.935708 -85.090199)
			(xy 332.927952 -85.036251) (xy 330.790451 -85.036251) (xy 329.536253 -86.290449) (xy 329.920604 -86.290449)
			(xy 329.920604 -86.235951) (xy 329.92836 -86.182007) (xy 329.943714 -86.129716) (xy 329.966354 -86.080142)
			(xy 329.995818 -86.034295) (xy 330.031507 -85.993107) (xy 330.072695 -85.957418) (xy 330.118542 -85.927954)
			(xy 330.168116 -85.905314) (xy 330.220407 -85.88996) (xy 330.274351 -85.882204) (xy 330.3016 -85.881718)
			(xy 330.327509 -85.882125) (xy 330.378849 -85.889162) (xy 330.428764 -85.90308) (xy 330.476338 -85.923622)
			(xy 330.520695 -85.950411) (xy 330.56102 -85.982955) (xy 330.596573 -86.020655) (xy 330.611988 -86.041484)
			(xy 330.617723 -86.048819) (xy 330.63323 -86.059102) (xy 330.642214 -86.06155) (xy 330.672694 -86.068154)
			(xy 330.681908 -86.069801) (xy 330.700409 -86.067048) (xy 330.708762 -86.06282) (xy 330.734776 -86.048549)
			(xy 330.789708 -86.026119) (xy 330.847074 -86.010962) (xy 330.905916 -86.003332) (xy 330.935584 -86.002876)
			(xy 330.965551 -86.003397) (xy 331.024971 -86.011218) (xy 331.082863 -86.026728) (xy 331.138235 -86.049661)
			(xy 331.19014 -86.079626) (xy 331.237689 -86.116109) (xy 331.28007 -86.158487) (xy 331.316556 -86.206034)
			(xy 331.346525 -86.257936) (xy 331.347349 -86.259924) (xy 333.146144 -86.259924) (xy 333.150215 -86.204302)
			(xy 333.162341 -86.149865) (xy 333.182264 -86.097774) (xy 333.20956 -86.049139) (xy 333.243646 -86.004996)
			(xy 333.283795 -85.966287) (xy 333.329153 -85.933836) (xy 333.378753 -85.908335) (xy 333.431537 -85.890328)
			(xy 333.48638 -85.880198) (xy 333.542114 -85.878161) (xy 333.597551 -85.884261) (xy 333.651508 -85.898367)
			(xy 333.702837 -85.920179) (xy 333.750443 -85.949233) (xy 333.793311 -85.984908) (xy 333.830528 -86.026445)
			(xy 333.861301 -86.072958) (xy 333.884973 -86.123455) (xy 333.901041 -86.176862) (xy 333.909161 -86.232038)
			(xy 333.90967 -86.259924) (xy 333.909161 -86.28781) (xy 333.901041 -86.342986) (xy 333.884973 -86.396393)
			(xy 333.861301 -86.44689) (xy 333.830528 -86.493403) (xy 333.793311 -86.53494) (xy 333.750443 -86.570615)
			(xy 333.702837 -86.599669) (xy 333.651508 -86.621481) (xy 333.597551 -86.635587) (xy 333.542114 -86.641687)
			(xy 333.48638 -86.63965) (xy 333.431537 -86.62952) (xy 333.378753 -86.611513) (xy 333.329153 -86.586012)
			(xy 333.283795 -86.553561) (xy 333.243646 -86.514852) (xy 333.20956 -86.470709) (xy 333.182264 -86.422074)
			(xy 333.162341 -86.369983) (xy 333.150215 -86.315546) (xy 333.146144 -86.259924) (xy 331.347349 -86.259924)
			(xy 331.369462 -86.313307) (xy 331.384976 -86.371197) (xy 331.392801 -86.430617) (xy 331.393292 -86.460584)
			(xy 331.393292 -86.77021) (xy 335.867246 -86.77021) (xy 335.871317 -86.714588) (xy 335.883443 -86.660151)
			(xy 335.903366 -86.60806) (xy 335.930662 -86.559425) (xy 335.964748 -86.515282) (xy 336.004897 -86.476573)
			(xy 336.050255 -86.444122) (xy 336.099855 -86.418621) (xy 336.152639 -86.400614) (xy 336.207482 -86.390484)
			(xy 336.263216 -86.388447) (xy 336.318653 -86.394547) (xy 336.37261 -86.408653) (xy 336.423939 -86.430465)
			(xy 336.471545 -86.459519) (xy 336.514413 -86.495194) (xy 336.55163 -86.536731) (xy 336.582403 -86.583244)
			(xy 336.606075 -86.633741) (xy 336.622143 -86.687148) (xy 336.630263 -86.742324) (xy 336.630716 -86.767162)
			(xy 339.539832 -86.767162) (xy 339.543903 -86.71154) (xy 339.556029 -86.657103) (xy 339.575952 -86.605012)
			(xy 339.603248 -86.556377) (xy 339.637334 -86.512234) (xy 339.677483 -86.473525) (xy 339.722841 -86.441074)
			(xy 339.772441 -86.415573) (xy 339.825225 -86.397566) (xy 339.880068 -86.387436) (xy 339.935802 -86.385399)
			(xy 339.991239 -86.391499) (xy 340.045196 -86.405605) (xy 340.096525 -86.427417) (xy 340.144131 -86.456471)
			(xy 340.186999 -86.492146) (xy 340.224216 -86.533683) (xy 340.244585 -86.56447) (xy 341.525604 -86.56447)
			(xy 341.529675 -86.508848) (xy 341.541801 -86.454411) (xy 341.561724 -86.40232) (xy 341.58902 -86.353685)
			(xy 341.623106 -86.309542) (xy 341.663255 -86.270833) (xy 341.708613 -86.238382) (xy 341.758213 -86.212881)
			(xy 341.810997 -86.194874) (xy 341.86584 -86.184744) (xy 341.921574 -86.182707) (xy 341.977011 -86.188807)
			(xy 342.030968 -86.202913) (xy 342.082297 -86.224725) (xy 342.129903 -86.253779) (xy 342.172771 -86.289454)
			(xy 342.209988 -86.330991) (xy 342.240761 -86.377504) (xy 342.264433 -86.428001) (xy 342.280501 -86.481408)
			(xy 342.288621 -86.536584) (xy 342.28913 -86.56447) (xy 342.288621 -86.592356) (xy 342.280501 -86.647532)
			(xy 342.264433 -86.700939) (xy 342.240761 -86.751436) (xy 342.209988 -86.797949) (xy 342.172771 -86.839486)
			(xy 342.129903 -86.875161) (xy 342.082297 -86.904215) (xy 342.030968 -86.926027) (xy 341.977011 -86.940133)
			(xy 341.921574 -86.946233) (xy 341.86584 -86.944196) (xy 341.810997 -86.934066) (xy 341.758213 -86.916059)
			(xy 341.708613 -86.890558) (xy 341.663255 -86.858107) (xy 341.623106 -86.819398) (xy 341.58902 -86.775255)
			(xy 341.561724 -86.72662) (xy 341.541801 -86.674529) (xy 341.529675 -86.620092) (xy 341.525604 -86.56447)
			(xy 340.244585 -86.56447) (xy 340.254989 -86.580196) (xy 340.278661 -86.630693) (xy 340.294729 -86.6841)
			(xy 340.302849 -86.739276) (xy 340.303358 -86.767162) (xy 340.302849 -86.795048) (xy 340.294729 -86.850224)
			(xy 340.278661 -86.903631) (xy 340.254989 -86.954128) (xy 340.224216 -87.000641) (xy 340.186999 -87.042178)
			(xy 340.144131 -87.077853) (xy 340.096525 -87.106907) (xy 340.045196 -87.128719) (xy 339.991239 -87.142825)
			(xy 339.935802 -87.148925) (xy 339.880068 -87.146888) (xy 339.825225 -87.136758) (xy 339.772441 -87.118751)
			(xy 339.722841 -87.09325) (xy 339.677483 -87.060799) (xy 339.637334 -87.02209) (xy 339.603248 -86.977947)
			(xy 339.575952 -86.929312) (xy 339.556029 -86.877221) (xy 339.543903 -86.822784) (xy 339.539832 -86.767162)
			(xy 336.630716 -86.767162) (xy 336.630772 -86.77021) (xy 336.630263 -86.798096) (xy 336.622143 -86.853272)
			(xy 336.606075 -86.906679) (xy 336.582403 -86.957176) (xy 336.55163 -87.003689) (xy 336.514413 -87.045226)
			(xy 336.471545 -87.080901) (xy 336.423939 -87.109955) (xy 336.37261 -87.131767) (xy 336.318653 -87.145873)
			(xy 336.263216 -87.151973) (xy 336.207482 -87.149936) (xy 336.152639 -87.139806) (xy 336.099855 -87.121799)
			(xy 336.050255 -87.096298) (xy 336.004897 -87.063847) (xy 335.964748 -87.025138) (xy 335.930662 -86.980995)
			(xy 335.903366 -86.93236) (xy 335.883443 -86.880269) (xy 335.871317 -86.825832) (xy 335.867246 -86.77021)
			(xy 331.393292 -86.77021) (xy 331.393292 -87.324184) (xy 331.392824 -87.354153) (xy 331.385002 -87.413579)
			(xy 331.36949 -87.471476) (xy 331.346554 -87.526852) (xy 331.316585 -87.578761) (xy 331.280097 -87.626314)
			(xy 331.237714 -87.668697) (xy 331.190161 -87.705185) (xy 331.138252 -87.735154) (xy 331.082876 -87.75809)
			(xy 331.024979 -87.773602) (xy 330.965553 -87.781424) (xy 330.935584 -87.781892) (xy 330.905945 -87.781463)
			(xy 330.847162 -87.773834) (xy 330.789859 -87.758667) (xy 330.734998 -87.736217) (xy 330.709016 -87.721948)
			(xy 330.700604 -87.7177) (xy 330.681973 -87.714967) (xy 330.672694 -87.716614) (xy 330.642468 -87.723472)
			(xy 330.633482 -87.725918) (xy 330.617974 -87.736199) (xy 330.612242 -87.743538) (xy 330.596837 -87.764409)
			(xy 330.561273 -87.802173) (xy 330.520921 -87.83477) (xy 330.476524 -87.8616) (xy 330.428902 -87.882168)
			(xy 330.378933 -87.896095) (xy 330.327537 -87.903122) (xy 330.3016 -87.903558) (xy 330.274352 -87.902972)
			(xy 330.220412 -87.895216) (xy 330.168124 -87.879863) (xy 330.118553 -87.857225) (xy 330.072709 -87.827763)
			(xy 330.031524 -87.792076) (xy 329.995837 -87.750891) (xy 329.966375 -87.705047) (xy 329.943737 -87.655476)
			(xy 329.928384 -87.603188) (xy 329.920628 -87.549248) (xy 329.920628 -87.494752) (xy 329.928384 -87.440812)
			(xy 329.943737 -87.388524) (xy 329.966375 -87.338953) (xy 329.995837 -87.293109) (xy 330.031524 -87.251924)
			(xy 330.072709 -87.216237) (xy 330.118553 -87.186775) (xy 330.168124 -87.164137) (xy 330.220412 -87.148784)
			(xy 330.274352 -87.141028) (xy 330.3016 -87.140542) (xy 330.316393 -87.140675) (xy 330.345891 -87.142966)
			(xy 330.360528 -87.145114) (xy 330.37145 -87.146892) (xy 330.392786 -87.140796) (xy 330.460096 -87.083392)
			(xy 330.46812 -87.075821) (xy 330.477338 -87.055803) (xy 330.477876 -87.044784) (xy 330.477876 -86.740492)
			(xy 330.47735 -86.729471) (xy 330.468123 -86.709455) (xy 330.460096 -86.701884) (xy 330.392786 -86.64448)
			(xy 330.37145 -86.638384) (xy 330.360528 -86.640162) (xy 330.345891 -86.642306) (xy 330.316393 -86.644592)
			(xy 330.3016 -86.644734) (xy 330.274351 -86.644196) (xy 330.220407 -86.63644) (xy 330.168116 -86.621086)
			(xy 330.118542 -86.598446) (xy 330.072695 -86.568982) (xy 330.031507 -86.533293) (xy 329.995818 -86.492105)
			(xy 329.966354 -86.446258) (xy 329.943714 -86.396684) (xy 329.92836 -86.344393) (xy 329.920604 -86.290449)
			(xy 329.536253 -86.290449) (xy 328.429112 -87.39759) (xy 328.422263 -87.404987) (xy 328.414523 -87.423585)
			(xy 328.414126 -87.433658) (xy 328.414126 -88.406224) (xy 328.41476 -88.418737) (xy 328.415262 -88.419686)
			(xy 331.85303 -88.419686) (xy 331.857101 -88.364064) (xy 331.869227 -88.309627) (xy 331.88915 -88.257536)
			(xy 331.916446 -88.208901) (xy 331.950532 -88.164758) (xy 331.990681 -88.126049) (xy 332.036039 -88.093598)
			(xy 332.085639 -88.068097) (xy 332.138423 -88.05009) (xy 332.193266 -88.03996) (xy 332.249 -88.037923)
			(xy 332.304437 -88.044023) (xy 332.358394 -88.058129) (xy 332.409723 -88.079941) (xy 332.457329 -88.108995)
			(xy 332.500197 -88.14467) (xy 332.537414 -88.186207) (xy 332.568187 -88.23272) (xy 332.591859 -88.283217)
			(xy 332.607927 -88.336624) (xy 332.616047 -88.3918) (xy 332.616556 -88.419686) (xy 332.616047 -88.447572)
			(xy 332.607927 -88.502748) (xy 332.591859 -88.556155) (xy 332.568187 -88.606652) (xy 332.537414 -88.653165)
			(xy 332.500197 -88.694702) (xy 332.457329 -88.730377) (xy 332.409723 -88.759431) (xy 332.358394 -88.781243)
			(xy 332.304437 -88.795349) (xy 332.249 -88.801449) (xy 332.193266 -88.799412) (xy 332.138423 -88.789282)
			(xy 332.085639 -88.771275) (xy 332.036039 -88.745774) (xy 331.990681 -88.713323) (xy 331.950532 -88.674614)
			(xy 331.916446 -88.630471) (xy 331.88915 -88.581836) (xy 331.869227 -88.529745) (xy 331.857101 -88.475308)
			(xy 331.85303 -88.419686) (xy 328.415262 -88.419686) (xy 328.426467 -88.440857) (xy 328.436478 -88.448388)
			(xy 328.516996 -88.50249) (xy 328.541888 -88.505284) (xy 328.553572 -88.500458) (xy 328.576339 -88.491694)
			(xy 328.62354 -88.479364) (xy 328.671927 -88.473149) (xy 328.69632 -88.472772) (xy 328.723572 -88.473259)
			(xy 328.77752 -88.481018) (xy 328.829815 -88.496376) (xy 328.879393 -88.51902) (xy 328.925243 -88.548488)
			(xy 328.966433 -88.584181) (xy 329.002124 -88.625373) (xy 329.03159 -88.671225) (xy 329.054231 -88.720804)
			(xy 329.069586 -88.773099) (xy 329.077342 -88.827048) (xy 329.077342 -88.871806) (xy 333.8863 -88.871806)
			(xy 333.890371 -88.816184) (xy 333.902497 -88.761747) (xy 333.92242 -88.709656) (xy 333.949716 -88.661021)
			(xy 333.983802 -88.616878) (xy 334.023951 -88.578169) (xy 334.069309 -88.545718) (xy 334.118909 -88.520217)
			(xy 334.171693 -88.50221) (xy 334.226536 -88.49208) (xy 334.28227 -88.490043) (xy 334.337707 -88.496143)
			(xy 334.391664 -88.510249) (xy 334.442993 -88.532061) (xy 334.490599 -88.561115) (xy 334.533467 -88.59679)
			(xy 334.547518 -88.612472) (xy 335.867246 -88.612472) (xy 335.871317 -88.55685) (xy 335.883443 -88.502413)
			(xy 335.903366 -88.450322) (xy 335.930662 -88.401687) (xy 335.964748 -88.357544) (xy 336.004897 -88.318835)
			(xy 336.050255 -88.286384) (xy 336.099855 -88.260883) (xy 336.152639 -88.242876) (xy 336.207482 -88.232746)
			(xy 336.263216 -88.230709) (xy 336.318653 -88.236809) (xy 336.37261 -88.250915) (xy 336.423939 -88.272727)
			(xy 336.471545 -88.301781) (xy 336.514413 -88.337456) (xy 336.55163 -88.378993) (xy 336.582403 -88.425506)
			(xy 336.606075 -88.476003) (xy 336.622143 -88.52941) (xy 336.630263 -88.584586) (xy 336.630772 -88.612472)
			(xy 337.713572 -88.612472) (xy 337.717643 -88.55685) (xy 337.729769 -88.502413) (xy 337.749692 -88.450322)
			(xy 337.776988 -88.401687) (xy 337.811074 -88.357544) (xy 337.851223 -88.318835) (xy 337.896581 -88.286384)
			(xy 337.946181 -88.260883) (xy 337.998965 -88.242876) (xy 338.053808 -88.232746) (xy 338.109542 -88.230709)
			(xy 338.164979 -88.236809) (xy 338.218936 -88.250915) (xy 338.270265 -88.272727) (xy 338.317871 -88.301781)
			(xy 338.360739 -88.337456) (xy 338.397956 -88.378993) (xy 338.428729 -88.425506) (xy 338.452401 -88.476003)
			(xy 338.468469 -88.52941) (xy 338.476589 -88.584586) (xy 338.476922 -88.60282) (xy 339.565994 -88.60282)
			(xy 339.570065 -88.547198) (xy 339.582191 -88.492761) (xy 339.602114 -88.44067) (xy 339.62941 -88.392035)
			(xy 339.663496 -88.347892) (xy 339.703645 -88.309183) (xy 339.749003 -88.276732) (xy 339.798603 -88.251231)
			(xy 339.851387 -88.233224) (xy 339.90623 -88.223094) (xy 339.961964 -88.221057) (xy 340.017401 -88.227157)
			(xy 340.071358 -88.241263) (xy 340.122687 -88.263075) (xy 340.170293 -88.292129) (xy 340.213161 -88.327804)
			(xy 340.250378 -88.369341) (xy 340.281151 -88.415854) (xy 340.304823 -88.466351) (xy 340.320891 -88.519758)
			(xy 340.329011 -88.574934) (xy 340.32952 -88.60282) (xy 340.329011 -88.630706) (xy 340.320891 -88.685882)
			(xy 340.304823 -88.739289) (xy 340.281151 -88.789786) (xy 340.250378 -88.836299) (xy 340.213161 -88.877836)
			(xy 340.170293 -88.913511) (xy 340.122687 -88.942565) (xy 340.071358 -88.964377) (xy 340.017401 -88.978483)
			(xy 339.961964 -88.984583) (xy 339.90623 -88.982546) (xy 339.851387 -88.972416) (xy 339.798603 -88.954409)
			(xy 339.749003 -88.928908) (xy 339.703645 -88.896457) (xy 339.663496 -88.857748) (xy 339.62941 -88.813605)
			(xy 339.602114 -88.76497) (xy 339.582191 -88.712879) (xy 339.570065 -88.658442) (xy 339.565994 -88.60282)
			(xy 338.476922 -88.60282) (xy 338.477098 -88.612472) (xy 338.476589 -88.640358) (xy 338.468469 -88.695534)
			(xy 338.452401 -88.748941) (xy 338.428729 -88.799438) (xy 338.397956 -88.845951) (xy 338.360739 -88.887488)
			(xy 338.317871 -88.923163) (xy 338.270265 -88.952217) (xy 338.218936 -88.974029) (xy 338.164979 -88.988135)
			(xy 338.109542 -88.994235) (xy 338.053808 -88.992198) (xy 337.998965 -88.982068) (xy 337.946181 -88.964061)
			(xy 337.896581 -88.93856) (xy 337.851223 -88.906109) (xy 337.811074 -88.8674) (xy 337.776988 -88.823257)
			(xy 337.749692 -88.774622) (xy 337.729769 -88.722531) (xy 337.717643 -88.668094) (xy 337.713572 -88.612472)
			(xy 336.630772 -88.612472) (xy 336.630263 -88.640358) (xy 336.622143 -88.695534) (xy 336.606075 -88.748941)
			(xy 336.582403 -88.799438) (xy 336.55163 -88.845951) (xy 336.514413 -88.887488) (xy 336.471545 -88.923163)
			(xy 336.423939 -88.952217) (xy 336.37261 -88.974029) (xy 336.318653 -88.988135) (xy 336.263216 -88.994235)
			(xy 336.207482 -88.992198) (xy 336.152639 -88.982068) (xy 336.099855 -88.964061) (xy 336.050255 -88.93856)
			(xy 336.004897 -88.906109) (xy 335.964748 -88.8674) (xy 335.930662 -88.823257) (xy 335.903366 -88.774622)
			(xy 335.883443 -88.722531) (xy 335.871317 -88.668094) (xy 335.867246 -88.612472) (xy 334.547518 -88.612472)
			(xy 334.570684 -88.638327) (xy 334.601457 -88.68484) (xy 334.625129 -88.735337) (xy 334.641197 -88.788744)
			(xy 334.649317 -88.84392) (xy 334.649826 -88.871806) (xy 334.649317 -88.899692) (xy 334.641197 -88.954868)
			(xy 334.625129 -89.008275) (xy 334.601457 -89.058772) (xy 334.570684 -89.105285) (xy 334.533467 -89.146822)
			(xy 334.490599 -89.182497) (xy 334.442993 -89.211551) (xy 334.391664 -89.233363) (xy 334.337707 -89.247469)
			(xy 334.28227 -89.253569) (xy 334.226536 -89.251532) (xy 334.171693 -89.241402) (xy 334.118909 -89.223395)
			(xy 334.069309 -89.197894) (xy 334.023951 -89.165443) (xy 333.983802 -89.126734) (xy 333.949716 -89.082591)
			(xy 333.92242 -89.033956) (xy 333.902497 -88.981865) (xy 333.890371 -88.927428) (xy 333.8863 -88.871806)
			(xy 329.077342 -88.871806) (xy 329.077342 -88.881552) (xy 329.069586 -88.935501) (xy 329.054231 -88.987796)
			(xy 329.03159 -89.037375) (xy 329.002124 -89.083227) (xy 328.966433 -89.124419) (xy 328.925243 -89.160112)
			(xy 328.879393 -89.18958) (xy 328.829815 -89.212224) (xy 328.77752 -89.227582) (xy 328.723572 -89.235341)
			(xy 328.69632 -89.235788) (xy 328.671927 -89.235403) (xy 328.623539 -89.229195) (xy 328.576335 -89.216875)
			(xy 328.553572 -89.208102) (xy 328.541888 -89.203276) (xy 328.516996 -89.20607) (xy 328.436478 -89.260172)
			(xy 328.426445 -89.267694) (xy 328.425583 -89.269316) (xy 329.807568 -89.269316) (xy 329.811639 -89.213694)
			(xy 329.823765 -89.159257) (xy 329.843688 -89.107166) (xy 329.870984 -89.058531) (xy 329.90507 -89.014388)
			(xy 329.945219 -88.975679) (xy 329.990577 -88.943228) (xy 330.040177 -88.917727) (xy 330.092961 -88.89972)
			(xy 330.147804 -88.88959) (xy 330.203538 -88.887553) (xy 330.258975 -88.893653) (xy 330.312932 -88.907759)
			(xy 330.364261 -88.929571) (xy 330.411867 -88.958625) (xy 330.454735 -88.9943) (xy 330.491952 -89.035837)
			(xy 330.522725 -89.08235) (xy 330.546397 -89.132847) (xy 330.562465 -89.186254) (xy 330.570585 -89.24143)
			(xy 330.571094 -89.269316) (xy 330.570585 -89.297202) (xy 330.562465 -89.352378) (xy 330.546397 -89.405785)
			(xy 330.522725 -89.456282) (xy 330.491952 -89.502795) (xy 330.454735 -89.544332) (xy 330.411867 -89.580007)
			(xy 330.364261 -89.609061) (xy 330.312932 -89.630873) (xy 330.258975 -89.644979) (xy 330.203538 -89.651079)
			(xy 330.147804 -89.649042) (xy 330.092961 -89.638912) (xy 330.040177 -89.620905) (xy 329.990577 -89.595404)
			(xy 329.945219 -89.562953) (xy 329.90507 -89.524244) (xy 329.870984 -89.480101) (xy 329.843688 -89.431466)
			(xy 329.823765 -89.379375) (xy 329.811639 -89.324938) (xy 329.807568 -89.269316) (xy 328.425583 -89.269316)
			(xy 328.414694 -89.289812) (xy 328.414126 -89.302336) (xy 328.414126 -90.277188) (xy 328.414547 -90.287259)
			(xy 328.422262 -90.305864) (xy 328.429112 -90.313256) (xy 328.779886 -90.66403) (xy 336.546188 -90.66403)
			(xy 336.550259 -90.608408) (xy 336.562385 -90.553971) (xy 336.582308 -90.50188) (xy 336.609604 -90.453245)
			(xy 336.64369 -90.409102) (xy 336.683839 -90.370393) (xy 336.729197 -90.337942) (xy 336.778797 -90.312441)
			(xy 336.831581 -90.294434) (xy 336.886424 -90.284304) (xy 336.942158 -90.282267) (xy 336.997595 -90.288367)
			(xy 337.051552 -90.302473) (xy 337.102881 -90.324285) (xy 337.150487 -90.353339) (xy 337.193355 -90.389014)
			(xy 337.230572 -90.430551) (xy 337.261345 -90.477064) (xy 337.285017 -90.527561) (xy 337.301085 -90.580968)
			(xy 337.309205 -90.636144) (xy 337.309714 -90.66403) (xy 337.309205 -90.691916) (xy 337.301085 -90.747092)
			(xy 337.285017 -90.800499) (xy 337.261345 -90.850996) (xy 337.230572 -90.897509) (xy 337.193355 -90.939046)
			(xy 337.150487 -90.974721) (xy 337.102881 -91.003775) (xy 337.051552 -91.025587) (xy 336.997595 -91.039693)
			(xy 336.942158 -91.045793) (xy 336.886424 -91.043756) (xy 336.831581 -91.033626) (xy 336.778797 -91.015619)
			(xy 336.729197 -90.990118) (xy 336.683839 -90.957667) (xy 336.64369 -90.918958) (xy 336.609604 -90.874815)
			(xy 336.582308 -90.82618) (xy 336.562385 -90.774089) (xy 336.550259 -90.719652) (xy 336.546188 -90.66403)
			(xy 328.779886 -90.66403) (xy 329.841606 -91.72575) (xy 329.849002 -91.732601) (xy 329.867601 -91.740341)
			(xy 329.877674 -91.740736)
		)
		(stroke
			(width 0)
			(type solid)
		)
		(fill yes)
		(layer "In11.Cu")
		(net "P3V3_VDD_9ZXL0851_8_15")
	)
	(gr_poly
		(pts
			(xy 327.71334 -307.505354) (xy 327.723216 -307.504891) (xy 327.741514 -307.497448) (xy 327.7489 -307.490876)
			(xy 327.749154 -307.490622) (xy 327.911968 -307.327808) (xy 327.912476 -307.3273) (xy 327.919049 -307.319915)
			(xy 327.926479 -307.301616) (xy 327.926954 -307.29174) (xy 327.926954 -287.658048) (xy 327.927388 -287.647983)
			(xy 327.935122 -287.629398) (xy 327.94194 -287.62198) (xy 329.6158 -285.94812) (xy 329.616308 -285.947612)
			(xy 329.62289 -285.940231) (xy 329.630334 -285.921931) (xy 329.630786 -285.912052) (xy 329.630786 -284.808422)
			(xy 329.630348 -284.798358) (xy 329.622612 -284.779776) (xy 329.6158 -284.772354) (xy 329.250548 -284.407102)
			(xy 329.243436 -284.399736) (xy 329.22464 -284.392116) (xy 327.162668 -284.392116) (xy 327.152601 -284.392545)
			(xy 327.134006 -284.40027) (xy 327.1266 -284.407102) (xy 326.327008 -285.206694) (xy 326.319642 -285.213806)
			(xy 326.312022 -285.232602) (xy 326.312022 -288.835592) (xy 326.311601 -288.845663) (xy 326.303891 -288.864272)
			(xy 326.297036 -288.87166) (xy 326.197214 -288.971482) (xy 326.193404 -288.982912) (xy 326.182797 -289.013214)
			(xy 326.154687 -289.070936) (xy 326.11918 -289.124425) (xy 326.0769 -289.172739) (xy 326.028593 -289.215028)
			(xy 325.97511 -289.250545) (xy 325.917394 -289.278664) (xy 325.88708 -289.289236) (xy 325.87565 -289.293046)
			(xy 324.153784 -291.014912) (xy 324.146389 -291.021765) (xy 324.12779 -291.029508) (xy 324.117716 -291.029898)
			(xy 321.907916 -291.029898) (xy 321.897853 -291.030337) (xy 321.87927 -291.038072) (xy 321.871848 -291.044884)
			(xy 321.408044 -291.508688) (xy 321.400424 -291.530786) (xy 321.401948 -291.542724) (xy 321.403469 -291.554987)
			(xy 321.40512 -291.579644) (xy 321.40525 -291.592) (xy 321.404764 -291.619252) (xy 321.397008 -291.673202)
			(xy 321.381653 -291.725499) (xy 321.359013 -291.775079) (xy 321.329547 -291.820933) (xy 321.293856 -291.862126)
			(xy 321.252666 -291.897822) (xy 321.206816 -291.927293) (xy 321.157239 -291.949939) (xy 321.104943 -291.965299)
			(xy 321.050994 -291.973061) (xy 321.023742 -291.973508) (xy 321.011386 -291.973387) (xy 320.986728 -291.971737)
			(xy 320.974466 -291.970206) (xy 320.962528 -291.968682) (xy 320.94043 -291.976302) (xy 320.794634 -292.122098)
			(xy 325.457312 -292.122098) (xy 325.457754 -292.095494) (xy 325.465136 -292.0428) (xy 325.479771 -291.991644)
			(xy 325.501375 -291.943019) (xy 325.529528 -291.897869) (xy 325.563683 -291.85707) (xy 325.603177 -291.821415)
			(xy 325.624952 -291.806122) (xy 325.63639 -291.797731) (xy 325.6546 -291.776003) (xy 325.666125 -291.750101)
			(xy 325.670074 -291.722027) (xy 325.66614 -291.693951) (xy 325.654629 -291.668043) (xy 325.63643 -291.646306)
			(xy 325.624952 -291.637974) (xy 325.603163 -291.622704) (xy 325.563684 -291.587034) (xy 325.529542 -291.546226)
			(xy 325.501398 -291.501072) (xy 325.479799 -291.452447) (xy 325.465163 -291.401293) (xy 325.457773 -291.348601)
			(xy 325.457312 -291.321998) (xy 325.457798 -291.294747) (xy 325.465554 -291.240799) (xy 325.480909 -291.188504)
			(xy 325.503551 -291.138927) (xy 325.533017 -291.093077) (xy 325.568708 -291.051886) (xy 325.609899 -291.016195)
			(xy 325.655749 -290.986729) (xy 325.705326 -290.964087) (xy 325.757621 -290.948732) (xy 325.811569 -290.940976)
			(xy 325.866071 -290.940976) (xy 325.920019 -290.948732) (xy 325.972314 -290.964087) (xy 326.021891 -290.986729)
			(xy 326.067741 -291.016195) (xy 326.108932 -291.051886) (xy 326.144623 -291.093077) (xy 326.174089 -291.138927)
			(xy 326.196731 -291.188504) (xy 326.212086 -291.240799) (xy 326.219842 -291.294747) (xy 326.220328 -291.321998)
			(xy 326.219909 -291.348603) (xy 326.212526 -291.401299) (xy 326.197889 -291.452457) (xy 326.176282 -291.501083)
			(xy 326.148125 -291.546233) (xy 326.113965 -291.587031) (xy 326.074465 -291.622683) (xy 326.052688 -291.637974)
			(xy 326.041162 -291.64625) (xy 326.02296 -291.668007) (xy 326.011447 -291.693934) (xy 326.007513 -291.722027)
			(xy 326.011462 -291.750118) (xy 326.022988 -291.776039) (xy 326.041202 -291.797786) (xy 326.052688 -291.806122)
			(xy 326.074484 -291.821382) (xy 326.113961 -291.857055) (xy 326.148101 -291.897865) (xy 326.176243 -291.943021)
			(xy 326.197842 -291.991648) (xy 326.212477 -292.042803) (xy 326.219867 -292.095494) (xy 326.220328 -292.122098)
			(xy 326.219842 -292.149349) (xy 326.212086 -292.203297) (xy 326.196731 -292.255592) (xy 326.174089 -292.305169)
			(xy 326.144623 -292.351019) (xy 326.108932 -292.39221) (xy 326.067741 -292.427901) (xy 326.021891 -292.457367)
			(xy 325.972314 -292.480009) (xy 325.920019 -292.495364) (xy 325.866071 -292.50312) (xy 325.811569 -292.50312)
			(xy 325.757621 -292.495364) (xy 325.705326 -292.480009) (xy 325.655749 -292.457367) (xy 325.609899 -292.427901)
			(xy 325.568708 -292.39221) (xy 325.533017 -292.351019) (xy 325.503551 -292.305169) (xy 325.480909 -292.255592)
			(xy 325.465554 -292.203297) (xy 325.457798 -292.149349) (xy 325.457312 -292.122098) (xy 320.794634 -292.122098)
			(xy 320.519044 -292.397688) (xy 320.514315 -292.402707) (xy 320.507492 -292.414684) (xy 320.505582 -292.42131)
			(xy 320.503042 -292.431978) (xy 320.50482 -292.442646) (xy 320.507541 -292.459021) (xy 320.510468 -292.492088)
			(xy 320.510662 -292.508686) (xy 320.510142 -292.537405) (xy 320.501529 -292.594194) (xy 320.484494 -292.649047)
			(xy 320.459423 -292.700725) (xy 320.426884 -292.748058) (xy 320.387613 -292.789973) (xy 320.365374 -292.808152)
			(xy 320.363088 -292.810184) (xy 320.355503 -292.817696) (xy 320.3467 -292.83712) (xy 320.34607 -292.847776)
			(xy 320.34607 -294.429434) (xy 320.34607 -294.429688) (xy 320.346591 -294.440371) (xy 320.355406 -294.459837)
			(xy 320.363088 -294.46728) (xy 320.365374 -294.469312) (xy 320.387611 -294.487496) (xy 320.426886 -294.529411)
			(xy 320.459429 -294.576743) (xy 320.484504 -294.628421) (xy 320.492904 -294.655464) (xy 321.363026 -294.655464)
			(xy 321.370781 -294.601508) (xy 321.386135 -294.549205) (xy 321.408778 -294.49962) (xy 321.438246 -294.453761)
			(xy 321.473941 -294.412564) (xy 321.515135 -294.376866) (xy 321.560991 -294.347393) (xy 321.610574 -294.324747)
			(xy 321.662876 -294.309388) (xy 321.716831 -294.301628) (xy 321.744086 -294.301164) (xy 321.769486 -294.301926)
			(xy 321.784217 -294.302451) (xy 321.812948 -294.295898) (xy 321.838614 -294.281417) (xy 321.859079 -294.260214)
			(xy 321.872642 -294.234052) (xy 321.878174 -294.205107) (xy 321.875215 -294.175788) (xy 321.87007 -294.161972)
			(xy 321.860908 -294.13877) (xy 321.848018 -294.090579) (xy 321.841518 -294.041119) (xy 321.841114 -294.016176)
			(xy 321.841604 -293.988927) (xy 321.849363 -293.934985) (xy 321.86472 -293.882696) (xy 321.887361 -293.833124)
			(xy 321.916827 -293.787279) (xy 321.952517 -293.746094) (xy 321.993705 -293.710407) (xy 322.039553 -293.680946)
			(xy 322.089126 -293.658308) (xy 322.141417 -293.642956) (xy 322.19536 -293.635202) (xy 322.249857 -293.635203)
			(xy 322.3038 -293.64296) (xy 322.35609 -293.658314) (xy 322.405663 -293.680954) (xy 322.451509 -293.710418)
			(xy 322.492695 -293.746106) (xy 322.528383 -293.787293) (xy 322.557847 -293.833139) (xy 322.580487 -293.882712)
			(xy 322.595841 -293.935002) (xy 322.602399 -293.980616) (xy 323.480682 -293.980616) (xy 323.484753 -293.924994)
			(xy 323.496879 -293.870557) (xy 323.516802 -293.818466) (xy 323.544098 -293.769831) (xy 323.578184 -293.725688)
			(xy 323.618333 -293.686979) (xy 323.663691 -293.654528) (xy 323.713291 -293.629027) (xy 323.766075 -293.61102)
			(xy 323.820918 -293.60089) (xy 323.876652 -293.598853) (xy 323.932089 -293.604953) (xy 323.986046 -293.619059)
			(xy 324.037375 -293.640871) (xy 324.084981 -293.669925) (xy 324.127849 -293.7056) (xy 324.165066 -293.747137)
			(xy 324.195839 -293.79365) (xy 324.219511 -293.844147) (xy 324.235579 -293.897554) (xy 324.243699 -293.95273)
			(xy 324.244208 -293.980616) (xy 324.243699 -294.008502) (xy 324.235579 -294.063678) (xy 324.219511 -294.117085)
			(xy 324.195839 -294.167582) (xy 324.165066 -294.214095) (xy 324.127849 -294.255632) (xy 324.084981 -294.291307)
			(xy 324.037375 -294.320361) (xy 323.986046 -294.342173) (xy 323.932089 -294.356279) (xy 323.876652 -294.362379)
			(xy 323.820918 -294.360342) (xy 323.766075 -294.350212) (xy 323.713291 -294.332205) (xy 323.663691 -294.306704)
			(xy 323.618333 -294.274253) (xy 323.578184 -294.235544) (xy 323.544098 -294.191401) (xy 323.516802 -294.142766)
			(xy 323.496879 -294.090675) (xy 323.484753 -294.036238) (xy 323.480682 -293.980616) (xy 322.602399 -293.980616)
			(xy 322.603597 -293.988945) (xy 322.603598 -294.043442) (xy 322.595844 -294.097385) (xy 322.580491 -294.149676)
			(xy 322.557853 -294.199249) (xy 322.528391 -294.245096) (xy 322.492704 -294.286284) (xy 322.451519 -294.321974)
			(xy 322.405674 -294.35144) (xy 322.356103 -294.374081) (xy 322.303813 -294.389438) (xy 322.249871 -294.397196)
			(xy 322.222622 -294.397684) (xy 322.197222 -294.396922) (xy 322.182492 -294.396476) (xy 322.153774 -294.403023)
			(xy 322.128118 -294.417493) (xy 322.107658 -294.438682) (xy 322.094094 -294.464828) (xy 322.088555 -294.493757)
			(xy 322.08934 -294.50157) (xy 322.736462 -294.50157) (xy 322.740533 -294.445948) (xy 322.752659 -294.391511)
			(xy 322.772582 -294.33942) (xy 322.799878 -294.290785) (xy 322.833964 -294.246642) (xy 322.874113 -294.207933)
			(xy 322.919471 -294.175482) (xy 322.969071 -294.149981) (xy 323.021855 -294.131974) (xy 323.076698 -294.121844)
			(xy 323.132432 -294.119807) (xy 323.187869 -294.125907) (xy 323.241826 -294.140013) (xy 323.293155 -294.161825)
			(xy 323.340761 -294.190879) (xy 323.383629 -294.226554) (xy 323.420846 -294.268091) (xy 323.451619 -294.314604)
			(xy 323.475291 -294.365101) (xy 323.491359 -294.418508) (xy 323.499479 -294.473684) (xy 323.499988 -294.50157)
			(xy 323.499479 -294.529456) (xy 323.491359 -294.584632) (xy 323.475291 -294.638039) (xy 323.451619 -294.688536)
			(xy 323.420846 -294.735049) (xy 323.383629 -294.776586) (xy 323.340761 -294.812261) (xy 323.293155 -294.841315)
			(xy 323.241826 -294.863127) (xy 323.187869 -294.877233) (xy 323.132432 -294.883333) (xy 323.076698 -294.881296)
			(xy 323.021855 -294.871166) (xy 322.969071 -294.853159) (xy 322.919471 -294.827658) (xy 322.874113 -294.795207)
			(xy 322.833964 -294.756498) (xy 322.799878 -294.712355) (xy 322.772582 -294.66372) (xy 322.752659 -294.611629)
			(xy 322.740533 -294.557192) (xy 322.736462 -294.50157) (xy 322.08934 -294.50157) (xy 322.091501 -294.523064)
			(xy 322.096638 -294.536876) (xy 322.105784 -294.560084) (xy 322.118681 -294.608272) (xy 322.125186 -294.65773)
			(xy 322.125594 -294.682672) (xy 322.125175 -294.709927) (xy 322.117421 -294.763883) (xy 322.102068 -294.816186)
			(xy 322.079427 -294.865772) (xy 322.04996 -294.911631) (xy 322.014266 -294.952829) (xy 321.973072 -294.988529)
			(xy 321.927217 -295.018002) (xy 321.877634 -295.04065) (xy 321.825333 -295.05601) (xy 321.771378 -295.063771)
			(xy 321.716868 -295.063775) (xy 321.662912 -295.05602) (xy 321.610609 -295.040666) (xy 321.561024 -295.018025)
			(xy 321.515165 -294.988557) (xy 321.473967 -294.952863) (xy 321.438268 -294.911668) (xy 321.408795 -294.865813)
			(xy 321.386149 -294.81623) (xy 321.370789 -294.763929) (xy 321.363028 -294.709974) (xy 321.363026 -294.655464)
			(xy 320.492904 -294.655464) (xy 320.501543 -294.683276) (xy 320.510161 -294.740066) (xy 320.510163 -294.797507)
			(xy 320.501549 -294.854297) (xy 320.484514 -294.909153) (xy 320.459443 -294.960833) (xy 320.426903 -295.008168)
			(xy 320.387631 -295.050086) (xy 320.365374 -295.068244) (xy 320.363088 -295.070276) (xy 320.355501 -295.077788)
			(xy 320.346696 -295.097211) (xy 320.34607 -295.107868) (xy 320.34607 -295.355518) (xy 324.815706 -295.355518)
			(xy 324.819777 -295.299896) (xy 324.831903 -295.245459) (xy 324.851826 -295.193368) (xy 324.879122 -295.144733)
			(xy 324.913208 -295.10059) (xy 324.953357 -295.061881) (xy 324.998715 -295.02943) (xy 325.048315 -295.003929)
			(xy 325.101099 -294.985922) (xy 325.155942 -294.975792) (xy 325.211676 -294.973755) (xy 325.267113 -294.979855)
			(xy 325.32107 -294.993961) (xy 325.372399 -295.015773) (xy 325.420005 -295.044827) (xy 325.462873 -295.080502)
			(xy 325.50009 -295.122039) (xy 325.530863 -295.168552) (xy 325.554535 -295.219049) (xy 325.570603 -295.272456)
			(xy 325.578723 -295.327632) (xy 325.579232 -295.355518) (xy 325.578723 -295.383404) (xy 325.570603 -295.43858)
			(xy 325.554535 -295.491987) (xy 325.530863 -295.542484) (xy 325.50009 -295.588997) (xy 325.462873 -295.630534)
			(xy 325.420005 -295.666209) (xy 325.372399 -295.695263) (xy 325.32107 -295.717075) (xy 325.267113 -295.731181)
			(xy 325.211676 -295.737281) (xy 325.155942 -295.735244) (xy 325.101099 -295.725114) (xy 325.048315 -295.707107)
			(xy 324.998715 -295.681606) (xy 324.953357 -295.649155) (xy 324.913208 -295.610446) (xy 324.879122 -295.566303)
			(xy 324.851826 -295.517668) (xy 324.831903 -295.465577) (xy 324.819777 -295.41114) (xy 324.815706 -295.355518)
			(xy 320.34607 -295.355518) (xy 320.34607 -296.613072) (xy 321.462398 -296.613072) (xy 321.466469 -296.55745)
			(xy 321.478595 -296.503013) (xy 321.498518 -296.450922) (xy 321.525814 -296.402287) (xy 321.5599 -296.358144)
			(xy 321.600049 -296.319435) (xy 321.645407 -296.286984) (xy 321.695007 -296.261483) (xy 321.747791 -296.243476)
			(xy 321.802634 -296.233346) (xy 321.858368 -296.231309) (xy 321.913805 -296.237409) (xy 321.967762 -296.251515)
			(xy 322.019091 -296.273327) (xy 322.066697 -296.302381) (xy 322.109565 -296.338056) (xy 322.146782 -296.379593)
			(xy 322.177555 -296.426106) (xy 322.201227 -296.476603) (xy 322.217295 -296.53001) (xy 322.225415 -296.585186)
			(xy 322.225924 -296.613072) (xy 322.737224 -296.613072) (xy 322.741295 -296.55745) (xy 322.753421 -296.503013)
			(xy 322.773344 -296.450922) (xy 322.80064 -296.402287) (xy 322.834726 -296.358144) (xy 322.874875 -296.319435)
			(xy 322.920233 -296.286984) (xy 322.969833 -296.261483) (xy 323.022617 -296.243476) (xy 323.07746 -296.233346)
			(xy 323.133194 -296.231309) (xy 323.188631 -296.237409) (xy 323.242588 -296.251515) (xy 323.293917 -296.273327)
			(xy 323.341523 -296.302381) (xy 323.384391 -296.338056) (xy 323.421608 -296.379593) (xy 323.452381 -296.426106)
			(xy 323.476053 -296.476603) (xy 323.492121 -296.53001) (xy 323.500241 -296.585186) (xy 323.50075 -296.613072)
			(xy 323.500241 -296.640958) (xy 323.492121 -296.696134) (xy 323.476053 -296.749541) (xy 323.452381 -296.800038)
			(xy 323.421608 -296.846551) (xy 323.384391 -296.888088) (xy 323.341523 -296.923763) (xy 323.293917 -296.952817)
			(xy 323.242588 -296.974629) (xy 323.188631 -296.988735) (xy 323.133194 -296.994835) (xy 323.07746 -296.992798)
			(xy 323.022617 -296.982668) (xy 322.969833 -296.964661) (xy 322.920233 -296.93916) (xy 322.874875 -296.906709)
			(xy 322.834726 -296.868) (xy 322.80064 -296.823857) (xy 322.773344 -296.775222) (xy 322.753421 -296.723131)
			(xy 322.741295 -296.668694) (xy 322.737224 -296.613072) (xy 322.225924 -296.613072) (xy 322.225415 -296.640958)
			(xy 322.217295 -296.696134) (xy 322.201227 -296.749541) (xy 322.177555 -296.800038) (xy 322.146782 -296.846551)
			(xy 322.109565 -296.888088) (xy 322.066697 -296.923763) (xy 322.019091 -296.952817) (xy 321.967762 -296.974629)
			(xy 321.913805 -296.988735) (xy 321.858368 -296.994835) (xy 321.802634 -296.992798) (xy 321.747791 -296.982668)
			(xy 321.695007 -296.964661) (xy 321.645407 -296.93916) (xy 321.600049 -296.906709) (xy 321.5599 -296.868)
			(xy 321.525814 -296.823857) (xy 321.498518 -296.775222) (xy 321.478595 -296.723131) (xy 321.466469 -296.668694)
			(xy 321.462398 -296.613072) (xy 320.34607 -296.613072) (xy 320.34607 -299.314616) (xy 320.34669 -299.327033)
			(xy 320.358271 -299.349001) (xy 320.368168 -299.356526) (xy 320.43751 -299.40377) (xy 320.442692 -299.407139)
			(xy 320.454255 -299.411498) (xy 320.46037 -299.412406) (xy 320.472816 -299.413676) (xy 320.484754 -299.409104)
			(xy 320.485008 -299.409104) (xy 320.507179 -299.400814) (xy 320.553056 -299.389164) (xy 320.600025 -299.383292)
			(xy 320.623692 -299.382942) (xy 320.62801 -299.382942) (xy 320.655059 -299.38372) (xy 320.708538 -299.391971)
			(xy 320.760315 -299.407697) (xy 320.809349 -299.430581) (xy 320.854658 -299.460165) (xy 320.895332 -299.495855)
			(xy 320.930555 -299.536934) (xy 320.959619 -299.582578) (xy 320.981941 -299.631871) (xy 320.997074 -299.683824)
			(xy 321.004713 -299.737394) (xy 321.0052 -299.76445) (xy 321.004943 -299.77969) (xy 324.838312 -299.77969)
			(xy 324.842383 -299.724068) (xy 324.854509 -299.669631) (xy 324.874432 -299.61754) (xy 324.901728 -299.568905)
			(xy 324.935814 -299.524762) (xy 324.975963 -299.486053) (xy 325.021321 -299.453602) (xy 325.070921 -299.428101)
			(xy 325.123705 -299.410094) (xy 325.178548 -299.399964) (xy 325.234282 -299.397927) (xy 325.289719 -299.404027)
			(xy 325.343676 -299.418133) (xy 325.395005 -299.439945) (xy 325.442611 -299.468999) (xy 325.485479 -299.504674)
			(xy 325.522696 -299.546211) (xy 325.553469 -299.592724) (xy 325.577141 -299.643221) (xy 325.593209 -299.696628)
			(xy 325.601329 -299.751804) (xy 325.601838 -299.77969) (xy 325.601329 -299.807576) (xy 325.593209 -299.862752)
			(xy 325.577141 -299.916159) (xy 325.553469 -299.966656) (xy 325.522696 -300.013169) (xy 325.485479 -300.054706)
			(xy 325.442611 -300.090381) (xy 325.395005 -300.119435) (xy 325.343676 -300.141247) (xy 325.289719 -300.155353)
			(xy 325.234282 -300.161453) (xy 325.178548 -300.159416) (xy 325.123705 -300.149286) (xy 325.070921 -300.131279)
			(xy 325.021321 -300.105778) (xy 324.975963 -300.073327) (xy 324.935814 -300.034618) (xy 324.901728 -299.990475)
			(xy 324.874432 -299.94184) (xy 324.854509 -299.889749) (xy 324.842383 -299.835312) (xy 324.838312 -299.77969)
			(xy 321.004943 -299.77969) (xy 321.00474 -299.791705) (xy 320.996989 -299.845661) (xy 320.981637 -299.897964)
			(xy 320.958997 -299.94755) (xy 320.929531 -299.993409) (xy 320.893837 -300.034607) (xy 320.852643 -300.070305)
			(xy 320.806787 -300.099777) (xy 320.757204 -300.122422) (xy 320.704902 -300.13778) (xy 320.650947 -300.145537)
			(xy 320.623692 -300.145958) (xy 320.600026 -300.145585) (xy 320.553061 -300.139706) (xy 320.50718 -300.128077)
			(xy 320.485008 -300.119796) (xy 320.484754 -300.119796) (xy 320.484246 -300.119542) (xy 320.478557 -300.117581)
			(xy 320.466625 -300.116042) (xy 320.460624 -300.116494) (xy 320.447924 -300.118018) (xy 320.368168 -300.172374)
			(xy 320.358274 -300.179901) (xy 320.346693 -300.201868) (xy 320.34607 -300.214284) (xy 320.34607 -301.04207)
			(xy 322.517006 -301.04207) (xy 322.521077 -300.986448) (xy 322.533203 -300.932011) (xy 322.553126 -300.87992)
			(xy 322.580422 -300.831285) (xy 322.614508 -300.787142) (xy 322.654657 -300.748433) (xy 322.700015 -300.715982)
			(xy 322.749615 -300.690481) (xy 322.802399 -300.672474) (xy 322.857242 -300.662344) (xy 322.912976 -300.660307)
			(xy 322.968413 -300.666407) (xy 323.02237 -300.680513) (xy 323.073699 -300.702325) (xy 323.121305 -300.731379)
			(xy 323.164173 -300.767054) (xy 323.20139 -300.808591) (xy 323.232163 -300.855104) (xy 323.255835 -300.905601)
			(xy 323.271903 -300.959008) (xy 323.280023 -301.014184) (xy 323.280532 -301.04207) (xy 323.280379 -301.050452)
			(xy 324.89089 -301.050452) (xy 324.894961 -300.99483) (xy 324.907087 -300.940393) (xy 324.92701 -300.888302)
			(xy 324.954306 -300.839667) (xy 324.988392 -300.795524) (xy 325.028541 -300.756815) (xy 325.073899 -300.724364)
			(xy 325.123499 -300.698863) (xy 325.176283 -300.680856) (xy 325.231126 -300.670726) (xy 325.28686 -300.668689)
			(xy 325.342297 -300.674789) (xy 325.396254 -300.688895) (xy 325.447583 -300.710707) (xy 325.495189 -300.739761)
			(xy 325.538057 -300.775436) (xy 325.575274 -300.816973) (xy 325.606047 -300.863486) (xy 325.629719 -300.913983)
			(xy 325.645787 -300.96739) (xy 325.653907 -301.022566) (xy 325.654416 -301.050452) (xy 325.653907 -301.078338)
			(xy 325.645787 -301.133514) (xy 325.629719 -301.186921) (xy 325.606047 -301.237418) (xy 325.575274 -301.283931)
			(xy 325.538057 -301.325468) (xy 325.495189 -301.361143) (xy 325.447583 -301.390197) (xy 325.396254 -301.412009)
			(xy 325.342297 -301.426115) (xy 325.28686 -301.432215) (xy 325.231126 -301.430178) (xy 325.176283 -301.420048)
			(xy 325.123499 -301.402041) (xy 325.073899 -301.37654) (xy 325.028541 -301.344089) (xy 324.988392 -301.30538)
			(xy 324.954306 -301.261237) (xy 324.92701 -301.212602) (xy 324.907087 -301.160511) (xy 324.894961 -301.106074)
			(xy 324.89089 -301.050452) (xy 323.280379 -301.050452) (xy 323.280023 -301.069956) (xy 323.271903 -301.125132)
			(xy 323.255835 -301.178539) (xy 323.232163 -301.229036) (xy 323.20139 -301.275549) (xy 323.164173 -301.317086)
			(xy 323.121305 -301.352761) (xy 323.073699 -301.381815) (xy 323.02237 -301.403627) (xy 322.968413 -301.417733)
			(xy 322.912976 -301.423833) (xy 322.857242 -301.421796) (xy 322.802399 -301.411666) (xy 322.749615 -301.393659)
			(xy 322.700015 -301.368158) (xy 322.654657 -301.335707) (xy 322.614508 -301.296998) (xy 322.580422 -301.252855)
			(xy 322.553126 -301.20422) (xy 322.533203 -301.152129) (xy 322.521077 -301.097692) (xy 322.517006 -301.04207)
			(xy 320.34607 -301.04207) (xy 320.34607 -301.141638) (xy 320.346374 -301.15067) (xy 320.352551 -301.167641)
			(xy 320.364258 -301.181393) (xy 320.371978 -301.186088) (xy 320.372232 -301.186088) (xy 320.461894 -301.235872)
			(xy 320.489326 -301.235364) (xy 320.501264 -301.227998) (xy 320.523923 -301.21453) (xy 320.572158 -301.193273)
			(xy 320.622858 -301.178855) (xy 320.675061 -301.171549) (xy 320.701416 -301.171102) (xy 320.70802 -301.171102)
			(xy 320.73626 -301.172081) (xy 320.792002 -301.181339) (xy 320.845769 -301.198717) (xy 320.896385 -301.223834)
			(xy 320.942743 -301.256142) (xy 320.98383 -301.294933) (xy 321.018746 -301.33936) (xy 321.046728 -301.388451)
			(xy 321.067164 -301.441131) (xy 321.079607 -301.496249) (xy 321.083785 -301.5526) (xy 321.083464 -301.556928)
			(xy 323.713092 -301.556928) (xy 323.717163 -301.501306) (xy 323.729289 -301.446869) (xy 323.749212 -301.394778)
			(xy 323.776508 -301.346143) (xy 323.810594 -301.302) (xy 323.850743 -301.263291) (xy 323.896101 -301.23084)
			(xy 323.945701 -301.205339) (xy 323.998485 -301.187332) (xy 324.053328 -301.177202) (xy 324.109062 -301.175165)
			(xy 324.164499 -301.181265) (xy 324.218456 -301.195371) (xy 324.269785 -301.217183) (xy 324.317391 -301.246237)
			(xy 324.360259 -301.281912) (xy 324.397476 -301.323449) (xy 324.428249 -301.369962) (xy 324.451921 -301.420459)
			(xy 324.467989 -301.473866) (xy 324.476109 -301.529042) (xy 324.476618 -301.556928) (xy 324.476109 -301.584814)
			(xy 324.467989 -301.63999) (xy 324.451921 -301.693397) (xy 324.428249 -301.743894) (xy 324.397476 -301.790407)
			(xy 324.360259 -301.831944) (xy 324.317391 -301.867619) (xy 324.269785 -301.896673) (xy 324.218456 -301.918485)
			(xy 324.164499 -301.932591) (xy 324.109062 -301.938691) (xy 324.053328 -301.936654) (xy 323.998485 -301.926524)
			(xy 323.945701 -301.908517) (xy 323.896101 -301.883016) (xy 323.850743 -301.850565) (xy 323.810594 -301.811856)
			(xy 323.776508 -301.767713) (xy 323.749212 -301.719078) (xy 323.729289 -301.666987) (xy 323.717163 -301.61255)
			(xy 323.713092 -301.556928) (xy 321.083464 -301.556928) (xy 321.079607 -301.608951) (xy 321.067164 -301.664069)
			(xy 321.046728 -301.71675) (xy 321.018746 -301.76584) (xy 320.983829 -301.810267) (xy 320.942743 -301.849058)
			(xy 320.896385 -301.881366) (xy 320.845769 -301.906483) (xy 320.792002 -301.923861) (xy 320.73626 -301.933119)
			(xy 320.70802 -301.934118) (xy 320.701416 -301.934118) (xy 320.67506 -301.93366) (xy 320.622853 -301.926374)
			(xy 320.572148 -301.911967) (xy 320.52391 -301.890713) (xy 320.501264 -301.877222) (xy 320.489326 -301.869856)
			(xy 320.461894 -301.869348) (xy 320.372232 -301.919132) (xy 320.364496 -301.923836) (xy 320.352708 -301.937563)
			(xy 320.346437 -301.954535) (xy 320.34607 -301.963582) (xy 320.34607 -302.150272) (xy 320.36385 -302.17618)
			(xy 320.378836 -302.181768) (xy 320.405575 -302.192496) (xy 320.455736 -302.220835) (xy 320.501065 -302.256395)
			(xy 320.54053 -302.298368) (xy 320.573234 -302.345798) (xy 320.598433 -302.397608) (xy 320.615553 -302.452618)
			(xy 320.624205 -302.509578) (xy 320.624708 -302.538384) (xy 320.624134 -302.567473) (xy 320.615256 -302.62497)
			(xy 320.597766 -302.680457) (xy 320.572065 -302.732651) (xy 320.555874 -302.756824) (xy 320.545206 -302.772064)
			(xy 320.548508 -302.80864) (xy 320.675 -302.935132) (xy 320.681246 -302.940967) (xy 320.696609 -302.948434)
			(xy 320.71358 -302.950382) (xy 320.72199 -302.948848) (xy 320.818764 -302.927258) (xy 320.838068 -302.91024)
			(xy 320.84264 -302.897794) (xy 320.853014 -302.870452) (xy 320.880937 -302.819071) (xy 320.916379 -302.772557)
			(xy 320.958511 -302.732003) (xy 321.006342 -302.69836) (xy 321.058751 -302.672417) (xy 321.114507 -302.654783)
			(xy 321.172303 -302.645873) (xy 321.201542 -302.645318) (xy 321.228791 -302.645807) (xy 321.282732 -302.653569)
			(xy 321.33502 -302.668928) (xy 321.384591 -302.691572) (xy 321.430434 -302.721039) (xy 321.471617 -302.756731)
			(xy 321.507301 -302.797921) (xy 321.536761 -302.843769) (xy 321.559396 -302.893343) (xy 321.574746 -302.945634)
			(xy 321.582498 -302.999577) (xy 321.58305 -303.026826) (xy 321.835524 -303.026826) (xy 321.839595 -302.971204)
			(xy 321.851721 -302.916767) (xy 321.871644 -302.864676) (xy 321.89894 -302.816041) (xy 321.933026 -302.771898)
			(xy 321.973175 -302.733189) (xy 322.018533 -302.700738) (xy 322.068133 -302.675237) (xy 322.120917 -302.65723)
			(xy 322.17576 -302.6471) (xy 322.231494 -302.645063) (xy 322.286931 -302.651163) (xy 322.340888 -302.665269)
			(xy 322.392217 -302.687081) (xy 322.439823 -302.716135) (xy 322.482691 -302.75181) (xy 322.519908 -302.793347)
			(xy 322.550681 -302.83986) (xy 322.574353 -302.890357) (xy 322.590421 -302.943764) (xy 322.598541 -302.99894)
			(xy 322.59905 -303.026826) (xy 322.851524 -303.026826) (xy 322.855595 -302.971204) (xy 322.867721 -302.916767)
			(xy 322.887644 -302.864676) (xy 322.91494 -302.816041) (xy 322.949026 -302.771898) (xy 322.989175 -302.733189)
			(xy 323.034533 -302.700738) (xy 323.084133 -302.675237) (xy 323.136917 -302.65723) (xy 323.19176 -302.6471)
			(xy 323.247494 -302.645063) (xy 323.302931 -302.651163) (xy 323.356888 -302.665269) (xy 323.408217 -302.687081)
			(xy 323.455823 -302.716135) (xy 323.498691 -302.75181) (xy 323.535908 -302.793347) (xy 323.566681 -302.83986)
			(xy 323.590353 -302.890357) (xy 323.606421 -302.943764) (xy 323.614541 -302.99894) (xy 323.61505 -303.026826)
			(xy 323.867524 -303.026826) (xy 323.871595 -302.971204) (xy 323.883721 -302.916767) (xy 323.903644 -302.864676)
			(xy 323.93094 -302.816041) (xy 323.965026 -302.771898) (xy 324.005175 -302.733189) (xy 324.050533 -302.700738)
			(xy 324.100133 -302.675237) (xy 324.152917 -302.65723) (xy 324.20776 -302.6471) (xy 324.263494 -302.645063)
			(xy 324.318931 -302.651163) (xy 324.372888 -302.665269) (xy 324.424217 -302.687081) (xy 324.471823 -302.716135)
			(xy 324.514691 -302.75181) (xy 324.551908 -302.793347) (xy 324.582681 -302.83986) (xy 324.606353 -302.890357)
			(xy 324.622421 -302.943764) (xy 324.630541 -302.99894) (xy 324.63105 -303.026826) (xy 324.883524 -303.026826)
			(xy 324.887595 -302.971204) (xy 324.899721 -302.916767) (xy 324.919644 -302.864676) (xy 324.94694 -302.816041)
			(xy 324.981026 -302.771898) (xy 325.021175 -302.733189) (xy 325.066533 -302.700738) (xy 325.116133 -302.675237)
			(xy 325.168917 -302.65723) (xy 325.22376 -302.6471) (xy 325.279494 -302.645063) (xy 325.334931 -302.651163)
			(xy 325.388888 -302.665269) (xy 325.440217 -302.687081) (xy 325.487823 -302.716135) (xy 325.530691 -302.75181)
			(xy 325.567908 -302.793347) (xy 325.598681 -302.83986) (xy 325.622353 -302.890357) (xy 325.638421 -302.943764)
			(xy 325.646541 -302.99894) (xy 325.64705 -303.026826) (xy 325.646541 -303.054712) (xy 325.638421 -303.109888)
			(xy 325.622353 -303.163295) (xy 325.598681 -303.213792) (xy 325.567908 -303.260305) (xy 325.530691 -303.301842)
			(xy 325.487823 -303.337517) (xy 325.440217 -303.366571) (xy 325.388888 -303.388383) (xy 325.334931 -303.402489)
			(xy 325.279494 -303.408589) (xy 325.22376 -303.406552) (xy 325.168917 -303.396422) (xy 325.116133 -303.378415)
			(xy 325.066533 -303.352914) (xy 325.021175 -303.320463) (xy 324.981026 -303.281754) (xy 324.94694 -303.237611)
			(xy 324.919644 -303.188976) (xy 324.899721 -303.136885) (xy 324.887595 -303.082448) (xy 324.883524 -303.026826)
			(xy 324.63105 -303.026826) (xy 324.630541 -303.054712) (xy 324.622421 -303.109888) (xy 324.606353 -303.163295)
			(xy 324.582681 -303.213792) (xy 324.551908 -303.260305) (xy 324.514691 -303.301842) (xy 324.471823 -303.337517)
			(xy 324.424217 -303.366571) (xy 324.372888 -303.388383) (xy 324.318931 -303.402489) (xy 324.263494 -303.408589)
			(xy 324.20776 -303.406552) (xy 324.152917 -303.396422) (xy 324.100133 -303.378415) (xy 324.050533 -303.352914)
			(xy 324.005175 -303.320463) (xy 323.965026 -303.281754) (xy 323.93094 -303.237611) (xy 323.903644 -303.188976)
			(xy 323.883721 -303.136885) (xy 323.871595 -303.082448) (xy 323.867524 -303.026826) (xy 323.61505 -303.026826)
			(xy 323.614541 -303.054712) (xy 323.606421 -303.109888) (xy 323.590353 -303.163295) (xy 323.566681 -303.213792)
			(xy 323.535908 -303.260305) (xy 323.498691 -303.301842) (xy 323.455823 -303.337517) (xy 323.408217 -303.366571)
			(xy 323.356888 -303.388383) (xy 323.302931 -303.402489) (xy 323.247494 -303.408589) (xy 323.19176 -303.406552)
			(xy 323.136917 -303.396422) (xy 323.084133 -303.378415) (xy 323.034533 -303.352914) (xy 322.989175 -303.320463)
			(xy 322.949026 -303.281754) (xy 322.91494 -303.237611) (xy 322.887644 -303.188976) (xy 322.867721 -303.136885)
			(xy 322.855595 -303.082448) (xy 322.851524 -303.026826) (xy 322.59905 -303.026826) (xy 322.598541 -303.054712)
			(xy 322.590421 -303.109888) (xy 322.574353 -303.163295) (xy 322.550681 -303.213792) (xy 322.519908 -303.260305)
			(xy 322.482691 -303.301842) (xy 322.439823 -303.337517) (xy 322.392217 -303.366571) (xy 322.340888 -303.388383)
			(xy 322.286931 -303.402489) (xy 322.231494 -303.408589) (xy 322.17576 -303.406552) (xy 322.120917 -303.396422)
			(xy 322.068133 -303.378415) (xy 322.018533 -303.352914) (xy 321.973175 -303.320463) (xy 321.933026 -303.281754)
			(xy 321.89894 -303.237611) (xy 321.871644 -303.188976) (xy 321.851721 -303.136885) (xy 321.839595 -303.082448)
			(xy 321.835524 -303.026826) (xy 321.58305 -303.026826) (xy 321.582517 -303.056064) (xy 321.573586 -303.113853)
			(xy 321.555939 -303.169602) (xy 321.529988 -303.222004) (xy 321.496342 -303.26983) (xy 321.45579 -303.31196)
			(xy 321.409282 -303.347405) (xy 321.357908 -303.375335) (xy 321.330574 -303.385728) (xy 321.318128 -303.3903)
			(xy 321.30111 -303.409604) (xy 321.27952 -303.506378) (xy 321.278008 -303.514783) (xy 321.280008 -303.531734)
			(xy 321.287433 -303.547103) (xy 321.293236 -303.553368) (xy 322.702936 -304.963068) (xy 322.712388 -304.971499)
			(xy 322.736641 -304.978688) (xy 322.749164 -304.976784) (xy 322.84543 -304.956464) (xy 322.864734 -304.939954)
			(xy 322.869306 -304.927762) (xy 322.880125 -304.901169) (xy 322.908583 -304.85131) (xy 322.944183 -304.806271)
			(xy 322.986123 -304.767068) (xy 323.033458 -304.734584) (xy 323.085122 -304.709551) (xy 323.139951 -304.692532)
			(xy 323.19671 -304.683912) (xy 323.225414 -304.683414) (xy 323.252666 -304.683878) (xy 323.306614 -304.691637)
			(xy 323.358909 -304.706994) (xy 323.408486 -304.729638) (xy 323.454336 -304.759107) (xy 323.495525 -304.794801)
			(xy 323.531215 -304.835993) (xy 323.560679 -304.881846) (xy 323.583318 -304.931425) (xy 323.598671 -304.983721)
			(xy 323.606424 -305.03767) (xy 323.606903 -305.063906) (xy 323.868032 -305.063906) (xy 323.872103 -305.008284)
			(xy 323.884229 -304.953847) (xy 323.904152 -304.901756) (xy 323.931448 -304.853121) (xy 323.965534 -304.808978)
			(xy 324.005683 -304.770269) (xy 324.051041 -304.737818) (xy 324.100641 -304.712317) (xy 324.153425 -304.69431)
			(xy 324.208268 -304.68418) (xy 324.264002 -304.682143) (xy 324.319439 -304.688243) (xy 324.373396 -304.702349)
			(xy 324.424725 -304.724161) (xy 324.472331 -304.753215) (xy 324.515199 -304.78889) (xy 324.552416 -304.830427)
			(xy 324.583189 -304.87694) (xy 324.606861 -304.927437) (xy 324.622929 -304.980844) (xy 324.631049 -305.03602)
			(xy 324.631233 -305.046126) (xy 324.884032 -305.046126) (xy 324.888103 -304.990504) (xy 324.900229 -304.936067)
			(xy 324.920152 -304.883976) (xy 324.947448 -304.835341) (xy 324.981534 -304.791198) (xy 325.021683 -304.752489)
			(xy 325.067041 -304.720038) (xy 325.116641 -304.694537) (xy 325.169425 -304.67653) (xy 325.224268 -304.6664)
			(xy 325.280002 -304.664363) (xy 325.335439 -304.670463) (xy 325.389396 -304.684569) (xy 325.440725 -304.706381)
			(xy 325.488331 -304.735435) (xy 325.531199 -304.77111) (xy 325.568416 -304.812647) (xy 325.599189 -304.85916)
			(xy 325.622861 -304.909657) (xy 325.638929 -304.963064) (xy 325.647049 -305.01824) (xy 325.647558 -305.046126)
			(xy 325.647049 -305.074012) (xy 325.638929 -305.129188) (xy 325.622861 -305.182595) (xy 325.599189 -305.233092)
			(xy 325.568416 -305.279605) (xy 325.531199 -305.321142) (xy 325.488331 -305.356817) (xy 325.440725 -305.385871)
			(xy 325.389396 -305.407683) (xy 325.335439 -305.421789) (xy 325.280002 -305.427889) (xy 325.224268 -305.425852)
			(xy 325.169425 -305.415722) (xy 325.116641 -305.397715) (xy 325.067041 -305.372214) (xy 325.021683 -305.339763)
			(xy 324.981534 -305.301054) (xy 324.947448 -305.256911) (xy 324.920152 -305.208276) (xy 324.900229 -305.156185)
			(xy 324.888103 -305.101748) (xy 324.884032 -305.046126) (xy 324.631233 -305.046126) (xy 324.631558 -305.063906)
			(xy 324.631049 -305.091792) (xy 324.622929 -305.146968) (xy 324.606861 -305.200375) (xy 324.583189 -305.250872)
			(xy 324.552416 -305.297385) (xy 324.515199 -305.338922) (xy 324.472331 -305.374597) (xy 324.424725 -305.403651)
			(xy 324.373396 -305.425463) (xy 324.319439 -305.439569) (xy 324.264002 -305.445669) (xy 324.208268 -305.443632)
			(xy 324.153425 -305.433502) (xy 324.100641 -305.415495) (xy 324.051041 -305.389994) (xy 324.005683 -305.357543)
			(xy 323.965534 -305.318834) (xy 323.931448 -305.274691) (xy 323.904152 -305.226056) (xy 323.884229 -305.173965)
			(xy 323.872103 -305.119528) (xy 323.868032 -305.063906) (xy 323.606903 -305.063906) (xy 323.606922 -305.064922)
			(xy 323.60641 -305.09363) (xy 323.59782 -305.150401) (xy 323.580822 -305.205244) (xy 323.5558 -305.256921)
			(xy 323.523319 -305.304267) (xy 323.484112 -305.346213) (xy 323.439063 -305.381812) (xy 323.38919 -305.41026)
			(xy 323.362574 -305.42103) (xy 323.350382 -305.425602) (xy 323.333872 -305.444906) (xy 323.313552 -305.541172)
			(xy 323.311616 -305.553696) (xy 323.318811 -305.577962) (xy 323.327268 -305.5874) (xy 325.230236 -307.490368)
			(xy 325.230744 -307.490876) (xy 325.238126 -307.497457) (xy 325.256425 -307.504907) (xy 325.266304 -307.505354)
		)
		(stroke
			(width 0)
			(type solid)
		)
		(fill yes)
		(layer "In11.Cu")
		(net "P1V8_PEX")
	)
	(gr_poly
		(pts
			(xy 36.924488 -298.294552) (xy 36.933929 -298.294054) (xy 36.951506 -298.287135) (xy 36.958778 -298.28109)
			(xy 36.980876 -298.26077) (xy 36.987183 -298.254597) (xy 36.995394 -298.238988) (xy 36.996878 -298.23029)
			(xy 37.000937 -298.204205) (xy 37.016253 -298.153689) (xy 37.039401 -298.106248) (xy 37.069792 -298.063087)
			(xy 37.106654 -298.025302) (xy 37.149051 -297.993854) (xy 37.195905 -297.969541) (xy 37.246028 -297.952981)
			(xy 37.298144 -297.944594) (xy 37.350932 -297.944594) (xy 37.403048 -297.952981) (xy 37.453171 -297.969541)
			(xy 37.500025 -297.993854) (xy 37.542422 -298.025302) (xy 37.579284 -298.063087) (xy 37.609675 -298.106248)
			(xy 37.632823 -298.153689) (xy 37.648139 -298.204205) (xy 37.652198 -298.23029) (xy 37.653809 -298.238946)
			(xy 37.662001 -298.254516) (xy 37.6682 -298.26077) (xy 37.690298 -298.28109) (xy 37.6975 -298.287247)
			(xy 37.715121 -298.294176) (xy 37.724588 -298.294552) (xy 37.874702 -298.294552) (xy 37.88415 -298.294069)
			(xy 37.901747 -298.287172) (xy 37.908992 -298.28109) (xy 37.93109 -298.26077) (xy 37.937395 -298.254596)
			(xy 37.945604 -298.238987) (xy 37.947092 -298.23029) (xy 37.951151 -298.204205) (xy 37.966467 -298.153689)
			(xy 37.989615 -298.106248) (xy 38.020006 -298.063087) (xy 38.056868 -298.025302) (xy 38.099265 -297.993854)
			(xy 38.146119 -297.969541) (xy 38.196242 -297.952981) (xy 38.248358 -297.944594) (xy 38.301146 -297.944594)
			(xy 38.353262 -297.952981) (xy 38.403385 -297.969541) (xy 38.450239 -297.993854) (xy 38.492636 -298.025302)
			(xy 38.529498 -298.063087) (xy 38.559889 -298.106248) (xy 38.583037 -298.153689) (xy 38.598353 -298.204205)
			(xy 38.602412 -298.23029) (xy 38.604023 -298.238945) (xy 38.612217 -298.254514) (xy 38.618414 -298.26077)
			(xy 38.640512 -298.28109) (xy 38.647715 -298.287245) (xy 38.665336 -298.294169) (xy 38.674802 -298.294552)
			(xy 38.824916 -298.294552) (xy 38.834363 -298.294067) (xy 38.851957 -298.287166) (xy 38.859206 -298.28109)
			(xy 38.881304 -298.26077) (xy 38.887608 -298.254596) (xy 38.895814 -298.238986) (xy 38.897306 -298.23029)
			(xy 38.901365 -298.204205) (xy 38.916681 -298.153689) (xy 38.939829 -298.106248) (xy 38.97022 -298.063087)
			(xy 39.007082 -298.025302) (xy 39.049479 -297.993854) (xy 39.096333 -297.969541) (xy 39.146456 -297.952981)
			(xy 39.198572 -297.944594) (xy 39.25136 -297.944594) (xy 39.303476 -297.952981) (xy 39.353599 -297.969541)
			(xy 39.400453 -297.993854) (xy 39.44285 -298.025302) (xy 39.479712 -298.063087) (xy 39.510103 -298.106248)
			(xy 39.533251 -298.153689) (xy 39.548567 -298.204205) (xy 39.552626 -298.23029) (xy 39.554234 -298.238948)
			(xy 39.562418 -298.254526) (xy 39.568628 -298.26077) (xy 39.590726 -298.28109) (xy 39.59793 -298.287243)
			(xy 39.615551 -298.294162) (xy 39.625016 -298.294552) (xy 39.774876 -298.294552) (xy 39.784318 -298.294056)
			(xy 39.801898 -298.28714) (xy 39.809166 -298.28109) (xy 39.831264 -298.26077) (xy 39.837572 -298.254598)
			(xy 39.845785 -298.238989) (xy 39.847266 -298.23029) (xy 39.851325 -298.204205) (xy 39.866641 -298.153689)
			(xy 39.889789 -298.106248) (xy 39.92018 -298.063087) (xy 39.957042 -298.025302) (xy 39.999439 -297.993854)
			(xy 40.046293 -297.969541) (xy 40.096416 -297.952981) (xy 40.148532 -297.944594) (xy 40.20132 -297.944594)
			(xy 40.253436 -297.952981) (xy 40.303559 -297.969541) (xy 40.350413 -297.993854) (xy 40.39281 -298.025302)
			(xy 40.429672 -298.063087) (xy 40.460063 -298.106248) (xy 40.483211 -298.153689) (xy 40.498527 -298.204205)
			(xy 40.502586 -298.23029) (xy 40.504196 -298.238946) (xy 40.512387 -298.254518) (xy 40.518588 -298.26077)
			(xy 40.540686 -298.28109) (xy 40.547888 -298.287249) (xy 40.565508 -298.294182) (xy 40.574976 -298.294552)
			(xy 40.724836 -298.294552) (xy 40.734281 -298.294063) (xy 40.75187 -298.287157) (xy 40.759126 -298.28109)
			(xy 40.781224 -298.26077) (xy 40.787526 -298.254594) (xy 40.795729 -298.238985) (xy 40.797226 -298.23029)
			(xy 40.801285 -298.204205) (xy 40.816601 -298.153689) (xy 40.839749 -298.106248) (xy 40.87014 -298.063087)
			(xy 40.907002 -298.025302) (xy 40.949399 -297.993854) (xy 40.996253 -297.969541) (xy 41.046376 -297.952981)
			(xy 41.098492 -297.944594) (xy 41.15128 -297.944594) (xy 41.203396 -297.952981) (xy 41.253519 -297.969541)
			(xy 41.300373 -297.993854) (xy 41.34277 -298.025302) (xy 41.379632 -298.063087) (xy 41.410023 -298.106248)
			(xy 41.433171 -298.153689) (xy 41.448487 -298.204205) (xy 41.452546 -298.23029) (xy 41.454155 -298.238947)
			(xy 41.462341 -298.254523) (xy 41.468548 -298.26077) (xy 41.490646 -298.28109) (xy 41.497851 -298.28724)
			(xy 41.515472 -298.294152) (xy 41.524936 -298.294552) (xy 41.674796 -298.294552) (xy 41.684237 -298.294053)
			(xy 41.701812 -298.287132) (xy 41.709086 -298.28109) (xy 41.731184 -298.26077) (xy 41.73749 -298.254597)
			(xy 41.7457 -298.238988) (xy 41.747186 -298.23029) (xy 41.751245 -298.204205) (xy 41.766561 -298.153689)
			(xy 41.789709 -298.106248) (xy 41.8201 -298.063087) (xy 41.856962 -298.025302) (xy 41.899359 -297.993854)
			(xy 41.946213 -297.969541) (xy 41.996336 -297.952981) (xy 42.048452 -297.944594) (xy 42.10124 -297.944594)
			(xy 42.153356 -297.952981) (xy 42.203479 -297.969541) (xy 42.250333 -297.993854) (xy 42.29273 -298.025302)
			(xy 42.329592 -298.063087) (xy 42.359983 -298.106248) (xy 42.383131 -298.153689) (xy 42.398447 -298.204205)
			(xy 42.402506 -298.23029) (xy 42.404117 -298.238945) (xy 42.41231 -298.254515) (xy 42.418508 -298.26077)
			(xy 42.440606 -298.28109) (xy 42.447809 -298.287246) (xy 42.465429 -298.294172) (xy 42.474896 -298.294552)
			(xy 43.574716 -298.294552) (xy 43.584163 -298.294067) (xy 43.601757 -298.287166) (xy 43.609006 -298.28109)
			(xy 43.631104 -298.26077) (xy 43.637408 -298.254596) (xy 43.645614 -298.238986) (xy 43.647106 -298.23029)
			(xy 43.651165 -298.204205) (xy 43.666481 -298.153689) (xy 43.689629 -298.106248) (xy 43.72002 -298.063087)
			(xy 43.756882 -298.025302) (xy 43.799279 -297.993854) (xy 43.846133 -297.969541) (xy 43.896256 -297.952981)
			(xy 43.948372 -297.944594) (xy 44.00116 -297.944594) (xy 44.053276 -297.952981) (xy 44.103399 -297.969541)
			(xy 44.150253 -297.993854) (xy 44.19265 -298.025302) (xy 44.229512 -298.063087) (xy 44.259903 -298.106248)
			(xy 44.283051 -298.153689) (xy 44.298367 -298.204205) (xy 44.302426 -298.23029) (xy 44.304034 -298.238948)
			(xy 44.312218 -298.254526) (xy 44.318428 -298.26077) (xy 44.340526 -298.28109) (xy 44.34773 -298.287243)
			(xy 44.365351 -298.294162) (xy 44.374816 -298.294552) (xy 44.52493 -298.294552) (xy 44.534376 -298.294064)
			(xy 44.551966 -298.28716) (xy 44.55922 -298.28109) (xy 44.581318 -298.26077) (xy 44.58762 -298.254595)
			(xy 44.595825 -298.238985) (xy 44.59732 -298.23029) (xy 44.601379 -298.204205) (xy 44.616695 -298.153689)
			(xy 44.639843 -298.106248) (xy 44.670234 -298.063087) (xy 44.707096 -298.025302) (xy 44.749493 -297.993854)
			(xy 44.796347 -297.969541) (xy 44.84647 -297.952981) (xy 44.898586 -297.944594) (xy 44.951374 -297.944594)
			(xy 45.00349 -297.952981) (xy 45.053613 -297.969541) (xy 45.100467 -297.993854) (xy 45.142864 -298.025302)
			(xy 45.179726 -298.063087) (xy 45.210117 -298.106248) (xy 45.233265 -298.153689) (xy 45.248581 -298.204205)
			(xy 45.25264 -298.23029) (xy 45.254249 -298.238947) (xy 45.262434 -298.254524) (xy 45.268642 -298.26077)
			(xy 45.29074 -298.28109) (xy 45.297944 -298.287241) (xy 45.315565 -298.294155) (xy 45.32503 -298.294552)
			(xy 45.47489 -298.294552) (xy 45.484331 -298.294054) (xy 45.501908 -298.287134) (xy 45.50918 -298.28109)
			(xy 45.531278 -298.26077) (xy 45.537585 -298.254597) (xy 45.545795 -298.238988) (xy 45.54728 -298.23029)
			(xy 45.551339 -298.204205) (xy 45.566655 -298.153689) (xy 45.589803 -298.106248) (xy 45.620194 -298.063087)
			(xy 45.657056 -298.025302) (xy 45.699453 -297.993854) (xy 45.746307 -297.969541) (xy 45.79643 -297.952981)
			(xy 45.848546 -297.944594) (xy 45.901334 -297.944594) (xy 45.95345 -297.952981) (xy 46.003573 -297.969541)
			(xy 46.050427 -297.993854) (xy 46.092824 -298.025302) (xy 46.129686 -298.063087) (xy 46.160077 -298.106248)
			(xy 46.183225 -298.153689) (xy 46.198541 -298.204205) (xy 46.2026 -298.23029) (xy 46.204211 -298.238946)
			(xy 46.212403 -298.254516) (xy 46.218602 -298.26077) (xy 46.2407 -298.28109) (xy 46.247902 -298.287247)
			(xy 46.265523 -298.294175) (xy 46.27499 -298.294552) (xy 46.42485 -298.294552) (xy 46.434294 -298.294061)
			(xy 46.45188 -298.287151) (xy 46.45914 -298.28109) (xy 46.481238 -298.26077) (xy 46.487549 -298.254599)
			(xy 46.495766 -298.238991) (xy 46.49724 -298.23029) (xy 46.501302 -298.204205) (xy 46.516623 -298.15369)
			(xy 46.539773 -298.106248) (xy 46.570164 -298.063086) (xy 46.607025 -298.025299) (xy 46.649419 -297.993846)
			(xy 46.696271 -297.969525) (xy 46.746391 -297.952955) (xy 46.798506 -297.944555) (xy 46.8249 -297.944032)
			(xy 46.854374 -297.944703) (xy 46.912381 -297.955195) (xy 46.967613 -297.975795) (xy 46.993302 -297.99026)
			(xy 47.00524 -297.997118) (xy 47.032418 -297.997372) (xy 47.114714 -297.950382) (xy 47.12081 -297.946826)
			(xy 47.121826 -297.946318) (xy 47.129167 -297.941507) (xy 47.140281 -297.927939) (xy 47.146122 -297.911402)
			(xy 47.146464 -297.90263) (xy 47.146464 -297.627294) (xy 47.146718 -297.621198) (xy 47.146718 -297.028362)
			(xy 47.146464 -297.022266) (xy 47.146464 -296.74693) (xy 47.146083 -296.738176) (xy 47.140178 -296.72169)
			(xy 47.129105 -296.708124) (xy 47.121826 -296.703242) (xy 47.12081 -296.702734) (xy 47.114714 -296.699178)
			(xy 47.032418 -296.652188) (xy 47.00524 -296.652442) (xy 46.993302 -296.6593) (xy 46.967618 -296.673775)
			(xy 46.912385 -296.694374) (xy 46.854374 -296.704857) (xy 46.8249 -296.705528) (xy 46.798912 -296.705018)
			(xy 46.747577 -296.696888) (xy 46.698145 -296.680827) (xy 46.651834 -296.657232) (xy 46.609784 -296.626682)
			(xy 46.573031 -296.589931) (xy 46.542479 -296.547883) (xy 46.51888 -296.501574) (xy 46.502817 -296.452143)
			(xy 46.494683 -296.400808) (xy 46.494192 -296.37482) (xy 46.494657 -296.351111) (xy 46.501547 -296.304193)
			(xy 46.507908 -296.281348) (xy 46.50994 -296.274236) (xy 46.50994 -296.273982) (xy 46.512841 -296.26237)
			(xy 46.508854 -296.2388) (xy 46.50232 -296.22877) (xy 46.453806 -296.162476) (xy 46.446203 -296.153212)
			(xy 46.424876 -296.142345) (xy 46.412912 -296.141648) (xy 46.286928 -296.141648) (xy 46.274946 -296.142288)
			(xy 46.25359 -296.153156) (xy 46.246034 -296.162476) (xy 46.19752 -296.22877) (xy 46.191984 -296.237076)
			(xy 46.18716 -296.256425) (xy 46.188122 -296.266362) (xy 46.188884 -296.271442) (xy 46.190154 -296.275252)
			(xy 46.197351 -296.299514) (xy 46.205129 -296.349518) (xy 46.205648 -296.37482) (xy 46.205138 -296.400807)
			(xy 46.197008 -296.452142) (xy 46.180947 -296.501572) (xy 46.157351 -296.547882) (xy 46.126801 -296.58993)
			(xy 46.09005 -296.626681) (xy 46.048002 -296.657231) (xy 46.001692 -296.680827) (xy 45.952262 -296.696888)
			(xy 45.900927 -296.705018) (xy 45.848953 -296.705018) (xy 45.797618 -296.696888) (xy 45.748188 -296.680827)
			(xy 45.701878 -296.657231) (xy 45.65983 -296.626681) (xy 45.623079 -296.58993) (xy 45.592529 -296.547882)
			(xy 45.568933 -296.501572) (xy 45.552872 -296.452142) (xy 45.544742 -296.400807) (xy 45.544232 -296.37482)
			(xy 45.544697 -296.351111) (xy 45.551588 -296.304193) (xy 45.557948 -296.281348) (xy 45.55998 -296.274236)
			(xy 45.55998 -296.273982) (xy 45.56288 -296.262369) (xy 45.558896 -296.238799) (xy 45.55236 -296.22877)
			(xy 45.503846 -296.162476) (xy 45.496246 -296.153205) (xy 45.474919 -296.142322) (xy 45.462952 -296.141648)
			(xy 45.336968 -296.141648) (xy 45.324992 -296.142301) (xy 45.303658 -296.153183) (xy 45.296074 -296.162476)
			(xy 45.24756 -296.22877) (xy 45.24202 -296.237075) (xy 45.237192 -296.256425) (xy 45.238162 -296.266362)
			(xy 45.238924 -296.271442) (xy 45.240194 -296.275252) (xy 45.24739 -296.299514) (xy 45.255167 -296.349518)
			(xy 45.255688 -296.37482) (xy 45.255178 -296.400807) (xy 45.247048 -296.452142) (xy 45.230987 -296.501572)
			(xy 45.207391 -296.547882) (xy 45.176841 -296.58993) (xy 45.14009 -296.626681) (xy 45.098042 -296.657231)
			(xy 45.051732 -296.680827) (xy 45.002302 -296.696888) (xy 44.950967 -296.705018) (xy 44.898993 -296.705018)
			(xy 44.847658 -296.696888) (xy 44.798228 -296.680827) (xy 44.751918 -296.657231) (xy 44.70987 -296.626681)
			(xy 44.673119 -296.58993) (xy 44.642569 -296.547882) (xy 44.618973 -296.501572) (xy 44.602912 -296.452142)
			(xy 44.594782 -296.400807) (xy 44.594272 -296.37482) (xy 44.594737 -296.351111) (xy 44.601626 -296.304193)
			(xy 44.607988 -296.281348) (xy 44.61002 -296.274236) (xy 44.61002 -296.273982) (xy 44.612919 -296.262369)
			(xy 44.608937 -296.238798) (xy 44.6024 -296.22877) (xy 44.553886 -296.162476) (xy 44.546282 -296.153215)
			(xy 44.524954 -296.142356) (xy 44.512992 -296.141648) (xy 44.386754 -296.141648) (xy 44.374769 -296.142283)
			(xy 44.353404 -296.153144) (xy 44.34586 -296.162476) (xy 44.297346 -296.22877) (xy 44.291808 -296.237076)
			(xy 44.286981 -296.256425) (xy 44.287948 -296.266362) (xy 44.28871 -296.271442) (xy 44.28998 -296.275252)
			(xy 44.297177 -296.299514) (xy 44.304954 -296.349518) (xy 44.305474 -296.37482) (xy 44.304964 -296.400807)
			(xy 44.296834 -296.452142) (xy 44.280773 -296.501572) (xy 44.257177 -296.547882) (xy 44.226627 -296.58993)
			(xy 44.189876 -296.626681) (xy 44.147828 -296.657231) (xy 44.101518 -296.680827) (xy 44.052088 -296.696888)
			(xy 44.000753 -296.705018) (xy 43.948779 -296.705018) (xy 43.897444 -296.696888) (xy 43.848014 -296.680827)
			(xy 43.801704 -296.657231) (xy 43.759656 -296.626681) (xy 43.722905 -296.58993) (xy 43.692355 -296.547882)
			(xy 43.668759 -296.501572) (xy 43.652698 -296.452142) (xy 43.644568 -296.400807) (xy 43.644058 -296.37482)
			(xy 43.644523 -296.351111) (xy 43.651412 -296.304193) (xy 43.657774 -296.281348) (xy 43.659806 -296.274236)
			(xy 43.659806 -296.273982) (xy 43.662705 -296.262369) (xy 43.658723 -296.238798) (xy 43.652186 -296.22877)
			(xy 43.603672 -296.162476) (xy 43.596067 -296.153217) (xy 43.574739 -296.142365) (xy 43.562778 -296.141648)
			(xy 42.486834 -296.141648) (xy 42.474851 -296.142287) (xy 42.453493 -296.153153) (xy 42.44594 -296.162476)
			(xy 42.397426 -296.22877) (xy 42.39189 -296.237076) (xy 42.387065 -296.256425) (xy 42.388028 -296.266362)
			(xy 42.38879 -296.271442) (xy 42.39006 -296.275252) (xy 42.397257 -296.299514) (xy 42.405035 -296.349518)
			(xy 42.405554 -296.37482) (xy 42.405044 -296.400807) (xy 42.396914 -296.452142) (xy 42.380853 -296.501572)
			(xy 42.357257 -296.547882) (xy 42.326707 -296.58993) (xy 42.289956 -296.626681) (xy 42.247908 -296.657231)
			(xy 42.201598 -296.680827) (xy 42.152168 -296.696888) (xy 42.100833 -296.705018) (xy 42.048859 -296.705018)
			(xy 41.997524 -296.696888) (xy 41.948094 -296.680827) (xy 41.901784 -296.657231) (xy 41.859736 -296.626681)
			(xy 41.822985 -296.58993) (xy 41.792435 -296.547882) (xy 41.768839 -296.501572) (xy 41.752778 -296.452142)
			(xy 41.744648 -296.400807) (xy 41.744138 -296.37482) (xy 41.744603 -296.351111) (xy 41.751494 -296.304193)
			(xy 41.757854 -296.281348) (xy 41.759886 -296.274236) (xy 41.759886 -296.273982) (xy 41.762786 -296.262369)
			(xy 41.758802 -296.238799) (xy 41.752266 -296.22877) (xy 41.703752 -296.162476) (xy 41.696146 -296.153221)
			(xy 41.674818 -296.142376) (xy 41.662858 -296.141648) (xy 40.586914 -296.141648) (xy 40.574933 -296.142291)
			(xy 40.553583 -296.153162) (xy 40.54602 -296.162476) (xy 40.497506 -296.22877) (xy 40.491971 -296.237077)
			(xy 40.487148 -296.256425) (xy 40.488108 -296.266362) (xy 40.48887 -296.271442) (xy 40.49014 -296.275252)
			(xy 40.497337 -296.299514) (xy 40.505116 -296.349518) (xy 40.505634 -296.37482) (xy 40.505124 -296.400807)
			(xy 40.496994 -296.452142) (xy 40.480933 -296.501572) (xy 40.457337 -296.547882) (xy 40.426787 -296.58993)
			(xy 40.390036 -296.626681) (xy 40.347988 -296.657231) (xy 40.301678 -296.680827) (xy 40.252248 -296.696888)
			(xy 40.200913 -296.705018) (xy 40.148939 -296.705018) (xy 40.097604 -296.696888) (xy 40.048174 -296.680827)
			(xy 40.001864 -296.657231) (xy 39.959816 -296.626681) (xy 39.923065 -296.58993) (xy 39.892515 -296.547882)
			(xy 39.868919 -296.501572) (xy 39.852858 -296.452142) (xy 39.844728 -296.400807) (xy 39.844218 -296.37482)
			(xy 39.844683 -296.351111) (xy 39.851573 -296.304193) (xy 39.857934 -296.281348) (xy 39.859966 -296.274236)
			(xy 39.859966 -296.273982) (xy 39.862867 -296.26237) (xy 39.858881 -296.238799) (xy 39.852346 -296.22877)
			(xy 39.803832 -296.162476) (xy 39.796231 -296.153207) (xy 39.774904 -296.14233) (xy 39.762938 -296.141648)
			(xy 39.636954 -296.141648) (xy 39.624969 -296.142283) (xy 39.603604 -296.153144) (xy 39.59606 -296.162476)
			(xy 39.547546 -296.22877) (xy 39.542008 -296.237076) (xy 39.537181 -296.256425) (xy 39.538148 -296.266362)
			(xy 39.53891 -296.271442) (xy 39.54018 -296.275252) (xy 39.547377 -296.299514) (xy 39.555154 -296.349518)
			(xy 39.555674 -296.37482) (xy 39.555164 -296.400807) (xy 39.547034 -296.452142) (xy 39.530973 -296.501572)
			(xy 39.507377 -296.547882) (xy 39.476827 -296.58993) (xy 39.440076 -296.626681) (xy 39.398028 -296.657231)
			(xy 39.351718 -296.680827) (xy 39.302288 -296.696888) (xy 39.250953 -296.705018) (xy 39.198979 -296.705018)
			(xy 39.147644 -296.696888) (xy 39.098214 -296.680827) (xy 39.051904 -296.657231) (xy 39.009856 -296.626681)
			(xy 38.973105 -296.58993) (xy 38.942555 -296.547882) (xy 38.918959 -296.501572) (xy 38.902898 -296.452142)
			(xy 38.894768 -296.400807) (xy 38.894258 -296.37482) (xy 38.894723 -296.351111) (xy 38.901612 -296.304193)
			(xy 38.907974 -296.281348) (xy 38.910006 -296.274236) (xy 38.910006 -296.273982) (xy 38.912905 -296.262369)
			(xy 38.908923 -296.238798) (xy 38.902386 -296.22877) (xy 38.853872 -296.162476) (xy 38.846267 -296.153217)
			(xy 38.824939 -296.142365) (xy 38.812978 -296.141648) (xy 38.68674 -296.141648) (xy 38.674756 -296.142286)
			(xy 38.653396 -296.15315) (xy 38.645846 -296.162476) (xy 38.597332 -296.22877) (xy 38.591795 -296.237076)
			(xy 38.58697 -296.256425) (xy 38.587934 -296.266362) (xy 38.588696 -296.271442) (xy 38.589966 -296.275252)
			(xy 38.597163 -296.299514) (xy 38.604941 -296.349518) (xy 38.60546 -296.37482) (xy 38.60495 -296.400807)
			(xy 38.59682 -296.452142) (xy 38.580759 -296.501572) (xy 38.557163 -296.547882) (xy 38.526613 -296.58993)
			(xy 38.489862 -296.626681) (xy 38.447814 -296.657231) (xy 38.401504 -296.680827) (xy 38.352074 -296.696888)
			(xy 38.300739 -296.705018) (xy 38.248765 -296.705018) (xy 38.19743 -296.696888) (xy 38.148 -296.680827)
			(xy 38.10169 -296.657231) (xy 38.059642 -296.626681) (xy 38.022891 -296.58993) (xy 37.992341 -296.547882)
			(xy 37.968745 -296.501572) (xy 37.952684 -296.452142) (xy 37.944554 -296.400807) (xy 37.944044 -296.37482)
			(xy 37.944509 -296.351111) (xy 37.951398 -296.304193) (xy 37.95776 -296.281348) (xy 37.959792 -296.274236)
			(xy 37.959792 -296.273982) (xy 37.962691 -296.262369) (xy 37.958708 -296.238798) (xy 37.952172 -296.22877)
			(xy 37.903658 -296.162476) (xy 37.896052 -296.15322) (xy 37.874724 -296.142373) (xy 37.862764 -296.141648)
			(xy 37.716206 -296.141648) (xy 37.710766 -296.141508) (xy 37.700132 -296.139206) (xy 37.695124 -296.137076)
			(xy 37.681662 -296.130726) (xy 37.652706 -296.13479) (xy 37.628068 -296.155364) (xy 37.620007 -296.162873)
			(xy 37.610626 -296.182782) (xy 37.610359 -296.204788) (xy 37.614352 -296.215054) (xy 37.627288 -296.239677)
			(xy 37.645634 -296.29218) (xy 37.654937 -296.347012) (xy 37.6555 -296.37482) (xy 37.65499 -296.400807)
			(xy 37.64686 -296.452142) (xy 37.630799 -296.501572) (xy 37.607203 -296.547882) (xy 37.576653 -296.58993)
			(xy 37.539902 -296.626681) (xy 37.497854 -296.657231) (xy 37.451544 -296.680827) (xy 37.402114 -296.696888)
			(xy 37.350779 -296.705018) (xy 37.298805 -296.705018) (xy 37.24747 -296.696888) (xy 37.19804 -296.680827)
			(xy 37.15173 -296.657231) (xy 37.109682 -296.626681) (xy 37.072931 -296.58993) (xy 37.042381 -296.547882)
			(xy 37.018785 -296.501572) (xy 37.002724 -296.452142) (xy 36.994594 -296.400807) (xy 36.994084 -296.37482)
			(xy 36.994549 -296.349393) (xy 37.002333 -296.299137) (xy 37.017721 -296.250666) (xy 37.04035 -296.205123)
			(xy 37.069686 -296.163582) (xy 37.105037 -296.127024) (xy 37.145569 -296.096309) (xy 37.190326 -296.072164)
			(xy 37.238253 -296.055156) (xy 37.288219 -296.045689) (xy 37.313616 -296.044366) (xy 37.323431 -296.043564)
			(xy 37.341389 -296.035525) (xy 37.355011 -296.021329) (xy 37.359082 -296.012362) (xy 37.380672 -295.957752)
			(xy 37.393372 -295.925494) (xy 37.396549 -295.91613) (xy 37.396296 -295.896376) (xy 37.388623 -295.878172)
			(xy 37.381942 -295.870884) (xy 36.31565 -294.804592) (xy 36.303712 -294.797988) (xy 36.296854 -294.79621)
			(xy 36.271258 -294.789452) (xy 36.222466 -294.768923) (xy 36.17756 -294.740894) (xy 36.137685 -294.706079)
			(xy 36.103855 -294.665364) (xy 36.076933 -294.619787) (xy 36.057603 -294.570507) (xy 36.05149 -294.54475)
			(xy 36.049966 -294.537384) (xy 36.043108 -294.524684) (xy 34.104834 -292.586664) (xy 34.097435 -292.579821)
			(xy 34.078836 -292.5721) (xy 34.068766 -292.571678) (xy 32.210502 -292.571678) (xy 32.199751 -292.572152)
			(xy 32.180137 -292.580961) (xy 32.172656 -292.588696) (xy 32.12211 -292.645846) (xy 32.115372 -292.654155)
			(xy 32.108945 -292.674541) (xy 32.109664 -292.685216) (xy 32.109664 -292.685724) (xy 32.110993 -292.697426)
			(xy 32.112394 -292.720937) (xy 32.112458 -292.732714) (xy 32.111994 -292.759965) (xy 32.104235 -292.813912)
			(xy 32.088877 -292.866205) (xy 32.066233 -292.91578) (xy 32.036764 -292.961628) (xy 32.00107 -293.002815)
			(xy 31.959877 -293.038502) (xy 31.914024 -293.067964) (xy 31.864445 -293.090599) (xy 31.812149 -293.105948)
			(xy 31.758201 -293.113698) (xy 31.73095 -293.114222) (xy 31.730696 -293.114222) (xy 31.706118 -293.113822)
			(xy 31.657371 -293.107483) (xy 31.609838 -293.094948) (xy 31.586932 -293.086028) (xy 31.575248 -293.081202)
			(xy 31.550102 -293.083742) (xy 31.53791 -293.09187) (xy 31.496 -293.120064) (xy 31.482284 -293.129208)
			(xy 31.473902 -293.134796) (xy 31.466282 -293.141146) (xy 31.462218 -293.14521) (xy 31.455371 -293.152608)
			(xy 31.447638 -293.171206) (xy 31.447232 -293.181278) (xy 31.447232 -293.494714) (xy 33.620962 -293.494714)
			(xy 33.625033 -293.439092) (xy 33.637159 -293.384655) (xy 33.657082 -293.332564) (xy 33.684378 -293.283929)
			(xy 33.718464 -293.239786) (xy 33.758613 -293.201077) (xy 33.803971 -293.168626) (xy 33.853571 -293.143125)
			(xy 33.906355 -293.125118) (xy 33.961198 -293.114988) (xy 34.016932 -293.112951) (xy 34.072369 -293.119051)
			(xy 34.126326 -293.133157) (xy 34.177655 -293.154969) (xy 34.225261 -293.184023) (xy 34.268129 -293.219698)
			(xy 34.305346 -293.261235) (xy 34.336119 -293.307748) (xy 34.359791 -293.358245) (xy 34.375859 -293.411652)
			(xy 34.383979 -293.466828) (xy 34.384488 -293.494714) (xy 34.383979 -293.5226) (xy 34.375859 -293.577776)
			(xy 34.359791 -293.631183) (xy 34.336119 -293.68168) (xy 34.305346 -293.728193) (xy 34.268129 -293.76973)
			(xy 34.225261 -293.805405) (xy 34.177655 -293.834459) (xy 34.126326 -293.856271) (xy 34.072369 -293.870377)
			(xy 34.016932 -293.876477) (xy 33.961198 -293.87444) (xy 33.906355 -293.86431) (xy 33.853571 -293.846303)
			(xy 33.803971 -293.820802) (xy 33.758613 -293.788351) (xy 33.718464 -293.749642) (xy 33.684378 -293.705499)
			(xy 33.657082 -293.656864) (xy 33.637159 -293.604773) (xy 33.625033 -293.550336) (xy 33.620962 -293.494714)
			(xy 31.447232 -293.494714) (xy 31.447232 -295.207182) (xy 31.447722 -295.217142) (xy 31.455317 -295.23556)
			(xy 31.461964 -295.242996) (xy 31.629858 -295.411144) (xy 31.637257 -295.417987) (xy 31.655856 -295.42571)
			(xy 31.665926 -295.42613) (xy 33.206182 -295.42613) (xy 33.216245 -295.426569) (xy 33.234825 -295.434307)
			(xy 33.24225 -295.441116) (xy 33.551368 -295.750234) (xy 33.558213 -295.757633) (xy 33.56594 -295.776231)
			(xy 33.566354 -295.786302) (xy 33.566354 -296.288968) (xy 33.566448 -296.293987) (xy 33.568369 -296.303838)
			(xy 33.570164 -296.308526) (xy 33.577022 -296.324528) (xy 33.578817 -296.329215) (xy 33.580729 -296.339067)
			(xy 33.580832 -296.344086) (xy 33.580832 -296.348912) (xy 33.597088 -296.374058) (xy 33.694878 -296.418254)
			(xy 33.704002 -296.421923) (xy 33.723631 -296.42274) (xy 33.742114 -296.416081) (xy 33.749742 -296.409872)
			(xy 33.770786 -296.391838) (xy 33.817106 -296.361414) (xy 33.867342 -296.338015) (xy 33.920437 -296.322136)
			(xy 33.975271 -296.31411) (xy 34.00298 -296.313606) (xy 34.030233 -296.314068) (xy 34.084184 -296.321822)
			(xy 34.136482 -296.337176) (xy 34.186063 -296.359817) (xy 34.231917 -296.389283) (xy 34.273111 -296.424975)
			(xy 34.308805 -296.466167) (xy 34.338274 -296.512019) (xy 34.360917 -296.561599) (xy 34.376273 -296.613897)
			(xy 34.384031 -296.667847) (xy 34.384031 -296.722353) (xy 34.376273 -296.776303) (xy 34.360917 -296.828601)
			(xy 34.338274 -296.878181) (xy 34.308805 -296.924033) (xy 34.273111 -296.965225) (xy 34.231917 -297.000917)
			(xy 34.186063 -297.030383) (xy 34.136482 -297.053024) (xy 34.084184 -297.068378) (xy 34.030233 -297.076132)
			(xy 34.00298 -297.076622) (xy 33.975271 -297.076124) (xy 33.920437 -297.068096) (xy 33.867343 -297.052214)
			(xy 33.817108 -297.028812) (xy 33.770792 -296.998383) (xy 33.749742 -296.980356) (xy 33.742113 -296.974167)
			(xy 33.72363 -296.967568) (xy 33.70402 -296.968374) (xy 33.694878 -296.971974) (xy 33.610804 -297.010074)
			(xy 33.602111 -297.014478) (xy 33.588621 -297.028519) (xy 33.581316 -297.046568) (xy 33.580832 -297.056302)
			(xy 33.580832 -297.3245) (xy 35.433795 -297.3245) (xy 35.437965 -297.274168) (xy 35.450363 -297.22521)
			(xy 35.470649 -297.178959) (xy 35.498271 -297.136678) (xy 35.532475 -297.09952) (xy 35.572329 -297.068498)
			(xy 35.616745 -297.044458) (xy 35.664511 -297.028057) (xy 35.714326 -297.019741) (xy 35.739578 -297.019218)
			(xy 35.764974 -297.019712) (xy 35.815065 -297.028128) (xy 35.863073 -297.044715) (xy 35.907676 -297.069017)
			(xy 35.947643 -297.100363) (xy 35.96513 -297.118786) (xy 35.97275 -297.127168) (xy 35.992816 -297.135804)
			(xy 36.09213 -297.133264) (xy 36.111688 -297.123612) (xy 36.1188 -297.114976) (xy 36.134612 -297.096424)
			(xy 36.17074 -297.063703) (xy 36.211277 -297.036634) (xy 36.255344 -297.015802) (xy 36.30199 -297.001658)
			(xy 36.350206 -296.994507) (xy 36.374578 -296.994072) (xy 37.324538 -296.994072) (xy 37.350522 -296.994624)
			(xy 37.401848 -297.002759) (xy 37.451271 -297.018822) (xy 37.497572 -297.042419) (xy 37.539613 -297.072968)
			(xy 37.576357 -297.109716) (xy 37.606901 -297.15176) (xy 37.630492 -297.198064) (xy 37.64655 -297.247489)
			(xy 37.654679 -297.298816) (xy 37.654679 -297.32478) (xy 37.968948 -297.32478) (xy 37.972908 -297.275726)
			(xy 37.984685 -297.227942) (xy 38.003976 -297.182666) (xy 38.030279 -297.14107) (xy 38.062914 -297.104233)
			(xy 38.101035 -297.073108) (xy 38.143656 -297.048501) (xy 38.189672 -297.031049) (xy 38.237891 -297.021205)
			(xy 38.287066 -297.019224) (xy 38.335921 -297.025156) (xy 38.383192 -297.038848) (xy 38.427654 -297.059946)
			(xy 38.468157 -297.087902) (xy 38.50365 -297.121994) (xy 38.533215 -297.161338) (xy 38.556086 -297.204915)
			(xy 38.57167 -297.251596) (xy 38.579565 -297.300173) (xy 38.58006 -297.32478) (xy 38.919162 -297.32478)
			(xy 38.923122 -297.275726) (xy 38.934899 -297.227942) (xy 38.95419 -297.182666) (xy 38.980493 -297.14107)
			(xy 39.013128 -297.104233) (xy 39.051249 -297.073108) (xy 39.09387 -297.048501) (xy 39.139886 -297.031049)
			(xy 39.188105 -297.021205) (xy 39.23728 -297.019224) (xy 39.286135 -297.025156) (xy 39.333406 -297.038848)
			(xy 39.377868 -297.059946) (xy 39.418371 -297.087902) (xy 39.453864 -297.121994) (xy 39.483429 -297.161338)
			(xy 39.5063 -297.204915) (xy 39.521884 -297.251596) (xy 39.529779 -297.300173) (xy 39.530274 -297.32478)
			(xy 41.769042 -297.32478) (xy 41.773002 -297.275726) (xy 41.784779 -297.227942) (xy 41.80407 -297.182666)
			(xy 41.830373 -297.14107) (xy 41.863008 -297.104233) (xy 41.901129 -297.073108) (xy 41.94375 -297.048501)
			(xy 41.989766 -297.031049) (xy 42.037985 -297.021205) (xy 42.08716 -297.019224) (xy 42.136015 -297.025156)
			(xy 42.183286 -297.038848) (xy 42.227748 -297.059946) (xy 42.268251 -297.087902) (xy 42.303744 -297.121994)
			(xy 42.333309 -297.161338) (xy 42.35618 -297.204915) (xy 42.371764 -297.251596) (xy 42.379659 -297.300173)
			(xy 42.380154 -297.32478) (xy 43.668962 -297.32478) (xy 43.672922 -297.275726) (xy 43.684699 -297.227942)
			(xy 43.70399 -297.182666) (xy 43.730293 -297.14107) (xy 43.762928 -297.104233) (xy 43.801049 -297.073108)
			(xy 43.84367 -297.048501) (xy 43.889686 -297.031049) (xy 43.937905 -297.021205) (xy 43.98708 -297.019224)
			(xy 44.035935 -297.025156) (xy 44.083206 -297.038848) (xy 44.127668 -297.059946) (xy 44.168171 -297.087902)
			(xy 44.203664 -297.121994) (xy 44.233229 -297.161338) (xy 44.2561 -297.204915) (xy 44.271684 -297.251596)
			(xy 44.279579 -297.300173) (xy 44.280074 -297.32478) (xy 44.619176 -297.32478) (xy 44.623136 -297.275726)
			(xy 44.634913 -297.227942) (xy 44.654204 -297.182666) (xy 44.680507 -297.14107) (xy 44.713142 -297.104233)
			(xy 44.751263 -297.073108) (xy 44.793884 -297.048501) (xy 44.8399 -297.031049) (xy 44.888119 -297.021205)
			(xy 44.937294 -297.019224) (xy 44.986149 -297.025156) (xy 45.03342 -297.038848) (xy 45.077882 -297.059946)
			(xy 45.118385 -297.087902) (xy 45.153878 -297.121994) (xy 45.183443 -297.161338) (xy 45.206314 -297.204915)
			(xy 45.221898 -297.251596) (xy 45.229793 -297.300173) (xy 45.230288 -297.32478) (xy 45.569136 -297.32478)
			(xy 45.573096 -297.275726) (xy 45.584873 -297.227942) (xy 45.604164 -297.182666) (xy 45.630467 -297.14107)
			(xy 45.663102 -297.104233) (xy 45.701223 -297.073108) (xy 45.743844 -297.048501) (xy 45.78986 -297.031049)
			(xy 45.838079 -297.021205) (xy 45.887254 -297.019224) (xy 45.936109 -297.025156) (xy 45.98338 -297.038848)
			(xy 46.027842 -297.059946) (xy 46.068345 -297.087902) (xy 46.103838 -297.121994) (xy 46.133403 -297.161338)
			(xy 46.156274 -297.204915) (xy 46.171858 -297.251596) (xy 46.179753 -297.300173) (xy 46.180248 -297.32478)
			(xy 46.179753 -297.349387) (xy 46.171858 -297.397964) (xy 46.156274 -297.444645) (xy 46.133403 -297.488222)
			(xy 46.103838 -297.527566) (xy 46.068345 -297.561658) (xy 46.027842 -297.589614) (xy 45.98338 -297.610712)
			(xy 45.936109 -297.624404) (xy 45.887254 -297.630336) (xy 45.838079 -297.628355) (xy 45.78986 -297.618511)
			(xy 45.743844 -297.601059) (xy 45.701223 -297.576452) (xy 45.663102 -297.545327) (xy 45.630467 -297.50849)
			(xy 45.604164 -297.466894) (xy 45.584873 -297.421618) (xy 45.573096 -297.373834) (xy 45.569136 -297.32478)
			(xy 45.230288 -297.32478) (xy 45.229793 -297.349387) (xy 45.221898 -297.397964) (xy 45.206314 -297.444645)
			(xy 45.183443 -297.488222) (xy 45.153878 -297.527566) (xy 45.118385 -297.561658) (xy 45.077882 -297.589614)
			(xy 45.03342 -297.610712) (xy 44.986149 -297.624404) (xy 44.937294 -297.630336) (xy 44.888119 -297.628355)
			(xy 44.8399 -297.618511) (xy 44.793884 -297.601059) (xy 44.751263 -297.576452) (xy 44.713142 -297.545327)
			(xy 44.680507 -297.50849) (xy 44.654204 -297.466894) (xy 44.634913 -297.421618) (xy 44.623136 -297.373834)
			(xy 44.619176 -297.32478) (xy 44.280074 -297.32478) (xy 44.279579 -297.349387) (xy 44.271684 -297.397964)
			(xy 44.2561 -297.444645) (xy 44.233229 -297.488222) (xy 44.203664 -297.527566) (xy 44.168171 -297.561658)
			(xy 44.127668 -297.589614) (xy 44.083206 -297.610712) (xy 44.035935 -297.624404) (xy 43.98708 -297.630336)
			(xy 43.937905 -297.628355) (xy 43.889686 -297.618511) (xy 43.84367 -297.601059) (xy 43.801049 -297.576452)
			(xy 43.762928 -297.545327) (xy 43.730293 -297.50849) (xy 43.70399 -297.466894) (xy 43.684699 -297.421618)
			(xy 43.672922 -297.373834) (xy 43.668962 -297.32478) (xy 42.380154 -297.32478) (xy 42.379659 -297.349387)
			(xy 42.371764 -297.397964) (xy 42.35618 -297.444645) (xy 42.333309 -297.488222) (xy 42.303744 -297.527566)
			(xy 42.268251 -297.561658) (xy 42.227748 -297.589614) (xy 42.183286 -297.610712) (xy 42.136015 -297.624404)
			(xy 42.08716 -297.630336) (xy 42.037985 -297.628355) (xy 41.989766 -297.618511) (xy 41.94375 -297.601059)
			(xy 41.901129 -297.576452) (xy 41.863008 -297.545327) (xy 41.830373 -297.50849) (xy 41.80407 -297.466894)
			(xy 41.784779 -297.421618) (xy 41.773002 -297.373834) (xy 41.769042 -297.32478) (xy 39.530274 -297.32478)
			(xy 39.529779 -297.349387) (xy 39.521884 -297.397964) (xy 39.5063 -297.444645) (xy 39.483429 -297.488222)
			(xy 39.453864 -297.527566) (xy 39.418371 -297.561658) (xy 39.377868 -297.589614) (xy 39.333406 -297.610712)
			(xy 39.286135 -297.624404) (xy 39.23728 -297.630336) (xy 39.188105 -297.628355) (xy 39.139886 -297.618511)
			(xy 39.09387 -297.601059) (xy 39.051249 -297.576452) (xy 39.013128 -297.545327) (xy 38.980493 -297.50849)
			(xy 38.95419 -297.466894) (xy 38.934899 -297.421618) (xy 38.923122 -297.373834) (xy 38.919162 -297.32478)
			(xy 38.58006 -297.32478) (xy 38.579565 -297.349387) (xy 38.57167 -297.397964) (xy 38.556086 -297.444645)
			(xy 38.533215 -297.488222) (xy 38.50365 -297.527566) (xy 38.468157 -297.561658) (xy 38.427654 -297.589614)
			(xy 38.383192 -297.610712) (xy 38.335921 -297.624404) (xy 38.287066 -297.630336) (xy 38.237891 -297.628355)
			(xy 38.189672 -297.618511) (xy 38.143656 -297.601059) (xy 38.101035 -297.576452) (xy 38.062914 -297.545327)
			(xy 38.030279 -297.50849) (xy 38.003976 -297.466894) (xy 37.984685 -297.421618) (xy 37.972908 -297.373834)
			(xy 37.968948 -297.32478) (xy 37.654679 -297.32478) (xy 37.654679 -297.350784) (xy 37.64655 -297.402111)
			(xy 37.630492 -297.451536) (xy 37.606901 -297.49784) (xy 37.576357 -297.539884) (xy 37.539613 -297.576632)
			(xy 37.497572 -297.607181) (xy 37.451271 -297.630778) (xy 37.401848 -297.646841) (xy 37.350522 -297.654976)
			(xy 37.324538 -297.655488) (xy 36.374578 -297.655488) (xy 36.350206 -297.655043) (xy 36.301987 -297.647903)
			(xy 36.255338 -297.633766) (xy 36.211267 -297.612937) (xy 36.17073 -297.585868) (xy 36.134603 -297.553144)
			(xy 36.1188 -297.534584) (xy 36.111434 -297.525694) (xy 36.09213 -297.516296) (xy 35.992562 -297.513502)
			(xy 35.97275 -297.522138) (xy 35.96513 -297.530266) (xy 35.947651 -297.548698) (xy 35.907685 -297.580046)
			(xy 35.86308 -297.604346) (xy 35.815069 -297.620927) (xy 35.764975 -297.629331) (xy 35.739578 -297.629834)
			(xy 35.714326 -297.629259) (xy 35.664511 -297.620943) (xy 35.616745 -297.604542) (xy 35.572329 -297.580502)
			(xy 35.532475 -297.54948) (xy 35.498271 -297.512322) (xy 35.470649 -297.470041) (xy 35.450363 -297.42379)
			(xy 35.437965 -297.374832) (xy 35.433795 -297.3245) (xy 33.580832 -297.3245) (xy 33.580832 -297.997626)
			(xy 33.580716 -298.002722) (xy 33.578663 -298.012705) (xy 33.576768 -298.017438) (xy 33.572958 -298.026582)
			(xy 33.570672 -298.03217) (xy 33.568692 -298.03695) (xy 33.566522 -298.047065) (xy 33.566354 -298.052236)
			(xy 33.566354 -298.118276) (xy 33.566793 -298.128339) (xy 33.574532 -298.146918) (xy 33.58134 -298.154344)
			(xy 33.706562 -298.279566) (xy 33.713962 -298.286406) (xy 33.732561 -298.294124) (xy 33.74263 -298.294552)
		)
		(stroke
			(width 0)
			(type solid)
		)
		(fill yes)
		(layer "In11.Cu")
		(net "PCEPLL2_VDDA18_PEX0")
	)
	(gr_poly
		(pts
			(xy 156.383228 -191.392556) (xy 156.393586 -191.392013) (xy 156.412594 -191.383757) (xy 156.420058 -191.376554)
			(xy 156.420312 -191.376554) (xy 156.427062 -191.368641) (xy 156.43415 -191.349108) (xy 156.434028 -191.338708)
			(xy 154.625294 -161.638488) (xy 154.623902 -161.626445) (xy 154.611566 -161.605616) (xy 154.601672 -161.59861)
			(xy 154.578765 -161.583515) (xy 154.537125 -161.547799) (xy 154.501022 -161.506494) (xy 154.471201 -161.460448)
			(xy 154.448273 -161.41061) (xy 154.432712 -161.358004) (xy 154.424838 -161.303713) (xy 154.42438 -161.276284)
			(xy 154.424883 -161.248151) (xy 154.433145 -161.192495) (xy 154.449487 -161.138655) (xy 154.473556 -161.087797)
			(xy 154.50483 -161.041023) (xy 154.542631 -160.999347) (xy 154.56408 -160.981136) (xy 154.573121 -160.972948)
			(xy 154.582945 -160.950661) (xy 154.582876 -160.938464) (xy 154.13736 -153.62682) (xy 154.136326 -153.616822)
			(xy 154.127507 -153.598778) (xy 154.112439 -153.585501) (xy 154.10307 -153.581862) (xy 154.014424 -153.551128)
			(xy 154.004798 -153.548261) (xy 153.984767 -153.549504) (xy 153.966745 -153.558338) (xy 153.959814 -153.565606)
			(xy 153.95956 -153.56586) (xy 153.941373 -153.585905) (xy 153.900313 -153.621168) (xy 153.85468 -153.650271)
			(xy 153.80539 -153.67263) (xy 153.753434 -153.687794) (xy 153.699856 -153.69546) (xy 153.672794 -153.695908)
			(xy 153.645543 -153.695422) (xy 153.591596 -153.687665) (xy 153.539302 -153.672309) (xy 153.489725 -153.649667)
			(xy 153.443876 -153.620201) (xy 153.402686 -153.584509) (xy 153.366995 -153.543319) (xy 153.33753 -153.497469)
			(xy 153.314889 -153.447892) (xy 153.299534 -153.395598) (xy 153.291778 -153.341651) (xy 153.291778 -153.287149)
			(xy 153.299534 -153.233202) (xy 153.314889 -153.180908) (xy 153.33753 -153.131331) (xy 153.366995 -153.085481)
			(xy 153.402686 -153.044291) (xy 153.443876 -153.008599) (xy 153.489725 -152.979133) (xy 153.539302 -152.956491)
			(xy 153.591596 -152.941135) (xy 153.645543 -152.933378) (xy 153.672794 -152.932892) (xy 153.700632 -152.933397)
			(xy 153.755717 -152.941489) (xy 153.80904 -152.957502) (xy 153.85947 -152.981095) (xy 153.905935 -153.011768)
			(xy 153.927048 -153.02992) (xy 153.93484 -153.03621) (xy 153.953728 -153.042802) (xy 153.973701 -153.041686)
			(xy 153.982928 -153.037794) (xy 154.06751 -152.996646) (xy 154.076319 -152.991831) (xy 154.089655 -152.976851)
			(xy 154.096269 -152.957918) (xy 154.096212 -152.947878) (xy 153.639012 -145.440654) (xy 153.63698 -145.379948)
			(xy 153.637138 -145.35546) (xy 153.639554 -145.306543) (xy 153.641806 -145.282158) (xy 153.811732 -143.559022)
			(xy 153.811732 -143.558514) (xy 154.320748 -137.50798) (xy 154.323549 -137.477534) (xy 154.332443 -137.417038)
			(xy 154.338528 -137.387076) (xy 154.357324 -137.298938) (xy 154.358894 -137.289161) (xy 154.355371 -137.269693)
			(xy 154.350466 -137.261092) (xy 154.346577 -137.255348) (xy 154.336263 -137.246077) (xy 154.330146 -137.242804)
			(xy 154.307985 -137.231251) (xy 154.266624 -137.203198) (xy 154.229287 -137.169977) (xy 154.196614 -137.132159)
			(xy 154.182572 -137.111486) (xy 154.180286 -137.10793) (xy 154.156156 -137.094722) (xy 154.147214 -137.090391)
			(xy 154.127488 -137.088184) (xy 154.117802 -137.090404) (xy 154.110944 -137.092436) (xy 154.083501 -137.108991)
			(xy 154.024972 -137.135105) (xy 153.963375 -137.152807) (xy 153.899911 -137.161749) (xy 153.867866 -137.162286)
			(xy 153.837883 -137.161794) (xy 153.778429 -137.153963) (xy 153.720506 -137.138439) (xy 153.665105 -137.115488)
			(xy 153.613173 -137.085503) (xy 153.565599 -137.048997) (xy 153.523197 -137.006593) (xy 153.486691 -136.959018)
			(xy 153.456707 -136.907086) (xy 153.433758 -136.851684) (xy 153.418235 -136.793761) (xy 153.410406 -136.734307)
			(xy 153.409904 -136.704324) (xy 153.409904 -135.840724) (xy 153.410394 -135.81074) (xy 153.418222 -135.751284)
			(xy 153.433743 -135.693359) (xy 153.456692 -135.637955) (xy 153.486676 -135.586021) (xy 153.523182 -135.538445)
			(xy 153.565587 -135.49604) (xy 153.613163 -135.459534) (xy 153.665097 -135.42955) (xy 153.720501 -135.406601)
			(xy 153.778426 -135.39108) (xy 153.837882 -135.383252) (xy 153.89785 -135.383252) (xy 153.957306 -135.39108)
			(xy 154.015231 -135.406601) (xy 154.070635 -135.42955) (xy 154.122569 -135.459534) (xy 154.170145 -135.49604)
			(xy 154.21255 -135.538445) (xy 154.249056 -135.586021) (xy 154.27904 -135.637955) (xy 154.301989 -135.693359)
			(xy 154.31751 -135.751284) (xy 154.325338 -135.81074) (xy 154.325828 -135.840724) (xy 154.325828 -136.48817)
			(xy 154.326188 -136.497551) (xy 154.332969 -136.515042) (xy 154.339036 -136.522206) (xy 154.347926 -136.53008)
			(xy 154.354276 -136.534108) (xy 154.368608 -136.538638) (xy 154.37612 -136.53897) (xy 154.390344 -136.536938)
			(xy 154.3939 -136.535922) (xy 154.411116 -136.531064) (xy 154.446226 -136.524196) (xy 154.464004 -136.522206)
			(xy 154.464258 -136.522206) (xy 154.475816 -136.520465) (xy 154.495636 -136.508122) (xy 154.507971 -136.488297)
			(xy 154.509724 -136.47674) (xy 154.56535 -135.91286) (xy 154.565604 -135.90778) (xy 154.560778 -134.95274)
			(xy 154.560778 -134.952232) (xy 154.466798 -128.292098) (xy 154.43581 -126.107698) (xy 154.435195 -126.096833)
			(xy 154.426023 -126.077122) (xy 154.409531 -126.062956) (xy 154.399234 -126.059438) (xy 154.398726 -126.059438)
			(xy 154.373104 -126.051814) (xy 154.324131 -126.030383) (xy 154.278632 -126.002322) (xy 154.237498 -125.968181)
			(xy 154.201536 -125.928629) (xy 154.186128 -125.906784) (xy 154.180286 -125.898402) (xy 154.156156 -125.885194)
			(xy 154.147236 -125.880789) (xy 154.127502 -125.878422) (xy 154.117802 -125.880622) (xy 154.110944 -125.882654)
			(xy 154.083501 -125.899208) (xy 154.024972 -125.925322) (xy 153.963374 -125.943022) (xy 153.899911 -125.951965)
			(xy 153.867866 -125.952504) (xy 153.837882 -125.952012) (xy 153.778428 -125.944181) (xy 153.720504 -125.928657)
			(xy 153.665102 -125.905707) (xy 153.613169 -125.875722) (xy 153.565594 -125.839216) (xy 153.52319 -125.796812)
			(xy 153.486682 -125.749238) (xy 153.456697 -125.697305) (xy 153.433745 -125.641903) (xy 153.418221 -125.58398)
			(xy 153.410389 -125.524526) (xy 153.409904 -125.494542) (xy 153.409904 -124.630942) (xy 153.41037 -124.600954)
			(xy 153.418194 -124.54149) (xy 153.433712 -124.483556) (xy 153.456659 -124.428142) (xy 153.486642 -124.376199)
			(xy 153.52315 -124.328613) (xy 153.565556 -124.2862) (xy 153.613136 -124.249685) (xy 153.665074 -124.219692)
			(xy 153.720483 -124.196736) (xy 153.778415 -124.181208) (xy 153.837878 -124.173375) (xy 153.867866 -124.17298)
			(xy 153.86812 -124.17298) (xy 153.899308 -124.173503) (xy 153.961106 -124.181971) (xy 154.021179 -124.198758)
			(xy 154.078414 -124.223556) (xy 154.105356 -124.239274) (xy 154.111198 -124.24283) (xy 154.13736 -124.250704)
			(xy 154.138122 -124.250704) (xy 154.169364 -124.233432) (xy 154.174517 -124.230366) (xy 154.183367 -124.222282)
			(xy 154.18689 -124.21743) (xy 154.203158 -124.194585) (xy 154.241311 -124.153483) (xy 154.285079 -124.11842)
			(xy 154.333516 -124.090155) (xy 154.359356 -124.079254) (xy 154.359864 -124.079254) (xy 154.366468 -124.07646)
			(xy 154.377644 -124.06757) (xy 154.397202 -124.039884) (xy 154.401613 -124.033198) (xy 154.406396 -124.01792)
			(xy 154.4066 -124.009912) (xy 154.38501 -122.489976) (xy 154.38501 -122.489722) (xy 154.384375 -122.479964)
			(xy 154.376698 -122.462) (xy 154.362842 -122.448228) (xy 154.354022 -122.444002) (xy 154.353768 -122.443748)
			(xy 154.32792 -122.432349) (xy 154.279621 -122.403048) (xy 154.236174 -122.366942) (xy 154.198528 -122.324821)
			(xy 154.182572 -122.301508) (xy 154.180286 -122.297952) (xy 154.156156 -122.284744) (xy 154.147214 -122.280412)
			(xy 154.127487 -122.278204) (xy 154.117802 -122.280426) (xy 154.110944 -122.282458) (xy 154.083501 -122.299012)
			(xy 154.024972 -122.325125) (xy 153.963374 -122.342826) (xy 153.899911 -122.351768) (xy 153.867866 -122.352308)
			(xy 153.837882 -122.351816) (xy 153.778428 -122.343985) (xy 153.720504 -122.328461) (xy 153.665101 -122.305511)
			(xy 153.613168 -122.275526) (xy 153.565592 -122.23902) (xy 153.523188 -122.196617) (xy 153.48668 -122.149042)
			(xy 153.456694 -122.097109) (xy 153.433742 -122.041708) (xy 153.418217 -121.983784) (xy 153.410385 -121.92433)
			(xy 153.409904 -121.894346) (xy 153.409904 -121.030746) (xy 153.41037 -121.000758) (xy 153.418193 -120.941293)
			(xy 153.43371 -120.883359) (xy 153.456657 -120.827945) (xy 153.486641 -120.776001) (xy 153.523148 -120.728415)
			(xy 153.565555 -120.686001) (xy 153.613134 -120.649486) (xy 153.665073 -120.619493) (xy 153.720483 -120.596536)
			(xy 153.778415 -120.581009) (xy 153.837878 -120.573175) (xy 153.867866 -120.572784) (xy 153.899086 -120.573292)
			(xy 153.96095 -120.581742) (xy 154.021089 -120.598531) (xy 154.078385 -120.623345) (xy 154.105356 -120.639078)
			(xy 154.117802 -120.644666) (xy 154.127499 -120.64697) (xy 154.147277 -120.644622) (xy 154.156156 -120.640094)
			(xy 154.180286 -120.626886) (xy 154.186128 -120.618504) (xy 154.203523 -120.593985) (xy 154.244758 -120.550241)
			(xy 154.292351 -120.513516) (xy 154.318462 -120.498616) (xy 154.319478 -120.498108) (xy 154.328622 -120.492774)
			(xy 154.348434 -120.460516) (xy 154.35194 -120.454284) (xy 154.35567 -120.440488) (xy 154.3558 -120.433338)
			(xy 154.300936 -116.532152) (xy 154.300936 -116.518182) (xy 154.302714 -116.458746) (xy 154.318208 -116.199158)
			(xy 154.318402 -116.189792) (xy 154.31282 -116.171928) (xy 154.301165 -116.157284) (xy 154.293316 -116.152168)
			(xy 154.210766 -116.107464) (xy 154.204345 -116.104199) (xy 154.19028 -116.101108) (xy 154.18308 -116.101368)
			(xy 154.168856 -116.102384) (xy 154.156664 -116.111274) (xy 154.141564 -116.122083) (xy 154.109629 -116.141037)
			(xy 154.09291 -116.14912) (xy 154.08275 -116.153946) (xy 154.075892 -116.162074) (xy 154.072372 -116.166419)
			(xy 154.067118 -116.176287) (xy 154.065478 -116.181632) (xy 154.045158 -116.256562) (xy 154.042991 -116.266203)
			(xy 154.045347 -116.285804) (xy 154.04973 -116.294662) (xy 154.05227 -116.298218) (xy 154.067795 -116.322043)
			(xy 154.092378 -116.37332) (xy 154.109084 -116.427675) (xy 154.117542 -116.483908) (xy 154.118056 -116.51234)
			(xy 154.118056 -116.512594) (xy 154.117571 -116.539847) (xy 154.109815 -116.593798) (xy 154.094461 -116.646096)
			(xy 154.071821 -116.695677) (xy 154.042355 -116.741532) (xy 154.006665 -116.782726) (xy 153.965475 -116.818423)
			(xy 153.919624 -116.847895) (xy 153.870047 -116.870542) (xy 153.817751 -116.885904) (xy 153.763801 -116.893667)
			(xy 153.736548 -116.894102) (xy 153.710263 -116.893661) (xy 153.658189 -116.886445) (xy 153.607597 -116.872156)
			(xy 153.559443 -116.851065) (xy 153.514635 -116.82357) (xy 153.474021 -116.790191) (xy 153.455878 -116.771166)
			(xy 153.45537 -116.770658) (xy 153.427938 -116.75872) (xy 153.423098 -116.756718) (xy 153.412854 -116.754543)
			(xy 153.407618 -116.754402) (xy 153.354278 -116.754402) (xy 153.349044 -116.754559) (xy 153.338803 -116.756734)
			(xy 153.333958 -116.75872) (xy 153.306526 -116.770658) (xy 153.306018 -116.771166) (xy 153.287876 -116.790193)
			(xy 153.24727 -116.823583) (xy 153.202464 -116.851083) (xy 153.154307 -116.872171) (xy 153.103711 -116.886448)
			(xy 153.051634 -116.893645) (xy 153.025348 -116.894102) (xy 152.998093 -116.893642) (xy 152.944138 -116.885891)
			(xy 152.891835 -116.870539) (xy 152.84225 -116.8479) (xy 152.796391 -116.818433) (xy 152.755194 -116.78274)
			(xy 152.719495 -116.741547) (xy 152.690023 -116.695692) (xy 152.667378 -116.64611) (xy 152.65202 -116.593809)
			(xy 152.644261 -116.539855) (xy 152.644261 -116.485345) (xy 152.65202 -116.431391) (xy 152.667378 -116.37909)
			(xy 152.690023 -116.329508) (xy 152.719495 -116.283653) (xy 152.755194 -116.24246) (xy 152.796391 -116.206767)
			(xy 152.84225 -116.1773) (xy 152.891835 -116.154661) (xy 152.944138 -116.139309) (xy 152.998093 -116.131558)
			(xy 153.025348 -116.131086) (xy 153.051633 -116.131527) (xy 153.103705 -116.138744) (xy 153.154295 -116.153035)
			(xy 153.202447 -116.174129) (xy 153.247251 -116.201628) (xy 153.28786 -116.235012) (xy 153.306018 -116.254022)
			(xy 153.306526 -116.25453) (xy 153.333958 -116.266468) (xy 153.338798 -116.268471) (xy 153.349042 -116.270647)
			(xy 153.354278 -116.270786) (xy 153.407618 -116.270786) (xy 153.412852 -116.27063) (xy 153.423093 -116.268454)
			(xy 153.427938 -116.266468) (xy 153.45537 -116.25453) (xy 153.455878 -116.254022) (xy 153.465585 -116.243642)
			(xy 153.48631 -116.224194) (xy 153.49728 -116.21516) (xy 153.505078 -116.209019) (xy 153.521215 -116.197455)
			(xy 153.529538 -116.192046) (xy 153.540346 -116.185241) (xy 153.562717 -116.172913) (xy 153.574242 -116.167408)
			(xy 153.584402 -116.162582) (xy 153.59126 -116.154454) (xy 153.594785 -116.150112) (xy 153.600048 -116.140247)
			(xy 153.601674 -116.134896) (xy 153.621994 -116.059966) (xy 153.624168 -116.050324) (xy 153.621819 -116.030718)
			(xy 153.617422 -116.021866) (xy 153.614882 -116.01831) (xy 153.599363 -115.994483) (xy 153.574793 -115.943204)
			(xy 153.5581 -115.888849) (xy 153.549653 -115.832618) (xy 153.549096 -115.804188) (xy 153.549096 -115.803934)
			(xy 153.549633 -115.775046) (xy 153.55835 -115.717932) (xy 153.575575 -115.662783) (xy 153.600915 -115.610861)
			(xy 153.633791 -115.56335) (xy 153.673451 -115.521337) (xy 153.71899 -115.485781) (xy 153.769368 -115.457494)
			(xy 153.823433 -115.437122) (xy 153.879951 -115.425132) (xy 153.90876 -115.422934) (xy 153.919936 -115.422426)
			(xy 153.929588 -115.417346) (xy 153.934155 -115.414717) (xy 153.94222 -115.407936) (xy 153.94559 -115.403884)
			(xy 153.969212 -115.373912) (xy 153.993088 -115.343686) (xy 153.996295 -115.339466) (xy 154.001042 -115.32999)
			(xy 154.002486 -115.32489) (xy 154.005026 -115.314476) (xy 154.002994 -115.303554) (xy 154.000164 -115.286806)
			(xy 153.997112 -115.252974) (xy 153.996898 -115.23599) (xy 153.996898 -115.235228) (xy 153.997345 -115.20881)
			(xy 154.004634 -115.15648) (xy 154.019077 -115.105657) (xy 154.040396 -115.057314) (xy 154.068184 -115.012376)
			(xy 154.101908 -114.971704) (xy 154.140924 -114.936076) (xy 154.184484 -114.906174) (xy 154.231754 -114.882571)
			(xy 154.28183 -114.865719) (xy 154.333752 -114.85594) (xy 154.360118 -114.854228) (xy 154.373834 -114.853212)
			(xy 154.387296 -114.83975) (xy 154.393603 -114.832909) (xy 154.40129 -114.815981) (xy 154.402282 -114.80673)
			(xy 154.458924 -113.869978) (xy 154.458924 -113.866422) (xy 154.448002 -111.5949) (xy 154.447361 -111.583646)
			(xy 154.437651 -111.563334) (xy 154.420187 -111.549128) (xy 154.409394 -111.545878) (xy 154.38152 -111.538394)
			(xy 154.328254 -111.516175) (xy 154.278945 -111.486185) (xy 154.234717 -111.449106) (xy 154.196582 -111.405787)
			(xy 154.18054 -111.381794) (xy 154.17477 -111.373723) (xy 154.158518 -111.362375) (xy 154.139185 -111.358003)
			(xy 154.119632 -111.361254) (xy 154.110944 -111.366046) (xy 154.083501 -111.3826) (xy 154.024972 -111.408714)
			(xy 153.963374 -111.426415) (xy 153.899911 -111.435358) (xy 153.867866 -111.435896) (xy 153.837882 -111.435404)
			(xy 153.778428 -111.427573) (xy 153.720505 -111.412049) (xy 153.665103 -111.389099) (xy 153.613171 -111.359114)
			(xy 153.565596 -111.322607) (xy 153.523193 -111.280204) (xy 153.486686 -111.232629) (xy 153.456701 -111.180697)
			(xy 153.433751 -111.125295) (xy 153.418227 -111.067372) (xy 153.410396 -111.007918) (xy 153.409904 -110.977934)
			(xy 153.409904 -110.114334) (xy 153.410392 -110.084347) (xy 153.418216 -110.024887) (xy 153.433733 -109.966956)
			(xy 153.45668 -109.911547) (xy 153.486663 -109.859606) (xy 153.523168 -109.812024) (xy 153.565573 -109.769613)
			(xy 153.61315 -109.7331) (xy 153.665086 -109.70311) (xy 153.720492 -109.680155) (xy 153.77842 -109.664629)
			(xy 153.83788 -109.656796) (xy 153.867866 -109.656372) (xy 153.899912 -109.656907) (xy 153.963378 -109.665841)
			(xy 154.024978 -109.683539) (xy 154.083507 -109.709656) (xy 154.110944 -109.726222) (xy 154.119615 -109.731084)
			(xy 154.139193 -109.734408) (xy 154.158561 -109.730023) (xy 154.174797 -109.718588) (xy 154.18054 -109.710474)
			(xy 154.196023 -109.687253) (xy 154.232697 -109.645185) (xy 154.275118 -109.60892) (xy 154.322377 -109.579233)
			(xy 154.373462 -109.556759) (xy 154.40025 -109.54893) (xy 154.410829 -109.545434) (xy 154.427783 -109.531018)
			(xy 154.437053 -109.510785) (xy 154.437588 -109.499654) (xy 154.430476 -107.990132) (xy 154.429901 -107.979227)
			(xy 154.420754 -107.959423) (xy 154.40422 -107.945192) (xy 154.3939 -107.941618) (xy 154.368984 -107.933829)
			(xy 154.32139 -107.912384) (xy 154.27716 -107.884657) (xy 154.237119 -107.851163) (xy 154.202013 -107.812528)
			(xy 154.18689 -107.79125) (xy 154.183334 -107.78617) (xy 154.174952 -107.77855) (xy 154.156156 -107.768136)
			(xy 154.147214 -107.763805) (xy 154.127488 -107.761597) (xy 154.117802 -107.763818) (xy 154.110944 -107.76585)
			(xy 154.083501 -107.782404) (xy 154.024972 -107.808518) (xy 153.963374 -107.826219) (xy 153.899911 -107.835161)
			(xy 153.867866 -107.8357) (xy 153.837882 -107.835208) (xy 153.778428 -107.827377) (xy 153.720505 -107.811853)
			(xy 153.665103 -107.788903) (xy 153.61317 -107.758918) (xy 153.565595 -107.722412) (xy 153.523191 -107.680008)
			(xy 153.486684 -107.632433) (xy 153.456699 -107.580501) (xy 153.433748 -107.525099) (xy 153.418224 -107.467176)
			(xy 153.410392 -107.407722) (xy 153.409904 -107.377738) (xy 153.409904 -106.514138) (xy 153.410371 -106.48415)
			(xy 153.418194 -106.424686) (xy 153.433713 -106.366753) (xy 153.45666 -106.31134) (xy 153.486644 -106.259397)
			(xy 153.523151 -106.211812) (xy 153.565557 -106.169399) (xy 153.613137 -106.132884) (xy 153.665075 -106.102892)
			(xy 153.720484 -106.079936) (xy 153.778416 -106.064408) (xy 153.837878 -106.056575) (xy 153.867866 -106.056176)
			(xy 153.899086 -106.056684) (xy 153.96095 -106.065134) (xy 154.02109 -106.081922) (xy 154.078386 -106.106737)
			(xy 154.105356 -106.12247) (xy 154.117802 -106.128058) (xy 154.127481 -106.130325) (xy 154.147214 -106.128087)
			(xy 154.156156 -106.12374) (xy 154.180286 -106.110532) (xy 154.182572 -106.106976) (xy 154.197588 -106.085)
			(xy 154.232741 -106.045036) (xy 154.273106 -106.010344) (xy 154.3179 -105.981597) (xy 154.366254 -105.959352)
			(xy 154.391614 -105.951274) (xy 154.39263 -105.950766) (xy 154.401012 -105.948226) (xy 154.42057 -105.921302)
			(xy 154.412696 -104.351074) (xy 154.40406 -104.345232) (xy 154.37866 -104.336596) (xy 154.34919 -104.325896)
			(xy 154.293944 -104.296266) (xy 154.244284 -104.258003) (xy 154.22245 -104.235504) (xy 154.212538 -104.22471)
			(xy 154.19423 -104.201823) (xy 154.185874 -104.189784) (xy 154.180286 -104.181656) (xy 154.156156 -104.168448)
			(xy 154.147237 -104.16404) (xy 154.127502 -104.16167) (xy 154.117802 -104.163876) (xy 154.110944 -104.165908)
			(xy 154.083531 -104.182366) (xy 154.025115 -104.208364) (xy 153.963656 -104.225998) (xy 153.900343 -104.234928)
			(xy 153.868374 -104.235504) (xy 153.86812 -104.235504) (xy 153.857452 -104.235758) (xy 153.827924 -104.234628)
			(xy 153.769511 -104.225704) (xy 153.712731 -104.209338) (xy 153.658528 -104.185804) (xy 153.607803 -104.155493)
			(xy 153.561399 -104.118907) (xy 153.520088 -104.076656) (xy 153.484555 -104.029441) (xy 153.455392 -103.978048)
			(xy 153.433083 -103.923329) (xy 153.417999 -103.866195) (xy 153.410391 -103.807596) (xy 153.409904 -103.77805)
			(xy 153.409904 -102.914196) (xy 153.410394 -102.884239) (xy 153.418212 -102.824838) (xy 153.433714 -102.766965)
			(xy 153.456635 -102.71161) (xy 153.486582 -102.659718) (xy 153.523045 -102.612178) (xy 153.565399 -102.569802)
			(xy 153.61292 -102.533315) (xy 153.664796 -102.50334) (xy 153.72014 -102.48039) (xy 153.778005 -102.464858)
			(xy 153.837402 -102.457009) (xy 153.867358 -102.456488) (xy 153.867866 -102.456488) (xy 153.867866 -102.456234)
			(xy 153.899093 -102.456782) (xy 153.960963 -102.465305) (xy 154.0211 -102.482157) (xy 154.07839 -102.507026)
			(xy 154.105356 -102.522782) (xy 154.114754 -102.528624) (xy 154.120196 -102.531138) (xy 154.131875 -102.533828)
			(xy 154.137868 -102.533958) (xy 154.169618 -102.516686) (xy 154.174712 -102.513692) (xy 154.183449 -102.50574)
			(xy 154.18689 -102.500938) (xy 154.202884 -102.478416) (xy 154.240322 -102.437797) (xy 154.283234 -102.403014)
			(xy 154.330721 -102.374794) (xy 154.356054 -102.363778) (xy 154.360372 -102.362) (xy 154.371232 -102.355535)
			(xy 154.385354 -102.334611) (xy 154.387296 -102.322122) (xy 154.38755 -102.316026) (xy 154.354784 -100.772722)
			(xy 154.354459 -100.76588) (xy 154.35059 -100.752746) (xy 154.347164 -100.746814) (xy 154.330654 -100.720906)
			(xy 154.321002 -100.711762) (xy 154.315668 -100.708968) (xy 154.293935 -100.696357) (xy 154.253678 -100.666286)
			(xy 154.217719 -100.631189) (xy 154.201876 -100.611686) (xy 154.182572 -100.584762) (xy 154.180286 -100.58146)
			(xy 154.156156 -100.568252) (xy 154.147215 -100.56392) (xy 154.127487 -100.561711) (xy 154.117802 -100.563934)
			(xy 154.110944 -100.565966) (xy 154.083501 -100.58252) (xy 154.024971 -100.608633) (xy 153.963374 -100.626333)
			(xy 153.899911 -100.635275) (xy 153.867866 -100.635816) (xy 153.867358 -100.635816) (xy 153.854758 -100.635724)
			(xy 153.829598 -100.634329) (xy 153.817066 -100.633022) (xy 153.786908 -100.629161) (xy 153.727906 -100.614488)
			(xy 153.671363 -100.592137) (xy 153.618276 -100.5625) (xy 153.569577 -100.526099) (xy 153.526123 -100.483574)
			(xy 153.488679 -100.435673) (xy 153.457903 -100.383238) (xy 153.434335 -100.327192) (xy 153.418392 -100.26852)
			(xy 153.410352 -100.208254) (xy 153.409904 -100.177854) (xy 153.409904 -99.314254) (xy 153.410397 -99.284271)
			(xy 153.418229 -99.224818) (xy 153.433754 -99.166896) (xy 153.456705 -99.111496) (xy 153.48669 -99.059565)
			(xy 153.523197 -99.011991) (xy 153.5656 -98.969589) (xy 153.613175 -98.933084) (xy 153.665107 -98.9031)
			(xy 153.720508 -98.88015) (xy 153.77843 -98.864627) (xy 153.837883 -98.856796) (xy 153.867866 -98.856292)
			(xy 153.902312 -98.856909) (xy 153.970425 -98.867233) (xy 154.003502 -98.876866) (xy 154.027123 -98.884518)
			(xy 154.072691 -98.904247) (xy 154.094434 -98.916236) (xy 154.102798 -98.920623) (xy 154.121455 -98.923474)
			(xy 154.130756 -98.921824) (xy 154.160728 -98.914966) (xy 154.169767 -98.912527) (xy 154.185383 -98.902231)
			(xy 154.191208 -98.8949) (xy 154.211766 -98.867325) (xy 154.261095 -98.819404) (xy 154.289252 -98.79965)
			(xy 154.299261 -98.792177) (xy 154.31109 -98.770209) (xy 154.311858 -98.75774) (xy 154.304238 -98.39452)
			(xy 154.303617 -98.384797) (xy 154.296024 -98.366872) (xy 154.282304 -98.353063) (xy 154.264429 -98.345353)
			(xy 154.254708 -98.344736) (xy 152.15743 -98.289872) (xy 152.148064 -98.290054) (xy 152.130439 -98.296345)
			(xy 152.116271 -98.308573) (xy 152.10747 -98.32509) (xy 152.105868 -98.334322) (xy 151.942038 -99.658424)
			(xy 151.93264 -99.71913) (xy 151.7777 -100.544122) (xy 151.776265 -100.554133) (xy 151.780462 -100.573902)
			(xy 151.785828 -100.582476) (xy 151.787352 -100.584508) (xy 151.826976 -100.63607) (xy 151.830315 -100.640152)
			(xy 151.838392 -100.646928) (xy 151.842978 -100.649532) (xy 151.869394 -100.66401) (xy 151.879808 -100.665026)
			(xy 151.910304 -100.668476) (xy 151.970054 -100.682504) (xy 152.027392 -100.704392) (xy 152.081289 -100.733748)
			(xy 152.13078 -100.770044) (xy 152.174975 -100.81263) (xy 152.213081 -100.860741) (xy 152.244415 -100.913513)
			(xy 152.268414 -100.97) (xy 152.284647 -101.029188) (xy 152.292824 -101.090015) (xy 152.29332 -101.120702)
			(xy 152.29332 -101.984302) (xy 152.292831 -102.014264) (xy 152.285014 -102.073676) (xy 152.269514 -102.131561)
			(xy 152.246596 -102.186929) (xy 152.216652 -102.238835) (xy 152.180192 -102.286392) (xy 152.137841 -102.328786)
			(xy 152.090322 -102.365294) (xy 152.038446 -102.395291) (xy 151.983101 -102.418265) (xy 151.925232 -102.433823)
			(xy 151.865828 -102.441701) (xy 151.835866 -102.442264) (xy 151.828246 -102.442264) (xy 151.799468 -102.441368)
			(xy 151.742468 -102.433234) (xy 151.686938 -102.418019) (xy 151.633753 -102.395962) (xy 151.608536 -102.382066)
			(xy 151.600154 -102.377727) (xy 151.581492 -102.374995) (xy 151.572214 -102.376732) (xy 151.522176 -102.387908)
			(xy 151.516334 -102.396798) (xy 151.497245 -102.423631) (xy 151.451391 -102.470885) (xy 151.425148 -102.490778)
			(xy 151.418285 -102.49677) (xy 151.408922 -102.512384) (xy 151.40686 -102.521258) (xy 151.39924 -102.56139)
			(xy 151.398732 -102.56393) (xy 151.173688 -104.19715) (xy 151.172687 -104.208296) (xy 151.179282 -104.229652)
			(xy 151.186388 -104.238298) (xy 151.194262 -104.246934) (xy 151.197757 -104.250626) (xy 151.20595 -104.256642)
			(xy 151.210518 -104.258872) (xy 151.219916 -104.26319) (xy 151.230838 -104.26319) (xy 151.260599 -104.263982)
			(xy 151.319548 -104.272324) (xy 151.376917 -104.288239) (xy 151.431739 -104.311458) (xy 151.483088 -104.341588)
			(xy 151.530097 -104.378122) (xy 151.571972 -104.420442) (xy 151.608007 -104.467834) (xy 151.637593 -104.519498)
			(xy 151.660231 -104.574562) (xy 151.675539 -104.632097) (xy 151.683258 -104.69113) (xy 151.68372 -104.720898)
			(xy 151.68372 -105.584498) (xy 151.683251 -105.614483) (xy 151.675423 -105.673939) (xy 151.659901 -105.731865)
			(xy 151.636951 -105.787269) (xy 151.606965 -105.839204) (xy 151.570456 -105.886779) (xy 151.528049 -105.929182)
			(xy 151.48047 -105.965687) (xy 151.428533 -105.995669) (xy 151.373127 -106.018614) (xy 151.3152 -106.034131)
			(xy 151.255743 -106.041954) (xy 151.225758 -106.04246) (xy 151.222202 -106.04246) (xy 151.190244 -106.041664)
			(xy 151.127017 -106.032229) (xy 151.096218 -106.023664) (xy 151.085042 -106.020362) (xy 151.07412 -106.02214)
			(xy 151.068628 -106.023147) (xy 151.058248 -106.027255) (xy 151.053546 -106.030268) (xy 150.991316 -106.072686)
			(xy 150.987506 -106.075226) (xy 150.983442 -106.078528) (xy 150.901654 -107.863386) (xy 150.901679 -107.872501)
			(xy 150.907362 -107.889806) (xy 150.9187 -107.904061) (xy 150.926292 -107.909106) (xy 150.949914 -107.92333)
			(xy 150.959348 -107.927913) (xy 150.980217 -107.929766) (xy 150.9903 -107.926886) (xy 150.993348 -107.92587)
			(xy 150.99919 -107.922822) (xy 150.999698 -107.922568) (xy 151.029414 -107.906395) (xy 151.092524 -107.88202)
			(xy 151.158537 -107.86721) (xy 151.19223 -107.864148) (xy 151.202898 -107.863386) (xy 151.225758 -107.862878)
			(xy 151.255733 -107.863365) (xy 151.31517 -107.871182) (xy 151.373078 -107.886689) (xy 151.428468 -107.909621)
			(xy 151.480392 -107.939584) (xy 151.527962 -107.976067) (xy 151.570364 -108.018445) (xy 151.606874 -108.065995)
			(xy 151.636866 -108.117902) (xy 151.659828 -108.173279) (xy 151.675368 -108.231179) (xy 151.683218 -108.290612)
			(xy 151.68372 -108.320586) (xy 151.68372 -109.18444) (xy 151.683266 -109.213608) (xy 151.675863 -109.271472)
			(xy 151.66117 -109.327927) (xy 151.639424 -109.382057) (xy 151.610978 -109.432987) (xy 151.576293 -109.479891)
			(xy 151.53593 -109.522009) (xy 151.490544 -109.558658) (xy 151.440871 -109.589245) (xy 151.387714 -109.613274)
			(xy 151.331935 -109.630356) (xy 151.274439 -109.640214) (xy 151.245316 -109.641894) (xy 151.234394 -109.642402)
			(xy 151.225758 -109.642402) (xy 151.196083 -109.641912) (xy 151.137233 -109.634215) (xy 151.079868 -109.618993)
			(xy 151.024944 -109.596501) (xy 150.998936 -109.582204) (xy 150.990553 -109.577869) (xy 150.971893 -109.57514)
			(xy 150.962614 -109.57687) (xy 150.932134 -109.583728) (xy 150.923151 -109.586177) (xy 150.907651 -109.596466)
			(xy 150.901908 -109.603794) (xy 150.88362 -109.627416) (xy 150.872248 -109.640652) (xy 150.847442 -109.665201)
			(xy 150.83409 -109.676438) (xy 150.833582 -109.676946) (xy 150.826724 -109.682534) (xy 150.81758 -109.70133)
			(xy 150.74138 -111.364268) (xy 150.74436 -111.368369) (xy 150.751654 -111.375405) (xy 150.755858 -111.378238)
			(xy 150.76932 -111.385604) (xy 150.769828 -111.385604) (xy 150.79574 -111.399966) (xy 150.843172 -111.435461)
			(xy 150.884544 -111.477863) (xy 150.902162 -111.501682) (xy 150.907915 -111.508961) (xy 150.923418 -111.519125)
			(xy 150.932388 -111.521494) (xy 150.962614 -111.528352) (xy 150.971892 -111.529996) (xy 150.990519 -111.527255)
			(xy 150.998936 -111.523018) (xy 151.029924 -111.507016) (xy 151.060676 -111.493098) (xy 151.12525 -111.473438)
			(xy 151.192009 -111.463468) (xy 151.225758 -111.46282) (xy 151.255746 -111.463286) (xy 151.315209 -111.47111)
			(xy 151.373143 -111.486628) (xy 151.428555 -111.509575) (xy 151.480497 -111.539559) (xy 151.528082 -111.576067)
			(xy 151.570494 -111.618473) (xy 151.607008 -111.666053) (xy 151.636998 -111.717992) (xy 151.659953 -111.773401)
			(xy 151.675479 -111.831332) (xy 151.68331 -111.890794) (xy 151.68372 -111.920782) (xy 151.68372 -112.784382)
			(xy 151.683252 -112.814367) (xy 151.675426 -112.873825) (xy 151.659905 -112.931753) (xy 151.636956 -112.987159)
			(xy 151.60697 -113.039095) (xy 151.570462 -113.086673) (xy 151.528055 -113.129077) (xy 151.480475 -113.165584)
			(xy 151.428538 -113.195566) (xy 151.37313 -113.218513) (xy 151.315202 -113.234031) (xy 151.255743 -113.241854)
			(xy 151.225758 -113.242344) (xy 151.199586 -113.241981) (xy 151.147584 -113.236004) (xy 151.096604 -113.224133)
			(xy 151.071834 -113.215674) (xy 151.048559 -113.206967) (xy 151.003885 -113.185197) (xy 150.98268 -113.17224)
			(xy 150.982426 -113.17224) (xy 150.974314 -113.167638) (xy 150.956029 -113.164048) (xy 150.937674 -113.167259)
			(xy 150.921693 -113.176842) (xy 150.915624 -113.183924) (xy 150.91283 -113.187734) (xy 150.912068 -113.189004)
			(xy 150.897931 -113.21014) (xy 150.864932 -113.248827) (xy 150.827088 -113.28279) (xy 150.785069 -113.311426)
			(xy 150.73962 -113.334228) (xy 150.715726 -113.342928) (xy 150.715218 -113.342928) (xy 150.708379 -113.345613)
			(xy 150.696513 -113.354267) (xy 150.69185 -113.359946) (xy 150.675086 -113.381536) (xy 150.670555 -113.388002)
			(xy 150.66527 -113.402872) (xy 150.664672 -113.410746) (xy 150.573486 -116.19357) (xy 150.573486 -116.19611)
			(xy 150.601665 -117.7544) (xy 153.187906 -117.7544) (xy 153.191977 -117.698778) (xy 153.204103 -117.644341)
			(xy 153.224026 -117.59225) (xy 153.251322 -117.543615) (xy 153.285408 -117.499472) (xy 153.325557 -117.460763)
			(xy 153.370915 -117.428312) (xy 153.420515 -117.402811) (xy 153.473299 -117.384804) (xy 153.528142 -117.374674)
			(xy 153.583876 -117.372637) (xy 153.639313 -117.378737) (xy 153.69327 -117.392843) (xy 153.744599 -117.414655)
			(xy 153.792205 -117.443709) (xy 153.835073 -117.479384) (xy 153.87229 -117.520921) (xy 153.903063 -117.567434)
			(xy 153.926735 -117.617931) (xy 153.942803 -117.671338) (xy 153.950923 -117.726514) (xy 153.951432 -117.7544)
			(xy 153.950923 -117.782286) (xy 153.942803 -117.837462) (xy 153.926735 -117.890869) (xy 153.903063 -117.941366)
			(xy 153.87229 -117.987879) (xy 153.835073 -118.029416) (xy 153.792205 -118.065091) (xy 153.744599 -118.094145)
			(xy 153.69327 -118.115957) (xy 153.639313 -118.130063) (xy 153.583876 -118.136163) (xy 153.528142 -118.134126)
			(xy 153.473299 -118.123996) (xy 153.420515 -118.105989) (xy 153.370915 -118.080488) (xy 153.325557 -118.048037)
			(xy 153.285408 -118.009328) (xy 153.251322 -117.965185) (xy 153.224026 -117.91655) (xy 153.204103 -117.864459)
			(xy 153.191977 -117.810022) (xy 153.187906 -117.7544) (xy 150.601665 -117.7544) (xy 150.616666 -118.583964)
			(xy 150.617173 -118.592776) (xy 150.623415 -118.609272) (xy 150.628858 -118.616222) (xy 150.652734 -118.644162)
			(xy 150.666704 -118.652544) (xy 150.674832 -118.654322) (xy 150.70264 -118.661073) (xy 150.755988 -118.681767)
			(xy 150.805654 -118.710186) (xy 150.850528 -118.745692) (xy 150.889605 -118.787492) (xy 150.906226 -118.810786)
			(xy 150.90972 -118.815663) (xy 150.918582 -118.823744) (xy 150.923752 -118.826788) (xy 150.954994 -118.84406)
			(xy 150.955756 -118.84406) (xy 150.981918 -118.836186) (xy 150.98776 -118.83263) (xy 151.014732 -118.8169)
			(xy 151.07203 -118.792094) (xy 151.132168 -118.775307) (xy 151.194031 -118.766853) (xy 151.22525 -118.766336)
			(xy 151.225758 -118.766336) (xy 151.255746 -118.766802) (xy 151.315208 -118.774626) (xy 151.373141 -118.790144)
			(xy 151.428552 -118.813091) (xy 151.480493 -118.843076) (xy 151.528077 -118.879583) (xy 151.570487 -118.92199)
			(xy 151.607 -118.96957) (xy 151.636989 -119.021509) (xy 151.659942 -119.076918) (xy 151.675466 -119.134849)
			(xy 151.683295 -119.194311) (xy 151.68372 -119.224298) (xy 151.68372 -120.087898) (xy 151.683251 -120.117883)
			(xy 151.675423 -120.177339) (xy 151.659901 -120.235265) (xy 151.636951 -120.290669) (xy 151.606965 -120.342604)
			(xy 151.570456 -120.390179) (xy 151.528049 -120.432582) (xy 151.48047 -120.469087) (xy 151.428533 -120.499069)
			(xy 151.373127 -120.522014) (xy 151.3152 -120.537531) (xy 151.255743 -120.545354) (xy 151.225758 -120.54586)
			(xy 151.22525 -120.54586) (xy 151.194032 -120.545331) (xy 151.132175 -120.536858) (xy 151.072037 -120.520076)
			(xy 151.01473 -120.495295) (xy 150.98776 -120.479566) (xy 150.981918 -120.47601) (xy 150.955756 -120.46839)
			(xy 150.954994 -120.46839) (xy 150.918418 -120.488456) (xy 150.909782 -120.49633) (xy 150.906226 -120.50141)
			(xy 150.890664 -120.523269) (xy 150.854398 -120.562813) (xy 150.812951 -120.596889) (xy 150.767142 -120.624827)
			(xy 150.717872 -120.646075) (xy 150.692104 -120.653556) (xy 150.679658 -120.65889) (xy 150.672159 -120.663739)
			(xy 150.660863 -120.677558) (xy 150.654989 -120.694412) (xy 150.654766 -120.70334) (xy 150.654766 -120.703594)
			(xy 150.681944 -122.218704) (xy 150.682452 -122.225562) (xy 150.684227 -122.234659) (xy 150.693329 -122.250785)
			(xy 150.707595 -122.262592) (xy 150.716234 -122.265948) (xy 150.73999 -122.274591) (xy 150.785167 -122.297272)
			(xy 150.826949 -122.325728) (xy 150.864602 -122.359459) (xy 150.897464 -122.397872) (xy 150.91156 -122.418856)
			(xy 150.91283 -122.420888) (xy 150.917656 -122.426984) (xy 150.925194 -122.434775) (xy 150.944927 -122.443707)
			(xy 150.955756 -122.444256) (xy 150.981918 -122.436636) (xy 150.98776 -122.43308) (xy 151.014757 -122.417228)
			(xy 151.072161 -122.392245) (xy 151.132436 -122.375324) (xy 151.194455 -122.36678) (xy 151.225758 -122.366278)
			(xy 151.226266 -122.366278) (xy 151.238865 -122.366371) (xy 151.264026 -122.367768) (xy 151.276558 -122.369072)
			(xy 151.306703 -122.372933) (xy 151.365682 -122.387599) (xy 151.422203 -122.409938) (xy 151.475273 -122.439556)
			(xy 151.523958 -122.475934) (xy 151.567404 -122.518432) (xy 151.604847 -122.566303) (xy 151.635629 -122.618706)
			(xy 151.659209 -122.67472) (xy 151.675173 -122.733361) (xy 151.68324 -122.793599) (xy 151.68372 -122.823986)
			(xy 151.68372 -123.68784) (xy 151.683248 -123.717818) (xy 151.675414 -123.777261) (xy 151.659887 -123.835172)
			(xy 151.636932 -123.89056) (xy 151.606942 -123.942476) (xy 151.57043 -123.990033) (xy 151.528021 -124.032416)
			(xy 151.480442 -124.068898) (xy 151.428506 -124.098857) (xy 151.373104 -124.121778) (xy 151.315184 -124.137269)
			(xy 151.255736 -124.145066) (xy 151.225758 -124.145548) (xy 151.196091 -124.145091) (xy 151.13725 -124.137457)
			(xy 151.079884 -124.122298) (xy 151.024954 -124.099867) (xy 150.998936 -124.085604) (xy 150.990553 -124.081269)
			(xy 150.971893 -124.07854) (xy 150.962614 -124.08027) (xy 150.932388 -124.087128) (xy 150.923428 -124.08952)
			(xy 150.907929 -124.099677) (xy 150.902162 -124.10694) (xy 150.886499 -124.128105) (xy 150.850305 -124.166346)
			(xy 150.830026 -124.18314) (xy 150.811254 -124.197758) (xy 150.77075 -124.222726) (xy 150.749254 -124.232924)
			(xy 150.740811 -124.237103) (xy 150.727556 -124.250472) (xy 150.720033 -124.26773) (xy 150.719282 -124.27712)
			(xy 150.789835 -128.189736) (xy 151.62733 -128.189736) (xy 151.631401 -128.134114) (xy 151.643527 -128.079677)
			(xy 151.66345 -128.027586) (xy 151.690746 -127.978951) (xy 151.724832 -127.934808) (xy 151.764981 -127.896099)
			(xy 151.810339 -127.863648) (xy 151.859939 -127.838147) (xy 151.912723 -127.82014) (xy 151.967566 -127.81001)
			(xy 152.0233 -127.807973) (xy 152.078737 -127.814073) (xy 152.132694 -127.828179) (xy 152.184023 -127.849991)
			(xy 152.231629 -127.879045) (xy 152.274497 -127.91472) (xy 152.311714 -127.956257) (xy 152.342487 -128.00277)
			(xy 152.366159 -128.053267) (xy 152.382227 -128.106674) (xy 152.390347 -128.16185) (xy 152.390856 -128.189736)
			(xy 152.390347 -128.217622) (xy 152.382227 -128.272798) (xy 152.366159 -128.326205) (xy 152.342487 -128.376702)
			(xy 152.311714 -128.423215) (xy 152.274497 -128.464752) (xy 152.231629 -128.500427) (xy 152.184023 -128.529481)
			(xy 152.132694 -128.551293) (xy 152.078737 -128.565399) (xy 152.0233 -128.571499) (xy 151.967566 -128.569462)
			(xy 151.912723 -128.559332) (xy 151.859939 -128.541325) (xy 151.810339 -128.515824) (xy 151.764981 -128.483373)
			(xy 151.724832 -128.444664) (xy 151.690746 -128.400521) (xy 151.66345 -128.351886) (xy 151.643527 -128.299795)
			(xy 151.631401 -128.245358) (xy 151.62733 -128.189736) (xy 150.789835 -128.189736) (xy 150.820628 -129.897378)
			(xy 150.820839 -129.902768) (xy 150.823265 -129.913276) (xy 150.825454 -129.918206) (xy 150.838662 -129.945892)
			(xy 150.846282 -129.952496) (xy 150.866348 -129.972054) (xy 150.878127 -129.98458) (xy 150.899623 -130.011418)
			(xy 150.909274 -130.025648) (xy 150.912576 -130.030728) (xy 150.962614 -130.041904) (xy 150.971893 -130.043547)
			(xy 150.99052 -130.040808) (xy 150.998936 -130.03657) (xy 151.02494 -130.022262) (xy 151.079856 -129.999742)
			(xy 151.137225 -129.984517) (xy 151.196081 -129.976844) (xy 151.225758 -129.976372) (xy 151.255745 -129.976839)
			(xy 151.315205 -129.984662) (xy 151.373136 -130.00018) (xy 151.428545 -130.023128) (xy 151.480485 -130.053113)
			(xy 151.528065 -130.089621) (xy 151.570473 -130.132029) (xy 151.606982 -130.179609) (xy 151.636968 -130.231548)
			(xy 151.659917 -130.286956) (xy 151.675436 -130.344887) (xy 151.683261 -130.404347) (xy 151.68372 -130.434334)
			(xy 151.68372 -131.297934) (xy 151.683249 -131.327917) (xy 151.675417 -131.38737) (xy 151.659892 -131.445292)
			(xy 151.63694 -131.500692) (xy 151.606952 -131.552622) (xy 151.570443 -131.600194) (xy 151.528037 -131.642593)
			(xy 151.480459 -131.679094) (xy 151.428524 -131.709073) (xy 151.37312 -131.732017) (xy 151.315195 -131.747532)
			(xy 151.255741 -131.755354) (xy 151.225758 -131.755896) (xy 151.197023 -131.755453) (xy 151.140009 -131.748227)
			(xy 151.084352 -131.733906) (xy 151.03093 -131.712717) (xy 151.00554 -131.699254) (xy 151.005032 -131.699254)
			(xy 151.004524 -131.699) (xy 150.998801 -131.696039) (xy 150.986327 -131.692819) (xy 150.979886 -131.69265)
			(xy 150.966424 -131.692904) (xy 150.88997 -131.738878) (xy 150.884128 -131.743196) (xy 150.875492 -131.750308)
			(xy 150.87473 -131.751324) (xy 150.868634 -131.757928) (xy 150.86838 -131.758182) (xy 150.858474 -131.783328)
			(xy 150.856835 -131.78798) (xy 150.855177 -131.7977) (xy 150.855172 -131.802632) (xy 150.878513 -133.104382)
			(xy 153.409904 -133.104382) (xy 153.409904 -132.240782) (xy 153.410394 -132.210798) (xy 153.418222 -132.151342)
			(xy 153.433743 -132.093417) (xy 153.456692 -132.038013) (xy 153.486676 -131.986079) (xy 153.523182 -131.938503)
			(xy 153.565587 -131.896098) (xy 153.613163 -131.859592) (xy 153.665097 -131.829608) (xy 153.720501 -131.806659)
			(xy 153.778426 -131.791138) (xy 153.837882 -131.78331) (xy 153.89785 -131.78331) (xy 153.957306 -131.791138)
			(xy 154.015231 -131.806659) (xy 154.070635 -131.829608) (xy 154.122569 -131.859592) (xy 154.170145 -131.896098)
			(xy 154.21255 -131.938503) (xy 154.249056 -131.986079) (xy 154.27904 -132.038013) (xy 154.301989 -132.093417)
			(xy 154.31751 -132.151342) (xy 154.325338 -132.210798) (xy 154.325828 -132.240782) (xy 154.325828 -133.104382)
			(xy 154.325338 -133.134366) (xy 154.31751 -133.193822) (xy 154.301989 -133.251747) (xy 154.27904 -133.307151)
			(xy 154.249056 -133.359085) (xy 154.21255 -133.406661) (xy 154.170145 -133.449066) (xy 154.122569 -133.485572)
			(xy 154.070635 -133.515556) (xy 154.015231 -133.538505) (xy 153.957306 -133.554026) (xy 153.89785 -133.561854)
			(xy 153.837882 -133.561854) (xy 153.778426 -133.554026) (xy 153.720501 -133.538505) (xy 153.665097 -133.515556)
			(xy 153.613163 -133.485572) (xy 153.565587 -133.449066) (xy 153.523182 -133.406661) (xy 153.486676 -133.359085)
			(xy 153.456692 -133.307151) (xy 153.433743 -133.251747) (xy 153.418222 -133.193822) (xy 153.410394 -133.134366)
			(xy 153.409904 -133.104382) (xy 150.878513 -133.104382) (xy 150.88616 -133.530848) (xy 150.886579 -133.537349)
			(xy 150.890295 -133.54983) (xy 150.893526 -133.555486) (xy 150.89677 -133.560412) (xy 150.905111 -133.568749)
			(xy 150.910036 -133.571996) (xy 150.982934 -133.617208) (xy 150.988354 -133.62038) (xy 151.000305 -133.624223)
			(xy 151.006556 -133.624828) (xy 151.019002 -133.62559) (xy 151.03094 -133.620002) (xy 151.061493 -133.606334)
			(xy 151.125574 -133.587013) (xy 151.191785 -133.577223) (xy 151.22525 -133.576568) (xy 151.225504 -133.576568)
			(xy 151.236426 -133.576314) (xy 151.265947 -133.577454) (xy 151.324345 -133.586397) (xy 151.381107 -133.602777)
			(xy 151.435292 -133.62632) (xy 151.485998 -133.656637) (xy 151.532385 -133.693224) (xy 151.57368 -133.735473)
			(xy 151.609199 -133.782682) (xy 151.638351 -133.834067) (xy 151.660652 -133.888775) (xy 151.675732 -133.945896)
			(xy 151.683341 -134.004483) (xy 151.68372 -134.034022) (xy 151.68372 -134.897876) (xy 151.683232 -134.927834)
			(xy 151.675417 -134.987239) (xy 151.659918 -135.045117) (xy 151.636999 -135.100477) (xy 151.607052 -135.152373)
			(xy 151.57059 -135.199918) (xy 151.528236 -135.242299) (xy 151.480714 -135.278791) (xy 151.428837 -135.30877)
			(xy 151.373491 -135.331724) (xy 151.315624 -135.34726) (xy 151.256224 -135.355113) (xy 151.226266 -135.355584)
			(xy 151.225758 -135.355584) (xy 151.225758 -135.355838) (xy 151.197231 -135.355365) (xy 151.140625 -135.348213)
			(xy 151.085343 -135.3341) (xy 151.058626 -135.324088) (xy 151.046712 -135.320109) (xy 151.021796 -135.323045)
			(xy 151.011128 -135.329676) (xy 150.94204 -135.377936) (xy 150.932109 -135.385659) (xy 150.920672 -135.408034)
			(xy 150.920196 -135.420608) (xy 150.965154 -137.9093) (xy 150.965154 -137.909808) (xy 150.965408 -137.927334)
			(xy 150.965408 -138.210544) (xy 150.965662 -138.215116) (xy 151.15161 -140.326364) (xy 151.791922 -140.326364)
			(xy 151.795993 -140.270742) (xy 151.808119 -140.216305) (xy 151.828042 -140.164214) (xy 151.855338 -140.115579)
			(xy 151.889424 -140.071436) (xy 151.929573 -140.032727) (xy 151.974931 -140.000276) (xy 152.024531 -139.974775)
			(xy 152.077315 -139.956768) (xy 152.132158 -139.946638) (xy 152.187892 -139.944601) (xy 152.243329 -139.950701)
			(xy 152.297286 -139.964807) (xy 152.348615 -139.986619) (xy 152.396221 -140.015673) (xy 152.439089 -140.051348)
			(xy 152.476306 -140.092885) (xy 152.507079 -140.139398) (xy 152.530751 -140.189895) (xy 152.546819 -140.243302)
			(xy 152.554939 -140.298478) (xy 152.555448 -140.326364) (xy 152.554939 -140.35425) (xy 152.546819 -140.409426)
			(xy 152.530751 -140.462833) (xy 152.507079 -140.51333) (xy 152.476306 -140.559843) (xy 152.439089 -140.60138)
			(xy 152.396221 -140.637055) (xy 152.348615 -140.666109) (xy 152.297286 -140.687921) (xy 152.243329 -140.702027)
			(xy 152.187892 -140.708127) (xy 152.132158 -140.70609) (xy 152.077315 -140.69596) (xy 152.024531 -140.677953)
			(xy 151.974931 -140.652452) (xy 151.929573 -140.620001) (xy 151.889424 -140.581292) (xy 151.855338 -140.537149)
			(xy 151.828042 -140.488514) (xy 151.808119 -140.436423) (xy 151.795993 -140.381986) (xy 151.791922 -140.326364)
			(xy 151.15161 -140.326364) (xy 152.653471 -157.3784) (xy 153.290776 -157.3784) (xy 153.294847 -157.322778)
			(xy 153.306973 -157.268341) (xy 153.326896 -157.21625) (xy 153.354192 -157.167615) (xy 153.388278 -157.123472)
			(xy 153.428427 -157.084763) (xy 153.473785 -157.052312) (xy 153.523385 -157.026811) (xy 153.576169 -157.008804)
			(xy 153.631012 -156.998674) (xy 153.686746 -156.996637) (xy 153.742183 -157.002737) (xy 153.79614 -157.016843)
			(xy 153.847469 -157.038655) (xy 153.895075 -157.067709) (xy 153.937943 -157.103384) (xy 153.97516 -157.144921)
			(xy 154.005933 -157.191434) (xy 154.029605 -157.241931) (xy 154.045673 -157.295338) (xy 154.053793 -157.350514)
			(xy 154.054302 -157.3784) (xy 154.053793 -157.406286) (xy 154.045673 -157.461462) (xy 154.029605 -157.514869)
			(xy 154.005933 -157.565366) (xy 153.97516 -157.611879) (xy 153.937943 -157.653416) (xy 153.895075 -157.689091)
			(xy 153.847469 -157.718145) (xy 153.79614 -157.739957) (xy 153.742183 -157.754063) (xy 153.686746 -157.760163)
			(xy 153.631012 -157.758126) (xy 153.576169 -157.747996) (xy 153.523385 -157.729989) (xy 153.473785 -157.704488)
			(xy 153.428427 -157.672037) (xy 153.388278 -157.633328) (xy 153.354192 -157.589185) (xy 153.326896 -157.54055)
			(xy 153.306973 -157.488459) (xy 153.294847 -157.434022) (xy 153.290776 -157.3784) (xy 152.653471 -157.3784)
			(xy 152.742955 -158.3944) (xy 153.290776 -158.3944) (xy 153.294847 -158.338778) (xy 153.306973 -158.284341)
			(xy 153.326896 -158.23225) (xy 153.354192 -158.183615) (xy 153.388278 -158.139472) (xy 153.428427 -158.100763)
			(xy 153.473785 -158.068312) (xy 153.523385 -158.042811) (xy 153.576169 -158.024804) (xy 153.631012 -158.014674)
			(xy 153.686746 -158.012637) (xy 153.742183 -158.018737) (xy 153.79614 -158.032843) (xy 153.847469 -158.054655)
			(xy 153.895075 -158.083709) (xy 153.937943 -158.119384) (xy 153.97516 -158.160921) (xy 154.005933 -158.207434)
			(xy 154.029605 -158.257931) (xy 154.045673 -158.311338) (xy 154.053793 -158.366514) (xy 154.054302 -158.3944)
			(xy 154.053793 -158.422286) (xy 154.045673 -158.477462) (xy 154.029605 -158.530869) (xy 154.005933 -158.581366)
			(xy 153.97516 -158.627879) (xy 153.937943 -158.669416) (xy 153.895075 -158.705091) (xy 153.847469 -158.734145)
			(xy 153.79614 -158.755957) (xy 153.742183 -158.770063) (xy 153.686746 -158.776163) (xy 153.631012 -158.774126)
			(xy 153.576169 -158.763996) (xy 153.523385 -158.745989) (xy 153.473785 -158.720488) (xy 153.428427 -158.688037)
			(xy 153.388278 -158.649328) (xy 153.354192 -158.605185) (xy 153.326896 -158.55655) (xy 153.306973 -158.504459)
			(xy 153.294847 -158.450022) (xy 153.290776 -158.3944) (xy 152.742955 -158.3944) (xy 155.361894 -188.129672)
			(xy 155.646374 -191.346328) (xy 155.647662 -191.35567) (xy 155.656038 -191.372546) (xy 155.669943 -191.385258)
			(xy 155.687501 -191.39209) (xy 155.69692 -191.392556)
		)
		(stroke
			(width 0)
			(type solid)
		)
		(fill yes)
		(layer "In11.Cu")
		(net "GND")
	)
	(gr_poly
		(pts
			(xy 387.216904 -184.212484) (xy 387.218793 -184.221839) (xy 387.228458 -184.23828) (xy 387.243459 -184.250056)
			(xy 387.261724 -184.255543) (xy 387.27126 -184.255156) (xy 388.130288 -184.182258) (xy 388.148068 -184.180734)
			(xy 388.157832 -184.179426) (xy 388.175362 -184.170477) (xy 388.188258 -184.155609) (xy 388.19464 -184.136991)
			(xy 388.19455 -184.12714) (xy 386.99948 -164.500306) (xy 386.980938 -164.475922) (xy 386.972048 -164.472874)
			(xy 386.946578 -164.464381) (xy 386.898129 -164.441243) (xy 386.853405 -164.411538) (xy 386.813289 -164.375855)
			(xy 386.778574 -164.334897) (xy 386.749948 -164.289475) (xy 386.727975 -164.240487) (xy 386.713091 -164.188901)
			(xy 386.705589 -164.135737) (xy 386.705094 -164.108892) (xy 386.705562 -164.081595) (xy 386.713349 -164.027559)
			(xy 386.728763 -163.975186) (xy 386.751489 -163.925547) (xy 386.781063 -163.879657) (xy 386.816878 -163.838453)
			(xy 386.858205 -163.802779) (xy 386.904196 -163.773363) (xy 386.928868 -163.761674) (xy 386.929884 -163.761166)
			(xy 386.936996 -163.757864) (xy 386.952744 -163.731194) (xy 386.824474 -161.626042) (xy 386.812282 -161.605214)
			(xy 386.804662 -161.600388) (xy 386.780155 -161.584504) (xy 386.735832 -161.54648) (xy 386.697823 -161.502145)
			(xy 386.667015 -161.452534) (xy 386.655056 -161.42589) (xy 386.652695 -161.420547) (xy 386.645884 -161.41106)
			(xy 386.641594 -161.407094) (xy 386.637022 -161.403284) (xy 386.627116 -161.39795) (xy 386.543042 -161.37636)
			(xy 386.537284 -161.375054) (xy 386.525484 -161.374804) (xy 386.519674 -161.375852) (xy 386.509006 -161.378138)
			(xy 386.499608 -161.385504) (xy 386.4991 -161.385504) (xy 386.478953 -161.400641) (xy 386.435435 -161.42605)
			(xy 386.388952 -161.445513) (xy 386.340313 -161.458691) (xy 386.290362 -161.465356) (xy 386.265166 -161.465768)
			(xy 386.237919 -161.46528) (xy 386.183981 -161.45752) (xy 386.131696 -161.442163) (xy 386.082128 -161.419523)
			(xy 386.036287 -161.390059) (xy 385.995105 -161.354371) (xy 385.959421 -161.313186) (xy 385.929961 -161.267342)
			(xy 385.907325 -161.217772) (xy 385.891973 -161.165486) (xy 385.884218 -161.111547) (xy 385.884218 -161.057053)
			(xy 385.891973 -161.003114) (xy 385.907325 -160.950828) (xy 385.929961 -160.901258) (xy 385.959421 -160.855414)
			(xy 385.995105 -160.814229) (xy 386.036287 -160.778541) (xy 386.082128 -160.749077) (xy 386.131696 -160.726437)
			(xy 386.183981 -160.71108) (xy 386.237919 -160.70332) (xy 386.265166 -160.702752) (xy 386.293028 -160.703263)
			(xy 386.348158 -160.711374) (xy 386.401523 -160.727414) (xy 386.451989 -160.751042) (xy 386.498484 -160.781756)
			(xy 386.540019 -160.818904) (xy 386.575712 -160.861696) (xy 386.604804 -160.909222) (xy 386.616194 -160.934654)
			(xy 386.617464 -160.937448) (xy 386.622844 -160.947056) (xy 386.639961 -160.960873) (xy 386.650484 -160.964118)
			(xy 386.739892 -160.986978) (xy 386.747004 -160.985454) (xy 386.763768 -160.971738) (xy 386.77261 -160.963522)
			(xy 386.782153 -160.941389) (xy 386.782056 -160.92932) (xy 386.337302 -153.627074) (xy 386.336262 -153.61708)
			(xy 386.327438 -153.599044) (xy 386.312374 -153.585768) (xy 386.303012 -153.582116) (xy 386.199634 -153.546556)
			(xy 386.169916 -153.55443) (xy 386.159756 -153.566114) (xy 386.141547 -153.586121) (xy 386.100458 -153.621308)
			(xy 386.054815 -153.650345) (xy 386.00553 -153.67265) (xy 385.953592 -153.687778) (xy 385.900038 -153.695424)
			(xy 385.87299 -153.695908) (xy 385.845739 -153.695422) (xy 385.791793 -153.687664) (xy 385.739499 -153.672308)
			(xy 385.689923 -153.649666) (xy 385.644074 -153.6202) (xy 385.602885 -153.584508) (xy 385.567194 -153.543318)
			(xy 385.537729 -153.497468) (xy 385.515089 -153.447892) (xy 385.499734 -153.395598) (xy 385.491978 -153.341651)
			(xy 385.491978 -153.287149) (xy 385.499734 -153.233202) (xy 385.515089 -153.180908) (xy 385.537729 -153.131332)
			(xy 385.567194 -153.085482) (xy 385.602885 -153.044292) (xy 385.644074 -153.0086) (xy 385.689923 -152.979134)
			(xy 385.739499 -152.956492) (xy 385.791793 -152.941136) (xy 385.845739 -152.933378) (xy 385.87299 -152.932892)
			(xy 385.900794 -152.933393) (xy 385.955812 -152.941461) (xy 386.009079 -152.957426) (xy 386.059464 -152.98095)
			(xy 386.105903 -153.011537) (xy 386.12699 -153.029666) (xy 386.134781 -153.035954) (xy 386.153665 -153.042538)
			(xy 386.173633 -153.041406) (xy 386.18287 -153.03754) (xy 386.267452 -152.996392) (xy 386.276261 -152.991575)
			(xy 386.289599 -152.976595) (xy 386.296223 -152.957664) (xy 386.296154 -152.947624) (xy 385.838954 -145.440654)
			(xy 385.837176 -145.379948) (xy 385.837272 -145.355463) (xy 385.839561 -145.306546) (xy 385.841748 -145.282158)
			(xy 386.011674 -143.559022) (xy 386.011674 -143.558514) (xy 386.52069 -137.50798) (xy 386.523491 -137.477534)
			(xy 386.532385 -137.417038) (xy 386.53847 -137.387076) (xy 386.557012 -137.298176) (xy 386.558398 -137.29)
			(xy 386.556466 -137.27354) (xy 386.553202 -137.265918) (xy 386.5499 -137.25906) (xy 386.538216 -137.246868)
			(xy 386.530088 -137.242804) (xy 386.500237 -137.226922) (xy 386.446195 -137.186296) (xy 386.422646 -137.162032)
			(xy 386.415666 -137.154415) (xy 386.402448 -137.138533) (xy 386.39623 -137.130282) (xy 386.390896 -137.12317)
			(xy 386.366258 -137.107168) (xy 386.354066 -137.101834) (xy 386.330698 -137.0965) (xy 386.326049 -137.095613)
			(xy 386.316591 -137.095352) (xy 386.311902 -137.095992) (xy 386.302758 -137.097262) (xy 386.276071 -137.112615)
			(xy 386.219455 -137.136811) (xy 386.160108 -137.153204) (xy 386.0991 -137.161496) (xy 386.068316 -137.162032)
			(xy 386.067808 -137.162032) (xy 386.037839 -137.161542) (xy 385.978415 -137.15372) (xy 385.92052 -137.138209)
			(xy 385.865145 -137.115273) (xy 385.813237 -137.085306) (xy 385.765684 -137.04882) (xy 385.723301 -137.00644)
			(xy 385.686812 -136.95889) (xy 385.656841 -136.906984) (xy 385.633901 -136.851611) (xy 385.618386 -136.793716)
			(xy 385.61056 -136.734293) (xy 385.6101 -136.704324) (xy 385.6101 -135.840724) (xy 385.61059 -135.810756)
			(xy 385.618413 -135.751334) (xy 385.633926 -135.693441) (xy 385.656862 -135.638068) (xy 385.686829 -135.586162)
			(xy 385.723316 -135.538612) (xy 385.765696 -135.496232) (xy 385.813246 -135.459745) (xy 385.865152 -135.429778)
			(xy 385.920525 -135.406842) (xy 385.978418 -135.391329) (xy 386.03784 -135.383506) (xy 386.097776 -135.383506)
			(xy 386.157198 -135.391329) (xy 386.215091 -135.406842) (xy 386.270464 -135.429778) (xy 386.32237 -135.459745)
			(xy 386.36992 -135.496232) (xy 386.4123 -135.538612) (xy 386.448787 -135.586162) (xy 386.478754 -135.638068)
			(xy 386.50169 -135.693441) (xy 386.517203 -135.751334) (xy 386.525026 -135.810756) (xy 386.525516 -135.840724)
			(xy 386.525516 -136.42467) (xy 386.52577 -136.430258) (xy 386.527224 -136.439768) (xy 386.536226 -136.456755)
			(xy 386.543296 -136.463278) (xy 386.60197 -136.513316) (xy 386.60941 -136.519033) (xy 386.627131 -136.52515)
			(xy 386.636514 -136.525254) (xy 386.642864 -136.525) (xy 386.644642 -136.524746) (xy 386.653532 -136.523476)
			(xy 386.6642 -136.522206) (xy 386.697474 -136.518904) (xy 386.70611 -136.513824) (xy 386.765292 -135.91286)
			(xy 386.765546 -135.90778) (xy 386.76072 -134.951978) (xy 386.76072 -134.95147) (xy 386.677916 -129.092198)
			(xy 386.635752 -126.10719) (xy 386.635279 -126.099027) (xy 386.629835 -126.083619) (xy 386.625084 -126.076964)
			(xy 386.620512 -126.070868) (xy 386.606796 -126.061724) (xy 386.598668 -126.059438) (xy 386.574697 -126.0523)
			(xy 386.528723 -126.032601) (xy 386.48572 -126.00706) (xy 386.446427 -125.976114) (xy 386.411518 -125.940295)
			(xy 386.39623 -125.9205) (xy 386.390896 -125.913388) (xy 386.366258 -125.897386) (xy 386.354066 -125.892052)
			(xy 386.330698 -125.886718) (xy 386.326049 -125.885831) (xy 386.316591 -125.88557) (xy 386.311902 -125.88621)
			(xy 386.302758 -125.88748) (xy 386.276022 -125.902894) (xy 386.219292 -125.927191) (xy 386.159814 -125.943651)
			(xy 386.098665 -125.951978) (xy 386.067808 -125.952504) (xy 386.037851 -125.952015) (xy 385.978448 -125.944198)
			(xy 385.920573 -125.928697) (xy 385.865216 -125.905777) (xy 385.813323 -125.87583) (xy 385.765781 -125.839368)
			(xy 385.723403 -125.797014) (xy 385.686913 -125.749492) (xy 385.656937 -125.697616) (xy 385.633986 -125.642271)
			(xy 385.618452 -125.584405) (xy 385.610602 -125.525007) (xy 385.6101 -125.49505) (xy 385.6101 -125.062742)
			(xy 385.609846 -124.630942) (xy 385.610333 -124.600967) (xy 385.61815 -124.541528) (xy 385.633657 -124.483618)
			(xy 385.656588 -124.428226) (xy 385.686551 -124.3763) (xy 385.723033 -124.328728) (xy 385.765411 -124.286323)
			(xy 385.81296 -124.249811) (xy 385.864867 -124.219815) (xy 385.920245 -124.19685) (xy 385.978145 -124.181307)
			(xy 386.037579 -124.173452) (xy 386.067554 -124.17298) (xy 386.068316 -124.17298) (xy 386.097187 -124.173397)
			(xy 386.154476 -124.180619) (xy 386.210399 -124.194996) (xy 386.264066 -124.216301) (xy 386.28955 -124.229876)
			(xy 386.295138 -124.232924) (xy 386.319776 -124.239782) (xy 386.331206 -124.238512) (xy 386.351018 -124.23394)
			(xy 386.352796 -124.233432) (xy 386.356531 -124.232452) (xy 386.363674 -124.229518) (xy 386.36702 -124.22759)
			(xy 386.371846 -124.224542) (xy 386.390896 -124.211842) (xy 386.39623 -124.20473) (xy 386.413314 -124.18269)
			(xy 386.452859 -124.143373) (xy 386.497713 -124.110243) (xy 386.546919 -124.084006) (xy 386.573014 -124.074174)
			(xy 386.575808 -124.073158) (xy 386.584731 -124.068865) (xy 386.59867 -124.054826) (xy 386.606275 -124.036564)
			(xy 386.606796 -124.026676) (xy 386.584952 -122.489214) (xy 386.584545 -122.48192) (xy 386.580169 -122.467988)
			(xy 386.576316 -122.461782) (xy 386.572506 -122.45594) (xy 386.561076 -122.446542) (xy 386.55371 -122.443494)
			(xy 386.530556 -122.433295) (xy 386.486933 -122.407664) (xy 386.44708 -122.376492) (xy 386.411698 -122.340326)
			(xy 386.39623 -122.320304) (xy 386.390896 -122.313446) (xy 386.369052 -122.298714) (xy 386.3651 -122.296285)
			(xy 386.356539 -122.292712) (xy 386.352034 -122.291602) (xy 386.331206 -122.286776) (xy 386.326558 -122.285887)
			(xy 386.317098 -122.285624) (xy 386.31241 -122.286268) (xy 386.303266 -122.287538) (xy 386.294884 -122.292364)
			(xy 386.269545 -122.306283) (xy 386.216104 -122.328339) (xy 386.160312 -122.343497) (xy 386.103057 -122.351516)
			(xy 386.074158 -122.352308) (xy 386.067808 -122.352308) (xy 386.037851 -122.351819) (xy 385.978448 -122.344002)
			(xy 385.920573 -122.328502) (xy 385.865215 -122.305581) (xy 385.813322 -122.275634) (xy 385.765779 -122.239172)
			(xy 385.723401 -122.196818) (xy 385.686911 -122.149296) (xy 385.656935 -122.09742) (xy 385.633983 -122.042075)
			(xy 385.618449 -121.984209) (xy 385.610598 -121.924811) (xy 385.6101 -121.894854) (xy 385.6101 -121.4628)
			(xy 385.609846 -121.030746) (xy 385.610333 -121.000771) (xy 385.61815 -120.941331) (xy 385.633656 -120.883421)
			(xy 385.656587 -120.828028) (xy 385.686549 -120.776102) (xy 385.723032 -120.72853) (xy 385.76541 -120.686124)
			(xy 385.812959 -120.649612) (xy 385.864866 -120.619616) (xy 385.920244 -120.59665) (xy 385.978145 -120.581107)
			(xy 386.037579 -120.573252) (xy 386.067554 -120.572784) (xy 386.068316 -120.572784) (xy 386.097187 -120.573201)
			(xy 386.154475 -120.580423) (xy 386.210399 -120.5948) (xy 386.264066 -120.616105) (xy 386.28955 -120.62968)
			(xy 386.295138 -120.632728) (xy 386.319776 -120.639586) (xy 386.331206 -120.638316) (xy 386.351018 -120.633744)
			(xy 386.352796 -120.633236) (xy 386.356531 -120.632256) (xy 386.363674 -120.629322) (xy 386.36702 -120.627394)
			(xy 386.371846 -120.624346) (xy 386.390896 -120.611646) (xy 386.39623 -120.604534) (xy 386.414065 -120.581599)
			(xy 386.455522 -120.540897) (xy 386.50268 -120.506965) (xy 386.52831 -120.493282) (xy 386.53456 -120.489872)
			(xy 386.544993 -120.480195) (xy 386.548884 -120.474232) (xy 386.552294 -120.468039) (xy 386.555913 -120.454377)
			(xy 386.555996 -120.447308) (xy 386.500878 -116.531644) (xy 386.500878 -116.53139) (xy 386.500624 -116.51869)
			(xy 386.500624 -116.517674) (xy 386.502656 -116.458746) (xy 386.51815 -116.199412) (xy 386.518354 -116.19004)
			(xy 386.512787 -116.172158) (xy 386.501142 -116.15749) (xy 386.493258 -116.152422) (xy 386.411216 -116.107718)
			(xy 386.40478 -116.104491) (xy 386.390726 -116.1014) (xy 386.38353 -116.101622) (xy 386.383276 -116.101622)
			(xy 386.376238 -116.102385) (xy 386.36296 -116.10728) (xy 386.357114 -116.111274) (xy 386.35686 -116.111274)
			(xy 386.341812 -116.122059) (xy 386.310006 -116.141014) (xy 386.29336 -116.14912) (xy 386.292344 -116.149628)
			(xy 386.283381 -116.154556) (xy 386.270022 -116.17002) (xy 386.266436 -116.1796) (xy 386.245354 -116.25707)
			(xy 386.244056 -116.262369) (xy 386.243535 -116.273264) (xy 386.244338 -116.27866) (xy 386.246116 -116.28882)
			(xy 386.252212 -116.298218) (xy 386.25272 -116.298726) (xy 386.268207 -116.322528) (xy 386.292718 -116.37375)
			(xy 386.309357 -116.428042) (xy 386.317755 -116.484202) (xy 386.318252 -116.512594) (xy 386.317767 -116.539847)
			(xy 386.310011 -116.593797) (xy 386.294657 -116.646095) (xy 386.272017 -116.695676) (xy 386.242551 -116.74153)
			(xy 386.20686 -116.782725) (xy 386.165671 -116.818421) (xy 386.11982 -116.847893) (xy 386.070242 -116.870539)
			(xy 386.017946 -116.8859) (xy 385.963997 -116.893663) (xy 385.936744 -116.894102) (xy 385.911226 -116.893672)
			(xy 385.860647 -116.886864) (xy 385.811425 -116.873376) (xy 385.76444 -116.853449) (xy 385.72053 -116.827439)
			(xy 385.680477 -116.79581) (xy 385.662424 -116.77777) (xy 385.655566 -116.770658) (xy 385.628388 -116.75872)
			(xy 385.62788 -116.758466) (xy 385.624161 -116.75697) (xy 385.616374 -116.755065) (xy 385.612386 -116.754656)
			(xy 385.608068 -116.754402) (xy 385.559808 -116.754402) (xy 385.549394 -116.755418) (xy 385.53898 -116.757704)
			(xy 385.529074 -116.760752) (xy 385.506722 -116.770658) (xy 385.499864 -116.77777) (xy 385.481834 -116.795837)
			(xy 385.441784 -116.827481) (xy 385.397872 -116.853501) (xy 385.350881 -116.873432) (xy 385.301653 -116.886918)
			(xy 385.251065 -116.893718) (xy 385.225544 -116.894102) (xy 385.19829 -116.893642) (xy 385.144335 -116.88589)
			(xy 385.092032 -116.870538) (xy 385.042448 -116.847898) (xy 384.99659 -116.818432) (xy 384.955392 -116.782739)
			(xy 384.919694 -116.741546) (xy 384.890223 -116.695691) (xy 384.867577 -116.646109) (xy 384.852219 -116.593808)
			(xy 384.844461 -116.539854) (xy 384.844461 -116.485346) (xy 384.852219 -116.431392) (xy 384.867577 -116.379091)
			(xy 384.890223 -116.329509) (xy 384.919694 -116.283654) (xy 384.955392 -116.242461) (xy 384.99659 -116.206768)
			(xy 385.042447 -116.177302) (xy 385.092032 -116.154662) (xy 385.144335 -116.13931) (xy 385.19829 -116.131558)
			(xy 385.225544 -116.131086) (xy 385.251062 -116.131515) (xy 385.301643 -116.138322) (xy 385.350865 -116.151808)
			(xy 385.397852 -116.171733) (xy 385.441764 -116.197742) (xy 385.481819 -116.22937) (xy 385.499864 -116.247418)
			(xy 385.506722 -116.25453) (xy 385.5339 -116.266468) (xy 385.545076 -116.270024) (xy 385.554474 -116.270786)
			(xy 385.602988 -116.270786) (xy 385.61264 -116.26977) (xy 385.626356 -116.26723) (xy 385.626864 -116.266976)
			(xy 385.628388 -116.266468) (xy 385.655566 -116.25453) (xy 385.662424 -116.247164) (xy 385.687012 -116.222896)
			(xy 385.743238 -116.182766) (xy 385.774184 -116.167408) (xy 385.77647 -116.166392) (xy 385.785526 -116.16105)
			(xy 385.798646 -116.14465) (xy 385.80187 -116.134642) (xy 385.807204 -116.115592) (xy 385.807204 -116.115084)
			(xy 385.82219 -116.059458) (xy 385.823479 -116.054159) (xy 385.823985 -116.043266) (xy 385.823206 -116.037868)
			(xy 385.821428 -116.027708) (xy 385.815332 -116.01831) (xy 385.814824 -116.017802) (xy 385.799337 -115.994)
			(xy 385.774826 -115.942778) (xy 385.758186 -115.888486) (xy 385.749785 -115.832326) (xy 385.749292 -115.803934)
			(xy 385.749369 -115.791196) (xy 385.751021 -115.765774) (xy 385.752594 -115.753134) (xy 385.756927 -115.724751)
			(xy 385.773003 -115.669634) (xy 385.797155 -115.617548) (xy 385.828838 -115.569668) (xy 385.867336 -115.527074)
			(xy 385.911781 -115.490728) (xy 385.961169 -115.461451) (xy 386.014385 -115.439903) (xy 386.07023 -115.426571)
			(xy 386.098796 -115.423696) (xy 386.099812 -115.423696) (xy 386.10921 -115.42268) (xy 386.136134 -115.408964)
			(xy 386.14604 -115.402106) (xy 386.152898 -115.394994) (xy 386.193284 -115.343686) (xy 386.196422 -115.339451)
			(xy 386.201024 -115.329971) (xy 386.202428 -115.32489) (xy 386.205222 -115.314476) (xy 386.20319 -115.303554)
			(xy 386.20036 -115.286806) (xy 386.197308 -115.252974) (xy 386.197094 -115.23599) (xy 386.197094 -115.235228)
			(xy 386.197616 -115.206443) (xy 386.206262 -115.149525) (xy 386.223362 -115.094553) (xy 386.248528 -115.042774)
			(xy 386.281187 -114.995364) (xy 386.3206 -114.953399) (xy 386.36587 -114.917833) (xy 386.415971 -114.889473)
			(xy 386.469764 -114.868962) (xy 386.526027 -114.856767) (xy 386.554726 -114.854482) (xy 386.567934 -114.85372)
			(xy 386.590032 -114.839496) (xy 386.593588 -114.832892) (xy 386.597144 -114.826542) (xy 386.599065 -114.822509)
			(xy 386.601615 -114.813949) (xy 386.602224 -114.809524) (xy 386.6388 -114.206528) (xy 386.658866 -113.873788)
			(xy 386.658866 -113.87074) (xy 386.647944 -111.5949) (xy 386.64734 -111.583606) (xy 386.637656 -111.563199)
			(xy 386.620157 -111.548915) (xy 386.609336 -111.545624) (xy 386.581455 -111.538108) (xy 386.528181 -111.515831)
			(xy 386.478867 -111.48579) (xy 386.434636 -111.44867) (xy 386.396495 -111.405315) (xy 386.380482 -111.381286)
			(xy 386.37591 -111.37519) (xy 386.369693 -111.368678) (xy 386.353862 -111.360129) (xy 386.336052 -111.357576)
			(xy 386.318458 -111.361336) (xy 386.310632 -111.365792) (xy 386.283221 -111.38234) (xy 386.224756 -111.408446)
			(xy 386.163223 -111.426144) (xy 386.099822 -111.435088) (xy 386.067808 -111.435642) (xy 386.037839 -111.435152)
			(xy 385.978414 -111.42733) (xy 385.920519 -111.411819) (xy 385.865143 -111.388884) (xy 385.813234 -111.358917)
			(xy 385.765681 -111.322431) (xy 385.723297 -111.280051) (xy 385.686807 -111.232501) (xy 385.656835 -111.180595)
			(xy 385.633895 -111.125221) (xy 385.618378 -111.067327) (xy 385.61055 -111.007903) (xy 385.6101 -110.977934)
			(xy 385.6101 -110.114334) (xy 385.610567 -110.084364) (xy 385.618387 -110.024936) (xy 385.633897 -109.967037)
			(xy 385.656833 -109.911658) (xy 385.6868 -109.859746) (xy 385.723288 -109.812191) (xy 385.765671 -109.769805)
			(xy 385.813225 -109.733315) (xy 385.865134 -109.703344) (xy 385.920512 -109.680405) (xy 385.97841 -109.664892)
			(xy 386.037838 -109.657069) (xy 386.067808 -109.656626) (xy 386.099821 -109.657181) (xy 386.163218 -109.66614)
			(xy 386.22475 -109.68384) (xy 386.283217 -109.709936) (xy 386.310632 -109.726476) (xy 386.318475 -109.731011)
			(xy 386.336183 -109.734773) (xy 386.354094 -109.732136) (xy 386.369967 -109.723432) (xy 386.376164 -109.716824)
			(xy 386.380482 -109.710982) (xy 386.395957 -109.687722) (xy 386.432621 -109.645569) (xy 386.475037 -109.60921)
			(xy 386.522298 -109.57942) (xy 386.573396 -109.556836) (xy 386.600192 -109.54893) (xy 386.61078 -109.545443)
			(xy 386.627754 -109.531031) (xy 386.637036 -109.510791) (xy 386.63753 -109.499654) (xy 386.630418 -107.989878)
			(xy 386.629853 -107.978965) (xy 386.620718 -107.959138) (xy 386.604186 -107.94488) (xy 386.593842 -107.941364)
			(xy 386.5646 -107.932093) (xy 386.509302 -107.905547) (xy 386.458954 -107.87051) (xy 386.414847 -107.827881)
			(xy 386.395976 -107.803696) (xy 386.390642 -107.796584) (xy 386.371592 -107.783884) (xy 386.366766 -107.780836)
			(xy 386.354066 -107.775248) (xy 386.330698 -107.769914) (xy 386.326049 -107.769027) (xy 386.316591 -107.768766)
			(xy 386.311902 -107.769406) (xy 386.302758 -107.770676) (xy 386.276022 -107.78609) (xy 386.219292 -107.810387)
			(xy 386.159814 -107.826848) (xy 386.098665 -107.835174) (xy 386.067808 -107.8357) (xy 386.037851 -107.835211)
			(xy 385.978448 -107.827394) (xy 385.920574 -107.811893) (xy 385.865217 -107.788973) (xy 385.813324 -107.759026)
			(xy 385.765782 -107.722564) (xy 385.723404 -107.680209) (xy 385.686915 -107.632688) (xy 385.656939 -107.580811)
			(xy 385.633988 -107.525467) (xy 385.618455 -107.467601) (xy 385.610606 -107.408203) (xy 385.6101 -107.378246)
			(xy 385.6101 -106.514138) (xy 385.610587 -106.484162) (xy 385.618405 -106.424721) (xy 385.633911 -106.366809)
			(xy 385.656842 -106.311415) (xy 385.686804 -106.259487) (xy 385.723286 -106.211912) (xy 385.765663 -106.169504)
			(xy 385.813212 -106.132988) (xy 385.865119 -106.102988) (xy 385.920496 -106.080018) (xy 385.978397 -106.064469)
			(xy 386.037832 -106.056609) (xy 386.067808 -106.056176) (xy 386.100019 -106.056762) (xy 386.163795 -106.065872)
			(xy 386.225662 -106.083841) (xy 386.25526 -106.096562) (xy 386.290312 -106.114088) (xy 386.294884 -106.116374)
			(xy 386.32003 -106.123232) (xy 386.32765 -106.12247) (xy 386.354066 -106.116628) (xy 386.366258 -106.111294)
			(xy 386.390896 -106.095292) (xy 386.39623 -106.08818) (xy 386.414318 -106.0649) (xy 386.45645 -106.023664)
			(xy 386.50441 -105.989382) (xy 386.557064 -105.962866) (xy 386.584952 -105.953306) (xy 386.595075 -105.949529)
			(xy 386.611112 -105.935079) (xy 386.619838 -105.915334) (xy 386.620258 -105.904538) (xy 386.612638 -104.382062)
			(xy 386.612324 -104.37387) (xy 386.607136 -104.358329) (xy 386.602478 -104.351582) (xy 386.599938 -104.34828)
			(xy 386.588 -104.339898) (xy 386.578602 -104.336596) (xy 386.562854 -104.330754) (xy 386.537355 -104.320269)
			(xy 386.489433 -104.29301) (xy 386.445947 -104.259121) (xy 386.407806 -104.219311) (xy 386.391404 -104.19715)
			(xy 386.388864 -104.193594) (xy 386.378704 -104.18445) (xy 386.374658 -104.181894) (xy 386.365834 -104.178192)
			(xy 386.361178 -104.177084) (xy 386.334762 -104.170988) (xy 386.3213 -104.169718) (xy 386.310124 -104.171496)
			(xy 386.294884 -104.17556) (xy 386.289296 -104.178608) (xy 386.263827 -104.192139) (xy 386.210219 -104.21341)
			(xy 386.154367 -104.227794) (xy 386.097153 -104.235063) (xy 386.068316 -104.235504) (xy 386.067808 -104.235504)
			(xy 386.037839 -104.235035) (xy 385.978413 -104.227213) (xy 385.920517 -104.2117) (xy 385.86514 -104.188763)
			(xy 385.813232 -104.158795) (xy 385.765679 -104.122307) (xy 385.723296 -104.079924) (xy 385.686808 -104.032372)
			(xy 385.656838 -103.980463) (xy 385.633901 -103.925087) (xy 385.618388 -103.867191) (xy 385.610565 -103.807765)
			(xy 385.6101 -103.777796) (xy 385.6101 -102.914196) (xy 385.610569 -102.884227) (xy 385.618393 -102.824803)
			(xy 385.633907 -102.766908) (xy 385.656844 -102.711533) (xy 385.686814 -102.659626) (xy 385.723302 -102.612075)
			(xy 385.765684 -102.569694) (xy 385.813236 -102.533207) (xy 385.865144 -102.503239) (xy 385.920519 -102.480303)
			(xy 385.978415 -102.464791) (xy 386.037839 -102.456969) (xy 386.067808 -102.456488) (xy 386.068062 -102.456488)
			(xy 386.097082 -102.456957) (xy 386.154652 -102.464326) (xy 386.210833 -102.478899) (xy 386.264726 -102.500445)
			(xy 386.290312 -102.514146) (xy 386.294884 -102.516432) (xy 386.32003 -102.52329) (xy 386.32765 -102.522528)
			(xy 386.354066 -102.516686) (xy 386.366258 -102.511352) (xy 386.390896 -102.49535) (xy 386.39623 -102.488238)
			(xy 386.412126 -102.467659) (xy 386.44859 -102.430585) (xy 386.489755 -102.398813) (xy 386.534857 -102.372932)
			(xy 386.55879 -102.362762) (xy 386.564886 -102.359206) (xy 386.567929 -102.357097) (xy 386.573414 -102.352125)
			(xy 386.575808 -102.3493) (xy 386.581344 -102.342066) (xy 386.587337 -102.324879) (xy 386.587492 -102.315772)
			(xy 386.554218 -100.758498) (xy 386.553871 -100.751719) (xy 386.550007 -100.738714) (xy 386.546598 -100.732844)
			(xy 386.543042 -100.727002) (xy 386.53339 -100.718112) (xy 386.526786 -100.714556) (xy 386.501464 -100.7009)
			(xy 386.454877 -100.667145) (xy 386.413879 -100.626786) (xy 386.39623 -100.604066) (xy 386.390896 -100.596954)
			(xy 386.371846 -100.584254) (xy 386.36702 -100.581206) (xy 386.363903 -100.579407) (xy 386.357272 -100.576611)
			(xy 386.353812 -100.575618) (xy 386.324602 -100.56876) (xy 386.322062 -100.568252) (xy 386.303266 -100.571046)
			(xy 386.294884 -100.575872) (xy 386.269545 -100.589791) (xy 386.216104 -100.611847) (xy 386.160312 -100.627004)
			(xy 386.103057 -100.635022) (xy 386.074158 -100.635816) (xy 386.067808 -100.635816) (xy 386.03785 -100.635327)
			(xy 385.978447 -100.62751) (xy 385.920572 -100.61201) (xy 385.865214 -100.58909) (xy 385.81332 -100.559143)
			(xy 385.765777 -100.52268) (xy 385.723398 -100.480326) (xy 385.686908 -100.432805) (xy 385.65693 -100.380928)
			(xy 385.633977 -100.325584) (xy 385.618442 -100.267718) (xy 385.610591 -100.208319) (xy 385.6101 -100.178362)
			(xy 385.6101 -99.746308) (xy 385.609846 -99.314254) (xy 385.610336 -99.284325) (xy 385.61814 -99.224977)
			(xy 385.633611 -99.167152) (xy 385.656484 -99.111836) (xy 385.686369 -99.059971) (xy 385.722757 -99.012443)
			(xy 385.765028 -98.97006) (xy 385.81246 -98.933546) (xy 385.864245 -98.903523) (xy 385.9195 -98.880504)
			(xy 385.977284 -98.864879) (xy 386.03661 -98.856917) (xy 386.066538 -98.856292) (xy 386.067808 -98.856292)
			(xy 386.096686 -98.856745) (xy 386.15398 -98.864039) (xy 386.2099 -98.878484) (xy 386.263558 -98.899851)
			(xy 386.289042 -98.913442) (xy 386.29463 -98.91649) (xy 386.313426 -98.921316) (xy 386.317959 -98.922122)
			(xy 386.327162 -98.922259) (xy 386.331714 -98.92157) (xy 386.352034 -98.916998) (xy 386.356554 -98.915935)
			(xy 386.365119 -98.912354) (xy 386.369052 -98.909886) (xy 386.390896 -98.895154) (xy 386.39623 -98.888296)
			(xy 386.40341 -98.878801) (xy 386.418787 -98.860625) (xy 386.426964 -98.851974) (xy 386.441254 -98.837455)
			(xy 386.472435 -98.811232) (xy 386.489194 -98.79965) (xy 386.493349 -98.796746) (xy 386.500518 -98.789583)
			(xy 386.503418 -98.785426) (xy 386.504942 -98.782632) (xy 386.507274 -98.778353) (xy 386.510467 -98.769147)
			(xy 386.511292 -98.764344) (xy 386.511292 -98.763836) (xy 386.5118 -98.758502) (xy 386.46989 -96.790764)
			(xy 386.46989 -96.789748) (xy 386.393182 -94.873826) (xy 386.392378 -94.864475) (xy 386.38494 -94.84726)
			(xy 386.371818 -94.833863) (xy 386.354762 -94.826069) (xy 386.34543 -94.825058) (xy 385.901946 -94.811088)
			(xy 384.792474 -94.775782) (xy 384.783068 -94.775867) (xy 384.765341 -94.782123) (xy 384.751082 -94.794373)
			(xy 384.742224 -94.810954) (xy 384.740658 -94.820232) (xy 384.574331 -96.1644) (xy 385.525516 -96.1644)
			(xy 385.529587 -96.108778) (xy 385.541713 -96.054341) (xy 385.561636 -96.00225) (xy 385.588932 -95.953615)
			(xy 385.623018 -95.909472) (xy 385.663167 -95.870763) (xy 385.708525 -95.838312) (xy 385.758125 -95.812811)
			(xy 385.810909 -95.794804) (xy 385.865752 -95.784674) (xy 385.921486 -95.782637) (xy 385.976923 -95.788737)
			(xy 386.03088 -95.802843) (xy 386.082209 -95.824655) (xy 386.129815 -95.853709) (xy 386.172683 -95.889384)
			(xy 386.2099 -95.930921) (xy 386.240673 -95.977434) (xy 386.264345 -96.027931) (xy 386.280413 -96.081338)
			(xy 386.288533 -96.136514) (xy 386.289042 -96.1644) (xy 386.288533 -96.192286) (xy 386.280413 -96.247462)
			(xy 386.264345 -96.300869) (xy 386.240673 -96.351366) (xy 386.2099 -96.397879) (xy 386.172683 -96.439416)
			(xy 386.129815 -96.475091) (xy 386.082209 -96.504145) (xy 386.03088 -96.525957) (xy 385.976923 -96.540063)
			(xy 385.921486 -96.546163) (xy 385.865752 -96.544126) (xy 385.810909 -96.533996) (xy 385.758125 -96.515989)
			(xy 385.708525 -96.490488) (xy 385.663167 -96.458037) (xy 385.623018 -96.419328) (xy 385.588932 -96.375185)
			(xy 385.561636 -96.32655) (xy 385.541713 -96.274459) (xy 385.529587 -96.220022) (xy 385.525516 -96.1644)
			(xy 384.574331 -96.1644) (xy 384.448611 -97.1804) (xy 385.525516 -97.1804) (xy 385.529587 -97.124778)
			(xy 385.541713 -97.070341) (xy 385.561636 -97.01825) (xy 385.588932 -96.969615) (xy 385.623018 -96.925472)
			(xy 385.663167 -96.886763) (xy 385.708525 -96.854312) (xy 385.758125 -96.828811) (xy 385.810909 -96.810804)
			(xy 385.865752 -96.800674) (xy 385.921486 -96.798637) (xy 385.976923 -96.804737) (xy 386.03088 -96.818843)
			(xy 386.082209 -96.840655) (xy 386.129815 -96.869709) (xy 386.172683 -96.905384) (xy 386.2099 -96.946921)
			(xy 386.240673 -96.993434) (xy 386.264345 -97.043931) (xy 386.280413 -97.097338) (xy 386.288533 -97.152514)
			(xy 386.289042 -97.1804) (xy 386.288533 -97.208286) (xy 386.280413 -97.263462) (xy 386.264345 -97.316869)
			(xy 386.240673 -97.367366) (xy 386.2099 -97.413879) (xy 386.172683 -97.455416) (xy 386.129815 -97.491091)
			(xy 386.082209 -97.520145) (xy 386.03088 -97.541957) (xy 385.976923 -97.556063) (xy 385.921486 -97.562163)
			(xy 385.865752 -97.560126) (xy 385.810909 -97.549996) (xy 385.758125 -97.531989) (xy 385.708525 -97.506488)
			(xy 385.663167 -97.474037) (xy 385.623018 -97.435328) (xy 385.588932 -97.391185) (xy 385.561636 -97.34255)
			(xy 385.541713 -97.290459) (xy 385.529587 -97.236022) (xy 385.525516 -97.1804) (xy 384.448611 -97.1804)
			(xy 384.14198 -99.658424) (xy 384.132582 -99.71913) (xy 383.977642 -100.544122) (xy 383.976836 -100.548851)
			(xy 383.976845 -100.558441) (xy 383.977642 -100.563172) (xy 383.979928 -100.57511) (xy 384.026664 -100.635816)
			(xy 384.028996 -100.638687) (xy 384.034348 -100.643791) (xy 384.037332 -100.645976) (xy 384.04292 -100.649532)
			(xy 384.06959 -100.66401) (xy 384.080258 -100.665026) (xy 384.110719 -100.668531) (xy 384.170387 -100.68265)
			(xy 384.227637 -100.704605) (xy 384.281447 -100.734002) (xy 384.330853 -100.770315) (xy 384.374972 -100.812895)
			(xy 384.413016 -100.860982) (xy 384.444304 -100.913714) (xy 384.468276 -100.970149) (xy 384.484504 -101.029278)
			(xy 384.492698 -101.090044) (xy 384.493262 -101.120702) (xy 384.493262 -101.984302) (xy 384.492777 -102.014202)
			(xy 384.484994 -102.073492) (xy 384.469559 -102.131265) (xy 384.446736 -102.186538) (xy 384.416913 -102.23837)
			(xy 384.380597 -102.285879) (xy 384.338406 -102.328257) (xy 384.291059 -102.364783) (xy 384.23936 -102.394835)
			(xy 384.184189 -102.417903) (xy 384.126485 -102.433594) (xy 384.067229 -102.44164) (xy 384.037332 -102.442264)
			(xy 384.028696 -102.442264) (xy 384.000623 -102.441412) (xy 383.94499 -102.433706) (xy 383.890713 -102.419267)
			(xy 383.838605 -102.39831) (xy 383.813812 -102.385114) (xy 383.808224 -102.382066) (xy 383.789428 -102.37724)
			(xy 383.784956 -102.376477) (xy 383.775886 -102.37635) (xy 383.771394 -102.376986) (xy 383.751074 -102.381558)
			(xy 383.746554 -102.38262) (xy 383.737985 -102.386196) (xy 383.734056 -102.38867) (xy 383.712212 -102.403402)
			(xy 383.706878 -102.41026) (xy 383.699358 -102.420172) (xy 383.683214 -102.439109) (xy 383.67462 -102.448106)
			(xy 383.663397 -102.459385) (xy 383.639364 -102.480243) (xy 383.626614 -102.489762) (xy 383.619335 -102.495515)
			(xy 383.609172 -102.511018) (xy 383.606802 -102.519988) (xy 383.606548 -102.521512) (xy 383.600198 -102.555548)
			(xy 383.59969 -102.558088) (xy 383.467102 -103.519478) (xy 383.37363 -104.19715) (xy 383.372629 -104.208297)
			(xy 383.379218 -104.229657) (xy 383.38633 -104.238298) (xy 383.394204 -104.246934) (xy 383.397701 -104.250623)
			(xy 383.405896 -104.256633) (xy 383.41046 -104.258872) (xy 383.419858 -104.26319) (xy 383.43078 -104.26319)
			(xy 383.460531 -104.263997) (xy 383.519456 -104.272365) (xy 383.576799 -104.2883) (xy 383.631594 -104.311532)
			(xy 383.682915 -104.341671) (xy 383.729896 -104.378207) (xy 383.771747 -104.420524) (xy 383.807759 -104.467908)
			(xy 383.837327 -104.519561) (xy 383.85995 -104.574609) (xy 383.875248 -104.632126) (xy 383.882962 -104.69114)
			(xy 383.883408 -104.720898) (xy 383.883408 -105.152698) (xy 383.883662 -105.584498) (xy 383.883193 -105.614484)
			(xy 383.875365 -105.673942) (xy 383.859844 -105.73187) (xy 383.836894 -105.787277) (xy 383.806908 -105.839214)
			(xy 383.7704 -105.886792) (xy 383.727994 -105.929199) (xy 383.680415 -105.965707) (xy 383.628479 -105.995693)
			(xy 383.573072 -106.018643) (xy 383.515144 -106.034165) (xy 383.455686 -106.041993) (xy 383.4257 -106.04246)
			(xy 383.399882 -106.042076) (xy 383.348579 -106.036218) (xy 383.323338 -106.030776) (xy 383.296414 -106.023664)
			(xy 383.285238 -106.020362) (xy 383.274062 -106.02214) (xy 383.268568 -106.023143) (xy 383.258183 -106.027244)
			(xy 383.253488 -106.030268) (xy 383.204466 -106.063796) (xy 383.195595 -106.070454) (xy 383.18415 -106.089423)
			(xy 383.182368 -106.100372) (xy 383.101596 -107.866688) (xy 383.102524 -107.878808) (xy 383.114066 -107.900161)
			(xy 383.123694 -107.907582) (xy 383.150364 -107.923584) (xy 383.159709 -107.928003) (xy 383.180292 -107.929696)
			(xy 383.190242 -107.926886) (xy 383.196084 -107.9246) (xy 383.197608 -107.923838) (xy 383.199386 -107.922822)
			(xy 383.225293 -107.908634) (xy 383.279979 -107.886308) (xy 383.337084 -107.871209) (xy 383.395658 -107.86359)
			(xy 383.425192 -107.863132) (xy 383.4257 -107.863132) (xy 383.455668 -107.863601) (xy 383.515091 -107.871425)
			(xy 383.572985 -107.886938) (xy 383.628358 -107.909876) (xy 383.680264 -107.939846) (xy 383.727813 -107.976334)
			(xy 383.770192 -108.018717) (xy 383.806677 -108.06627) (xy 383.836642 -108.118178) (xy 383.859575 -108.173553)
			(xy 383.875083 -108.231448) (xy 383.882902 -108.290872) (xy 383.883408 -108.32084) (xy 383.883408 -109.18444)
			(xy 383.882915 -109.214406) (xy 383.875088 -109.273825) (xy 383.859572 -109.331713) (xy 383.836634 -109.387082)
			(xy 383.806665 -109.438983) (xy 383.770178 -109.486528) (xy 383.727798 -109.528904) (xy 383.680249 -109.565387)
			(xy 383.628346 -109.595351) (xy 383.572975 -109.618285) (xy 383.515085 -109.633796) (xy 383.455666 -109.641618)
			(xy 383.4257 -109.642148) (xy 383.425192 -109.642148) (xy 383.395588 -109.641669) (xy 383.336876 -109.634013)
			(xy 383.27964 -109.618856) (xy 383.224834 -109.596449) (xy 383.198878 -109.582204) (xy 383.190496 -109.577378)
			(xy 383.18186 -109.576108) (xy 383.177099 -109.57549) (xy 383.167507 -109.575875) (xy 383.16281 -109.57687)
			(xy 383.138934 -109.582204) (xy 383.12725 -109.587284) (xy 383.102866 -109.603032) (xy 383.097532 -109.610144)
			(xy 383.087231 -109.623643) (xy 383.06459 -109.648952) (xy 383.05232 -109.66069) (xy 383.049272 -109.663484)
			(xy 383.035048 -109.67593) (xy 383.02692 -109.682788) (xy 383.022348 -109.691678) (xy 383.020059 -109.696526)
			(xy 383.017376 -109.706903) (xy 383.017014 -109.712252) (xy 382.942592 -111.339122) (xy 382.942433 -111.346273)
			(xy 382.94565 -111.360204) (xy 382.948942 -111.366554) (xy 382.95199 -111.371888) (xy 382.962658 -111.382048)
			(xy 382.969516 -111.385604) (xy 382.994285 -111.399222) (xy 383.039855 -111.432659) (xy 383.079972 -111.472476)
			(xy 383.097278 -111.494824) (xy 383.102612 -111.501682) (xy 383.124456 -111.516414) (xy 383.128408 -111.518845)
			(xy 383.136968 -111.522422) (xy 383.141474 -111.523526) (xy 383.162302 -111.528352) (xy 383.173732 -111.529622)
			(xy 383.19837 -111.522764) (xy 383.203958 -111.519716) (xy 383.229456 -111.506174) (xy 383.283127 -111.484892)
			(xy 383.339044 -111.470514) (xy 383.396324 -111.463267) (xy 383.425192 -111.46282) (xy 383.426462 -111.46282)
			(xy 383.456386 -111.463357) (xy 383.515712 -111.471257) (xy 383.573502 -111.486823) (xy 383.628769 -111.509788)
			(xy 383.680572 -111.539762) (xy 383.728026 -111.576232) (xy 383.770321 -111.618577) (xy 383.806736 -111.666074)
			(xy 383.836649 -111.717912) (xy 383.85955 -111.773206) (xy 383.875048 -111.831015) (xy 383.882879 -111.89035)
			(xy 383.883408 -111.920274) (xy 383.883408 -112.352328) (xy 383.883662 -112.784382) (xy 383.883174 -112.814356)
			(xy 383.875354 -112.873793) (xy 383.859845 -112.931701) (xy 383.836913 -112.987091) (xy 383.806949 -113.039014)
			(xy 383.770467 -113.086584) (xy 383.728089 -113.128987) (xy 383.680541 -113.165498) (xy 383.628635 -113.195492)
			(xy 383.573259 -113.218457) (xy 383.51536 -113.234001) (xy 383.455928 -113.241856) (xy 383.425954 -113.242344)
			(xy 383.425192 -113.242344) (xy 383.395556 -113.241877) (xy 383.336778 -113.234235) (xy 383.279476 -113.21908)
			(xy 383.224605 -113.196664) (xy 383.198624 -113.1824) (xy 383.190242 -113.177574) (xy 383.171446 -113.17478)
			(xy 383.168906 -113.175288) (xy 383.139696 -113.182146) (xy 383.136234 -113.183129) (xy 383.129607 -113.185937)
			(xy 383.126488 -113.187734) (xy 383.121662 -113.190782) (xy 383.102612 -113.203482) (xy 383.097278 -113.210594)
			(xy 383.078597 -113.23458) (xy 383.034925 -113.27687) (xy 382.985103 -113.311705) (xy 382.930389 -113.338203)
			(xy 382.901444 -113.3475) (xy 382.900936 -113.3475) (xy 382.900682 -113.347754) (xy 382.893331 -113.350276)
			(xy 382.880532 -113.359073) (xy 382.875536 -113.365026) (xy 382.87071 -113.371122) (xy 382.865376 -113.386108)
			(xy 382.773428 -116.19357) (xy 382.773428 -116.19611) (xy 382.801548 -117.7544) (xy 385.388102 -117.7544)
			(xy 385.392173 -117.698778) (xy 385.404299 -117.644341) (xy 385.424222 -117.59225) (xy 385.451518 -117.543615)
			(xy 385.485604 -117.499472) (xy 385.525753 -117.460763) (xy 385.571111 -117.428312) (xy 385.620711 -117.402811)
			(xy 385.673495 -117.384804) (xy 385.728338 -117.374674) (xy 385.784072 -117.372637) (xy 385.839509 -117.378737)
			(xy 385.893466 -117.392843) (xy 385.944795 -117.414655) (xy 385.992401 -117.443709) (xy 386.035269 -117.479384)
			(xy 386.072486 -117.520921) (xy 386.103259 -117.567434) (xy 386.126931 -117.617931) (xy 386.142999 -117.671338)
			(xy 386.151119 -117.726514) (xy 386.151628 -117.7544) (xy 386.151119 -117.782286) (xy 386.142999 -117.837462)
			(xy 386.126931 -117.890869) (xy 386.103259 -117.941366) (xy 386.072486 -117.987879) (xy 386.035269 -118.029416)
			(xy 385.992401 -118.065091) (xy 385.944795 -118.094145) (xy 385.893466 -118.115957) (xy 385.839509 -118.130063)
			(xy 385.784072 -118.136163) (xy 385.728338 -118.134126) (xy 385.673495 -118.123996) (xy 385.620711 -118.105989)
			(xy 385.571111 -118.080488) (xy 385.525753 -118.048037) (xy 385.485604 -118.009328) (xy 385.451518 -117.965185)
			(xy 385.424222 -117.91655) (xy 385.404299 -117.864459) (xy 385.392173 -117.810022) (xy 385.388102 -117.7544)
			(xy 382.801548 -117.7544) (xy 382.816862 -118.603014) (xy 382.817828 -118.613989) (xy 382.82783 -118.633592)
			(xy 382.845146 -118.647174) (xy 382.855724 -118.650258) (xy 382.860804 -118.651274) (xy 382.8669 -118.652544)
			(xy 382.894138 -118.658566) (xy 382.946626 -118.677448) (xy 382.995811 -118.703761) (xy 383.040648 -118.736946)
			(xy 383.080183 -118.776297) (xy 383.097278 -118.79834) (xy 383.102612 -118.805452) (xy 383.12725 -118.821454)
			(xy 383.139442 -118.826788) (xy 383.165858 -118.83263) (xy 383.173478 -118.833392) (xy 383.198624 -118.826534)
			(xy 383.203196 -118.824248) (xy 383.238248 -118.806722) (xy 383.267844 -118.793995) (xy 383.329713 -118.776034)
			(xy 383.393489 -118.766922) (xy 383.4257 -118.766336) (xy 383.455656 -118.766825) (xy 383.515056 -118.774643)
			(xy 383.572928 -118.790145) (xy 383.628282 -118.813066) (xy 383.680172 -118.843014) (xy 383.72771 -118.879477)
			(xy 383.770084 -118.921832) (xy 383.806569 -118.969353) (xy 383.836541 -119.02123) (xy 383.859487 -119.076573)
			(xy 383.875016 -119.134438) (xy 383.882861 -119.193834) (xy 383.883408 -119.22379) (xy 383.883408 -120.087898)
			(xy 383.882919 -120.117873) (xy 383.875097 -120.17731) (xy 383.859588 -120.235219) (xy 383.836655 -120.290609)
			(xy 383.806692 -120.342534) (xy 383.77021 -120.390105) (xy 383.727833 -120.43251) (xy 383.680285 -120.469024)
			(xy 383.62838 -120.499021) (xy 383.573005 -120.52199) (xy 383.515107 -120.537538) (xy 383.455675 -120.545399)
			(xy 383.4257 -120.54586) (xy 383.395984 -120.545372) (xy 383.337054 -120.537648) (xy 383.279622 -120.522355)
			(xy 383.224655 -120.499751) (xy 383.198624 -120.485408) (xy 383.194513 -120.483196) (xy 383.185694 -120.480136)
			(xy 383.181098 -120.479312) (xy 383.172208 -120.478042) (xy 383.139442 -120.485408) (xy 383.12725 -120.490742)
			(xy 383.102612 -120.506744) (xy 383.097278 -120.513856) (xy 383.081814 -120.533848) (xy 383.046469 -120.569978)
			(xy 383.00667 -120.601134) (xy 382.963113 -120.626774) (xy 382.916556 -120.646449) (xy 382.8923 -120.653556)
			(xy 382.891538 -120.65381) (xy 382.883635 -120.656366) (xy 382.869907 -120.665697) (xy 382.864614 -120.672098)
			(xy 382.859788 -120.678702) (xy 382.854708 -120.694704) (xy 382.881886 -122.218704) (xy 382.881886 -122.221244)
			(xy 382.88214 -122.22226) (xy 382.883214 -122.230821) (xy 382.890331 -122.246527) (xy 382.902289 -122.25895)
			(xy 382.909826 -122.263154) (xy 382.911858 -122.26417) (xy 382.914652 -122.26544) (xy 382.91643 -122.265948)
			(xy 382.944095 -122.276119) (xy 382.996155 -122.303756) (xy 383.043351 -122.339062) (xy 383.084563 -122.381199)
			(xy 383.102104 -122.404886) (xy 383.104644 -122.408188) (xy 383.110273 -122.414313) (xy 383.124531 -122.422863)
			(xy 383.132584 -122.424952) (xy 383.159254 -122.431048) (xy 383.164665 -122.432099) (xy 383.175687 -122.432099)
			(xy 383.181098 -122.431048) (xy 383.183384 -122.43054) (xy 383.198878 -122.426476) (xy 383.204466 -122.423428)
			(xy 383.229903 -122.409905) (xy 383.283448 -122.388647) (xy 383.339236 -122.374272) (xy 383.396387 -122.367008)
			(xy 383.425192 -122.366532) (xy 383.4257 -122.366532) (xy 383.455668 -122.367001) (xy 383.515091 -122.374825)
			(xy 383.572985 -122.390338) (xy 383.628358 -122.413276) (xy 383.680264 -122.443246) (xy 383.727813 -122.479734)
			(xy 383.770192 -122.522117) (xy 383.806677 -122.56967) (xy 383.836642 -122.621578) (xy 383.859575 -122.676953)
			(xy 383.875083 -122.734848) (xy 383.882902 -122.794272) (xy 383.883408 -122.82424) (xy 383.883408 -123.68784)
			(xy 383.882915 -123.717806) (xy 383.875088 -123.777225) (xy 383.859572 -123.835113) (xy 383.836634 -123.890482)
			(xy 383.806665 -123.942383) (xy 383.770178 -123.989928) (xy 383.727798 -124.032304) (xy 383.680249 -124.068787)
			(xy 383.628346 -124.098751) (xy 383.572975 -124.121685) (xy 383.515085 -124.137196) (xy 383.455666 -124.145018)
			(xy 383.4257 -124.145548) (xy 383.425192 -124.145548) (xy 383.396353 -124.145115) (xy 383.339133 -124.137873)
			(xy 383.283277 -124.123492) (xy 383.229673 -124.102202) (xy 383.204212 -124.088652) (xy 383.198624 -124.085604)
			(xy 383.183384 -124.08154) (xy 383.181098 -124.081032) (xy 383.175562 -124.07994) (xy 383.164282 -124.07994)
			(xy 383.158746 -124.081032) (xy 383.145792 -124.08408) (xy 383.131568 -124.087382) (xy 383.127327 -124.088473)
			(xy 383.119279 -124.091919) (xy 383.115566 -124.09424) (xy 383.102866 -124.106178) (xy 383.100072 -124.109988)
			(xy 383.080888 -124.135219) (xy 383.035561 -124.179518) (xy 383.009902 -124.198126) (xy 382.995448 -124.20803)
			(xy 382.965046 -124.225455) (xy 382.949196 -124.232924) (xy 382.948942 -124.232924) (xy 382.948434 -124.233178)
			(xy 382.940209 -124.237486) (xy 382.927312 -124.250822) (xy 382.919989 -124.267868) (xy 382.919224 -124.27712)
			(xy 383.020824 -129.911094) (xy 383.022084 -129.920898) (xy 383.030971 -129.938533) (xy 383.038096 -129.945384)
			(xy 383.038604 -129.945892) (xy 383.047494 -129.953512) (xy 383.048002 -129.95402) (xy 383.061427 -129.966496)
			(xy 383.086104 -129.993595) (xy 383.097278 -130.008122) (xy 383.102612 -130.015234) (xy 383.124202 -130.029712)
			(xy 383.128033 -130.032114) (xy 383.136332 -130.035701) (xy 383.140712 -130.036824) (xy 383.141728 -130.037078)
			(xy 383.162556 -130.041904) (xy 383.173986 -130.043174) (xy 383.198624 -130.03657) (xy 383.198878 -130.036316)
			(xy 383.224836 -130.022074) (xy 383.279639 -129.999659) (xy 383.336874 -129.9845) (xy 383.395587 -129.97685)
			(xy 383.425192 -129.976372) (xy 383.434844 -129.976372) (xy 383.464411 -129.977422) (xy 383.52292 -129.986205)
			(xy 383.579809 -130.002455) (xy 383.634129 -130.025902) (xy 383.684974 -130.056154) (xy 383.731497 -130.092707)
			(xy 383.77292 -130.13495) (xy 383.808554 -130.18218) (xy 383.837803 -130.233608) (xy 383.860181 -130.288378)
			(xy 383.875313 -130.345574) (xy 383.882947 -130.404244) (xy 383.883408 -130.433826) (xy 383.883408 -130.86588)
			(xy 383.883662 -131.297934) (xy 383.88317 -131.327917) (xy 383.875339 -131.387369) (xy 383.859815 -131.445291)
			(xy 383.836864 -131.50069) (xy 383.806878 -131.552621) (xy 383.770371 -131.600193) (xy 383.727968 -131.642594)
			(xy 383.680393 -131.679097) (xy 383.62846 -131.709079) (xy 383.573058 -131.732026) (xy 383.515136 -131.747545)
			(xy 383.455683 -131.755372) (xy 383.4257 -131.755896) (xy 383.400468 -131.755548) (xy 383.350314 -131.749965)
			(xy 383.301081 -131.73889) (xy 383.27711 -131.731004) (xy 383.258567 -131.72443) (xy 383.222576 -131.708533)
			(xy 383.205228 -131.699254) (xy 383.20472 -131.699) (xy 383.196803 -131.695139) (xy 383.179398 -131.692535)
			(xy 383.162148 -131.696028) (xy 383.154428 -131.70027) (xy 383.080768 -131.744466) (xy 383.075942 -131.750054)
			(xy 383.075434 -131.750816) (xy 383.06883 -131.757928) (xy 383.068068 -131.75869) (xy 383.062409 -131.765433)
			(xy 383.055648 -131.781673) (xy 383.05486 -131.79044) (xy 383.078447 -133.104382) (xy 385.6101 -133.104382)
			(xy 385.6101 -132.240782) (xy 385.61059 -132.210814) (xy 385.618413 -132.151392) (xy 385.633926 -132.093499)
			(xy 385.656862 -132.038126) (xy 385.686829 -131.98622) (xy 385.723316 -131.93867) (xy 385.765696 -131.89629)
			(xy 385.813246 -131.859803) (xy 385.865152 -131.829836) (xy 385.920525 -131.8069) (xy 385.978418 -131.791387)
			(xy 386.03784 -131.783564) (xy 386.097776 -131.783564) (xy 386.157198 -131.791387) (xy 386.215091 -131.8069)
			(xy 386.270464 -131.829836) (xy 386.32237 -131.859803) (xy 386.36992 -131.89629) (xy 386.4123 -131.93867)
			(xy 386.448787 -131.98622) (xy 386.478754 -132.038126) (xy 386.50169 -132.093499) (xy 386.517203 -132.151392)
			(xy 386.525026 -132.210814) (xy 386.525516 -132.240782) (xy 386.525516 -133.104382) (xy 386.525026 -133.13435)
			(xy 386.517203 -133.193772) (xy 386.50169 -133.251665) (xy 386.478754 -133.307038) (xy 386.448787 -133.358944)
			(xy 386.4123 -133.406494) (xy 386.36992 -133.448874) (xy 386.32237 -133.485361) (xy 386.270464 -133.515328)
			(xy 386.215091 -133.538264) (xy 386.157198 -133.553777) (xy 386.097776 -133.5616) (xy 386.03784 -133.5616)
			(xy 385.978418 -133.553777) (xy 385.920525 -133.538264) (xy 385.865152 -133.515328) (xy 385.813246 -133.485361)
			(xy 385.765696 -133.448874) (xy 385.723316 -133.406494) (xy 385.686829 -133.358944) (xy 385.656862 -133.307038)
			(xy 385.633926 -133.251665) (xy 385.618413 -133.193772) (xy 385.61059 -133.13435) (xy 385.6101 -133.104382)
			(xy 383.078447 -133.104382) (xy 383.086102 -133.530848) (xy 383.087064 -133.541411) (xy 383.096383 -133.560439)
			(xy 383.104136 -133.567678) (xy 383.109978 -133.571996) (xy 383.182876 -133.617208) (xy 383.188294 -133.620386)
			(xy 383.200244 -133.624243) (xy 383.206498 -133.624828) (xy 383.218944 -133.62559) (xy 383.230882 -133.620002)
			(xy 383.261434 -133.60633) (xy 383.325515 -133.587001) (xy 383.391726 -133.577203) (xy 383.425192 -133.576568)
			(xy 383.4257 -133.576568) (xy 383.455668 -133.577058) (xy 383.515092 -133.584881) (xy 383.572986 -133.600393)
			(xy 383.628361 -133.623329) (xy 383.680268 -133.653296) (xy 383.727819 -133.689782) (xy 383.770202 -133.732163)
			(xy 383.80669 -133.779712) (xy 383.83666 -133.831618) (xy 383.859599 -133.886991) (xy 383.875114 -133.944885)
			(xy 383.88294 -134.004308) (xy 383.883408 -134.034276) (xy 383.883408 -134.897876) (xy 383.88294 -134.927846)
			(xy 383.87512 -134.987274) (xy 383.859608 -135.045172) (xy 383.836673 -135.10055) (xy 383.806704 -135.152461)
			(xy 383.770217 -135.200016) (xy 383.727834 -135.242401) (xy 383.680281 -135.278891) (xy 383.628372 -135.308862)
			(xy 383.572995 -135.331801) (xy 383.515097 -135.347315) (xy 383.45567 -135.355139) (xy 383.4257 -135.355584)
			(xy 383.418842 -135.355584) (xy 383.391471 -135.354793) (xy 383.337203 -135.347476) (xy 383.2842 -135.333722)
			(xy 383.258568 -135.324088) (xy 383.258314 -135.324088) (xy 383.252342 -135.32192) (xy 383.239752 -135.320241)
			(xy 383.233422 -135.320786) (xy 383.221738 -135.32231) (xy 383.140204 -135.378952) (xy 383.132809 -135.385097)
			(xy 383.122883 -135.401548) (xy 383.1209 -135.410956) (xy 383.120138 -135.41629) (xy 383.120138 -135.417814)
			(xy 383.165096 -137.908538) (xy 383.165096 -137.909554) (xy 383.165096 -138.210036) (xy 383.16535 -138.214354)
			(xy 383.351316 -140.326364) (xy 383.992118 -140.326364) (xy 383.996189 -140.270742) (xy 384.008315 -140.216305)
			(xy 384.028238 -140.164214) (xy 384.055534 -140.115579) (xy 384.08962 -140.071436) (xy 384.129769 -140.032727)
			(xy 384.175127 -140.000276) (xy 384.224727 -139.974775) (xy 384.277511 -139.956768) (xy 384.332354 -139.946638)
			(xy 384.388088 -139.944601) (xy 384.443525 -139.950701) (xy 384.497482 -139.964807) (xy 384.548811 -139.986619)
			(xy 384.596417 -140.015673) (xy 384.639285 -140.051348) (xy 384.676502 -140.092885) (xy 384.707275 -140.139398)
			(xy 384.730947 -140.189895) (xy 384.747015 -140.243302) (xy 384.755135 -140.298478) (xy 384.755644 -140.326364)
			(xy 384.755135 -140.35425) (xy 384.747015 -140.409426) (xy 384.730947 -140.462833) (xy 384.707275 -140.51333)
			(xy 384.676502 -140.559843) (xy 384.639285 -140.60138) (xy 384.596417 -140.637055) (xy 384.548811 -140.666109)
			(xy 384.497482 -140.687921) (xy 384.443525 -140.702027) (xy 384.388088 -140.708127) (xy 384.332354 -140.70609)
			(xy 384.277511 -140.69596) (xy 384.224727 -140.677953) (xy 384.175127 -140.652452) (xy 384.129769 -140.620001)
			(xy 384.08962 -140.581292) (xy 384.055534 -140.537149) (xy 384.028238 -140.488514) (xy 384.008315 -140.436423)
			(xy 383.996189 -140.381986) (xy 383.992118 -140.326364) (xy 383.351316 -140.326364) (xy 383.415794 -141.058646)
			(xy 384.853283 -157.3784) (xy 385.490972 -157.3784) (xy 385.495043 -157.322778) (xy 385.507169 -157.268341)
			(xy 385.527092 -157.21625) (xy 385.554388 -157.167615) (xy 385.588474 -157.123472) (xy 385.628623 -157.084763)
			(xy 385.673981 -157.052312) (xy 385.723581 -157.026811) (xy 385.776365 -157.008804) (xy 385.831208 -156.998674)
			(xy 385.886942 -156.996637) (xy 385.942379 -157.002737) (xy 385.996336 -157.016843) (xy 386.047665 -157.038655)
			(xy 386.095271 -157.067709) (xy 386.138139 -157.103384) (xy 386.175356 -157.144921) (xy 386.206129 -157.191434)
			(xy 386.229801 -157.241931) (xy 386.245869 -157.295338) (xy 386.253989 -157.350514) (xy 386.254498 -157.3784)
			(xy 386.253989 -157.406286) (xy 386.245869 -157.461462) (xy 386.229801 -157.514869) (xy 386.206129 -157.565366)
			(xy 386.175356 -157.611879) (xy 386.138139 -157.653416) (xy 386.095271 -157.689091) (xy 386.047665 -157.718145)
			(xy 385.996336 -157.739957) (xy 385.942379 -157.754063) (xy 385.886942 -157.760163) (xy 385.831208 -157.758126)
			(xy 385.776365 -157.747996) (xy 385.723581 -157.729989) (xy 385.673981 -157.704488) (xy 385.628623 -157.672037)
			(xy 385.588474 -157.633328) (xy 385.554388 -157.589185) (xy 385.527092 -157.54055) (xy 385.507169 -157.488459)
			(xy 385.495043 -157.434022) (xy 385.490972 -157.3784) (xy 384.853283 -157.3784) (xy 384.942775 -158.3944)
			(xy 385.490972 -158.3944) (xy 385.495043 -158.338778) (xy 385.507169 -158.284341) (xy 385.527092 -158.23225)
			(xy 385.554388 -158.183615) (xy 385.588474 -158.139472) (xy 385.628623 -158.100763) (xy 385.673981 -158.068312)
			(xy 385.723581 -158.042811) (xy 385.776365 -158.024804) (xy 385.831208 -158.014674) (xy 385.886942 -158.012637)
			(xy 385.942379 -158.018737) (xy 385.996336 -158.032843) (xy 386.047665 -158.054655) (xy 386.095271 -158.083709)
			(xy 386.138139 -158.119384) (xy 386.175356 -158.160921) (xy 386.206129 -158.207434) (xy 386.229801 -158.257931)
			(xy 386.245869 -158.311338) (xy 386.253989 -158.366514) (xy 386.254498 -158.3944) (xy 386.253989 -158.422286)
			(xy 386.245869 -158.477462) (xy 386.229801 -158.530869) (xy 386.206129 -158.581366) (xy 386.175356 -158.627879)
			(xy 386.138139 -158.669416) (xy 386.095271 -158.705091) (xy 386.047665 -158.734145) (xy 385.996336 -158.755957)
			(xy 385.942379 -158.770063) (xy 385.886942 -158.776163) (xy 385.831208 -158.774126) (xy 385.776365 -158.763996)
			(xy 385.723581 -158.745989) (xy 385.673981 -158.720488) (xy 385.628623 -158.688037) (xy 385.588474 -158.649328)
			(xy 385.554388 -158.605185) (xy 385.527092 -158.55655) (xy 385.507169 -158.504459) (xy 385.495043 -158.450022)
			(xy 385.490972 -158.3944) (xy 384.942775 -158.3944)
		)
		(stroke
			(width 0)
			(type solid)
		)
		(fill yes)
		(layer "In11.Cu")
		(net "GND")
	)
	(gr_poly
		(pts
			(xy 39.860728 -184.455308) (xy 39.871085 -184.454763) (xy 39.890088 -184.446502) (xy 39.897558 -184.439306)
			(xy 39.897812 -184.439306) (xy 39.904554 -184.431391) (xy 39.911624 -184.411858) (xy 39.911528 -184.40146)
			(xy 38.69055 -164.354764) (xy 38.68947 -164.344551) (xy 38.680284 -164.326206) (xy 38.67277 -164.319204)
			(xy 38.665658 -164.313108) (xy 38.647116 -164.30752) (xy 38.63594 -164.308282) (xy 38.635686 -164.308282)
			(xy 38.597332 -164.310314) (xy 38.570078 -164.309853) (xy 38.516123 -164.3021) (xy 38.463821 -164.286746)
			(xy 38.414236 -164.264106) (xy 38.368379 -164.234639) (xy 38.327182 -164.198945) (xy 38.291484 -164.157752)
			(xy 38.262012 -164.111897) (xy 38.239367 -164.062315) (xy 38.224008 -164.010014) (xy 38.21625 -163.95606)
			(xy 38.215824 -163.928806) (xy 38.216305 -163.901191) (xy 38.224253 -163.846535) (xy 38.239997 -163.793596)
			(xy 38.263209 -163.74348) (xy 38.293403 -163.697235) (xy 38.32995 -163.655825) (xy 38.372085 -163.620117)
			(xy 38.418928 -163.590857) (xy 38.469499 -163.568656) (xy 38.522744 -163.553978) (xy 38.550088 -163.550092)
			(xy 38.551104 -163.550092) (xy 38.556692 -163.54933) (xy 38.573456 -163.539932) (xy 38.623748 -163.479226)
			(xy 38.629521 -163.471546) (xy 38.635405 -163.45327) (xy 38.635178 -163.443666) (xy 38.524434 -161.626042)
			(xy 38.512242 -161.605214) (xy 38.504622 -161.600388) (xy 38.480112 -161.584506) (xy 38.435784 -161.546486)
			(xy 38.397769 -161.502153) (xy 38.366956 -161.452543) (xy 38.355016 -161.42589) (xy 38.352658 -161.420544)
			(xy 38.345853 -161.411051) (xy 38.341554 -161.407094) (xy 38.332664 -161.399474) (xy 38.325298 -161.397442)
			(xy 38.243002 -161.37636) (xy 38.237309 -161.375057) (xy 38.225635 -161.374806) (xy 38.219888 -161.375852)
			(xy 38.208712 -161.378138) (xy 38.199314 -161.385504) (xy 38.179146 -161.400656) (xy 38.135581 -161.426087)
			(xy 38.089046 -161.445558) (xy 38.040353 -161.458732) (xy 37.990348 -161.465379) (xy 37.965126 -161.465768)
			(xy 37.937875 -161.465307) (xy 37.883927 -161.457553) (xy 37.831631 -161.442201) (xy 37.782053 -161.419563)
			(xy 37.736201 -161.390098) (xy 37.69501 -161.354408) (xy 37.659317 -161.313219) (xy 37.62985 -161.26737)
			(xy 37.607208 -161.217793) (xy 37.591852 -161.165499) (xy 37.584095 -161.111551) (xy 37.584095 -161.057049)
			(xy 37.591852 -161.003101) (xy 37.607208 -160.950807) (xy 37.62985 -160.90123) (xy 37.659317 -160.855381)
			(xy 37.69501 -160.814192) (xy 37.736201 -160.778502) (xy 37.782053 -160.749037) (xy 37.831631 -160.726399)
			(xy 37.883927 -160.711047) (xy 37.937875 -160.703293) (xy 37.965126 -160.702752) (xy 37.992989 -160.70326)
			(xy 38.048123 -160.711366) (xy 38.101493 -160.727402) (xy 38.151963 -160.751028) (xy 38.198463 -160.78174)
			(xy 38.240003 -160.818887) (xy 38.2757 -160.861679) (xy 38.304797 -160.909206) (xy 38.316154 -160.934654)
			(xy 38.31851 -160.940001) (xy 38.325315 -160.949495) (xy 38.329616 -160.95345) (xy 38.333934 -160.957006)
			(xy 38.344348 -160.962594) (xy 38.439852 -160.986978) (xy 38.446964 -160.985454) (xy 38.463728 -160.971738)
			(xy 38.472561 -160.963518) (xy 38.482093 -160.941387) (xy 38.482016 -160.92932) (xy 38.037262 -153.627074)
			(xy 38.036221 -153.617082) (xy 38.027393 -153.599052) (xy 38.012325 -153.585787) (xy 38.002972 -153.582116)
			(xy 37.899594 -153.546556) (xy 37.869876 -153.55443) (xy 37.859716 -153.566114) (xy 37.841506 -153.586118)
			(xy 37.800416 -153.621301) (xy 37.754772 -153.650333) (xy 37.705488 -153.672633) (xy 37.65355 -153.687755)
			(xy 37.599997 -153.695396) (xy 37.57295 -153.695908) (xy 37.545701 -153.695419) (xy 37.491759 -153.687657)
			(xy 37.43947 -153.672297) (xy 37.389899 -153.649653) (xy 37.344055 -153.620185) (xy 37.302871 -153.584494)
			(xy 37.267185 -153.543305) (xy 37.237723 -153.497457) (xy 37.215085 -153.447883) (xy 37.199733 -153.395592)
			(xy 37.191978 -153.341649) (xy 37.191978 -153.287151) (xy 37.199733 -153.233208) (xy 37.215085 -153.180917)
			(xy 37.237723 -153.131343) (xy 37.267185 -153.085495) (xy 37.302871 -153.044306) (xy 37.344055 -153.008615)
			(xy 37.389899 -152.979147) (xy 37.43947 -152.956503) (xy 37.491759 -152.941143) (xy 37.545701 -152.933381)
			(xy 37.57295 -152.932892) (xy 37.600755 -152.933391) (xy 37.655776 -152.941452) (xy 37.709046 -152.957413)
			(xy 37.759436 -152.980934) (xy 37.805879 -153.011519) (xy 37.82695 -153.029666) (xy 37.83474 -153.035961)
			(xy 37.853629 -153.04256) (xy 37.873605 -153.041441) (xy 37.88283 -153.03754) (xy 37.967412 -152.996392)
			(xy 37.976226 -152.991578) (xy 37.989575 -152.976601) (xy 37.996205 -152.957665) (xy 37.996114 -152.947624)
			(xy 37.538914 -145.440654) (xy 37.537136 -145.379948) (xy 37.537232 -145.355463) (xy 37.539521 -145.306546)
			(xy 37.541708 -145.282158) (xy 37.711634 -143.559022) (xy 37.711634 -143.558514) (xy 38.22065 -137.50798)
			(xy 38.223451 -137.477534) (xy 38.232345 -137.417038) (xy 38.23843 -137.387076) (xy 38.256972 -137.298176)
			(xy 38.258357 -137.29) (xy 38.256428 -137.273539) (xy 38.253162 -137.265918) (xy 38.249606 -137.258552)
			(xy 38.238176 -137.246868) (xy 38.230302 -137.242804) (xy 38.203382 -137.228555) (xy 38.154043 -137.192843)
			(xy 38.110982 -137.149769) (xy 38.092634 -137.125456) (xy 38.090856 -137.12317) (xy 38.06825 -137.108438)
			(xy 38.064417 -137.106041) (xy 38.056115 -137.102465) (xy 38.05174 -137.101326) (xy 38.030658 -137.0965)
			(xy 38.023038 -137.095484) (xy 38.016713 -137.095197) (xy 38.004245 -137.097371) (xy 37.9984 -137.099802)
			(xy 37.99459 -137.102088) (xy 37.968664 -137.116322) (xy 37.913925 -137.138726) (xy 37.856753 -137.15388)
			(xy 37.798103 -137.161529) (xy 37.76853 -137.162032) (xy 37.767768 -137.162032) (xy 37.737801 -137.16154)
			(xy 37.678381 -137.153713) (xy 37.62049 -137.138199) (xy 37.565119 -137.115261) (xy 37.513216 -137.085292)
			(xy 37.465668 -137.048806) (xy 37.423289 -137.006426) (xy 37.386803 -136.958878) (xy 37.356836 -136.906974)
			(xy 37.333899 -136.851603) (xy 37.318385 -136.793712) (xy 37.31056 -136.734291) (xy 37.31006 -136.704324)
			(xy 37.31006 -135.840724) (xy 37.31055 -135.810756) (xy 37.318373 -135.751334) (xy 37.333886 -135.693441)
			(xy 37.356822 -135.638068) (xy 37.386789 -135.586162) (xy 37.423276 -135.538612) (xy 37.465656 -135.496232)
			(xy 37.513206 -135.459745) (xy 37.565112 -135.429778) (xy 37.620485 -135.406842) (xy 37.678378 -135.391329)
			(xy 37.7378 -135.383506) (xy 37.797736 -135.383506) (xy 37.857158 -135.391329) (xy 37.915051 -135.406842)
			(xy 37.970424 -135.429778) (xy 38.02233 -135.459745) (xy 38.06988 -135.496232) (xy 38.11226 -135.538612)
			(xy 38.148747 -135.586162) (xy 38.178714 -135.638068) (xy 38.20165 -135.693441) (xy 38.217163 -135.751334)
			(xy 38.224986 -135.810756) (xy 38.225476 -135.840724) (xy 38.225476 -136.42467) (xy 38.225476 -136.424924)
			(xy 38.225943 -136.434557) (xy 38.233124 -136.45244) (xy 38.239446 -136.459722) (xy 38.243256 -136.463278)
			(xy 38.30193 -136.513316) (xy 38.309431 -136.519214) (xy 38.32744 -136.525486) (xy 38.336982 -136.525508)
			(xy 38.339522 -136.525508) (xy 38.342824 -136.525) (xy 38.343332 -136.525) (xy 38.344094 -136.524746)
			(xy 38.36416 -136.522206) (xy 38.392608 -136.519412) (xy 38.396141 -136.518458) (xy 38.402899 -136.515652)
			(xy 38.40607 -136.513824) (xy 38.465252 -135.91286) (xy 38.465506 -135.90778) (xy 38.46068 -134.95274)
			(xy 38.46068 -134.952232) (xy 38.369494 -128.505712) (xy 38.335712 -126.107698) (xy 38.335104 -126.097213)
			(xy 38.326518 -126.07807) (xy 38.310961 -126.063994) (xy 38.301168 -126.0602) (xy 38.298628 -126.059438)
			(xy 38.274085 -126.052117) (xy 38.227071 -126.031798) (xy 38.1832 -126.005369) (xy 38.143262 -125.973305)
			(xy 38.107974 -125.936184) (xy 38.092634 -125.915674) (xy 38.090856 -125.913388) (xy 38.06825 -125.898656)
			(xy 38.064417 -125.896259) (xy 38.056115 -125.892681) (xy 38.05174 -125.891544) (xy 38.030658 -125.886718)
			(xy 38.023038 -125.885702) (xy 38.016713 -125.885415) (xy 38.004245 -125.88759) (xy 37.9984 -125.89002)
			(xy 37.99459 -125.892306) (xy 37.968586 -125.906616) (xy 37.913671 -125.929141) (xy 37.856302 -125.94437)
			(xy 37.797446 -125.952047) (xy 37.767768 -125.952504) (xy 37.737812 -125.952013) (xy 37.678414 -125.944192)
			(xy 37.620543 -125.928687) (xy 37.565191 -125.905765) (xy 37.513302 -125.875816) (xy 37.465764 -125.839353)
			(xy 37.42339 -125.797) (xy 37.386905 -125.74948) (xy 37.356932 -125.697605) (xy 37.333983 -125.642263)
			(xy 37.318451 -125.5844) (xy 37.310602 -125.525005) (xy 37.31006 -125.49505) (xy 37.31006 -125.062742)
			(xy 37.309806 -124.630942) (xy 37.310291 -124.600987) (xy 37.318098 -124.541587) (xy 37.333582 -124.483713)
			(xy 37.356481 -124.428352) (xy 37.386403 -124.376449) (xy 37.422837 -124.328891) (xy 37.465161 -124.286489)
			(xy 37.512653 -124.249968) (xy 37.564501 -124.219952) (xy 37.619821 -124.196952) (xy 37.677667 -124.181361)
			(xy 37.737052 -124.173447) (xy 37.767006 -124.17298) (xy 37.768276 -124.17298) (xy 37.79788 -124.173462)
			(xy 37.856591 -124.181123) (xy 37.913826 -124.19628) (xy 37.968633 -124.218681) (xy 37.99459 -124.232924)
			(xy 37.998409 -124.234994) (xy 38.006584 -124.237926) (xy 38.010846 -124.238766) (xy 38.015896 -124.239627)
			(xy 38.026139 -124.239499) (xy 38.031166 -124.238512) (xy 38.051994 -124.233686) (xy 38.056379 -124.232578)
			(xy 38.064683 -124.228995) (xy 38.068504 -124.226574) (xy 38.09111 -124.211842) (xy 38.092888 -124.209556)
			(xy 38.11006 -124.186672) (xy 38.150131 -124.145839) (xy 38.195862 -124.111463) (xy 38.246223 -124.084319)
			(xy 38.272974 -124.074174) (xy 38.273228 -124.074174) (xy 38.280502 -124.071237) (xy 38.292915 -124.061661)
			(xy 38.297612 -124.055378) (xy 38.302438 -124.04852) (xy 38.30701 -124.033788) (xy 38.284912 -122.48769)
			(xy 38.284099 -122.479071) (xy 38.277479 -122.463088) (xy 38.265938 -122.450199) (xy 38.258496 -122.44578)
			(xy 38.253924 -122.443494) (xy 38.230742 -122.433342) (xy 38.187056 -122.407793) (xy 38.147138 -122.376684)
			(xy 38.11169 -122.340563) (xy 38.09619 -122.320558) (xy 38.09111 -122.313446) (xy 38.069012 -122.298714)
			(xy 38.065061 -122.29628) (xy 38.056503 -122.292698) (xy 38.051994 -122.291602) (xy 38.030658 -122.286776)
			(xy 38.021421 -122.285233) (xy 38.002932 -122.288107) (xy 37.99459 -122.292364) (xy 37.968632 -122.306605)
			(xy 37.913829 -122.329017) (xy 37.856593 -122.344172) (xy 37.79788 -122.351819) (xy 37.768276 -122.352308)
			(xy 37.751512 -122.352308) (xy 37.743892 -122.3518) (xy 37.71236 -122.349624) (xy 37.650294 -122.337681)
			(xy 37.590463 -122.317309) (xy 37.534004 -122.288898) (xy 37.481992 -122.252987) (xy 37.435417 -122.21026)
			(xy 37.395165 -122.16153) (xy 37.362003 -122.107725) (xy 37.33656 -122.049867) (xy 37.319322 -121.989058)
			(xy 37.310617 -121.926456) (xy 37.31006 -121.894854) (xy 37.31006 -121.4628) (xy 37.309806 -121.030746)
			(xy 37.310288 -121.000932) (xy 37.318034 -120.94181) (xy 37.333386 -120.884193) (xy 37.356086 -120.829056)
			(xy 37.38575 -120.777331) (xy 37.421875 -120.729893) (xy 37.463852 -120.687544) (xy 37.510969 -120.651002)
			(xy 37.562431 -120.620883) (xy 37.617365 -120.597697) (xy 37.674845 -120.581836) (xy 37.733896 -120.57357)
			(xy 37.763704 -120.572784) (xy 37.777928 -120.572784) (xy 37.80631 -120.573847) (xy 37.862503 -120.582121)
			(xy 37.917245 -120.597265) (xy 37.9697 -120.619046) (xy 37.99459 -120.632728) (xy 38.00475 -120.637046)
			(xy 38.008306 -120.638062) (xy 38.013888 -120.639269) (xy 38.025306 -120.639407) (xy 38.030912 -120.638316)
			(xy 38.051994 -120.63349) (xy 38.056379 -120.632383) (xy 38.064683 -120.628799) (xy 38.068504 -120.626378)
			(xy 38.09111 -120.611646) (xy 38.092888 -120.60936) (xy 38.110931 -120.585364) (xy 38.153296 -120.542828)
			(xy 38.201804 -120.507456) (xy 38.22827 -120.493282) (xy 38.231064 -120.491758) (xy 38.238566 -120.486909)
			(xy 38.24987 -120.473091) (xy 38.255756 -120.456238) (xy 38.255956 -120.447308) (xy 38.200838 -116.532152)
			(xy 38.200838 -116.531898) (xy 38.200584 -116.51869) (xy 38.200584 -116.517674) (xy 38.202616 -116.458746)
			(xy 38.21811 -116.199412) (xy 38.218255 -116.189774) (xy 38.212235 -116.171479) (xy 38.199936 -116.156657)
			(xy 38.191694 -116.15166) (xy 38.171628 -116.140738) (xy 38.109398 -116.106956) (xy 38.10183 -116.103497)
			(xy 38.085368 -116.101154) (xy 38.07714 -116.102384) (xy 38.056566 -116.111528) (xy 38.052502 -116.114576)
			(xy 38.038415 -116.124373) (xy 38.00878 -116.141675) (xy 37.99332 -116.14912) (xy 37.98316 -116.153946)
			(xy 37.976302 -116.162074) (xy 37.972701 -116.166466) (xy 37.967312 -116.17646) (xy 37.965634 -116.181886)
			(xy 37.96284 -116.1923) (xy 37.945314 -116.25707) (xy 37.944017 -116.262369) (xy 37.943496 -116.273264)
			(xy 37.944298 -116.27866) (xy 37.946076 -116.28882) (xy 37.952172 -116.298218) (xy 37.95268 -116.298726)
			(xy 37.968165 -116.322529) (xy 37.992672 -116.373751) (xy 38.009308 -116.428043) (xy 38.017705 -116.484202)
			(xy 38.018212 -116.512594) (xy 38.017749 -116.539847) (xy 38.009993 -116.593799) (xy 37.994637 -116.646098)
			(xy 37.971995 -116.695679) (xy 37.942527 -116.741533) (xy 37.906834 -116.782727) (xy 37.865641 -116.818421)
			(xy 37.819788 -116.84789) (xy 37.770207 -116.870534) (xy 37.717909 -116.885891) (xy 37.663957 -116.893648)
			(xy 37.636704 -116.894102) (xy 37.610417 -116.893664) (xy 37.55834 -116.886455) (xy 37.507743 -116.872173)
			(xy 37.459583 -116.851086) (xy 37.41477 -116.823595) (xy 37.37415 -116.790218) (xy 37.356034 -116.771166)
			(xy 37.355526 -116.770658) (xy 37.328094 -116.75872) (xy 37.323255 -116.756713) (xy 37.313011 -116.754526)
			(xy 37.307774 -116.754402) (xy 37.254434 -116.754402) (xy 37.249201 -116.754563) (xy 37.238964 -116.756747)
			(xy 37.234114 -116.75872) (xy 37.206682 -116.770658) (xy 37.206174 -116.771166) (xy 37.188033 -116.790195)
			(xy 37.147428 -116.823592) (xy 37.102623 -116.851098) (xy 37.054467 -116.872193) (xy 37.00387 -116.886478)
			(xy 36.951791 -116.893682) (xy 36.925504 -116.894102) (xy 36.898251 -116.893639) (xy 36.844301 -116.885883)
			(xy 36.792003 -116.870527) (xy 36.742424 -116.847885) (xy 36.696571 -116.818418) (xy 36.655378 -116.782725)
			(xy 36.619685 -116.741533) (xy 36.590217 -116.69568) (xy 36.567574 -116.6461) (xy 36.552218 -116.593803)
			(xy 36.544461 -116.539853) (xy 36.544461 -116.485347) (xy 36.552218 -116.431397) (xy 36.567574 -116.3791)
			(xy 36.590217 -116.32952) (xy 36.619685 -116.283667) (xy 36.655378 -116.242475) (xy 36.696571 -116.206782)
			(xy 36.742424 -116.177315) (xy 36.792003 -116.154673) (xy 36.844301 -116.139317) (xy 36.898251 -116.131561)
			(xy 36.925504 -116.131086) (xy 36.95179 -116.131524) (xy 37.003865 -116.138736) (xy 37.054459 -116.153022)
			(xy 37.102615 -116.174112) (xy 37.147424 -116.201608) (xy 37.188037 -116.234991) (xy 37.206174 -116.254022)
			(xy 37.206682 -116.25453) (xy 37.234114 -116.266468) (xy 37.238953 -116.268475) (xy 37.249197 -116.27066)
			(xy 37.254434 -116.270786) (xy 37.30752 -116.270786) (xy 37.312882 -116.270668) (xy 37.323381 -116.268489)
			(xy 37.328348 -116.266468) (xy 37.355526 -116.254276) (xy 37.359336 -116.250466) (xy 37.375929 -116.233451)
			(xy 37.412624 -116.203248) (xy 37.45279 -116.17784) (xy 37.474144 -116.167408) (xy 37.484304 -116.162582)
			(xy 37.491162 -116.154454) (xy 37.49476 -116.150061) (xy 37.500139 -116.140063) (xy 37.50183 -116.134642)
			(xy 37.504624 -116.124228) (xy 37.52215 -116.059458) (xy 37.52344 -116.054159) (xy 37.523946 -116.043266)
			(xy 37.523166 -116.037868) (xy 37.521388 -116.027708) (xy 37.515292 -116.01831) (xy 37.514784 -116.017802)
			(xy 37.499295 -115.994) (xy 37.47478 -115.942779) (xy 37.458137 -115.888487) (xy 37.449735 -115.832327)
			(xy 37.449252 -115.803934) (xy 37.449789 -115.775045) (xy 37.458505 -115.717928) (xy 37.47573 -115.662777)
			(xy 37.501069 -115.610852) (xy 37.533944 -115.563338) (xy 37.573603 -115.521321) (xy 37.619142 -115.48576)
			(xy 37.669519 -115.457468) (xy 37.723585 -115.437091) (xy 37.780104 -115.425094) (xy 37.808916 -115.422934)
			(xy 37.820092 -115.422426) (xy 37.829744 -115.417346) (xy 37.834308 -115.414713) (xy 37.842366 -115.407927)
			(xy 37.845746 -115.403884) (xy 37.869368 -115.373912) (xy 37.893244 -115.343686) (xy 37.896449 -115.339464)
			(xy 37.901191 -115.329987) (xy 37.902642 -115.32489) (xy 37.905182 -115.314476) (xy 37.90315 -115.303554)
			(xy 37.90032 -115.286806) (xy 37.897267 -115.252974) (xy 37.897054 -115.23599) (xy 37.897054 -115.235228)
			(xy 37.897576 -115.206444) (xy 37.906223 -115.14953) (xy 37.923323 -115.094561) (xy 37.94849 -115.042786)
			(xy 37.981151 -114.995381) (xy 38.020565 -114.953421) (xy 38.065836 -114.917861) (xy 38.115937 -114.889508)
			(xy 38.169729 -114.869005) (xy 38.225992 -114.856818) (xy 38.254686 -114.854482) (xy 38.263898 -114.853521)
			(xy 38.280772 -114.845918) (xy 38.293852 -114.832823) (xy 38.301435 -114.81594) (xy 38.302438 -114.80673)
			(xy 38.358826 -113.873788) (xy 38.358826 -113.870486) (xy 38.347904 -111.5949) (xy 38.347299 -111.583608)
			(xy 38.337612 -111.563209) (xy 38.32011 -111.548937) (xy 38.309296 -111.545624) (xy 38.281416 -111.538105)
			(xy 38.228147 -111.515824) (xy 38.178837 -111.48578) (xy 38.13461 -111.448658) (xy 38.096473 -111.405303)
			(xy 38.080442 -111.381286) (xy 38.07587 -111.37519) (xy 38.069654 -111.368668) (xy 38.053819 -111.360099)
			(xy 38.035998 -111.357529) (xy 38.018387 -111.361275) (xy 38.010592 -111.365792) (xy 37.983182 -111.382344)
			(xy 37.924719 -111.408458) (xy 37.863185 -111.426164) (xy 37.799783 -111.435116) (xy 37.767768 -111.435642)
			(xy 37.737801 -111.43515) (xy 37.67838 -111.427324) (xy 37.620489 -111.411809) (xy 37.565117 -111.388871)
			(xy 37.513213 -111.358903) (xy 37.465665 -111.322417) (xy 37.423285 -111.280037) (xy 37.386798 -111.232488)
			(xy 37.35683 -111.180585) (xy 37.333892 -111.125213) (xy 37.318377 -111.067322) (xy 37.31055 -111.007901)
			(xy 37.31006 -110.977934) (xy 37.31006 -110.114334) (xy 37.310527 -110.084363) (xy 37.318347 -110.024933)
			(xy 37.333857 -109.967032) (xy 37.356791 -109.91165) (xy 37.386759 -109.859737) (xy 37.423246 -109.812178)
			(xy 37.465629 -109.76979) (xy 37.513182 -109.733296) (xy 37.565091 -109.703321) (xy 37.620469 -109.680378)
			(xy 37.678368 -109.664859) (xy 37.737797 -109.657031) (xy 37.767768 -109.656626) (xy 37.799782 -109.657178)
			(xy 37.863181 -109.666132) (xy 37.924716 -109.683827) (xy 37.983187 -109.709919) (xy 38.010592 -109.726476)
			(xy 38.018436 -109.731019) (xy 38.036151 -109.734794) (xy 38.054073 -109.732167) (xy 38.069959 -109.723466)
			(xy 38.076124 -109.716824) (xy 38.080442 -109.710982) (xy 38.095918 -109.687724) (xy 38.132585 -109.645577)
			(xy 38.175003 -109.609225) (xy 38.222267 -109.579442) (xy 38.273366 -109.556865) (xy 38.300152 -109.54893)
			(xy 38.310731 -109.545434) (xy 38.327684 -109.531017) (xy 38.336954 -109.510785) (xy 38.33749 -109.499654)
			(xy 38.330378 -107.989878) (xy 38.329812 -107.978967) (xy 38.320674 -107.959146) (xy 38.304139 -107.9449)
			(xy 38.293802 -107.941364) (xy 38.264558 -107.932097) (xy 38.209254 -107.905557) (xy 38.158899 -107.870525)
			(xy 38.114785 -107.827899) (xy 38.095936 -107.803696) (xy 38.090856 -107.796584) (xy 38.06825 -107.781852)
			(xy 38.064417 -107.779455) (xy 38.056115 -107.775878) (xy 38.05174 -107.77474) (xy 38.030658 -107.769914)
			(xy 38.023038 -107.768898) (xy 38.016713 -107.768611) (xy 38.004245 -107.770786) (xy 37.9984 -107.773216)
			(xy 37.99459 -107.775502) (xy 37.968586 -107.789812) (xy 37.913671 -107.812337) (xy 37.856302 -107.827566)
			(xy 37.797446 -107.835243) (xy 37.767768 -107.8357) (xy 37.737812 -107.835209) (xy 37.678414 -107.827388)
			(xy 37.620544 -107.811883) (xy 37.565191 -107.788961) (xy 37.513303 -107.759012) (xy 37.465765 -107.722549)
			(xy 37.423392 -107.680196) (xy 37.386907 -107.632675) (xy 37.356934 -107.580801) (xy 37.333986 -107.525459)
			(xy 37.318454 -107.467596) (xy 37.310605 -107.408201) (xy 37.31006 -107.378246) (xy 37.31006 -106.514138)
			(xy 37.310547 -106.484163) (xy 37.318365 -106.424726) (xy 37.333872 -106.366816) (xy 37.356803 -106.311426)
			(xy 37.386767 -106.259501) (xy 37.423249 -106.211931) (xy 37.465627 -106.169527) (xy 37.513177 -106.133017)
			(xy 37.565083 -106.103023) (xy 37.62046 -106.080059) (xy 37.67836 -106.064518) (xy 37.737793 -106.056665)
			(xy 37.767768 -106.056176) (xy 37.797443 -106.056667) (xy 37.856291 -106.064367) (xy 37.913655 -106.079591)
			(xy 37.968578 -106.102085) (xy 37.99459 -106.116374) (xy 37.9984 -106.11866) (xy 38.004248 -106.121087)
			(xy 38.016714 -106.123279) (xy 38.023038 -106.122978) (xy 38.030658 -106.121962) (xy 38.05174 -106.117136)
			(xy 38.056128 -106.116034) (xy 38.064438 -106.112461) (xy 38.06825 -106.110024) (xy 38.090856 -106.095292)
			(xy 38.092634 -106.093006) (xy 38.107614 -106.072916) (xy 38.142008 -106.036468) (xy 38.180888 -106.00485)
			(xy 38.223582 -105.978608) (xy 38.246304 -105.968038) (xy 38.255774 -105.963894) (xy 38.275089 -105.956524)
			(xy 38.284912 -105.953306) (xy 38.295026 -105.949521) (xy 38.311044 -105.935066) (xy 38.319758 -105.915328)
			(xy 38.320218 -105.904538) (xy 38.312598 -104.351074) (xy 38.303962 -104.345232) (xy 38.278562 -104.336596)
			(xy 38.245796 -104.323642) (xy 38.222919 -104.312933) (xy 38.17996 -104.286361) (xy 38.140881 -104.254354)
			(xy 38.106366 -104.217472) (xy 38.091364 -104.19715) (xy 38.088824 -104.193848) (xy 38.083519 -104.188026)
			(xy 38.070198 -104.179634) (xy 38.062662 -104.177338) (xy 38.05555 -104.175814) (xy 38.030912 -104.170226)
			(xy 38.019482 -104.168956) (xy 37.994844 -104.17556) (xy 37.989256 -104.178608) (xy 37.970206 -104.188514)
			(xy 37.969698 -104.188514) (xy 37.938191 -104.203279) (xy 37.871826 -104.22418) (xy 37.803064 -104.234811)
			(xy 37.768276 -104.235504) (xy 37.767768 -104.235504) (xy 37.737802 -104.235012) (xy 37.678383 -104.227185)
			(xy 37.620493 -104.21167) (xy 37.565124 -104.188732) (xy 37.513223 -104.158763) (xy 37.465677 -104.122277)
			(xy 37.4233 -104.079896) (xy 37.386817 -104.032347) (xy 37.356852 -103.980444) (xy 37.333918 -103.925073)
			(xy 37.318408 -103.867182) (xy 37.310586 -103.807762) (xy 37.31006 -103.777796) (xy 37.31006 -102.914196)
			(xy 37.31055 -102.884228) (xy 37.318374 -102.824804) (xy 37.333886 -102.76691) (xy 37.356822 -102.711535)
			(xy 37.38679 -102.659628) (xy 37.423275 -102.612077) (xy 37.465656 -102.569694) (xy 37.513205 -102.533205)
			(xy 37.56511 -102.503235) (xy 37.620483 -102.480295) (xy 37.678377 -102.464779) (xy 37.7378 -102.456952)
			(xy 37.767768 -102.456488) (xy 37.76853 -102.456488) (xy 37.798101 -102.45699) (xy 37.856742 -102.464676)
			(xy 37.913909 -102.479837) (xy 37.968651 -102.502224) (xy 37.99459 -102.516432) (xy 37.9984 -102.518718)
			(xy 38.004248 -102.521146) (xy 38.016714 -102.52334) (xy 38.023038 -102.523036) (xy 38.030658 -102.52202)
			(xy 38.05174 -102.517194) (xy 38.056127 -102.516091) (xy 38.064436 -102.512515) (xy 38.06825 -102.510082)
			(xy 38.090856 -102.49535) (xy 38.092634 -102.493064) (xy 38.108444 -102.471964) (xy 38.144927 -102.4339)
			(xy 38.186297 -102.401214) (xy 38.231769 -102.374526) (xy 38.255956 -102.364032) (xy 38.25621 -102.364032)
			(xy 38.263185 -102.360848) (xy 38.274949 -102.351025) (xy 38.279324 -102.344728) (xy 38.283388 -102.338378)
			(xy 38.287452 -102.3239) (xy 38.254178 -100.758498) (xy 38.25385 -100.751657) (xy 38.249975 -100.738527)
			(xy 38.246558 -100.73259) (xy 38.243002 -100.727002) (xy 38.232842 -100.717604) (xy 38.226746 -100.714556)
			(xy 38.210431 -100.70585) (xy 38.179391 -100.685746) (xy 38.16477 -100.674424) (xy 38.145687 -100.658832)
			(xy 38.111289 -100.623542) (xy 38.09619 -100.604066) (xy 38.09111 -100.596954) (xy 38.068504 -100.582222)
			(xy 38.064669 -100.579829) (xy 38.056365 -100.576261) (xy 38.051994 -100.57511) (xy 38.029642 -100.57003)
			(xy 38.020633 -100.568673) (xy 38.002674 -100.571669) (xy 37.99459 -100.575872) (xy 37.968632 -100.590113)
			(xy 37.913829 -100.612524) (xy 37.856593 -100.627679) (xy 37.79788 -100.635326) (xy 37.768276 -100.635816)
			(xy 37.751512 -100.635816) (xy 37.743892 -100.635308) (xy 37.71236 -100.633132) (xy 37.650294 -100.621189)
			(xy 37.590461 -100.600818) (xy 37.534002 -100.572406) (xy 37.48199 -100.536496) (xy 37.435414 -100.493769)
			(xy 37.395161 -100.445039) (xy 37.361998 -100.391233) (xy 37.336555 -100.333375) (xy 37.319316 -100.272567)
			(xy 37.310609 -100.209964) (xy 37.31006 -100.178362) (xy 37.31006 -99.746308) (xy 37.309806 -99.314254)
			(xy 37.310299 -99.284271) (xy 37.318131 -99.224818) (xy 37.333656 -99.166896) (xy 37.356607 -99.111496)
			(xy 37.386593 -99.059565) (xy 37.423099 -99.011992) (xy 37.465502 -98.96959) (xy 37.513077 -98.933085)
			(xy 37.565009 -98.903101) (xy 37.62041 -98.880151) (xy 37.678332 -98.864629) (xy 37.737785 -98.856798)
			(xy 37.767768 -98.856292) (xy 37.795799 -98.856745) (xy 37.851433 -98.863657) (xy 37.905805 -98.87732)
			(xy 37.932106 -98.887026) (xy 37.946778 -98.892765) (xy 37.975377 -98.905987) (xy 37.989256 -98.913442)
			(xy 37.994844 -98.91649) (xy 38.019228 -98.923094) (xy 38.030658 -98.921824) (xy 38.051994 -98.916998)
			(xy 38.056515 -98.915938) (xy 38.065085 -98.912364) (xy 38.069012 -98.909886) (xy 38.09111 -98.895154)
			(xy 38.09619 -98.888042) (xy 38.109906 -98.87077) (xy 38.127444 -98.850606) (xy 38.167216 -98.814911)
			(xy 38.189154 -98.79965) (xy 38.197892 -98.793204) (xy 38.209345 -98.77478) (xy 38.211252 -98.76409)
			(xy 38.21176 -98.756216) (xy 38.16985 -96.790764) (xy 38.16985 -96.789748) (xy 38.10762 -95.231458)
			(xy 38.106788 -95.221727) (xy 38.098773 -95.203935) (xy 38.084689 -95.190428) (xy 38.066578 -95.183164)
			(xy 38.05682 -95.18269) (xy 36.440364 -95.18269) (xy 36.431152 -95.183102) (xy 36.413919 -95.189628)
			(xy 36.400083 -95.201798) (xy 36.39141 -95.218057) (xy 36.389818 -95.22714) (xy 36.273937 -96.1644)
			(xy 37.225476 -96.1644) (xy 37.229547 -96.108778) (xy 37.241673 -96.054341) (xy 37.261596 -96.00225)
			(xy 37.288892 -95.953615) (xy 37.322978 -95.909472) (xy 37.363127 -95.870763) (xy 37.408485 -95.838312)
			(xy 37.458085 -95.812811) (xy 37.510869 -95.794804) (xy 37.565712 -95.784674) (xy 37.621446 -95.782637)
			(xy 37.676883 -95.788737) (xy 37.73084 -95.802843) (xy 37.782169 -95.824655) (xy 37.829775 -95.853709)
			(xy 37.872643 -95.889384) (xy 37.90986 -95.930921) (xy 37.940633 -95.977434) (xy 37.964305 -96.027931)
			(xy 37.980373 -96.081338) (xy 37.988493 -96.136514) (xy 37.989002 -96.1644) (xy 37.988493 -96.192286)
			(xy 37.980373 -96.247462) (xy 37.964305 -96.300869) (xy 37.940633 -96.351366) (xy 37.90986 -96.397879)
			(xy 37.872643 -96.439416) (xy 37.829775 -96.475091) (xy 37.782169 -96.504145) (xy 37.73084 -96.525957)
			(xy 37.676883 -96.540063) (xy 37.621446 -96.546163) (xy 37.565712 -96.544126) (xy 37.510869 -96.533996)
			(xy 37.458085 -96.515989) (xy 37.408485 -96.490488) (xy 37.363127 -96.458037) (xy 37.322978 -96.419328)
			(xy 37.288892 -96.375185) (xy 37.261596 -96.32655) (xy 37.241673 -96.274459) (xy 37.229547 -96.220022)
			(xy 37.225476 -96.1644) (xy 36.273937 -96.1644) (xy 36.14832 -97.1804) (xy 37.225476 -97.1804) (xy 37.229547 -97.124778)
			(xy 37.241673 -97.070341) (xy 37.261596 -97.01825) (xy 37.288892 -96.969615) (xy 37.322978 -96.925472)
			(xy 37.363127 -96.886763) (xy 37.408485 -96.854312) (xy 37.458085 -96.828811) (xy 37.510869 -96.810804)
			(xy 37.565712 -96.800674) (xy 37.621446 -96.798637) (xy 37.676883 -96.804737) (xy 37.73084 -96.818843)
			(xy 37.782169 -96.840655) (xy 37.829775 -96.869709) (xy 37.872643 -96.905384) (xy 37.90986 -96.946921)
			(xy 37.940633 -96.993434) (xy 37.964305 -97.043931) (xy 37.980373 -97.097338) (xy 37.988493 -97.152514)
			(xy 37.989002 -97.1804) (xy 37.988493 -97.208286) (xy 37.980373 -97.263462) (xy 37.964305 -97.316869)
			(xy 37.940633 -97.367366) (xy 37.90986 -97.413879) (xy 37.872643 -97.455416) (xy 37.829775 -97.491091)
			(xy 37.782169 -97.520145) (xy 37.73084 -97.541957) (xy 37.676883 -97.556063) (xy 37.621446 -97.562163)
			(xy 37.565712 -97.560126) (xy 37.510869 -97.549996) (xy 37.458085 -97.531989) (xy 37.408485 -97.506488)
			(xy 37.363127 -97.474037) (xy 37.322978 -97.435328) (xy 37.288892 -97.391185) (xy 37.261596 -97.34255)
			(xy 37.241673 -97.290459) (xy 37.229547 -97.236022) (xy 37.225476 -97.1804) (xy 36.14832 -97.1804)
			(xy 35.84194 -99.658424) (xy 35.832542 -99.71913) (xy 35.677602 -100.544122) (xy 35.676167 -100.554133)
			(xy 35.680364 -100.573902) (xy 35.68573 -100.582476) (xy 35.687254 -100.584508) (xy 35.726878 -100.63607)
			(xy 35.730212 -100.640158) (xy 35.738282 -100.646948) (xy 35.74288 -100.649532) (xy 35.769296 -100.66401)
			(xy 35.77971 -100.665026) (xy 35.810185 -100.668516) (xy 35.869884 -100.682609) (xy 35.927168 -100.704544)
			(xy 35.981012 -100.733927) (xy 36.030454 -100.770233) (xy 36.074608 -100.812813) (xy 36.112685 -100.860904)
			(xy 36.144003 -100.913646) (xy 36.168002 -100.970096) (xy 36.184254 -101.029244) (xy 36.192466 -101.090032)
			(xy 36.192968 -101.120702) (xy 36.192968 -101.552502) (xy 36.193222 -101.984302) (xy 36.192753 -102.014287)
			(xy 36.184924 -102.073743) (xy 36.169402 -102.131668) (xy 36.146452 -102.187072) (xy 36.116465 -102.239006)
			(xy 36.079956 -102.286581) (xy 36.03755 -102.328984) (xy 35.989971 -102.365489) (xy 35.938034 -102.39547)
			(xy 35.882629 -102.418416) (xy 35.824702 -102.433933) (xy 35.765245 -102.441755) (xy 35.73526 -102.442264)
			(xy 35.706824 -102.441818) (xy 35.650393 -102.434742) (xy 35.595275 -102.420728) (xy 35.568636 -102.410768)
			(xy 35.55456 -102.405153) (xy 35.527106 -102.392315) (xy 35.513772 -102.385114) (xy 35.508184 -102.382066)
			(xy 35.4838 -102.375462) (xy 35.47237 -102.376732) (xy 35.451034 -102.381558) (xy 35.446515 -102.382623)
			(xy 35.437951 -102.386205) (xy 35.434016 -102.38867) (xy 35.411918 -102.403402) (xy 35.406838 -102.410514)
			(xy 35.389445 -102.432865) (xy 35.349149 -102.47266) (xy 35.326574 -102.489762) (xy 35.326066 -102.490016)
			(xy 35.319013 -102.495739) (xy 35.309136 -102.510966) (xy 35.306762 -102.519734) (xy 35.304984 -102.529386)
			(xy 35.29965 -102.558596) (xy 35.299142 -102.560882) (xy 35.07359 -104.19715) (xy 35.072589 -104.208296)
			(xy 35.079185 -104.229651) (xy 35.08629 -104.238298) (xy 35.094164 -104.246934) (xy 35.097659 -104.250625)
			(xy 35.105852 -104.256642) (xy 35.11042 -104.258872) (xy 35.119818 -104.26319) (xy 35.13074 -104.26319)
			(xy 35.160493 -104.263994) (xy 35.219422 -104.272358) (xy 35.276769 -104.28829) (xy 35.331568 -104.31152)
			(xy 35.382894 -104.341657) (xy 35.42988 -104.378193) (xy 35.471734 -104.42051) (xy 35.507751 -104.467896)
			(xy 35.537321 -104.51955) (xy 35.559947 -104.574601) (xy 35.575246 -104.632121) (xy 35.582961 -104.691138)
			(xy 35.583368 -104.720898) (xy 35.583368 -105.152698) (xy 35.583622 -105.584498) (xy 35.58314 -105.614367)
			(xy 35.575373 -105.673599) (xy 35.559972 -105.731319) (xy 35.537197 -105.786546) (xy 35.507435 -105.838344)
			(xy 35.471192 -105.885832) (xy 35.429082 -105.928206) (xy 35.38182 -105.964745) (xy 35.330209 -105.994829)
			(xy 35.275125 -106.017948) (xy 35.217503 -106.033709) (xy 35.15832 -106.041845) (xy 35.128454 -106.04246)
			(xy 35.122104 -106.04246) (xy 35.090146 -106.041665) (xy 35.026919 -106.032229) (xy 34.99612 -106.023664)
			(xy 34.984944 -106.020362) (xy 34.974022 -106.02214) (xy 34.96853 -106.023147) (xy 34.958149 -106.027255)
			(xy 34.953448 -106.030268) (xy 34.891218 -106.072686) (xy 34.887408 -106.075226) (xy 34.883344 -106.078528)
			(xy 34.801556 -107.863386) (xy 34.801581 -107.8725) (xy 34.807264 -107.889806) (xy 34.818603 -107.90406)
			(xy 34.826194 -107.909106) (xy 34.848038 -107.922314) (xy 34.85167 -107.924394) (xy 34.859456 -107.927463)
			(xy 34.863532 -107.92841) (xy 34.869996 -107.929608) (xy 34.883122 -107.928958) (xy 34.88944 -107.92714)
			(xy 34.895536 -107.924854) (xy 34.89706 -107.924092) (xy 34.899346 -107.922822) (xy 34.925254 -107.908637)
			(xy 34.97994 -107.886319) (xy 35.037046 -107.871227) (xy 35.095619 -107.863616) (xy 35.125152 -107.863132)
			(xy 35.12566 -107.863132) (xy 35.15563 -107.863599) (xy 35.215057 -107.871418) (xy 35.272955 -107.886928)
			(xy 35.328333 -107.909863) (xy 35.380243 -107.939832) (xy 35.427797 -107.97632) (xy 35.47018 -108.018703)
			(xy 35.506668 -108.066257) (xy 35.536637 -108.118167) (xy 35.559572 -108.173545) (xy 35.575082 -108.231443)
			(xy 35.582901 -108.29087) (xy 35.583368 -108.32084) (xy 35.583368 -109.18444) (xy 35.582875 -109.214405)
			(xy 35.575048 -109.273822) (xy 35.559532 -109.331708) (xy 35.536593 -109.387074) (xy 35.506623 -109.438973)
			(xy 35.470136 -109.486515) (xy 35.427755 -109.528889) (xy 35.380206 -109.565368) (xy 35.328303 -109.595328)
			(xy 35.272932 -109.618257) (xy 35.215043 -109.633763) (xy 35.155625 -109.641581) (xy 35.12566 -109.642148)
			(xy 35.124898 -109.642148) (xy 35.095327 -109.641648) (xy 35.036684 -109.633966) (xy 34.979515 -109.618808)
			(xy 34.92477 -109.596426) (xy 34.898838 -109.582204) (xy 34.89579 -109.580426) (xy 34.890627 -109.578107)
			(xy 34.879603 -109.575551) (xy 34.873946 -109.575346) (xy 34.862516 -109.576616) (xy 34.841434 -109.581442)
			(xy 34.837048 -109.582548) (xy 34.828743 -109.586129) (xy 34.824924 -109.588554) (xy 34.802826 -109.603032)
			(xy 34.797492 -109.610144) (xy 34.783689 -109.628109) (xy 34.752492 -109.660965) (xy 34.735262 -109.675676)
			(xy 34.735008 -109.67593) (xy 34.727293 -109.683119) (xy 34.717972 -109.702009) (xy 34.716974 -109.712506)
			(xy 34.641282 -111.364522) (xy 34.64687 -111.373666) (xy 34.669476 -111.385604) (xy 34.694226 -111.399196)
			(xy 34.739779 -111.432558) (xy 34.779914 -111.472272) (xy 34.797238 -111.49457) (xy 34.802318 -111.501682)
			(xy 34.82467 -111.516414) (xy 34.828547 -111.518858) (xy 34.83698 -111.522446) (xy 34.841434 -111.523526)
			(xy 34.862516 -111.528352) (xy 34.868387 -111.529437) (xy 34.880322 -111.529191) (xy 34.886138 -111.527844)
			(xy 34.887662 -111.52759) (xy 34.898584 -111.522764) (xy 34.899092 -111.522764) (xy 34.925022 -111.508538)
			(xy 34.979763 -111.486144) (xy 35.036934 -111.470989) (xy 35.09558 -111.463325) (xy 35.125152 -111.46282)
			(xy 35.141916 -111.46282) (xy 35.149536 -111.463328) (xy 35.18107 -111.4655) (xy 35.243142 -111.477435)
			(xy 35.302981 -111.497801) (xy 35.359446 -111.526209) (xy 35.411465 -111.562119) (xy 35.458046 -111.604846)
			(xy 35.498302 -111.653578) (xy 35.531468 -111.707387) (xy 35.556912 -111.765249) (xy 35.57415 -111.826062)
			(xy 35.582853 -111.888669) (xy 35.583368 -111.920274) (xy 35.583368 -112.352328) (xy 35.583622 -112.784382)
			(xy 35.583144 -112.814199) (xy 35.575407 -112.87333) (xy 35.560061 -112.930956) (xy 35.537365 -112.986103)
			(xy 35.507704 -113.037838) (xy 35.47158 -113.085286) (xy 35.429603 -113.127644) (xy 35.382484 -113.164197)
			(xy 35.331019 -113.194324) (xy 35.276079 -113.217517) (xy 35.218594 -113.233384) (xy 35.159536 -113.241656)
			(xy 35.129724 -113.242344) (xy 35.114738 -113.242344) (xy 35.086483 -113.241232) (xy 35.030553 -113.232903)
			(xy 34.976071 -113.217761) (xy 34.923864 -113.196035) (xy 34.899092 -113.1824) (xy 34.898838 -113.1824)
			(xy 34.89093 -113.178279) (xy 34.873389 -113.175147) (xy 34.864548 -113.176304) (xy 34.841434 -113.181638)
			(xy 34.837048 -113.182744) (xy 34.828743 -113.186325) (xy 34.824924 -113.18875) (xy 34.802318 -113.203482)
			(xy 34.80054 -113.205768) (xy 34.785603 -113.225707) (xy 34.75138 -113.261914) (xy 34.712737 -113.29336)
			(xy 34.670331 -113.31951) (xy 34.624884 -113.339921) (xy 34.60115 -113.3475) (xy 34.59353 -113.349786)
			(xy 34.580576 -113.358422) (xy 34.57575 -113.364772) (xy 34.571054 -113.371241) (xy 34.565605 -113.38626)
			(xy 34.565082 -113.394236) (xy 34.473388 -116.19357) (xy 34.473388 -116.19611) (xy 34.50152 -117.7544)
			(xy 37.088062 -117.7544) (xy 37.092133 -117.698778) (xy 37.104259 -117.644341) (xy 37.124182 -117.59225)
			(xy 37.151478 -117.543615) (xy 37.185564 -117.499472) (xy 37.225713 -117.460763) (xy 37.271071 -117.428312)
			(xy 37.320671 -117.402811) (xy 37.373455 -117.384804) (xy 37.428298 -117.374674) (xy 37.484032 -117.372637)
			(xy 37.539469 -117.378737) (xy 37.593426 -117.392843) (xy 37.644755 -117.414655) (xy 37.692361 -117.443709)
			(xy 37.735229 -117.479384) (xy 37.772446 -117.520921) (xy 37.803219 -117.567434) (xy 37.826891 -117.617931)
			(xy 37.842959 -117.671338) (xy 37.851079 -117.726514) (xy 37.851588 -117.7544) (xy 37.851079 -117.782286)
			(xy 37.842959 -117.837462) (xy 37.826891 -117.890869) (xy 37.803219 -117.941366) (xy 37.772446 -117.987879)
			(xy 37.735229 -118.029416) (xy 37.692361 -118.065091) (xy 37.644755 -118.094145) (xy 37.593426 -118.115957)
			(xy 37.539469 -118.130063) (xy 37.484032 -118.136163) (xy 37.428298 -118.134126) (xy 37.373455 -118.123996)
			(xy 37.320671 -118.105989) (xy 37.271071 -118.080488) (xy 37.225713 -118.048037) (xy 37.185564 -118.009328)
			(xy 37.151478 -117.965185) (xy 37.124182 -117.91655) (xy 37.104259 -117.864459) (xy 37.092133 -117.810022)
			(xy 37.088062 -117.7544) (xy 34.50152 -117.7544) (xy 34.516822 -118.601998) (xy 34.516822 -118.602506)
			(xy 34.517458 -118.61154) (xy 34.524219 -118.628327) (xy 34.53003 -118.635272) (xy 34.535911 -118.641351)
			(xy 34.55071 -118.649521) (xy 34.558986 -118.651274) (xy 34.571432 -118.65356) (xy 34.57194 -118.65356)
			(xy 34.599209 -118.659932) (xy 34.651644 -118.679586) (xy 34.700646 -118.706688) (xy 34.745164 -118.740658)
			(xy 34.784242 -118.780766) (xy 34.801048 -118.803166) (xy 34.802572 -118.805452) (xy 34.825178 -118.820184)
			(xy 34.829012 -118.822578) (xy 34.837316 -118.826148) (xy 34.841688 -118.827296) (xy 34.86277 -118.832122)
			(xy 34.87039 -118.833138) (xy 34.876714 -118.833421) (xy 34.889178 -118.831238) (xy 34.895028 -118.82882)
			(xy 34.898838 -118.826534) (xy 34.924842 -118.812224) (xy 34.979757 -118.789701) (xy 35.037126 -118.774474)
			(xy 35.095983 -118.7668) (xy 35.12566 -118.766336) (xy 35.155618 -118.766823) (xy 35.215021 -118.774636)
			(xy 35.272898 -118.790135) (xy 35.328256 -118.813054) (xy 35.380151 -118.843) (xy 35.427694 -118.879463)
			(xy 35.470072 -118.921818) (xy 35.506561 -118.969341) (xy 35.536536 -119.021219) (xy 35.559485 -119.076565)
			(xy 35.575015 -119.134433) (xy 35.582861 -119.193833) (xy 35.583368 -119.22379) (xy 35.583368 -120.087898)
			(xy 35.582879 -120.117872) (xy 35.575057 -120.177307) (xy 35.559547 -120.235214) (xy 35.536614 -120.290602)
			(xy 35.50665 -120.342524) (xy 35.470167 -120.390093) (xy 35.42779 -120.432495) (xy 35.380242 -120.469004)
			(xy 35.328337 -120.498998) (xy 35.272962 -120.521963) (xy 35.215065 -120.537506) (xy 35.155634 -120.545362)
			(xy 35.12566 -120.54586) (xy 35.095985 -120.54537) (xy 35.037136 -120.537673) (xy 34.979771 -120.52245)
			(xy 34.924848 -120.499956) (xy 34.898838 -120.485662) (xy 34.895028 -120.483376) (xy 34.889179 -120.480957)
			(xy 34.876714 -120.478781) (xy 34.87039 -120.479058) (xy 34.86277 -120.480074) (xy 34.841688 -120.4849)
			(xy 34.8373 -120.486001) (xy 34.828988 -120.489572) (xy 34.825178 -120.492012) (xy 34.802572 -120.506744)
			(xy 34.800794 -120.50903) (xy 34.78228 -120.533678) (xy 34.738628 -120.577202) (xy 34.713926 -120.595644)
			(xy 34.686015 -120.614775) (xy 34.624947 -120.643906) (xy 34.592514 -120.653556) (xy 34.592006 -120.653556)
			(xy 34.591498 -120.65381) (xy 34.58359 -120.656358) (xy 34.569848 -120.66568) (xy 34.564574 -120.672098)
			(xy 34.559748 -120.678702) (xy 34.554668 -120.694704) (xy 34.581846 -122.218704) (xy 34.582354 -122.225054)
			(xy 34.584067 -122.23424) (xy 34.593121 -122.250567) (xy 34.607429 -122.262561) (xy 34.616136 -122.265948)
			(xy 34.643844 -122.276085) (xy 34.695986 -122.303686) (xy 34.743245 -122.339003) (xy 34.784489 -122.381188)
			(xy 34.802064 -122.404886) (xy 34.805474 -122.409374) (xy 34.813939 -122.416814) (xy 34.818828 -122.419618)
			(xy 34.82207 -122.421391) (xy 34.828956 -122.424068) (xy 34.832544 -122.424952) (xy 34.86277 -122.43181)
			(xy 34.8742 -122.43308) (xy 34.898584 -122.426476) (xy 34.904172 -122.423428) (xy 34.929589 -122.409936)
			(xy 34.98307 -122.388695) (xy 35.03879 -122.374322) (xy 35.095872 -122.367043) (xy 35.124644 -122.366532)
			(xy 35.12566 -122.366532) (xy 35.15563 -122.366999) (xy 35.215057 -122.374818) (xy 35.272955 -122.390328)
			(xy 35.328333 -122.413263) (xy 35.380243 -122.443232) (xy 35.427797 -122.47972) (xy 35.47018 -122.522103)
			(xy 35.506668 -122.569657) (xy 35.536637 -122.621567) (xy 35.559572 -122.676945) (xy 35.575082 -122.734843)
			(xy 35.582901 -122.79427) (xy 35.583368 -122.82424) (xy 35.583368 -123.68784) (xy 35.582875 -123.717805)
			(xy 35.575048 -123.777222) (xy 35.559532 -123.835108) (xy 35.536593 -123.890474) (xy 35.506623 -123.942373)
			(xy 35.470136 -123.989915) (xy 35.427755 -124.032289) (xy 35.380206 -124.068768) (xy 35.328303 -124.098728)
			(xy 35.272932 -124.121657) (xy 35.215043 -124.137163) (xy 35.155625 -124.144981) (xy 35.12566 -124.145548)
			(xy 35.098143 -124.145165) (xy 35.043498 -124.13863) (xy 34.990026 -124.125612) (xy 34.964116 -124.116338)
			(xy 34.948707 -124.11037) (xy 34.918707 -124.096513) (xy 34.904172 -124.088652) (xy 34.898584 -124.085604)
			(xy 34.873946 -124.079) (xy 34.862516 -124.08027) (xy 34.837878 -124.085858) (xy 34.830766 -124.087382)
			(xy 34.823207 -124.089625) (xy 34.809878 -124.098031) (xy 34.804604 -124.103892) (xy 34.802064 -124.107194)
			(xy 34.787184 -124.127338) (xy 34.752989 -124.163929) (xy 34.714305 -124.195737) (xy 34.671796 -124.222217)
			(xy 34.649156 -124.232924) (xy 34.648902 -124.233178) (xy 34.642327 -124.236405) (xy 34.631225 -124.245951)
			(xy 34.627058 -124.251974) (xy 34.622994 -124.258324) (xy 34.619184 -124.272294) (xy 34.72053 -129.908046)
			(xy 34.720772 -129.913513) (xy 34.723337 -129.92415) (xy 34.72561 -129.929128) (xy 34.730182 -129.93878)
			(xy 34.738564 -129.945892) (xy 34.745168 -129.95148) (xy 34.745676 -129.951988) (xy 34.754937 -129.960373)
			(xy 34.772475 -129.978169) (xy 34.780728 -129.987548) (xy 34.800794 -130.012694) (xy 34.802572 -130.015234)
			(xy 34.82467 -130.029966) (xy 34.828623 -130.032394) (xy 34.837184 -130.035965) (xy 34.841688 -130.037078)
			(xy 34.86531 -130.042412) (xy 34.873228 -130.043422) (xy 34.889009 -130.041092) (xy 34.896298 -130.03784)
			(xy 34.924335 -130.022256) (xy 34.983811 -129.998229) (xy 35.046062 -129.982752) (xy 35.077908 -129.978912)
			(xy 35.089811 -129.977727) (xy 35.113699 -129.976457) (xy 35.12566 -129.976372) (xy 35.155619 -129.976859)
			(xy 35.215026 -129.984672) (xy 35.272906 -130.00017) (xy 35.328268 -130.023088) (xy 35.380166 -130.053034)
			(xy 35.427714 -130.089496) (xy 35.470097 -130.13185) (xy 35.506592 -130.179372) (xy 35.536573 -130.23125)
			(xy 35.559529 -130.286597) (xy 35.575067 -130.344466) (xy 35.582921 -130.403867) (xy 35.583368 -130.433826)
			(xy 35.583368 -130.86588) (xy 35.583622 -131.297934) (xy 35.583151 -131.327917) (xy 35.575319 -131.38737)
			(xy 35.559794 -131.445292) (xy 35.536842 -131.500692) (xy 35.506854 -131.552623) (xy 35.470345 -131.600195)
			(xy 35.427939 -131.642594) (xy 35.380361 -131.679095) (xy 35.328426 -131.709074) (xy 35.273022 -131.732018)
			(xy 35.215098 -131.747533) (xy 35.155643 -131.755356) (xy 35.12566 -131.755896) (xy 35.119818 -131.755896)
			(xy 35.09179 -131.755102) (xy 35.036233 -131.747522) (xy 34.982016 -131.73322) (xy 34.929949 -131.712409)
			(xy 34.905188 -131.699254) (xy 34.904934 -131.699254) (xy 34.894266 -131.693412) (xy 34.892996 -131.69265)
			(xy 34.880296 -131.69265) (xy 34.873475 -131.692944) (xy 34.860348 -131.696684) (xy 34.854388 -131.700016)
			(xy 34.780728 -131.744466) (xy 34.775902 -131.750054) (xy 34.775394 -131.750816) (xy 34.768536 -131.758182)
			(xy 34.761678 -131.765548) (xy 34.758122 -131.774438) (xy 34.756486 -131.77909) (xy 34.754832 -131.78881)
			(xy 34.75482 -131.793742) (xy 34.778308 -133.104382) (xy 37.31006 -133.104382) (xy 37.31006 -132.240782)
			(xy 37.31055 -132.210814) (xy 37.318373 -132.151392) (xy 37.333886 -132.093499) (xy 37.356822 -132.038126)
			(xy 37.386789 -131.98622) (xy 37.423276 -131.93867) (xy 37.465656 -131.89629) (xy 37.513206 -131.859803)
			(xy 37.565112 -131.829836) (xy 37.620485 -131.8069) (xy 37.678378 -131.791387) (xy 37.7378 -131.783564)
			(xy 37.797736 -131.783564) (xy 37.857158 -131.791387) (xy 37.915051 -131.8069) (xy 37.970424 -131.829836)
			(xy 38.02233 -131.859803) (xy 38.06988 -131.89629) (xy 38.11226 -131.93867) (xy 38.148747 -131.98622)
			(xy 38.178714 -132.038126) (xy 38.20165 -132.093499) (xy 38.217163 -132.151392) (xy 38.224986 -132.210814)
			(xy 38.225476 -132.240782) (xy 38.225476 -133.104382) (xy 38.224986 -133.13435) (xy 38.217163 -133.193772)
			(xy 38.20165 -133.251665) (xy 38.178714 -133.307038) (xy 38.148747 -133.358944) (xy 38.11226 -133.406494)
			(xy 38.06988 -133.448874) (xy 38.02233 -133.485361) (xy 37.970424 -133.515328) (xy 37.915051 -133.538264)
			(xy 37.857158 -133.553777) (xy 37.797736 -133.5616) (xy 37.7378 -133.5616) (xy 37.678378 -133.553777)
			(xy 37.620485 -133.538264) (xy 37.565112 -133.515328) (xy 37.513206 -133.485361) (xy 37.465656 -133.448874)
			(xy 37.423276 -133.406494) (xy 37.386789 -133.358944) (xy 37.356822 -133.307038) (xy 37.333886 -133.251665)
			(xy 37.318373 -133.193772) (xy 37.31055 -133.13435) (xy 37.31006 -133.104382) (xy 34.778308 -133.104382)
			(xy 34.78276 -133.352794) (xy 34.786062 -133.530594) (xy 34.787135 -133.543098) (xy 34.799641 -133.564825)
			(xy 34.809938 -133.571996) (xy 34.882836 -133.617208) (xy 34.888256 -133.62038) (xy 34.900207 -133.624222)
			(xy 34.906458 -133.624828) (xy 34.918904 -133.62559) (xy 34.930842 -133.620002) (xy 34.961395 -133.606334)
			(xy 35.025476 -133.587014) (xy 35.091687 -133.577224) (xy 35.125152 -133.576568) (xy 35.12566 -133.576568)
			(xy 35.155631 -133.577035) (xy 35.215062 -133.584854) (xy 35.272963 -133.600363) (xy 35.328344 -133.623298)
			(xy 35.380258 -133.653265) (xy 35.427817 -133.689752) (xy 35.470205 -133.732135) (xy 35.506699 -133.779688)
			(xy 35.536674 -133.831598) (xy 35.559616 -133.886976) (xy 35.575134 -133.944875) (xy 35.582961 -134.004305)
			(xy 35.583368 -134.034276) (xy 35.583368 -134.897876) (xy 35.5829 -134.927845) (xy 35.575079 -134.987271)
			(xy 35.559568 -135.045167) (xy 35.536632 -135.100543) (xy 35.506663 -135.152451) (xy 35.470174 -135.200003)
			(xy 35.427791 -135.242385) (xy 35.380238 -135.278872) (xy 35.328329 -135.308839) (xy 35.272952 -135.331773)
			(xy 35.215055 -135.347282) (xy 35.155629 -135.355101) (xy 35.12566 -135.355584) (xy 35.12566 -135.355838)
			(xy 35.097133 -135.355365) (xy 35.040527 -135.348214) (xy 34.985245 -135.334101) (xy 34.958528 -135.324088)
			(xy 34.946614 -135.320109) (xy 34.921698 -135.323043) (xy 34.91103 -135.329676) (xy 34.841942 -135.377936)
			(xy 34.83201 -135.385659) (xy 34.820573 -135.408034) (xy 34.820098 -135.420608) (xy 34.865056 -137.908538)
			(xy 34.865056 -138.210544) (xy 34.86531 -138.215116) (xy 35.05126 -140.326364) (xy 35.692078 -140.326364)
			(xy 35.696149 -140.270742) (xy 35.708275 -140.216305) (xy 35.728198 -140.164214) (xy 35.755494 -140.115579)
			(xy 35.78958 -140.071436) (xy 35.829729 -140.032727) (xy 35.875087 -140.000276) (xy 35.924687 -139.974775)
			(xy 35.977471 -139.956768) (xy 36.032314 -139.946638) (xy 36.088048 -139.944601) (xy 36.143485 -139.950701)
			(xy 36.197442 -139.964807) (xy 36.248771 -139.986619) (xy 36.296377 -140.015673) (xy 36.339245 -140.051348)
			(xy 36.376462 -140.092885) (xy 36.407235 -140.139398) (xy 36.430907 -140.189895) (xy 36.446975 -140.243302)
			(xy 36.455095 -140.298478) (xy 36.455604 -140.326364) (xy 36.455095 -140.35425) (xy 36.446975 -140.409426)
			(xy 36.430907 -140.462833) (xy 36.407235 -140.51333) (xy 36.376462 -140.559843) (xy 36.339245 -140.60138)
			(xy 36.296377 -140.637055) (xy 36.248771 -140.666109) (xy 36.197442 -140.687921) (xy 36.143485 -140.702027)
			(xy 36.088048 -140.708127) (xy 36.032314 -140.70609) (xy 35.977471 -140.69596) (xy 35.924687 -140.677953)
			(xy 35.875087 -140.652452) (xy 35.829729 -140.620001) (xy 35.78958 -140.581292) (xy 35.755494 -140.537149)
			(xy 35.728198 -140.488514) (xy 35.708275 -140.436423) (xy 35.696149 -140.381986) (xy 35.692078 -140.326364)
			(xy 35.05126 -140.326364) (xy 36.553132 -157.3784) (xy 37.190932 -157.3784) (xy 37.195003 -157.322778)
			(xy 37.207129 -157.268341) (xy 37.227052 -157.21625) (xy 37.254348 -157.167615) (xy 37.288434 -157.123472)
			(xy 37.328583 -157.084763) (xy 37.373941 -157.052312) (xy 37.423541 -157.026811) (xy 37.476325 -157.008804)
			(xy 37.531168 -156.998674) (xy 37.586902 -156.996637) (xy 37.642339 -157.002737) (xy 37.696296 -157.016843)
			(xy 37.747625 -157.038655) (xy 37.795231 -157.067709) (xy 37.838099 -157.103384) (xy 37.875316 -157.144921)
			(xy 37.906089 -157.191434) (xy 37.929761 -157.241931) (xy 37.945829 -157.295338) (xy 37.953949 -157.350514)
			(xy 37.954458 -157.3784) (xy 37.953949 -157.406286) (xy 37.945829 -157.461462) (xy 37.929761 -157.514869)
			(xy 37.906089 -157.565366) (xy 37.875316 -157.611879) (xy 37.838099 -157.653416) (xy 37.795231 -157.689091)
			(xy 37.747625 -157.718145) (xy 37.696296 -157.739957) (xy 37.642339 -157.754063) (xy 37.586902 -157.760163)
			(xy 37.531168 -157.758126) (xy 37.476325 -157.747996) (xy 37.423541 -157.729989) (xy 37.373941 -157.704488)
			(xy 37.328583 -157.672037) (xy 37.288434 -157.633328) (xy 37.254348 -157.589185) (xy 37.227052 -157.54055)
			(xy 37.207129 -157.488459) (xy 37.195003 -157.434022) (xy 37.190932 -157.3784) (xy 36.553132 -157.3784)
			(xy 36.642617 -158.3944) (xy 37.190932 -158.3944) (xy 37.195003 -158.338778) (xy 37.207129 -158.284341)
			(xy 37.227052 -158.23225) (xy 37.254348 -158.183615) (xy 37.288434 -158.139472) (xy 37.328583 -158.100763)
			(xy 37.373941 -158.068312) (xy 37.423541 -158.042811) (xy 37.476325 -158.024804) (xy 37.531168 -158.014674)
			(xy 37.586902 -158.012637) (xy 37.642339 -158.018737) (xy 37.696296 -158.032843) (xy 37.747625 -158.054655)
			(xy 37.795231 -158.083709) (xy 37.838099 -158.119384) (xy 37.875316 -158.160921) (xy 37.906089 -158.207434)
			(xy 37.929761 -158.257931) (xy 37.945829 -158.311338) (xy 37.953949 -158.366514) (xy 37.954458 -158.3944)
			(xy 37.953949 -158.422286) (xy 37.945829 -158.477462) (xy 37.929761 -158.530869) (xy 37.906089 -158.581366)
			(xy 37.875316 -158.627879) (xy 37.838099 -158.669416) (xy 37.795231 -158.705091) (xy 37.747625 -158.734145)
			(xy 37.696296 -158.755957) (xy 37.642339 -158.770063) (xy 37.586902 -158.776163) (xy 37.531168 -158.774126)
			(xy 37.476325 -158.763996) (xy 37.423541 -158.745989) (xy 37.373941 -158.720488) (xy 37.328583 -158.688037)
			(xy 37.288434 -158.649328) (xy 37.254348 -158.605185) (xy 37.227052 -158.55655) (xy 37.207129 -158.504459)
			(xy 37.195003 -158.450022) (xy 37.190932 -158.3944) (xy 36.642617 -158.3944) (xy 38.933882 -184.40908)
			(xy 38.935107 -184.418443) (xy 38.943485 -184.435352) (xy 38.957408 -184.44809) (xy 38.974993 -184.454935)
			(xy 38.984428 -184.455308)
		)
		(stroke
			(width 0)
			(type solid)
		)
		(fill yes)
		(layer "In11.Cu")
		(net "GND")
	)
	(gr_poly
		(pts
			(xy 272.686018 -194.756278) (xy 272.696736 -194.756181) (xy 272.716591 -194.748156) (xy 272.724372 -194.740784)
			(xy 272.731738 -194.733164) (xy 272.739104 -194.713098) (xy 270.889984 -164.34435) (xy 270.880586 -164.326062)
			(xy 270.873982 -164.32022) (xy 270.86684 -164.314603) (xy 270.849789 -164.308364) (xy 270.840708 -164.308028)
			(xy 270.835628 -164.308282) (xy 270.797274 -164.310314) (xy 270.770024 -164.309826) (xy 270.716079 -164.302067)
			(xy 270.663787 -164.28671) (xy 270.614212 -164.264067) (xy 270.568365 -164.2346) (xy 270.527177 -164.198909)
			(xy 270.491488 -164.157719) (xy 270.462023 -164.11187) (xy 270.439383 -164.062295) (xy 270.424029 -164.010002)
			(xy 270.416272 -163.956056) (xy 270.415766 -163.928806) (xy 270.416247 -163.901189) (xy 270.424194 -163.846531)
			(xy 270.439937 -163.793589) (xy 270.463148 -163.74347) (xy 270.493342 -163.69722) (xy 270.529887 -163.655806)
			(xy 270.57202 -163.620093) (xy 270.618862 -163.590826) (xy 270.669434 -163.568618) (xy 270.722679 -163.553932)
			(xy 270.75003 -163.550092) (xy 270.750538 -163.550092) (xy 270.756634 -163.549076) (xy 270.773398 -163.539932)
			(xy 270.82369 -163.479226) (xy 270.829468 -163.471547) (xy 270.835359 -163.453271) (xy 270.83512 -163.443666)
			(xy 270.724376 -161.626042) (xy 270.712184 -161.605214) (xy 270.704564 -161.600388) (xy 270.680057 -161.584504)
			(xy 270.635734 -161.54648) (xy 270.597724 -161.502145) (xy 270.566916 -161.452534) (xy 270.554958 -161.42589)
			(xy 270.552597 -161.420547) (xy 270.545787 -161.411059) (xy 270.541496 -161.407094) (xy 270.532606 -161.399474)
			(xy 270.52524 -161.397442) (xy 270.442944 -161.37636) (xy 270.437251 -161.375052) (xy 270.425575 -161.374792)
			(xy 270.41983 -161.375852) (xy 270.408654 -161.378138) (xy 270.399256 -161.385504) (xy 270.379088 -161.400653)
			(xy 270.335521 -161.426077) (xy 270.288986 -161.445541) (xy 270.240292 -161.458708) (xy 270.190289 -161.465347)
			(xy 270.165068 -161.465768) (xy 270.137821 -161.46528) (xy 270.083883 -161.45752) (xy 270.031597 -161.442164)
			(xy 269.982029 -161.419523) (xy 269.936188 -161.390059) (xy 269.895006 -161.354372) (xy 269.859321 -161.313187)
			(xy 269.829861 -161.267343) (xy 269.807225 -161.217773) (xy 269.791873 -161.165486) (xy 269.784118 -161.111547)
			(xy 269.784118 -161.057053) (xy 269.791873 -161.003114) (xy 269.807225 -160.950827) (xy 269.829861 -160.901257)
			(xy 269.859321 -160.855413) (xy 269.895006 -160.814228) (xy 269.936188 -160.778541) (xy 269.982029 -160.749077)
			(xy 270.031597 -160.726436) (xy 270.083883 -160.71108) (xy 270.137821 -160.70332) (xy 270.165068 -160.702752)
			(xy 270.19293 -160.703263) (xy 270.24806 -160.711374) (xy 270.301424 -160.727415) (xy 270.35189 -160.751043)
			(xy 270.398385 -160.781757) (xy 270.43992 -160.818905) (xy 270.475612 -160.861696) (xy 270.504705 -160.909223)
			(xy 270.516096 -160.934654) (xy 270.51845 -160.940003) (xy 270.525249 -160.949503) (xy 270.529558 -160.95345)
			(xy 270.533876 -160.957006) (xy 270.54429 -160.962594) (xy 270.639794 -160.986978) (xy 270.646906 -160.985454)
			(xy 270.66367 -160.971738) (xy 270.672511 -160.963522) (xy 270.682054 -160.941389) (xy 270.681958 -160.92932)
			(xy 270.237204 -153.627074) (xy 270.236164 -153.61708) (xy 270.22734 -153.599043) (xy 270.212276 -153.585767)
			(xy 270.202914 -153.582116) (xy 270.099536 -153.546556) (xy 270.069818 -153.55443) (xy 270.059658 -153.566114)
			(xy 270.041449 -153.586121) (xy 270.00036 -153.621308) (xy 269.954717 -153.650345) (xy 269.905433 -153.672651)
			(xy 269.853494 -153.687779) (xy 269.79994 -153.695425) (xy 269.772892 -153.695908) (xy 269.745641 -153.695422)
			(xy 269.691694 -153.687664) (xy 269.6394 -153.672308) (xy 269.589824 -153.649667) (xy 269.543975 -153.6202)
			(xy 269.502786 -153.584509) (xy 269.467095 -153.543319) (xy 269.437629 -153.497469) (xy 269.414989 -153.447892)
			(xy 269.399634 -153.395598) (xy 269.391878 -153.341651) (xy 269.391878 -153.287149) (xy 269.399634 -153.233202)
			(xy 269.414989 -153.180908) (xy 269.437629 -153.131331) (xy 269.467095 -153.085481) (xy 269.502786 -153.044291)
			(xy 269.543975 -153.0086) (xy 269.589824 -152.979133) (xy 269.6394 -152.956492) (xy 269.691694 -152.941136)
			(xy 269.745641 -152.933378) (xy 269.772892 -152.932892) (xy 269.800696 -152.933394) (xy 269.855714 -152.941461)
			(xy 269.90898 -152.957426) (xy 269.959366 -152.980951) (xy 270.005805 -153.011538) (xy 270.026892 -153.029666)
			(xy 270.034683 -153.035954) (xy 270.053567 -153.042537) (xy 270.073534 -153.041405) (xy 270.082772 -153.03754)
			(xy 270.167354 -152.996392) (xy 270.176163 -152.991575) (xy 270.1895 -152.976595) (xy 270.196124 -152.957664)
			(xy 270.196056 -152.947624) (xy 269.738856 -145.440654) (xy 269.736824 -145.379948) (xy 269.736982 -145.35546)
			(xy 269.739398 -145.306543) (xy 269.74165 -145.282158) (xy 269.911576 -143.559022) (xy 269.911576 -143.558514)
			(xy 270.420592 -137.50798) (xy 270.423393 -137.477534) (xy 270.432287 -137.417038) (xy 270.438372 -137.387076)
			(xy 270.456914 -137.298176) (xy 270.4583 -137.29) (xy 270.456368 -137.27354) (xy 270.453104 -137.265918)
			(xy 270.449548 -137.258552) (xy 270.438118 -137.246868) (xy 270.430244 -137.242804) (xy 270.403368 -137.228596)
			(xy 270.354108 -137.192974) (xy 270.311115 -137.149997) (xy 270.29283 -137.12571) (xy 270.291052 -137.123424)
			(xy 270.268446 -137.108692) (xy 270.264614 -137.106293) (xy 270.256312 -137.102714) (xy 270.251936 -137.10158)
			(xy 270.231108 -137.096754) (xy 270.227597 -137.096062) (xy 270.220458 -137.095552) (xy 270.216884 -137.095738)
			(xy 270.211951 -137.096132) (xy 270.202362 -137.098568) (xy 270.197834 -137.100564) (xy 270.194786 -137.102342)
			(xy 270.168799 -137.116597) (xy 270.113935 -137.139026) (xy 270.056633 -137.154182) (xy 269.997854 -137.161812)
			(xy 269.968218 -137.162286) (xy 269.96771 -137.162286) (xy 269.937725 -137.161797) (xy 269.878267 -137.15397)
			(xy 269.820339 -137.13845) (xy 269.764933 -137.115502) (xy 269.712996 -137.085519) (xy 269.665417 -137.049012)
			(xy 269.62301 -137.006608) (xy 269.5865 -136.959032) (xy 269.556513 -136.907097) (xy 269.533561 -136.851693)
			(xy 269.518036 -136.793766) (xy 269.510206 -136.734309) (xy 269.509748 -136.704324) (xy 269.509748 -135.840724)
			(xy 269.510238 -135.81074) (xy 269.518066 -135.751284) (xy 269.533587 -135.693359) (xy 269.556536 -135.637955)
			(xy 269.58652 -135.586021) (xy 269.623026 -135.538445) (xy 269.665431 -135.49604) (xy 269.713007 -135.459534)
			(xy 269.764941 -135.42955) (xy 269.820345 -135.406601) (xy 269.87827 -135.39108) (xy 269.937726 -135.383252)
			(xy 269.997694 -135.383252) (xy 270.05715 -135.39108) (xy 270.115075 -135.406601) (xy 270.170479 -135.42955)
			(xy 270.222413 -135.459534) (xy 270.269989 -135.49604) (xy 270.312394 -135.538445) (xy 270.3489 -135.586021)
			(xy 270.378884 -135.637955) (xy 270.401833 -135.693359) (xy 270.417354 -135.751284) (xy 270.425182 -135.81074)
			(xy 270.425672 -135.840724) (xy 270.425672 -136.42467) (xy 270.426176 -136.435506) (xy 270.435134 -136.45524)
			(xy 270.442944 -136.46277) (xy 270.474186 -136.489694) (xy 270.501872 -136.513316) (xy 270.509013 -136.518936)
			(xy 270.526064 -136.525186) (xy 270.535146 -136.525508) (xy 270.542512 -136.525) (xy 270.54429 -136.524746)
			(xy 270.564102 -136.522206) (xy 270.59255 -136.519412) (xy 270.596085 -136.518462) (xy 270.602847 -136.515662)
			(xy 270.606012 -136.513824) (xy 270.665194 -135.91286) (xy 270.665448 -135.90778) (xy 270.660622 -134.95274)
			(xy 270.660622 -134.952232) (xy 270.569436 -128.505712) (xy 270.535654 -126.107698) (xy 270.535045 -126.097216)
			(xy 270.526454 -126.078082) (xy 270.510891 -126.064021) (xy 270.50111 -126.0602) (xy 270.49857 -126.059438)
			(xy 270.474609 -126.052319) (xy 270.428651 -126.032664) (xy 270.385655 -126.007171) (xy 270.346359 -125.976279)
			(xy 270.311437 -125.940516) (xy 270.296132 -125.920754) (xy 270.291052 -125.913642) (xy 270.268954 -125.89891)
			(xy 270.265002 -125.896481) (xy 270.256441 -125.892908) (xy 270.251936 -125.891798) (xy 270.2306 -125.886972)
			(xy 270.222222 -125.885491) (xy 270.205344 -125.887557) (xy 270.19758 -125.891036) (xy 270.194786 -125.89256)
			(xy 270.168799 -125.906815) (xy 270.113934 -125.929243) (xy 270.056633 -125.944398) (xy 269.997854 -125.952028)
			(xy 269.968218 -125.952504) (xy 269.96771 -125.952504) (xy 269.937724 -125.952015) (xy 269.878266 -125.944188)
			(xy 269.820337 -125.928669) (xy 269.76493 -125.905721) (xy 269.712992 -125.875737) (xy 269.665411 -125.839231)
			(xy 269.623003 -125.796828) (xy 269.586492 -125.749251) (xy 269.556502 -125.697317) (xy 269.533548 -125.641912)
			(xy 269.518022 -125.583985) (xy 269.510189 -125.524528) (xy 269.509748 -125.494542) (xy 269.509748 -124.630942)
			(xy 269.510214 -124.600955) (xy 269.518038 -124.541493) (xy 269.533556 -124.483561) (xy 269.556504 -124.42815)
			(xy 269.586488 -124.376209) (xy 269.622996 -124.328627) (xy 269.665403 -124.286217) (xy 269.712983 -124.249706)
			(xy 269.764922 -124.219718) (xy 269.820331 -124.196766) (xy 269.878261 -124.181244) (xy 269.937723 -124.173417)
			(xy 269.96771 -124.17298) (xy 269.968218 -124.17298) (xy 269.997821 -124.173465) (xy 270.05653 -124.18113)
			(xy 270.113763 -124.196292) (xy 270.168567 -124.218697) (xy 270.194532 -124.232924) (xy 270.198349 -124.234999)
			(xy 270.206523 -124.23794) (xy 270.210788 -124.238766) (xy 270.215838 -124.239623) (xy 270.226079 -124.239486)
			(xy 270.231108 -124.238512) (xy 270.251936 -124.233686) (xy 270.256323 -124.232583) (xy 270.264633 -124.229008)
			(xy 270.268446 -124.226574) (xy 270.291052 -124.211842) (xy 270.29283 -124.209556) (xy 270.31 -124.18667)
			(xy 270.350069 -124.145832) (xy 270.395797 -124.111449) (xy 270.446156 -124.084297) (xy 270.472916 -124.074174)
			(xy 270.47317 -124.074174) (xy 270.48044 -124.071233) (xy 270.492845 -124.061651) (xy 270.497554 -124.055378)
			(xy 270.50238 -124.04852) (xy 270.506952 -124.033788) (xy 270.484854 -122.48769) (xy 270.484039 -122.479073)
			(xy 270.477415 -122.463096) (xy 270.465867 -122.450218) (xy 270.458438 -122.44578) (xy 270.453866 -122.443494)
			(xy 270.430682 -122.433344) (xy 270.386993 -122.407798) (xy 270.347071 -122.376692) (xy 270.31162 -122.340573)
			(xy 270.296132 -122.320558) (xy 270.291052 -122.313446) (xy 270.268954 -122.298714) (xy 270.265002 -122.296285)
			(xy 270.256441 -122.292711) (xy 270.251936 -122.291602) (xy 270.2306 -122.286776) (xy 270.222222 -122.285295)
			(xy 270.205344 -122.287361) (xy 270.19758 -122.29084) (xy 270.194786 -122.292364) (xy 270.168799 -122.306619)
			(xy 270.113934 -122.329046) (xy 270.056633 -122.344202) (xy 269.997854 -122.351832) (xy 269.968218 -122.352308)
			(xy 269.96771 -122.352308) (xy 269.937724 -122.351819) (xy 269.878265 -122.343992) (xy 269.820337 -122.328473)
			(xy 269.764929 -122.305525) (xy 269.712991 -122.275541) (xy 269.66541 -122.239036) (xy 269.623001 -122.196632)
			(xy 269.58649 -122.149056) (xy 269.5565 -122.097121) (xy 269.533545 -122.041716) (xy 269.518019 -121.98379)
			(xy 269.510185 -121.924332) (xy 269.509748 -121.894346) (xy 269.509748 -121.030746) (xy 269.510214 -121.000759)
			(xy 269.518037 -120.941296) (xy 269.533555 -120.883364) (xy 269.556503 -120.827953) (xy 269.586487 -120.776012)
			(xy 269.622995 -120.728429) (xy 269.665402 -120.686018) (xy 269.712982 -120.649507) (xy 269.764921 -120.619518)
			(xy 269.82033 -120.596567) (xy 269.878261 -120.581044) (xy 269.937723 -120.573217) (xy 269.96771 -120.572784)
			(xy 269.968218 -120.572784) (xy 269.997821 -120.573269) (xy 270.05653 -120.580934) (xy 270.113763 -120.596096)
			(xy 270.168567 -120.618502) (xy 270.194532 -120.632728) (xy 270.198349 -120.634844) (xy 270.206521 -120.637906)
			(xy 270.210788 -120.638824) (xy 270.215852 -120.639594) (xy 270.226089 -120.639339) (xy 270.231108 -120.638316)
			(xy 270.251936 -120.63349) (xy 270.256324 -120.632387) (xy 270.264633 -120.628812) (xy 270.268446 -120.626378)
			(xy 270.291052 -120.611646) (xy 270.29283 -120.60936) (xy 270.310757 -120.585593) (xy 270.352738 -120.543387)
			(xy 270.40075 -120.508193) (xy 270.426942 -120.494044) (xy 270.429482 -120.492774) (xy 270.430498 -120.492266)
			(xy 270.438143 -120.487407) (xy 270.449673 -120.473452) (xy 270.45565 -120.456365) (xy 270.455898 -120.447308)
			(xy 270.40078 -116.532152) (xy 270.40078 -116.517928) (xy 270.402558 -116.458746) (xy 270.418052 -116.199412)
			(xy 270.418196 -116.189776) (xy 270.412173 -116.171486) (xy 270.399867 -116.156675) (xy 270.391636 -116.15166)
			(xy 270.37157 -116.140738) (xy 270.30934 -116.106956) (xy 270.301772 -116.103506) (xy 270.285313 -116.101181)
			(xy 270.277082 -116.102384) (xy 270.261334 -116.109496) (xy 270.252444 -116.114322) (xy 270.238361 -116.124181)
			(xy 270.208724 -116.141606) (xy 270.193262 -116.14912) (xy 270.183102 -116.153946) (xy 270.176244 -116.162074)
			(xy 270.17264 -116.166464) (xy 270.167247 -116.176458) (xy 270.165576 -116.181886) (xy 270.162782 -116.1923)
			(xy 270.145256 -116.25707) (xy 270.143958 -116.262369) (xy 270.143437 -116.273264) (xy 270.14424 -116.27866)
			(xy 270.146018 -116.28882) (xy 270.152114 -116.298218) (xy 270.152622 -116.298726) (xy 270.168109 -116.322528)
			(xy 270.19262 -116.37375) (xy 270.209259 -116.428042) (xy 270.217656 -116.484202) (xy 270.218154 -116.512594)
			(xy 270.217669 -116.539847) (xy 270.209913 -116.593798) (xy 270.194559 -116.646096) (xy 270.171919 -116.695677)
			(xy 270.142453 -116.741531) (xy 270.106763 -116.782726) (xy 270.065573 -116.818422) (xy 270.019722 -116.847894)
			(xy 269.970144 -116.870541) (xy 269.917848 -116.885902) (xy 269.863899 -116.893665) (xy 269.836646 -116.894102)
			(xy 269.810361 -116.89366) (xy 269.758288 -116.886444) (xy 269.707696 -116.872156) (xy 269.659541 -116.851065)
			(xy 269.614734 -116.823569) (xy 269.57412 -116.79019) (xy 269.555976 -116.771166) (xy 269.555468 -116.770658)
			(xy 269.528036 -116.75872) (xy 269.523196 -116.756718) (xy 269.512952 -116.754544) (xy 269.507716 -116.754402)
			(xy 269.454376 -116.754402) (xy 269.449142 -116.754559) (xy 269.438901 -116.756735) (xy 269.434056 -116.75872)
			(xy 269.406624 -116.770658) (xy 269.406116 -116.771166) (xy 269.387974 -116.790192) (xy 269.347367 -116.823583)
			(xy 269.302562 -116.851082) (xy 269.254405 -116.87217) (xy 269.203809 -116.886447) (xy 269.151732 -116.893643)
			(xy 269.125446 -116.894102) (xy 269.098191 -116.893642) (xy 269.044236 -116.88589) (xy 268.991934 -116.870538)
			(xy 268.942349 -116.847899) (xy 268.896491 -116.818433) (xy 268.855293 -116.78274) (xy 268.819595 -116.741546)
			(xy 268.790123 -116.695692) (xy 268.767478 -116.646109) (xy 268.75212 -116.593809) (xy 268.744361 -116.539855)
			(xy 268.744361 -116.485345) (xy 268.75212 -116.431391) (xy 268.767478 -116.379091) (xy 268.790123 -116.329508)
			(xy 268.819595 -116.283654) (xy 268.855293 -116.24246) (xy 268.896491 -116.206767) (xy 268.942349 -116.177301)
			(xy 268.991934 -116.154662) (xy 269.044236 -116.13931) (xy 269.098191 -116.131558) (xy 269.125446 -116.131086)
			(xy 269.151731 -116.131527) (xy 269.203803 -116.138744) (xy 269.254393 -116.153034) (xy 269.302546 -116.174128)
			(xy 269.34735 -116.201627) (xy 269.387959 -116.235011) (xy 269.406116 -116.254022) (xy 269.406624 -116.25453)
			(xy 269.434056 -116.266468) (xy 269.438896 -116.268471) (xy 269.44914 -116.270648) (xy 269.454376 -116.270786)
			(xy 269.507462 -116.270786) (xy 269.512823 -116.270663) (xy 269.523318 -116.268477) (xy 269.52829 -116.266468)
			(xy 269.555468 -116.254276) (xy 269.559278 -116.250466) (xy 269.575872 -116.233452) (xy 269.612569 -116.203253)
			(xy 269.652737 -116.17785) (xy 269.674086 -116.167408) (xy 269.684246 -116.162582) (xy 269.691104 -116.154454)
			(xy 269.694699 -116.150059) (xy 269.700074 -116.140061) (xy 269.701772 -116.134642) (xy 269.704566 -116.124228)
			(xy 269.722092 -116.059458) (xy 269.723381 -116.054159) (xy 269.723887 -116.043266) (xy 269.723108 -116.037868)
			(xy 269.72133 -116.027708) (xy 269.715234 -116.01831) (xy 269.714726 -116.017802) (xy 269.699239 -115.994)
			(xy 269.674728 -115.942778) (xy 269.658087 -115.888486) (xy 269.649687 -115.832326) (xy 269.649194 -115.803934)
			(xy 269.649731 -115.775394) (xy 269.658243 -115.718952) (xy 269.675067 -115.664407) (xy 269.699829 -115.612977)
			(xy 269.731974 -115.565809) (xy 269.770787 -115.523956) (xy 269.815401 -115.48835) (xy 269.86482 -115.459787)
			(xy 269.917943 -115.438904) (xy 269.973584 -115.426167) (xy 270.002 -115.423442) (xy 270.009112 -115.42268)
			(xy 270.03629 -115.40871) (xy 270.041004 -115.406055) (xy 270.049317 -115.399134) (xy 270.0528 -115.394994)
			(xy 270.093186 -115.343686) (xy 270.096324 -115.339451) (xy 270.100926 -115.329971) (xy 270.10233 -115.32489)
			(xy 270.105124 -115.314476) (xy 270.103092 -115.303554) (xy 270.100262 -115.286806) (xy 270.09721 -115.252974)
			(xy 270.096996 -115.23599) (xy 270.096996 -115.235228) (xy 270.097518 -115.206443) (xy 270.106164 -115.149525)
			(xy 270.123264 -115.094553) (xy 270.14843 -115.042774) (xy 270.18109 -114.995365) (xy 270.220502 -114.9534)
			(xy 270.265772 -114.917834) (xy 270.315873 -114.889474) (xy 270.369666 -114.868964) (xy 270.42593 -114.856768)
			(xy 270.454628 -114.854482) (xy 270.463848 -114.85353) (xy 270.480739 -114.845936) (xy 270.493835 -114.832841)
			(xy 270.501429 -114.81595) (xy 270.50238 -114.80673) (xy 270.558768 -113.873788) (xy 270.558768 -113.870486)
			(xy 270.547846 -111.5949) (xy 270.547242 -111.583606) (xy 270.537558 -111.563199) (xy 270.520059 -111.548914)
			(xy 270.509238 -111.545624) (xy 270.481391 -111.538123) (xy 270.428181 -111.515884) (xy 270.378925 -111.485889)
			(xy 270.334745 -111.448822) (xy 270.296648 -111.405528) (xy 270.280638 -111.38154) (xy 270.274878 -111.373444)
			(xy 270.258608 -111.362077) (xy 270.239236 -111.357757) (xy 270.219678 -111.361136) (xy 270.211042 -111.366046)
			(xy 270.183627 -111.382585) (xy 270.125159 -111.408681) (xy 270.063628 -111.426382) (xy 270.000231 -111.435341)
			(xy 269.968218 -111.435896) (xy 269.96771 -111.435896) (xy 269.937724 -111.435407) (xy 269.878266 -111.42758)
			(xy 269.820338 -111.41206) (xy 269.764931 -111.389112) (xy 269.712994 -111.359129) (xy 269.665414 -111.322623)
			(xy 269.623006 -111.280219) (xy 269.586495 -111.232643) (xy 269.556507 -111.180708) (xy 269.533554 -111.125303)
			(xy 269.518028 -111.067377) (xy 269.510196 -111.007919) (xy 269.509748 -110.977934) (xy 269.509748 -110.114334)
			(xy 269.510215 -110.084347) (xy 269.518039 -110.024886) (xy 269.533558 -109.966955) (xy 269.556506 -109.911545)
			(xy 269.586491 -109.859605) (xy 269.622999 -109.812024) (xy 269.665406 -109.769615) (xy 269.712985 -109.733104)
			(xy 269.764924 -109.703117) (xy 269.820332 -109.680166) (xy 269.878262 -109.664644) (xy 269.937723 -109.656817)
			(xy 269.96771 -109.656372) (xy 269.968218 -109.656372) (xy 270.000232 -109.656922) (xy 270.063632 -109.665873)
			(xy 270.125166 -109.683571) (xy 270.183633 -109.70967) (xy 270.211042 -109.726222) (xy 270.219695 -109.731089)
			(xy 270.239241 -109.734453) (xy 270.258602 -109.730146) (xy 270.274879 -109.718814) (xy 270.280638 -109.710728)
			(xy 270.296135 -109.687533) (xy 270.33278 -109.645475) (xy 270.375149 -109.60919) (xy 270.422341 -109.579447)
			(xy 270.473355 -109.55688) (xy 270.500094 -109.54893) (xy 270.510682 -109.545443) (xy 270.527655 -109.53103)
			(xy 270.536937 -109.510791) (xy 270.537432 -109.499654) (xy 270.53032 -107.989878) (xy 270.529755 -107.978965)
			(xy 270.52062 -107.959137) (xy 270.504089 -107.944879) (xy 270.493744 -107.941364) (xy 270.46849 -107.933415)
			(xy 270.420283 -107.911523) (xy 270.375554 -107.883197) (xy 270.35506 -107.866434) (xy 270.337769 -107.851294)
			(xy 270.306565 -107.817551) (xy 270.29283 -107.799124) (xy 270.291052 -107.796838) (xy 270.268446 -107.782106)
			(xy 270.264612 -107.779711) (xy 270.25631 -107.776138) (xy 270.251936 -107.774994) (xy 270.231108 -107.770168)
			(xy 270.227597 -107.769475) (xy 270.220458 -107.768966) (xy 270.216884 -107.769152) (xy 270.211952 -107.769546)
			(xy 270.202363 -107.771983) (xy 270.197834 -107.773978) (xy 270.194786 -107.775756) (xy 270.168799 -107.790011)
			(xy 270.113934 -107.812439) (xy 270.056633 -107.827595) (xy 269.997854 -107.835225) (xy 269.968218 -107.8357)
			(xy 269.96771 -107.8357) (xy 269.937724 -107.835211) (xy 269.878266 -107.827384) (xy 269.820338 -107.811865)
			(xy 269.764931 -107.788917) (xy 269.712993 -107.758933) (xy 269.665413 -107.722427) (xy 269.623004 -107.680023)
			(xy 269.586494 -107.632447) (xy 269.556505 -107.580512) (xy 269.533551 -107.525108) (xy 269.518025 -107.467181)
			(xy 269.510193 -107.407724) (xy 269.509748 -107.377738) (xy 269.509748 -106.514138) (xy 269.510215 -106.484151)
			(xy 269.518039 -106.424689) (xy 269.533557 -106.366758) (xy 269.556505 -106.311348) (xy 269.58649 -106.259407)
			(xy 269.622998 -106.211825) (xy 269.665404 -106.169416) (xy 269.712984 -106.132905) (xy 269.764923 -106.102917)
			(xy 269.820331 -106.079966) (xy 269.878262 -106.064444) (xy 269.937723 -106.056617) (xy 269.96771 -106.056176)
			(xy 269.968218 -106.056176) (xy 269.997821 -106.056661) (xy 270.05653 -106.064326) (xy 270.113763 -106.079488)
			(xy 270.168567 -106.101893) (xy 270.194532 -106.11612) (xy 270.198349 -106.118236) (xy 270.206521 -106.121299)
			(xy 270.210788 -106.122216) (xy 270.215852 -106.122986) (xy 270.226089 -106.122731) (xy 270.231108 -106.121708)
			(xy 270.251936 -106.116882) (xy 270.256323 -106.115779) (xy 270.264632 -106.112203) (xy 270.268446 -106.10977)
			(xy 270.291052 -106.095038) (xy 270.29283 -106.092752) (xy 270.310372 -106.069481) (xy 270.35134 -106.028038)
			(xy 270.398131 -105.993305) (xy 270.42364 -105.979214) (xy 270.438423 -105.97157) (xy 270.469075 -105.958597)
			(xy 270.484854 -105.953306) (xy 270.494977 -105.949529) (xy 270.511013 -105.935078) (xy 270.519739 -105.915334)
			(xy 270.52016 -105.904538) (xy 270.51254 -104.351074) (xy 270.503904 -104.345232) (xy 270.478504 -104.336596)
			(xy 270.445738 -104.323642) (xy 270.422859 -104.312935) (xy 270.379897 -104.286366) (xy 270.340815 -104.254362)
			(xy 270.306296 -104.217481) (xy 270.291306 -104.19715) (xy 270.288766 -104.193848) (xy 270.283463 -104.188022)
			(xy 270.270145 -104.17962) (xy 270.262604 -104.177338) (xy 270.255492 -104.175814) (xy 270.230854 -104.170226)
			(xy 270.219424 -104.168956) (xy 270.194786 -104.17556) (xy 270.189198 -104.178608) (xy 270.170148 -104.188514)
			(xy 270.16964 -104.188514) (xy 270.138132 -104.203275) (xy 270.071766 -104.224168) (xy 270.003005 -104.23479)
			(xy 269.968218 -104.235504) (xy 269.967964 -104.235504) (xy 269.957296 -104.235758) (xy 269.927766 -104.234631)
			(xy 269.869348 -104.225711) (xy 269.812564 -104.209349) (xy 269.758356 -104.185818) (xy 269.707626 -104.155508)
			(xy 269.661217 -104.118923) (xy 269.619902 -104.076671) (xy 269.584365 -104.029455) (xy 269.555199 -103.978059)
			(xy 269.532887 -103.923337) (xy 269.517801 -103.8662) (xy 269.510192 -103.807597) (xy 269.509748 -103.77805)
			(xy 269.509748 -102.914196) (xy 269.510238 -102.884238) (xy 269.518055 -102.824834) (xy 269.533557 -102.766958)
			(xy 269.556477 -102.7116) (xy 269.586424 -102.659705) (xy 269.622886 -102.612161) (xy 269.665239 -102.56978)
			(xy 269.71276 -102.533288) (xy 269.764636 -102.503307) (xy 269.81998 -102.480352) (xy 269.877846 -102.464813)
			(xy 269.937244 -102.456957) (xy 269.967202 -102.456488) (xy 269.96771 -102.456488) (xy 269.997378 -102.456943)
			(xy 270.056221 -102.464572) (xy 270.113589 -102.479725) (xy 270.168524 -102.502151) (xy 270.194532 -102.516432)
			(xy 270.198342 -102.518718) (xy 270.204191 -102.521141) (xy 270.216656 -102.523325) (xy 270.22298 -102.523036)
			(xy 270.2306 -102.52202) (xy 270.251682 -102.517194) (xy 270.256068 -102.516088) (xy 270.264373 -102.512506)
			(xy 270.268192 -102.510082) (xy 270.290798 -102.49535) (xy 270.292576 -102.493064) (xy 270.308387 -102.471966)
			(xy 270.344872 -102.433905) (xy 270.386244 -102.401223) (xy 270.431717 -102.37454) (xy 270.455898 -102.364032)
			(xy 270.456152 -102.364032) (xy 270.463132 -102.360854) (xy 270.474907 -102.351037) (xy 270.479266 -102.344728)
			(xy 270.48333 -102.338378) (xy 270.487394 -102.3239) (xy 270.45412 -100.758498) (xy 270.453792 -100.751657)
			(xy 270.449921 -100.738525) (xy 270.4465 -100.73259) (xy 270.442944 -100.727002) (xy 270.432784 -100.717604)
			(xy 270.426688 -100.714556) (xy 270.410373 -100.705851) (xy 270.37933 -100.68575) (xy 270.364712 -100.674424)
			(xy 270.345627 -100.658833) (xy 270.311226 -100.623546) (xy 270.296132 -100.604066) (xy 270.291052 -100.596954)
			(xy 270.268446 -100.582222) (xy 270.264612 -100.579826) (xy 270.25631 -100.576252) (xy 270.251936 -100.57511)
			(xy 270.229584 -100.57003) (xy 270.220573 -100.568666) (xy 270.202607 -100.571649) (xy 270.194532 -100.575872)
			(xy 270.168574 -100.590115) (xy 270.113772 -100.612531) (xy 270.056536 -100.627692) (xy 269.997823 -100.635344)
			(xy 269.968218 -100.635816) (xy 269.96136 -100.635816) (xy 269.931647 -100.634932) (xy 269.872815 -100.626425)
			(xy 269.815577 -100.610377) (xy 269.760898 -100.587058) (xy 269.709695 -100.556861) (xy 269.66283 -100.520291)
			(xy 269.621091 -100.477966) (xy 269.585179 -100.430596) (xy 269.555698 -100.378977) (xy 269.533144 -100.323977)
			(xy 269.517896 -100.266522) (xy 269.51021 -100.207576) (xy 269.509748 -100.177854) (xy 269.509748 -99.314254)
			(xy 269.510241 -99.284272) (xy 269.518073 -99.224821) (xy 269.533598 -99.166902) (xy 269.55655 -99.111504)
			(xy 269.586536 -99.059575) (xy 269.623043 -99.012005) (xy 269.665447 -98.969606) (xy 269.713022 -98.933105)
			(xy 269.764954 -98.903125) (xy 269.820355 -98.88018) (xy 269.878276 -98.864663) (xy 269.937728 -98.856837)
			(xy 269.96771 -98.856292) (xy 269.995741 -98.856742) (xy 270.051378 -98.863647) (xy 270.105753 -98.877303)
			(xy 270.132048 -98.887026) (xy 270.146721 -98.892763) (xy 270.175322 -98.905982) (xy 270.189198 -98.913442)
			(xy 270.194786 -98.91649) (xy 270.21917 -98.923094) (xy 270.2306 -98.921824) (xy 270.251936 -98.916998)
			(xy 270.256456 -98.915935) (xy 270.265021 -98.912354) (xy 270.268954 -98.909886) (xy 270.291052 -98.895154)
			(xy 270.296132 -98.888042) (xy 270.309848 -98.87077) (xy 270.327387 -98.850607) (xy 270.367161 -98.814916)
			(xy 270.389096 -98.79965) (xy 270.397828 -98.7932) (xy 270.409271 -98.774775) (xy 270.411194 -98.76409)
			(xy 270.411702 -98.756216) (xy 270.369792 -96.790764) (xy 270.369792 -96.789748) (xy 270.251174 -93.820996)
			(xy 270.1925 -92.35186) (xy 270.147542 -91.227148) (xy 270.146738 -91.217541) (xy 270.138913 -91.199939)
			(xy 270.125146 -91.186465) (xy 270.107379 -91.179022) (xy 270.097758 -91.17838) (xy 269.139416 -91.157552)
			(xy 269.130051 -91.157736) (xy 269.112427 -91.16403) (xy 269.098259 -91.176256) (xy 269.089455 -91.192771)
			(xy 269.087854 -91.202002) (xy 268.798408 -93.542104) (xy 269.030448 -93.542104) (xy 269.034519 -93.486482)
			(xy 269.046645 -93.432045) (xy 269.066568 -93.379954) (xy 269.093864 -93.331319) (xy 269.12795 -93.287176)
			(xy 269.168099 -93.248467) (xy 269.213457 -93.216016) (xy 269.263057 -93.190515) (xy 269.315841 -93.172508)
			(xy 269.370684 -93.162378) (xy 269.426418 -93.160341) (xy 269.481855 -93.166441) (xy 269.535812 -93.180547)
			(xy 269.587141 -93.202359) (xy 269.634747 -93.231413) (xy 269.677615 -93.267088) (xy 269.714832 -93.308625)
			(xy 269.745605 -93.355138) (xy 269.769277 -93.405635) (xy 269.785345 -93.459042) (xy 269.793465 -93.514218)
			(xy 269.793974 -93.542104) (xy 269.793465 -93.56999) (xy 269.785345 -93.625166) (xy 269.769277 -93.678573)
			(xy 269.745605 -93.72907) (xy 269.714832 -93.775583) (xy 269.677615 -93.81712) (xy 269.634747 -93.852795)
			(xy 269.587141 -93.881849) (xy 269.535812 -93.903661) (xy 269.481855 -93.917767) (xy 269.426418 -93.923867)
			(xy 269.370684 -93.92183) (xy 269.315841 -93.9117) (xy 269.263057 -93.893693) (xy 269.213457 -93.868192)
			(xy 269.168099 -93.835741) (xy 269.12795 -93.797032) (xy 269.093864 -93.752889) (xy 269.066568 -93.704254)
			(xy 269.046645 -93.652163) (xy 269.034519 -93.597726) (xy 269.030448 -93.542104) (xy 268.798408 -93.542104)
			(xy 268.474057 -96.1644) (xy 269.425418 -96.1644) (xy 269.429489 -96.108778) (xy 269.441615 -96.054341)
			(xy 269.461538 -96.00225) (xy 269.488834 -95.953615) (xy 269.52292 -95.909472) (xy 269.563069 -95.870763)
			(xy 269.608427 -95.838312) (xy 269.658027 -95.812811) (xy 269.710811 -95.794804) (xy 269.765654 -95.784674)
			(xy 269.821388 -95.782637) (xy 269.876825 -95.788737) (xy 269.930782 -95.802843) (xy 269.982111 -95.824655)
			(xy 270.029717 -95.853709) (xy 270.072585 -95.889384) (xy 270.109802 -95.930921) (xy 270.140575 -95.977434)
			(xy 270.164247 -96.027931) (xy 270.180315 -96.081338) (xy 270.188435 -96.136514) (xy 270.188944 -96.1644)
			(xy 270.188435 -96.192286) (xy 270.180315 -96.247462) (xy 270.164247 -96.300869) (xy 270.140575 -96.351366)
			(xy 270.109802 -96.397879) (xy 270.072585 -96.439416) (xy 270.029717 -96.475091) (xy 269.982111 -96.504145)
			(xy 269.930782 -96.525957) (xy 269.876825 -96.540063) (xy 269.821388 -96.546163) (xy 269.765654 -96.544126)
			(xy 269.710811 -96.533996) (xy 269.658027 -96.515989) (xy 269.608427 -96.490488) (xy 269.563069 -96.458037)
			(xy 269.52292 -96.419328) (xy 269.488834 -96.375185) (xy 269.461538 -96.32655) (xy 269.441615 -96.274459)
			(xy 269.429489 -96.220022) (xy 269.425418 -96.1644) (xy 268.474057 -96.1644) (xy 268.348388 -97.1804)
			(xy 269.425418 -97.1804) (xy 269.429489 -97.124778) (xy 269.441615 -97.070341) (xy 269.461538 -97.01825)
			(xy 269.488834 -96.969615) (xy 269.52292 -96.925472) (xy 269.563069 -96.886763) (xy 269.608427 -96.854312)
			(xy 269.658027 -96.828811) (xy 269.710811 -96.810804) (xy 269.765654 -96.800674) (xy 269.821388 -96.798637)
			(xy 269.876825 -96.804737) (xy 269.930782 -96.818843) (xy 269.982111 -96.840655) (xy 270.029717 -96.869709)
			(xy 270.072585 -96.905384) (xy 270.109802 -96.946921) (xy 270.140575 -96.993434) (xy 270.164247 -97.043931)
			(xy 270.180315 -97.097338) (xy 270.188435 -97.152514) (xy 270.188944 -97.1804) (xy 270.188435 -97.208286)
			(xy 270.180315 -97.263462) (xy 270.164247 -97.316869) (xy 270.140575 -97.367366) (xy 270.109802 -97.413879)
			(xy 270.072585 -97.455416) (xy 270.029717 -97.491091) (xy 269.982111 -97.520145) (xy 269.930782 -97.541957)
			(xy 269.876825 -97.556063) (xy 269.821388 -97.562163) (xy 269.765654 -97.560126) (xy 269.710811 -97.549996)
			(xy 269.658027 -97.531989) (xy 269.608427 -97.506488) (xy 269.563069 -97.474037) (xy 269.52292 -97.435328)
			(xy 269.488834 -97.391185) (xy 269.461538 -97.34255) (xy 269.441615 -97.290459) (xy 269.429489 -97.236022)
			(xy 269.425418 -97.1804) (xy 268.348388 -97.1804) (xy 268.041882 -99.658424) (xy 268.032484 -99.71913)
			(xy 267.877544 -100.544122) (xy 267.876109 -100.554134) (xy 267.880303 -100.573904) (xy 267.885672 -100.582476)
			(xy 267.887196 -100.584508) (xy 267.92682 -100.63607) (xy 267.930156 -100.640155) (xy 267.938229 -100.646939)
			(xy 267.942822 -100.649532) (xy 267.969238 -100.66401) (xy 267.979652 -100.665026) (xy 268.010151 -100.668473)
			(xy 268.069906 -100.682495) (xy 268.12725 -100.704379) (xy 268.181154 -100.733732) (xy 268.230651 -100.770027)
			(xy 268.274852 -100.812613) (xy 268.312964 -100.860725) (xy 268.344302 -100.9135) (xy 268.368305 -100.96999)
			(xy 268.384541 -101.029182) (xy 268.392718 -101.090013) (xy 268.393164 -101.120702) (xy 268.393164 -101.984302)
			(xy 268.392674 -102.014286) (xy 268.384846 -102.073742) (xy 268.369325 -102.131667) (xy 268.346376 -102.18707)
			(xy 268.316392 -102.239005) (xy 268.279885 -102.286581) (xy 268.237481 -102.328985) (xy 268.189905 -102.365492)
			(xy 268.13797 -102.395476) (xy 268.082567 -102.418425) (xy 268.024642 -102.433946) (xy 267.965186 -102.441774)
			(xy 267.935202 -102.442264) (xy 267.906765 -102.441821) (xy 267.850333 -102.434749) (xy 267.795212 -102.42074)
			(xy 267.768578 -102.410768) (xy 267.754502 -102.405154) (xy 267.727046 -102.392319) (xy 267.713714 -102.385114)
			(xy 267.708126 -102.382066) (xy 267.683742 -102.375462) (xy 267.672312 -102.376732) (xy 267.650976 -102.381558)
			(xy 267.646455 -102.38262) (xy 267.637887 -102.386196) (xy 267.633958 -102.38867) (xy 267.61186 -102.403402)
			(xy 267.60678 -102.410514) (xy 267.589385 -102.432863) (xy 267.549085 -102.472653) (xy 267.526516 -102.489762)
			(xy 267.526008 -102.490016) (xy 267.518951 -102.495735) (xy 267.509065 -102.510962) (xy 267.506704 -102.519734)
			(xy 267.504926 -102.529386) (xy 267.499592 -102.558596) (xy 267.499084 -102.560882) (xy 267.273532 -104.19715)
			(xy 267.272531 -104.208297) (xy 267.27912 -104.229656) (xy 267.286232 -104.238298) (xy 267.294106 -104.246934)
			(xy 267.297603 -104.250623) (xy 267.305799 -104.256632) (xy 267.310362 -104.258872) (xy 267.31976 -104.26319)
			(xy 267.330682 -104.26319) (xy 267.360446 -104.263978) (xy 267.4194 -104.272315) (xy 267.476775 -104.288225)
			(xy 267.531603 -104.31144) (xy 267.582958 -104.341569) (xy 267.629973 -104.378102) (xy 267.671855 -104.420423)
			(xy 267.707895 -104.467817) (xy 267.737485 -104.519484) (xy 267.760127 -104.574551) (xy 267.775437 -104.63209)
			(xy 267.783158 -104.691128) (xy 267.783564 -104.720898) (xy 267.783564 -105.584498) (xy 267.783074 -105.614482)
			(xy 267.775247 -105.673938) (xy 267.759726 -105.731864) (xy 267.736777 -105.787268) (xy 267.706793 -105.839203)
			(xy 267.670286 -105.886779) (xy 267.627882 -105.929184) (xy 267.580306 -105.965691) (xy 267.528371 -105.995675)
			(xy 267.472968 -106.018625) (xy 267.415042 -106.034146) (xy 267.355586 -106.041974) (xy 267.325602 -106.04246)
			(xy 267.322046 -106.04246) (xy 267.290087 -106.041668) (xy 267.226859 -106.032237) (xy 267.196062 -106.023664)
			(xy 267.184886 -106.020362) (xy 267.173964 -106.02214) (xy 267.16847 -106.023143) (xy 267.158085 -106.027243)
			(xy 267.15339 -106.030268) (xy 267.09116 -106.072686) (xy 267.08735 -106.075226) (xy 267.083286 -106.078528)
			(xy 267.001498 -107.863386) (xy 267.001524 -107.872499) (xy 267.007209 -107.889801) (xy 267.018553 -107.904048)
			(xy 267.026136 -107.909106) (xy 267.04798 -107.922314) (xy 267.051613 -107.924391) (xy 267.0594 -107.927453)
			(xy 267.063474 -107.92841) (xy 267.069939 -107.929615) (xy 267.083069 -107.92898) (xy 267.089382 -107.92714)
			(xy 267.095478 -107.924854) (xy 267.097002 -107.924092) (xy 267.099288 -107.922822) (xy 267.129043 -107.906613)
			(xy 267.192235 -107.882161) (xy 267.258334 -107.867263) (xy 267.292074 -107.864148) (xy 267.302742 -107.863386)
			(xy 267.325602 -107.862878) (xy 267.355575 -107.863368) (xy 267.415007 -107.87119) (xy 267.472911 -107.886701)
			(xy 267.528296 -107.909634) (xy 267.580215 -107.939599) (xy 267.62778 -107.976082) (xy 267.670178 -108.01846)
			(xy 267.706683 -108.066008) (xy 267.736672 -108.117913) (xy 267.759631 -108.173288) (xy 267.775169 -108.231184)
			(xy 267.783019 -108.290614) (xy 267.783564 -108.320586) (xy 267.783564 -109.18444) (xy 267.783072 -109.214394)
			(xy 267.77525 -109.27379) (xy 267.759745 -109.331658) (xy 267.736821 -109.387007) (xy 267.706872 -109.438893)
			(xy 267.670408 -109.486426) (xy 267.628054 -109.528796) (xy 267.580534 -109.565277) (xy 267.52866 -109.595246)
			(xy 267.473319 -109.61819) (xy 267.415457 -109.633717) (xy 267.356064 -109.641561) (xy 267.32611 -109.642148)
			(xy 267.325602 -109.642148) (xy 267.295936 -109.641687) (xy 267.237097 -109.634047) (xy 267.179736 -109.618882)
			(xy 267.124809 -109.596445) (xy 267.09878 -109.582204) (xy 267.095732 -109.580426) (xy 267.09057 -109.578103)
			(xy 267.079546 -109.575538) (xy 267.073888 -109.575346) (xy 267.062458 -109.576616) (xy 267.041376 -109.581442)
			(xy 267.036989 -109.582545) (xy 267.02868 -109.586121) (xy 267.024866 -109.588554) (xy 267.002768 -109.603032)
			(xy 266.997434 -109.610144) (xy 266.983629 -109.628108) (xy 266.952429 -109.660959) (xy 266.935204 -109.675676)
			(xy 266.93495 -109.67593) (xy 266.92723 -109.683116) (xy 266.917901 -109.702006) (xy 266.916916 -109.712506)
			(xy 266.841224 -111.364522) (xy 266.846812 -111.373666) (xy 266.869418 -111.385604) (xy 266.894166 -111.399198)
			(xy 266.939715 -111.432563) (xy 266.979847 -111.47228) (xy 266.99718 -111.49457) (xy 267.00226 -111.501682)
			(xy 267.024358 -111.516414) (xy 267.02831 -111.518845) (xy 267.03687 -111.522421) (xy 267.041376 -111.523526)
			(xy 267.064998 -111.52886) (xy 267.072916 -111.529871) (xy 267.0887 -111.527547) (xy 267.095986 -111.524288)
			(xy 267.122211 -111.509703) (xy 267.177643 -111.48672) (xy 267.2356 -111.471168) (xy 267.29509 -111.463311)
			(xy 267.325094 -111.46282) (xy 267.325602 -111.46282) (xy 267.355587 -111.46331) (xy 267.415043 -111.471138)
			(xy 267.472969 -111.486659) (xy 267.528373 -111.509608) (xy 267.580309 -111.539592) (xy 267.627886 -111.576098)
			(xy 267.670291 -111.618502) (xy 267.706799 -111.666078) (xy 267.736785 -111.718012) (xy 267.759736 -111.773416)
			(xy 267.775259 -111.831341) (xy 267.783089 -111.890797) (xy 267.783564 -111.920782) (xy 267.783564 -112.784382)
			(xy 267.783096 -112.814368) (xy 267.77527 -112.873829) (xy 267.75975 -112.931759) (xy 267.736801 -112.987167)
			(xy 267.706816 -113.039106) (xy 267.670308 -113.086687) (xy 267.627902 -113.129095) (xy 267.580323 -113.165605)
			(xy 267.528385 -113.195592) (xy 267.472977 -113.218543) (xy 267.415048 -113.234066) (xy 267.355588 -113.241895)
			(xy 267.325602 -113.242344) (xy 267.325094 -113.242344) (xy 267.295458 -113.241877) (xy 267.23668 -113.234235)
			(xy 267.179378 -113.21908) (xy 267.124507 -113.196665) (xy 267.098526 -113.1824) (xy 267.095478 -113.180622)
			(xy 267.090962 -113.178591) (xy 267.081367 -113.176151) (xy 267.076428 -113.175796) (xy 267.072854 -113.175608)
			(xy 267.065716 -113.176122) (xy 267.062204 -113.176812) (xy 267.041376 -113.181638) (xy 267.036989 -113.182741)
			(xy 267.028679 -113.186316) (xy 267.024866 -113.18875) (xy 267.00226 -113.203482) (xy 267.000482 -113.205768)
			(xy 266.985546 -113.225709) (xy 266.951325 -113.261919) (xy 266.912683 -113.293368) (xy 266.870279 -113.319524)
			(xy 266.824832 -113.33994) (xy 266.801092 -113.3475) (xy 266.793472 -113.349786) (xy 266.780518 -113.358422)
			(xy 266.775692 -113.364772) (xy 266.771 -113.371242) (xy 266.765557 -113.386262) (xy 266.765024 -113.394236)
			(xy 266.67333 -116.19357) (xy 266.67333 -116.19611) (xy 266.70145 -117.7544) (xy 269.288004 -117.7544)
			(xy 269.292075 -117.698778) (xy 269.304201 -117.644341) (xy 269.324124 -117.59225) (xy 269.35142 -117.543615)
			(xy 269.385506 -117.499472) (xy 269.425655 -117.460763) (xy 269.471013 -117.428312) (xy 269.520613 -117.402811)
			(xy 269.573397 -117.384804) (xy 269.62824 -117.374674) (xy 269.683974 -117.372637) (xy 269.739411 -117.378737)
			(xy 269.793368 -117.392843) (xy 269.844697 -117.414655) (xy 269.892303 -117.443709) (xy 269.935171 -117.479384)
			(xy 269.972388 -117.520921) (xy 270.003161 -117.567434) (xy 270.026833 -117.617931) (xy 270.042901 -117.671338)
			(xy 270.051021 -117.726514) (xy 270.05153 -117.7544) (xy 270.051021 -117.782286) (xy 270.042901 -117.837462)
			(xy 270.026833 -117.890869) (xy 270.003161 -117.941366) (xy 269.972388 -117.987879) (xy 269.935171 -118.029416)
			(xy 269.892303 -118.065091) (xy 269.844697 -118.094145) (xy 269.793368 -118.115957) (xy 269.739411 -118.130063)
			(xy 269.683974 -118.136163) (xy 269.62824 -118.134126) (xy 269.573397 -118.123996) (xy 269.520613 -118.105989)
			(xy 269.471013 -118.080488) (xy 269.425655 -118.048037) (xy 269.385506 -118.009328) (xy 269.35142 -117.965185)
			(xy 269.324124 -117.91655) (xy 269.304201 -117.864459) (xy 269.292075 -117.810022) (xy 269.288004 -117.7544)
			(xy 266.70145 -117.7544) (xy 266.716764 -118.603014) (xy 266.717773 -118.614535) (xy 266.728684 -118.634901)
			(xy 266.747396 -118.648453) (xy 266.758674 -118.65102) (xy 266.768072 -118.652798) (xy 266.769342 -118.653052)
			(xy 266.796284 -118.659154) (xy 266.848179 -118.678082) (xy 266.896802 -118.704298) (xy 266.941134 -118.737253)
			(xy 266.980249 -118.776259) (xy 266.99718 -118.798086) (xy 267.00226 -118.805198) (xy 267.024866 -118.81993)
			(xy 267.028699 -118.822327) (xy 267.037001 -118.825902) (xy 267.041376 -118.827042) (xy 267.062204 -118.831868)
			(xy 267.067222 -118.832897) (xy 267.077461 -118.833152) (xy 267.082524 -118.832376) (xy 267.0868 -118.83149)
			(xy 267.094976 -118.828425) (xy 267.09878 -118.82628) (xy 267.124738 -118.812039) (xy 267.179541 -118.789626)
			(xy 267.236777 -118.774469) (xy 267.29549 -118.766819) (xy 267.325094 -118.766336) (xy 267.325602 -118.766336)
			(xy 267.355586 -118.766826) (xy 267.415042 -118.774654) (xy 267.472967 -118.790175) (xy 267.52837 -118.813124)
			(xy 267.580305 -118.843108) (xy 267.627881 -118.879615) (xy 267.670285 -118.922019) (xy 267.706792 -118.969595)
			(xy 267.736776 -119.02153) (xy 267.759725 -119.076933) (xy 267.775246 -119.134858) (xy 267.783074 -119.194314)
			(xy 267.783564 -119.224298) (xy 267.783564 -120.087898) (xy 267.783074 -120.117882) (xy 267.775247 -120.177338)
			(xy 267.759726 -120.235264) (xy 267.736777 -120.290668) (xy 267.706793 -120.342603) (xy 267.670286 -120.390179)
			(xy 267.627882 -120.432584) (xy 267.580306 -120.469091) (xy 267.528371 -120.499075) (xy 267.472968 -120.522025)
			(xy 267.415042 -120.537546) (xy 267.355586 -120.545374) (xy 267.325602 -120.54586) (xy 267.325094 -120.54586)
			(xy 267.295458 -120.545393) (xy 267.23668 -120.537752) (xy 267.179377 -120.522597) (xy 267.124506 -120.500182)
			(xy 267.098526 -120.485916) (xy 267.095732 -120.484392) (xy 267.087961 -120.480936) (xy 267.071091 -120.478869)
			(xy 267.062712 -120.480328) (xy 267.041376 -120.485154) (xy 267.036855 -120.486215) (xy 267.028287 -120.489791)
			(xy 267.024358 -120.492266) (xy 267.00226 -120.506998) (xy 266.99718 -120.51411) (xy 266.981736 -120.534074)
			(xy 266.946436 -120.570151) (xy 266.906688 -120.601261) (xy 266.863186 -120.626859) (xy 266.81669 -120.646499)
			(xy 266.792456 -120.653556) (xy 266.791948 -120.653556) (xy 266.79144 -120.65381) (xy 266.783537 -120.656366)
			(xy 266.769808 -120.665696) (xy 266.764516 -120.672098) (xy 266.75969 -120.678702) (xy 266.75461 -120.694704)
			(xy 266.781788 -122.218704) (xy 266.782296 -122.225054) (xy 266.78401 -122.234238) (xy 266.793068 -122.250558)
			(xy 266.80738 -122.262541) (xy 266.816078 -122.265948) (xy 266.843788 -122.276082) (xy 266.895936 -122.303677)
			(xy 266.943201 -122.338989) (xy 266.984452 -122.381172) (xy 267.002006 -122.404886) (xy 267.005418 -122.409371)
			(xy 267.013886 -122.416805) (xy 267.01877 -122.419618) (xy 267.02201 -122.421395) (xy 267.028895 -122.424079)
			(xy 267.032486 -122.424952) (xy 267.062712 -122.43181) (xy 267.074142 -122.43308) (xy 267.098526 -122.426476)
			(xy 267.104114 -122.423428) (xy 267.129637 -122.409862) (xy 267.183367 -122.388549) (xy 267.239351 -122.374167)
			(xy 267.2967 -122.366944) (xy 267.325602 -122.366532) (xy 267.338329 -122.366614) (xy 267.363743 -122.368013)
			(xy 267.376402 -122.369326) (xy 267.376402 -122.369072) (xy 267.406545 -122.372935) (xy 267.46552 -122.387606)
			(xy 267.522036 -122.409948) (xy 267.5751 -122.439568) (xy 267.623781 -122.475947) (xy 267.667222 -122.518445)
			(xy 267.704661 -122.566315) (xy 267.73544 -122.618716) (xy 267.759017 -122.674728) (xy 267.774979 -122.733366)
			(xy 267.783045 -122.7936) (xy 267.783564 -122.823986) (xy 267.783564 -123.68784) (xy 267.783078 -123.717815)
			(xy 267.775261 -123.777252) (xy 267.759755 -123.835161) (xy 267.736823 -123.890551) (xy 267.706858 -123.942474)
			(xy 267.670372 -123.990043) (xy 267.627991 -124.032442) (xy 267.580439 -124.068948) (xy 267.55471 -124.084334)
			(xy 267.528478 -124.098889) (xy 267.473038 -124.12181) (xy 267.415081 -124.137298) (xy 267.355598 -124.145089)
			(xy 267.325602 -124.145548) (xy 267.298084 -124.145167) (xy 267.243438 -124.138638) (xy 267.189964 -124.125624)
			(xy 267.164058 -124.116338) (xy 267.148649 -124.110371) (xy 267.118647 -124.096516) (xy 267.104114 -124.088652)
			(xy 267.098526 -124.085604) (xy 267.073888 -124.079) (xy 267.062458 -124.08027) (xy 267.03782 -124.085858)
			(xy 267.030708 -124.087382) (xy 267.023154 -124.089632) (xy 267.009836 -124.098048) (xy 267.004546 -124.103892)
			(xy 267.002006 -124.107194) (xy 266.987125 -124.127336) (xy 266.952927 -124.163923) (xy 266.91424 -124.195726)
			(xy 266.871729 -124.222199) (xy 266.849098 -124.232924) (xy 266.848844 -124.233178) (xy 266.842265 -124.236401)
			(xy 266.831156 -124.245942) (xy 266.827 -124.251974) (xy 266.822936 -124.258324) (xy 266.819126 -124.272294)
			(xy 266.920472 -129.908046) (xy 266.920715 -129.913513) (xy 266.923282 -129.924148) (xy 266.925552 -129.929128)
			(xy 266.930124 -129.93878) (xy 266.938506 -129.945892) (xy 266.94511 -129.95148) (xy 266.945618 -129.951988)
			(xy 266.95488 -129.960372) (xy 266.97242 -129.978166) (xy 266.98067 -129.987548) (xy 267.000736 -130.012694)
			(xy 267.002514 -130.015234) (xy 267.024612 -130.029966) (xy 267.028563 -130.032399) (xy 267.037122 -130.035979)
			(xy 267.04163 -130.037078) (xy 267.065252 -130.042412) (xy 267.073168 -130.043415) (xy 267.088944 -130.041074)
			(xy 267.09624 -130.03784) (xy 267.122437 -130.023273) (xy 267.177809 -130.000316) (xy 267.2357 -129.984773)
			(xy 267.295124 -129.976907) (xy 267.325094 -129.976372) (xy 267.325602 -129.976372) (xy 267.355587 -129.976841)
			(xy 267.415043 -129.984669) (xy 267.472969 -130.000192) (xy 267.528373 -130.023142) (xy 267.580308 -130.053128)
			(xy 267.627883 -130.089637) (xy 267.670287 -130.132044) (xy 267.706792 -130.179622) (xy 267.736774 -130.231559)
			(xy 267.75972 -130.286965) (xy 267.775238 -130.344892) (xy 267.783061 -130.404349) (xy 267.783564 -130.434334)
			(xy 267.783564 -131.297934) (xy 267.783072 -131.327917) (xy 267.775241 -131.387369) (xy 267.759717 -131.445291)
			(xy 267.736766 -131.500691) (xy 267.70678 -131.552621) (xy 267.670274 -131.600194) (xy 267.62787 -131.642595)
			(xy 267.580295 -131.679098) (xy 267.528362 -131.70908) (xy 267.47296 -131.732027) (xy 267.415038 -131.747547)
			(xy 267.355585 -131.755374) (xy 267.325602 -131.755896) (xy 267.296866 -131.755456) (xy 267.23985 -131.748235)
			(xy 267.18419 -131.733919) (xy 267.130766 -131.712734) (xy 267.105384 -131.699254) (xy 267.104876 -131.699254)
			(xy 267.104368 -131.699) (xy 267.098643 -131.696045) (xy 267.08617 -131.692839) (xy 267.07973 -131.69265)
			(xy 267.066522 -131.692904) (xy 267.015976 -131.723384) (xy 266.98067 -131.744466) (xy 266.975844 -131.750054)
			(xy 266.975336 -131.750816) (xy 266.968478 -131.758182) (xy 266.96162 -131.765548) (xy 266.958064 -131.774438)
			(xy 266.956426 -131.77909) (xy 266.954771 -131.78881) (xy 266.954762 -131.793742) (xy 266.97825 -133.104382)
			(xy 269.509748 -133.104382) (xy 269.509748 -132.240782) (xy 269.510238 -132.210798) (xy 269.518066 -132.151342)
			(xy 269.533587 -132.093417) (xy 269.556536 -132.038013) (xy 269.58652 -131.986079) (xy 269.623026 -131.938503)
			(xy 269.665431 -131.896098) (xy 269.713007 -131.859592) (xy 269.764941 -131.829608) (xy 269.820345 -131.806659)
			(xy 269.87827 -131.791138) (xy 269.937726 -131.78331) (xy 269.997694 -131.78331) (xy 270.05715 -131.791138)
			(xy 270.115075 -131.806659) (xy 270.170479 -131.829608) (xy 270.222413 -131.859592) (xy 270.269989 -131.896098)
			(xy 270.312394 -131.938503) (xy 270.3489 -131.986079) (xy 270.378884 -132.038013) (xy 270.401833 -132.093417)
			(xy 270.417354 -132.151342) (xy 270.425182 -132.210798) (xy 270.425672 -132.240782) (xy 270.425672 -133.104382)
			(xy 270.425182 -133.134366) (xy 270.417354 -133.193822) (xy 270.401833 -133.251747) (xy 270.378884 -133.307151)
			(xy 270.3489 -133.359085) (xy 270.312394 -133.406661) (xy 270.269989 -133.449066) (xy 270.222413 -133.485572)
			(xy 270.170479 -133.515556) (xy 270.115075 -133.538505) (xy 270.05715 -133.554026) (xy 269.997694 -133.561854)
			(xy 269.937726 -133.561854) (xy 269.87827 -133.554026) (xy 269.820345 -133.538505) (xy 269.764941 -133.515556)
			(xy 269.713007 -133.485572) (xy 269.665431 -133.449066) (xy 269.623026 -133.406661) (xy 269.58652 -133.359085)
			(xy 269.556536 -133.307151) (xy 269.533587 -133.251747) (xy 269.518066 -133.193822) (xy 269.510238 -133.134366)
			(xy 269.509748 -133.104382) (xy 266.97825 -133.104382) (xy 266.982702 -133.352794) (xy 266.986004 -133.530594)
			(xy 266.987079 -133.543096) (xy 266.999591 -133.564815) (xy 267.00988 -133.571996) (xy 267.082778 -133.617208)
			(xy 267.088196 -133.620386) (xy 267.100146 -133.624242) (xy 267.1064 -133.624828) (xy 267.118846 -133.62559)
			(xy 267.130784 -133.620002) (xy 267.161336 -133.60633) (xy 267.225417 -133.587002) (xy 267.291628 -133.577203)
			(xy 267.325094 -133.576568) (xy 267.325348 -133.576568) (xy 267.33627 -133.576314) (xy 267.365789 -133.577457)
			(xy 267.424182 -133.586404) (xy 267.48094 -133.602787) (xy 267.53512 -133.626334) (xy 267.585822 -133.656652)
			(xy 267.632203 -133.693239) (xy 267.673494 -133.735488) (xy 267.709009 -133.782695) (xy 267.738158 -133.834078)
			(xy 267.760456 -133.888783) (xy 267.775535 -133.945901) (xy 267.783142 -134.004485) (xy 267.783564 -134.034022)
			(xy 267.783564 -134.897876) (xy 267.783076 -134.927833) (xy 267.775261 -134.987235) (xy 267.759761 -135.04511)
			(xy 267.736841 -135.100467) (xy 267.706894 -135.152359) (xy 267.670431 -135.1999) (xy 267.628076 -135.242277)
			(xy 267.580554 -135.278764) (xy 267.528677 -135.308738) (xy 267.473331 -135.331686) (xy 267.415465 -135.347215)
			(xy 267.356067 -135.355061) (xy 267.32611 -135.355584) (xy 267.325602 -135.355584) (xy 267.325602 -135.355838)
			(xy 267.297074 -135.355368) (xy 267.240467 -135.348221) (xy 267.185182 -135.334113) (xy 267.15847 -135.324088)
			(xy 267.146554 -135.320099) (xy 267.121626 -135.323016) (xy 267.110972 -135.329676) (xy 267.041884 -135.377936)
			(xy 267.031946 -135.385655) (xy 267.020499 -135.408032) (xy 267.02004 -135.420608) (xy 267.064998 -137.909554)
			(xy 267.064998 -137.909808) (xy 267.065252 -137.927334) (xy 267.065252 -138.210544) (xy 267.065506 -138.215116)
			(xy 267.298184 -140.85697) (xy 267.812772 -140.85697) (xy 267.816843 -140.801348) (xy 267.828969 -140.746911)
			(xy 267.848892 -140.69482) (xy 267.876188 -140.646185) (xy 267.910274 -140.602042) (xy 267.950423 -140.563333)
			(xy 267.995781 -140.530882) (xy 268.045381 -140.505381) (xy 268.098165 -140.487374) (xy 268.153008 -140.477244)
			(xy 268.208742 -140.475207) (xy 268.264179 -140.481307) (xy 268.318136 -140.495413) (xy 268.369465 -140.517225)
			(xy 268.417071 -140.546279) (xy 268.459939 -140.581954) (xy 268.497156 -140.623491) (xy 268.527929 -140.670004)
			(xy 268.551601 -140.720501) (xy 268.567669 -140.773908) (xy 268.575789 -140.829084) (xy 268.576298 -140.85697)
			(xy 268.575789 -140.884856) (xy 268.567669 -140.940032) (xy 268.551601 -140.993439) (xy 268.527929 -141.043936)
			(xy 268.497156 -141.090449) (xy 268.459939 -141.131986) (xy 268.417071 -141.167661) (xy 268.369465 -141.196715)
			(xy 268.318136 -141.218527) (xy 268.264179 -141.232633) (xy 268.208742 -141.238733) (xy 268.153008 -141.236696)
			(xy 268.098165 -141.226566) (xy 268.045381 -141.208559) (xy 267.995781 -141.183058) (xy 267.950423 -141.150607)
			(xy 267.910274 -141.111898) (xy 267.876188 -141.067755) (xy 267.848892 -141.01912) (xy 267.828969 -140.967029)
			(xy 267.816843 -140.912592) (xy 267.812772 -140.85697) (xy 267.298184 -140.85697) (xy 268.544571 -155.00858)
			(xy 269.19936 -155.00858) (xy 269.19936 -155.008326) (xy 269.199846 -154.981075) (xy 269.207602 -154.927127)
			(xy 269.222957 -154.874832) (xy 269.245599 -154.825255) (xy 269.275065 -154.779405) (xy 269.310756 -154.738214)
			(xy 269.351947 -154.702523) (xy 269.397797 -154.673057) (xy 269.447374 -154.650415) (xy 269.499669 -154.63506)
			(xy 269.553617 -154.627304) (xy 269.608119 -154.627304) (xy 269.662067 -154.63506) (xy 269.714362 -154.650415)
			(xy 269.763939 -154.673057) (xy 269.809789 -154.702523) (xy 269.85098 -154.738214) (xy 269.886671 -154.779405)
			(xy 269.916137 -154.825255) (xy 269.938779 -154.874832) (xy 269.954134 -154.927127) (xy 269.96189 -154.981075)
			(xy 269.962376 -155.008326) (xy 269.961963 -155.033651) (xy 269.955244 -155.083853) (xy 269.941941 -155.132724)
			(xy 269.922288 -155.179406) (xy 269.89663 -155.223076) (xy 269.88135 -155.243276) (xy 269.881096 -155.24353)
			(xy 269.875866 -155.250933) (xy 269.870543 -155.268248) (xy 269.870682 -155.277312) (xy 269.875508 -155.354274)
			(xy 269.883128 -155.371038) (xy 269.889732 -155.377642) (xy 269.910514 -155.399258) (xy 269.945773 -155.447753)
			(xy 269.973008 -155.50117) (xy 269.991547 -155.558191) (xy 270.000933 -155.617411) (xy 270.001492 -155.64739)
			(xy 270.001492 -155.647644) (xy 270.001006 -155.674895) (xy 269.99325 -155.728843) (xy 269.977895 -155.781138)
			(xy 269.955253 -155.830715) (xy 269.925787 -155.876565) (xy 269.890096 -155.917756) (xy 269.848905 -155.953447)
			(xy 269.803055 -155.982913) (xy 269.753478 -156.005555) (xy 269.701183 -156.02091) (xy 269.647235 -156.028666)
			(xy 269.592733 -156.028666) (xy 269.538785 -156.02091) (xy 269.48649 -156.005555) (xy 269.436913 -155.982913)
			(xy 269.391063 -155.953447) (xy 269.349872 -155.917756) (xy 269.314181 -155.876565) (xy 269.284715 -155.830715)
			(xy 269.262073 -155.781138) (xy 269.246718 -155.728843) (xy 269.238962 -155.674895) (xy 269.238476 -155.647644)
			(xy 269.238916 -155.62232) (xy 269.245627 -155.572119) (xy 269.258923 -155.523247) (xy 269.278571 -155.476565)
			(xy 269.304224 -155.432895) (xy 269.319502 -155.412694) (xy 269.319756 -155.41244) (xy 269.32496 -155.405022)
			(xy 269.330298 -155.387718) (xy 269.33017 -155.378658) (xy 269.325344 -155.301696) (xy 269.317724 -155.284932)
			(xy 269.31112 -155.278328) (xy 269.290315 -155.256734) (xy 269.25506 -155.208231) (xy 269.227831 -155.154809)
			(xy 269.209297 -155.097784) (xy 269.199916 -155.038561) (xy 269.19936 -155.00858) (xy 268.544571 -155.00858)
			(xy 268.75329 -157.3784) (xy 269.390874 -157.3784) (xy 269.394945 -157.322778) (xy 269.407071 -157.268341)
			(xy 269.426994 -157.21625) (xy 269.45429 -157.167615) (xy 269.488376 -157.123472) (xy 269.528525 -157.084763)
			(xy 269.573883 -157.052312) (xy 269.623483 -157.026811) (xy 269.676267 -157.008804) (xy 269.73111 -156.998674)
			(xy 269.786844 -156.996637) (xy 269.842281 -157.002737) (xy 269.896238 -157.016843) (xy 269.947567 -157.038655)
			(xy 269.995173 -157.067709) (xy 270.038041 -157.103384) (xy 270.075258 -157.144921) (xy 270.106031 -157.191434)
			(xy 270.129703 -157.241931) (xy 270.145771 -157.295338) (xy 270.153891 -157.350514) (xy 270.1544 -157.3784)
			(xy 270.153891 -157.406286) (xy 270.145771 -157.461462) (xy 270.129703 -157.514869) (xy 270.106031 -157.565366)
			(xy 270.075258 -157.611879) (xy 270.038041 -157.653416) (xy 269.995173 -157.689091) (xy 269.947567 -157.718145)
			(xy 269.896238 -157.739957) (xy 269.842281 -157.754063) (xy 269.786844 -157.760163) (xy 269.73111 -157.758126)
			(xy 269.676267 -157.747996) (xy 269.623483 -157.729989) (xy 269.573883 -157.704488) (xy 269.528525 -157.672037)
			(xy 269.488376 -157.633328) (xy 269.45429 -157.589185) (xy 269.426994 -157.54055) (xy 269.407071 -157.488459)
			(xy 269.394945 -157.434022) (xy 269.390874 -157.3784) (xy 268.75329 -157.3784) (xy 268.842773 -158.3944)
			(xy 269.390874 -158.3944) (xy 269.394945 -158.338778) (xy 269.407071 -158.284341) (xy 269.426994 -158.23225)
			(xy 269.45429 -158.183615) (xy 269.488376 -158.139472) (xy 269.528525 -158.100763) (xy 269.573883 -158.068312)
			(xy 269.623483 -158.042811) (xy 269.676267 -158.024804) (xy 269.73111 -158.014674) (xy 269.786844 -158.012637)
			(xy 269.842281 -158.018737) (xy 269.896238 -158.032843) (xy 269.947567 -158.054655) (xy 269.995173 -158.083709)
			(xy 270.038041 -158.119384) (xy 270.075258 -158.160921) (xy 270.106031 -158.207434) (xy 270.129703 -158.257931)
			(xy 270.145771 -158.311338) (xy 270.153891 -158.366514) (xy 270.1544 -158.3944) (xy 270.153891 -158.422286)
			(xy 270.145771 -158.477462) (xy 270.129703 -158.530869) (xy 270.106031 -158.581366) (xy 270.075258 -158.627879)
			(xy 270.038041 -158.669416) (xy 269.995173 -158.705091) (xy 269.947567 -158.734145) (xy 269.896238 -158.755957)
			(xy 269.842281 -158.770063) (xy 269.786844 -158.776163) (xy 269.73111 -158.774126) (xy 269.676267 -158.763996)
			(xy 269.623483 -158.745989) (xy 269.573883 -158.720488) (xy 269.528525 -158.688037) (xy 269.488376 -158.649328)
			(xy 269.45429 -158.605185) (xy 269.426994 -158.55655) (xy 269.407071 -158.504459) (xy 269.394945 -158.450022)
			(xy 269.390874 -158.3944) (xy 268.842773 -158.3944) (xy 271.463262 -188.147706) (xy 272.042128 -194.689984)
			(xy 272.043372 -194.699137) (xy 272.051462 -194.715727) (xy 272.064897 -194.728382) (xy 272.081941 -194.735467)
			(xy 272.09115 -194.736212) (xy 272.402554 -194.746626)
		)
		(stroke
			(width 0)
			(type solid)
		)
		(fill yes)
		(layer "In11.Cu")
		(net "GND")
	)
	(gr_poly
		(pts
			(xy 374.10009 -301.515272) (xy 374.109443 -301.514953) (xy 374.126918 -301.508289) (xy 374.134126 -301.502318)
			(xy 374.17068 -301.470379) (xy 374.248962 -301.412971) (xy 374.332452 -301.363441) (xy 374.420359 -301.322256)
			(xy 374.511851 -301.289807) (xy 374.558814 -301.277528) (xy 374.56237 -301.276766) (xy 374.744996 -301.201074)
			(xy 374.750584 -301.196756) (xy 374.786909 -301.168518) (xy 374.863917 -301.118156) (xy 374.945272 -301.07517)
			(xy 374.987566 -301.057056) (xy 375.704862 -300.759876) (xy 375.71553 -300.755304) (xy 375.72188 -300.749462)
			(xy 375.739912 -300.733545) (xy 375.779272 -300.7059) (xy 375.800366 -300.694344) (xy 375.819416 -300.684946)
			(xy 375.81967 -300.684946) (xy 375.844054 -300.674024) (xy 375.84507 -300.67377) (xy 375.846086 -300.673516)
			(xy 375.86031 -300.668944) (xy 375.862342 -300.668436) (xy 375.862596 -300.668182) (xy 375.88536 -300.661327)
			(xy 375.932106 -300.652669) (xy 375.955814 -300.65091) (xy 375.959878 -300.650656) (xy 375.972832 -300.647608)
			(xy 375.981214 -300.645068) (xy 376.281442 -300.520862) (xy 376.28322 -300.5201) (xy 376.291885 -300.515683)
			(xy 376.305306 -300.501629) (xy 376.31253 -300.483589) (xy 376.312938 -300.473872) (xy 376.312938 -299.551344)
			(xy 376.312508 -299.542441) (xy 376.306339 -299.525734) (xy 376.294832 -299.512141) (xy 376.287284 -299.507402)
			(xy 376.198892 -299.456602) (xy 376.172222 -299.456856) (xy 376.160284 -299.463714) (xy 376.138402 -299.475912)
			(xy 376.092127 -299.495107) (xy 376.04374 -299.508091) (xy 375.994071 -299.514641) (xy 375.969022 -299.515022)
			(xy 375.941767 -299.514561) (xy 375.887812 -299.506806) (xy 375.835509 -299.491451) (xy 375.785924 -299.468809)
			(xy 375.740067 -299.439341) (xy 375.69887 -299.403646) (xy 375.663173 -299.362451) (xy 375.633701 -299.316595)
			(xy 375.611057 -299.267011) (xy 375.595699 -299.21471) (xy 375.587941 -299.160755) (xy 375.587941 -299.106245)
			(xy 375.595699 -299.05229) (xy 375.611057 -298.999989) (xy 375.633701 -298.950405) (xy 375.663173 -298.904549)
			(xy 375.69887 -298.863354) (xy 375.740067 -298.827659) (xy 375.785924 -298.798191) (xy 375.835509 -298.775549)
			(xy 375.887812 -298.760194) (xy 375.941767 -298.752439) (xy 375.969022 -298.752006) (xy 375.994074 -298.752379)
			(xy 376.04375 -298.758899) (xy 376.092144 -298.771875) (xy 376.138418 -298.791084) (xy 376.160284 -298.803314)
			(xy 376.172222 -298.810172) (xy 376.198892 -298.810426) (xy 376.286522 -298.760388) (xy 376.291348 -298.755308)
			(xy 376.298206 -298.74845) (xy 376.29846 -298.748196) (xy 376.305034 -298.740812) (xy 376.312464 -298.722513)
			(xy 376.312938 -298.712636) (xy 376.312938 -296.350944) (xy 376.312508 -296.342041) (xy 376.306339 -296.325334)
			(xy 376.294832 -296.311741) (xy 376.287284 -296.307002) (xy 376.198892 -296.256202) (xy 376.172222 -296.256456)
			(xy 376.160284 -296.263314) (xy 376.138402 -296.275512) (xy 376.092127 -296.294707) (xy 376.04374 -296.307691)
			(xy 375.994071 -296.314241) (xy 375.969022 -296.314622) (xy 375.941767 -296.314161) (xy 375.887812 -296.306406)
			(xy 375.835509 -296.291051) (xy 375.785924 -296.268409) (xy 375.740067 -296.238941) (xy 375.69887 -296.203246)
			(xy 375.663173 -296.162051) (xy 375.633701 -296.116195) (xy 375.611057 -296.066611) (xy 375.595699 -296.01431)
			(xy 375.587941 -295.960355) (xy 375.587941 -295.905845) (xy 375.595699 -295.85189) (xy 375.611057 -295.799589)
			(xy 375.633701 -295.750005) (xy 375.663173 -295.704149) (xy 375.69887 -295.662954) (xy 375.740067 -295.627259)
			(xy 375.785924 -295.597791) (xy 375.835509 -295.575149) (xy 375.887812 -295.559794) (xy 375.941767 -295.552039)
			(xy 375.969022 -295.551606) (xy 375.994074 -295.551979) (xy 376.04375 -295.558499) (xy 376.092144 -295.571475)
			(xy 376.138418 -295.590684) (xy 376.160284 -295.602914) (xy 376.172222 -295.609772) (xy 376.198892 -295.610026)
			(xy 376.286522 -295.559988) (xy 376.291348 -295.554908) (xy 376.298206 -295.54805) (xy 376.29846 -295.547796)
			(xy 376.305034 -295.540412) (xy 376.312464 -295.522113) (xy 376.312938 -295.512236) (xy 376.312938 -293.150544)
			(xy 376.312508 -293.141641) (xy 376.306339 -293.124934) (xy 376.294832 -293.111341) (xy 376.287284 -293.106602)
			(xy 376.198892 -293.055802) (xy 376.172222 -293.056056) (xy 376.160284 -293.062914) (xy 376.138402 -293.075112)
			(xy 376.092127 -293.094307) (xy 376.04374 -293.107291) (xy 375.994071 -293.113841) (xy 375.969022 -293.114222)
			(xy 375.941767 -293.113761) (xy 375.887812 -293.106006) (xy 375.835509 -293.090651) (xy 375.785924 -293.068009)
			(xy 375.740067 -293.038541) (xy 375.69887 -293.002846) (xy 375.663173 -292.961651) (xy 375.633701 -292.915795)
			(xy 375.611057 -292.866211) (xy 375.595699 -292.81391) (xy 375.587941 -292.759955) (xy 375.587941 -292.705445)
			(xy 375.595699 -292.65149) (xy 375.611057 -292.599189) (xy 375.633701 -292.549605) (xy 375.663173 -292.503749)
			(xy 375.69887 -292.462554) (xy 375.740067 -292.426859) (xy 375.785924 -292.397391) (xy 375.835509 -292.374749)
			(xy 375.887812 -292.359394) (xy 375.941767 -292.351639) (xy 375.969022 -292.351206) (xy 375.994074 -292.351579)
			(xy 376.04375 -292.358099) (xy 376.092144 -292.371075) (xy 376.138418 -292.390284) (xy 376.160284 -292.402514)
			(xy 376.172222 -292.409372) (xy 376.198892 -292.409626) (xy 376.286522 -292.359588) (xy 376.291348 -292.354508)
			(xy 376.298206 -292.34765) (xy 376.29846 -292.347396) (xy 376.305034 -292.340012) (xy 376.312464 -292.321713)
			(xy 376.312938 -292.311836) (xy 376.312938 -289.950144) (xy 376.312508 -289.941241) (xy 376.306339 -289.924534)
			(xy 376.294832 -289.910941) (xy 376.287284 -289.906202) (xy 376.198892 -289.855402) (xy 376.172222 -289.855656)
			(xy 376.160284 -289.862514) (xy 376.138402 -289.874712) (xy 376.092127 -289.893907) (xy 376.04374 -289.906891)
			(xy 375.994071 -289.913441) (xy 375.969022 -289.913822) (xy 375.941767 -289.913361) (xy 375.887812 -289.905606)
			(xy 375.835509 -289.890251) (xy 375.785924 -289.867609) (xy 375.740067 -289.838141) (xy 375.69887 -289.802446)
			(xy 375.663173 -289.761251) (xy 375.633701 -289.715395) (xy 375.611057 -289.665811) (xy 375.595699 -289.61351)
			(xy 375.587941 -289.559555) (xy 375.587941 -289.505045) (xy 375.595699 -289.45109) (xy 375.611057 -289.398789)
			(xy 375.633701 -289.349205) (xy 375.663173 -289.303349) (xy 375.69887 -289.262154) (xy 375.740067 -289.226459)
			(xy 375.785924 -289.196991) (xy 375.835509 -289.174349) (xy 375.887812 -289.158994) (xy 375.941767 -289.151239)
			(xy 375.969022 -289.150806) (xy 375.994074 -289.151179) (xy 376.04375 -289.157699) (xy 376.092144 -289.170675)
			(xy 376.138418 -289.189884) (xy 376.160284 -289.202114) (xy 376.172222 -289.208972) (xy 376.198892 -289.209226)
			(xy 376.286522 -289.159188) (xy 376.291348 -289.154108) (xy 376.298206 -289.14725) (xy 376.29846 -289.146996)
			(xy 376.305034 -289.139612) (xy 376.312464 -289.121313) (xy 376.312938 -289.111436) (xy 376.312938 -286.749744)
			(xy 376.312508 -286.740841) (xy 376.306339 -286.724134) (xy 376.294832 -286.710541) (xy 376.287284 -286.705802)
			(xy 376.198892 -286.655002) (xy 376.172222 -286.655256) (xy 376.160284 -286.662114) (xy 376.138402 -286.674312)
			(xy 376.092127 -286.693507) (xy 376.04374 -286.706491) (xy 375.994071 -286.713041) (xy 375.969022 -286.713422)
			(xy 375.941767 -286.712961) (xy 375.887812 -286.705206) (xy 375.835509 -286.689851) (xy 375.785924 -286.667209)
			(xy 375.740067 -286.637741) (xy 375.69887 -286.602046) (xy 375.663173 -286.560851) (xy 375.633701 -286.514995)
			(xy 375.611057 -286.465411) (xy 375.595699 -286.41311) (xy 375.587941 -286.359155) (xy 375.587941 -286.304645)
			(xy 375.595699 -286.25069) (xy 375.611057 -286.198389) (xy 375.633701 -286.148805) (xy 375.663173 -286.102949)
			(xy 375.69887 -286.061754) (xy 375.740067 -286.026059) (xy 375.785924 -285.996591) (xy 375.835509 -285.973949)
			(xy 375.887812 -285.958594) (xy 375.941767 -285.950839) (xy 375.969022 -285.950406) (xy 375.994074 -285.950779)
			(xy 376.04375 -285.957299) (xy 376.092144 -285.970275) (xy 376.138418 -285.989484) (xy 376.160284 -286.001714)
			(xy 376.172222 -286.008572) (xy 376.198892 -286.008826) (xy 376.286522 -285.958788) (xy 376.291348 -285.953708)
			(xy 376.298206 -285.94685) (xy 376.29846 -285.946596) (xy 376.305034 -285.939212) (xy 376.312464 -285.920913)
			(xy 376.312938 -285.911036) (xy 376.312938 -283.549344) (xy 376.312508 -283.540441) (xy 376.306339 -283.523734)
			(xy 376.294832 -283.510141) (xy 376.287284 -283.505402) (xy 376.198892 -283.454602) (xy 376.172222 -283.454856)
			(xy 376.160284 -283.461714) (xy 376.138402 -283.473912) (xy 376.092127 -283.493107) (xy 376.04374 -283.506091)
			(xy 375.994071 -283.512641) (xy 375.969022 -283.513022) (xy 375.941767 -283.512561) (xy 375.887812 -283.504806)
			(xy 375.835509 -283.489451) (xy 375.785924 -283.466809) (xy 375.740067 -283.437341) (xy 375.69887 -283.401646)
			(xy 375.663173 -283.360451) (xy 375.633701 -283.314595) (xy 375.611057 -283.265011) (xy 375.595699 -283.21271)
			(xy 375.587941 -283.158755) (xy 375.587941 -283.104245) (xy 375.595699 -283.05029) (xy 375.611057 -282.997989)
			(xy 375.633701 -282.948405) (xy 375.663173 -282.902549) (xy 375.69887 -282.861354) (xy 375.740067 -282.825659)
			(xy 375.785924 -282.796191) (xy 375.835509 -282.773549) (xy 375.887812 -282.758194) (xy 375.941767 -282.750439)
			(xy 375.969022 -282.750006) (xy 375.994074 -282.750379) (xy 376.04375 -282.756899) (xy 376.092144 -282.769875)
			(xy 376.138418 -282.789084) (xy 376.160284 -282.801314) (xy 376.172222 -282.808172) (xy 376.198892 -282.808426)
			(xy 376.286522 -282.758388) (xy 376.291348 -282.753308) (xy 376.298206 -282.74645) (xy 376.29846 -282.746196)
			(xy 376.305034 -282.738812) (xy 376.312464 -282.720513) (xy 376.312938 -282.710636) (xy 376.312938 -280.348944)
			(xy 376.312508 -280.340041) (xy 376.306339 -280.323334) (xy 376.294832 -280.309741) (xy 376.287284 -280.305002)
			(xy 376.198892 -280.254202) (xy 376.172222 -280.254456) (xy 376.160284 -280.261314) (xy 376.138402 -280.273512)
			(xy 376.092127 -280.292707) (xy 376.04374 -280.305691) (xy 375.994071 -280.312241) (xy 375.969022 -280.312622)
			(xy 375.941767 -280.312161) (xy 375.887812 -280.304406) (xy 375.835509 -280.289051) (xy 375.785924 -280.266409)
			(xy 375.740067 -280.236941) (xy 375.69887 -280.201246) (xy 375.663173 -280.160051) (xy 375.633701 -280.114195)
			(xy 375.611057 -280.064611) (xy 375.595699 -280.01231) (xy 375.587941 -279.958355) (xy 375.587941 -279.903845)
			(xy 375.595699 -279.84989) (xy 375.611057 -279.797589) (xy 375.633701 -279.748005) (xy 375.663173 -279.702149)
			(xy 375.69887 -279.660954) (xy 375.740067 -279.625259) (xy 375.785924 -279.595791) (xy 375.835509 -279.573149)
			(xy 375.887812 -279.557794) (xy 375.941767 -279.550039) (xy 375.969022 -279.549606) (xy 375.994074 -279.549979)
			(xy 376.04375 -279.556499) (xy 376.092144 -279.569475) (xy 376.138418 -279.588684) (xy 376.160284 -279.600914)
			(xy 376.172222 -279.607772) (xy 376.198892 -279.608026) (xy 376.286522 -279.557988) (xy 376.291348 -279.552908)
			(xy 376.298206 -279.54605) (xy 376.29846 -279.545796) (xy 376.305034 -279.538412) (xy 376.312464 -279.520113)
			(xy 376.312938 -279.510236) (xy 376.312938 -278.875236) (xy 376.305318 -278.85644) (xy 376.297952 -278.849328)
			(xy 372.795292 -275.346668) (xy 372.788452 -275.339267) (xy 372.78073 -275.320669) (xy 372.780306 -275.3106)
			(xy 372.780306 -268.781276) (xy 372.780734 -268.771208) (xy 372.788455 -268.75261) (xy 372.795292 -268.745208)
			(xy 379.428756 -262.111744) (xy 379.429264 -262.111236) (xy 379.435843 -262.103854) (xy 379.443288 -262.085555)
			(xy 379.443742 -262.075676) (xy 379.443742 -259.659628) (xy 379.442726 -259.654294) (xy 379.438949 -259.63502)
			(xy 379.434882 -259.595954) (xy 379.434598 -259.576316) (xy 379.434855 -259.556676) (xy 379.438931 -259.517609)
			(xy 379.442726 -259.498338) (xy 379.443742 -259.493004) (xy 379.443742 -258.112514) (xy 379.439678 -258.1021)
			(xy 379.439678 -256.438146) (xy 379.43917 -256.434336) (xy 379.437041 -256.419825) (xy 379.434751 -256.390582)
			(xy 379.434598 -256.375916) (xy 379.434757 -256.36125) (xy 379.437048 -256.332008) (xy 379.43917 -256.317496)
			(xy 379.439678 -256.313686) (xy 379.439678 -255.22301) (xy 379.432058 -255.204214) (xy 379.424692 -255.197102)
			(xy 378.40412 -254.17653) (xy 378.396719 -254.169693) (xy 378.37812 -254.161983) (xy 378.368052 -254.161544)
			(xy 376.886216 -254.161544) (xy 376.88266 -254.161544) (xy 376.870577 -254.163091) (xy 376.849775 -254.175698)
			(xy 376.842782 -254.185674) (xy 376.838718 -254.19431) (xy 376.806968 -254.277114) (xy 376.803925 -254.286656)
			(xy 376.804576 -254.306654) (xy 376.808238 -254.315976) (xy 376.818144 -254.338582) (xy 376.825764 -254.34544)
			(xy 376.844304 -254.363547) (xy 376.876818 -254.403901) (xy 376.903576 -254.448282) (xy 376.924085 -254.495874)
			(xy 376.937967 -254.545803) (xy 376.944969 -254.59715) (xy 376.945398 -254.623062) (xy 376.944912 -254.650313)
			(xy 376.937156 -254.704261) (xy 376.921801 -254.756556) (xy 376.899159 -254.806133) (xy 376.869693 -254.851983)
			(xy 376.834002 -254.893174) (xy 376.792811 -254.928865) (xy 376.746961 -254.958331) (xy 376.697384 -254.980973)
			(xy 376.645089 -254.996328) (xy 376.591141 -255.004084) (xy 376.536639 -255.004084) (xy 376.482691 -254.996328)
			(xy 376.430396 -254.980973) (xy 376.380819 -254.958331) (xy 376.334969 -254.928865) (xy 376.293778 -254.893174)
			(xy 376.258087 -254.851983) (xy 376.228621 -254.806133) (xy 376.205979 -254.756556) (xy 376.190624 -254.704261)
			(xy 376.182868 -254.650313) (xy 376.182382 -254.623062) (xy 376.182813 -254.597139) (xy 376.18983 -254.545769)
			(xy 376.203742 -254.495824) (xy 376.224294 -254.448224) (xy 376.251105 -254.403848) (xy 376.283682 -254.363514)
			(xy 376.30227 -254.34544) (xy 376.309636 -254.338582) (xy 376.319542 -254.315976) (xy 376.323331 -254.30668)
			(xy 376.323998 -254.286633) (xy 376.320812 -254.277114) (xy 376.289062 -254.19431) (xy 376.284998 -254.185674)
			(xy 376.278044 -254.17566) (xy 376.257218 -254.163054) (xy 376.24512 -254.161544) (xy 369.951254 -254.161544)
			(xy 369.932458 -254.169164) (xy 369.925346 -254.17653) (xy 369.277392 -254.824484) (xy 369.27056 -254.831888)
			(xy 369.262857 -254.850486) (xy 369.262406 -254.860552) (xy 369.262406 -255.910588) (xy 370.17655 -255.910588)
			(xy 370.180621 -255.854966) (xy 370.192747 -255.800529) (xy 370.21267 -255.748438) (xy 370.239966 -255.699803)
			(xy 370.274052 -255.65566) (xy 370.314201 -255.616951) (xy 370.359559 -255.5845) (xy 370.409159 -255.558999)
			(xy 370.461943 -255.540992) (xy 370.516786 -255.530862) (xy 370.57252 -255.528825) (xy 370.627957 -255.534925)
			(xy 370.681914 -255.549031) (xy 370.733243 -255.570843) (xy 370.780849 -255.599897) (xy 370.823717 -255.635572)
			(xy 370.860934 -255.677109) (xy 370.871743 -255.693446) (xy 371.065618 -255.693446) (xy 371.065618 -255.638954)
			(xy 371.073372 -255.585016) (xy 371.088724 -255.532731) (xy 371.111359 -255.483162) (xy 371.140817 -255.437319)
			(xy 371.1765 -255.396134) (xy 371.21768 -255.360446) (xy 371.26352 -255.330982) (xy 371.313086 -255.30834)
			(xy 371.365369 -255.292983) (xy 371.419306 -255.285221) (xy 371.446552 -255.284732) (xy 371.475504 -255.285312)
			(xy 371.532742 -255.294063) (xy 371.588003 -255.311356) (xy 371.640019 -255.336794) (xy 371.687598 -255.369795)
			(xy 371.729649 -255.409602) (xy 371.765207 -255.455301) (xy 371.7798 -255.480312) (xy 371.787615 -255.493169)
			(xy 371.809268 -255.514035) (xy 371.836061 -255.527686) (xy 371.865669 -255.532938) (xy 371.895523 -255.529336)
			(xy 371.923031 -255.517191) (xy 371.945808 -255.497558) (xy 371.954298 -255.485138) (xy 371.969379 -255.462142)
			(xy 372.005086 -255.420318) (xy 372.046426 -255.384052) (xy 372.092544 -255.354096) (xy 372.142484 -255.33107)
			(xy 372.195212 -255.315451) (xy 372.249636 -255.307562) (xy 372.277132 -255.307084) (xy 372.304381 -255.307588)
			(xy 372.358324 -255.315348) (xy 372.410614 -255.330706) (xy 372.460186 -255.353348) (xy 372.506032 -255.382815)
			(xy 372.547217 -255.418505) (xy 372.582905 -255.459694) (xy 372.612367 -255.505542) (xy 372.635006 -255.555116)
			(xy 372.650359 -255.607407) (xy 372.658114 -255.661351) (xy 372.658114 -255.715849) (xy 372.650359 -255.769793)
			(xy 372.635006 -255.822084) (xy 372.612367 -255.871658) (xy 372.582905 -255.917506) (xy 372.547217 -255.958695)
			(xy 372.506032 -255.994385) (xy 372.460186 -256.023852) (xy 372.410614 -256.046494) (xy 372.358324 -256.061852)
			(xy 372.304381 -256.069612) (xy 372.277132 -256.0701) (xy 372.248178 -256.069567) (xy 372.190936 -256.060812)
			(xy 372.135672 -256.043514) (xy 372.083654 -256.018068) (xy 372.036076 -255.985059) (xy 371.994027 -255.945244)
			(xy 371.958474 -255.899535) (xy 371.943884 -255.87452) (xy 371.936088 -255.861654) (xy 371.914426 -255.8408)
			(xy 371.88763 -255.827159) (xy 371.858023 -255.821912) (xy 371.828171 -255.825514) (xy 371.800663 -255.837654)
			(xy 371.777881 -255.857278) (xy 371.769386 -255.869694) (xy 371.754326 -255.892705) (xy 371.718615 -255.934527)
			(xy 371.67727 -255.970791) (xy 371.631149 -256.000744) (xy 371.581206 -256.023768) (xy 371.528475 -256.039385)
			(xy 371.474049 -256.047271) (xy 371.446552 -256.047748) (xy 371.419306 -256.047179) (xy 371.365369 -256.039417)
			(xy 371.313086 -256.02406) (xy 371.26352 -256.001418) (xy 371.21768 -255.971954) (xy 371.1765 -255.936266)
			(xy 371.140817 -255.895081) (xy 371.111359 -255.849238) (xy 371.088724 -255.799669) (xy 371.073372 -255.747384)
			(xy 371.065618 -255.693446) (xy 370.871743 -255.693446) (xy 370.891707 -255.723622) (xy 370.915379 -255.774119)
			(xy 370.931447 -255.827526) (xy 370.939567 -255.882702) (xy 370.940076 -255.910588) (xy 370.939567 -255.938474)
			(xy 370.931447 -255.99365) (xy 370.915379 -256.047057) (xy 370.891707 -256.097554) (xy 370.891049 -256.098548)
			(xy 376.181872 -256.098548) (xy 376.185943 -256.042926) (xy 376.198069 -255.988489) (xy 376.217992 -255.936398)
			(xy 376.245288 -255.887763) (xy 376.279374 -255.84362) (xy 376.319523 -255.804911) (xy 376.364881 -255.77246)
			(xy 376.414481 -255.746959) (xy 376.467265 -255.728952) (xy 376.522108 -255.718822) (xy 376.577842 -255.716785)
			(xy 376.633279 -255.722885) (xy 376.687236 -255.736991) (xy 376.738565 -255.758803) (xy 376.786171 -255.787857)
			(xy 376.829039 -255.823532) (xy 376.866256 -255.865069) (xy 376.897029 -255.911582) (xy 376.920701 -255.962079)
			(xy 376.936769 -256.015486) (xy 376.944889 -256.070662) (xy 376.945398 -256.098548) (xy 376.944889 -256.126434)
			(xy 376.936769 -256.18161) (xy 376.920701 -256.235017) (xy 376.897029 -256.285514) (xy 376.866256 -256.332027)
			(xy 376.829039 -256.373564) (xy 376.826213 -256.375916) (xy 377.069602 -256.375916) (xy 377.073673 -256.320294)
			(xy 377.085799 -256.265857) (xy 377.105722 -256.213766) (xy 377.133018 -256.165131) (xy 377.167104 -256.120988)
			(xy 377.207253 -256.082279) (xy 377.252611 -256.049828) (xy 377.302211 -256.024327) (xy 377.354995 -256.00632)
			(xy 377.409838 -255.99619) (xy 377.465572 -255.994153) (xy 377.521009 -256.000253) (xy 377.574966 -256.014359)
			(xy 377.626295 -256.036171) (xy 377.673901 -256.065225) (xy 377.716769 -256.1009) (xy 377.753986 -256.142437)
			(xy 377.784759 -256.18895) (xy 377.808431 -256.239447) (xy 377.824499 -256.292854) (xy 377.832619 -256.34803)
			(xy 377.833128 -256.375916) (xy 378.545088 -256.375916) (xy 378.549159 -256.320294) (xy 378.561285 -256.265857)
			(xy 378.581208 -256.213766) (xy 378.608504 -256.165131) (xy 378.64259 -256.120988) (xy 378.682739 -256.082279)
			(xy 378.728097 -256.049828) (xy 378.777697 -256.024327) (xy 378.830481 -256.00632) (xy 378.885324 -255.99619)
			(xy 378.941058 -255.994153) (xy 378.996495 -256.000253) (xy 379.050452 -256.014359) (xy 379.101781 -256.036171)
			(xy 379.149387 -256.065225) (xy 379.192255 -256.1009) (xy 379.229472 -256.142437) (xy 379.260245 -256.18895)
			(xy 379.283917 -256.239447) (xy 379.299985 -256.292854) (xy 379.308105 -256.34803) (xy 379.308614 -256.375916)
			(xy 379.308105 -256.403802) (xy 379.299985 -256.458978) (xy 379.283917 -256.512385) (xy 379.260245 -256.562882)
			(xy 379.229472 -256.609395) (xy 379.192255 -256.650932) (xy 379.149387 -256.686607) (xy 379.101781 -256.715661)
			(xy 379.050452 -256.737473) (xy 378.996495 -256.751579) (xy 378.941058 -256.757679) (xy 378.885324 -256.755642)
			(xy 378.830481 -256.745512) (xy 378.777697 -256.727505) (xy 378.728097 -256.702004) (xy 378.682739 -256.669553)
			(xy 378.64259 -256.630844) (xy 378.608504 -256.586701) (xy 378.581208 -256.538066) (xy 378.561285 -256.485975)
			(xy 378.549159 -256.431538) (xy 378.545088 -256.375916) (xy 377.833128 -256.375916) (xy 377.832619 -256.403802)
			(xy 377.824499 -256.458978) (xy 377.808431 -256.512385) (xy 377.784759 -256.562882) (xy 377.753986 -256.609395)
			(xy 377.716769 -256.650932) (xy 377.673901 -256.686607) (xy 377.626295 -256.715661) (xy 377.574966 -256.737473)
			(xy 377.521009 -256.751579) (xy 377.465572 -256.757679) (xy 377.409838 -256.755642) (xy 377.354995 -256.745512)
			(xy 377.302211 -256.727505) (xy 377.252611 -256.702004) (xy 377.207253 -256.669553) (xy 377.167104 -256.630844)
			(xy 377.133018 -256.586701) (xy 377.105722 -256.538066) (xy 377.085799 -256.485975) (xy 377.073673 -256.431538)
			(xy 377.069602 -256.375916) (xy 376.826213 -256.375916) (xy 376.786171 -256.409239) (xy 376.738565 -256.438293)
			(xy 376.687236 -256.460105) (xy 376.633279 -256.474211) (xy 376.577842 -256.480311) (xy 376.522108 -256.478274)
			(xy 376.467265 -256.468144) (xy 376.414481 -256.450137) (xy 376.364881 -256.424636) (xy 376.319523 -256.392185)
			(xy 376.279374 -256.353476) (xy 376.245288 -256.309333) (xy 376.217992 -256.260698) (xy 376.198069 -256.208607)
			(xy 376.185943 -256.15417) (xy 376.181872 -256.098548) (xy 370.891049 -256.098548) (xy 370.860934 -256.144067)
			(xy 370.823717 -256.185604) (xy 370.780849 -256.221279) (xy 370.733243 -256.250333) (xy 370.681914 -256.272145)
			(xy 370.627957 -256.286251) (xy 370.57252 -256.292351) (xy 370.516786 -256.290314) (xy 370.461943 -256.280184)
			(xy 370.409159 -256.262177) (xy 370.359559 -256.236676) (xy 370.314201 -256.204225) (xy 370.274052 -256.165516)
			(xy 370.239966 -256.121373) (xy 370.21267 -256.072738) (xy 370.192747 -256.020647) (xy 370.180621 -255.96621)
			(xy 370.17655 -255.910588) (xy 369.262406 -255.910588) (xy 369.262406 -256.987548) (xy 376.181872 -256.987548)
			(xy 376.185943 -256.931926) (xy 376.198069 -256.877489) (xy 376.217992 -256.825398) (xy 376.245288 -256.776763)
			(xy 376.279374 -256.73262) (xy 376.319523 -256.693911) (xy 376.364881 -256.66146) (xy 376.414481 -256.635959)
			(xy 376.467265 -256.617952) (xy 376.522108 -256.607822) (xy 376.577842 -256.605785) (xy 376.633279 -256.611885)
			(xy 376.687236 -256.625991) (xy 376.738565 -256.647803) (xy 376.786171 -256.676857) (xy 376.829039 -256.712532)
			(xy 376.866256 -256.754069) (xy 376.897029 -256.800582) (xy 376.920701 -256.851079) (xy 376.936769 -256.904486)
			(xy 376.944889 -256.959662) (xy 376.945398 -256.987548) (xy 376.944889 -257.015434) (xy 376.936769 -257.07061)
			(xy 376.920701 -257.124017) (xy 376.897029 -257.174514) (xy 376.866256 -257.221027) (xy 376.829039 -257.262564)
			(xy 376.786171 -257.298239) (xy 376.738565 -257.327293) (xy 376.687236 -257.349105) (xy 376.633279 -257.363211)
			(xy 376.577842 -257.369311) (xy 376.522108 -257.367274) (xy 376.467265 -257.357144) (xy 376.414481 -257.339137)
			(xy 376.364881 -257.313636) (xy 376.319523 -257.281185) (xy 376.279374 -257.242476) (xy 376.245288 -257.198333)
			(xy 376.217992 -257.149698) (xy 376.198069 -257.097607) (xy 376.185943 -257.04317) (xy 376.181872 -256.987548)
			(xy 369.262406 -256.987548) (xy 369.262406 -257.474212) (xy 370.2718 -257.474212) (xy 370.275871 -257.41859)
			(xy 370.287997 -257.364153) (xy 370.30792 -257.312062) (xy 370.335216 -257.263427) (xy 370.369302 -257.219284)
			(xy 370.409451 -257.180575) (xy 370.454809 -257.148124) (xy 370.504409 -257.122623) (xy 370.557193 -257.104616)
			(xy 370.612036 -257.094486) (xy 370.66777 -257.092449) (xy 370.723207 -257.098549) (xy 370.777164 -257.112655)
			(xy 370.828493 -257.134467) (xy 370.876099 -257.163521) (xy 370.918967 -257.199196) (xy 370.956184 -257.240733)
			(xy 370.986957 -257.287246) (xy 371.010629 -257.337743) (xy 371.026697 -257.39115) (xy 371.034817 -257.446326)
			(xy 371.035326 -257.474212) (xy 371.034817 -257.502098) (xy 371.026697 -257.557274) (xy 371.010629 -257.610681)
			(xy 370.986957 -257.661178) (xy 370.956184 -257.707691) (xy 370.918967 -257.749228) (xy 370.876099 -257.784903)
			(xy 370.828493 -257.813957) (xy 370.777164 -257.835769) (xy 370.723207 -257.849875) (xy 370.66777 -257.855975)
			(xy 370.612036 -257.853938) (xy 370.557193 -257.843808) (xy 370.504409 -257.825801) (xy 370.454809 -257.8003)
			(xy 370.409451 -257.767849) (xy 370.369302 -257.72914) (xy 370.335216 -257.684997) (xy 370.30792 -257.636362)
			(xy 370.287997 -257.584271) (xy 370.275871 -257.529834) (xy 370.2718 -257.474212) (xy 369.262406 -257.474212)
			(xy 369.262406 -258.248404) (xy 369.262162 -258.255354) (xy 369.25842 -258.268742) (xy 369.25504 -258.27482)
			(xy 369.254786 -258.275074) (xy 369.25123 -258.28117) (xy 369.249452 -258.28752) (xy 369.24742 -258.30149)
			(xy 369.24742 -258.665472) (xy 369.426488 -258.665472) (xy 369.430559 -258.60985) (xy 369.442685 -258.555413)
			(xy 369.462608 -258.503322) (xy 369.489904 -258.454687) (xy 369.52399 -258.410544) (xy 369.564139 -258.371835)
			(xy 369.609497 -258.339384) (xy 369.659097 -258.313883) (xy 369.711881 -258.295876) (xy 369.766724 -258.285746)
			(xy 369.822458 -258.283709) (xy 369.877895 -258.289809) (xy 369.931852 -258.303915) (xy 369.983181 -258.325727)
			(xy 370.030787 -258.354781) (xy 370.073655 -258.390456) (xy 370.110872 -258.431993) (xy 370.141645 -258.478506)
			(xy 370.165317 -258.529003) (xy 370.181385 -258.58241) (xy 370.189505 -258.637586) (xy 370.189731 -258.649978)
			(xy 371.226332 -258.649978) (xy 371.230403 -258.594356) (xy 371.242529 -258.539919) (xy 371.262452 -258.487828)
			(xy 371.289748 -258.439193) (xy 371.323834 -258.39505) (xy 371.363983 -258.356341) (xy 371.409341 -258.32389)
			(xy 371.458941 -258.298389) (xy 371.511725 -258.280382) (xy 371.566568 -258.270252) (xy 371.622302 -258.268215)
			(xy 371.677739 -258.274315) (xy 371.731696 -258.288421) (xy 371.783025 -258.310233) (xy 371.830631 -258.339287)
			(xy 371.873499 -258.374962) (xy 371.910716 -258.416499) (xy 371.941489 -258.463012) (xy 371.965161 -258.513509)
			(xy 371.981229 -258.566916) (xy 371.989349 -258.622092) (xy 371.989858 -258.649978) (xy 371.989349 -258.677864)
			(xy 371.987397 -258.691126) (xy 372.710708 -258.691126) (xy 372.714779 -258.635504) (xy 372.726905 -258.581067)
			(xy 372.746828 -258.528976) (xy 372.774124 -258.480341) (xy 372.80821 -258.436198) (xy 372.848359 -258.397489)
			(xy 372.893717 -258.365038) (xy 372.943317 -258.339537) (xy 372.996101 -258.32153) (xy 373.050944 -258.3114)
			(xy 373.106678 -258.309363) (xy 373.162115 -258.315463) (xy 373.216072 -258.329569) (xy 373.267401 -258.351381)
			(xy 373.315007 -258.380435) (xy 373.357875 -258.41611) (xy 373.395092 -258.457647) (xy 373.425865 -258.50416)
			(xy 373.449537 -258.554657) (xy 373.465605 -258.608064) (xy 373.473725 -258.66324) (xy 373.474234 -258.691126)
			(xy 373.473725 -258.719012) (xy 373.465605 -258.774188) (xy 373.449537 -258.827595) (xy 373.425865 -258.878092)
			(xy 373.395092 -258.924605) (xy 373.357875 -258.966142) (xy 373.315007 -259.001817) (xy 373.267401 -259.030871)
			(xy 373.216072 -259.052683) (xy 373.162115 -259.066789) (xy 373.106678 -259.072889) (xy 373.050944 -259.070852)
			(xy 372.996101 -259.060722) (xy 372.943317 -259.042715) (xy 372.893717 -259.017214) (xy 372.848359 -258.984763)
			(xy 372.80821 -258.946054) (xy 372.774124 -258.901911) (xy 372.746828 -258.853276) (xy 372.726905 -258.801185)
			(xy 372.714779 -258.746748) (xy 372.710708 -258.691126) (xy 371.987397 -258.691126) (xy 371.981229 -258.73304)
			(xy 371.965161 -258.786447) (xy 371.941489 -258.836944) (xy 371.910716 -258.883457) (xy 371.873499 -258.924994)
			(xy 371.830631 -258.960669) (xy 371.783025 -258.989723) (xy 371.731696 -259.011535) (xy 371.677739 -259.025641)
			(xy 371.622302 -259.031741) (xy 371.566568 -259.029704) (xy 371.511725 -259.019574) (xy 371.458941 -259.001567)
			(xy 371.409341 -258.976066) (xy 371.363983 -258.943615) (xy 371.323834 -258.904906) (xy 371.289748 -258.860763)
			(xy 371.262452 -258.812128) (xy 371.242529 -258.760037) (xy 371.230403 -258.7056) (xy 371.226332 -258.649978)
			(xy 370.189731 -258.649978) (xy 370.190014 -258.665472) (xy 370.189505 -258.693358) (xy 370.181385 -258.748534)
			(xy 370.165317 -258.801941) (xy 370.141645 -258.852438) (xy 370.110872 -258.898951) (xy 370.073655 -258.940488)
			(xy 370.030787 -258.976163) (xy 369.983181 -259.005217) (xy 369.931852 -259.027029) (xy 369.877895 -259.041135)
			(xy 369.822458 -259.047235) (xy 369.766724 -259.045198) (xy 369.711881 -259.035068) (xy 369.659097 -259.017061)
			(xy 369.609497 -258.99156) (xy 369.564139 -258.959109) (xy 369.52399 -258.9204) (xy 369.489904 -258.876257)
			(xy 369.462608 -258.827622) (xy 369.442685 -258.775531) (xy 369.430559 -258.721094) (xy 369.426488 -258.665472)
			(xy 369.24742 -258.665472) (xy 369.24742 -259.94487) (xy 369.513102 -259.94487) (xy 369.517173 -259.889248)
			(xy 369.529299 -259.834811) (xy 369.549222 -259.78272) (xy 369.576518 -259.734085) (xy 369.610604 -259.689942)
			(xy 369.650753 -259.651233) (xy 369.696111 -259.618782) (xy 369.745711 -259.593281) (xy 369.798495 -259.575274)
			(xy 369.853338 -259.565144) (xy 369.909072 -259.563107) (xy 369.964509 -259.569207) (xy 369.991702 -259.576316)
			(xy 377.069602 -259.576316) (xy 377.073673 -259.520694) (xy 377.085799 -259.466257) (xy 377.105722 -259.414166)
			(xy 377.133018 -259.365531) (xy 377.167104 -259.321388) (xy 377.207253 -259.282679) (xy 377.252611 -259.250228)
			(xy 377.302211 -259.224727) (xy 377.354995 -259.20672) (xy 377.409838 -259.19659) (xy 377.465572 -259.194553)
			(xy 377.521009 -259.200653) (xy 377.574966 -259.214759) (xy 377.626295 -259.236571) (xy 377.673901 -259.265625)
			(xy 377.716769 -259.3013) (xy 377.753986 -259.342837) (xy 377.784759 -259.38935) (xy 377.808431 -259.439847)
			(xy 377.824499 -259.493254) (xy 377.832619 -259.54843) (xy 377.833128 -259.576316) (xy 378.545088 -259.576316)
			(xy 378.549159 -259.520694) (xy 378.561285 -259.466257) (xy 378.581208 -259.414166) (xy 378.608504 -259.365531)
			(xy 378.64259 -259.321388) (xy 378.682739 -259.282679) (xy 378.728097 -259.250228) (xy 378.777697 -259.224727)
			(xy 378.830481 -259.20672) (xy 378.885324 -259.19659) (xy 378.941058 -259.194553) (xy 378.996495 -259.200653)
			(xy 379.050452 -259.214759) (xy 379.101781 -259.236571) (xy 379.149387 -259.265625) (xy 379.192255 -259.3013)
			(xy 379.229472 -259.342837) (xy 379.260245 -259.38935) (xy 379.283917 -259.439847) (xy 379.299985 -259.493254)
			(xy 379.308105 -259.54843) (xy 379.308614 -259.576316) (xy 379.308105 -259.604202) (xy 379.299985 -259.659378)
			(xy 379.283917 -259.712785) (xy 379.260245 -259.763282) (xy 379.229472 -259.809795) (xy 379.192255 -259.851332)
			(xy 379.149387 -259.887007) (xy 379.101781 -259.916061) (xy 379.050452 -259.937873) (xy 378.996495 -259.951979)
			(xy 378.941058 -259.958079) (xy 378.885324 -259.956042) (xy 378.830481 -259.945912) (xy 378.777697 -259.927905)
			(xy 378.728097 -259.902404) (xy 378.682739 -259.869953) (xy 378.64259 -259.831244) (xy 378.608504 -259.787101)
			(xy 378.581208 -259.738466) (xy 378.561285 -259.686375) (xy 378.549159 -259.631938) (xy 378.545088 -259.576316)
			(xy 377.833128 -259.576316) (xy 377.832619 -259.604202) (xy 377.824499 -259.659378) (xy 377.808431 -259.712785)
			(xy 377.784759 -259.763282) (xy 377.753986 -259.809795) (xy 377.716769 -259.851332) (xy 377.673901 -259.887007)
			(xy 377.626295 -259.916061) (xy 377.574966 -259.937873) (xy 377.521009 -259.951979) (xy 377.465572 -259.958079)
			(xy 377.409838 -259.956042) (xy 377.354995 -259.945912) (xy 377.302211 -259.927905) (xy 377.252611 -259.902404)
			(xy 377.207253 -259.869953) (xy 377.167104 -259.831244) (xy 377.133018 -259.787101) (xy 377.105722 -259.738466)
			(xy 377.085799 -259.686375) (xy 377.073673 -259.631938) (xy 377.069602 -259.576316) (xy 369.991702 -259.576316)
			(xy 370.018466 -259.583313) (xy 370.069795 -259.605125) (xy 370.117401 -259.634179) (xy 370.160269 -259.669854)
			(xy 370.197486 -259.711391) (xy 370.228259 -259.757904) (xy 370.251931 -259.808401) (xy 370.267999 -259.861808)
			(xy 370.276119 -259.916984) (xy 370.276628 -259.94487) (xy 370.276119 -259.972756) (xy 370.267999 -260.027932)
			(xy 370.255162 -260.0706) (xy 371.942866 -260.0706) (xy 371.946937 -260.014978) (xy 371.959063 -259.960541)
			(xy 371.978986 -259.90845) (xy 372.006282 -259.859815) (xy 372.040368 -259.815672) (xy 372.080517 -259.776963)
			(xy 372.125875 -259.744512) (xy 372.175475 -259.719011) (xy 372.228259 -259.701004) (xy 372.283102 -259.690874)
			(xy 372.338836 -259.688837) (xy 372.394273 -259.694937) (xy 372.44823 -259.709043) (xy 372.499559 -259.730855)
			(xy 372.547165 -259.759909) (xy 372.590033 -259.795584) (xy 372.62725 -259.837121) (xy 372.658023 -259.883634)
			(xy 372.681695 -259.934131) (xy 372.697763 -259.987538) (xy 372.705883 -260.042714) (xy 372.706392 -260.0706)
			(xy 372.705883 -260.098486) (xy 372.697763 -260.153662) (xy 372.695701 -260.160516) (xy 376.181872 -260.160516)
			(xy 376.185943 -260.104894) (xy 376.198069 -260.050457) (xy 376.217992 -259.998366) (xy 376.245288 -259.949731)
			(xy 376.279374 -259.905588) (xy 376.319523 -259.866879) (xy 376.364881 -259.834428) (xy 376.414481 -259.808927)
			(xy 376.467265 -259.79092) (xy 376.522108 -259.78079) (xy 376.577842 -259.778753) (xy 376.633279 -259.784853)
			(xy 376.687236 -259.798959) (xy 376.738565 -259.820771) (xy 376.786171 -259.849825) (xy 376.829039 -259.8855)
			(xy 376.866256 -259.927037) (xy 376.897029 -259.97355) (xy 376.920701 -260.024047) (xy 376.936769 -260.077454)
			(xy 376.944889 -260.13263) (xy 376.945398 -260.160516) (xy 376.944889 -260.188402) (xy 376.936769 -260.243578)
			(xy 376.920701 -260.296985) (xy 376.897029 -260.347482) (xy 376.866256 -260.393995) (xy 376.829039 -260.435532)
			(xy 376.786171 -260.471207) (xy 376.738565 -260.500261) (xy 376.687236 -260.522073) (xy 376.633279 -260.536179)
			(xy 376.577842 -260.542279) (xy 376.522108 -260.540242) (xy 376.467265 -260.530112) (xy 376.414481 -260.512105)
			(xy 376.364881 -260.486604) (xy 376.319523 -260.454153) (xy 376.279374 -260.415444) (xy 376.245288 -260.371301)
			(xy 376.217992 -260.322666) (xy 376.198069 -260.270575) (xy 376.185943 -260.216138) (xy 376.181872 -260.160516)
			(xy 372.695701 -260.160516) (xy 372.681695 -260.207069) (xy 372.658023 -260.257566) (xy 372.62725 -260.304079)
			(xy 372.590033 -260.345616) (xy 372.547165 -260.381291) (xy 372.499559 -260.410345) (xy 372.44823 -260.432157)
			(xy 372.394273 -260.446263) (xy 372.338836 -260.452363) (xy 372.283102 -260.450326) (xy 372.228259 -260.440196)
			(xy 372.175475 -260.422189) (xy 372.125875 -260.396688) (xy 372.080517 -260.364237) (xy 372.040368 -260.325528)
			(xy 372.006282 -260.281385) (xy 371.978986 -260.23275) (xy 371.959063 -260.180659) (xy 371.946937 -260.126222)
			(xy 371.942866 -260.0706) (xy 370.255162 -260.0706) (xy 370.251931 -260.081339) (xy 370.228259 -260.131836)
			(xy 370.197486 -260.178349) (xy 370.160269 -260.219886) (xy 370.117401 -260.255561) (xy 370.069795 -260.284615)
			(xy 370.018466 -260.306427) (xy 369.964509 -260.320533) (xy 369.909072 -260.326633) (xy 369.853338 -260.324596)
			(xy 369.798495 -260.314466) (xy 369.745711 -260.296459) (xy 369.696111 -260.270958) (xy 369.650753 -260.238507)
			(xy 369.610604 -260.199798) (xy 369.576518 -260.155655) (xy 369.549222 -260.10702) (xy 369.529299 -260.054929)
			(xy 369.517173 -260.000492) (xy 369.513102 -259.94487) (xy 369.24742 -259.94487) (xy 369.24742 -261.207758)
			(xy 370.377464 -261.207758) (xy 370.381535 -261.152136) (xy 370.393661 -261.097699) (xy 370.413584 -261.045608)
			(xy 370.44088 -260.996973) (xy 370.474966 -260.95283) (xy 370.515115 -260.914121) (xy 370.560473 -260.88167)
			(xy 370.610073 -260.856169) (xy 370.662857 -260.838162) (xy 370.7177 -260.828032) (xy 370.773434 -260.825995)
			(xy 370.828871 -260.832095) (xy 370.882828 -260.846201) (xy 370.934157 -260.868013) (xy 370.981763 -260.897067)
			(xy 371.024631 -260.932742) (xy 371.061848 -260.974279) (xy 371.092621 -261.020792) (xy 371.116293 -261.071289)
			(xy 371.132361 -261.124696) (xy 371.140481 -261.179872) (xy 371.14099 -261.207758) (xy 371.140481 -261.235644)
			(xy 371.132361 -261.29082) (xy 371.116293 -261.344227) (xy 371.092621 -261.394724) (xy 371.061848 -261.441237)
			(xy 371.024631 -261.482774) (xy 370.981763 -261.518449) (xy 370.934157 -261.547503) (xy 370.882828 -261.569315)
			(xy 370.828871 -261.583421) (xy 370.773434 -261.589521) (xy 370.7177 -261.587484) (xy 370.662857 -261.577354)
			(xy 370.610073 -261.559347) (xy 370.560473 -261.533846) (xy 370.515115 -261.501395) (xy 370.474966 -261.462686)
			(xy 370.44088 -261.418543) (xy 370.413584 -261.369908) (xy 370.393661 -261.317817) (xy 370.381535 -261.26338)
			(xy 370.377464 -261.207758) (xy 369.24742 -261.207758) (xy 369.24742 -261.706451) (xy 371.85676 -261.706451)
			(xy 371.85676 -261.651949) (xy 371.864516 -261.598002) (xy 371.87987 -261.545708) (xy 371.902509 -261.496131)
			(xy 371.931973 -261.45028) (xy 371.967662 -261.409089) (xy 372.00885 -261.373396) (xy 372.054698 -261.343927)
			(xy 372.104272 -261.321283) (xy 372.156565 -261.305924) (xy 372.210511 -261.298162) (xy 372.237762 -261.297674)
			(xy 372.265879 -261.298183) (xy 372.321506 -261.306428) (xy 372.375321 -261.322745) (xy 372.42616 -261.346782)
			(xy 372.472922 -261.378016) (xy 372.514596 -261.415774) (xy 372.550279 -261.459237) (xy 372.565168 -261.483094)
			(xy 372.57101 -261.493) (xy 372.589298 -261.505446) (xy 372.688358 -261.521448) (xy 372.709694 -261.515606)
			(xy 372.71833 -261.50824) (xy 372.739141 -261.491027) (xy 372.784716 -261.462051) (xy 372.833919 -261.439788)
			(xy 372.885769 -261.424681) (xy 372.939231 -261.417032) (xy 372.966234 -261.416546) (xy 372.99348 -261.417126)
			(xy 373.047418 -261.424886) (xy 373.099702 -261.440242) (xy 373.149269 -261.462883) (xy 373.19511 -261.492346)
			(xy 373.236291 -261.528033) (xy 373.271974 -261.569218) (xy 373.301434 -261.615061) (xy 373.32407 -261.66463)
			(xy 373.339421 -261.716915) (xy 373.347176 -261.770854) (xy 373.347176 -261.817955) (xy 373.819343 -261.817955)
			(xy 373.819343 -261.763445) (xy 373.827101 -261.709491) (xy 373.842458 -261.65719) (xy 373.865103 -261.607607)
			(xy 373.894574 -261.561751) (xy 373.930271 -261.520557) (xy 373.971467 -261.484862) (xy 374.017324 -261.455393)
			(xy 374.066909 -261.432751) (xy 374.11921 -261.417396) (xy 374.173165 -261.409642) (xy 374.20042 -261.40918)
			(xy 374.229336 -261.409726) (xy 374.286508 -261.418445) (xy 374.341707 -261.435695) (xy 374.39367 -261.461082)
			(xy 374.441204 -261.494022) (xy 374.48322 -261.533761) (xy 374.50141 -261.556246) (xy 374.508964 -261.565015)
			(xy 374.529729 -261.575193) (xy 374.541288 -261.575804) (xy 374.621552 -261.575804) (xy 374.633116 -261.575205)
			(xy 374.653887 -261.56503) (xy 374.66143 -261.556246) (xy 374.67959 -261.533737) (xy 374.721618 -261.494006)
			(xy 374.76916 -261.461071) (xy 374.821127 -261.435688) (xy 374.876329 -261.418437) (xy 374.933502 -261.409713)
			(xy 374.96242 -261.40918) (xy 374.989669 -261.409692) (xy 375.043613 -261.41745) (xy 375.095904 -261.432807)
			(xy 375.145477 -261.455448) (xy 375.191323 -261.484914) (xy 375.23251 -261.520604) (xy 375.268198 -261.561793)
			(xy 375.297662 -261.607641) (xy 375.3203 -261.657215) (xy 375.335654 -261.709506) (xy 375.34341 -261.763451)
			(xy 375.34341 -261.817949) (xy 375.335654 -261.871894) (xy 375.3203 -261.924185) (xy 375.297662 -261.973759)
			(xy 375.268198 -262.019607) (xy 375.23251 -262.060796) (xy 375.191323 -262.096486) (xy 375.145477 -262.125952)
			(xy 375.095904 -262.148593) (xy 375.043613 -262.16395) (xy 374.989669 -262.171708) (xy 374.96242 -262.172196)
			(xy 374.933504 -262.171665) (xy 374.876333 -262.162939) (xy 374.821134 -262.145683) (xy 374.769173 -262.120294)
			(xy 374.721638 -262.087353) (xy 374.679621 -262.047614) (xy 374.66143 -262.02513) (xy 374.653863 -262.016374)
			(xy 374.633108 -262.00619) (xy 374.621552 -262.005572) (xy 374.541288 -262.005572) (xy 374.529715 -262.00611)
			(xy 374.508943 -262.016325) (xy 374.50141 -262.02513) (xy 374.483221 -262.047615) (xy 374.4412 -262.087349)
			(xy 374.393664 -262.120287) (xy 374.341703 -262.145674) (xy 374.286505 -262.162931) (xy 374.229336 -262.17166)
			(xy 374.20042 -262.172196) (xy 374.173165 -262.171758) (xy 374.11921 -262.164004) (xy 374.066909 -262.148649)
			(xy 374.017324 -262.126007) (xy 373.971467 -262.096538) (xy 373.930271 -262.060843) (xy 373.894574 -262.019649)
			(xy 373.865103 -261.973793) (xy 373.842458 -261.92421) (xy 373.827101 -261.871909) (xy 373.819343 -261.817955)
			(xy 373.347176 -261.817955) (xy 373.347176 -261.825346) (xy 373.339421 -261.879285) (xy 373.32407 -261.93157)
			(xy 373.301434 -261.981139) (xy 373.271974 -262.026982) (xy 373.236291 -262.068167) (xy 373.19511 -262.103854)
			(xy 373.149269 -262.133317) (xy 373.099702 -262.155958) (xy 373.047418 -262.171314) (xy 372.99348 -262.179074)
			(xy 372.966234 -262.179562) (xy 372.938117 -262.179038) (xy 372.882492 -262.170794) (xy 372.828678 -262.154478)
			(xy 372.77784 -262.130444) (xy 372.731078 -262.099211) (xy 372.689403 -262.061457) (xy 372.653719 -262.017997)
			(xy 372.638828 -261.994142) (xy 372.632986 -261.984236) (xy 372.614698 -261.97179) (xy 372.515638 -261.955788)
			(xy 372.494302 -261.96163) (xy 372.485666 -261.968996) (xy 372.464861 -261.986216) (xy 372.419284 -262.01519)
			(xy 372.370079 -262.037451) (xy 372.318228 -262.052557) (xy 372.264765 -262.060204) (xy 372.237762 -262.06069)
			(xy 372.210511 -262.060238) (xy 372.156565 -262.052476) (xy 372.104272 -262.037117) (xy 372.054698 -262.014473)
			(xy 372.00885 -261.985004) (xy 371.967662 -261.949311) (xy 371.931973 -261.90812) (xy 371.902509 -261.862269)
			(xy 371.87987 -261.812692) (xy 371.864516 -261.760398) (xy 371.85676 -261.706451) (xy 369.24742 -261.706451)
			(xy 369.24742 -262.912352) (xy 373.468898 -262.912352) (xy 373.472969 -262.85673) (xy 373.485095 -262.802293)
			(xy 373.505018 -262.750202) (xy 373.532314 -262.701567) (xy 373.5664 -262.657424) (xy 373.606549 -262.618715)
			(xy 373.651907 -262.586264) (xy 373.701507 -262.560763) (xy 373.754291 -262.542756) (xy 373.809134 -262.532626)
			(xy 373.864868 -262.530589) (xy 373.920305 -262.536689) (xy 373.974262 -262.550795) (xy 374.025591 -262.572607)
			(xy 374.073197 -262.601661) (xy 374.116065 -262.637336) (xy 374.153282 -262.678873) (xy 374.184055 -262.725386)
			(xy 374.207727 -262.775883) (xy 374.223795 -262.82929) (xy 374.231915 -262.884466) (xy 374.232424 -262.912352)
			(xy 374.232359 -262.915908) (xy 375.442478 -262.915908) (xy 375.446549 -262.860286) (xy 375.458675 -262.805849)
			(xy 375.478598 -262.753758) (xy 375.505894 -262.705123) (xy 375.53998 -262.66098) (xy 375.580129 -262.622271)
			(xy 375.625487 -262.58982) (xy 375.675087 -262.564319) (xy 375.727871 -262.546312) (xy 375.782714 -262.536182)
			(xy 375.838448 -262.534145) (xy 375.893885 -262.540245) (xy 375.947842 -262.554351) (xy 375.999171 -262.576163)
			(xy 376.046777 -262.605217) (xy 376.089645 -262.640892) (xy 376.126862 -262.682429) (xy 376.157635 -262.728942)
			(xy 376.181307 -262.779439) (xy 376.197375 -262.832846) (xy 376.205495 -262.888022) (xy 376.206004 -262.915908)
			(xy 376.205495 -262.943794) (xy 376.197375 -262.99897) (xy 376.181307 -263.052377) (xy 376.157635 -263.102874)
			(xy 376.126862 -263.149387) (xy 376.089645 -263.190924) (xy 376.046777 -263.226599) (xy 375.999171 -263.255653)
			(xy 375.947842 -263.277465) (xy 375.893885 -263.291571) (xy 375.838448 -263.297671) (xy 375.782714 -263.295634)
			(xy 375.727871 -263.285504) (xy 375.675087 -263.267497) (xy 375.625487 -263.241996) (xy 375.580129 -263.209545)
			(xy 375.53998 -263.170836) (xy 375.505894 -263.126693) (xy 375.478598 -263.078058) (xy 375.458675 -263.025967)
			(xy 375.446549 -262.97153) (xy 375.442478 -262.915908) (xy 374.232359 -262.915908) (xy 374.231915 -262.940238)
			(xy 374.223795 -262.995414) (xy 374.207727 -263.048821) (xy 374.184055 -263.099318) (xy 374.153282 -263.145831)
			(xy 374.116065 -263.187368) (xy 374.073197 -263.223043) (xy 374.025591 -263.252097) (xy 373.974262 -263.273909)
			(xy 373.920305 -263.288015) (xy 373.864868 -263.294115) (xy 373.809134 -263.292078) (xy 373.754291 -263.281948)
			(xy 373.701507 -263.263941) (xy 373.651907 -263.23844) (xy 373.606549 -263.205989) (xy 373.5664 -263.16728)
			(xy 373.532314 -263.123137) (xy 373.505018 -263.074502) (xy 373.485095 -263.022411) (xy 373.472969 -262.967974)
			(xy 373.468898 -262.912352) (xy 369.24742 -262.912352) (xy 369.24742 -272.669762) (xy 369.24759 -272.676494)
			(xy 369.251064 -272.689499) (xy 369.254278 -272.695416) (xy 369.25631 -272.698718) (xy 369.274598 -272.72234)
			(xy 369.277356 -272.725754) (xy 369.283868 -272.731638) (xy 369.287552 -272.734024) (xy 369.294664 -272.738596)
			(xy 369.374333 -272.759677) (xy 369.53172 -272.808611) (xy 369.686535 -272.865161) (xy 369.838408 -272.929191)
			(xy 369.986978 -273.000551) (xy 370.131893 -273.079069) (xy 370.272806 -273.16456) (xy 370.409384 -273.25682)
			(xy 370.541301 -273.355629) (xy 370.668244 -273.460752) (xy 370.78991 -273.57194) (xy 370.90601 -273.688927)
			(xy 371.016268 -273.811437) (xy 371.120421 -273.939176) (xy 371.218223 -274.071842) (xy 371.30944 -274.209118)
			(xy 371.393855 -274.350679) (xy 371.471267 -274.496187) (xy 371.541493 -274.645297) (xy 371.604365 -274.797653)
			(xy 371.659734 -274.952894) (xy 371.707468 -275.110649) (xy 371.747453 -275.270544) (xy 371.779595 -275.432199)
			(xy 371.803817 -275.595229) (xy 371.820061 -275.759245) (xy 371.828289 -275.923859) (xy 371.828481 -276.088678)
			(xy 371.820636 -276.25331) (xy 371.804774 -276.417364) (xy 371.780932 -276.58045) (xy 371.749166 -276.742179)
			(xy 371.709553 -276.902167) (xy 371.662186 -277.060033) (xy 371.607179 -277.215402) (xy 371.544662 -277.367904)
			(xy 371.474783 -277.517177) (xy 371.397709 -277.662865) (xy 371.313624 -277.804621) (xy 371.222727 -277.94211)
			(xy 371.125234 -278.075003) (xy 371.021378 -278.202984) (xy 370.911406 -278.32575) (xy 370.795578 -278.443007)
			(xy 370.674172 -278.554478) (xy 370.547474 -278.659897) (xy 370.415787 -278.759012) (xy 370.279425 -278.85159)
			(xy 370.13871 -278.937408) (xy 369.993979 -279.016264) (xy 369.845575 -279.087969) (xy 369.693852 -279.152353)
			(xy 369.539169 -279.209262) (xy 369.381896 -279.258563) (xy 369.302284 -279.279858) (xy 369.298473 -279.28088)
			(xy 369.291203 -279.283946) (xy 369.287806 -279.285954) (xy 369.280186 -279.291034) (xy 369.258342 -279.318974)
			(xy 369.254532 -279.324562) (xy 369.254278 -279.324816) (xy 369.251106 -279.330751) (xy 369.247623 -279.343744)
			(xy 369.24742 -279.35047) (xy 369.24742 -279.931114) (xy 374.111518 -279.931114) (xy 374.115589 -279.875492)
			(xy 374.127715 -279.821055) (xy 374.147638 -279.768964) (xy 374.174934 -279.720329) (xy 374.20902 -279.676186)
			(xy 374.249169 -279.637477) (xy 374.294527 -279.605026) (xy 374.344127 -279.579525) (xy 374.396911 -279.561518)
			(xy 374.451754 -279.551388) (xy 374.507488 -279.549351) (xy 374.562925 -279.555451) (xy 374.616882 -279.569557)
			(xy 374.668211 -279.591369) (xy 374.715817 -279.620423) (xy 374.758685 -279.656098) (xy 374.795902 -279.697635)
			(xy 374.826675 -279.744148) (xy 374.850347 -279.794645) (xy 374.866415 -279.848052) (xy 374.874535 -279.903228)
			(xy 374.875044 -279.931114) (xy 374.874535 -279.959) (xy 374.866415 -280.014176) (xy 374.850347 -280.067583)
			(xy 374.826675 -280.11808) (xy 374.795902 -280.164593) (xy 374.758685 -280.20613) (xy 374.715817 -280.241805)
			(xy 374.668211 -280.270859) (xy 374.616882 -280.292671) (xy 374.562925 -280.306777) (xy 374.507488 -280.312877)
			(xy 374.451754 -280.31084) (xy 374.396911 -280.30071) (xy 374.344127 -280.282703) (xy 374.294527 -280.257202)
			(xy 374.249169 -280.224751) (xy 374.20902 -280.186042) (xy 374.174934 -280.141899) (xy 374.147638 -280.093264)
			(xy 374.127715 -280.041173) (xy 374.115589 -279.986736) (xy 374.111518 -279.931114) (xy 369.24742 -279.931114)
			(xy 369.24742 -283.131514) (xy 374.111518 -283.131514) (xy 374.115589 -283.075892) (xy 374.127715 -283.021455)
			(xy 374.147638 -282.969364) (xy 374.174934 -282.920729) (xy 374.20902 -282.876586) (xy 374.249169 -282.837877)
			(xy 374.294527 -282.805426) (xy 374.344127 -282.779925) (xy 374.396911 -282.761918) (xy 374.451754 -282.751788)
			(xy 374.507488 -282.749751) (xy 374.562925 -282.755851) (xy 374.616882 -282.769957) (xy 374.668211 -282.791769)
			(xy 374.715817 -282.820823) (xy 374.758685 -282.856498) (xy 374.795902 -282.898035) (xy 374.826675 -282.944548)
			(xy 374.850347 -282.995045) (xy 374.866415 -283.048452) (xy 374.874535 -283.103628) (xy 374.875044 -283.131514)
			(xy 374.874535 -283.1594) (xy 374.866415 -283.214576) (xy 374.850347 -283.267983) (xy 374.826675 -283.31848)
			(xy 374.795902 -283.364993) (xy 374.758685 -283.40653) (xy 374.715817 -283.442205) (xy 374.668211 -283.471259)
			(xy 374.616882 -283.493071) (xy 374.562925 -283.507177) (xy 374.507488 -283.513277) (xy 374.451754 -283.51124)
			(xy 374.396911 -283.50111) (xy 374.344127 -283.483103) (xy 374.294527 -283.457602) (xy 374.249169 -283.425151)
			(xy 374.20902 -283.386442) (xy 374.174934 -283.342299) (xy 374.147638 -283.293664) (xy 374.127715 -283.241573)
			(xy 374.115589 -283.187136) (xy 374.111518 -283.131514) (xy 369.24742 -283.131514) (xy 369.24742 -284.138116)
			(xy 373.346978 -284.138116) (xy 373.351049 -284.082494) (xy 373.363175 -284.028057) (xy 373.383098 -283.975966)
			(xy 373.410394 -283.927331) (xy 373.44448 -283.883188) (xy 373.484629 -283.844479) (xy 373.529987 -283.812028)
			(xy 373.579587 -283.786527) (xy 373.632371 -283.76852) (xy 373.687214 -283.75839) (xy 373.742948 -283.756353)
			(xy 373.798385 -283.762453) (xy 373.852342 -283.776559) (xy 373.903671 -283.798371) (xy 373.951277 -283.827425)
			(xy 373.994145 -283.8631) (xy 374.031362 -283.904637) (xy 374.062135 -283.95115) (xy 374.085807 -284.001647)
			(xy 374.101875 -284.055054) (xy 374.109995 -284.11023) (xy 374.110504 -284.138116) (xy 374.109995 -284.166002)
			(xy 374.101875 -284.221178) (xy 374.085807 -284.274585) (xy 374.062135 -284.325082) (xy 374.031362 -284.371595)
			(xy 373.994145 -284.413132) (xy 373.951277 -284.448807) (xy 373.903671 -284.477861) (xy 373.852342 -284.499673)
			(xy 373.798385 -284.513779) (xy 373.742948 -284.519879) (xy 373.687214 -284.517842) (xy 373.632371 -284.507712)
			(xy 373.579587 -284.489705) (xy 373.529987 -284.464204) (xy 373.484629 -284.431753) (xy 373.44448 -284.393044)
			(xy 373.410394 -284.348901) (xy 373.383098 -284.300266) (xy 373.363175 -284.248175) (xy 373.351049 -284.193738)
			(xy 373.346978 -284.138116) (xy 369.24742 -284.138116) (xy 369.24742 -286.331914) (xy 374.111518 -286.331914)
			(xy 374.115589 -286.276292) (xy 374.127715 -286.221855) (xy 374.147638 -286.169764) (xy 374.174934 -286.121129)
			(xy 374.20902 -286.076986) (xy 374.249169 -286.038277) (xy 374.294527 -286.005826) (xy 374.344127 -285.980325)
			(xy 374.396911 -285.962318) (xy 374.451754 -285.952188) (xy 374.507488 -285.950151) (xy 374.562925 -285.956251)
			(xy 374.616882 -285.970357) (xy 374.668211 -285.992169) (xy 374.715817 -286.021223) (xy 374.758685 -286.056898)
			(xy 374.795902 -286.098435) (xy 374.826675 -286.144948) (xy 374.850347 -286.195445) (xy 374.866415 -286.248852)
			(xy 374.874535 -286.304028) (xy 374.875044 -286.331914) (xy 374.874535 -286.3598) (xy 374.866415 -286.414976)
			(xy 374.850347 -286.468383) (xy 374.826675 -286.51888) (xy 374.795902 -286.565393) (xy 374.758685 -286.60693)
			(xy 374.715817 -286.642605) (xy 374.668211 -286.671659) (xy 374.616882 -286.693471) (xy 374.562925 -286.707577)
			(xy 374.507488 -286.713677) (xy 374.451754 -286.71164) (xy 374.396911 -286.70151) (xy 374.344127 -286.683503)
			(xy 374.294527 -286.658002) (xy 374.249169 -286.625551) (xy 374.20902 -286.586842) (xy 374.174934 -286.542699)
			(xy 374.147638 -286.494064) (xy 374.127715 -286.441973) (xy 374.115589 -286.387536) (xy 374.111518 -286.331914)
			(xy 369.24742 -286.331914) (xy 369.24742 -289.532314) (xy 374.111518 -289.532314) (xy 374.115589 -289.476692)
			(xy 374.127715 -289.422255) (xy 374.147638 -289.370164) (xy 374.174934 -289.321529) (xy 374.20902 -289.277386)
			(xy 374.249169 -289.238677) (xy 374.294527 -289.206226) (xy 374.344127 -289.180725) (xy 374.396911 -289.162718)
			(xy 374.451754 -289.152588) (xy 374.507488 -289.150551) (xy 374.562925 -289.156651) (xy 374.616882 -289.170757)
			(xy 374.668211 -289.192569) (xy 374.715817 -289.221623) (xy 374.758685 -289.257298) (xy 374.795902 -289.298835)
			(xy 374.826675 -289.345348) (xy 374.850347 -289.395845) (xy 374.866415 -289.449252) (xy 374.874535 -289.504428)
			(xy 374.875044 -289.532314) (xy 374.874535 -289.5602) (xy 374.866415 -289.615376) (xy 374.850347 -289.668783)
			(xy 374.826675 -289.71928) (xy 374.795902 -289.765793) (xy 374.758685 -289.80733) (xy 374.715817 -289.843005)
			(xy 374.668211 -289.872059) (xy 374.616882 -289.893871) (xy 374.562925 -289.907977) (xy 374.507488 -289.914077)
			(xy 374.451754 -289.91204) (xy 374.396911 -289.90191) (xy 374.344127 -289.883903) (xy 374.294527 -289.858402)
			(xy 374.249169 -289.825951) (xy 374.20902 -289.787242) (xy 374.174934 -289.743099) (xy 374.147638 -289.694464)
			(xy 374.127715 -289.642373) (xy 374.115589 -289.587936) (xy 374.111518 -289.532314) (xy 369.24742 -289.532314)
			(xy 369.24742 -292.732714) (xy 374.111518 -292.732714) (xy 374.115589 -292.677092) (xy 374.127715 -292.622655)
			(xy 374.147638 -292.570564) (xy 374.174934 -292.521929) (xy 374.20902 -292.477786) (xy 374.249169 -292.439077)
			(xy 374.294527 -292.406626) (xy 374.344127 -292.381125) (xy 374.396911 -292.363118) (xy 374.451754 -292.352988)
			(xy 374.507488 -292.350951) (xy 374.562925 -292.357051) (xy 374.616882 -292.371157) (xy 374.668211 -292.392969)
			(xy 374.715817 -292.422023) (xy 374.758685 -292.457698) (xy 374.795902 -292.499235) (xy 374.826675 -292.545748)
			(xy 374.850347 -292.596245) (xy 374.866415 -292.649652) (xy 374.874535 -292.704828) (xy 374.875044 -292.732714)
			(xy 374.874535 -292.7606) (xy 374.866415 -292.815776) (xy 374.850347 -292.869183) (xy 374.826675 -292.91968)
			(xy 374.795902 -292.966193) (xy 374.758685 -293.00773) (xy 374.715817 -293.043405) (xy 374.668211 -293.072459)
			(xy 374.616882 -293.094271) (xy 374.562925 -293.108377) (xy 374.507488 -293.114477) (xy 374.451754 -293.11244)
			(xy 374.396911 -293.10231) (xy 374.344127 -293.084303) (xy 374.294527 -293.058802) (xy 374.249169 -293.026351)
			(xy 374.20902 -292.987642) (xy 374.174934 -292.943499) (xy 374.147638 -292.894864) (xy 374.127715 -292.842773)
			(xy 374.115589 -292.788336) (xy 374.111518 -292.732714) (xy 369.24742 -292.732714) (xy 369.24742 -295.933114)
			(xy 374.111518 -295.933114) (xy 374.115589 -295.877492) (xy 374.127715 -295.823055) (xy 374.147638 -295.770964)
			(xy 374.174934 -295.722329) (xy 374.20902 -295.678186) (xy 374.249169 -295.639477) (xy 374.294527 -295.607026)
			(xy 374.344127 -295.581525) (xy 374.396911 -295.563518) (xy 374.451754 -295.553388) (xy 374.507488 -295.551351)
			(xy 374.562925 -295.557451) (xy 374.616882 -295.571557) (xy 374.668211 -295.593369) (xy 374.715817 -295.622423)
			(xy 374.758685 -295.658098) (xy 374.795902 -295.699635) (xy 374.826675 -295.746148) (xy 374.850347 -295.796645)
			(xy 374.866415 -295.850052) (xy 374.874535 -295.905228) (xy 374.875044 -295.933114) (xy 374.874535 -295.961)
			(xy 374.866415 -296.016176) (xy 374.850347 -296.069583) (xy 374.826675 -296.12008) (xy 374.795902 -296.166593)
			(xy 374.758685 -296.20813) (xy 374.715817 -296.243805) (xy 374.668211 -296.272859) (xy 374.616882 -296.294671)
			(xy 374.562925 -296.308777) (xy 374.507488 -296.314877) (xy 374.451754 -296.31284) (xy 374.396911 -296.30271)
			(xy 374.344127 -296.284703) (xy 374.294527 -296.259202) (xy 374.249169 -296.226751) (xy 374.20902 -296.188042)
			(xy 374.174934 -296.143899) (xy 374.147638 -296.095264) (xy 374.127715 -296.043173) (xy 374.115589 -295.988736)
			(xy 374.111518 -295.933114) (xy 369.24742 -295.933114) (xy 369.24742 -299.133514) (xy 374.111518 -299.133514)
			(xy 374.115589 -299.077892) (xy 374.127715 -299.023455) (xy 374.147638 -298.971364) (xy 374.174934 -298.922729)
			(xy 374.20902 -298.878586) (xy 374.249169 -298.839877) (xy 374.294527 -298.807426) (xy 374.344127 -298.781925)
			(xy 374.396911 -298.763918) (xy 374.451754 -298.753788) (xy 374.507488 -298.751751) (xy 374.562925 -298.757851)
			(xy 374.616882 -298.771957) (xy 374.668211 -298.793769) (xy 374.715817 -298.822823) (xy 374.758685 -298.858498)
			(xy 374.795902 -298.900035) (xy 374.826675 -298.946548) (xy 374.850347 -298.997045) (xy 374.866415 -299.050452)
			(xy 374.874535 -299.105628) (xy 374.875044 -299.133514) (xy 374.874535 -299.1614) (xy 374.866415 -299.216576)
			(xy 374.850347 -299.269983) (xy 374.826675 -299.32048) (xy 374.795902 -299.366993) (xy 374.758685 -299.40853)
			(xy 374.715817 -299.444205) (xy 374.668211 -299.473259) (xy 374.616882 -299.495071) (xy 374.562925 -299.509177)
			(xy 374.507488 -299.515277) (xy 374.451754 -299.51324) (xy 374.396911 -299.50311) (xy 374.344127 -299.485103)
			(xy 374.294527 -299.459602) (xy 374.249169 -299.427151) (xy 374.20902 -299.388442) (xy 374.174934 -299.344299)
			(xy 374.147638 -299.295664) (xy 374.127715 -299.243573) (xy 374.115589 -299.189136) (xy 374.111518 -299.133514)
			(xy 369.24742 -299.133514) (xy 369.24742 -300.813724) (xy 369.247848 -300.823792) (xy 369.255571 -300.842388)
			(xy 369.262406 -300.849792) (xy 369.9129 -301.500286) (xy 369.913408 -301.500794) (xy 369.920789 -301.507379)
			(xy 369.939087 -301.514839) (xy 369.948968 -301.515272)
		)
		(stroke
			(width 0)
			(type solid)
		)
		(fill yes)
		(layer "In11.Cu")
		(net "P1V8_PLL0_PEX3")
	)
	(gr_poly
		(pts
			(xy 49.57572 -219.34805) (xy 49.585549 -219.347831) (xy 49.603926 -219.340895) (xy 49.618366 -219.327579)
			(xy 49.626765 -219.309822) (xy 49.62779 -219.300044) (xy 51.942746 -176.611534) (xy 51.942915 -176.60215)
			(xy 51.937154 -176.5843) (xy 51.925321 -176.569746) (xy 51.917346 -176.564798) (xy 51.825652 -176.512474)
			(xy 51.797204 -176.51349) (xy 51.785012 -176.521364) (xy 51.761425 -176.536491) (xy 51.710754 -176.560409)
			(xy 51.657127 -176.57665) (xy 51.6017 -176.584865) (xy 51.573684 -176.585372) (xy 51.567842 -176.585372)
			(xy 51.557428 -176.585118) (xy 51.53914 -176.592484) (xy 51.472846 -176.656492) (xy 51.464972 -176.674526)
			(xy 51.464718 -176.68494) (xy 51.463737 -176.711847) (xy 51.455143 -176.764998) (xy 51.43916 -176.816412)
			(xy 51.416107 -176.865069) (xy 51.386442 -176.910001) (xy 51.350754 -176.950315) (xy 51.309752 -176.985211)
			(xy 51.264251 -177.013996) (xy 51.215155 -177.036096) (xy 51.163439 -177.051074) (xy 51.110131 -177.058632)
			(xy 51.08321 -177.059082) (xy 51.055959 -177.058619) (xy 51.00201 -177.050864) (xy 50.949715 -177.03551)
			(xy 50.900137 -177.01287) (xy 50.854285 -176.983404) (xy 50.813094 -176.947713) (xy 50.777402 -176.906523)
			(xy 50.747935 -176.860672) (xy 50.725293 -176.811095) (xy 50.709938 -176.7588) (xy 50.702181 -176.704851)
			(xy 50.702181 -176.650349) (xy 50.709938 -176.5964) (xy 50.725293 -176.544105) (xy 50.747935 -176.494528)
			(xy 50.777402 -176.448677) (xy 50.813094 -176.407487) (xy 50.854285 -176.371796) (xy 50.900137 -176.34233)
			(xy 50.949715 -176.31969) (xy 51.00201 -176.304336) (xy 51.055959 -176.296581) (xy 51.08321 -176.296066)
			(xy 51.089052 -176.296066) (xy 51.099466 -176.29632) (xy 51.117754 -176.288954) (xy 51.184048 -176.224946)
			(xy 51.191922 -176.206912) (xy 51.192176 -176.196498) (xy 51.193154 -176.169589) (xy 51.201744 -176.116434)
			(xy 51.217724 -176.065015) (xy 51.240774 -176.016353) (xy 51.270438 -175.971416) (xy 51.306126 -175.931097)
			(xy 51.347129 -175.896196) (xy 51.392632 -175.867407) (xy 51.441731 -175.845303) (xy 51.49345 -175.830323)
			(xy 51.546761 -175.822763) (xy 51.573684 -175.822356) (xy 51.600216 -175.822837) (xy 51.652764 -175.830234)
			(xy 51.703782 -175.844832) (xy 51.752288 -175.86635) (xy 51.79735 -175.894374) (xy 51.818032 -175.911002)
			(xy 51.829462 -175.9204) (xy 51.857656 -175.924464) (xy 51.954176 -175.8823) (xy 51.962617 -175.878128)
			(xy 51.975977 -175.864882) (xy 51.983696 -175.847726) (xy 51.984656 -175.838358) (xy 52.284122 -170.317922)
			(xy 52.2605 -170.288204) (xy 52.241196 -170.284648) (xy 52.215135 -170.279475) (xy 52.164666 -170.262869)
			(xy 52.116989 -170.239421) (xy 52.073027 -170.209585) (xy 52.03363 -170.173937) (xy 51.99956 -170.133167)
			(xy 51.971477 -170.088064) (xy 51.949924 -170.039502) (xy 51.935317 -169.988418) (xy 51.92794 -169.935801)
			(xy 51.927506 -169.909236) (xy 51.928018 -169.880593) (xy 51.93658 -169.823951) (xy 51.953517 -169.769227)
			(xy 51.978448 -169.717651) (xy 52.010812 -169.670384) (xy 52.049881 -169.628489) (xy 52.094777 -169.592908)
			(xy 52.144489 -169.564441) (xy 52.197899 -169.54373) (xy 52.253806 -169.531239) (xy 52.282344 -169.528744)
			(xy 52.301648 -169.52722) (xy 52.328318 -169.500042) (xy 52.893976 -159.070802) (xy 52.889404 -159.0548)
			(xy 52.88407 -159.047434) (xy 52.8674 -159.023071) (xy 52.840986 -158.97028) (xy 52.823033 -158.914046)
			(xy 52.813971 -158.855716) (xy 52.813458 -158.8262) (xy 52.813957 -158.798432) (xy 52.822003 -158.743481)
			(xy 52.837924 -158.690275) (xy 52.861384 -158.639937) (xy 52.89189 -158.593529) (xy 52.909978 -158.572454)
			(xy 52.91582 -158.56585) (xy 52.92217 -158.550356) (xy 52.93614 -158.291784) (xy 52.91328 -158.262066)
			(xy 52.894484 -158.258256) (xy 52.866019 -158.252017) (xy 52.81127 -158.232064) (xy 52.760192 -158.204017)
			(xy 52.713974 -158.168528) (xy 52.673689 -158.126425) (xy 52.640275 -158.078685) (xy 52.61451 -158.026419)
			(xy 52.596992 -157.970843) (xy 52.588128 -157.91325) (xy 52.587652 -157.884114) (xy 52.588165 -157.855829)
			(xy 52.596517 -157.799879) (xy 52.613042 -157.745776) (xy 52.637375 -157.694707) (xy 52.668984 -157.647792)
			(xy 52.707176 -157.606059) (xy 52.751112 -157.570425) (xy 52.799829 -157.54167) (xy 52.852258 -157.520426)
			(xy 52.90725 -157.507158) (xy 52.935378 -157.50413) (xy 52.954428 -157.502352) (xy 52.98059 -157.475428)
			(xy 53.0098 -156.935424) (xy 52.991766 -156.907738) (xy 52.976018 -156.901896) (xy 52.949124 -156.891232)
			(xy 52.898648 -156.862965) (xy 52.853014 -156.827407) (xy 52.813265 -156.785372) (xy 52.780313 -156.737822)
			(xy 52.75491 -156.685845) (xy 52.737639 -156.630631) (xy 52.728894 -156.573444) (xy 52.728368 -156.544518)
			(xy 52.728446 -156.53178) (xy 52.730098 -156.506359) (xy 52.73167 -156.493718) (xy 52.735955 -156.465708)
			(xy 52.751717 -156.411283) (xy 52.775348 -156.359784) (xy 52.806327 -156.31234) (xy 52.843976 -156.269995)
			(xy 52.887468 -156.233676) (xy 52.935848 -156.204182) (xy 52.988055 -156.182159) (xy 53.015388 -156.174694)
			(xy 53.031644 -156.17063) (xy 53.052726 -156.144976) (xy 53.09489 -155.366466) (xy 53.071522 -155.336494)
			(xy 53.05298 -155.332938) (xy 53.027254 -155.327448) (xy 52.977511 -155.31034) (xy 52.930587 -155.286564)
			(xy 52.887372 -155.256571) (xy 52.848684 -155.220929) (xy 52.815257 -155.180313) (xy 52.787722 -155.135492)
			(xy 52.766601 -155.087315) (xy 52.752295 -155.036695) (xy 52.745075 -154.98459) (xy 52.744624 -154.958288)
			(xy 52.745151 -154.929926) (xy 52.753563 -154.87383) (xy 52.770184 -154.819596) (xy 52.794648 -154.76842)
			(xy 52.826418 -154.721427) (xy 52.864792 -154.679655) (xy 52.908926 -154.644021) (xy 52.957848 -154.615312)
			(xy 53.01048 -154.59416) (xy 53.065663 -154.58103) (xy 53.093874 -154.57805) (xy 53.11267 -154.576526)
			(xy 53.139086 -154.549348) (xy 53.173884 -153.907998) (xy 53.173975 -153.898179) (xy 53.167618 -153.879619)
			(xy 53.154755 -153.864806) (xy 53.146198 -153.859992) (xy 53.11394 -153.843482) (xy 53.084222 -153.846784)
			(xy 53.072538 -153.856182) (xy 53.052044 -153.872242) (xy 53.007529 -153.899251) (xy 52.959758 -153.919962)
			(xy 52.909616 -153.933991) (xy 52.858034 -153.941078) (xy 52.832 -153.941526) (xy 52.804747 -153.94104)
			(xy 52.750797 -153.933283) (xy 52.6985 -153.917927) (xy 52.64892 -153.895285) (xy 52.603068 -153.865818)
			(xy 52.561876 -153.830124) (xy 52.526182 -153.788932) (xy 52.496715 -153.74308) (xy 52.474073 -153.6935)
			(xy 52.458717 -153.641203) (xy 52.45096 -153.587253) (xy 52.45096 -153.532747) (xy 52.458717 -153.478797)
			(xy 52.474073 -153.4265) (xy 52.496715 -153.37692) (xy 52.526182 -153.331068) (xy 52.561876 -153.289876)
			(xy 52.603068 -153.254182) (xy 52.64892 -153.224715) (xy 52.6985 -153.202073) (xy 52.750797 -153.186717)
			(xy 52.804747 -153.17896) (xy 52.832 -153.17851) (xy 52.861584 -153.179067) (xy 52.920044 -153.188202)
			(xy 52.976392 -153.206254) (xy 53.029277 -153.232789) (xy 53.077431 -153.267171) (xy 53.098954 -153.287476)
			(xy 53.109876 -153.298144) (xy 53.139086 -153.30424) (xy 53.177948 -153.288746) (xy 53.186784 -153.284778)
			(xy 53.200849 -153.271484) (xy 53.209009 -153.253935) (xy 53.209952 -153.244296) (xy 53.297582 -151.627332)
			(xy 53.297724 -151.617764) (xy 53.291699 -151.599617) (xy 53.279387 -151.584987) (xy 53.271166 -151.580088)
			(xy 53.237638 -151.5618) (xy 53.231181 -151.55865) (xy 53.217131 -151.555686) (xy 53.209952 -151.555958)
			(xy 53.202786 -151.556677) (xy 53.189253 -151.561582) (xy 53.183282 -151.56561) (xy 53.15887 -151.582648)
			(xy 53.105867 -151.609746) (xy 53.049299 -151.628286) (xy 52.990539 -151.637818) (xy 52.960778 -151.638508)
			(xy 52.953412 -151.638508) (xy 52.926424 -151.637644) (xy 52.873085 -151.629247) (xy 52.821463 -151.613413)
			(xy 52.772591 -151.590457) (xy 52.727444 -151.560838) (xy 52.686924 -151.525148) (xy 52.651843 -151.484102)
			(xy 52.622901 -151.438518) (xy 52.600676 -151.389308) (xy 52.585613 -151.337456) (xy 52.578012 -151.283998)
			(xy 52.577492 -151.257) (xy 52.577978 -151.229749) (xy 52.585734 -151.175801) (xy 52.601089 -151.123506)
			(xy 52.623731 -151.073929) (xy 52.653197 -151.028079) (xy 52.688888 -150.986888) (xy 52.730079 -150.951197)
			(xy 52.775929 -150.921731) (xy 52.825506 -150.899089) (xy 52.877801 -150.883734) (xy 52.931749 -150.875978)
			(xy 52.959 -150.875492) (xy 52.986569 -150.875977) (xy 53.041133 -150.883913) (xy 53.093986 -150.899618)
			(xy 53.144029 -150.922767) (xy 53.19022 -150.952876) (xy 53.211222 -150.970742) (xy 53.222144 -150.980394)
			(xy 53.2511 -150.984966) (xy 53.305202 -150.962106) (xy 53.313809 -150.958025) (xy 53.327429 -150.944726)
			(xy 53.335299 -150.927393) (xy 53.33619 -150.91791) (xy 53.64226 -145.272506) (xy 53.64226 -145.272252)
			(xy 53.761386 -142.719044) (xy 53.760878 -142.709392) (xy 53.759354 -142.698978) (xy 53.74894 -142.681706)
			(xy 53.740558 -142.67561) (xy 53.720026 -142.660167) (xy 53.682899 -142.624654) (xy 53.650874 -142.58448)
			(xy 53.624529 -142.540371) (xy 53.604342 -142.493127) (xy 53.590678 -142.4436) (xy 53.583783 -142.392688)
			(xy 53.583332 -142.367) (xy 53.583804 -142.339609) (xy 53.591635 -142.285388) (xy 53.607135 -142.232844)
			(xy 53.629987 -142.183055) (xy 53.65972 -142.137043) (xy 53.695725 -142.095754) (xy 53.737263 -142.060036)
			(xy 53.760116 -142.044928) (xy 53.76545 -142.041626) (xy 53.773324 -142.033498) (xy 53.78831 -142.008606)
			(xy 53.791317 -142.003141) (xy 53.794911 -141.991201) (xy 53.795422 -141.984984) (xy 53.955696 -138.553698)
			(xy 53.957728 -138.520678) (xy 54.1147 -136.561322) (xy 54.1147 -136.559798) (xy 54.175914 -135.43407)
			(xy 54.175965 -135.423796) (xy 54.168891 -135.404527) (xy 54.162198 -135.396732) (xy 54.130448 -135.362442)
			(xy 54.111144 -135.35406) (xy 54.100222 -135.35406) (xy 54.09692 -135.35406) (xy 54.066951 -135.353592)
			(xy 54.007526 -135.345771) (xy 53.949631 -135.330259) (xy 53.894256 -135.307322) (xy 53.842349 -135.277353)
			(xy 53.794798 -135.240865) (xy 53.752417 -135.198481) (xy 53.715931 -135.150928) (xy 53.685966 -135.099019)
			(xy 53.663032 -135.043642) (xy 53.647524 -134.985746) (xy 53.639706 -134.926321) (xy 53.639212 -134.896352)
			(xy 53.639212 -134.032752) (xy 53.639705 -134.002787) (xy 53.647533 -133.94337) (xy 53.66305 -133.885483)
			(xy 53.685989 -133.830117) (xy 53.715959 -133.778218) (xy 53.752446 -133.730675) (xy 53.794826 -133.688301)
			(xy 53.842375 -133.651821) (xy 53.894278 -133.621859) (xy 53.949648 -133.598928) (xy 54.007537 -133.58342)
			(xy 54.066955 -133.575601) (xy 54.09692 -133.575044) (xy 54.123452 -133.57541) (xy 54.176163 -133.581523)
			(xy 54.202076 -133.587236) (xy 54.229 -133.594348) (xy 54.240176 -133.59765) (xy 54.262782 -133.594094)
			(xy 54.302914 -133.566662) (xy 54.311969 -133.559831) (xy 54.323449 -133.540305) (xy 54.325012 -133.52907)
			(xy 54.448202 -132.05968) (xy 54.440836 -132.03936) (xy 54.432962 -132.031232) (xy 54.412827 -132.00978)
			(xy 54.378733 -131.961834) (xy 54.352402 -131.909223) (xy 54.334459 -131.853193) (xy 54.32933 -131.824222)
			(xy 54.327806 -131.813554) (xy 54.316376 -131.796028) (xy 54.236112 -131.742434) (xy 54.215538 -131.738878)
			(xy 54.20487 -131.741418) (xy 54.169939 -131.749203) (xy 54.098618 -131.755071) (xy 54.062884 -131.753102)
			(xy 54.0512 -131.751832) (xy 54.020789 -131.748289) (xy 53.961228 -131.73411) (xy 53.904089 -131.712117)
			(xy 53.850391 -131.682703) (xy 53.801094 -131.646394) (xy 53.757077 -131.603837) (xy 53.719127 -131.555792)
			(xy 53.687919 -131.503116) (xy 53.664013 -131.446751) (xy 53.647833 -131.387702) (xy 53.63967 -131.327023)
			(xy 53.639212 -131.29641) (xy 53.639212 -130.864864) (xy 53.638958 -130.864864) (xy 53.638958 -130.43281)
			(xy 53.639447 -130.402836) (xy 53.647268 -130.343401) (xy 53.662777 -130.285495) (xy 53.68571 -130.230108)
			(xy 53.715674 -130.178186) (xy 53.752157 -130.130619) (xy 53.794535 -130.088218) (xy 53.842083 -130.05171)
			(xy 53.893989 -130.021718) (xy 53.949364 -129.998756) (xy 54.007262 -129.983215) (xy 54.066693 -129.975363)
			(xy 54.096666 -129.974848) (xy 54.097174 -129.974848) (xy 54.124491 -129.975246) (xy 54.178738 -129.981743)
			(xy 54.205378 -129.987802) (xy 54.215792 -129.990342) (xy 54.23662 -129.986786) (xy 54.31663 -129.933446)
			(xy 54.32806 -129.915666) (xy 54.329838 -129.904998) (xy 54.334762 -129.877194) (xy 54.351727 -129.82334)
			(xy 54.376447 -129.772576) (xy 54.408382 -129.726012) (xy 54.446833 -129.684665) (xy 54.49096 -129.649439)
			(xy 54.539799 -129.621105) (xy 54.592282 -129.600282) (xy 54.619652 -129.59334) (xy 54.635908 -129.589784)
			(xy 54.657244 -129.564892) (xy 55.048912 -124.892562) (xy 55.101236 -124.24029) (xy 55.102506 -124.225812)
			(xy 55.102506 -124.225558) (xy 55.483252 -119.473472) (xy 55.489602 -119.416322) (xy 55.623714 -118.45036)
			(xy 55.624157 -118.446817) (xy 55.624164 -118.439678) (xy 55.623714 -118.436136) (xy 55.622698 -118.429024)
			(xy 55.619904 -118.42242) (xy 55.609566 -118.397999) (xy 55.59498 -118.347015) (xy 55.587595 -118.294502)
			(xy 55.587138 -118.267988) (xy 55.587744 -118.236975) (xy 55.59777 -118.175765) (xy 55.617558 -118.116979)
			(xy 55.646586 -118.062165) (xy 55.664862 -118.037102) (xy 55.676546 -118.021608) (xy 55.68032 -118.016332)
			(xy 55.685345 -118.004377) (xy 55.686452 -117.997986) (xy 55.97906 -115.894104) (xy 55.980085 -115.882078)
			(xy 55.972265 -115.859281) (xy 55.964074 -115.850416) (xy 55.946007 -115.832387) (xy 55.914365 -115.792337)
			(xy 55.888348 -115.748424) (xy 55.86842 -115.701433) (xy 55.854939 -115.652204) (xy 55.848144 -115.601617)
			(xy 55.847742 -115.576096) (xy 55.848284 -115.546713) (xy 55.857297 -115.488644) (xy 55.875109 -115.432643)
			(xy 55.901298 -115.380036) (xy 55.935245 -115.332069) (xy 55.976148 -115.289874) (xy 56.023037 -115.254452)
			(xy 56.048656 -115.240054) (xy 56.059578 -115.234212) (xy 56.073294 -115.2144) (xy 56.434736 -112.61344)
			(xy 56.43499 -112.612678) (xy 56.435498 -112.607598) (xy 56.437784 -112.591088) (xy 57.632092 -103.994712)
			(xy 57.632603 -103.990399) (xy 57.632342 -103.981717) (xy 57.631584 -103.97744) (xy 57.629044 -103.964994)
			(xy 57.627266 -103.960422) (xy 57.618077 -103.937184) (xy 57.605169 -103.888907) (xy 57.598674 -103.839358)
			(xy 57.59831 -103.814372) (xy 57.598731 -103.789024) (xy 57.605448 -103.738775) (xy 57.618749 -103.689854)
			(xy 57.638398 -103.643121) (xy 57.664052 -103.599394) (xy 57.679336 -103.579168) (xy 57.6834 -103.574088)
			(xy 57.691528 -103.555546) (xy 57.695338 -103.542084) (xy 57.75325 -103.12273) (xy 57.744106 -103.0986)
			(xy 57.733946 -103.089964) (xy 57.713099 -103.071753) (xy 57.67637 -103.03034) (xy 57.646016 -102.984052)
			(xy 57.622675 -102.93386) (xy 57.606838 -102.880821) (xy 57.598837 -102.826049) (xy 57.59831 -102.798372)
			(xy 57.598783 -102.771017) (xy 57.606602 -102.716867) (xy 57.622077 -102.664391) (xy 57.64489 -102.614663)
			(xy 57.674573 -102.568704) (xy 57.710516 -102.527457) (xy 57.751983 -102.491767) (xy 57.798124 -102.462368)
			(xy 57.822846 -102.450646) (xy 57.832752 -102.446328) (xy 57.839864 -102.4382) (xy 57.844687 -102.432396)
			(xy 57.851032 -102.418712) (xy 57.85231 -102.411276) (xy 57.882282 -102.19563) (xy 57.883352 -102.184043)
			(xy 57.876172 -102.161934) (xy 57.860008 -102.145228) (xy 57.849262 -102.140766) (xy 57.822075 -102.130275)
			(xy 57.770992 -102.102235) (xy 57.724766 -102.066755) (xy 57.684472 -102.02466) (xy 57.651045 -101.976928)
			(xy 57.625263 -101.92467) (xy 57.607726 -101.869099) (xy 57.598841 -101.811508) (xy 57.59831 -101.782372)
			(xy 57.598822 -101.75378) (xy 57.607361 -101.697238) (xy 57.624243 -101.642604) (xy 57.649091 -101.591102)
			(xy 57.681347 -101.543885) (xy 57.72029 -101.502011) (xy 57.765046 -101.466419) (xy 57.814613 -101.437905)
			(xy 57.86788 -101.417109) (xy 57.923655 -101.404496) (xy 57.952132 -101.40188) (xy 57.970166 -101.40061)
			(xy 57.996328 -101.376226) (xy 58.012584 -101.258878) (xy 58.01358 -101.248826) (xy 58.008484 -101.229297)
			(xy 58.002678 -101.221032) (xy 57.953148 -101.1555) (xy 57.93613 -101.145594) (xy 57.92597 -101.14407)
			(xy 57.899033 -101.139761) (xy 57.846673 -101.124449) (xy 57.797029 -101.101835) (xy 57.751113 -101.07238)
			(xy 57.70986 -101.036685) (xy 57.674112 -100.995478) (xy 57.644599 -100.949599) (xy 57.621921 -100.899984)
			(xy 57.606543 -100.847644) (xy 57.598776 -100.793648) (xy 57.59831 -100.766372) (xy 57.598798 -100.739123)
			(xy 57.606558 -100.685179) (xy 57.621916 -100.632889) (xy 57.644559 -100.583316) (xy 57.674026 -100.537471)
			(xy 57.709718 -100.496285) (xy 57.750907 -100.460598) (xy 57.796757 -100.431137) (xy 57.846332 -100.4085)
			(xy 57.898624 -100.393148) (xy 57.952569 -100.385395) (xy 57.979818 -100.384864) (xy 57.992686 -100.384997)
			(xy 58.018363 -100.386774) (xy 58.031126 -100.38842) (xy 58.041286 -100.38969) (xy 58.060844 -100.38461)
			(xy 58.125868 -100.33508) (xy 58.133519 -100.328641) (xy 58.143574 -100.31138) (xy 58.145426 -100.301552)
			(xy 59.276742 -92.160852) (xy 59.276996 -92.160344) (xy 59.278012 -92.151962) (xy 59.27979 -92.138754)
			(xy 59.336432 -91.730322) (xy 59.337348 -91.720104) (xy 59.33197 -91.700325) (xy 59.326018 -91.691968)
			(xy 59.325256 -91.691206) (xy 59.268614 -91.62415) (xy 59.249564 -91.615006) (xy 59.238388 -91.614752)
			(xy 59.211561 -91.61366) (xy 59.158593 -91.604878) (xy 59.10738 -91.588754) (xy 59.058933 -91.565609)
			(xy 59.014211 -91.535899) (xy 58.974098 -91.500211) (xy 58.939384 -91.459251) (xy 58.910758 -91.413828)
			(xy 58.888783 -91.364839) (xy 58.873895 -91.313254) (xy 58.866388 -91.26009) (xy 58.866024 -91.233244)
			(xy 58.8665 -91.206178) (xy 58.874159 -91.152591) (xy 58.889313 -91.100623) (xy 58.91166 -91.051319)
			(xy 58.940751 -91.005668) (xy 58.976001 -90.964587) (xy 59.016704 -90.9289) (xy 59.062041 -90.899323)
			(xy 59.111104 -90.876451) (xy 59.162906 -90.860742) (xy 59.216409 -90.852512) (xy 59.243468 -90.851736)
			(xy 59.247786 -90.851736) (xy 59.271666 -90.852122) (xy 59.319049 -90.858107) (xy 59.342274 -90.863674)
			(xy 59.342782 -90.863674) (xy 59.353297 -90.865806) (xy 59.37443 -90.862259) (xy 59.383676 -90.856816)
			(xy 59.455558 -90.80881) (xy 59.466988 -90.790268) (xy 59.468512 -90.779346) (xy 59.93892 -87.395812)
			(xy 59.9186 -87.364316) (xy 59.90082 -87.358728) (xy 59.874976 -87.350406) (xy 59.825765 -87.327472)
			(xy 59.780299 -87.297797) (xy 59.739498 -87.261978) (xy 59.704184 -87.220739) (xy 59.67507 -87.174913)
			(xy 59.652743 -87.125423) (xy 59.637654 -87.073269) (xy 59.630108 -87.019503) (xy 59.630257 -86.96521)
			(xy 59.638097 -86.911486) (xy 59.653471 -86.859415) (xy 59.676069 -86.810049) (xy 59.705433 -86.764382)
			(xy 59.740973 -86.723337) (xy 59.78197 -86.687742) (xy 59.804554 -86.672674) (xy 59.827024 -86.658753)
			(xy 59.874997 -86.636557) (xy 59.925572 -86.621184) (xy 59.977782 -86.612928) (xy 60.004198 -86.611968)
			(xy 60.023248 -86.611714) (xy 60.051188 -86.587076) (xy 60.839096 -80.91805) (xy 61.42863 -76.675488)
			(xy 61.43028 -76.666521) (xy 61.438986 -76.650517) (xy 61.452744 -76.638574) (xy 61.469812 -76.632203)
			(xy 61.478922 -76.6318) (xy 61.486288 -76.6318) (xy 61.741558 -74.809858) (xy 61.742583 -74.798978)
			(xy 61.736404 -74.778039) (xy 61.72962 -74.769472) (xy 61.722254 -74.76109) (xy 61.702696 -74.7522)
			(xy 60.605416 -74.7522) (xy 60.595142 -74.752667) (xy 60.576237 -74.760714) (xy 60.561997 -74.775526)
			(xy 60.557918 -74.784966) (xy 58.82259 -79.368396) (xy 58.833258 -79.40167) (xy 58.84799 -79.41183)
			(xy 58.869724 -79.427128) (xy 58.909143 -79.462779) (xy 58.943232 -79.503555) (xy 58.971331 -79.548668)
			(xy 58.992898 -79.597245) (xy 59.007514 -79.648344) (xy 59.014897 -79.700978) (xy 59.015376 -79.727552)
			(xy 59.014916 -79.754806) (xy 59.007164 -79.808761) (xy 58.991812 -79.861062) (xy 58.969172 -79.910647)
			(xy 58.939705 -79.956503) (xy 58.904011 -79.997699) (xy 58.862816 -80.033395) (xy 58.816961 -80.062864)
			(xy 58.767377 -80.085507) (xy 58.715076 -80.100861) (xy 58.661122 -80.108615) (xy 58.633868 -80.10906)
			(xy 58.621643 -80.108975) (xy 58.597241 -80.10745) (xy 58.5851 -80.106012) (xy 58.567574 -80.103726)
			(xy 58.537348 -80.12176) (xy 58.485024 -80.259682) (xy 58.485786 -80.270858) (xy 58.486548 -80.294988)
			(xy 58.486014 -80.325069) (xy 58.476627 -80.384493) (xy 58.458022 -80.441704) (xy 58.43066 -80.495283)
			(xy 58.395221 -80.543897) (xy 58.37428 -80.565498) (xy 58.370216 -80.569308) (xy 58.364628 -80.578198)
			(xy 56.544635 -85.384894) (xy 59.304426 -85.384894) (xy 59.308497 -85.329272) (xy 59.320623 -85.274835)
			(xy 59.340546 -85.222744) (xy 59.367842 -85.174109) (xy 59.401928 -85.129966) (xy 59.442077 -85.091257)
			(xy 59.487435 -85.058806) (xy 59.537035 -85.033305) (xy 59.589819 -85.015298) (xy 59.644662 -85.005168)
			(xy 59.700396 -85.003131) (xy 59.755833 -85.009231) (xy 59.80979 -85.023337) (xy 59.861119 -85.045149)
			(xy 59.908725 -85.074203) (xy 59.951593 -85.109878) (xy 59.98881 -85.151415) (xy 60.019583 -85.197928)
			(xy 60.043255 -85.248425) (xy 60.059323 -85.301832) (xy 60.067443 -85.357008) (xy 60.067952 -85.384894)
			(xy 60.067443 -85.41278) (xy 60.059323 -85.467956) (xy 60.043255 -85.521363) (xy 60.019583 -85.57186)
			(xy 59.98881 -85.618373) (xy 59.951593 -85.65991) (xy 59.908725 -85.695585) (xy 59.861119 -85.724639)
			(xy 59.80979 -85.746451) (xy 59.755833 -85.760557) (xy 59.700396 -85.766657) (xy 59.644662 -85.76462)
			(xy 59.589819 -85.75449) (xy 59.537035 -85.736483) (xy 59.487435 -85.710982) (xy 59.442077 -85.678531)
			(xy 59.401928 -85.639822) (xy 59.367842 -85.595679) (xy 59.340546 -85.547044) (xy 59.320623 -85.494953)
			(xy 59.308497 -85.440516) (xy 59.304426 -85.384894) (xy 56.544635 -85.384894) (xy 52.484274 -96.10852)
			(xy 52.482496 -96.113346) (xy 52.295298 -96.813624) (xy 52.298854 -96.83496) (xy 52.30495 -96.844104)
			(xy 52.31954 -96.866845) (xy 52.342859 -96.915585) (xy 52.359069 -96.967126) (xy 52.367847 -97.020439)
			(xy 52.369017 -97.074456) (xy 52.362555 -97.128099) (xy 52.348592 -97.180294) (xy 52.327405 -97.229997)
			(xy 52.29942 -97.276215) (xy 52.265194 -97.318023) (xy 52.225414 -97.354585) (xy 52.180874 -97.385171)
			(xy 52.156868 -97.39757) (xy 52.147216 -97.402396) (xy 52.133246 -97.41916) (xy 51.843178 -98.503994)
			(xy 51.85283 -98.532696) (xy 51.865276 -98.542348) (xy 51.888077 -98.560529) (xy 51.92841 -98.602644)
			(xy 51.961863 -98.650407) (xy 51.987655 -98.702707) (xy 52.005185 -98.758323) (xy 52.014044 -98.815959)
			(xy 52.014628 -98.845116) (xy 52.014149 -98.872583) (xy 52.006268 -98.926949) (xy 51.990671 -98.979623)
			(xy 51.967681 -99.029515) (xy 51.937773 -99.075595) (xy 51.901566 -99.116908) (xy 51.859807 -99.152602)
			(xy 51.813362 -99.181937) (xy 51.763189 -99.204308) (xy 51.710326 -99.219252) (xy 51.683158 -99.223322)
			(xy 51.667664 -99.225354) (xy 51.644804 -99.24542) (xy 51.395789 -100.17633) (xy 53.639212 -100.17633)
			(xy 53.639212 -99.31273) (xy 53.639702 -99.282762) (xy 53.647525 -99.22334) (xy 53.663038 -99.165447)
			(xy 53.685974 -99.110074) (xy 53.715941 -99.058168) (xy 53.752428 -99.010618) (xy 53.794808 -98.968238)
			(xy 53.842358 -98.931751) (xy 53.894264 -98.901784) (xy 53.949637 -98.878848) (xy 54.00753 -98.863335)
			(xy 54.066952 -98.855512) (xy 54.126888 -98.855512) (xy 54.18631 -98.863335) (xy 54.244203 -98.878848)
			(xy 54.299576 -98.901784) (xy 54.351482 -98.931751) (xy 54.399032 -98.968238) (xy 54.441412 -99.010618)
			(xy 54.477899 -99.058168) (xy 54.507866 -99.110074) (xy 54.530802 -99.165447) (xy 54.546315 -99.22334)
			(xy 54.554138 -99.282762) (xy 54.554628 -99.31273) (xy 54.554628 -100.17633) (xy 54.554138 -100.206298)
			(xy 54.546315 -100.26572) (xy 54.530802 -100.323613) (xy 54.507866 -100.378986) (xy 54.477899 -100.430892)
			(xy 54.441412 -100.478442) (xy 54.399032 -100.520822) (xy 54.351482 -100.557309) (xy 54.299576 -100.587276)
			(xy 54.244203 -100.610212) (xy 54.18631 -100.625725) (xy 54.126888 -100.633548) (xy 54.066952 -100.633548)
			(xy 54.00753 -100.625725) (xy 53.949637 -100.610212) (xy 53.894264 -100.587276) (xy 53.842358 -100.557309)
			(xy 53.794808 -100.520822) (xy 53.752428 -100.478442) (xy 53.715941 -100.430892) (xy 53.685974 -100.378986)
			(xy 53.663038 -100.323613) (xy 53.647525 -100.26572) (xy 53.639702 -100.206298) (xy 53.639212 -100.17633)
			(xy 51.395789 -100.17633) (xy 50.91427 -101.976428) (xy 51.785012 -101.976428) (xy 51.785012 -101.112828)
			(xy 51.785502 -101.08286) (xy 51.793325 -101.023438) (xy 51.808838 -100.965545) (xy 51.831774 -100.910172)
			(xy 51.861741 -100.858266) (xy 51.898228 -100.810716) (xy 51.940608 -100.768336) (xy 51.988158 -100.731849)
			(xy 52.040064 -100.701882) (xy 52.095437 -100.678946) (xy 52.15333 -100.663433) (xy 52.212752 -100.65561)
			(xy 52.272688 -100.65561) (xy 52.33211 -100.663433) (xy 52.390003 -100.678946) (xy 52.445376 -100.701882)
			(xy 52.497282 -100.731849) (xy 52.544832 -100.768336) (xy 52.587212 -100.810716) (xy 52.623699 -100.858266)
			(xy 52.653666 -100.910172) (xy 52.676602 -100.965545) (xy 52.692115 -101.023438) (xy 52.699938 -101.08286)
			(xy 52.700428 -101.112828) (xy 52.700428 -101.976428) (xy 52.699938 -102.006396) (xy 52.692115 -102.065818)
			(xy 52.676602 -102.123711) (xy 52.653666 -102.179084) (xy 52.623699 -102.23099) (xy 52.587212 -102.27854)
			(xy 52.544832 -102.32092) (xy 52.497282 -102.357407) (xy 52.445376 -102.387374) (xy 52.390003 -102.41031)
			(xy 52.33211 -102.425823) (xy 52.272688 -102.433646) (xy 52.212752 -102.433646) (xy 52.15333 -102.425823)
			(xy 52.095437 -102.41031) (xy 52.040064 -102.387374) (xy 51.988158 -102.357407) (xy 51.940608 -102.32092)
			(xy 51.898228 -102.27854) (xy 51.861741 -102.23099) (xy 51.831774 -102.179084) (xy 51.808838 -102.123711)
			(xy 51.793325 -102.065818) (xy 51.785502 -102.006396) (xy 51.785012 -101.976428) (xy 50.91427 -101.976428)
			(xy 50.432818 -103.776272) (xy 53.639212 -103.776272) (xy 53.639212 -102.912672) (xy 53.639702 -102.882704)
			(xy 53.647525 -102.823282) (xy 53.663038 -102.765389) (xy 53.685974 -102.710016) (xy 53.715941 -102.65811)
			(xy 53.752428 -102.61056) (xy 53.794808 -102.56818) (xy 53.842358 -102.531693) (xy 53.894264 -102.501726)
			(xy 53.949637 -102.47879) (xy 54.00753 -102.463277) (xy 54.066952 -102.455454) (xy 54.126888 -102.455454)
			(xy 54.18631 -102.463277) (xy 54.244203 -102.47879) (xy 54.299576 -102.501726) (xy 54.351482 -102.531693)
			(xy 54.399032 -102.56818) (xy 54.441412 -102.61056) (xy 54.477899 -102.65811) (xy 54.507866 -102.710016)
			(xy 54.530802 -102.765389) (xy 54.546315 -102.823282) (xy 54.554138 -102.882704) (xy 54.554628 -102.912672)
			(xy 54.554628 -103.776272) (xy 54.554138 -103.80624) (xy 54.546315 -103.865662) (xy 54.530802 -103.923555)
			(xy 54.507866 -103.978928) (xy 54.477899 -104.030834) (xy 54.441412 -104.078384) (xy 54.399032 -104.120764)
			(xy 54.351482 -104.157251) (xy 54.299576 -104.187218) (xy 54.244203 -104.210154) (xy 54.18631 -104.225667)
			(xy 54.126888 -104.23349) (xy 54.066952 -104.23349) (xy 54.00753 -104.225667) (xy 53.949637 -104.210154)
			(xy 53.894264 -104.187218) (xy 53.842358 -104.157251) (xy 53.794808 -104.120764) (xy 53.752428 -104.078384)
			(xy 53.715941 -104.030834) (xy 53.685974 -103.978928) (xy 53.663038 -103.923555) (xy 53.647525 -103.865662)
			(xy 53.639702 -103.80624) (xy 53.639212 -103.776272) (xy 50.432818 -103.776272) (xy 49.951299 -105.57637)
			(xy 51.785012 -105.57637) (xy 51.785012 -104.71277) (xy 51.785502 -104.682802) (xy 51.793325 -104.62338)
			(xy 51.808838 -104.565487) (xy 51.831774 -104.510114) (xy 51.861741 -104.458208) (xy 51.898228 -104.410658)
			(xy 51.940608 -104.368278) (xy 51.988158 -104.331791) (xy 52.040064 -104.301824) (xy 52.095437 -104.278888)
			(xy 52.15333 -104.263375) (xy 52.212752 -104.255552) (xy 52.272688 -104.255552) (xy 52.33211 -104.263375)
			(xy 52.390003 -104.278888) (xy 52.445376 -104.301824) (xy 52.497282 -104.331791) (xy 52.544832 -104.368278)
			(xy 52.587212 -104.410658) (xy 52.623699 -104.458208) (xy 52.653666 -104.510114) (xy 52.676602 -104.565487)
			(xy 52.692115 -104.62338) (xy 52.699938 -104.682802) (xy 52.700428 -104.71277) (xy 52.700428 -105.57637)
			(xy 52.699938 -105.606338) (xy 52.692115 -105.66576) (xy 52.676602 -105.723653) (xy 52.653666 -105.779026)
			(xy 52.623699 -105.830932) (xy 52.587212 -105.878482) (xy 52.544832 -105.920862) (xy 52.497282 -105.957349)
			(xy 52.445376 -105.987316) (xy 52.390003 -106.010252) (xy 52.33211 -106.025765) (xy 52.272688 -106.033588)
			(xy 52.212752 -106.033588) (xy 52.15333 -106.025765) (xy 52.095437 -106.010252) (xy 52.040064 -105.987316)
			(xy 51.988158 -105.957349) (xy 51.940608 -105.920862) (xy 51.898228 -105.878482) (xy 51.861741 -105.830932)
			(xy 51.831774 -105.779026) (xy 51.808838 -105.723653) (xy 51.793325 -105.66576) (xy 51.785502 -105.606338)
			(xy 51.785012 -105.57637) (xy 49.951299 -105.57637) (xy 49.56429 -107.023154) (xy 49.57953 -107.056174)
			(xy 49.59604 -107.064302) (xy 49.61981 -107.076405) (xy 49.664038 -107.106222) (xy 49.703686 -107.141902)
			(xy 49.737984 -107.182753) (xy 49.766263 -107.227979) (xy 49.787974 -107.2767) (xy 49.802694 -107.327969)
			(xy 49.809492 -107.376214) (xy 53.639212 -107.376214) (xy 53.639212 -106.512614) (xy 53.639702 -106.482646)
			(xy 53.647525 -106.423224) (xy 53.663038 -106.365331) (xy 53.685974 -106.309958) (xy 53.715941 -106.258052)
			(xy 53.752428 -106.210502) (xy 53.794808 -106.168122) (xy 53.842358 -106.131635) (xy 53.894264 -106.101668)
			(xy 53.949637 -106.078732) (xy 54.00753 -106.063219) (xy 54.066952 -106.055396) (xy 54.126888 -106.055396)
			(xy 54.18631 -106.063219) (xy 54.244203 -106.078732) (xy 54.299576 -106.101668) (xy 54.351482 -106.131635)
			(xy 54.399032 -106.168122) (xy 54.441412 -106.210502) (xy 54.477899 -106.258052) (xy 54.507866 -106.309958)
			(xy 54.530802 -106.365331) (xy 54.546315 -106.423224) (xy 54.554138 -106.482646) (xy 54.554628 -106.512614)
			(xy 54.554628 -107.376214) (xy 54.554138 -107.406182) (xy 54.546315 -107.465604) (xy 54.530802 -107.523497)
			(xy 54.507866 -107.57887) (xy 54.477899 -107.630776) (xy 54.441412 -107.678326) (xy 54.399032 -107.720706)
			(xy 54.351482 -107.757193) (xy 54.299576 -107.78716) (xy 54.244203 -107.810096) (xy 54.18631 -107.825609)
			(xy 54.126888 -107.833432) (xy 54.066952 -107.833432) (xy 54.00753 -107.825609) (xy 53.949637 -107.810096)
			(xy 53.894264 -107.78716) (xy 53.842358 -107.757193) (xy 53.794808 -107.720706) (xy 53.752428 -107.678326)
			(xy 53.715941 -107.630776) (xy 53.685974 -107.57887) (xy 53.663038 -107.523497) (xy 53.647525 -107.465604)
			(xy 53.639702 -107.406182) (xy 53.639212 -107.376214) (xy 49.809492 -107.376214) (xy 49.810136 -107.380786)
			(xy 49.81067 -107.407456) (xy 49.81021 -107.43471) (xy 49.802458 -107.488664) (xy 49.787105 -107.540965)
			(xy 49.764464 -107.590548) (xy 49.734997 -107.636404) (xy 49.699303 -107.677599) (xy 49.658109 -107.713293)
			(xy 49.612253 -107.742762) (xy 49.56267 -107.765403) (xy 49.510369 -107.780756) (xy 49.456416 -107.788509)
			(xy 49.429162 -107.788964) (xy 49.4284 -107.788964) (xy 49.402238 -107.787948) (xy 49.383696 -107.786678)
			(xy 49.354486 -107.80776) (xy 48.988314 -109.176312) (xy 51.785012 -109.176312) (xy 51.785012 -108.312712)
			(xy 51.785502 -108.282744) (xy 51.793325 -108.223322) (xy 51.808838 -108.165429) (xy 51.831774 -108.110056)
			(xy 51.861741 -108.05815) (xy 51.898228 -108.0106) (xy 51.940608 -107.96822) (xy 51.988158 -107.931733)
			(xy 52.040064 -107.901766) (xy 52.095437 -107.87883) (xy 52.15333 -107.863317) (xy 52.212752 -107.855494)
			(xy 52.272688 -107.855494) (xy 52.33211 -107.863317) (xy 52.390003 -107.87883) (xy 52.445376 -107.901766)
			(xy 52.497282 -107.931733) (xy 52.544832 -107.96822) (xy 52.587212 -108.0106) (xy 52.623699 -108.05815)
			(xy 52.653666 -108.110056) (xy 52.676602 -108.165429) (xy 52.692115 -108.223322) (xy 52.699938 -108.282744)
			(xy 52.700428 -108.312712) (xy 52.700428 -109.176312) (xy 52.699938 -109.20628) (xy 52.692115 -109.265702)
			(xy 52.676602 -109.323595) (xy 52.653666 -109.378968) (xy 52.623699 -109.430874) (xy 52.587212 -109.478424)
			(xy 52.544832 -109.520804) (xy 52.497282 -109.557291) (xy 52.445376 -109.587258) (xy 52.390003 -109.610194)
			(xy 52.33211 -109.625707) (xy 52.272688 -109.63353) (xy 52.212752 -109.63353) (xy 52.15333 -109.625707)
			(xy 52.095437 -109.610194) (xy 52.040064 -109.587258) (xy 51.988158 -109.557291) (xy 51.940608 -109.520804)
			(xy 51.898228 -109.478424) (xy 51.861741 -109.430874) (xy 51.831774 -109.378968) (xy 51.808838 -109.323595)
			(xy 51.793325 -109.265702) (xy 51.785502 -109.20628) (xy 51.785012 -109.176312) (xy 48.988314 -109.176312)
			(xy 48.706278 -110.230412) (xy 48.706278 -110.230666) (xy 48.51242 -110.97641) (xy 53.639212 -110.97641)
			(xy 53.639212 -110.11281) (xy 53.639702 -110.082842) (xy 53.647525 -110.02342) (xy 53.663038 -109.965527)
			(xy 53.685974 -109.910154) (xy 53.715941 -109.858248) (xy 53.752428 -109.810698) (xy 53.794808 -109.768318)
			(xy 53.842358 -109.731831) (xy 53.894264 -109.701864) (xy 53.949637 -109.678928) (xy 54.00753 -109.663415)
			(xy 54.066952 -109.655592) (xy 54.126888 -109.655592) (xy 54.18631 -109.663415) (xy 54.244203 -109.678928)
			(xy 54.299576 -109.701864) (xy 54.351482 -109.731831) (xy 54.399032 -109.768318) (xy 54.441412 -109.810698)
			(xy 54.477899 -109.858248) (xy 54.507866 -109.910154) (xy 54.530802 -109.965527) (xy 54.546315 -110.02342)
			(xy 54.554138 -110.082842) (xy 54.554628 -110.11281) (xy 54.554628 -110.97641) (xy 54.554138 -111.006378)
			(xy 54.546315 -111.0658) (xy 54.530802 -111.123693) (xy 54.507866 -111.179066) (xy 54.477899 -111.230972)
			(xy 54.441412 -111.278522) (xy 54.399032 -111.320902) (xy 54.351482 -111.357389) (xy 54.299576 -111.387356)
			(xy 54.244203 -111.410292) (xy 54.18631 -111.425805) (xy 54.126888 -111.433628) (xy 54.066952 -111.433628)
			(xy 54.00753 -111.425805) (xy 53.949637 -111.410292) (xy 53.894264 -111.387356) (xy 53.842358 -111.357389)
			(xy 53.794808 -111.320902) (xy 53.752428 -111.278522) (xy 53.715941 -111.230972) (xy 53.685974 -111.179066)
			(xy 53.663038 -111.123693) (xy 53.647525 -111.0658) (xy 53.639702 -111.006378) (xy 53.639212 -110.97641)
			(xy 48.51242 -110.97641) (xy 48.04448 -112.776508) (xy 51.785012 -112.776508) (xy 51.785012 -111.912908)
			(xy 51.785502 -111.88294) (xy 51.793325 -111.823518) (xy 51.808838 -111.765625) (xy 51.831774 -111.710252)
			(xy 51.861741 -111.658346) (xy 51.898228 -111.610796) (xy 51.940608 -111.568416) (xy 51.988158 -111.531929)
			(xy 52.040064 -111.501962) (xy 52.095437 -111.479026) (xy 52.15333 -111.463513) (xy 52.212752 -111.45569)
			(xy 52.272688 -111.45569) (xy 52.33211 -111.463513) (xy 52.390003 -111.479026) (xy 52.445376 -111.501962)
			(xy 52.497282 -111.531929) (xy 52.544832 -111.568416) (xy 52.587212 -111.610796) (xy 52.623699 -111.658346)
			(xy 52.653666 -111.710252) (xy 52.676602 -111.765625) (xy 52.692115 -111.823518) (xy 52.699938 -111.88294)
			(xy 52.700428 -111.912908) (xy 52.700428 -112.776508) (xy 52.699938 -112.806476) (xy 52.692115 -112.865898)
			(xy 52.676602 -112.923791) (xy 52.653666 -112.979164) (xy 52.623699 -113.03107) (xy 52.587212 -113.07862)
			(xy 52.544832 -113.121) (xy 52.497282 -113.157487) (xy 52.445376 -113.187454) (xy 52.390003 -113.21039)
			(xy 52.33211 -113.225903) (xy 52.272688 -113.233726) (xy 52.212752 -113.233726) (xy 52.15333 -113.225903)
			(xy 52.095437 -113.21039) (xy 52.040064 -113.187454) (xy 51.988158 -113.157487) (xy 51.940608 -113.121)
			(xy 51.898228 -113.07862) (xy 51.861741 -113.03107) (xy 51.831774 -112.979164) (xy 51.808838 -112.923791)
			(xy 51.793325 -112.865898) (xy 51.785502 -112.806476) (xy 51.785012 -112.776508) (xy 48.04448 -112.776508)
			(xy 47.210218 -115.985798) (xy 47.20844 -115.992656) (xy 47.229268 -118.413276) (xy 47.240698 -118.434612)
			(xy 47.251112 -118.441978) (xy 47.272372 -118.457335) (xy 47.310875 -118.492944) (xy 47.344139 -118.53349)
			(xy 47.371539 -118.578209) (xy 47.392556 -118.626259) (xy 47.406796 -118.676734) (xy 47.413991 -118.728683)
			(xy 47.414434 -118.754906) (xy 47.413884 -118.78405) (xy 47.405026 -118.841662) (xy 47.387517 -118.897258)
			(xy 47.361764 -118.949549) (xy 47.328365 -118.997319) (xy 47.288095 -119.03946) (xy 47.265336 -119.057674)
			(xy 47.260764 -119.06123) (xy 47.253652 -119.069612) (xy 47.240952 -119.09425) (xy 47.238328 -119.099797)
			(xy 47.235508 -119.111737) (xy 47.235364 -119.117872) (xy 47.243592 -120.086374) (xy 53.639212 -120.086374)
			(xy 53.639212 -119.222774) (xy 53.639702 -119.192806) (xy 53.647525 -119.133384) (xy 53.663038 -119.075491)
			(xy 53.685974 -119.020118) (xy 53.715941 -118.968212) (xy 53.752428 -118.920662) (xy 53.794808 -118.878282)
			(xy 53.842358 -118.841795) (xy 53.894264 -118.811828) (xy 53.949637 -118.788892) (xy 54.00753 -118.773379)
			(xy 54.066952 -118.765556) (xy 54.126888 -118.765556) (xy 54.18631 -118.773379) (xy 54.244203 -118.788892)
			(xy 54.299576 -118.811828) (xy 54.351482 -118.841795) (xy 54.399032 -118.878282) (xy 54.441412 -118.920662)
			(xy 54.477899 -118.968212) (xy 54.507866 -119.020118) (xy 54.530802 -119.075491) (xy 54.546315 -119.133384)
			(xy 54.554138 -119.192806) (xy 54.554628 -119.222774) (xy 54.554628 -120.086374) (xy 54.554138 -120.116342)
			(xy 54.546315 -120.175764) (xy 54.530802 -120.233657) (xy 54.507866 -120.28903) (xy 54.477899 -120.340936)
			(xy 54.441412 -120.388486) (xy 54.399032 -120.430866) (xy 54.351482 -120.467353) (xy 54.299576 -120.49732)
			(xy 54.244203 -120.520256) (xy 54.18631 -120.535769) (xy 54.126888 -120.543592) (xy 54.066952 -120.543592)
			(xy 54.00753 -120.535769) (xy 53.949637 -120.520256) (xy 53.894264 -120.49732) (xy 53.842358 -120.467353)
			(xy 53.794808 -120.430866) (xy 53.752428 -120.388486) (xy 53.715941 -120.340936) (xy 53.685974 -120.28903)
			(xy 53.663038 -120.233657) (xy 53.647525 -120.175764) (xy 53.639702 -120.116342) (xy 53.639212 -120.086374)
			(xy 47.243592 -120.086374) (xy 47.244762 -120.224042) (xy 47.255176 -120.24487) (xy 47.264574 -120.251982)
			(xy 47.287445 -120.270147) (xy 47.327915 -120.312256) (xy 47.36149 -120.360044) (xy 47.387383 -120.412395)
			(xy 47.404989 -120.468082) (xy 47.413896 -120.525802) (xy 47.414434 -120.555004) (xy 47.413936 -120.582761)
			(xy 47.405898 -120.637691) (xy 47.389993 -120.690878) (xy 47.366555 -120.741202) (xy 47.336079 -120.787603)
			(xy 47.299206 -120.829103) (xy 47.27829 -120.847358) (xy 47.273972 -120.850914) (xy 47.267622 -120.859042)
			(xy 47.255938 -120.883172) (xy 47.253544 -120.888512) (xy 47.250983 -120.899927) (xy 47.250858 -120.905778)
			(xy 47.258224 -121.752614) (xy 47.258224 -121.766584) (xy 47.272194 -121.789952) (xy 47.284386 -121.79681)
			(xy 47.309479 -121.811366) (xy 47.355342 -121.846883) (xy 47.392963 -121.886472) (xy 51.785012 -121.886472)
			(xy 51.785012 -121.022872) (xy 51.785502 -120.992904) (xy 51.793325 -120.933482) (xy 51.808838 -120.875589)
			(xy 51.831774 -120.820216) (xy 51.861741 -120.76831) (xy 51.898228 -120.72076) (xy 51.940608 -120.67838)
			(xy 51.988158 -120.641893) (xy 52.040064 -120.611926) (xy 52.095437 -120.58899) (xy 52.15333 -120.573477)
			(xy 52.212752 -120.565654) (xy 52.272688 -120.565654) (xy 52.33211 -120.573477) (xy 52.390003 -120.58899)
			(xy 52.445376 -120.611926) (xy 52.497282 -120.641893) (xy 52.544832 -120.67838) (xy 52.587212 -120.72076)
			(xy 52.623699 -120.76831) (xy 52.653666 -120.820216) (xy 52.676602 -120.875589) (xy 52.692115 -120.933482)
			(xy 52.699938 -120.992904) (xy 52.700428 -121.022872) (xy 52.700428 -121.886472) (xy 52.699938 -121.91644)
			(xy 52.692115 -121.975862) (xy 52.676602 -122.033755) (xy 52.653666 -122.089128) (xy 52.623699 -122.141034)
			(xy 52.587212 -122.188584) (xy 52.544832 -122.230964) (xy 52.497282 -122.267451) (xy 52.445376 -122.297418)
			(xy 52.390003 -122.320354) (xy 52.33211 -122.335867) (xy 52.272688 -122.34369) (xy 52.212752 -122.34369)
			(xy 52.15333 -122.335867) (xy 52.095437 -122.320354) (xy 52.040064 -122.297418) (xy 51.988158 -122.267451)
			(xy 51.940608 -122.230964) (xy 51.898228 -122.188584) (xy 51.861741 -122.141034) (xy 51.831774 -122.089128)
			(xy 51.808838 -122.033755) (xy 51.793325 -121.975862) (xy 51.785502 -121.91644) (xy 51.785012 -121.886472)
			(xy 47.392963 -121.886472) (xy 47.395301 -121.888932) (xy 47.428436 -121.936545) (xy 47.453983 -121.988625)
			(xy 47.471353 -122.043971) (xy 47.480146 -122.101308) (xy 47.480728 -122.130312) (xy 47.480235 -122.157978)
			(xy 47.472242 -122.21273) (xy 47.456427 -122.265753) (xy 47.433119 -122.315936) (xy 47.402809 -122.362228)
			(xy 47.366131 -122.403657) (xy 47.323855 -122.439355) (xy 47.300642 -122.454416) (xy 47.295054 -122.457718)
			(xy 47.286672 -122.466608) (xy 47.271432 -122.49277) (xy 47.268226 -122.498759) (xy 47.264759 -122.511887)
			(xy 47.264574 -122.518678) (xy 47.271686 -123.318524) (xy 47.274856 -123.686316) (xy 53.639212 -123.686316)
			(xy 53.639212 -122.822716) (xy 53.639702 -122.792748) (xy 53.647525 -122.733326) (xy 53.663038 -122.675433)
			(xy 53.685974 -122.62006) (xy 53.715941 -122.568154) (xy 53.752428 -122.520604) (xy 53.794808 -122.478224)
			(xy 53.842358 -122.441737) (xy 53.894264 -122.41177) (xy 53.949637 -122.388834) (xy 54.00753 -122.373321)
			(xy 54.066952 -122.365498) (xy 54.126888 -122.365498) (xy 54.18631 -122.373321) (xy 54.244203 -122.388834)
			(xy 54.299576 -122.41177) (xy 54.351482 -122.441737) (xy 54.399032 -122.478224) (xy 54.441412 -122.520604)
			(xy 54.477899 -122.568154) (xy 54.507866 -122.62006) (xy 54.530802 -122.675433) (xy 54.546315 -122.733326)
			(xy 54.554138 -122.792748) (xy 54.554628 -122.822716) (xy 54.554628 -123.686316) (xy 54.554138 -123.716284)
			(xy 54.546315 -123.775706) (xy 54.530802 -123.833599) (xy 54.507866 -123.888972) (xy 54.477899 -123.940878)
			(xy 54.441412 -123.988428) (xy 54.399032 -124.030808) (xy 54.351482 -124.067295) (xy 54.299576 -124.097262)
			(xy 54.244203 -124.120198) (xy 54.18631 -124.135711) (xy 54.126888 -124.143534) (xy 54.066952 -124.143534)
			(xy 54.00753 -124.135711) (xy 53.949637 -124.120198) (xy 53.894264 -124.097262) (xy 53.842358 -124.067295)
			(xy 53.794808 -124.030808) (xy 53.752428 -123.988428) (xy 53.715941 -123.940878) (xy 53.685974 -123.888972)
			(xy 53.663038 -123.833599) (xy 53.647525 -123.775706) (xy 53.639702 -123.716284) (xy 53.639212 -123.686316)
			(xy 47.274856 -123.686316) (xy 47.290373 -125.486414) (xy 51.785012 -125.486414) (xy 51.785012 -124.622814)
			(xy 51.785502 -124.592846) (xy 51.793325 -124.533424) (xy 51.808838 -124.475531) (xy 51.831774 -124.420158)
			(xy 51.861741 -124.368252) (xy 51.898228 -124.320702) (xy 51.940608 -124.278322) (xy 51.988158 -124.241835)
			(xy 52.040064 -124.211868) (xy 52.095437 -124.188932) (xy 52.15333 -124.173419) (xy 52.212752 -124.165596)
			(xy 52.272688 -124.165596) (xy 52.33211 -124.173419) (xy 52.390003 -124.188932) (xy 52.445376 -124.211868)
			(xy 52.497282 -124.241835) (xy 52.544832 -124.278322) (xy 52.587212 -124.320702) (xy 52.623699 -124.368252)
			(xy 52.653666 -124.420158) (xy 52.676602 -124.475531) (xy 52.692115 -124.533424) (xy 52.699938 -124.592846)
			(xy 52.700428 -124.622814) (xy 52.700428 -125.486414) (xy 52.699938 -125.516382) (xy 52.692115 -125.575804)
			(xy 52.676602 -125.633697) (xy 52.653666 -125.68907) (xy 52.623699 -125.740976) (xy 52.587212 -125.788526)
			(xy 52.544832 -125.830906) (xy 52.497282 -125.867393) (xy 52.445376 -125.89736) (xy 52.390003 -125.920296)
			(xy 52.33211 -125.935809) (xy 52.272688 -125.943632) (xy 52.212752 -125.943632) (xy 52.15333 -125.935809)
			(xy 52.095437 -125.920296) (xy 52.040064 -125.89736) (xy 51.988158 -125.867393) (xy 51.940608 -125.830906)
			(xy 51.898228 -125.788526) (xy 51.861741 -125.740976) (xy 51.831774 -125.68907) (xy 51.808838 -125.633697)
			(xy 51.793325 -125.575804) (xy 51.785502 -125.516382) (xy 51.785012 -125.486414) (xy 47.290373 -125.486414)
			(xy 47.326804 -129.71272) (xy 47.331884 -129.727706) (xy 47.337218 -129.73431) (xy 47.355435 -129.759362)
			(xy 47.384369 -129.814128) (xy 47.404088 -129.872844) (xy 47.414075 -129.933972) (xy 47.414688 -129.964942)
			(xy 47.414135 -129.99418) (xy 47.405229 -130.051975) (xy 47.387616 -130.107736) (xy 47.361708 -130.16016)
			(xy 47.345346 -130.184398) (xy 47.340774 -130.190494) (xy 47.333916 -130.21183) (xy 47.332719 -130.215786)
			(xy 47.331446 -130.223953) (xy 47.331376 -130.228086) (xy 47.342552 -131.519422) (xy 47.342629 -131.523165)
			(xy 47.343772 -131.530565) (xy 47.344838 -131.534154) (xy 47.351188 -131.554728) (xy 47.354744 -131.560316)
			(xy 47.368875 -131.583363) (xy 47.391199 -131.632598) (xy 47.406338 -131.684495) (xy 47.413988 -131.73801)
			(xy 47.414434 -131.76504) (xy 47.413992 -131.791271) (xy 47.406806 -131.843238) (xy 47.392587 -131.893736)
			(xy 47.371603 -131.941819) (xy 47.3583 -131.96443) (xy 47.354744 -131.970272) (xy 47.348902 -131.990084)
			(xy 47.347938 -131.993625) (xy 47.34692 -132.000892) (xy 47.34687 -132.004562) (xy 47.356378 -133.096508)
			(xy 51.785012 -133.096508) (xy 51.785012 -132.232908) (xy 51.785502 -132.20294) (xy 51.793325 -132.143518)
			(xy 51.808838 -132.085625) (xy 51.831774 -132.030252) (xy 51.861741 -131.978346) (xy 51.898228 -131.930796)
			(xy 51.940608 -131.888416) (xy 51.988158 -131.851929) (xy 52.040064 -131.821962) (xy 52.095437 -131.799026)
			(xy 52.15333 -131.783513) (xy 52.212752 -131.77569) (xy 52.272688 -131.77569) (xy 52.33211 -131.783513)
			(xy 52.390003 -131.799026) (xy 52.445376 -131.821962) (xy 52.497282 -131.851929) (xy 52.544832 -131.888416)
			(xy 52.587212 -131.930796) (xy 52.623699 -131.978346) (xy 52.653666 -132.030252) (xy 52.676602 -132.085625)
			(xy 52.692115 -132.143518) (xy 52.699938 -132.20294) (xy 52.700428 -132.232908) (xy 52.700428 -133.096508)
			(xy 52.699938 -133.126476) (xy 52.692115 -133.185898) (xy 52.676602 -133.243791) (xy 52.653666 -133.299164)
			(xy 52.623699 -133.35107) (xy 52.587212 -133.39862) (xy 52.544832 -133.441) (xy 52.497282 -133.477487)
			(xy 52.445376 -133.507454) (xy 52.390003 -133.53039) (xy 52.33211 -133.545903) (xy 52.272688 -133.553726)
			(xy 52.212752 -133.553726) (xy 52.15333 -133.545903) (xy 52.095437 -133.53039) (xy 52.040064 -133.507454)
			(xy 51.988158 -133.477487) (xy 51.940608 -133.441) (xy 51.898228 -133.39862) (xy 51.861741 -133.35107)
			(xy 51.831774 -133.299164) (xy 51.808838 -133.243791) (xy 51.793325 -133.185898) (xy 51.785502 -133.126476)
			(xy 51.785012 -133.096508) (xy 47.356378 -133.096508) (xy 47.358554 -133.346444) (xy 47.360078 -133.35889)
			(xy 47.364904 -133.376924) (xy 47.367952 -133.382512) (xy 47.382602 -133.410697) (xy 47.403343 -133.470733)
			(xy 47.413831 -133.533379) (xy 47.414434 -133.565138) (xy 47.413796 -133.596757) (xy 47.403341 -133.659127)
			(xy 47.382755 -133.718922) (xy 47.368206 -133.747002) (xy 47.368206 -133.747256) (xy 47.36465 -133.755384)
			(xy 47.363331 -133.759514) (xy 47.361928 -133.768068) (xy 47.361856 -133.772402) (xy 47.387325 -136.69645)
			(xy 51.785012 -136.69645) (xy 51.785012 -135.83285) (xy 51.785502 -135.802882) (xy 51.793325 -135.74346)
			(xy 51.808838 -135.685567) (xy 51.831774 -135.630194) (xy 51.861741 -135.578288) (xy 51.898228 -135.530738)
			(xy 51.940608 -135.488358) (xy 51.988158 -135.451871) (xy 52.040064 -135.421904) (xy 52.095437 -135.398968)
			(xy 52.15333 -135.383455) (xy 52.212752 -135.375632) (xy 52.272688 -135.375632) (xy 52.33211 -135.383455)
			(xy 52.390003 -135.398968) (xy 52.445376 -135.421904) (xy 52.497282 -135.451871) (xy 52.544832 -135.488358)
			(xy 52.587212 -135.530738) (xy 52.623699 -135.578288) (xy 52.653666 -135.630194) (xy 52.676602 -135.685567)
			(xy 52.692115 -135.74346) (xy 52.699938 -135.802882) (xy 52.700428 -135.83285) (xy 52.700428 -136.69645)
			(xy 52.699938 -136.726418) (xy 52.692115 -136.78584) (xy 52.676602 -136.843733) (xy 52.653666 -136.899106)
			(xy 52.623699 -136.951012) (xy 52.587212 -136.998562) (xy 52.544832 -137.040942) (xy 52.497282 -137.077429)
			(xy 52.445376 -137.107396) (xy 52.390003 -137.130332) (xy 52.33211 -137.145845) (xy 52.272688 -137.153668)
			(xy 52.212752 -137.153668) (xy 52.15333 -137.145845) (xy 52.095437 -137.130332) (xy 52.040064 -137.107396)
			(xy 51.988158 -137.077429) (xy 51.940608 -137.040942) (xy 51.898228 -136.998562) (xy 51.861741 -136.951012)
			(xy 51.831774 -136.899106) (xy 51.808838 -136.843733) (xy 51.793325 -136.78584) (xy 51.785502 -136.726418)
			(xy 51.785012 -136.69645) (xy 47.387325 -136.69645) (xy 47.401734 -138.350752) (xy 47.403258 -138.36269)
			(xy 47.40783 -138.38047) (xy 47.410624 -138.385804) (xy 47.424587 -138.413516) (xy 47.444319 -138.472345)
			(xy 47.454258 -138.533594) (xy 47.45482 -138.56462) (xy 47.45482 -138.571478) (xy 47.45369 -138.601079)
			(xy 47.443395 -138.659413) (xy 47.424187 -138.715447) (xy 47.410878 -138.741912) (xy 47.40783 -138.7475)
			(xy 47.405036 -138.759438) (xy 47.410624 -139.397486) (xy 47.411307 -139.408645) (xy 47.420915 -139.428805)
			(xy 47.429166 -139.436348) (xy 47.450568 -139.454566) (xy 47.488305 -139.496215) (xy 47.519522 -139.542951)
			(xy 47.543544 -139.593761) (xy 47.559852 -139.647545) (xy 47.568092 -139.703141) (xy 47.568612 -139.731242)
			(xy 47.568129 -139.758818) (xy 47.560194 -139.813395) (xy 47.544481 -139.866261) (xy 47.521318 -139.916312)
			(xy 47.491188 -139.962505) (xy 47.454718 -140.003877) (xy 47.433992 -140.022072) (xy 47.42561 -140.029184)
			(xy 47.416212 -140.049758) (xy 47.416704 -140.127482) (xy 51.605178 -140.127482) (xy 51.609249 -140.07186)
			(xy 51.621375 -140.017423) (xy 51.641298 -139.965332) (xy 51.668594 -139.916697) (xy 51.70268 -139.872554)
			(xy 51.742829 -139.833845) (xy 51.788187 -139.801394) (xy 51.837787 -139.775893) (xy 51.890571 -139.757886)
			(xy 51.945414 -139.747756) (xy 52.001148 -139.745719) (xy 52.056585 -139.751819) (xy 52.110542 -139.765925)
			(xy 52.161871 -139.787737) (xy 52.209477 -139.816791) (xy 52.252345 -139.852466) (xy 52.289562 -139.894003)
			(xy 52.320335 -139.940516) (xy 52.344007 -139.991013) (xy 52.360075 -140.04442) (xy 52.368195 -140.099596)
			(xy 52.368704 -140.127482) (xy 52.368195 -140.155368) (xy 52.360075 -140.210544) (xy 52.344007 -140.263951)
			(xy 52.320335 -140.314448) (xy 52.289562 -140.360961) (xy 52.252345 -140.402498) (xy 52.209477 -140.438173)
			(xy 52.161871 -140.467227) (xy 52.110542 -140.489039) (xy 52.056585 -140.503145) (xy 52.001148 -140.509245)
			(xy 51.945414 -140.507208) (xy 51.890571 -140.497078) (xy 51.837787 -140.479071) (xy 51.788187 -140.45357)
			(xy 51.742829 -140.421119) (xy 51.70268 -140.38241) (xy 51.668594 -140.338267) (xy 51.641298 -140.289632)
			(xy 51.621375 -140.237541) (xy 51.609249 -140.183104) (xy 51.605178 -140.127482) (xy 47.416704 -140.127482)
			(xy 47.41672 -140.130022) (xy 47.417232 -140.139682) (xy 47.42453 -140.157581) (xy 47.430944 -140.16482)
			(xy 47.452951 -140.188621) (xy 47.489348 -140.242256) (xy 47.503334 -140.2715) (xy 47.506636 -140.278866)
			(xy 47.516438 -140.302754) (xy 47.530243 -140.352509) (xy 47.53721 -140.403671) (xy 47.537624 -140.429488)
			(xy 47.537094 -140.457941) (xy 47.528645 -140.514216) (xy 47.511945 -140.568616) (xy 47.487364 -140.61994)
			(xy 47.455445 -140.667051) (xy 47.436532 -140.688314) (xy 47.43069 -140.694664) (xy 47.420022 -140.718286)
			(xy 47.418325 -140.722482) (xy 47.416275 -140.731297) (xy 47.415958 -140.735812) (xy 47.37481 -141.360652)
			(xy 47.37481 -141.364462) (xy 47.37989 -141.876526) (xy 47.380144 -141.886686) (xy 47.380071 -141.90359)
			(xy 47.378928 -141.937379) (xy 47.377858 -141.95425) (xy 47.333882 -142.60068) (xy 51.605688 -142.60068)
			(xy 51.606137 -142.573274) (xy 51.61399 -142.519029) (xy 51.629529 -142.466466) (xy 51.652436 -142.416671)
			(xy 51.682238 -142.37067) (xy 51.699922 -142.349728) (xy 51.706018 -142.342616) (xy 51.712368 -142.325598)
			(xy 51.712368 -142.24) (xy 51.706018 -142.222982) (xy 51.699922 -142.21587) (xy 51.682243 -142.194925)
			(xy 51.652449 -142.148922) (xy 51.629549 -142.099127) (xy 51.614014 -142.046566) (xy 51.606164 -141.992322)
			(xy 51.605688 -141.964918) (xy 51.606174 -141.937667) (xy 51.61393 -141.883719) (xy 51.629285 -141.831424)
			(xy 51.651927 -141.781847) (xy 51.681393 -141.735997) (xy 51.717084 -141.694806) (xy 51.758275 -141.659115)
			(xy 51.804125 -141.629649) (xy 51.853702 -141.607007) (xy 51.905997 -141.591652) (xy 51.959945 -141.583896)
			(xy 52.014447 -141.583896) (xy 52.068395 -141.591652) (xy 52.12069 -141.607007) (xy 52.170267 -141.629649)
			(xy 52.216117 -141.659115) (xy 52.257308 -141.694806) (xy 52.292999 -141.735997) (xy 52.322465 -141.781847)
			(xy 52.345107 -141.831424) (xy 52.360462 -141.883719) (xy 52.368218 -141.937667) (xy 52.368704 -141.964918)
			(xy 52.368256 -141.992324) (xy 52.360403 -142.04657) (xy 52.344863 -142.099132) (xy 52.321956 -142.148927)
			(xy 52.292154 -142.194928) (xy 52.27447 -142.21587) (xy 52.268374 -142.222982) (xy 52.262024 -142.24)
			(xy 52.262024 -142.325598) (xy 52.268374 -142.342616) (xy 52.27447 -142.349728) (xy 52.292146 -142.370675)
			(xy 52.321941 -142.416677) (xy 52.344842 -142.466472) (xy 52.360378 -142.519033) (xy 52.368228 -142.573276)
			(xy 52.368704 -142.60068) (xy 52.368218 -142.627931) (xy 52.360462 -142.681879) (xy 52.345107 -142.734174)
			(xy 52.322465 -142.783751) (xy 52.292999 -142.829601) (xy 52.257308 -142.870792) (xy 52.216117 -142.906483)
			(xy 52.170267 -142.935949) (xy 52.12069 -142.958591) (xy 52.068395 -142.973946) (xy 52.014447 -142.981702)
			(xy 51.959945 -142.981702) (xy 51.905997 -142.973946) (xy 51.853702 -142.958591) (xy 51.804125 -142.935949)
			(xy 51.758275 -142.906483) (xy 51.717084 -142.870792) (xy 51.681393 -142.829601) (xy 51.651927 -142.783751)
			(xy 51.629285 -142.734174) (xy 51.61393 -142.681879) (xy 51.606174 -142.627931) (xy 51.605688 -142.60068)
			(xy 47.333882 -142.60068) (xy 47.331376 -142.63751) (xy 47.335186 -142.652496) (xy 47.339504 -142.659608)
			(xy 47.353044 -142.682344) (xy 47.37441 -142.730755) (xy 47.388885 -142.781654) (xy 47.396191 -142.834064)
			(xy 47.396654 -142.860522) (xy 47.396191 -142.886858) (xy 47.388911 -142.939024) (xy 47.374534 -142.989696)
			(xy 47.353333 -143.037913) (xy 47.325709 -143.08276) (xy 47.309278 -143.103346) (xy 47.304198 -143.109696)
			(xy 47.298356 -143.124174) (xy 47.053218 -146.739864) (xy 48.909984 -146.739864) (xy 48.914055 -146.684242)
			(xy 48.926181 -146.629805) (xy 48.946104 -146.577714) (xy 48.9734 -146.529079) (xy 49.007486 -146.484936)
			(xy 49.047635 -146.446227) (xy 49.092993 -146.413776) (xy 49.142593 -146.388275) (xy 49.195377 -146.370268)
			(xy 49.25022 -146.360138) (xy 49.305954 -146.358101) (xy 49.361391 -146.364201) (xy 49.415348 -146.378307)
			(xy 49.466677 -146.400119) (xy 49.514283 -146.429173) (xy 49.557151 -146.464848) (xy 49.594368 -146.506385)
			(xy 49.625141 -146.552898) (xy 49.648813 -146.603395) (xy 49.664881 -146.656802) (xy 49.673001 -146.711978)
			(xy 49.67351 -146.739864) (xy 49.673001 -146.76775) (xy 49.668844 -146.795998) (xy 50.543712 -146.795998)
			(xy 50.547783 -146.740376) (xy 50.559909 -146.685939) (xy 50.579832 -146.633848) (xy 50.607128 -146.585213)
			(xy 50.641214 -146.54107) (xy 50.681363 -146.502361) (xy 50.726721 -146.46991) (xy 50.776321 -146.444409)
			(xy 50.829105 -146.426402) (xy 50.883948 -146.416272) (xy 50.939682 -146.414235) (xy 50.995119 -146.420335)
			(xy 51.049076 -146.434441) (xy 51.100405 -146.456253) (xy 51.148011 -146.485307) (xy 51.190879 -146.520982)
			(xy 51.228096 -146.562519) (xy 51.258869 -146.609032) (xy 51.282541 -146.659529) (xy 51.298609 -146.712936)
			(xy 51.306729 -146.768112) (xy 51.307238 -146.795998) (xy 51.306729 -146.823884) (xy 51.298609 -146.87906)
			(xy 51.282541 -146.932467) (xy 51.258869 -146.982964) (xy 51.228096 -147.029477) (xy 51.190879 -147.071014)
			(xy 51.148011 -147.106689) (xy 51.100405 -147.135743) (xy 51.049076 -147.157555) (xy 50.995119 -147.171661)
			(xy 50.939682 -147.177761) (xy 50.883948 -147.175724) (xy 50.829105 -147.165594) (xy 50.776321 -147.147587)
			(xy 50.726721 -147.122086) (xy 50.681363 -147.089635) (xy 50.641214 -147.050926) (xy 50.607128 -147.006783)
			(xy 50.579832 -146.958148) (xy 50.559909 -146.906057) (xy 50.547783 -146.85162) (xy 50.543712 -146.795998)
			(xy 49.668844 -146.795998) (xy 49.664881 -146.822926) (xy 49.648813 -146.876333) (xy 49.625141 -146.92683)
			(xy 49.594368 -146.973343) (xy 49.557151 -147.01488) (xy 49.514283 -147.050555) (xy 49.466677 -147.079609)
			(xy 49.415348 -147.101421) (xy 49.361391 -147.115527) (xy 49.305954 -147.121627) (xy 49.25022 -147.11959)
			(xy 49.195377 -147.10946) (xy 49.142593 -147.091453) (xy 49.092993 -147.065952) (xy 49.047635 -147.033501)
			(xy 49.007486 -146.994792) (xy 48.9734 -146.950649) (xy 48.946104 -146.902014) (xy 48.926181 -146.849923)
			(xy 48.914055 -146.795486) (xy 48.909984 -146.739864) (xy 47.053218 -146.739864) (xy 46.550146 -154.159966)
			(xy 51.306982 -154.159966) (xy 51.311053 -154.104344) (xy 51.323179 -154.049907) (xy 51.343102 -153.997816)
			(xy 51.370398 -153.949181) (xy 51.404484 -153.905038) (xy 51.444633 -153.866329) (xy 51.489991 -153.833878)
			(xy 51.539591 -153.808377) (xy 51.592375 -153.79037) (xy 51.647218 -153.78024) (xy 51.702952 -153.778203)
			(xy 51.758389 -153.784303) (xy 51.812346 -153.798409) (xy 51.863675 -153.820221) (xy 51.911281 -153.849275)
			(xy 51.954149 -153.88495) (xy 51.991366 -153.926487) (xy 52.022139 -153.973) (xy 52.045811 -154.023497)
			(xy 52.061879 -154.076904) (xy 52.069999 -154.13208) (xy 52.070508 -154.159966) (xy 52.069999 -154.187852)
			(xy 52.061879 -154.243028) (xy 52.045811 -154.296435) (xy 52.022139 -154.346932) (xy 51.991366 -154.393445)
			(xy 51.954149 -154.434982) (xy 51.911281 -154.470657) (xy 51.863675 -154.499711) (xy 51.812346 -154.521523)
			(xy 51.758389 -154.535629) (xy 51.702952 -154.541729) (xy 51.647218 -154.539692) (xy 51.592375 -154.529562)
			(xy 51.539591 -154.511555) (xy 51.489991 -154.486054) (xy 51.444633 -154.453603) (xy 51.404484 -154.414894)
			(xy 51.370398 -154.370751) (xy 51.343102 -154.322116) (xy 51.323179 -154.270025) (xy 51.311053 -154.215588)
			(xy 51.306982 -154.159966) (xy 46.550146 -154.159966) (xy 46.490372 -155.0416) (xy 48.163732 -155.0416)
			(xy 48.167803 -154.985978) (xy 48.179929 -154.931541) (xy 48.199852 -154.87945) (xy 48.227148 -154.830815)
			(xy 48.261234 -154.786672) (xy 48.301383 -154.747963) (xy 48.346741 -154.715512) (xy 48.396341 -154.690011)
			(xy 48.449125 -154.672004) (xy 48.503968 -154.661874) (xy 48.559702 -154.659837) (xy 48.615139 -154.665937)
			(xy 48.669096 -154.680043) (xy 48.720425 -154.701855) (xy 48.768031 -154.730909) (xy 48.810899 -154.766584)
			(xy 48.848116 -154.808121) (xy 48.878889 -154.854634) (xy 48.902561 -154.905131) (xy 48.918629 -154.958538)
			(xy 48.926749 -155.013714) (xy 48.927258 -155.0416) (xy 48.926749 -155.069486) (xy 48.918629 -155.124662)
			(xy 48.902561 -155.178069) (xy 48.878889 -155.228566) (xy 48.848116 -155.275079) (xy 48.810899 -155.316616)
			(xy 48.768031 -155.352291) (xy 48.720425 -155.381345) (xy 48.669096 -155.403157) (xy 48.615139 -155.417263)
			(xy 48.559702 -155.423363) (xy 48.503968 -155.421326) (xy 48.449125 -155.411196) (xy 48.396341 -155.393189)
			(xy 48.346741 -155.367688) (xy 48.301383 -155.335237) (xy 48.261234 -155.296528) (xy 48.227148 -155.252385)
			(xy 48.199852 -155.20375) (xy 48.179929 -155.151659) (xy 48.167803 -155.097222) (xy 48.163732 -155.0416)
			(xy 46.490372 -155.0416) (xy 46.452624 -155.598368) (xy 51.368196 -155.598368) (xy 51.372267 -155.542746)
			(xy 51.384393 -155.488309) (xy 51.404316 -155.436218) (xy 51.431612 -155.387583) (xy 51.465698 -155.34344)
			(xy 51.505847 -155.304731) (xy 51.551205 -155.27228) (xy 51.600805 -155.246779) (xy 51.653589 -155.228772)
			(xy 51.708432 -155.218642) (xy 51.764166 -155.216605) (xy 51.819603 -155.222705) (xy 51.87356 -155.236811)
			(xy 51.924889 -155.258623) (xy 51.972495 -155.287677) (xy 52.015363 -155.323352) (xy 52.05258 -155.364889)
			(xy 52.083353 -155.411402) (xy 52.107025 -155.461899) (xy 52.123093 -155.515306) (xy 52.131213 -155.570482)
			(xy 52.131722 -155.598368) (xy 52.131213 -155.626254) (xy 52.123093 -155.68143) (xy 52.107025 -155.734837)
			(xy 52.083353 -155.785334) (xy 52.05258 -155.831847) (xy 52.015363 -155.873384) (xy 51.972495 -155.909059)
			(xy 51.924889 -155.938113) (xy 51.87356 -155.959925) (xy 51.819603 -155.974031) (xy 51.764166 -155.980131)
			(xy 51.708432 -155.978094) (xy 51.653589 -155.967964) (xy 51.600805 -155.949957) (xy 51.551205 -155.924456)
			(xy 51.505847 -155.892005) (xy 51.465698 -155.853296) (xy 51.431612 -155.809153) (xy 51.404316 -155.760518)
			(xy 51.384393 -155.708427) (xy 51.372267 -155.65399) (xy 51.368196 -155.598368) (xy 46.452624 -155.598368)
			(xy 46.352606 -157.0736) (xy 51.296822 -157.0736) (xy 51.300893 -157.017978) (xy 51.313019 -156.963541)
			(xy 51.332942 -156.91145) (xy 51.360238 -156.862815) (xy 51.394324 -156.818672) (xy 51.434473 -156.779963)
			(xy 51.479831 -156.747512) (xy 51.529431 -156.722011) (xy 51.582215 -156.704004) (xy 51.637058 -156.693874)
			(xy 51.692792 -156.691837) (xy 51.748229 -156.697937) (xy 51.802186 -156.712043) (xy 51.853515 -156.733855)
			(xy 51.901121 -156.762909) (xy 51.943989 -156.798584) (xy 51.981206 -156.840121) (xy 52.011979 -156.886634)
			(xy 52.035651 -156.937131) (xy 52.051719 -156.990538) (xy 52.059839 -157.045714) (xy 52.060348 -157.0736)
			(xy 52.059839 -157.101486) (xy 52.051719 -157.156662) (xy 52.035651 -157.210069) (xy 52.011979 -157.260566)
			(xy 51.981206 -157.307079) (xy 51.943989 -157.348616) (xy 51.901121 -157.384291) (xy 51.853515 -157.413345)
			(xy 51.802186 -157.435157) (xy 51.748229 -157.449263) (xy 51.692792 -157.455363) (xy 51.637058 -157.453326)
			(xy 51.582215 -157.443196) (xy 51.529431 -157.425189) (xy 51.479831 -157.399688) (xy 51.434473 -157.367237)
			(xy 51.394324 -157.328528) (xy 51.360238 -157.284385) (xy 51.332942 -157.23575) (xy 51.313019 -157.183659)
			(xy 51.300893 -157.129222) (xy 51.296822 -157.0736) (xy 46.352606 -157.0736) (xy 46.21911 -159.042608)
			(xy 46.218964 -159.054596) (xy 46.228361 -159.076615) (xy 46.237144 -159.084772) (xy 46.298358 -159.136588)
			(xy 46.303078 -159.140339) (xy 46.313863 -159.145723) (xy 46.319694 -159.147256) (xy 46.331124 -159.149796)
			(xy 46.343062 -159.147002) (xy 46.343316 -159.147002) (xy 46.388629 -159.136637) (xy 46.480564 -159.122872)
			(xy 46.573348 -159.117153) (xy 46.666278 -159.119524) (xy 46.75865 -159.129967) (xy 46.849764 -159.148402)
			(xy 46.93893 -159.174691) (xy 47.025471 -159.208634) (xy 47.108734 -159.249974) (xy 47.188086 -159.298397)
			(xy 47.262927 -159.353537) (xy 47.33269 -159.414977) (xy 47.396845 -159.48225) (xy 47.454908 -159.554847)
			(xy 47.506438 -159.632218) (xy 47.551045 -159.713776) (xy 47.588391 -159.798905) (xy 47.618192 -159.886959)
			(xy 47.640224 -159.977271) (xy 47.65432 -160.069156) (xy 47.660371 -160.161919) (xy 47.658334 -160.254857)
			(xy 47.648222 -160.347266) (xy 47.630113 -160.438445) (xy 47.604144 -160.527704) (xy 47.570512 -160.614367)
			(xy 47.529471 -160.697778) (xy 47.481332 -160.777303) (xy 47.426461 -160.852341) (xy 47.365272 -160.922324)
			(xy 47.29823 -160.98672) (xy 47.225841 -161.045043) (xy 47.148656 -161.09685) (xy 47.067257 -161.141749)
			(xy 46.982263 -161.1794) (xy 46.894317 -161.209517) (xy 46.804085 -161.231873) (xy 46.71225 -161.246297)
			(xy 46.619509 -161.252682) (xy 46.526565 -161.250977) (xy 46.43412 -161.241197) (xy 46.342877 -161.223415)
			(xy 46.253525 -161.197767) (xy 46.209966 -161.181542) (xy 46.19879 -161.177224) (xy 46.17466 -161.179764)
			(xy 46.095412 -161.23031) (xy 46.094396 -161.231072) (xy 46.085039 -161.23808) (xy 46.07339 -161.258322)
			(xy 46.072044 -161.269934) (xy 46.03623 -161.81832) (xy 46.034198 -161.844736) (xy 46.02099 -161.987484)
			(xy 46.020736 -161.993834) (xy 47.934626 -219.255594) (xy 47.935381 -219.265206) (xy 47.943114 -219.28285)
			(xy 47.95681 -219.296398) (xy 47.974537 -219.30394) (xy 47.984156 -219.304616)
		)
		(stroke
			(width 0)
			(type solid)
		)
		(fill yes)
		(layer "In11.Cu")
		(net "GND")
	)
	(gr_poly
		(pts
			(xy 163.718748 -299.856144) (xy 163.726358 -299.854638) (xy 163.740206 -299.847666) (xy 163.745926 -299.842428)
			(xy 163.86048 -299.727874) (xy 163.865681 -299.722126) (xy 163.872665 -299.708295) (xy 163.874196 -299.700696)
			(xy 163.874958 -299.692314) (xy 163.874958 -299.577506) (xy 163.874578 -299.568404) (xy 163.868187 -299.55136)
			(xy 163.862512 -299.544232) (xy 163.85667 -299.537374) (xy 163.840668 -299.528484) (xy 163.831524 -299.527214)
			(xy 163.807602 -299.523303) (xy 163.761318 -299.508907) (xy 163.71789 -299.48738) (xy 163.678408 -299.459262)
			(xy 163.643865 -299.425259) (xy 163.615129 -299.386226) (xy 163.59292 -299.343142) (xy 163.577797 -299.297091)
			(xy 163.57014 -299.249229) (xy 163.570141 -299.200758) (xy 163.5778 -299.152896) (xy 163.592925 -299.106846)
			(xy 163.615135 -299.063763) (xy 163.643874 -299.024731) (xy 163.678418 -298.99073) (xy 163.717901 -298.962613)
			(xy 163.76133 -298.941088) (xy 163.807615 -298.926695) (xy 163.831524 -298.922694) (xy 163.832794 -298.92244)
			(xy 163.837366 -298.921932) (xy 163.845388 -298.919879) (xy 163.859631 -298.911453) (xy 163.865306 -298.905422)
			(xy 163.874958 -298.894246) (xy 163.897805 -298.894668) (xy 163.943052 -298.901048) (xy 163.965128 -298.906946)
			(xy 163.976812 -298.910248) (xy 163.988242 -298.908216) (xy 163.994018 -298.90693) (xy 164.004792 -298.902045)
			(xy 164.009578 -298.898564) (xy 164.075618 -298.848526) (xy 164.08414 -298.840898) (xy 164.094048 -298.82032)
			(xy 164.094668 -298.808902) (xy 164.094668 -297.740832) (xy 164.09404 -297.729413) (xy 164.084145 -297.70883)
			(xy 164.075618 -297.701208) (xy 164.009578 -297.65117) (xy 164.004793 -297.647689) (xy 163.994017 -297.642808)
			(xy 163.988242 -297.641518) (xy 163.976812 -297.639486) (xy 163.965128 -297.642788) (xy 163.943051 -297.648679)
			(xy 163.897804 -297.655049) (xy 163.874958 -297.655488) (xy 163.848974 -297.654975) (xy 163.797645 -297.646839)
			(xy 163.748222 -297.630774) (xy 163.701919 -297.607176) (xy 163.659879 -297.576625) (xy 163.623134 -297.539874)
			(xy 163.592592 -297.497828) (xy 163.569002 -297.451521) (xy 163.552946 -297.402094) (xy 163.54482 -297.350765)
			(xy 163.54425 -297.32478) (xy 163.5448 -297.298269) (xy 163.553307 -297.245933) (xy 163.570052 -297.195624)
			(xy 163.581842 -297.171872) (xy 163.582096 -297.17111) (xy 163.586312 -297.162052) (xy 163.588145 -297.142177)
			(xy 163.585652 -297.132502) (xy 163.585144 -297.13047) (xy 163.535614 -297.047666) (xy 163.52774 -297.03776)
			(xy 163.520437 -297.031145) (xy 163.502272 -297.023559) (xy 163.492434 -297.023028) (xy 163.30803 -297.023028)
			(xy 163.307522 -297.023028) (xy 163.295805 -297.023729) (xy 163.274884 -297.034314) (xy 163.26739 -297.043348)
			(xy 163.264596 -297.047412) (xy 163.218622 -297.123358) (xy 163.213122 -297.134624) (xy 163.212743 -297.159662)
			(xy 163.21786 -297.17111) (xy 163.219638 -297.174412) (xy 163.223194 -297.181778) (xy 163.233443 -297.204209)
			(xy 163.247921 -297.251352) (xy 163.255235 -297.300122) (xy 163.255706 -297.32478) (xy 163.255196 -297.350767)
			(xy 163.247066 -297.402102) (xy 163.231005 -297.451532) (xy 163.207409 -297.497842) (xy 163.176859 -297.53989)
			(xy 163.140108 -297.576641) (xy 163.09806 -297.607191) (xy 163.05175 -297.630787) (xy 163.00232 -297.646848)
			(xy 162.950985 -297.654978) (xy 162.899011 -297.654978) (xy 162.847676 -297.646848) (xy 162.798246 -297.630787)
			(xy 162.751936 -297.607191) (xy 162.709888 -297.576641) (xy 162.673137 -297.53989) (xy 162.642587 -297.497842)
			(xy 162.618991 -297.451532) (xy 162.60293 -297.402102) (xy 162.5948 -297.350767) (xy 162.59429 -297.32478)
			(xy 162.594839 -297.298269) (xy 162.603345 -297.245932) (xy 162.620088 -297.195622) (xy 162.631882 -297.171872)
			(xy 162.632136 -297.17111) (xy 162.636349 -297.162051) (xy 162.638181 -297.142178) (xy 162.635692 -297.132502)
			(xy 162.635184 -297.13047) (xy 162.585654 -297.047666) (xy 162.57778 -297.03776) (xy 162.570474 -297.031154)
			(xy 162.552309 -297.02359) (xy 162.542474 -297.023028) (xy 162.35807 -297.023028) (xy 162.357562 -297.023028)
			(xy 162.345852 -297.023742) (xy 162.324951 -297.034341) (xy 162.31743 -297.043348) (xy 162.314636 -297.047412)
			(xy 162.268662 -297.123358) (xy 162.263159 -297.134624) (xy 162.26278 -297.159663) (xy 162.2679 -297.17111)
			(xy 162.269678 -297.174412) (xy 162.273234 -297.181778) (xy 162.283482 -297.20421) (xy 162.297958 -297.251352)
			(xy 162.305271 -297.300122) (xy 162.305746 -297.32478) (xy 162.305236 -297.350767) (xy 162.297106 -297.402102)
			(xy 162.281045 -297.451532) (xy 162.257449 -297.497842) (xy 162.226899 -297.53989) (xy 162.190148 -297.576641)
			(xy 162.1481 -297.607191) (xy 162.10179 -297.630787) (xy 162.05236 -297.646848) (xy 162.001025 -297.654978)
			(xy 161.949051 -297.654978) (xy 161.897716 -297.646848) (xy 161.848286 -297.630787) (xy 161.801976 -297.607191)
			(xy 161.759928 -297.576641) (xy 161.723177 -297.53989) (xy 161.692627 -297.497842) (xy 161.669031 -297.451532)
			(xy 161.65297 -297.402102) (xy 161.64484 -297.350767) (xy 161.64433 -297.32478) (xy 161.64488 -297.298269)
			(xy 161.653386 -297.245933) (xy 161.670131 -297.195623) (xy 161.681922 -297.171872) (xy 161.682176 -297.17111)
			(xy 161.686393 -297.162052) (xy 161.688227 -297.142177) (xy 161.685732 -297.132502) (xy 161.685224 -297.13047)
			(xy 161.635694 -297.047666) (xy 161.62782 -297.03776) (xy 161.620516 -297.031148) (xy 161.602351 -297.023569)
			(xy 161.592514 -297.023028) (xy 161.40811 -297.023028) (xy 161.407602 -297.023028) (xy 161.395887 -297.023734)
			(xy 161.374973 -297.034323) (xy 161.36747 -297.043348) (xy 161.364676 -297.047412) (xy 161.318702 -297.123358)
			(xy 161.313204 -297.134625) (xy 161.312825 -297.159662) (xy 161.31794 -297.17111) (xy 161.319718 -297.174412)
			(xy 161.323274 -297.181778) (xy 161.333524 -297.204209) (xy 161.348003 -297.251352) (xy 161.355317 -297.300122)
			(xy 161.355786 -297.32478) (xy 161.355276 -297.350767) (xy 161.347146 -297.402102) (xy 161.331085 -297.451532)
			(xy 161.307489 -297.497842) (xy 161.276939 -297.53989) (xy 161.240188 -297.576641) (xy 161.19814 -297.607191)
			(xy 161.15183 -297.630787) (xy 161.1024 -297.646848) (xy 161.051065 -297.654978) (xy 160.999091 -297.654978)
			(xy 160.947756 -297.646848) (xy 160.898326 -297.630787) (xy 160.852016 -297.607191) (xy 160.809968 -297.576641)
			(xy 160.773217 -297.53989) (xy 160.742667 -297.497842) (xy 160.719071 -297.451532) (xy 160.70301 -297.402102)
			(xy 160.69488 -297.350767) (xy 160.69437 -297.32478) (xy 160.694919 -297.298269) (xy 160.703424 -297.245932)
			(xy 160.720166 -297.195621) (xy 160.731962 -297.171872) (xy 160.732216 -297.17111) (xy 160.736431 -297.162051)
			(xy 160.738263 -297.142177) (xy 160.735772 -297.132502) (xy 160.735264 -297.13047) (xy 160.685734 -297.047666)
			(xy 160.67786 -297.03776) (xy 160.670558 -297.031142) (xy 160.652394 -297.023549) (xy 160.642554 -297.023028)
			(xy 160.457896 -297.023028) (xy 160.457388 -297.023028) (xy 160.445675 -297.023736) (xy 160.424765 -297.03433)
			(xy 160.417256 -297.043348) (xy 160.414462 -297.047412) (xy 160.368488 -297.123358) (xy 160.362991 -297.134625)
			(xy 160.362612 -297.159661) (xy 160.367726 -297.17111) (xy 160.369504 -297.174412) (xy 160.37306 -297.181778)
			(xy 160.38331 -297.204209) (xy 160.39779 -297.251352) (xy 160.405105 -297.300122) (xy 160.405572 -297.32478)
			(xy 160.405062 -297.350767) (xy 160.396932 -297.402102) (xy 160.380871 -297.451532) (xy 160.357275 -297.497842)
			(xy 160.326725 -297.53989) (xy 160.289974 -297.576641) (xy 160.247926 -297.607191) (xy 160.201616 -297.630787)
			(xy 160.152186 -297.646848) (xy 160.100851 -297.654978) (xy 160.048877 -297.654978) (xy 159.997542 -297.646848)
			(xy 159.948112 -297.630787) (xy 159.901802 -297.607191) (xy 159.859754 -297.576641) (xy 159.823003 -297.53989)
			(xy 159.792453 -297.497842) (xy 159.768857 -297.451532) (xy 159.752796 -297.402102) (xy 159.744666 -297.350767)
			(xy 159.744156 -297.32478) (xy 159.744705 -297.298269) (xy 159.75321 -297.245932) (xy 159.769951 -297.195621)
			(xy 159.781748 -297.171872) (xy 159.782002 -297.17111) (xy 159.786218 -297.162052) (xy 159.788051 -297.142177)
			(xy 159.785558 -297.132502) (xy 159.78505 -297.13047) (xy 159.73552 -297.047666) (xy 159.727646 -297.03776)
			(xy 159.720344 -297.031144) (xy 159.702179 -297.023556) (xy 159.69234 -297.023028) (xy 158.557976 -297.023028)
			(xy 158.557468 -297.023028) (xy 158.545757 -297.023741) (xy 158.524854 -297.034339) (xy 158.517336 -297.043348)
			(xy 158.514542 -297.047412) (xy 158.468568 -297.123358) (xy 158.463065 -297.134624) (xy 158.462686 -297.159663)
			(xy 158.467806 -297.17111) (xy 158.469584 -297.174412) (xy 158.47314 -297.181778) (xy 158.483388 -297.20421)
			(xy 158.497864 -297.251352) (xy 158.505177 -297.300122) (xy 158.505652 -297.32478) (xy 158.505142 -297.350767)
			(xy 158.497012 -297.402102) (xy 158.480951 -297.451532) (xy 158.457355 -297.497842) (xy 158.426805 -297.53989)
			(xy 158.390054 -297.576641) (xy 158.348006 -297.607191) (xy 158.301696 -297.630787) (xy 158.252266 -297.646848)
			(xy 158.200931 -297.654978) (xy 158.148957 -297.654978) (xy 158.097622 -297.646848) (xy 158.048192 -297.630787)
			(xy 158.001882 -297.607191) (xy 157.959834 -297.576641) (xy 157.923083 -297.53989) (xy 157.892533 -297.497842)
			(xy 157.868937 -297.451532) (xy 157.852876 -297.402102) (xy 157.844746 -297.350767) (xy 157.844236 -297.32478)
			(xy 157.844738 -297.29858) (xy 157.853005 -297.246836) (xy 157.86933 -297.197043) (xy 157.893304 -297.150448)
			(xy 157.924327 -297.108218) (xy 157.961622 -297.071409) (xy 157.982666 -297.055794) (xy 157.98292 -297.05554)
			(xy 157.990644 -297.049391) (xy 158.001097 -297.032665) (xy 158.00324 -297.023028) (xy 158.003494 -297.022012)
			(xy 158.00705 -296.980102) (xy 158.00705 -296.979594) (xy 158.010098 -296.94124) (xy 158.010417 -296.930156)
			(xy 158.002771 -296.909364) (xy 157.995366 -296.901108) (xy 154.798776 -293.704518) (xy 154.790567 -293.697041)
			(xy 154.769743 -293.689415) (xy 154.758644 -293.689786) (xy 154.72029 -293.692834) (xy 154.719782 -293.692834)
			(xy 154.677872 -293.69639) (xy 154.676856 -293.696644) (xy 154.667211 -293.69877) (xy 154.650478 -293.709224)
			(xy 154.644344 -293.716964) (xy 154.64409 -293.717218) (xy 154.62846 -293.738253) (xy 154.591666 -293.775565)
			(xy 154.549442 -293.8066) (xy 154.502848 -293.83058) (xy 154.453053 -293.846903) (xy 154.401305 -293.855161)
			(xy 154.375104 -293.855648) (xy 154.349115 -293.855139) (xy 154.297778 -293.847009) (xy 154.248345 -293.830949)
			(xy 154.202032 -293.807354) (xy 154.15998 -293.776805) (xy 154.123224 -293.740054) (xy 154.092669 -293.698006)
			(xy 154.069068 -293.651696) (xy 154.053001 -293.602265) (xy 154.044865 -293.550928) (xy 154.044396 -293.52494)
			(xy 154.044901 -293.498742) (xy 154.053175 -293.447003) (xy 154.069506 -293.397217) (xy 154.093486 -293.35063)
			(xy 154.124514 -293.308408) (xy 154.161814 -293.27161) (xy 154.182826 -293.255954) (xy 154.18308 -293.2557)
			(xy 154.190804 -293.249552) (xy 154.201252 -293.232824) (xy 154.2034 -293.223188) (xy 154.203654 -293.222172)
			(xy 154.20721 -293.180262) (xy 154.20721 -293.179754) (xy 154.210258 -293.1414) (xy 154.210588 -293.130311)
			(xy 154.202955 -293.109506) (xy 154.195526 -293.101268) (xy 153.848562 -292.754304) (xy 153.840357 -292.746814)
			(xy 153.819531 -292.739154) (xy 153.80843 -292.739572) (xy 153.731214 -292.745922) (xy 153.726896 -292.74643)
			(xy 153.717873 -292.748389) (xy 153.701985 -292.757767) (xy 153.695908 -292.764718) (xy 153.69413 -292.767004)
			(xy 153.678491 -292.788068) (xy 153.641668 -292.825435) (xy 153.599408 -292.85652) (xy 153.55277 -292.880542)
			(xy 153.502924 -292.896899) (xy 153.451121 -292.90518) (xy 153.42489 -292.905688) (xy 153.398902 -292.905204)
			(xy 153.347566 -292.897072) (xy 153.298134 -292.881008) (xy 153.251823 -292.85741) (xy 153.209775 -292.826857)
			(xy 153.173024 -292.790102) (xy 153.142475 -292.748051) (xy 153.11888 -292.701739) (xy 153.102821 -292.652305)
			(xy 153.094694 -292.600968) (xy 153.094182 -292.57498) (xy 153.094686 -292.54875) (xy 153.102971 -292.496947)
			(xy 153.11933 -292.447103) (xy 153.143354 -292.400466) (xy 153.174439 -292.358206) (xy 153.211805 -292.321384)
			(xy 153.232866 -292.30574) (xy 153.235152 -292.303962) (xy 153.242106 -292.297886) (xy 153.251492 -292.282)
			(xy 153.25344 -292.272974) (xy 153.253948 -292.268656) (xy 153.260298 -292.19144) (xy 153.260617 -292.180356)
			(xy 153.252971 -292.159564) (xy 153.245566 -292.151308) (xy 152.898602 -291.804344) (xy 152.890396 -291.79686)
			(xy 152.86957 -291.789219) (xy 152.85847 -291.789612) (xy 152.781 -291.795962) (xy 152.776682 -291.79647)
			(xy 152.766956 -291.798637) (xy 152.750099 -291.809229) (xy 152.743916 -291.817044) (xy 152.728287 -291.838079)
			(xy 152.691494 -291.87539) (xy 152.64927 -291.906422) (xy 152.602675 -291.930398) (xy 152.552879 -291.946715)
			(xy 152.501131 -291.954963) (xy 152.47493 -291.955474) (xy 152.44894 -291.954993) (xy 152.3976 -291.946865)
			(xy 152.348164 -291.930805) (xy 152.301849 -291.907209) (xy 152.259796 -291.876656) (xy 152.223041 -291.839901)
			(xy 152.192489 -291.797848) (xy 152.168893 -291.751533) (xy 152.152834 -291.702096) (xy 152.144707 -291.650756)
			(xy 152.144222 -291.624766) (xy 152.144725 -291.598566) (xy 152.152994 -291.546823) (xy 152.16932 -291.497031)
			(xy 152.193294 -291.450437) (xy 152.224317 -291.408208) (xy 152.261611 -291.371399) (xy 152.282652 -291.35578)
			(xy 152.290538 -291.349665) (xy 152.301134 -291.332772) (xy 152.303226 -291.323014) (xy 152.303734 -291.318696)
			(xy 152.310084 -291.241226) (xy 152.310399 -291.230143) (xy 152.302748 -291.209357) (xy 152.295352 -291.201094)
			(xy 150.458932 -289.364674) (xy 150.452086 -289.357276) (xy 150.444356 -289.338677) (xy 150.443946 -289.328606)
			(xy 150.443946 -287.513268) (xy 150.443729 -287.506664) (xy 150.440262 -287.493917) (xy 150.437088 -287.488122)
			(xy 150.433786 -287.48228) (xy 150.424642 -287.473136) (xy 150.418546 -287.46958) (xy 150.34514 -287.426908)
			(xy 150.332694 -287.421574) (xy 150.327614 -287.420558) (xy 150.324058 -287.42005) (xy 150.320168 -287.419764)
			(xy 150.312383 -287.420273) (xy 150.308564 -287.421066) (xy 150.292308 -287.425384) (xy 150.28672 -287.428432)
			(xy 150.258435 -287.443209) (xy 150.198159 -287.464157) (xy 150.135238 -287.474781) (xy 150.103332 -287.475422)
			(xy 150.103078 -287.475422) (xy 150.075827 -287.474935) (xy 150.021879 -287.467175) (xy 149.969585 -287.451818)
			(xy 149.920009 -287.429175) (xy 149.87416 -287.399707) (xy 149.832971 -287.364014) (xy 149.79728 -287.322823)
			(xy 149.767815 -287.276972) (xy 149.745175 -287.227394) (xy 149.72982 -287.175099) (xy 149.722064 -287.121151)
			(xy 149.722064 -287.066649) (xy 149.72982 -287.012701) (xy 149.745175 -286.960406) (xy 149.767815 -286.910828)
			(xy 149.79728 -286.864977) (xy 149.832971 -286.823786) (xy 149.87416 -286.788093) (xy 149.920009 -286.758625)
			(xy 149.969585 -286.735982) (xy 150.021879 -286.720625) (xy 150.075827 -286.712865) (xy 150.103078 -286.712406)
			(xy 150.103332 -286.712406) (xy 150.135235 -286.713071) (xy 150.19815 -286.723709) (xy 150.25843 -286.744634)
			(xy 150.28672 -286.759396) (xy 150.292308 -286.762444) (xy 150.308564 -286.766762) (xy 150.312388 -286.767523)
			(xy 150.320168 -286.768035) (xy 150.324058 -286.767778) (xy 150.327614 -286.76727) (xy 150.332694 -286.766254)
			(xy 150.34514 -286.76092) (xy 150.418546 -286.718248) (xy 150.420324 -286.717232) (xy 150.427377 -286.712388)
			(xy 150.438018 -286.699001) (xy 150.443654 -286.682856) (xy 150.443946 -286.674306) (xy 150.443946 -284.312868)
			(xy 150.443729 -284.306264) (xy 150.440262 -284.293517) (xy 150.437088 -284.287722) (xy 150.433786 -284.28188)
			(xy 150.424642 -284.272736) (xy 150.418546 -284.26918) (xy 150.34514 -284.226508) (xy 150.332694 -284.221174)
			(xy 150.327614 -284.220158) (xy 150.324058 -284.21965) (xy 150.320168 -284.219364) (xy 150.312383 -284.219873)
			(xy 150.308564 -284.220666) (xy 150.292308 -284.224984) (xy 150.28672 -284.228032) (xy 150.258435 -284.242809)
			(xy 150.198159 -284.263757) (xy 150.135238 -284.274381) (xy 150.103332 -284.275022) (xy 150.103078 -284.275022)
			(xy 150.075827 -284.274535) (xy 150.021879 -284.266775) (xy 149.969585 -284.251418) (xy 149.920009 -284.228775)
			(xy 149.87416 -284.199307) (xy 149.832971 -284.163614) (xy 149.79728 -284.122423) (xy 149.767815 -284.076572)
			(xy 149.745175 -284.026994) (xy 149.72982 -283.974699) (xy 149.722064 -283.920751) (xy 149.722064 -283.866249)
			(xy 149.72982 -283.812301) (xy 149.745175 -283.760006) (xy 149.767815 -283.710428) (xy 149.79728 -283.664577)
			(xy 149.832971 -283.623386) (xy 149.87416 -283.587693) (xy 149.920009 -283.558225) (xy 149.969585 -283.535582)
			(xy 150.021879 -283.520225) (xy 150.075827 -283.512465) (xy 150.103078 -283.512006) (xy 150.103332 -283.512006)
			(xy 150.135235 -283.512671) (xy 150.19815 -283.523309) (xy 150.25843 -283.544234) (xy 150.28672 -283.558996)
			(xy 150.292308 -283.562044) (xy 150.308564 -283.566362) (xy 150.312388 -283.567123) (xy 150.320168 -283.567635)
			(xy 150.324058 -283.567378) (xy 150.327614 -283.56687) (xy 150.332694 -283.565854) (xy 150.34514 -283.56052)
			(xy 150.418546 -283.517848) (xy 150.420324 -283.516832) (xy 150.427377 -283.511988) (xy 150.438018 -283.498601)
			(xy 150.443654 -283.482456) (xy 150.443946 -283.473906) (xy 150.443946 -281.112468) (xy 150.443729 -281.105864)
			(xy 150.440262 -281.093117) (xy 150.437088 -281.087322) (xy 150.433786 -281.08148) (xy 150.424642 -281.072336)
			(xy 150.418546 -281.06878) (xy 150.34514 -281.026108) (xy 150.332694 -281.020774) (xy 150.327614 -281.019758)
			(xy 150.324058 -281.01925) (xy 150.320168 -281.018964) (xy 150.312383 -281.019473) (xy 150.308564 -281.020266)
			(xy 150.292308 -281.024584) (xy 150.28672 -281.027632) (xy 150.258435 -281.042409) (xy 150.198159 -281.063357)
			(xy 150.135238 -281.073981) (xy 150.103332 -281.074622) (xy 150.103078 -281.074622) (xy 150.075827 -281.074135)
			(xy 150.021879 -281.066375) (xy 149.969585 -281.051018) (xy 149.920009 -281.028375) (xy 149.87416 -280.998907)
			(xy 149.832971 -280.963214) (xy 149.79728 -280.922023) (xy 149.767815 -280.876172) (xy 149.745175 -280.826594)
			(xy 149.72982 -280.774299) (xy 149.722064 -280.720351) (xy 149.722064 -280.665849) (xy 149.72982 -280.611901)
			(xy 149.745175 -280.559606) (xy 149.767815 -280.510028) (xy 149.79728 -280.464177) (xy 149.832971 -280.422986)
			(xy 149.87416 -280.387293) (xy 149.920009 -280.357825) (xy 149.969585 -280.335182) (xy 150.021879 -280.319825)
			(xy 150.075827 -280.312065) (xy 150.103078 -280.311606) (xy 150.103332 -280.311606) (xy 150.135235 -280.312271)
			(xy 150.19815 -280.322909) (xy 150.25843 -280.343834) (xy 150.28672 -280.358596) (xy 150.292308 -280.361644)
			(xy 150.308564 -280.365962) (xy 150.312388 -280.366723) (xy 150.320168 -280.367235) (xy 150.324058 -280.366978)
			(xy 150.327614 -280.36647) (xy 150.332694 -280.365454) (xy 150.34514 -280.36012) (xy 150.418546 -280.317448)
			(xy 150.420324 -280.316432) (xy 150.427377 -280.311588) (xy 150.438018 -280.298201) (xy 150.443654 -280.282056)
			(xy 150.443946 -280.273506) (xy 150.443946 -280.044144) (xy 150.443849 -280.039267) (xy 150.44206 -280.029678)
			(xy 150.44039 -280.025094) (xy 150.43658 -280.01595) (xy 150.175976 -279.755346) (xy 150.173125 -279.752641)
			(xy 150.166745 -279.74805) (xy 150.163276 -279.746202) (xy 150.15785 -279.743617) (xy 150.14617 -279.740789)
			(xy 150.140162 -279.740614) (xy 148.305774 -279.740614) (xy 148.302472 -279.740614) (xy 148.292538 -279.741803)
			(xy 148.274643 -279.750705) (xy 148.267674 -279.757886) (xy 148.249386 -279.779984) (xy 148.216874 -279.819354)
			(xy 148.213429 -279.823719) (xy 148.208306 -279.833584) (xy 148.206714 -279.838912) (xy 148.20392 -279.84958)
			(xy 148.205952 -279.86101) (xy 148.209014 -279.878375) (xy 148.21232 -279.913483) (xy 148.212556 -279.931114)
			(xy 148.21207 -279.958365) (xy 148.204314 -280.012313) (xy 148.188959 -280.064608) (xy 148.166317 -280.114185)
			(xy 148.136851 -280.160035) (xy 148.10116 -280.201226) (xy 148.059969 -280.236917) (xy 148.014119 -280.266383)
			(xy 147.964542 -280.289025) (xy 147.912247 -280.30438) (xy 147.858299 -280.312136) (xy 147.803797 -280.312136)
			(xy 147.749849 -280.30438) (xy 147.697554 -280.289025) (xy 147.647977 -280.266383) (xy 147.602127 -280.236917)
			(xy 147.560936 -280.201226) (xy 147.525245 -280.160035) (xy 147.495779 -280.114185) (xy 147.473137 -280.064608)
			(xy 147.457782 -280.012313) (xy 147.450026 -279.958365) (xy 147.44954 -279.931114) (xy 147.44954 -279.930352)
			(xy 147.450189 -279.899107) (xy 147.460401 -279.837456) (xy 147.46986 -279.80767) (xy 147.472654 -279.799796)
			(xy 147.472654 -279.791414) (xy 147.472236 -279.781394) (xy 147.464567 -279.76288) (xy 147.450393 -279.748715)
			(xy 147.431874 -279.741058) (xy 147.421854 -279.740614) (xy 147.385786 -279.740614) (xy 147.375781 -279.741105)
			(xy 147.357297 -279.748767) (xy 147.343151 -279.76292) (xy 147.335499 -279.781409) (xy 147.334986 -279.791414)
			(xy 147.334986 -283.893514) (xy 147.43811 -283.893514) (xy 147.438654 -283.864132) (xy 147.447683 -283.806065)
			(xy 147.465514 -283.750071) (xy 147.491725 -283.697475) (xy 147.525695 -283.649524) (xy 147.56662 -283.607352)
			(xy 147.589748 -283.589222) (xy 147.598672 -283.581742) (xy 147.609132 -283.560968) (xy 147.609814 -283.549344)
			(xy 147.611084 -283.457396) (xy 147.601178 -283.436314) (xy 147.592034 -283.428948) (xy 147.570186 -283.410742)
			(xy 147.531644 -283.368924) (xy 147.499736 -283.321849) (xy 147.475169 -283.270559) (xy 147.458486 -283.216191)
			(xy 147.450058 -283.159949) (xy 147.44954 -283.131514) (xy 147.450026 -283.104263) (xy 147.457782 -283.050315)
			(xy 147.473137 -282.99802) (xy 147.495779 -282.948443) (xy 147.525245 -282.902593) (xy 147.560936 -282.861402)
			(xy 147.602127 -282.825711) (xy 147.647977 -282.796245) (xy 147.697554 -282.773603) (xy 147.749849 -282.758248)
			(xy 147.803797 -282.750492) (xy 147.858299 -282.750492) (xy 147.912247 -282.758248) (xy 147.964542 -282.773603)
			(xy 148.014119 -282.796245) (xy 148.059969 -282.825711) (xy 148.10116 -282.861402) (xy 148.136851 -282.902593)
			(xy 148.166317 -282.948443) (xy 148.188959 -282.99802) (xy 148.204314 -283.050315) (xy 148.21207 -283.104263)
			(xy 148.212556 -283.131514) (xy 148.212006 -283.160896) (xy 148.202975 -283.218961) (xy 148.185143 -283.274954)
			(xy 148.158933 -283.327549) (xy 148.124966 -283.375501) (xy 148.084044 -283.417674) (xy 148.060918 -283.435806)
			(xy 148.051975 -283.443267) (xy 148.041527 -283.464056) (xy 148.040852 -283.475684) (xy 148.039582 -283.567632)
			(xy 148.049488 -283.588714) (xy 148.058632 -283.59608) (xy 148.080459 -283.614309) (xy 148.118999 -283.656124)
			(xy 148.150908 -283.703195) (xy 148.175478 -283.75448) (xy 148.192166 -283.808843) (xy 148.200603 -283.865081)
			(xy 148.201126 -283.893514) (xy 148.8346 -283.893514) (xy 148.838671 -283.837892) (xy 148.850797 -283.783455)
			(xy 148.87072 -283.731364) (xy 148.898016 -283.682729) (xy 148.932102 -283.638586) (xy 148.972251 -283.599877)
			(xy 149.017609 -283.567426) (xy 149.067209 -283.541925) (xy 149.119993 -283.523918) (xy 149.174836 -283.513788)
			(xy 149.23057 -283.511751) (xy 149.286007 -283.517851) (xy 149.339964 -283.531957) (xy 149.391293 -283.553769)
			(xy 149.438899 -283.582823) (xy 149.481767 -283.618498) (xy 149.518984 -283.660035) (xy 149.549757 -283.706548)
			(xy 149.573429 -283.757045) (xy 149.589497 -283.810452) (xy 149.597617 -283.865628) (xy 149.598126 -283.893514)
			(xy 149.597617 -283.9214) (xy 149.589497 -283.976576) (xy 149.573429 -284.029983) (xy 149.549757 -284.08048)
			(xy 149.518984 -284.126993) (xy 149.481767 -284.16853) (xy 149.438899 -284.204205) (xy 149.391293 -284.233259)
			(xy 149.339964 -284.255071) (xy 149.286007 -284.269177) (xy 149.23057 -284.275277) (xy 149.174836 -284.27324)
			(xy 149.119993 -284.26311) (xy 149.067209 -284.245103) (xy 149.017609 -284.219602) (xy 148.972251 -284.187151)
			(xy 148.932102 -284.148442) (xy 148.898016 -284.104299) (xy 148.87072 -284.055664) (xy 148.850797 -284.003573)
			(xy 148.838671 -283.949136) (xy 148.8346 -283.893514) (xy 148.201126 -283.893514) (xy 148.20064 -283.920765)
			(xy 148.192884 -283.974713) (xy 148.177529 -284.027008) (xy 148.154887 -284.076585) (xy 148.125421 -284.122435)
			(xy 148.08973 -284.163626) (xy 148.048539 -284.199317) (xy 148.002689 -284.228783) (xy 147.953112 -284.251425)
			(xy 147.900817 -284.26678) (xy 147.846869 -284.274536) (xy 147.792367 -284.274536) (xy 147.738419 -284.26678)
			(xy 147.686124 -284.251425) (xy 147.636547 -284.228783) (xy 147.590697 -284.199317) (xy 147.549506 -284.163626)
			(xy 147.513815 -284.122435) (xy 147.484349 -284.076585) (xy 147.461707 -284.027008) (xy 147.446352 -283.974713)
			(xy 147.438596 -283.920765) (xy 147.43811 -283.893514) (xy 147.334986 -283.893514) (xy 147.334986 -287.093914)
			(xy 147.43811 -287.093914) (xy 147.438654 -287.064532) (xy 147.447683 -287.006465) (xy 147.465514 -286.950471)
			(xy 147.491725 -286.897875) (xy 147.525695 -286.849924) (xy 147.56662 -286.807752) (xy 147.589748 -286.789622)
			(xy 147.598672 -286.782142) (xy 147.609132 -286.761368) (xy 147.609814 -286.749744) (xy 147.611084 -286.657796)
			(xy 147.601178 -286.636714) (xy 147.592034 -286.629348) (xy 147.570186 -286.611142) (xy 147.531644 -286.569324)
			(xy 147.499736 -286.522249) (xy 147.475169 -286.470959) (xy 147.458486 -286.416591) (xy 147.450058 -286.360349)
			(xy 147.44954 -286.331914) (xy 147.450026 -286.304663) (xy 147.457782 -286.250715) (xy 147.473137 -286.19842)
			(xy 147.495779 -286.148843) (xy 147.525245 -286.102993) (xy 147.560936 -286.061802) (xy 147.602127 -286.026111)
			(xy 147.647977 -285.996645) (xy 147.697554 -285.974003) (xy 147.749849 -285.958648) (xy 147.803797 -285.950892)
			(xy 147.858299 -285.950892) (xy 147.912247 -285.958648) (xy 147.964542 -285.974003) (xy 148.014119 -285.996645)
			(xy 148.059969 -286.026111) (xy 148.10116 -286.061802) (xy 148.136851 -286.102993) (xy 148.166317 -286.148843)
			(xy 148.188959 -286.19842) (xy 148.204314 -286.250715) (xy 148.21207 -286.304663) (xy 148.212556 -286.331914)
			(xy 148.212006 -286.361296) (xy 148.202975 -286.419361) (xy 148.185143 -286.475354) (xy 148.158933 -286.527949)
			(xy 148.124966 -286.575901) (xy 148.084044 -286.618074) (xy 148.060918 -286.636206) (xy 148.051975 -286.643667)
			(xy 148.041527 -286.664456) (xy 148.040852 -286.676084) (xy 148.039582 -286.768032) (xy 148.049488 -286.789114)
			(xy 148.058632 -286.79648) (xy 148.080459 -286.814709) (xy 148.118999 -286.856524) (xy 148.150908 -286.903595)
			(xy 148.175478 -286.95488) (xy 148.192166 -287.009243) (xy 148.200603 -287.065481) (xy 148.201126 -287.093914)
			(xy 148.8346 -287.093914) (xy 148.838671 -287.038292) (xy 148.850797 -286.983855) (xy 148.87072 -286.931764)
			(xy 148.898016 -286.883129) (xy 148.932102 -286.838986) (xy 148.972251 -286.800277) (xy 149.017609 -286.767826)
			(xy 149.067209 -286.742325) (xy 149.119993 -286.724318) (xy 149.174836 -286.714188) (xy 149.23057 -286.712151)
			(xy 149.286007 -286.718251) (xy 149.339964 -286.732357) (xy 149.391293 -286.754169) (xy 149.438899 -286.783223)
			(xy 149.481767 -286.818898) (xy 149.518984 -286.860435) (xy 149.549757 -286.906948) (xy 149.573429 -286.957445)
			(xy 149.589497 -287.010852) (xy 149.597617 -287.066028) (xy 149.598126 -287.093914) (xy 149.597617 -287.1218)
			(xy 149.589497 -287.176976) (xy 149.573429 -287.230383) (xy 149.549757 -287.28088) (xy 149.518984 -287.327393)
			(xy 149.481767 -287.36893) (xy 149.438899 -287.404605) (xy 149.391293 -287.433659) (xy 149.339964 -287.455471)
			(xy 149.286007 -287.469577) (xy 149.23057 -287.475677) (xy 149.174836 -287.47364) (xy 149.119993 -287.46351)
			(xy 149.067209 -287.445503) (xy 149.017609 -287.420002) (xy 148.972251 -287.387551) (xy 148.932102 -287.348842)
			(xy 148.898016 -287.304699) (xy 148.87072 -287.256064) (xy 148.850797 -287.203973) (xy 148.838671 -287.149536)
			(xy 148.8346 -287.093914) (xy 148.201126 -287.093914) (xy 148.20064 -287.121165) (xy 148.192884 -287.175113)
			(xy 148.177529 -287.227408) (xy 148.154887 -287.276985) (xy 148.125421 -287.322835) (xy 148.08973 -287.364026)
			(xy 148.048539 -287.399717) (xy 148.002689 -287.429183) (xy 147.953112 -287.451825) (xy 147.900817 -287.46718)
			(xy 147.846869 -287.474936) (xy 147.792367 -287.474936) (xy 147.738419 -287.46718) (xy 147.686124 -287.451825)
			(xy 147.636547 -287.429183) (xy 147.590697 -287.399717) (xy 147.549506 -287.364026) (xy 147.513815 -287.322835)
			(xy 147.484349 -287.276985) (xy 147.461707 -287.227408) (xy 147.446352 -287.175113) (xy 147.438596 -287.121165)
			(xy 147.43811 -287.093914) (xy 147.334986 -287.093914) (xy 147.334986 -290.294314) (xy 147.43811 -290.294314)
			(xy 147.438654 -290.264932) (xy 147.447683 -290.206865) (xy 147.465514 -290.150871) (xy 147.491725 -290.098275)
			(xy 147.525695 -290.050324) (xy 147.56662 -290.008152) (xy 147.589748 -289.990022) (xy 147.598672 -289.982542)
			(xy 147.609132 -289.961768) (xy 147.609814 -289.950144) (xy 147.611084 -289.858196) (xy 147.601178 -289.837114)
			(xy 147.592034 -289.829748) (xy 147.570186 -289.811542) (xy 147.531644 -289.769724) (xy 147.499736 -289.722649)
			(xy 147.475169 -289.671359) (xy 147.458486 -289.616991) (xy 147.450058 -289.560749) (xy 147.44954 -289.532314)
			(xy 147.450026 -289.505063) (xy 147.457782 -289.451115) (xy 147.473137 -289.39882) (xy 147.495779 -289.349243)
			(xy 147.525245 -289.303393) (xy 147.560936 -289.262202) (xy 147.602127 -289.226511) (xy 147.647977 -289.197045)
			(xy 147.697554 -289.174403) (xy 147.749849 -289.159048) (xy 147.803797 -289.151292) (xy 147.858299 -289.151292)
			(xy 147.912247 -289.159048) (xy 147.964542 -289.174403) (xy 148.014119 -289.197045) (xy 148.059969 -289.226511)
			(xy 148.10116 -289.262202) (xy 148.136851 -289.303393) (xy 148.166317 -289.349243) (xy 148.188959 -289.39882)
			(xy 148.204314 -289.451115) (xy 148.21207 -289.505063) (xy 148.212556 -289.532314) (xy 148.212006 -289.561696)
			(xy 148.202975 -289.619761) (xy 148.185143 -289.675754) (xy 148.158933 -289.728349) (xy 148.124966 -289.776301)
			(xy 148.084044 -289.818474) (xy 148.060918 -289.836606) (xy 148.051975 -289.844067) (xy 148.041527 -289.864856)
			(xy 148.040852 -289.876484) (xy 148.039582 -289.968432) (xy 148.049488 -289.989514) (xy 148.058632 -289.99688)
			(xy 148.080459 -290.015109) (xy 148.118999 -290.056924) (xy 148.150908 -290.103995) (xy 148.175478 -290.15528)
			(xy 148.192166 -290.209643) (xy 148.200603 -290.265881) (xy 148.201126 -290.294314) (xy 148.8346 -290.294314)
			(xy 148.838671 -290.238692) (xy 148.850797 -290.184255) (xy 148.87072 -290.132164) (xy 148.898016 -290.083529)
			(xy 148.932102 -290.039386) (xy 148.972251 -290.000677) (xy 149.017609 -289.968226) (xy 149.067209 -289.942725)
			(xy 149.119993 -289.924718) (xy 149.174836 -289.914588) (xy 149.23057 -289.912551) (xy 149.286007 -289.918651)
			(xy 149.339964 -289.932757) (xy 149.391293 -289.954569) (xy 149.438899 -289.983623) (xy 149.481767 -290.019298)
			(xy 149.518984 -290.060835) (xy 149.549757 -290.107348) (xy 149.573429 -290.157845) (xy 149.589497 -290.211252)
			(xy 149.597617 -290.266428) (xy 149.598126 -290.294314) (xy 149.72106 -290.294314) (xy 149.725131 -290.238692)
			(xy 149.737257 -290.184255) (xy 149.75718 -290.132164) (xy 149.784476 -290.083529) (xy 149.818562 -290.039386)
			(xy 149.858711 -290.000677) (xy 149.904069 -289.968226) (xy 149.953669 -289.942725) (xy 150.006453 -289.924718)
			(xy 150.061296 -289.914588) (xy 150.11703 -289.912551) (xy 150.172467 -289.918651) (xy 150.226424 -289.932757)
			(xy 150.277753 -289.954569) (xy 150.325359 -289.983623) (xy 150.368227 -290.019298) (xy 150.405444 -290.060835)
			(xy 150.436217 -290.107348) (xy 150.459889 -290.157845) (xy 150.475957 -290.211252) (xy 150.484077 -290.266428)
			(xy 150.484586 -290.294314) (xy 150.484077 -290.3222) (xy 150.475957 -290.377376) (xy 150.459889 -290.430783)
			(xy 150.436217 -290.48128) (xy 150.405444 -290.527793) (xy 150.368227 -290.56933) (xy 150.325359 -290.605005)
			(xy 150.277753 -290.634059) (xy 150.226424 -290.655871) (xy 150.172467 -290.669977) (xy 150.11703 -290.676077)
			(xy 150.061296 -290.67404) (xy 150.006453 -290.66391) (xy 149.953669 -290.645903) (xy 149.904069 -290.620402)
			(xy 149.858711 -290.587951) (xy 149.818562 -290.549242) (xy 149.784476 -290.505099) (xy 149.75718 -290.456464)
			(xy 149.737257 -290.404373) (xy 149.725131 -290.349936) (xy 149.72106 -290.294314) (xy 149.598126 -290.294314)
			(xy 149.597617 -290.3222) (xy 149.589497 -290.377376) (xy 149.573429 -290.430783) (xy 149.549757 -290.48128)
			(xy 149.518984 -290.527793) (xy 149.481767 -290.56933) (xy 149.438899 -290.605005) (xy 149.391293 -290.634059)
			(xy 149.339964 -290.655871) (xy 149.286007 -290.669977) (xy 149.23057 -290.676077) (xy 149.174836 -290.67404)
			(xy 149.119993 -290.66391) (xy 149.067209 -290.645903) (xy 149.017609 -290.620402) (xy 148.972251 -290.587951)
			(xy 148.932102 -290.549242) (xy 148.898016 -290.505099) (xy 148.87072 -290.456464) (xy 148.850797 -290.404373)
			(xy 148.838671 -290.349936) (xy 148.8346 -290.294314) (xy 148.201126 -290.294314) (xy 148.20064 -290.321565)
			(xy 148.192884 -290.375513) (xy 148.177529 -290.427808) (xy 148.154887 -290.477385) (xy 148.125421 -290.523235)
			(xy 148.08973 -290.564426) (xy 148.048539 -290.600117) (xy 148.002689 -290.629583) (xy 147.953112 -290.652225)
			(xy 147.900817 -290.66758) (xy 147.846869 -290.675336) (xy 147.792367 -290.675336) (xy 147.738419 -290.66758)
			(xy 147.686124 -290.652225) (xy 147.636547 -290.629583) (xy 147.590697 -290.600117) (xy 147.549506 -290.564426)
			(xy 147.513815 -290.523235) (xy 147.484349 -290.477385) (xy 147.461707 -290.427808) (xy 147.446352 -290.375513)
			(xy 147.438596 -290.321565) (xy 147.43811 -290.294314) (xy 147.334986 -290.294314) (xy 147.334986 -292.278054)
			(xy 147.335748 -292.286436) (xy 147.337265 -292.29404) (xy 147.344254 -292.307871) (xy 147.349464 -292.313614)
			(xy 147.479512 -292.443662) (xy 147.487894 -292.45052) (xy 147.493536 -292.453843) (xy 147.506009 -292.457819)
			(xy 147.512532 -292.458394) (xy 147.536154 -292.458648) (xy 147.540895 -292.458594) (xy 147.550231 -292.456942)
			(xy 147.554696 -292.455346) (xy 147.57908 -292.445948) (xy 147.58289 -292.4429) (xy 147.603733 -292.425688)
			(xy 147.649354 -292.396693) (xy 147.698607 -292.374419) (xy 147.750508 -292.35931) (xy 147.804021 -292.351668)
			(xy 147.831048 -292.351206) (xy 147.858297 -292.351696) (xy 147.912238 -292.359458) (xy 147.964526 -292.374817)
			(xy 148.014097 -292.397461) (xy 148.05994 -292.426929) (xy 148.101123 -292.462621) (xy 148.136808 -292.50381)
			(xy 148.166269 -292.549658) (xy 148.177831 -292.57498) (xy 152.169126 -292.57498) (xy 152.173086 -292.525926)
			(xy 152.184863 -292.478142) (xy 152.204154 -292.432866) (xy 152.230457 -292.39127) (xy 152.263092 -292.354433)
			(xy 152.301213 -292.323308) (xy 152.343834 -292.298701) (xy 152.38985 -292.281249) (xy 152.438069 -292.271405)
			(xy 152.487244 -292.269424) (xy 152.536099 -292.275356) (xy 152.58337 -292.289048) (xy 152.627832 -292.310146)
			(xy 152.668335 -292.338102) (xy 152.703828 -292.372194) (xy 152.733393 -292.411538) (xy 152.756264 -292.455115)
			(xy 152.771848 -292.501796) (xy 152.779743 -292.550373) (xy 152.780238 -292.57498) (xy 152.779743 -292.599587)
			(xy 152.771848 -292.648164) (xy 152.756264 -292.694845) (xy 152.733393 -292.738422) (xy 152.703828 -292.777766)
			(xy 152.668335 -292.811858) (xy 152.627832 -292.839814) (xy 152.58337 -292.860912) (xy 152.536099 -292.874604)
			(xy 152.487244 -292.880536) (xy 152.438069 -292.878555) (xy 152.38985 -292.868711) (xy 152.343834 -292.851259)
			(xy 152.301213 -292.826652) (xy 152.263092 -292.795527) (xy 152.230457 -292.75869) (xy 152.204154 -292.717094)
			(xy 152.184863 -292.671818) (xy 152.173086 -292.624034) (xy 152.169126 -292.57498) (xy 148.177831 -292.57498)
			(xy 148.188905 -292.599232) (xy 148.204256 -292.651522) (xy 148.212009 -292.705465) (xy 148.212556 -292.732714)
			(xy 148.212075 -292.760212) (xy 148.204182 -292.814638) (xy 148.18856 -292.867368) (xy 148.165533 -292.917311)
			(xy 148.135579 -292.963433) (xy 148.117814 -292.984428) (xy 148.111964 -292.991692) (xy 148.105431 -293.009144)
			(xy 148.105114 -293.018464) (xy 148.105368 -293.048944) (xy 148.105942 -293.058866) (xy 148.113658 -293.077159)
			(xy 148.120354 -293.084504) (xy 148.530564 -293.494714) (xy 148.8346 -293.494714) (xy 148.838671 -293.439092)
			(xy 148.850797 -293.384655) (xy 148.87072 -293.332564) (xy 148.898016 -293.283929) (xy 148.932102 -293.239786)
			(xy 148.972251 -293.201077) (xy 149.017609 -293.168626) (xy 149.067209 -293.143125) (xy 149.119993 -293.125118)
			(xy 149.174836 -293.114988) (xy 149.23057 -293.112951) (xy 149.286007 -293.119051) (xy 149.339964 -293.133157)
			(xy 149.391293 -293.154969) (xy 149.438899 -293.184023) (xy 149.481767 -293.219698) (xy 149.518984 -293.261235)
			(xy 149.549757 -293.307748) (xy 149.573429 -293.358245) (xy 149.589497 -293.411652) (xy 149.597617 -293.466828)
			(xy 149.598126 -293.494714) (xy 149.72106 -293.494714) (xy 149.725131 -293.439092) (xy 149.737257 -293.384655)
			(xy 149.75718 -293.332564) (xy 149.784476 -293.283929) (xy 149.818562 -293.239786) (xy 149.858711 -293.201077)
			(xy 149.904069 -293.168626) (xy 149.953669 -293.143125) (xy 150.006453 -293.125118) (xy 150.061296 -293.114988)
			(xy 150.11703 -293.112951) (xy 150.172467 -293.119051) (xy 150.226424 -293.133157) (xy 150.277753 -293.154969)
			(xy 150.325359 -293.184023) (xy 150.368227 -293.219698) (xy 150.405444 -293.261235) (xy 150.436217 -293.307748)
			(xy 150.459889 -293.358245) (xy 150.475957 -293.411652) (xy 150.484077 -293.466828) (xy 150.484586 -293.494714)
			(xy 150.484077 -293.5226) (xy 150.475957 -293.577776) (xy 150.459889 -293.631183) (xy 150.436217 -293.68168)
			(xy 150.405444 -293.728193) (xy 150.368227 -293.76973) (xy 150.325359 -293.805405) (xy 150.277753 -293.834459)
			(xy 150.226424 -293.856271) (xy 150.172467 -293.870377) (xy 150.11703 -293.876477) (xy 150.061296 -293.87444)
			(xy 150.006453 -293.86431) (xy 149.953669 -293.846303) (xy 149.904069 -293.820802) (xy 149.858711 -293.788351)
			(xy 149.818562 -293.749642) (xy 149.784476 -293.705499) (xy 149.75718 -293.656864) (xy 149.737257 -293.604773)
			(xy 149.725131 -293.550336) (xy 149.72106 -293.494714) (xy 149.598126 -293.494714) (xy 149.597617 -293.5226)
			(xy 149.589497 -293.577776) (xy 149.573429 -293.631183) (xy 149.549757 -293.68168) (xy 149.518984 -293.728193)
			(xy 149.481767 -293.76973) (xy 149.438899 -293.805405) (xy 149.391293 -293.834459) (xy 149.339964 -293.856271)
			(xy 149.286007 -293.870377) (xy 149.23057 -293.876477) (xy 149.174836 -293.87444) (xy 149.119993 -293.86431)
			(xy 149.067209 -293.846303) (xy 149.017609 -293.820802) (xy 148.972251 -293.788351) (xy 148.932102 -293.749642)
			(xy 148.898016 -293.705499) (xy 148.87072 -293.656864) (xy 148.850797 -293.604773) (xy 148.838671 -293.550336)
			(xy 148.8346 -293.494714) (xy 148.530564 -293.494714) (xy 149.51075 -294.4749) (xy 152.169126 -294.4749)
			(xy 152.173086 -294.425846) (xy 152.184863 -294.378062) (xy 152.204154 -294.332786) (xy 152.230457 -294.29119)
			(xy 152.263092 -294.254353) (xy 152.301213 -294.223228) (xy 152.343834 -294.198621) (xy 152.38985 -294.181169)
			(xy 152.438069 -294.171325) (xy 152.487244 -294.169344) (xy 152.536099 -294.175276) (xy 152.58337 -294.188968)
			(xy 152.627832 -294.210066) (xy 152.668335 -294.238022) (xy 152.703828 -294.272114) (xy 152.733393 -294.311458)
			(xy 152.756264 -294.355035) (xy 152.771848 -294.401716) (xy 152.779743 -294.450293) (xy 152.780238 -294.4749)
			(xy 153.119086 -294.4749) (xy 153.123046 -294.425846) (xy 153.134823 -294.378062) (xy 153.154114 -294.332786)
			(xy 153.180417 -294.29119) (xy 153.213052 -294.254353) (xy 153.251173 -294.223228) (xy 153.293794 -294.198621)
			(xy 153.33981 -294.181169) (xy 153.388029 -294.171325) (xy 153.437204 -294.169344) (xy 153.486059 -294.175276)
			(xy 153.53333 -294.188968) (xy 153.577792 -294.210066) (xy 153.618295 -294.238022) (xy 153.653788 -294.272114)
			(xy 153.683353 -294.311458) (xy 153.706224 -294.355035) (xy 153.721808 -294.401716) (xy 153.729703 -294.450293)
			(xy 153.730198 -294.4749) (xy 154.0693 -294.4749) (xy 154.07326 -294.425846) (xy 154.085037 -294.378062)
			(xy 154.104328 -294.332786) (xy 154.130631 -294.29119) (xy 154.163266 -294.254353) (xy 154.201387 -294.223228)
			(xy 154.244008 -294.198621) (xy 154.290024 -294.181169) (xy 154.338243 -294.171325) (xy 154.387418 -294.169344)
			(xy 154.436273 -294.175276) (xy 154.483544 -294.188968) (xy 154.528006 -294.210066) (xy 154.568509 -294.238022)
			(xy 154.604002 -294.272114) (xy 154.633567 -294.311458) (xy 154.656438 -294.355035) (xy 154.672022 -294.401716)
			(xy 154.679917 -294.450293) (xy 154.680412 -294.4749) (xy 154.679917 -294.499507) (xy 154.672022 -294.548084)
			(xy 154.656438 -294.594765) (xy 154.633567 -294.638342) (xy 154.604002 -294.677686) (xy 154.568509 -294.711778)
			(xy 154.528006 -294.739734) (xy 154.483544 -294.760832) (xy 154.436273 -294.774524) (xy 154.387418 -294.780456)
			(xy 154.338243 -294.778475) (xy 154.290024 -294.768631) (xy 154.244008 -294.751179) (xy 154.201387 -294.726572)
			(xy 154.163266 -294.695447) (xy 154.130631 -294.65861) (xy 154.104328 -294.617014) (xy 154.085037 -294.571738)
			(xy 154.07326 -294.523954) (xy 154.0693 -294.4749) (xy 153.730198 -294.4749) (xy 153.729703 -294.499507)
			(xy 153.721808 -294.548084) (xy 153.706224 -294.594765) (xy 153.683353 -294.638342) (xy 153.653788 -294.677686)
			(xy 153.618295 -294.711778) (xy 153.577792 -294.739734) (xy 153.53333 -294.760832) (xy 153.486059 -294.774524)
			(xy 153.437204 -294.780456) (xy 153.388029 -294.778475) (xy 153.33981 -294.768631) (xy 153.293794 -294.751179)
			(xy 153.251173 -294.726572) (xy 153.213052 -294.695447) (xy 153.180417 -294.65861) (xy 153.154114 -294.617014)
			(xy 153.134823 -294.571738) (xy 153.123046 -294.523954) (xy 153.119086 -294.4749) (xy 152.780238 -294.4749)
			(xy 152.779743 -294.499507) (xy 152.771848 -294.548084) (xy 152.756264 -294.594765) (xy 152.733393 -294.638342)
			(xy 152.703828 -294.677686) (xy 152.668335 -294.711778) (xy 152.627832 -294.739734) (xy 152.58337 -294.760832)
			(xy 152.536099 -294.774524) (xy 152.487244 -294.780456) (xy 152.438069 -294.778475) (xy 152.38985 -294.768631)
			(xy 152.343834 -294.751179) (xy 152.301213 -294.726572) (xy 152.263092 -294.695447) (xy 152.230457 -294.65861)
			(xy 152.204154 -294.617014) (xy 152.184863 -294.571738) (xy 152.173086 -294.523954) (xy 152.169126 -294.4749)
			(xy 149.51075 -294.4749) (xy 151.41067 -296.37482) (xy 153.11934 -296.37482) (xy 153.1233 -296.325766)
			(xy 153.135077 -296.277982) (xy 153.154368 -296.232706) (xy 153.180671 -296.19111) (xy 153.213306 -296.154273)
			(xy 153.251427 -296.123148) (xy 153.294048 -296.098541) (xy 153.340064 -296.081089) (xy 153.388283 -296.071245)
			(xy 153.437458 -296.069264) (xy 153.486313 -296.075196) (xy 153.533584 -296.088888) (xy 153.578046 -296.109986)
			(xy 153.618549 -296.137942) (xy 153.654042 -296.172034) (xy 153.683607 -296.211378) (xy 153.706478 -296.254955)
			(xy 153.722062 -296.301636) (xy 153.729957 -296.350213) (xy 153.730452 -296.37482) (xy 154.069046 -296.37482)
			(xy 154.073006 -296.325766) (xy 154.084783 -296.277982) (xy 154.104074 -296.232706) (xy 154.130377 -296.19111)
			(xy 154.163012 -296.154273) (xy 154.201133 -296.123148) (xy 154.243754 -296.098541) (xy 154.28977 -296.081089)
			(xy 154.337989 -296.071245) (xy 154.387164 -296.069264) (xy 154.436019 -296.075196) (xy 154.48329 -296.088888)
			(xy 154.527752 -296.109986) (xy 154.568255 -296.137942) (xy 154.603748 -296.172034) (xy 154.633313 -296.211378)
			(xy 154.656184 -296.254955) (xy 154.671768 -296.301636) (xy 154.679663 -296.350213) (xy 154.680158 -296.37482)
			(xy 155.01926 -296.37482) (xy 155.02322 -296.325766) (xy 155.034997 -296.277982) (xy 155.054288 -296.232706)
			(xy 155.080591 -296.19111) (xy 155.113226 -296.154273) (xy 155.151347 -296.123148) (xy 155.193968 -296.098541)
			(xy 155.239984 -296.081089) (xy 155.288203 -296.071245) (xy 155.337378 -296.069264) (xy 155.386233 -296.075196)
			(xy 155.433504 -296.088888) (xy 155.477966 -296.109986) (xy 155.518469 -296.137942) (xy 155.553962 -296.172034)
			(xy 155.583527 -296.211378) (xy 155.606398 -296.254955) (xy 155.621982 -296.301636) (xy 155.629877 -296.350213)
			(xy 155.630372 -296.37482) (xy 155.96922 -296.37482) (xy 155.97318 -296.325766) (xy 155.984957 -296.277982)
			(xy 156.004248 -296.232706) (xy 156.030551 -296.19111) (xy 156.063186 -296.154273) (xy 156.101307 -296.123148)
			(xy 156.143928 -296.098541) (xy 156.189944 -296.081089) (xy 156.238163 -296.071245) (xy 156.287338 -296.069264)
			(xy 156.336193 -296.075196) (xy 156.383464 -296.088888) (xy 156.427926 -296.109986) (xy 156.468429 -296.137942)
			(xy 156.503922 -296.172034) (xy 156.533487 -296.211378) (xy 156.556358 -296.254955) (xy 156.571942 -296.301636)
			(xy 156.579837 -296.350213) (xy 156.580332 -296.37482) (xy 156.579837 -296.399427) (xy 156.571942 -296.448004)
			(xy 156.556358 -296.494685) (xy 156.533487 -296.538262) (xy 156.503922 -296.577606) (xy 156.468429 -296.611698)
			(xy 156.427926 -296.639654) (xy 156.383464 -296.660752) (xy 156.336193 -296.674444) (xy 156.287338 -296.680376)
			(xy 156.238163 -296.678395) (xy 156.189944 -296.668551) (xy 156.143928 -296.651099) (xy 156.101307 -296.626492)
			(xy 156.063186 -296.595367) (xy 156.030551 -296.55853) (xy 156.004248 -296.516934) (xy 155.984957 -296.471658)
			(xy 155.97318 -296.423874) (xy 155.96922 -296.37482) (xy 155.630372 -296.37482) (xy 155.629877 -296.399427)
			(xy 155.621982 -296.448004) (xy 155.606398 -296.494685) (xy 155.583527 -296.538262) (xy 155.553962 -296.577606)
			(xy 155.518469 -296.611698) (xy 155.477966 -296.639654) (xy 155.433504 -296.660752) (xy 155.386233 -296.674444)
			(xy 155.337378 -296.680376) (xy 155.288203 -296.678395) (xy 155.239984 -296.668551) (xy 155.193968 -296.651099)
			(xy 155.151347 -296.626492) (xy 155.113226 -296.595367) (xy 155.080591 -296.55853) (xy 155.054288 -296.516934)
			(xy 155.034997 -296.471658) (xy 155.02322 -296.423874) (xy 155.01926 -296.37482) (xy 154.680158 -296.37482)
			(xy 154.679663 -296.399427) (xy 154.671768 -296.448004) (xy 154.656184 -296.494685) (xy 154.633313 -296.538262)
			(xy 154.603748 -296.577606) (xy 154.568255 -296.611698) (xy 154.527752 -296.639654) (xy 154.48329 -296.660752)
			(xy 154.436019 -296.674444) (xy 154.387164 -296.680376) (xy 154.337989 -296.678395) (xy 154.28977 -296.668551)
			(xy 154.243754 -296.651099) (xy 154.201133 -296.626492) (xy 154.163012 -296.595367) (xy 154.130377 -296.55853)
			(xy 154.104074 -296.516934) (xy 154.084783 -296.471658) (xy 154.073006 -296.423874) (xy 154.069046 -296.37482)
			(xy 153.730452 -296.37482) (xy 153.729957 -296.399427) (xy 153.722062 -296.448004) (xy 153.706478 -296.494685)
			(xy 153.683607 -296.538262) (xy 153.654042 -296.577606) (xy 153.618549 -296.611698) (xy 153.578046 -296.639654)
			(xy 153.533584 -296.660752) (xy 153.486313 -296.674444) (xy 153.437458 -296.680376) (xy 153.388283 -296.678395)
			(xy 153.340064 -296.668551) (xy 153.294048 -296.651099) (xy 153.251427 -296.626492) (xy 153.213306 -296.595367)
			(xy 153.180671 -296.55853) (xy 153.154368 -296.516934) (xy 153.135077 -296.471658) (xy 153.1233 -296.423874)
			(xy 153.11934 -296.37482) (xy 151.41067 -296.37482) (xy 152.11298 -297.07713) (xy 152.120064 -297.083438)
			(xy 152.137551 -297.090747) (xy 152.147016 -297.091354) (xy 152.17775 -297.092116) (xy 152.216866 -297.093132)
			(xy 152.2218 -297.093144) (xy 152.231524 -297.091489) (xy 152.23617 -297.08983) (xy 152.244806 -297.086528)
			(xy 152.252172 -297.079924) (xy 152.270523 -297.063862) (xy 152.311061 -297.036752) (xy 152.355138 -297.015885)
			(xy 152.401801 -297.001714) (xy 152.450038 -296.994544) (xy 152.474422 -296.994072) (xy 153.424636 -296.994072)
			(xy 153.450623 -296.994584) (xy 153.501956 -297.00272) (xy 153.551385 -297.018785) (xy 153.597692 -297.042384)
			(xy 153.639738 -297.072936) (xy 153.676487 -297.109689) (xy 153.707035 -297.151739) (xy 153.730629 -297.198048)
			(xy 153.746689 -297.247479) (xy 153.754819 -297.298813) (xy 153.754819 -297.32478) (xy 154.069046 -297.32478)
			(xy 154.073006 -297.275726) (xy 154.084783 -297.227942) (xy 154.104074 -297.182666) (xy 154.130377 -297.14107)
			(xy 154.163012 -297.104233) (xy 154.201133 -297.073108) (xy 154.243754 -297.048501) (xy 154.28977 -297.031049)
			(xy 154.337989 -297.021205) (xy 154.387164 -297.019224) (xy 154.436019 -297.025156) (xy 154.48329 -297.038848)
			(xy 154.527752 -297.059946) (xy 154.568255 -297.087902) (xy 154.603748 -297.121994) (xy 154.633313 -297.161338)
			(xy 154.656184 -297.204915) (xy 154.671768 -297.251596) (xy 154.679663 -297.300173) (xy 154.680158 -297.32478)
			(xy 155.01926 -297.32478) (xy 155.02322 -297.275726) (xy 155.034997 -297.227942) (xy 155.054288 -297.182666)
			(xy 155.080591 -297.14107) (xy 155.113226 -297.104233) (xy 155.151347 -297.073108) (xy 155.193968 -297.048501)
			(xy 155.239984 -297.031049) (xy 155.288203 -297.021205) (xy 155.337378 -297.019224) (xy 155.386233 -297.025156)
			(xy 155.433504 -297.038848) (xy 155.477966 -297.059946) (xy 155.518469 -297.087902) (xy 155.553962 -297.121994)
			(xy 155.583527 -297.161338) (xy 155.606398 -297.204915) (xy 155.621982 -297.251596) (xy 155.629877 -297.300173)
			(xy 155.630372 -297.32478) (xy 155.629877 -297.349387) (xy 155.621982 -297.397964) (xy 155.606398 -297.444645)
			(xy 155.583527 -297.488222) (xy 155.553962 -297.527566) (xy 155.518469 -297.561658) (xy 155.477966 -297.589614)
			(xy 155.433504 -297.610712) (xy 155.386233 -297.624404) (xy 155.337378 -297.630336) (xy 155.288203 -297.628355)
			(xy 155.239984 -297.618511) (xy 155.193968 -297.601059) (xy 155.151347 -297.576452) (xy 155.113226 -297.545327)
			(xy 155.080591 -297.50849) (xy 155.054288 -297.466894) (xy 155.034997 -297.421618) (xy 155.02322 -297.373834)
			(xy 155.01926 -297.32478) (xy 154.680158 -297.32478) (xy 154.679663 -297.349387) (xy 154.671768 -297.397964)
			(xy 154.656184 -297.444645) (xy 154.633313 -297.488222) (xy 154.603748 -297.527566) (xy 154.568255 -297.561658)
			(xy 154.527752 -297.589614) (xy 154.48329 -297.610712) (xy 154.436019 -297.624404) (xy 154.387164 -297.630336)
			(xy 154.337989 -297.628355) (xy 154.28977 -297.618511) (xy 154.243754 -297.601059) (xy 154.201133 -297.576452)
			(xy 154.163012 -297.545327) (xy 154.130377 -297.50849) (xy 154.104074 -297.466894) (xy 154.084783 -297.421618)
			(xy 154.073006 -297.373834) (xy 154.069046 -297.32478) (xy 153.754819 -297.32478) (xy 153.754819 -297.350787)
			(xy 153.746689 -297.402121) (xy 153.730629 -297.451552) (xy 153.707035 -297.497861) (xy 153.676487 -297.539911)
			(xy 153.639738 -297.576664) (xy 153.597692 -297.607216) (xy 153.551385 -297.630815) (xy 153.501956 -297.64688)
			(xy 153.450623 -297.655016) (xy 153.424636 -297.655488) (xy 152.814274 -297.655488) (xy 152.807162 -297.655996)
			(xy 152.794762 -297.658445) (xy 152.774406 -297.673375) (xy 152.7683 -297.684444) (xy 152.764744 -297.692572)
			(xy 152.761188 -297.701462) (xy 152.763982 -297.71594) (xy 152.76572 -297.723279) (xy 152.772816 -297.73658)
			(xy 152.777952 -297.742102) (xy 152.843738 -297.807888) (xy 152.846312 -297.810399) (xy 152.852045 -297.814741)
			(xy 152.855168 -297.816524) (xy 152.860756 -297.819572) (xy 152.867614 -297.82135) (xy 152.897164 -297.82896)
			(xy 152.954531 -297.849768) (xy 153.009286 -297.876711) (xy 153.060773 -297.909466) (xy 153.10838 -297.947643)
			(xy 153.13025 -297.968924) (xy 153.164286 -298.002706) (xy 153.170927 -298.008827) (xy 153.187322 -298.016374)
			(xy 153.19629 -298.017438) (xy 153.204926 -298.017946) (xy 153.222452 -298.01312) (xy 153.229818 -298.007532)
			(xy 153.251162 -297.992579) (xy 153.297566 -297.968864) (xy 153.347114 -297.952718) (xy 153.39858 -297.944539)
			(xy 153.424636 -297.944032) (xy 153.450111 -297.944497) (xy 153.50046 -297.9523) (xy 153.549017 -297.967731)
			(xy 153.594633 -297.990425) (xy 153.63623 -298.019846) (xy 153.672823 -298.055298) (xy 153.688542 -298.07535)
			(xy 153.692323 -298.080095) (xy 153.701699 -298.087792) (xy 153.707084 -298.09059) (xy 153.710671 -298.092164)
			(xy 153.718195 -298.094339) (xy 153.72207 -298.094908) (xy 153.729182 -298.095416) (xy 154.102816 -298.095416)
			(xy 154.112722 -298.0944) (xy 154.121072 -298.092398) (xy 154.135871 -298.083707) (xy 154.141678 -298.077382)
			(xy 154.15925 -298.057519) (xy 154.199998 -298.023585) (xy 154.245993 -297.997195) (xy 154.295854 -297.979143)
			(xy 154.348082 -297.96997) (xy 154.374596 -297.969432) (xy 154.37485 -297.969432) (xy 154.387544 -297.969535)
			(xy 154.412849 -297.971571) (xy 154.425396 -297.973496) (xy 154.448518 -297.977818) (xy 154.493167 -297.992621)
			(xy 154.514296 -298.00296) (xy 154.540794 -298.017344) (xy 154.588005 -298.054835) (xy 154.608022 -298.077382)
			(xy 154.613807 -298.083738) (xy 154.628609 -298.092446) (xy 154.636978 -298.0944) (xy 154.646884 -298.095416)
			(xy 155.053284 -298.095416) (xy 155.057348 -298.095162) (xy 155.072447 -298.073564) (xy 155.108505 -298.035139)
			(xy 155.150334 -298.003092) (xy 155.196821 -297.978279) (xy 155.246725 -297.96136) (xy 155.298717 -297.952786)
			(xy 155.351411 -297.952786) (xy 155.403403 -297.96136) (xy 155.453307 -297.978279) (xy 155.499794 -298.003092)
			(xy 155.541623 -298.035139) (xy 155.577681 -298.073564) (xy 155.59278 -298.095162) (xy 155.596844 -298.095416)
			(xy 155.654248 -298.095416) (xy 155.684574 -298.095849) (xy 155.744863 -298.102485) (xy 155.80408 -298.11561)
			(xy 155.861527 -298.135069) (xy 155.889198 -298.147486) (xy 155.897834 -298.15155) (xy 155.90647 -298.152312)
			(xy 155.911147 -298.152631) (xy 155.920478 -298.151729) (xy 155.925012 -298.150534) (xy 155.956762 -298.141136)
			(xy 155.95727 -298.141136) (xy 155.990036 -298.13123) (xy 155.99418 -298.129846) (xy 156.001968 -298.125886)
			(xy 156.00553 -298.123356) (xy 156.012134 -298.11853) (xy 156.017722 -298.110148) (xy 156.03191 -298.088943)
			(xy 156.066176 -298.051146) (xy 156.106245 -298.019567) (xy 156.151003 -297.995083) (xy 156.199206 -297.978373)
			(xy 156.249515 -297.969902) (xy 156.275024 -297.969432) (xy 156.299015 -297.96988) (xy 156.346405 -297.97739)
			(xy 156.392037 -297.992221) (xy 156.434787 -298.014008) (xy 156.473602 -298.042215) (xy 156.507526 -298.076147)
			(xy 156.535725 -298.114968) (xy 156.557503 -298.157722) (xy 156.572325 -298.203357) (xy 156.579825 -298.250749)
			(xy 156.580332 -298.27474) (xy 156.91918 -298.27474) (xy 156.92314 -298.225686) (xy 156.934917 -298.177902)
			(xy 156.954208 -298.132626) (xy 156.980511 -298.09103) (xy 157.013146 -298.054193) (xy 157.051267 -298.023068)
			(xy 157.093888 -297.998461) (xy 157.139904 -297.981009) (xy 157.188123 -297.971165) (xy 157.237298 -297.969184)
			(xy 157.286153 -297.975116) (xy 157.333424 -297.988808) (xy 157.377886 -298.009906) (xy 157.418389 -298.037862)
			(xy 157.453882 -298.071954) (xy 157.483447 -298.111298) (xy 157.506318 -298.154875) (xy 157.521902 -298.201556)
			(xy 157.529797 -298.250133) (xy 157.530292 -298.27474) (xy 157.86914 -298.27474) (xy 157.8731 -298.225686)
			(xy 157.884877 -298.177902) (xy 157.904168 -298.132626) (xy 157.930471 -298.09103) (xy 157.963106 -298.054193)
			(xy 158.001227 -298.023068) (xy 158.043848 -297.998461) (xy 158.089864 -297.981009) (xy 158.138083 -297.971165)
			(xy 158.187258 -297.969184) (xy 158.236113 -297.975116) (xy 158.283384 -297.988808) (xy 158.327846 -298.009906)
			(xy 158.368349 -298.037862) (xy 158.403842 -298.071954) (xy 158.433407 -298.111298) (xy 158.456278 -298.154875)
			(xy 158.471862 -298.201556) (xy 158.479757 -298.250133) (xy 158.480252 -298.27474) (xy 159.76906 -298.27474)
			(xy 159.77302 -298.225686) (xy 159.784797 -298.177902) (xy 159.804088 -298.132626) (xy 159.830391 -298.09103)
			(xy 159.863026 -298.054193) (xy 159.901147 -298.023068) (xy 159.943768 -297.998461) (xy 159.989784 -297.981009)
			(xy 160.038003 -297.971165) (xy 160.087178 -297.969184) (xy 160.136033 -297.975116) (xy 160.183304 -297.988808)
			(xy 160.227766 -298.009906) (xy 160.268269 -298.037862) (xy 160.303762 -298.071954) (xy 160.333327 -298.111298)
			(xy 160.356198 -298.154875) (xy 160.371782 -298.201556) (xy 160.379677 -298.250133) (xy 160.380172 -298.27474)
			(xy 160.719274 -298.27474) (xy 160.723234 -298.225686) (xy 160.735011 -298.177902) (xy 160.754302 -298.132626)
			(xy 160.780605 -298.09103) (xy 160.81324 -298.054193) (xy 160.851361 -298.023068) (xy 160.893982 -297.998461)
			(xy 160.939998 -297.981009) (xy 160.988217 -297.971165) (xy 161.037392 -297.969184) (xy 161.086247 -297.975116)
			(xy 161.133518 -297.988808) (xy 161.17798 -298.009906) (xy 161.218483 -298.037862) (xy 161.253976 -298.071954)
			(xy 161.283541 -298.111298) (xy 161.306412 -298.154875) (xy 161.321996 -298.201556) (xy 161.329891 -298.250133)
			(xy 161.330386 -298.27474) (xy 161.669234 -298.27474) (xy 161.673194 -298.225686) (xy 161.684971 -298.177902)
			(xy 161.704262 -298.132626) (xy 161.730565 -298.09103) (xy 161.7632 -298.054193) (xy 161.801321 -298.023068)
			(xy 161.843942 -297.998461) (xy 161.889958 -297.981009) (xy 161.938177 -297.971165) (xy 161.987352 -297.969184)
			(xy 162.036207 -297.975116) (xy 162.083478 -297.988808) (xy 162.12794 -298.009906) (xy 162.168443 -298.037862)
			(xy 162.203936 -298.071954) (xy 162.233501 -298.111298) (xy 162.256372 -298.154875) (xy 162.271956 -298.201556)
			(xy 162.279851 -298.250133) (xy 162.280346 -298.27474) (xy 162.619194 -298.27474) (xy 162.623154 -298.225686)
			(xy 162.634931 -298.177902) (xy 162.654222 -298.132626) (xy 162.680525 -298.09103) (xy 162.71316 -298.054193)
			(xy 162.751281 -298.023068) (xy 162.793902 -297.998461) (xy 162.839918 -297.981009) (xy 162.888137 -297.971165)
			(xy 162.937312 -297.969184) (xy 162.986167 -297.975116) (xy 163.033438 -297.988808) (xy 163.0779 -298.009906)
			(xy 163.118403 -298.037862) (xy 163.153896 -298.071954) (xy 163.183461 -298.111298) (xy 163.206332 -298.154875)
			(xy 163.221916 -298.201556) (xy 163.229811 -298.250133) (xy 163.230306 -298.27474) (xy 163.229811 -298.299347)
			(xy 163.221916 -298.347924) (xy 163.206332 -298.394605) (xy 163.183461 -298.438182) (xy 163.153896 -298.477526)
			(xy 163.118403 -298.511618) (xy 163.0779 -298.539574) (xy 163.033438 -298.560672) (xy 162.986167 -298.574364)
			(xy 162.937312 -298.580296) (xy 162.888137 -298.578315) (xy 162.839918 -298.568471) (xy 162.793902 -298.551019)
			(xy 162.751281 -298.526412) (xy 162.71316 -298.495287) (xy 162.680525 -298.45845) (xy 162.654222 -298.416854)
			(xy 162.634931 -298.371578) (xy 162.623154 -298.323794) (xy 162.619194 -298.27474) (xy 162.280346 -298.27474)
			(xy 162.279851 -298.299347) (xy 162.271956 -298.347924) (xy 162.256372 -298.394605) (xy 162.233501 -298.438182)
			(xy 162.203936 -298.477526) (xy 162.168443 -298.511618) (xy 162.12794 -298.539574) (xy 162.083478 -298.560672)
			(xy 162.036207 -298.574364) (xy 161.987352 -298.580296) (xy 161.938177 -298.578315) (xy 161.889958 -298.568471)
			(xy 161.843942 -298.551019) (xy 161.801321 -298.526412) (xy 161.7632 -298.495287) (xy 161.730565 -298.45845)
			(xy 161.704262 -298.416854) (xy 161.684971 -298.371578) (xy 161.673194 -298.323794) (xy 161.669234 -298.27474)
			(xy 161.330386 -298.27474) (xy 161.329891 -298.299347) (xy 161.321996 -298.347924) (xy 161.306412 -298.394605)
			(xy 161.283541 -298.438182) (xy 161.253976 -298.477526) (xy 161.218483 -298.511618) (xy 161.17798 -298.539574)
			(xy 161.133518 -298.560672) (xy 161.086247 -298.574364) (xy 161.037392 -298.580296) (xy 160.988217 -298.578315)
			(xy 160.939998 -298.568471) (xy 160.893982 -298.551019) (xy 160.851361 -298.526412) (xy 160.81324 -298.495287)
			(xy 160.780605 -298.45845) (xy 160.754302 -298.416854) (xy 160.735011 -298.371578) (xy 160.723234 -298.323794)
			(xy 160.719274 -298.27474) (xy 160.380172 -298.27474) (xy 160.379677 -298.299347) (xy 160.371782 -298.347924)
			(xy 160.356198 -298.394605) (xy 160.333327 -298.438182) (xy 160.303762 -298.477526) (xy 160.268269 -298.511618)
			(xy 160.227766 -298.539574) (xy 160.183304 -298.560672) (xy 160.136033 -298.574364) (xy 160.087178 -298.580296)
			(xy 160.038003 -298.578315) (xy 159.989784 -298.568471) (xy 159.943768 -298.551019) (xy 159.901147 -298.526412)
			(xy 159.863026 -298.495287) (xy 159.830391 -298.45845) (xy 159.804088 -298.416854) (xy 159.784797 -298.371578)
			(xy 159.77302 -298.323794) (xy 159.76906 -298.27474) (xy 158.480252 -298.27474) (xy 158.479757 -298.299347)
			(xy 158.471862 -298.347924) (xy 158.456278 -298.394605) (xy 158.433407 -298.438182) (xy 158.403842 -298.477526)
			(xy 158.368349 -298.511618) (xy 158.327846 -298.539574) (xy 158.283384 -298.560672) (xy 158.236113 -298.574364)
			(xy 158.187258 -298.580296) (xy 158.138083 -298.578315) (xy 158.089864 -298.568471) (xy 158.043848 -298.551019)
			(xy 158.001227 -298.526412) (xy 157.963106 -298.495287) (xy 157.930471 -298.45845) (xy 157.904168 -298.416854)
			(xy 157.884877 -298.371578) (xy 157.8731 -298.323794) (xy 157.86914 -298.27474) (xy 157.530292 -298.27474)
			(xy 157.529797 -298.299347) (xy 157.521902 -298.347924) (xy 157.506318 -298.394605) (xy 157.483447 -298.438182)
			(xy 157.453882 -298.477526) (xy 157.418389 -298.511618) (xy 157.377886 -298.539574) (xy 157.333424 -298.560672)
			(xy 157.286153 -298.574364) (xy 157.237298 -298.580296) (xy 157.188123 -298.578315) (xy 157.139904 -298.568471)
			(xy 157.093888 -298.551019) (xy 157.051267 -298.526412) (xy 157.013146 -298.495287) (xy 156.980511 -298.45845)
			(xy 156.954208 -298.416854) (xy 156.934917 -298.371578) (xy 156.92314 -298.323794) (xy 156.91918 -298.27474)
			(xy 156.580332 -298.27474) (xy 156.580332 -298.275248) (xy 156.580215 -298.286852) (xy 156.578438 -298.309991)
			(xy 156.576776 -298.321476) (xy 156.576268 -298.324524) (xy 156.576268 -298.32554) (xy 156.571582 -298.350383)
			(xy 156.55509 -298.398169) (xy 156.530954 -298.442588) (xy 156.499835 -298.482426) (xy 156.46258 -298.516596)
			(xy 156.441648 -298.530772) (xy 156.44114 -298.531026) (xy 156.433266 -298.53636) (xy 156.428186 -298.543218)
			(xy 156.42541 -298.547034) (xy 156.421192 -298.555472) (xy 156.419804 -298.559982) (xy 156.401516 -298.624498)
			(xy 156.400363 -298.629103) (xy 156.399598 -298.638563) (xy 156.399992 -298.643294) (xy 156.400754 -298.651676)
			(xy 156.404818 -298.660312) (xy 156.405072 -298.66082) (xy 156.405072 -298.661074) (xy 156.405326 -298.661582)
			(xy 156.406596 -298.664122) (xy 156.407612 -298.666408) (xy 156.412722 -298.675125) (xy 156.428299 -298.687972)
			(xy 156.437838 -298.6913) (xy 156.468154 -298.701017) (xy 156.52654 -298.7264) (xy 156.581655 -298.758266)
			(xy 156.632782 -298.796202) (xy 156.679256 -298.839715) (xy 156.720472 -298.888236) (xy 156.755894 -298.941136)
			(xy 156.785061 -298.997727) (xy 156.79674 -299.027342) (xy 156.79674 -299.027596) (xy 156.799385 -299.033934)
			(xy 156.807492 -299.045013) (xy 156.812742 -299.04944) (xy 156.818076 -299.053758) (xy 156.830776 -299.058838)
			(xy 156.927042 -299.07103) (xy 156.933985 -299.071687) (xy 156.947774 -299.069627) (xy 156.95422 -299.066966)
			(xy 156.960316 -299.064172) (xy 156.97073 -299.05579) (xy 156.975048 -299.049694) (xy 156.989461 -299.029981)
			(xy 157.023507 -298.994975) (xy 157.062689 -298.965832) (xy 157.106008 -298.943295) (xy 157.152362 -298.927936)
			(xy 157.200568 -298.920149) (xy 157.224984 -298.919646) (xy 157.248977 -298.920115) (xy 157.296374 -298.927619)
			(xy 157.342013 -298.942445) (xy 157.384771 -298.964227) (xy 157.423596 -298.992429) (xy 157.457531 -299.026357)
			(xy 157.485741 -299.065176) (xy 157.507532 -299.10793) (xy 157.522366 -299.153566) (xy 157.52988 -299.200961)
			(xy 157.530288 -299.2247) (xy 157.86914 -299.2247) (xy 157.8731 -299.175646) (xy 157.884877 -299.127862)
			(xy 157.904168 -299.082586) (xy 157.930471 -299.04099) (xy 157.963106 -299.004153) (xy 158.001227 -298.973028)
			(xy 158.043848 -298.948421) (xy 158.089864 -298.930969) (xy 158.138083 -298.921125) (xy 158.187258 -298.919144)
			(xy 158.236113 -298.925076) (xy 158.283384 -298.938768) (xy 158.327846 -298.959866) (xy 158.368349 -298.987822)
			(xy 158.403842 -299.021914) (xy 158.433407 -299.061258) (xy 158.456278 -299.104835) (xy 158.471862 -299.151516)
			(xy 158.479757 -299.200093) (xy 158.480252 -299.2247) (xy 158.480247 -299.224954) (xy 159.76906 -299.224954)
			(xy 159.77302 -299.1759) (xy 159.784797 -299.128116) (xy 159.804088 -299.08284) (xy 159.830391 -299.041244)
			(xy 159.863026 -299.004407) (xy 159.901147 -298.973282) (xy 159.943768 -298.948675) (xy 159.989784 -298.931223)
			(xy 160.038003 -298.921379) (xy 160.087178 -298.919398) (xy 160.136033 -298.92533) (xy 160.183304 -298.939022)
			(xy 160.227766 -298.96012) (xy 160.268269 -298.988076) (xy 160.303762 -299.022168) (xy 160.333327 -299.061512)
			(xy 160.356198 -299.105089) (xy 160.371782 -299.15177) (xy 160.379677 -299.200347) (xy 160.380172 -299.224954)
			(xy 160.719274 -299.224954) (xy 160.723234 -299.1759) (xy 160.735011 -299.128116) (xy 160.754302 -299.08284)
			(xy 160.780605 -299.041244) (xy 160.81324 -299.004407) (xy 160.851361 -298.973282) (xy 160.893982 -298.948675)
			(xy 160.939998 -298.931223) (xy 160.988217 -298.921379) (xy 161.037392 -298.919398) (xy 161.086247 -298.92533)
			(xy 161.133518 -298.939022) (xy 161.17798 -298.96012) (xy 161.218483 -298.988076) (xy 161.253976 -299.022168)
			(xy 161.283541 -299.061512) (xy 161.306412 -299.105089) (xy 161.321996 -299.15177) (xy 161.329891 -299.200347)
			(xy 161.330386 -299.224954) (xy 161.669234 -299.224954) (xy 161.673194 -299.1759) (xy 161.684971 -299.128116)
			(xy 161.704262 -299.08284) (xy 161.730565 -299.041244) (xy 161.7632 -299.004407) (xy 161.801321 -298.973282)
			(xy 161.843942 -298.948675) (xy 161.889958 -298.931223) (xy 161.938177 -298.921379) (xy 161.987352 -298.919398)
			(xy 162.036207 -298.92533) (xy 162.083478 -298.939022) (xy 162.12794 -298.96012) (xy 162.168443 -298.988076)
			(xy 162.203936 -299.022168) (xy 162.233501 -299.061512) (xy 162.256372 -299.105089) (xy 162.271956 -299.15177)
			(xy 162.279851 -299.200347) (xy 162.280346 -299.224954) (xy 162.619194 -299.224954) (xy 162.623154 -299.1759)
			(xy 162.634931 -299.128116) (xy 162.654222 -299.08284) (xy 162.680525 -299.041244) (xy 162.71316 -299.004407)
			(xy 162.751281 -298.973282) (xy 162.793902 -298.948675) (xy 162.839918 -298.931223) (xy 162.888137 -298.921379)
			(xy 162.937312 -298.919398) (xy 162.986167 -298.92533) (xy 163.033438 -298.939022) (xy 163.0779 -298.96012)
			(xy 163.118403 -298.988076) (xy 163.153896 -299.022168) (xy 163.183461 -299.061512) (xy 163.206332 -299.105089)
			(xy 163.221916 -299.15177) (xy 163.229811 -299.200347) (xy 163.230306 -299.224954) (xy 163.229811 -299.249561)
			(xy 163.221916 -299.298138) (xy 163.206332 -299.344819) (xy 163.183461 -299.388396) (xy 163.153896 -299.42774)
			(xy 163.118403 -299.461832) (xy 163.0779 -299.489788) (xy 163.033438 -299.510886) (xy 162.986167 -299.524578)
			(xy 162.937312 -299.53051) (xy 162.888137 -299.528529) (xy 162.839918 -299.518685) (xy 162.793902 -299.501233)
			(xy 162.751281 -299.476626) (xy 162.71316 -299.445501) (xy 162.680525 -299.408664) (xy 162.654222 -299.367068)
			(xy 162.634931 -299.321792) (xy 162.623154 -299.274008) (xy 162.619194 -299.224954) (xy 162.280346 -299.224954)
			(xy 162.279851 -299.249561) (xy 162.271956 -299.298138) (xy 162.256372 -299.344819) (xy 162.233501 -299.388396)
			(xy 162.203936 -299.42774) (xy 162.168443 -299.461832) (xy 162.12794 -299.489788) (xy 162.083478 -299.510886)
			(xy 162.036207 -299.524578) (xy 161.987352 -299.53051) (xy 161.938177 -299.528529) (xy 161.889958 -299.518685)
			(xy 161.843942 -299.501233) (xy 161.801321 -299.476626) (xy 161.7632 -299.445501) (xy 161.730565 -299.408664)
			(xy 161.704262 -299.367068) (xy 161.684971 -299.321792) (xy 161.673194 -299.274008) (xy 161.669234 -299.224954)
			(xy 161.330386 -299.224954) (xy 161.329891 -299.249561) (xy 161.321996 -299.298138) (xy 161.306412 -299.344819)
			(xy 161.283541 -299.388396) (xy 161.253976 -299.42774) (xy 161.218483 -299.461832) (xy 161.17798 -299.489788)
			(xy 161.133518 -299.510886) (xy 161.086247 -299.524578) (xy 161.037392 -299.53051) (xy 160.988217 -299.528529)
			(xy 160.939998 -299.518685) (xy 160.893982 -299.501233) (xy 160.851361 -299.476626) (xy 160.81324 -299.445501)
			(xy 160.780605 -299.408664) (xy 160.754302 -299.367068) (xy 160.735011 -299.321792) (xy 160.723234 -299.274008)
			(xy 160.719274 -299.224954) (xy 160.380172 -299.224954) (xy 160.379677 -299.249561) (xy 160.371782 -299.298138)
			(xy 160.356198 -299.344819) (xy 160.333327 -299.388396) (xy 160.303762 -299.42774) (xy 160.268269 -299.461832)
			(xy 160.227766 -299.489788) (xy 160.183304 -299.510886) (xy 160.136033 -299.524578) (xy 160.087178 -299.53051)
			(xy 160.038003 -299.528529) (xy 159.989784 -299.518685) (xy 159.943768 -299.501233) (xy 159.901147 -299.476626)
			(xy 159.863026 -299.445501) (xy 159.830391 -299.408664) (xy 159.804088 -299.367068) (xy 159.784797 -299.321792)
			(xy 159.77302 -299.274008) (xy 159.76906 -299.224954) (xy 158.480247 -299.224954) (xy 158.479757 -299.249307)
			(xy 158.471862 -299.297884) (xy 158.456278 -299.344565) (xy 158.433407 -299.388142) (xy 158.403842 -299.427486)
			(xy 158.368349 -299.461578) (xy 158.327846 -299.489534) (xy 158.283384 -299.510632) (xy 158.236113 -299.524324)
			(xy 158.187258 -299.530256) (xy 158.138083 -299.528275) (xy 158.089864 -299.518431) (xy 158.043848 -299.500979)
			(xy 158.001227 -299.476372) (xy 157.963106 -299.445247) (xy 157.930471 -299.40841) (xy 157.904168 -299.366814)
			(xy 157.884877 -299.321538) (xy 157.8731 -299.273754) (xy 157.86914 -299.2247) (xy 157.530288 -299.2247)
			(xy 157.530292 -299.224954) (xy 157.529881 -299.247872) (xy 157.523038 -299.293194) (xy 157.509514 -299.33699)
			(xy 157.489611 -299.378279) (xy 157.463775 -299.416139) (xy 157.448504 -299.433234) (xy 157.44254 -299.440725)
			(xy 157.436191 -299.458774) (xy 157.436928 -299.477893) (xy 157.440376 -299.486828) (xy 157.474666 -299.564806)
			(xy 157.478222 -299.57268) (xy 157.482667 -299.581245) (xy 157.496666 -299.594504) (xy 157.514558 -299.601695)
			(xy 157.524196 -299.602144) (xy 157.566868 -299.602144) (xy 157.60997 -299.602616) (xy 157.695829 -299.610303)
			(xy 157.780659 -299.625628) (xy 157.863782 -299.648468) (xy 157.944532 -299.678639) (xy 158.022265 -299.715903)
			(xy 158.096359 -299.759959) (xy 158.166223 -299.810457) (xy 158.199074 -299.838364) (xy 158.205932 -299.844206)
			(xy 158.229046 -299.853096) (xy 158.23057 -299.853604) (xy 158.234917 -299.855152) (xy 158.243991 -299.856822)
			(xy 158.248604 -299.856906) (xy 163.710366 -299.856906)
		)
		(stroke
			(width 0)
			(type solid)
		)
		(fill yes)
		(layer "In11.Cu")
		(net "SYSPLL_VDDA18_PEX1")
	)
	(gr_poly
		(pts
			(xy 167.193214 -191.392556) (xy 167.202845 -191.392086) (xy 167.220718 -191.384888) (xy 167.234691 -191.371621)
			(xy 167.242803 -191.354145) (xy 167.24376 -191.34455) (xy 167.851836 -180.133498) (xy 167.829738 -180.104288)
			(xy 167.811704 -180.09997) (xy 167.784135 -180.092966) (xy 167.731296 -180.071907) (xy 167.682166 -180.043242)
			(xy 167.637831 -180.007607) (xy 167.599273 -179.96579) (xy 167.567344 -179.918716) (xy 167.542752 -179.867426)
			(xy 167.52604 -179.813056) (xy 167.517577 -179.756808) (xy 167.517064 -179.728368) (xy 167.517574 -179.700167)
			(xy 167.525884 -179.644379) (xy 167.54232 -179.590424) (xy 167.566521 -179.539478) (xy 167.597961 -179.49265)
			(xy 167.635954 -179.450963) (xy 167.679671 -179.415325) (xy 167.72816 -179.386514) (xy 167.754046 -179.375308)
			(xy 167.763879 -179.37072) (xy 167.778754 -179.354949) (xy 167.785818 -179.334453) (xy 167.783819 -179.312866)
			(xy 167.778938 -179.303172) (xy 167.777922 -179.301648) (xy 167.776398 -179.299362) (xy 167.760165 -179.275211)
			(xy 167.734435 -179.223022) (xy 167.71694 -179.167526) (xy 167.708088 -179.110016) (xy 167.707564 -179.080922)
			(xy 167.708101 -179.051954) (xy 167.716859 -178.994685) (xy 167.734177 -178.939399) (xy 167.759656 -178.887368)
			(xy 167.792711 -178.839788) (xy 167.832581 -178.797754) (xy 167.87835 -178.762233) (xy 167.903398 -178.747674)
			(xy 167.910676 -178.743179) (xy 167.921975 -178.730349) (xy 167.928467 -178.714532) (xy 167.929306 -178.706018)
			(xy 168.417494 -169.700448) (xy 168.417432 -169.688101) (xy 168.407217 -169.665664) (xy 168.397936 -169.657522)
			(xy 168.32199 -169.59834) (xy 168.29786 -169.594022) (xy 168.286938 -169.597324) (xy 168.258786 -169.605723)
			(xy 168.200741 -169.614775) (xy 168.171368 -169.615358) (xy 168.144115 -169.61487) (xy 168.090163 -169.607109)
			(xy 168.037866 -169.591749) (xy 167.988286 -169.569103) (xy 167.942434 -169.539632) (xy 167.901242 -169.503936)
			(xy 167.865549 -169.462741) (xy 167.836082 -169.416886) (xy 167.81344 -169.367304) (xy 167.798085 -169.315005)
			(xy 167.790328 -169.261053) (xy 167.790328 -169.206547) (xy 167.798085 -169.152595) (xy 167.81344 -169.100296)
			(xy 167.836082 -169.050714) (xy 167.865549 -169.004859) (xy 167.901242 -168.963664) (xy 167.942434 -168.927968)
			(xy 167.988286 -168.898497) (xy 168.037866 -168.875851) (xy 168.090163 -168.860491) (xy 168.144115 -168.85273)
			(xy 168.171368 -168.852342) (xy 168.171876 -168.852342) (xy 168.198068 -168.852789) (xy 168.249955 -168.859988)
			(xy 168.300367 -168.874227) (xy 168.32453 -168.884346) (xy 168.336102 -168.888613) (xy 168.360667 -168.886899)
			(xy 168.37152 -168.881044) (xy 168.44264 -168.837356) (xy 168.452751 -168.830233) (xy 168.465363 -168.809003)
			(xy 168.46677 -168.796716) (xy 168.71442 -164.227764) (xy 168.711372 -164.21862) (xy 168.702254 -164.189293)
			(xy 168.692423 -164.128675) (xy 168.691814 -164.09797) (xy 168.692327 -164.069307) (xy 168.700907 -164.012628)
			(xy 168.717884 -163.957875) (xy 168.729914 -163.931854) (xy 168.730676 -163.930076) (xy 169.109898 -156.935424)
			(xy 169.091864 -156.907992) (xy 169.08145 -156.903928) (xy 169.057258 -156.894821) (xy 169.011381 -156.871004)
			(xy 168.96914 -156.841211) (xy 168.931308 -156.805987) (xy 168.898579 -156.765977) (xy 168.871552 -156.721914)
			(xy 168.860724 -156.698442) (xy 168.849564 -156.671879) (xy 168.834471 -156.616275) (xy 168.827912 -156.559034)
			(xy 168.830038 -156.501457) (xy 168.8408 -156.444856) (xy 168.859953 -156.390517) (xy 168.887061 -156.339676)
			(xy 168.921507 -156.293492) (xy 168.962508 -156.253013) (xy 169.00913 -156.219162) (xy 169.03446 -156.205428)
			(xy 169.053899 -156.195739) (xy 169.094511 -156.180333) (xy 169.115486 -156.174694) (xy 169.131488 -156.17063)
			(xy 169.15257 -156.144976) (xy 169.196258 -155.342336) (xy 169.193464 -155.340812) (xy 169.153078 -155.332938)
			(xy 169.127339 -155.32746) (xy 169.077568 -155.310372) (xy 169.030616 -155.286611) (xy 168.98737 -155.256627)
			(xy 168.948653 -155.220989) (xy 168.915196 -155.180371) (xy 168.887633 -155.135544) (xy 168.866488 -155.087357)
			(xy 168.85216 -155.036722) (xy 168.844922 -154.984599) (xy 168.844468 -154.958288) (xy 168.844989 -154.92991)
			(xy 168.853396 -154.87378) (xy 168.870024 -154.819515) (xy 168.894505 -154.76831) (xy 168.926299 -154.721296)
			(xy 168.964705 -154.679509) (xy 169.008877 -154.643871) (xy 169.05784 -154.615167) (xy 169.110513 -154.594032)
			(xy 169.165736 -154.58093) (xy 169.193972 -154.57805) (xy 169.21988 -154.575764) (xy 169.223525 -154.575383)
			(xy 169.230664 -154.573725) (xy 169.234104 -154.572462) (xy 169.238168 -154.570938) (xy 169.274236 -153.907744)
			(xy 169.274334 -153.897925) (xy 169.267977 -153.879367) (xy 169.255098 -153.864569) (xy 169.24655 -153.859738)
			(xy 169.2275 -153.850086) (xy 169.220831 -153.847008) (xy 169.206376 -153.844436) (xy 169.199052 -153.845006)
			(xy 169.191686 -153.845768) (xy 169.178478 -153.851102) (xy 169.172636 -153.855928) (xy 169.152147 -153.872055)
			(xy 169.1076 -153.899154) (xy 169.059777 -153.919935) (xy 169.009571 -153.934009) (xy 168.957915 -153.941116)
			(xy 168.931844 -153.941526) (xy 168.904588 -153.941066) (xy 168.850629 -153.933314) (xy 168.798324 -153.917961)
			(xy 168.748736 -153.89532) (xy 168.702875 -153.865852) (xy 168.661675 -153.830156) (xy 168.625975 -153.78896)
			(xy 168.596501 -153.743103) (xy 168.573855 -153.693517) (xy 168.558496 -153.641214) (xy 168.550737 -153.587256)
			(xy 168.550737 -153.532744) (xy 168.558496 -153.478786) (xy 168.573855 -153.426483) (xy 168.596501 -153.376897)
			(xy 168.625975 -153.33104) (xy 168.661675 -153.289844) (xy 168.702875 -153.254148) (xy 168.748736 -153.22468)
			(xy 168.798324 -153.202039) (xy 168.850629 -153.186686) (xy 168.904588 -153.178934) (xy 168.931844 -153.17851)
			(xy 168.961465 -153.179066) (xy 169.019996 -153.188218) (xy 169.076408 -153.20631) (xy 169.129344 -153.232907)
			(xy 169.177531 -153.26737) (xy 169.199052 -153.28773) (xy 169.19956 -153.288238) (xy 169.206451 -153.294347)
			(xy 169.223358 -153.30161) (xy 169.241742 -153.302399) (xy 169.250614 -153.299922) (xy 169.278046 -153.289)
			(xy 169.286877 -153.28503) (xy 169.300931 -153.271733) (xy 169.309077 -153.254184) (xy 169.31005 -153.24455)
			(xy 169.39768 -151.627332) (xy 169.397802 -151.617703) (xy 169.391703 -151.599452) (xy 169.379294 -151.584746)
			(xy 169.37101 -151.579834) (xy 169.337482 -151.561546) (xy 169.331026 -151.558393) (xy 169.316975 -151.55542)
			(xy 169.309796 -151.555704) (xy 169.302684 -151.556212) (xy 169.289476 -151.561038) (xy 169.283634 -151.565356)
			(xy 169.258999 -151.58259) (xy 169.205449 -151.609916) (xy 169.14828 -151.628519) (xy 169.088904 -151.637941)
			(xy 169.058844 -151.638508) (xy 169.05097 -151.638508) (xy 169.024086 -151.637495) (xy 168.970988 -151.628845)
			(xy 168.919633 -151.612821) (xy 168.871037 -151.589741) (xy 168.826166 -151.560063) (xy 168.78591 -151.524375)
			(xy 168.751067 -151.483386) (xy 168.722327 -151.437908) (xy 168.700263 -151.388843) (xy 168.68531 -151.337165)
			(xy 168.677766 -151.283899) (xy 168.677336 -151.257) (xy 168.677799 -151.229748) (xy 168.685557 -151.1758)
			(xy 168.700913 -151.123504) (xy 168.723556 -151.073927) (xy 168.753025 -151.028077) (xy 168.788719 -150.986888)
			(xy 168.829912 -150.951198) (xy 168.875766 -150.921735) (xy 168.925346 -150.899098) (xy 168.977643 -150.883747)
			(xy 169.031592 -150.875996) (xy 169.058844 -150.875492) (xy 169.086449 -150.875977) (xy 169.141083 -150.883929)
			(xy 169.193999 -150.899675) (xy 169.244093 -150.922886) (xy 169.290316 -150.953078) (xy 169.31132 -150.970996)
			(xy 169.316654 -150.975822) (xy 169.329608 -150.981918) (xy 169.336974 -150.982934) (xy 169.343996 -150.983841)
			(xy 169.358049 -150.982167) (xy 169.36466 -150.979632) (xy 169.405808 -150.962106) (xy 169.418762 -150.956518)
			(xy 169.435526 -150.932896) (xy 169.742358 -145.270982) (xy 169.742358 -145.270474) (xy 169.861484 -142.717012)
			(xy 169.861365 -142.712199) (xy 169.859581 -142.702738) (xy 169.857928 -142.698216) (xy 169.856404 -142.69466)
			(xy 169.85392 -142.689884) (xy 169.847257 -142.68143) (xy 169.843196 -142.677896) (xy 169.840656 -142.675864)
			(xy 169.820081 -142.660427) (xy 169.782871 -142.624911) (xy 169.750773 -142.584715) (xy 169.724369 -142.54057)
			(xy 169.704138 -142.493277) (xy 169.690448 -142.443693) (xy 169.683547 -142.392719) (xy 169.683176 -142.367)
			(xy 169.683685 -142.339095) (xy 169.69181 -142.28388) (xy 169.707887 -142.230436) (xy 169.731573 -142.179901)
			(xy 169.762363 -142.133354) (xy 169.799602 -142.091785) (xy 169.842496 -142.056079) (xy 169.866056 -142.041118)
			(xy 169.870374 -142.038578) (xy 169.888408 -142.008352) (xy 169.891421 -142.002889) (xy 169.895025 -141.990949)
			(xy 169.89552 -141.98473) (xy 170.055794 -138.553698) (xy 170.057826 -138.520678) (xy 170.214798 -136.561322)
			(xy 170.214798 -136.559798) (xy 170.275758 -135.43407) (xy 170.275857 -135.423822) (xy 170.268915 -135.404557)
			(xy 170.262296 -135.396732) (xy 170.235626 -135.36803) (xy 170.228415 -135.361711) (xy 170.210658 -135.354516)
			(xy 170.201082 -135.35406) (xy 170.19905 -135.35406) (xy 170.197018 -135.354314) (xy 170.167045 -135.353826)
			(xy 170.10761 -135.346005) (xy 170.049705 -135.330496) (xy 169.994318 -135.307564) (xy 169.942397 -135.277599)
			(xy 169.894831 -135.241116) (xy 169.852432 -135.198738) (xy 169.815925 -135.151189) (xy 169.785936 -135.099283)
			(xy 169.762976 -135.043908) (xy 169.747438 -134.98601) (xy 169.739589 -134.926579) (xy 169.739056 -134.896606)
			(xy 169.739056 -134.032752) (xy 169.739529 -134.002774) (xy 169.747363 -133.943331) (xy 169.76289 -133.885419)
			(xy 169.785846 -133.830031) (xy 169.815836 -133.778114) (xy 169.852348 -133.730556) (xy 169.894756 -133.688172)
			(xy 169.942335 -133.651688) (xy 169.99427 -133.621728) (xy 170.049672 -133.598805) (xy 170.107592 -133.583311)
			(xy 170.167039 -133.575511) (xy 170.197018 -133.575044) (xy 170.230526 -133.575591) (xy 170.296836 -133.585279)
			(xy 170.329098 -133.594348) (xy 170.34002 -133.59765) (xy 170.350942 -133.596126) (xy 170.356646 -133.595131)
			(xy 170.367419 -133.590894) (xy 170.372278 -133.587744) (xy 170.40479 -133.565646) (xy 170.411353 -133.560741)
			(xy 170.421203 -133.547658) (xy 170.424094 -133.539992) (xy 170.5483 -132.059934) (xy 170.540934 -132.03936)
			(xy 170.53814 -132.036566) (xy 170.51903 -132.017015) (xy 170.486033 -131.973425) (xy 170.459595 -131.925573)
			(xy 170.449494 -131.900168) (xy 170.442782 -131.88167) (xy 170.432733 -131.843621) (xy 170.429428 -131.824222)
			(xy 170.427904 -131.813554) (xy 170.416474 -131.795774) (xy 170.33621 -131.742434) (xy 170.315636 -131.738878)
			(xy 170.305222 -131.741418) (xy 170.296332 -131.74345) (xy 170.27182 -131.74855) (xy 170.222052 -131.754023)
			(xy 170.197018 -131.754372) (xy 170.167031 -131.753904) (xy 170.107571 -131.746078) (xy 170.04964 -131.730558)
			(xy 169.994232 -131.707609) (xy 169.942292 -131.677624) (xy 169.894711 -131.641116) (xy 169.852302 -131.59871)
			(xy 169.815791 -131.551131) (xy 169.785803 -131.499194) (xy 169.762851 -131.443786) (xy 169.747327 -131.385857)
			(xy 169.739498 -131.326397) (xy 169.739056 -131.29641) (xy 169.739056 -130.43281) (xy 169.739525 -130.402824)
			(xy 169.747351 -130.343366) (xy 169.762872 -130.285438) (xy 169.785822 -130.230032) (xy 169.815808 -130.178095)
			(xy 169.852316 -130.130516) (xy 169.894723 -130.088111) (xy 169.942301 -130.051603) (xy 169.994239 -130.021619)
			(xy 170.049646 -129.99867) (xy 170.107574 -129.98315) (xy 170.167032 -129.975324) (xy 170.197018 -129.974848)
			(xy 170.231662 -129.975502) (xy 170.300158 -129.985954) (xy 170.333416 -129.995676) (xy 170.33367 -129.995676)
			(xy 170.344799 -129.998499) (xy 170.367489 -129.995195) (xy 170.377358 -129.989326) (xy 170.404028 -129.971292)
			(xy 170.413206 -129.964489) (xy 170.424717 -129.944783) (xy 170.426126 -129.933446) (xy 170.428776 -129.906883)
			(xy 170.440556 -129.854817) (xy 170.459474 -129.804899) (xy 170.485162 -129.758103) (xy 170.517118 -129.715343)
			(xy 170.554719 -129.67745) (xy 170.597233 -129.645166) (xy 170.643829 -129.619118) (xy 170.693599 -129.599816)
			(xy 170.719496 -129.59334) (xy 170.720004 -129.59334) (xy 170.744134 -129.587498) (xy 170.755818 -129.581402)
			(xy 171.14901 -124.892562) (xy 171.201334 -124.24029) (xy 171.202858 -124.223272) (xy 171.202858 -124.222002)
			(xy 171.58335 -119.473472) (xy 171.5897 -119.416322) (xy 171.68114 -118.757192) (xy 171.682127 -118.745507)
			(xy 171.674706 -118.723288) (xy 171.666916 -118.71452) (xy 171.609258 -118.656862) (xy 171.604904 -118.652694)
			(xy 171.594628 -118.646403) (xy 171.588938 -118.644416) (xy 171.577762 -118.64086) (xy 171.565824 -118.642638)
			(xy 171.551808 -118.644575) (xy 171.523585 -118.646612) (xy 171.509436 -118.646702) (xy 171.509182 -118.646702)
			(xy 171.481978 -118.646147) (xy 171.428141 -118.638273) (xy 171.375969 -118.62283) (xy 171.32652 -118.600131)
			(xy 171.280798 -118.570637) (xy 171.239729 -118.534946) (xy 171.204149 -118.493782) (xy 171.174777 -118.44798)
			(xy 171.152211 -118.398471) (xy 171.136908 -118.346257) (xy 171.129179 -118.292399) (xy 171.12869 -118.265194)
			(xy 171.129176 -118.237943) (xy 171.136933 -118.183996) (xy 171.152289 -118.131702) (xy 171.17493 -118.082125)
			(xy 171.204397 -118.036275) (xy 171.240088 -117.995086) (xy 171.281278 -117.959394) (xy 171.327129 -117.929929)
			(xy 171.376705 -117.907288) (xy 171.429 -117.891933) (xy 171.482947 -117.884176) (xy 171.510198 -117.883686)
			(xy 171.537079 -117.884144) (xy 171.590309 -117.891683) (xy 171.641956 -117.906613) (xy 171.666662 -117.917214)
			(xy 171.67221 -117.91954) (xy 171.684014 -117.921852) (xy 171.69003 -117.921786) (xy 171.701206 -117.921278)
			(xy 171.783248 -117.875812) (xy 171.792702 -117.869811) (xy 171.805743 -117.851639) (xy 171.808394 -117.84076)
			(xy 172.049694 -116.105432) (xy 172.050259 -116.099998) (xy 172.049362 -116.089111) (xy 172.047916 -116.083842)
			(xy 172.045122 -116.07419) (xy 172.03801 -116.065808) (xy 172.020306 -116.044187) (xy 171.990761 -115.996755)
			(xy 171.968462 -115.945516) (xy 171.953887 -115.891569) (xy 171.950126 -115.863878) (xy 171.948602 -115.85067)
			(xy 171.947332 -115.819174) (xy 171.947775 -115.793146) (xy 171.954854 -115.741574) (xy 171.968876 -115.691442)
			(xy 171.989582 -115.643682) (xy 172.016587 -115.599179) (xy 172.04939 -115.558759) (xy 172.087382 -115.523173)
			(xy 172.108368 -115.50777) (xy 172.116496 -115.501928) (xy 172.132498 -115.476274) (xy 172.135226 -115.471697)
			(xy 172.138932 -115.461709) (xy 172.139864 -115.456462) (xy 172.534834 -112.61344) (xy 172.535088 -112.612678)
			(xy 172.535596 -112.607598) (xy 172.537882 -112.591342) (xy 172.537882 -112.590834) (xy 173.732952 -103.990648)
			(xy 173.733206 -103.98506) (xy 173.729142 -103.965248) (xy 173.727364 -103.96093) (xy 173.718113 -103.937617)
			(xy 173.705104 -103.889176) (xy 173.698538 -103.83945) (xy 173.698154 -103.814372) (xy 173.698154 -103.8098)
			(xy 173.69917 -103.784908) (xy 173.701835 -103.756935) (xy 173.714355 -103.702157) (xy 173.734794 -103.649816)
			(xy 173.76271 -103.601051) (xy 173.779688 -103.57866) (xy 173.786292 -103.567738) (xy 173.791626 -103.555292)
			(xy 173.795436 -103.54183) (xy 173.85157 -103.136192) (xy 173.852626 -103.12453) (xy 173.845346 -103.102302)
			(xy 173.8376 -103.09352) (xy 173.834044 -103.090218) (xy 173.813155 -103.072006) (xy 173.77635 -103.030577)
			(xy 173.745932 -102.984254) (xy 173.722544 -102.934014) (xy 173.706679 -102.880916) (xy 173.698672 -102.826081)
			(xy 173.698154 -102.798372) (xy 173.698628 -102.771003) (xy 173.706456 -102.716827) (xy 173.721948 -102.664327)
			(xy 173.744786 -102.61458) (xy 173.7745 -102.568608) (xy 173.81048 -102.527356) (xy 173.851987 -102.491671)
			(xy 173.898169 -102.462285) (xy 173.922944 -102.450646) (xy 173.923198 -102.450392) (xy 173.930818 -102.446573)
			(xy 173.943149 -102.434821) (xy 173.950936 -102.41967) (xy 173.952408 -102.411276) (xy 173.963838 -102.329234)
			(xy 173.98238 -102.195376) (xy 173.983363 -102.183691) (xy 173.975942 -102.161474) (xy 173.968156 -102.152704)
			(xy 173.965007 -102.149637) (xy 173.957858 -102.144522) (xy 173.953932 -102.142544) (xy 173.94936 -102.14102)
			(xy 173.922137 -102.130546) (xy 173.870982 -102.102522) (xy 173.824693 -102.067034) (xy 173.784348 -102.024911)
			(xy 173.750888 -101.977135) (xy 173.725095 -101.924821) (xy 173.70757 -101.869188) (xy 173.698722 -101.811536)
			(xy 173.698154 -101.782372) (xy 173.69868 -101.753591) (xy 173.707334 -101.696683) (xy 173.724439 -101.641721)
			(xy 173.749609 -101.589953) (xy 173.782271 -101.542555) (xy 173.821685 -101.500603) (xy 173.866954 -101.465049)
			(xy 173.917052 -101.436701) (xy 173.97084 -101.416202) (xy 174.027098 -101.404018) (xy 174.055786 -101.401626)
			(xy 174.056294 -101.401626) (xy 174.070264 -101.40061) (xy 174.096172 -101.376226) (xy 174.112936 -101.255576)
			(xy 174.113184 -101.24641) (xy 174.107971 -101.228843) (xy 174.102776 -101.221286) (xy 174.102776 -101.221032)
			(xy 174.05858 -101.162358) (xy 174.052725 -101.155693) (xy 174.037502 -101.146601) (xy 174.028862 -101.144578)
			(xy 174.026068 -101.14407) (xy 173.999118 -101.139774) (xy 173.94673 -101.124484) (xy 173.897056 -101.101885)
			(xy 173.851108 -101.07244) (xy 173.809823 -101.036749) (xy 173.774045 -100.995541) (xy 173.744503 -100.949655)
			(xy 173.721799 -100.900029) (xy 173.706398 -100.847674) (xy 173.698612 -100.793659) (xy 173.698154 -100.766372)
			(xy 173.698642 -100.739121) (xy 173.706401 -100.685174) (xy 173.721758 -100.632881) (xy 173.744401 -100.583305)
			(xy 173.773867 -100.537455) (xy 173.809558 -100.496265) (xy 173.850747 -100.460573) (xy 173.896596 -100.431105)
			(xy 173.946171 -100.408462) (xy 173.998465 -100.393103) (xy 174.052411 -100.385342) (xy 174.079662 -100.384864)
			(xy 174.092594 -100.384994) (xy 174.118396 -100.386776) (xy 174.131224 -100.38842) (xy 174.141384 -100.38969)
			(xy 174.150528 -100.387404) (xy 174.155384 -100.386058) (xy 174.16447 -100.381709) (xy 174.168562 -100.378768)
			(xy 174.182278 -100.368354) (xy 174.225966 -100.33508) (xy 174.233617 -100.328641) (xy 174.243673 -100.31138)
			(xy 174.245524 -100.301552) (xy 174.83455 -96.0628) (xy 174.835391 -96.053598) (xy 174.831233 -96.035608)
			(xy 174.820992 -96.020245) (xy 174.813722 -96.01454) (xy 174.740062 -95.962216) (xy 174.734222 -95.958415)
			(xy 174.721086 -95.953785) (xy 174.714154 -95.953072) (xy 174.700184 -95.952056) (xy 174.687484 -95.95866)
			(xy 174.66024 -95.972089) (xy 174.602557 -95.991099) (xy 174.542591 -96.000744) (xy 174.512224 -96.001332)
			(xy 174.51197 -96.001332) (xy 174.484718 -96.000844) (xy 174.430771 -95.993084) (xy 174.378476 -95.977725)
			(xy 174.3289 -95.955081) (xy 174.28305 -95.925612) (xy 174.241861 -95.889918) (xy 174.20617 -95.848726)
			(xy 174.176705 -95.802874) (xy 174.154065 -95.753296) (xy 174.13871 -95.701) (xy 174.130954 -95.647052)
			(xy 174.130954 -95.592548) (xy 174.13871 -95.5386) (xy 174.154065 -95.486304) (xy 174.176705 -95.436726)
			(xy 174.20617 -95.390874) (xy 174.241861 -95.349682) (xy 174.28305 -95.313988) (xy 174.3289 -95.284519)
			(xy 174.378476 -95.261875) (xy 174.430771 -95.246516) (xy 174.484718 -95.238756) (xy 174.51197 -95.238316)
			(xy 174.540745 -95.238838) (xy 174.597642 -95.24748) (xy 174.652595 -95.264573) (xy 174.704356 -95.289729)
			(xy 174.75175 -95.322375) (xy 174.773082 -95.341694) (xy 174.773336 -95.341948) (xy 174.780206 -95.347817)
			(xy 174.796895 -95.354711) (xy 174.814939 -95.355352) (xy 174.823628 -95.35287) (xy 174.837598 -95.348044)
			(xy 174.838106 -95.348044) (xy 174.909734 -95.322644) (xy 174.918425 -95.319183) (xy 174.932692 -95.307112)
			(xy 174.941649 -95.290709) (xy 174.943262 -95.281496) (xy 175.37684 -92.160852) (xy 175.377094 -92.160344)
			(xy 175.377856 -92.154502) (xy 175.37811 -92.151962) (xy 175.379888 -92.138754) (xy 177.01641 -80.361536)
			(xy 177.036476 -80.36306) (xy 177.067464 -80.337914) (xy 177.26787 -78.906624) (xy 177.268763 -78.896077)
			(xy 177.262927 -78.875755) (xy 177.249403 -78.859502) (xy 177.240184 -78.8543) (xy 177.228754 -78.832456)
			(xy 177.528474 -76.675488) (xy 177.530122 -76.666517) (xy 177.538826 -76.650502) (xy 177.552582 -76.638545)
			(xy 177.569653 -76.632157) (xy 177.578766 -76.6318) (xy 177.586386 -76.6318) (xy 177.841656 -74.809858)
			(xy 177.842681 -74.798978) (xy 177.836501 -74.778039) (xy 177.829718 -74.769472) (xy 177.822606 -74.76109)
			(xy 177.802794 -74.7522) (xy 176.705514 -74.7522) (xy 176.695241 -74.752667) (xy 176.676336 -74.760714)
			(xy 176.662097 -74.775527) (xy 176.658016 -74.784966) (xy 172.32576 -86.227158) (xy 173.06366 -86.227158)
			(xy 173.067731 -86.171536) (xy 173.079857 -86.117099) (xy 173.09978 -86.065008) (xy 173.127076 -86.016373)
			(xy 173.161162 -85.97223) (xy 173.201311 -85.933521) (xy 173.246669 -85.90107) (xy 173.296269 -85.875569)
			(xy 173.349053 -85.857562) (xy 173.403896 -85.847432) (xy 173.45963 -85.845395) (xy 173.515067 -85.851495)
			(xy 173.569024 -85.865601) (xy 173.620353 -85.887413) (xy 173.667959 -85.916467) (xy 173.710827 -85.952142)
			(xy 173.748044 -85.993679) (xy 173.778817 -86.040192) (xy 173.802489 -86.090689) (xy 173.818557 -86.144096)
			(xy 173.826677 -86.199272) (xy 173.827186 -86.227158) (xy 173.826695 -86.254082) (xy 174.747426 -86.254082)
			(xy 174.751497 -86.19846) (xy 174.763623 -86.144023) (xy 174.783546 -86.091932) (xy 174.810842 -86.043297)
			(xy 174.844928 -85.999154) (xy 174.885077 -85.960445) (xy 174.930435 -85.927994) (xy 174.980035 -85.902493)
			(xy 175.032819 -85.884486) (xy 175.087662 -85.874356) (xy 175.143396 -85.872319) (xy 175.198833 -85.878419)
			(xy 175.25279 -85.892525) (xy 175.304119 -85.914337) (xy 175.351725 -85.943391) (xy 175.394593 -85.979066)
			(xy 175.43181 -86.020603) (xy 175.462583 -86.067116) (xy 175.486255 -86.117613) (xy 175.502323 -86.17102)
			(xy 175.510443 -86.226196) (xy 175.510952 -86.254082) (xy 175.510443 -86.281968) (xy 175.502323 -86.337144)
			(xy 175.486255 -86.390551) (xy 175.462583 -86.441048) (xy 175.43181 -86.487561) (xy 175.394593 -86.529098)
			(xy 175.351725 -86.564773) (xy 175.304119 -86.593827) (xy 175.25279 -86.615639) (xy 175.198833 -86.629745)
			(xy 175.143396 -86.635845) (xy 175.087662 -86.633808) (xy 175.032819 -86.623678) (xy 174.980035 -86.605671)
			(xy 174.930435 -86.58017) (xy 174.885077 -86.547719) (xy 174.844928 -86.50901) (xy 174.810842 -86.464867)
			(xy 174.783546 -86.416232) (xy 174.763623 -86.364141) (xy 174.751497 -86.309704) (xy 174.747426 -86.254082)
			(xy 173.826695 -86.254082) (xy 173.826677 -86.255044) (xy 173.818557 -86.31022) (xy 173.802489 -86.363627)
			(xy 173.778817 -86.414124) (xy 173.748044 -86.460637) (xy 173.710827 -86.502174) (xy 173.667959 -86.537849)
			(xy 173.620353 -86.566903) (xy 173.569024 -86.588715) (xy 173.515067 -86.602821) (xy 173.45963 -86.608921)
			(xy 173.403896 -86.606884) (xy 173.349053 -86.596754) (xy 173.296269 -86.578747) (xy 173.246669 -86.553246)
			(xy 173.201311 -86.520795) (xy 173.161162 -86.482086) (xy 173.127076 -86.437943) (xy 173.09978 -86.389308)
			(xy 173.079857 -86.337217) (xy 173.067731 -86.28278) (xy 173.06366 -86.227158) (xy 172.32576 -86.227158)
			(xy 168.584372 -96.108774) (xy 168.582594 -96.1136) (xy 168.395396 -96.813878) (xy 168.398952 -96.835214)
			(xy 168.405048 -96.844358) (xy 168.420114 -96.867933) (xy 168.443929 -96.918557) (xy 168.460103 -96.972115)
			(xy 168.46829 -97.027459) (xy 168.468802 -97.055432) (xy 168.468802 -97.055686) (xy 168.46833 -97.082656)
			(xy 168.460722 -97.136057) (xy 168.44567 -97.187855) (xy 168.423474 -97.237017) (xy 168.394576 -97.282563)
			(xy 168.359552 -97.323586) (xy 168.3191 -97.359269) (xy 168.274027 -97.388899) (xy 168.249854 -97.400872)
			(xy 168.249346 -97.40138) (xy 168.247314 -97.402142) (xy 168.233598 -97.418906) (xy 167.943276 -98.503994)
			(xy 167.952928 -98.53295) (xy 167.963342 -98.541078) (xy 167.96385 -98.541586) (xy 167.98684 -98.559724)
			(xy 168.027504 -98.601858) (xy 168.061251 -98.649712) (xy 168.087288 -98.702161) (xy 168.105003 -98.757974)
			(xy 168.11398 -98.815838) (xy 168.114472 -98.845116) (xy 168.113994 -98.872572) (xy 168.10612 -98.926915)
			(xy 168.090538 -98.979569) (xy 168.067569 -99.029446) (xy 168.037688 -99.075515) (xy 168.001512 -99.116825)
			(xy 167.959788 -99.152523) (xy 167.913378 -99.181871) (xy 167.86324 -99.204264) (xy 167.81041 -99.219238)
			(xy 167.783256 -99.223322) (xy 167.768016 -99.225354) (xy 167.744902 -99.245674) (xy 167.495951 -100.17633)
			(xy 169.739056 -100.17633) (xy 169.739056 -99.31273) (xy 169.739546 -99.282746) (xy 169.747374 -99.22329)
			(xy 169.762895 -99.165365) (xy 169.785844 -99.109961) (xy 169.815828 -99.058027) (xy 169.852334 -99.010451)
			(xy 169.894739 -98.968046) (xy 169.942315 -98.93154) (xy 169.994249 -98.901556) (xy 170.049653 -98.878607)
			(xy 170.107578 -98.863086) (xy 170.167034 -98.855258) (xy 170.227002 -98.855258) (xy 170.286458 -98.863086)
			(xy 170.344383 -98.878607) (xy 170.399787 -98.901556) (xy 170.451721 -98.93154) (xy 170.499297 -98.968046)
			(xy 170.541702 -99.010451) (xy 170.578208 -99.058027) (xy 170.608192 -99.109961) (xy 170.631141 -99.165365)
			(xy 170.646662 -99.22329) (xy 170.65449 -99.282746) (xy 170.65498 -99.31273) (xy 170.65498 -100.17633)
			(xy 170.65449 -100.206314) (xy 170.646662 -100.26577) (xy 170.631141 -100.323695) (xy 170.608192 -100.379099)
			(xy 170.578208 -100.431033) (xy 170.541702 -100.478609) (xy 170.499297 -100.521014) (xy 170.451721 -100.55752)
			(xy 170.399787 -100.587504) (xy 170.344383 -100.610453) (xy 170.286458 -100.625974) (xy 170.227002 -100.633802)
			(xy 170.167034 -100.633802) (xy 170.107578 -100.625974) (xy 170.049653 -100.610453) (xy 169.994249 -100.587504)
			(xy 169.942315 -100.55752) (xy 169.894739 -100.521014) (xy 169.852334 -100.478609) (xy 169.815828 -100.431033)
			(xy 169.785844 -100.379099) (xy 169.762895 -100.323695) (xy 169.747374 -100.26577) (xy 169.739546 -100.206314)
			(xy 169.739056 -100.17633) (xy 167.495951 -100.17633) (xy 167.014424 -101.976428) (xy 167.884856 -101.976428)
			(xy 167.884856 -101.112828) (xy 167.885346 -101.082844) (xy 167.893174 -101.023388) (xy 167.908695 -100.965463)
			(xy 167.931644 -100.910059) (xy 167.961628 -100.858125) (xy 167.998134 -100.810549) (xy 168.040539 -100.768144)
			(xy 168.088115 -100.731638) (xy 168.140049 -100.701654) (xy 168.195453 -100.678705) (xy 168.253378 -100.663184)
			(xy 168.312834 -100.655356) (xy 168.372802 -100.655356) (xy 168.432258 -100.663184) (xy 168.490183 -100.678705)
			(xy 168.545587 -100.701654) (xy 168.597521 -100.731638) (xy 168.645097 -100.768144) (xy 168.687502 -100.810549)
			(xy 168.724008 -100.858125) (xy 168.753992 -100.910059) (xy 168.776941 -100.965463) (xy 168.792462 -101.023388)
			(xy 168.80029 -101.082844) (xy 168.80078 -101.112828) (xy 168.80078 -101.976428) (xy 168.80029 -102.006412)
			(xy 168.792462 -102.065868) (xy 168.776941 -102.123793) (xy 168.753992 -102.179197) (xy 168.724008 -102.231131)
			(xy 168.687502 -102.278707) (xy 168.645097 -102.321112) (xy 168.597521 -102.357618) (xy 168.545587 -102.387602)
			(xy 168.490183 -102.410551) (xy 168.432258 -102.426072) (xy 168.372802 -102.4339) (xy 168.312834 -102.4339)
			(xy 168.253378 -102.426072) (xy 168.195453 -102.410551) (xy 168.140049 -102.387602) (xy 168.088115 -102.357618)
			(xy 168.040539 -102.321112) (xy 167.998134 -102.278707) (xy 167.961628 -102.231131) (xy 167.931644 -102.179197)
			(xy 167.908695 -102.123793) (xy 167.893174 -102.065868) (xy 167.885346 -102.006412) (xy 167.884856 -101.976428)
			(xy 167.014424 -101.976428) (xy 166.532964 -103.776272) (xy 169.739056 -103.776272) (xy 169.739056 -102.912672)
			(xy 169.739546 -102.882688) (xy 169.747374 -102.823232) (xy 169.762895 -102.765307) (xy 169.785844 -102.709903)
			(xy 169.815828 -102.657969) (xy 169.852334 -102.610393) (xy 169.894739 -102.567988) (xy 169.942315 -102.531482)
			(xy 169.994249 -102.501498) (xy 170.049653 -102.478549) (xy 170.107578 -102.463028) (xy 170.167034 -102.4552)
			(xy 170.227002 -102.4552) (xy 170.286458 -102.463028) (xy 170.344383 -102.478549) (xy 170.399787 -102.501498)
			(xy 170.451721 -102.531482) (xy 170.499297 -102.567988) (xy 170.541702 -102.610393) (xy 170.578208 -102.657969)
			(xy 170.608192 -102.709903) (xy 170.631141 -102.765307) (xy 170.646662 -102.823232) (xy 170.65449 -102.882688)
			(xy 170.65498 -102.912672) (xy 170.65498 -103.776272) (xy 170.65449 -103.806256) (xy 170.646662 -103.865712)
			(xy 170.631141 -103.923637) (xy 170.608192 -103.979041) (xy 170.578208 -104.030975) (xy 170.541702 -104.078551)
			(xy 170.499297 -104.120956) (xy 170.451721 -104.157462) (xy 170.399787 -104.187446) (xy 170.344383 -104.210395)
			(xy 170.286458 -104.225916) (xy 170.227002 -104.233744) (xy 170.167034 -104.233744) (xy 170.107578 -104.225916)
			(xy 170.049653 -104.210395) (xy 169.994249 -104.187446) (xy 169.942315 -104.157462) (xy 169.894739 -104.120956)
			(xy 169.852334 -104.078551) (xy 169.815828 -104.030975) (xy 169.785844 -103.979041) (xy 169.762895 -103.923637)
			(xy 169.747374 -103.865712) (xy 169.739546 -103.806256) (xy 169.739056 -103.776272) (xy 166.532964 -103.776272)
			(xy 166.051437 -105.57637) (xy 167.884856 -105.57637) (xy 167.884856 -104.71277) (xy 167.885346 -104.682786)
			(xy 167.893174 -104.62333) (xy 167.908695 -104.565405) (xy 167.931644 -104.510001) (xy 167.961628 -104.458067)
			(xy 167.998134 -104.410491) (xy 168.040539 -104.368086) (xy 168.088115 -104.33158) (xy 168.140049 -104.301596)
			(xy 168.195453 -104.278647) (xy 168.253378 -104.263126) (xy 168.312834 -104.255298) (xy 168.372802 -104.255298)
			(xy 168.432258 -104.263126) (xy 168.490183 -104.278647) (xy 168.545587 -104.301596) (xy 168.597521 -104.33158)
			(xy 168.645097 -104.368086) (xy 168.687502 -104.410491) (xy 168.724008 -104.458067) (xy 168.753992 -104.510001)
			(xy 168.776941 -104.565405) (xy 168.792462 -104.62333) (xy 168.80029 -104.682786) (xy 168.80078 -104.71277)
			(xy 168.80078 -105.57637) (xy 168.80029 -105.606354) (xy 168.792462 -105.66581) (xy 168.776941 -105.723735)
			(xy 168.753992 -105.779139) (xy 168.724008 -105.831073) (xy 168.687502 -105.878649) (xy 168.645097 -105.921054)
			(xy 168.597521 -105.95756) (xy 168.545587 -105.987544) (xy 168.490183 -106.010493) (xy 168.432258 -106.026014)
			(xy 168.372802 -106.033842) (xy 168.312834 -106.033842) (xy 168.253378 -106.026014) (xy 168.195453 -106.010493)
			(xy 168.140049 -105.987544) (xy 168.088115 -105.95756) (xy 168.040539 -105.921054) (xy 167.998134 -105.878649)
			(xy 167.961628 -105.831073) (xy 167.931644 -105.779139) (xy 167.908695 -105.723735) (xy 167.893174 -105.66581)
			(xy 167.885346 -105.606354) (xy 167.884856 -105.57637) (xy 166.051437 -105.57637) (xy 165.659054 -107.04322)
			(xy 165.666674 -107.050078) (xy 165.695884 -107.064302) (xy 165.719657 -107.076403) (xy 165.76389 -107.106216)
			(xy 165.803545 -107.141894) (xy 165.837847 -107.182745) (xy 165.866131 -107.227971) (xy 165.887846 -107.276694)
			(xy 165.902568 -107.327964) (xy 165.909368 -107.376214) (xy 169.739056 -107.376214) (xy 169.739056 -106.512614)
			(xy 169.739546 -106.48263) (xy 169.747374 -106.423174) (xy 169.762895 -106.365249) (xy 169.785844 -106.309845)
			(xy 169.815828 -106.257911) (xy 169.852334 -106.210335) (xy 169.894739 -106.16793) (xy 169.942315 -106.131424)
			(xy 169.994249 -106.10144) (xy 170.049653 -106.078491) (xy 170.107578 -106.06297) (xy 170.167034 -106.055142)
			(xy 170.227002 -106.055142) (xy 170.286458 -106.06297) (xy 170.344383 -106.078491) (xy 170.399787 -106.10144)
			(xy 170.451721 -106.131424) (xy 170.499297 -106.16793) (xy 170.541702 -106.210335) (xy 170.578208 -106.257911)
			(xy 170.608192 -106.309845) (xy 170.631141 -106.365249) (xy 170.646662 -106.423174) (xy 170.65449 -106.48263)
			(xy 170.65498 -106.512614) (xy 170.65498 -107.376214) (xy 170.65449 -107.406198) (xy 170.646662 -107.465654)
			(xy 170.631141 -107.523579) (xy 170.608192 -107.578983) (xy 170.578208 -107.630917) (xy 170.541702 -107.678493)
			(xy 170.499297 -107.720898) (xy 170.451721 -107.757404) (xy 170.399787 -107.787388) (xy 170.344383 -107.810337)
			(xy 170.286458 -107.825858) (xy 170.227002 -107.833686) (xy 170.167034 -107.833686) (xy 170.107578 -107.825858)
			(xy 170.049653 -107.810337) (xy 169.994249 -107.787388) (xy 169.942315 -107.757404) (xy 169.894739 -107.720898)
			(xy 169.852334 -107.678493) (xy 169.815828 -107.630917) (xy 169.785844 -107.578983) (xy 169.762895 -107.523579)
			(xy 169.747374 -107.465654) (xy 169.739546 -107.406198) (xy 169.739056 -107.376214) (xy 165.909368 -107.376214)
			(xy 165.910012 -107.380785) (xy 165.910514 -107.407456) (xy 165.910054 -107.434711) (xy 165.902302 -107.488667)
			(xy 165.88695 -107.540971) (xy 165.86431 -107.590557) (xy 165.834843 -107.636416) (xy 165.799149 -107.677614)
			(xy 165.757956 -107.713313) (xy 165.712101 -107.742786) (xy 165.662517 -107.765432) (xy 165.610216 -107.780791)
			(xy 165.556261 -107.78855) (xy 165.529006 -107.788964) (xy 165.528752 -107.788964) (xy 165.494208 -107.78744)
			(xy 165.493192 -107.78744) (xy 165.479222 -107.786424) (xy 165.473946 -107.786726) (xy 165.463695 -107.789279)
			(xy 165.458902 -107.791504) (xy 165.088348 -109.176312) (xy 167.884856 -109.176312) (xy 167.884856 -108.312712)
			(xy 167.885346 -108.282728) (xy 167.893174 -108.223272) (xy 167.908695 -108.165347) (xy 167.931644 -108.109943)
			(xy 167.961628 -108.058009) (xy 167.998134 -108.010433) (xy 168.040539 -107.968028) (xy 168.088115 -107.931522)
			(xy 168.140049 -107.901538) (xy 168.195453 -107.878589) (xy 168.253378 -107.863068) (xy 168.312834 -107.85524)
			(xy 168.372802 -107.85524) (xy 168.432258 -107.863068) (xy 168.490183 -107.878589) (xy 168.545587 -107.901538)
			(xy 168.597521 -107.931522) (xy 168.645097 -107.968028) (xy 168.687502 -108.010433) (xy 168.724008 -108.058009)
			(xy 168.753992 -108.109943) (xy 168.776941 -108.165347) (xy 168.792462 -108.223272) (xy 168.80029 -108.282728)
			(xy 168.80078 -108.312712) (xy 168.80078 -109.176312) (xy 168.80029 -109.206296) (xy 168.792462 -109.265752)
			(xy 168.776941 -109.323677) (xy 168.753992 -109.379081) (xy 168.724008 -109.431015) (xy 168.687502 -109.478591)
			(xy 168.645097 -109.520996) (xy 168.597521 -109.557502) (xy 168.545587 -109.587486) (xy 168.490183 -109.610435)
			(xy 168.432258 -109.625956) (xy 168.372802 -109.633784) (xy 168.312834 -109.633784) (xy 168.253378 -109.625956)
			(xy 168.195453 -109.610435) (xy 168.140049 -109.587486) (xy 168.088115 -109.557502) (xy 168.040539 -109.520996)
			(xy 167.998134 -109.478591) (xy 167.961628 -109.431015) (xy 167.931644 -109.379081) (xy 167.908695 -109.323677)
			(xy 167.893174 -109.265752) (xy 167.885346 -109.206296) (xy 167.884856 -109.176312) (xy 165.088348 -109.176312)
			(xy 164.807646 -110.225332) (xy 164.807646 -110.22584) (xy 164.612532 -110.97641) (xy 169.739056 -110.97641)
			(xy 169.739056 -110.11281) (xy 169.739546 -110.082826) (xy 169.747374 -110.02337) (xy 169.762895 -109.965445)
			(xy 169.785844 -109.910041) (xy 169.815828 -109.858107) (xy 169.852334 -109.810531) (xy 169.894739 -109.768126)
			(xy 169.942315 -109.73162) (xy 169.994249 -109.701636) (xy 170.049653 -109.678687) (xy 170.107578 -109.663166)
			(xy 170.167034 -109.655338) (xy 170.227002 -109.655338) (xy 170.286458 -109.663166) (xy 170.344383 -109.678687)
			(xy 170.399787 -109.701636) (xy 170.451721 -109.73162) (xy 170.499297 -109.768126) (xy 170.541702 -109.810531)
			(xy 170.578208 -109.858107) (xy 170.608192 -109.910041) (xy 170.631141 -109.965445) (xy 170.646662 -110.02337)
			(xy 170.65449 -110.082826) (xy 170.65498 -110.11281) (xy 170.65498 -110.97641) (xy 170.65449 -111.006394)
			(xy 170.646662 -111.06585) (xy 170.631141 -111.123775) (xy 170.608192 -111.179179) (xy 170.578208 -111.231113)
			(xy 170.541702 -111.278689) (xy 170.499297 -111.321094) (xy 170.451721 -111.3576) (xy 170.399787 -111.387584)
			(xy 170.344383 -111.410533) (xy 170.286458 -111.426054) (xy 170.227002 -111.433882) (xy 170.167034 -111.433882)
			(xy 170.107578 -111.426054) (xy 170.049653 -111.410533) (xy 169.994249 -111.387584) (xy 169.942315 -111.3576)
			(xy 169.894739 -111.321094) (xy 169.852334 -111.278689) (xy 169.815828 -111.231113) (xy 169.785844 -111.179179)
			(xy 169.762895 -111.123775) (xy 169.747374 -111.06585) (xy 169.739546 -111.006394) (xy 169.739056 -110.97641)
			(xy 164.612532 -110.97641) (xy 164.144587 -112.776508) (xy 167.884856 -112.776508) (xy 167.884856 -111.912908)
			(xy 167.885346 -111.882924) (xy 167.893174 -111.823468) (xy 167.908695 -111.765543) (xy 167.931644 -111.710139)
			(xy 167.961628 -111.658205) (xy 167.998134 -111.610629) (xy 168.040539 -111.568224) (xy 168.088115 -111.531718)
			(xy 168.140049 -111.501734) (xy 168.195453 -111.478785) (xy 168.253378 -111.463264) (xy 168.312834 -111.455436)
			(xy 168.372802 -111.455436) (xy 168.432258 -111.463264) (xy 168.490183 -111.478785) (xy 168.545587 -111.501734)
			(xy 168.597521 -111.531718) (xy 168.645097 -111.568224) (xy 168.687502 -111.610629) (xy 168.724008 -111.658205)
			(xy 168.753992 -111.710139) (xy 168.776941 -111.765543) (xy 168.792462 -111.823468) (xy 168.80029 -111.882924)
			(xy 168.80078 -111.912908) (xy 168.80078 -112.776508) (xy 168.80029 -112.806492) (xy 168.792462 -112.865948)
			(xy 168.776941 -112.923873) (xy 168.753992 -112.979277) (xy 168.724008 -113.031211) (xy 168.687502 -113.078787)
			(xy 168.645097 -113.121192) (xy 168.597521 -113.157698) (xy 168.545587 -113.187682) (xy 168.490183 -113.210631)
			(xy 168.432258 -113.226152) (xy 168.372802 -113.23398) (xy 168.312834 -113.23398) (xy 168.253378 -113.226152)
			(xy 168.195453 -113.210631) (xy 168.140049 -113.187682) (xy 168.088115 -113.157698) (xy 168.040539 -113.121192)
			(xy 167.998134 -113.078787) (xy 167.961628 -113.031211) (xy 167.931644 -112.979277) (xy 167.908695 -112.923873)
			(xy 167.893174 -112.865948) (xy 167.885346 -112.806492) (xy 167.884856 -112.776508) (xy 164.144587 -112.776508)
			(xy 163.310316 -115.985798) (xy 163.310062 -115.987068) (xy 163.308538 -115.997228) (xy 163.329366 -118.388384)
			(xy 163.329569 -118.394472) (xy 163.332515 -118.406288) (xy 163.335208 -118.411752) (xy 163.350956 -118.441724)
			(xy 163.354004 -118.44401) (xy 163.374894 -118.459432) (xy 163.412707 -118.495016) (xy 163.44535 -118.535395)
			(xy 163.47222 -118.579826) (xy 163.492823 -118.627487) (xy 163.506777 -118.677501) (xy 163.513825 -118.728944)
			(xy 163.514278 -118.754906) (xy 163.51373 -118.78402) (xy 163.504889 -118.841573) (xy 163.487414 -118.897117)
			(xy 163.461709 -118.949364) (xy 163.42837 -118.997103) (xy 163.38817 -119.039227) (xy 163.365434 -119.05742)
			(xy 163.361878 -119.05996) (xy 163.361116 -119.060722) (xy 163.35629 -119.064278) (xy 163.34105 -119.093996)
			(xy 163.33842 -119.099542) (xy 163.335588 -119.111482) (xy 163.335462 -119.117618) (xy 163.343777 -120.086374)
			(xy 169.739056 -120.086374) (xy 169.739056 -119.222774) (xy 169.739546 -119.19279) (xy 169.747374 -119.133334)
			(xy 169.762895 -119.075409) (xy 169.785844 -119.020005) (xy 169.815828 -118.968071) (xy 169.852334 -118.920495)
			(xy 169.894739 -118.87809) (xy 169.942315 -118.841584) (xy 169.994249 -118.8116) (xy 170.049653 -118.788651)
			(xy 170.107578 -118.77313) (xy 170.167034 -118.765302) (xy 170.227002 -118.765302) (xy 170.286458 -118.77313)
			(xy 170.344383 -118.788651) (xy 170.399787 -118.8116) (xy 170.451721 -118.841584) (xy 170.499297 -118.87809)
			(xy 170.541702 -118.920495) (xy 170.578208 -118.968071) (xy 170.608192 -119.020005) (xy 170.631141 -119.075409)
			(xy 170.646662 -119.133334) (xy 170.65449 -119.19279) (xy 170.65498 -119.222774) (xy 170.65498 -120.086374)
			(xy 170.65449 -120.116358) (xy 170.646662 -120.175814) (xy 170.631141 -120.233739) (xy 170.608192 -120.289143)
			(xy 170.578208 -120.341077) (xy 170.541702 -120.388653) (xy 170.499297 -120.431058) (xy 170.451721 -120.467564)
			(xy 170.399787 -120.497548) (xy 170.344383 -120.520497) (xy 170.286458 -120.536018) (xy 170.227002 -120.543846)
			(xy 170.167034 -120.543846) (xy 170.107578 -120.536018) (xy 170.049653 -120.520497) (xy 169.994249 -120.497548)
			(xy 169.942315 -120.467564) (xy 169.894739 -120.431058) (xy 169.852334 -120.388653) (xy 169.815828 -120.341077)
			(xy 169.785844 -120.289143) (xy 169.762895 -120.233739) (xy 169.747374 -120.175814) (xy 169.739546 -120.116358)
			(xy 169.739056 -120.086374) (xy 163.343777 -120.086374) (xy 163.34486 -120.212612) (xy 163.345459 -120.222751)
			(xy 163.353579 -120.241349) (xy 163.360608 -120.24868) (xy 163.364164 -120.251982) (xy 163.364672 -120.252236)
			(xy 163.387499 -120.270403) (xy 163.427887 -120.312498) (xy 163.461393 -120.360254) (xy 163.487236 -120.412555)
			(xy 163.504812 -120.468181) (xy 163.513711 -120.525836) (xy 163.514278 -120.555004) (xy 163.513768 -120.583605)
			(xy 163.505234 -120.640168) (xy 163.488356 -120.694824) (xy 163.463512 -120.74635) (xy 163.431259 -120.793593)
			(xy 163.392319 -120.835496) (xy 163.37026 -120.853708) (xy 163.367212 -120.856248) (xy 163.359791 -120.863819)
			(xy 163.351367 -120.883248) (xy 163.350956 -120.89384) (xy 163.358322 -121.752868) (xy 163.359022 -121.765305)
			(xy 163.370745 -121.787253) (xy 163.380674 -121.794778) (xy 163.384484 -121.79681) (xy 163.409555 -121.811385)
			(xy 163.455373 -121.846928) (xy 163.492903 -121.886472) (xy 167.884856 -121.886472) (xy 167.884856 -121.022872)
			(xy 167.885346 -120.992888) (xy 167.893174 -120.933432) (xy 167.908695 -120.875507) (xy 167.931644 -120.820103)
			(xy 167.961628 -120.768169) (xy 167.998134 -120.720593) (xy 168.040539 -120.678188) (xy 168.088115 -120.641682)
			(xy 168.140049 -120.611698) (xy 168.195453 -120.588749) (xy 168.253378 -120.573228) (xy 168.312834 -120.5654)
			(xy 168.372802 -120.5654) (xy 168.432258 -120.573228) (xy 168.490183 -120.588749) (xy 168.545587 -120.611698)
			(xy 168.597521 -120.641682) (xy 168.645097 -120.678188) (xy 168.687502 -120.720593) (xy 168.724008 -120.768169)
			(xy 168.753992 -120.820103) (xy 168.776941 -120.875507) (xy 168.792462 -120.933432) (xy 168.80029 -120.992888)
			(xy 168.80078 -121.022872) (xy 168.80078 -121.886472) (xy 168.80029 -121.916456) (xy 168.792462 -121.975912)
			(xy 168.776941 -122.033837) (xy 168.753992 -122.089241) (xy 168.724008 -122.141175) (xy 168.687502 -122.188751)
			(xy 168.645097 -122.231156) (xy 168.597521 -122.267662) (xy 168.545587 -122.297646) (xy 168.490183 -122.320595)
			(xy 168.432258 -122.336116) (xy 168.372802 -122.343944) (xy 168.312834 -122.343944) (xy 168.253378 -122.336116)
			(xy 168.195453 -122.320595) (xy 168.140049 -122.297646) (xy 168.088115 -122.267662) (xy 168.040539 -122.231156)
			(xy 167.998134 -122.188751) (xy 167.961628 -122.141175) (xy 167.931644 -122.089241) (xy 167.908695 -122.033837)
			(xy 167.893174 -121.975912) (xy 167.885346 -121.916456) (xy 167.884856 -121.886472) (xy 163.492903 -121.886472)
			(xy 163.495292 -121.888989) (xy 163.528393 -121.936602) (xy 163.553917 -121.988671) (xy 163.571275 -122.044)
			(xy 163.58007 -122.101318) (xy 163.580572 -122.130312) (xy 163.580088 -122.158272) (xy 163.571935 -122.213595)
			(xy 163.55579 -122.267134) (xy 163.532 -122.317741) (xy 163.501075 -122.364332) (xy 163.463678 -122.405907)
			(xy 163.42061 -122.441575) (xy 163.39693 -122.456448) (xy 163.389818 -122.46102) (xy 163.37153 -122.492516)
			(xy 163.368318 -122.498503) (xy 163.364836 -122.511632) (xy 163.364672 -122.518424) (xy 163.371784 -123.318524)
			(xy 163.374962 -123.686316) (xy 169.739056 -123.686316) (xy 169.739056 -122.822716) (xy 169.739546 -122.792732)
			(xy 169.747374 -122.733276) (xy 169.762895 -122.675351) (xy 169.785844 -122.619947) (xy 169.815828 -122.568013)
			(xy 169.852334 -122.520437) (xy 169.894739 -122.478032) (xy 169.942315 -122.441526) (xy 169.994249 -122.411542)
			(xy 170.049653 -122.388593) (xy 170.107578 -122.373072) (xy 170.167034 -122.365244) (xy 170.227002 -122.365244)
			(xy 170.286458 -122.373072) (xy 170.344383 -122.388593) (xy 170.399787 -122.411542) (xy 170.451721 -122.441526)
			(xy 170.499297 -122.478032) (xy 170.541702 -122.520437) (xy 170.578208 -122.568013) (xy 170.608192 -122.619947)
			(xy 170.631141 -122.675351) (xy 170.646662 -122.733276) (xy 170.65449 -122.792732) (xy 170.65498 -122.822716)
			(xy 170.65498 -123.686316) (xy 170.65449 -123.7163) (xy 170.646662 -123.775756) (xy 170.631141 -123.833681)
			(xy 170.608192 -123.889085) (xy 170.578208 -123.941019) (xy 170.541702 -123.988595) (xy 170.499297 -124.031)
			(xy 170.451721 -124.067506) (xy 170.399787 -124.09749) (xy 170.344383 -124.120439) (xy 170.286458 -124.13596)
			(xy 170.227002 -124.143788) (xy 170.167034 -124.143788) (xy 170.107578 -124.13596) (xy 170.049653 -124.120439)
			(xy 169.994249 -124.09749) (xy 169.942315 -124.067506) (xy 169.894739 -124.031) (xy 169.852334 -123.988595)
			(xy 169.815828 -123.941019) (xy 169.785844 -123.889085) (xy 169.762895 -123.833681) (xy 169.747374 -123.775756)
			(xy 169.739546 -123.7163) (xy 169.739056 -123.686316) (xy 163.374962 -123.686316) (xy 163.390518 -125.486414)
			(xy 167.884856 -125.486414) (xy 167.884856 -124.622814) (xy 167.885346 -124.59283) (xy 167.893174 -124.533374)
			(xy 167.908695 -124.475449) (xy 167.931644 -124.420045) (xy 167.961628 -124.368111) (xy 167.998134 -124.320535)
			(xy 168.040539 -124.27813) (xy 168.088115 -124.241624) (xy 168.140049 -124.21164) (xy 168.195453 -124.188691)
			(xy 168.253378 -124.17317) (xy 168.312834 -124.165342) (xy 168.372802 -124.165342) (xy 168.432258 -124.17317)
			(xy 168.490183 -124.188691) (xy 168.545587 -124.21164) (xy 168.597521 -124.241624) (xy 168.645097 -124.27813)
			(xy 168.687502 -124.320535) (xy 168.724008 -124.368111) (xy 168.753992 -124.420045) (xy 168.776941 -124.475449)
			(xy 168.792462 -124.533374) (xy 168.80029 -124.59283) (xy 168.80078 -124.622814) (xy 168.80078 -125.486414)
			(xy 168.80029 -125.516398) (xy 168.792462 -125.575854) (xy 168.776941 -125.633779) (xy 168.753992 -125.689183)
			(xy 168.724008 -125.741117) (xy 168.687502 -125.788693) (xy 168.645097 -125.831098) (xy 168.597521 -125.867604)
			(xy 168.545587 -125.897588) (xy 168.490183 -125.920537) (xy 168.432258 -125.936058) (xy 168.372802 -125.943886)
			(xy 168.312834 -125.943886) (xy 168.253378 -125.936058) (xy 168.195453 -125.920537) (xy 168.140049 -125.897588)
			(xy 168.088115 -125.867604) (xy 168.040539 -125.831098) (xy 167.998134 -125.788693) (xy 167.961628 -125.741117)
			(xy 167.931644 -125.689183) (xy 167.908695 -125.633779) (xy 167.893174 -125.575854) (xy 167.885346 -125.516398)
			(xy 167.884856 -125.486414) (xy 163.390518 -125.486414) (xy 163.426902 -129.696718) (xy 163.426954 -129.70079)
			(xy 163.428227 -129.708833) (xy 163.429442 -129.71272) (xy 163.437062 -129.734564) (xy 163.437316 -129.734818)
			(xy 163.455431 -129.759803) (xy 163.484189 -129.814402) (xy 163.503773 -129.872922) (xy 163.513671 -129.933833)
			(xy 163.514278 -129.964688) (xy 163.514278 -129.964942) (xy 163.5125 -130.001772) (xy 163.511738 -130.009646)
			(xy 163.507437 -130.040724) (xy 163.489996 -130.100987) (xy 163.46292 -130.15758) (xy 163.445444 -130.183636)
			(xy 163.440872 -130.189986) (xy 163.434014 -130.211322) (xy 163.432835 -130.215217) (xy 163.431561 -130.223255)
			(xy 163.431474 -130.227324) (xy 163.44265 -131.519676) (xy 163.442731 -131.523419) (xy 163.443881 -131.530816)
			(xy 163.444936 -131.534408) (xy 163.451032 -131.55422) (xy 163.454588 -131.559808) (xy 163.468751 -131.582915)
			(xy 163.491131 -131.632274) (xy 163.506322 -131.684297) (xy 163.51402 -131.737943) (xy 163.514532 -131.76504)
			(xy 163.514278 -131.770628) (xy 163.512754 -131.800092) (xy 163.5125 -131.803648) (xy 163.511992 -131.807712)
			(xy 163.509078 -131.830432) (xy 163.498506 -131.875002) (xy 163.49091 -131.896612) (xy 163.484259 -131.914176)
			(xy 163.467971 -131.948018) (xy 163.458398 -131.964176) (xy 163.45281 -131.976622) (xy 163.449 -131.98983)
			(xy 163.448032 -131.99337) (xy 163.447006 -132.000638) (xy 163.446968 -132.004308) (xy 163.456473 -133.096508)
			(xy 167.884856 -133.096508) (xy 167.884856 -132.232908) (xy 167.885346 -132.202924) (xy 167.893174 -132.143468)
			(xy 167.908695 -132.085543) (xy 167.931644 -132.030139) (xy 167.961628 -131.978205) (xy 167.998134 -131.930629)
			(xy 168.040539 -131.888224) (xy 168.088115 -131.851718) (xy 168.140049 -131.821734) (xy 168.195453 -131.798785)
			(xy 168.253378 -131.783264) (xy 168.312834 -131.775436) (xy 168.372802 -131.775436) (xy 168.432258 -131.783264)
			(xy 168.490183 -131.798785) (xy 168.545587 -131.821734) (xy 168.597521 -131.851718) (xy 168.645097 -131.888224)
			(xy 168.687502 -131.930629) (xy 168.724008 -131.978205) (xy 168.753992 -132.030139) (xy 168.776941 -132.085543)
			(xy 168.792462 -132.143468) (xy 168.80029 -132.202924) (xy 168.80078 -132.232908) (xy 168.80078 -133.096508)
			(xy 168.80029 -133.126492) (xy 168.792462 -133.185948) (xy 168.776941 -133.243873) (xy 168.753992 -133.299277)
			(xy 168.724008 -133.351211) (xy 168.687502 -133.398787) (xy 168.645097 -133.441192) (xy 168.597521 -133.477698)
			(xy 168.545587 -133.507682) (xy 168.490183 -133.530631) (xy 168.432258 -133.546152) (xy 168.372802 -133.55398)
			(xy 168.312834 -133.55398) (xy 168.253378 -133.546152) (xy 168.195453 -133.530631) (xy 168.140049 -133.507682)
			(xy 168.088115 -133.477698) (xy 168.040539 -133.441192) (xy 167.998134 -133.398787) (xy 167.961628 -133.351211)
			(xy 167.931644 -133.299277) (xy 167.908695 -133.243873) (xy 167.893174 -133.185948) (xy 167.885346 -133.126492)
			(xy 167.884856 -133.096508) (xy 163.456473 -133.096508) (xy 163.458652 -133.346952) (xy 163.460176 -133.359398)
			(xy 163.465002 -133.377432) (xy 163.467288 -133.38175) (xy 163.482072 -133.410033) (xy 163.503027 -133.470308)
			(xy 163.51365 -133.533231) (xy 163.514278 -133.565138) (xy 163.514278 -133.565392) (xy 163.513871 -133.590063)
			(xy 163.507471 -133.63899) (xy 163.494816 -133.686684) (xy 163.48583 -133.709664) (xy 163.48583 -133.710172)
			(xy 163.474908 -133.737604) (xy 163.469034 -133.744794) (xy 163.462381 -133.762112) (xy 163.461954 -133.771386)
			(xy 163.487425 -136.69645) (xy 167.884856 -136.69645) (xy 167.884856 -135.83285) (xy 167.885346 -135.802866)
			(xy 167.893174 -135.74341) (xy 167.908695 -135.685485) (xy 167.931644 -135.630081) (xy 167.961628 -135.578147)
			(xy 167.998134 -135.530571) (xy 168.040539 -135.488166) (xy 168.088115 -135.45166) (xy 168.140049 -135.421676)
			(xy 168.195453 -135.398727) (xy 168.253378 -135.383206) (xy 168.312834 -135.375378) (xy 168.372802 -135.375378)
			(xy 168.432258 -135.383206) (xy 168.490183 -135.398727) (xy 168.545587 -135.421676) (xy 168.597521 -135.45166)
			(xy 168.645097 -135.488166) (xy 168.687502 -135.530571) (xy 168.724008 -135.578147) (xy 168.753992 -135.630081)
			(xy 168.776941 -135.685485) (xy 168.792462 -135.74341) (xy 168.80029 -135.802866) (xy 168.80078 -135.83285)
			(xy 168.80078 -136.69645) (xy 168.80029 -136.726434) (xy 168.792462 -136.78589) (xy 168.776941 -136.843815)
			(xy 168.753992 -136.899219) (xy 168.724008 -136.951153) (xy 168.687502 -136.998729) (xy 168.645097 -137.041134)
			(xy 168.597521 -137.07764) (xy 168.545587 -137.107624) (xy 168.490183 -137.130573) (xy 168.432258 -137.146094)
			(xy 168.372802 -137.153922) (xy 168.312834 -137.153922) (xy 168.253378 -137.146094) (xy 168.195453 -137.130573)
			(xy 168.140049 -137.107624) (xy 168.088115 -137.07764) (xy 168.040539 -137.041134) (xy 167.998134 -136.998729)
			(xy 167.961628 -136.951153) (xy 167.931644 -136.899219) (xy 167.908695 -136.843815) (xy 167.893174 -136.78589)
			(xy 167.885346 -136.726434) (xy 167.884856 -136.69645) (xy 163.487425 -136.69645) (xy 163.501832 -138.351006)
			(xy 163.503356 -138.363452) (xy 163.507928 -138.380978) (xy 163.510722 -138.386312) (xy 163.524567 -138.413882)
			(xy 163.544155 -138.47238) (xy 163.554086 -138.533267) (xy 163.554664 -138.564112) (xy 163.554046 -138.594859)
			(xy 163.544183 -138.655558) (xy 163.524717 -138.713891) (xy 163.510976 -138.741404) (xy 163.50869 -138.745722)
			(xy 163.507246 -138.749579) (xy 163.505456 -138.757618) (xy 163.505134 -138.761724) (xy 163.510722 -139.399772)
			(xy 163.511716 -139.409797) (xy 163.520334 -139.427984) (xy 163.527486 -139.435078) (xy 163.549106 -139.453296)
			(xy 163.587251 -139.495025) (xy 163.618817 -139.541928) (xy 163.643112 -139.592977) (xy 163.659603 -139.647055)
			(xy 163.66793 -139.702974) (xy 163.668456 -139.731242) (xy 163.667957 -139.75895) (xy 163.659932 -139.813783)
			(xy 163.644057 -139.866877) (xy 163.620666 -139.917116) (xy 163.590253 -139.963441) (xy 163.553456 -140.004878)
			(xy 163.532566 -140.023088) (xy 163.525268 -140.030507) (xy 163.516874 -140.049526) (xy 163.51631 -140.059918)
			(xy 163.51631 -140.060934) (xy 163.516564 -140.082016) (xy 163.516564 -140.082524) (xy 163.51679 -140.127482)
			(xy 167.705022 -140.127482) (xy 167.709093 -140.07186) (xy 167.721219 -140.017423) (xy 167.741142 -139.965332)
			(xy 167.768438 -139.916697) (xy 167.802524 -139.872554) (xy 167.842673 -139.833845) (xy 167.888031 -139.801394)
			(xy 167.937631 -139.775893) (xy 167.990415 -139.757886) (xy 168.045258 -139.747756) (xy 168.100992 -139.745719)
			(xy 168.156429 -139.751819) (xy 168.210386 -139.765925) (xy 168.261715 -139.787737) (xy 168.309321 -139.816791)
			(xy 168.352189 -139.852466) (xy 168.389406 -139.894003) (xy 168.420179 -139.940516) (xy 168.443851 -139.991013)
			(xy 168.459919 -140.04442) (xy 168.468039 -140.099596) (xy 168.468548 -140.127482) (xy 168.468039 -140.155368)
			(xy 168.459919 -140.210544) (xy 168.443851 -140.263951) (xy 168.420179 -140.314448) (xy 168.389406 -140.360961)
			(xy 168.352189 -140.402498) (xy 168.309321 -140.438173) (xy 168.261715 -140.467227) (xy 168.210386 -140.489039)
			(xy 168.156429 -140.503145) (xy 168.100992 -140.509245) (xy 168.045258 -140.507208) (xy 167.990415 -140.497078)
			(xy 167.937631 -140.479071) (xy 167.888031 -140.45357) (xy 167.842673 -140.421119) (xy 167.802524 -140.38241)
			(xy 167.768438 -140.338267) (xy 167.741142 -140.289632) (xy 167.721219 -140.237541) (xy 167.709093 -140.183104)
			(xy 167.705022 -140.127482) (xy 163.51679 -140.127482) (xy 163.516818 -140.13307) (xy 163.51763 -140.140961)
			(xy 163.52345 -140.155708) (xy 163.528248 -140.162026) (xy 163.531042 -140.16482) (xy 163.550876 -140.186235)
			(xy 163.584469 -140.233966) (xy 163.610409 -140.286252) (xy 163.628091 -140.341877) (xy 163.637104 -140.399544)
			(xy 163.637722 -140.428726) (xy 163.637722 -140.43025) (xy 163.637468 -140.436092) (xy 163.637214 -140.44168)
			(xy 163.637214 -140.444728) (xy 163.635684 -140.471641) (xy 163.625999 -140.524669) (xy 163.608955 -140.575809)
			(xy 163.584891 -140.624046) (xy 163.554285 -140.66842) (xy 163.536376 -140.688568) (xy 163.533613 -140.691655)
			(xy 163.52901 -140.698542) (xy 163.527232 -140.702284) (xy 163.52012 -140.718032) (xy 163.518426 -140.722229)
			(xy 163.516385 -140.731044) (xy 163.516056 -140.735558) (xy 163.474908 -141.360398) (xy 163.474908 -141.364462)
			(xy 163.479988 -141.876526) (xy 163.479988 -141.886686) (xy 163.479981 -141.903588) (xy 163.478966 -141.937378)
			(xy 163.477956 -141.95425) (xy 163.433996 -142.60068) (xy 167.705532 -142.60068) (xy 167.705995 -142.573275)
			(xy 167.713846 -142.51903) (xy 167.729383 -142.466469) (xy 167.752287 -142.416674) (xy 167.782085 -142.370671)
			(xy 167.799766 -142.349728) (xy 167.80002 -142.349474) (xy 167.805584 -142.342372) (xy 167.811844 -142.325467)
			(xy 167.812212 -142.316454) (xy 167.812212 -142.249144) (xy 167.811831 -142.24013) (xy 167.8056 -142.223213)
			(xy 167.80002 -142.216124) (xy 167.799512 -142.215616) (xy 167.781869 -142.194687) (xy 167.752157 -142.148714)
			(xy 167.729322 -142.098965) (xy 167.713832 -142.046464) (xy 167.706005 -141.992287) (xy 167.705532 -141.964918)
			(xy 167.706018 -141.937667) (xy 167.713774 -141.883719) (xy 167.729129 -141.831424) (xy 167.751771 -141.781847)
			(xy 167.781237 -141.735997) (xy 167.816928 -141.694806) (xy 167.858119 -141.659115) (xy 167.903969 -141.629649)
			(xy 167.953546 -141.607007) (xy 168.005841 -141.591652) (xy 168.059789 -141.583896) (xy 168.114291 -141.583896)
			(xy 168.168239 -141.591652) (xy 168.220534 -141.607007) (xy 168.270111 -141.629649) (xy 168.315961 -141.659115)
			(xy 168.357152 -141.694806) (xy 168.392843 -141.735997) (xy 168.422309 -141.781847) (xy 168.444951 -141.831424)
			(xy 168.460306 -141.883719) (xy 168.468062 -141.937667) (xy 168.468548 -141.964918) (xy 168.468089 -141.992323)
			(xy 168.460238 -142.046568) (xy 168.4447 -142.09913) (xy 168.421795 -142.148925) (xy 168.391996 -142.194927)
			(xy 168.374314 -142.21587) (xy 168.37406 -142.216124) (xy 168.368452 -142.223196) (xy 168.362219 -142.240124)
			(xy 168.361868 -142.249144) (xy 168.361868 -142.316454) (xy 168.362254 -142.325468) (xy 168.368482 -142.342385)
			(xy 168.37406 -142.349474) (xy 168.374568 -142.349982) (xy 168.392207 -142.370914) (xy 168.42192 -142.416886)
			(xy 168.444757 -142.466634) (xy 168.460247 -142.519135) (xy 168.468075 -142.573311) (xy 168.468548 -142.60068)
			(xy 168.468062 -142.627931) (xy 168.460306 -142.681879) (xy 168.444951 -142.734174) (xy 168.422309 -142.783751)
			(xy 168.392843 -142.829601) (xy 168.357152 -142.870792) (xy 168.315961 -142.906483) (xy 168.270111 -142.935949)
			(xy 168.220534 -142.958591) (xy 168.168239 -142.973946) (xy 168.114291 -142.981702) (xy 168.059789 -142.981702)
			(xy 168.005841 -142.973946) (xy 167.953546 -142.958591) (xy 167.903969 -142.935949) (xy 167.858119 -142.906483)
			(xy 167.816928 -142.870792) (xy 167.781237 -142.829601) (xy 167.751771 -142.783751) (xy 167.729129 -142.734174)
			(xy 167.713774 -142.681879) (xy 167.706018 -142.627931) (xy 167.705532 -142.60068) (xy 163.433996 -142.60068)
			(xy 163.431474 -142.637764) (xy 163.435538 -142.653258) (xy 163.439602 -142.659862) (xy 163.45307 -142.682521)
			(xy 163.474328 -142.730756) (xy 163.488746 -142.781456) (xy 163.496052 -142.833659) (xy 163.496498 -142.860014)
			(xy 163.496498 -142.860522) (xy 163.496043 -142.887315) (xy 163.488543 -142.940375) (xy 163.473694 -142.991863)
			(xy 163.451787 -143.040767) (xy 163.423254 -143.086126) (xy 163.406328 -143.106902) (xy 163.40582 -143.10741)
			(xy 163.404042 -143.109442) (xy 163.398454 -143.12392) (xy 163.153274 -146.739864) (xy 165.009828 -146.739864)
			(xy 165.013899 -146.684242) (xy 165.026025 -146.629805) (xy 165.045948 -146.577714) (xy 165.073244 -146.529079)
			(xy 165.10733 -146.484936) (xy 165.147479 -146.446227) (xy 165.192837 -146.413776) (xy 165.242437 -146.388275)
			(xy 165.295221 -146.370268) (xy 165.350064 -146.360138) (xy 165.405798 -146.358101) (xy 165.461235 -146.364201)
			(xy 165.515192 -146.378307) (xy 165.566521 -146.400119) (xy 165.614127 -146.429173) (xy 165.656995 -146.464848)
			(xy 165.694212 -146.506385) (xy 165.724985 -146.552898) (xy 165.748657 -146.603395) (xy 165.764725 -146.656802)
			(xy 165.772845 -146.711978) (xy 165.773354 -146.739864) (xy 165.772845 -146.76775) (xy 165.768688 -146.795998)
			(xy 166.643556 -146.795998) (xy 166.647627 -146.740376) (xy 166.659753 -146.685939) (xy 166.679676 -146.633848)
			(xy 166.706972 -146.585213) (xy 166.741058 -146.54107) (xy 166.781207 -146.502361) (xy 166.826565 -146.46991)
			(xy 166.876165 -146.444409) (xy 166.928949 -146.426402) (xy 166.983792 -146.416272) (xy 167.039526 -146.414235)
			(xy 167.094963 -146.420335) (xy 167.14892 -146.434441) (xy 167.200249 -146.456253) (xy 167.247855 -146.485307)
			(xy 167.290723 -146.520982) (xy 167.32794 -146.562519) (xy 167.358713 -146.609032) (xy 167.382385 -146.659529)
			(xy 167.398453 -146.712936) (xy 167.406573 -146.768112) (xy 167.407082 -146.795998) (xy 167.406573 -146.823884)
			(xy 167.398453 -146.87906) (xy 167.382385 -146.932467) (xy 167.358713 -146.982964) (xy 167.32794 -147.029477)
			(xy 167.290723 -147.071014) (xy 167.247855 -147.106689) (xy 167.200249 -147.135743) (xy 167.14892 -147.157555)
			(xy 167.094963 -147.171661) (xy 167.039526 -147.177761) (xy 166.983792 -147.175724) (xy 166.928949 -147.165594)
			(xy 166.876165 -147.147587) (xy 166.826565 -147.122086) (xy 166.781207 -147.089635) (xy 166.741058 -147.050926)
			(xy 166.706972 -147.006783) (xy 166.679676 -146.958148) (xy 166.659753 -146.906057) (xy 166.647627 -146.85162)
			(xy 166.643556 -146.795998) (xy 165.768688 -146.795998) (xy 165.764725 -146.822926) (xy 165.748657 -146.876333)
			(xy 165.724985 -146.92683) (xy 165.694212 -146.973343) (xy 165.656995 -147.01488) (xy 165.614127 -147.050555)
			(xy 165.566521 -147.079609) (xy 165.515192 -147.101421) (xy 165.461235 -147.115527) (xy 165.405798 -147.121627)
			(xy 165.350064 -147.11959) (xy 165.295221 -147.10946) (xy 165.242437 -147.091453) (xy 165.192837 -147.065952)
			(xy 165.147479 -147.033501) (xy 165.10733 -146.994792) (xy 165.073244 -146.950649) (xy 165.045948 -146.902014)
			(xy 165.026025 -146.849923) (xy 165.013899 -146.795486) (xy 165.009828 -146.739864) (xy 163.153274 -146.739864)
			(xy 162.650152 -154.159966) (xy 167.406826 -154.159966) (xy 167.410897 -154.104344) (xy 167.423023 -154.049907)
			(xy 167.442946 -153.997816) (xy 167.470242 -153.949181) (xy 167.504328 -153.905038) (xy 167.544477 -153.866329)
			(xy 167.589835 -153.833878) (xy 167.639435 -153.808377) (xy 167.692219 -153.79037) (xy 167.747062 -153.78024)
			(xy 167.802796 -153.778203) (xy 167.858233 -153.784303) (xy 167.91219 -153.798409) (xy 167.963519 -153.820221)
			(xy 168.011125 -153.849275) (xy 168.053993 -153.88495) (xy 168.09121 -153.926487) (xy 168.121983 -153.973)
			(xy 168.145655 -154.023497) (xy 168.161723 -154.076904) (xy 168.169843 -154.13208) (xy 168.170352 -154.159966)
			(xy 168.169843 -154.187852) (xy 168.161723 -154.243028) (xy 168.145655 -154.296435) (xy 168.121983 -154.346932)
			(xy 168.09121 -154.393445) (xy 168.053993 -154.434982) (xy 168.011125 -154.470657) (xy 167.963519 -154.499711)
			(xy 167.91219 -154.521523) (xy 167.858233 -154.535629) (xy 167.802796 -154.541729) (xy 167.747062 -154.539692)
			(xy 167.692219 -154.529562) (xy 167.639435 -154.511555) (xy 167.589835 -154.486054) (xy 167.544477 -154.453603)
			(xy 167.504328 -154.414894) (xy 167.470242 -154.370751) (xy 167.442946 -154.322116) (xy 167.423023 -154.270025)
			(xy 167.410897 -154.215588) (xy 167.406826 -154.159966) (xy 162.650152 -154.159966) (xy 162.590373 -155.0416)
			(xy 164.263576 -155.0416) (xy 164.267647 -154.985978) (xy 164.279773 -154.931541) (xy 164.299696 -154.87945)
			(xy 164.326992 -154.830815) (xy 164.361078 -154.786672) (xy 164.401227 -154.747963) (xy 164.446585 -154.715512)
			(xy 164.496185 -154.690011) (xy 164.548969 -154.672004) (xy 164.603812 -154.661874) (xy 164.659546 -154.659837)
			(xy 164.714983 -154.665937) (xy 164.76894 -154.680043) (xy 164.820269 -154.701855) (xy 164.867875 -154.730909)
			(xy 164.910743 -154.766584) (xy 164.94796 -154.808121) (xy 164.978733 -154.854634) (xy 165.002405 -154.905131)
			(xy 165.018473 -154.958538) (xy 165.026593 -155.013714) (xy 165.027102 -155.0416) (xy 165.026593 -155.069486)
			(xy 165.018473 -155.124662) (xy 165.002405 -155.178069) (xy 164.978733 -155.228566) (xy 164.94796 -155.275079)
			(xy 164.910743 -155.316616) (xy 164.867875 -155.352291) (xy 164.820269 -155.381345) (xy 164.76894 -155.403157)
			(xy 164.714983 -155.417263) (xy 164.659546 -155.423363) (xy 164.603812 -155.421326) (xy 164.548969 -155.411196)
			(xy 164.496185 -155.393189) (xy 164.446585 -155.367688) (xy 164.401227 -155.335237) (xy 164.361078 -155.296528)
			(xy 164.326992 -155.252385) (xy 164.299696 -155.20375) (xy 164.279773 -155.151659) (xy 164.267647 -155.097222)
			(xy 164.263576 -155.0416) (xy 162.590373 -155.0416) (xy 162.552621 -155.598368) (xy 167.46804 -155.598368)
			(xy 167.472111 -155.542746) (xy 167.484237 -155.488309) (xy 167.50416 -155.436218) (xy 167.531456 -155.387583)
			(xy 167.565542 -155.34344) (xy 167.605691 -155.304731) (xy 167.651049 -155.27228) (xy 167.700649 -155.246779)
			(xy 167.753433 -155.228772) (xy 167.808276 -155.218642) (xy 167.86401 -155.216605) (xy 167.919447 -155.222705)
			(xy 167.973404 -155.236811) (xy 168.024733 -155.258623) (xy 168.072339 -155.287677) (xy 168.115207 -155.323352)
			(xy 168.152424 -155.364889) (xy 168.183197 -155.411402) (xy 168.206869 -155.461899) (xy 168.222937 -155.515306)
			(xy 168.231057 -155.570482) (xy 168.231566 -155.598368) (xy 168.231057 -155.626254) (xy 168.222937 -155.68143)
			(xy 168.206869 -155.734837) (xy 168.183197 -155.785334) (xy 168.152424 -155.831847) (xy 168.115207 -155.873384)
			(xy 168.072339 -155.909059) (xy 168.024733 -155.938113) (xy 167.973404 -155.959925) (xy 167.919447 -155.974031)
			(xy 167.86401 -155.980131) (xy 167.808276 -155.978094) (xy 167.753433 -155.967964) (xy 167.700649 -155.949957)
			(xy 167.651049 -155.924456) (xy 167.605691 -155.892005) (xy 167.565542 -155.853296) (xy 167.531456 -155.809153)
			(xy 167.50416 -155.760518) (xy 167.484237 -155.708427) (xy 167.472111 -155.65399) (xy 167.46804 -155.598368)
			(xy 162.552621 -155.598368) (xy 162.452593 -157.0736) (xy 167.396666 -157.0736) (xy 167.400737 -157.017978)
			(xy 167.412863 -156.963541) (xy 167.432786 -156.91145) (xy 167.460082 -156.862815) (xy 167.494168 -156.818672)
			(xy 167.534317 -156.779963) (xy 167.579675 -156.747512) (xy 167.629275 -156.722011) (xy 167.682059 -156.704004)
			(xy 167.736902 -156.693874) (xy 167.792636 -156.691837) (xy 167.848073 -156.697937) (xy 167.90203 -156.712043)
			(xy 167.953359 -156.733855) (xy 168.000965 -156.762909) (xy 168.043833 -156.798584) (xy 168.08105 -156.840121)
			(xy 168.111823 -156.886634) (xy 168.135495 -156.937131) (xy 168.151563 -156.990538) (xy 168.159683 -157.045714)
			(xy 168.160192 -157.0736) (xy 168.159683 -157.101486) (xy 168.151563 -157.156662) (xy 168.135495 -157.210069)
			(xy 168.111823 -157.260566) (xy 168.08105 -157.307079) (xy 168.043833 -157.348616) (xy 168.000965 -157.384291)
			(xy 167.953359 -157.413345) (xy 167.90203 -157.435157) (xy 167.848073 -157.449263) (xy 167.792636 -157.455363)
			(xy 167.736902 -157.453326) (xy 167.682059 -157.443196) (xy 167.629275 -157.425189) (xy 167.579675 -157.399688)
			(xy 167.534317 -157.367237) (xy 167.494168 -157.328528) (xy 167.460082 -157.284385) (xy 167.432786 -157.23575)
			(xy 167.412863 -157.183659) (xy 167.400737 -157.129222) (xy 167.396666 -157.0736) (xy 162.452593 -157.0736)
			(xy 162.318446 -159.052006) (xy 162.320102 -159.060977) (xy 162.328833 -159.07698) (xy 162.335464 -159.083248)
			(xy 162.335972 -159.083756) (xy 162.398456 -159.136588) (xy 162.403176 -159.140339) (xy 162.41396 -159.145723)
			(xy 162.419792 -159.147256) (xy 162.431222 -159.149796) (xy 162.44316 -159.147002) (xy 162.488623 -159.136584)
			(xy 162.580873 -159.122781) (xy 162.673976 -159.117082) (xy 162.767221 -159.119531) (xy 162.859896 -159.130107)
			(xy 162.951295 -159.148731) (xy 163.04072 -159.175261) (xy 163.127488 -159.209494) (xy 163.210938 -159.251169)
			(xy 163.290432 -159.299968) (xy 163.365364 -159.355518) (xy 163.435162 -159.417395) (xy 163.499293 -159.485129)
			(xy 163.557269 -159.5582) (xy 163.608646 -159.636052) (xy 163.653033 -159.718092) (xy 163.69009 -159.803692)
			(xy 163.705286 -159.847788) (xy 163.719468 -159.891944) (xy 163.741032 -159.982151) (xy 163.754688 -160.07389)
			(xy 163.760332 -160.166467) (xy 163.757921 -160.259186) (xy 163.747475 -160.351345) (xy 163.729071 -160.44225)
			(xy 163.702849 -160.531215) (xy 163.669006 -160.61757) (xy 163.627797 -160.700662) (xy 163.579534 -160.779865)
			(xy 163.524581 -160.854582) (xy 163.463352 -160.924248) (xy 163.396308 -160.988339) (xy 163.323957 -161.04637)
			(xy 163.246843 -161.097905) (xy 163.165547 -161.142554) (xy 163.080685 -161.179981) (xy 162.992895 -161.209903)
			(xy 162.902839 -161.232095) (xy 162.811198 -161.246388) (xy 162.718662 -161.252676) (xy 162.625929 -161.250911)
			(xy 162.5337 -161.241106) (xy 162.442669 -161.223335) (xy 162.353523 -161.197733) (xy 162.310064 -161.181542)
			(xy 162.304222 -161.179256) (xy 162.292538 -161.177986) (xy 162.286696 -161.178494) (xy 162.28084 -161.179255)
			(xy 162.26968 -161.183107) (xy 162.264598 -161.186114) (xy 162.19551 -161.23031) (xy 162.194494 -161.231072)
			(xy 162.185137 -161.23808) (xy 162.173488 -161.258322) (xy 162.172142 -161.269934) (xy 162.136328 -161.81832)
			(xy 162.134296 -161.844736) (xy 162.121088 -161.987738) (xy 162.120834 -161.994088) (xy 162.194516 -164.198046)
			(xy 166.809164 -164.198046) (xy 166.813235 -164.142424) (xy 166.825361 -164.087987) (xy 166.845284 -164.035896)
			(xy 166.87258 -163.987261) (xy 166.906666 -163.943118) (xy 166.946815 -163.904409) (xy 166.992173 -163.871958)
			(xy 167.041773 -163.846457) (xy 167.094557 -163.82845) (xy 167.1494 -163.81832) (xy 167.205134 -163.816283)
			(xy 167.260571 -163.822383) (xy 167.314528 -163.836489) (xy 167.365857 -163.858301) (xy 167.413463 -163.887355)
			(xy 167.456331 -163.92303) (xy 167.493548 -163.964567) (xy 167.524321 -164.01108) (xy 167.547993 -164.061577)
			(xy 167.564061 -164.114984) (xy 167.572181 -164.17016) (xy 167.57269 -164.198046) (xy 167.572181 -164.225932)
			(xy 167.564061 -164.281108) (xy 167.547993 -164.334515) (xy 167.524321 -164.385012) (xy 167.493548 -164.431525)
			(xy 167.456331 -164.473062) (xy 167.413463 -164.508737) (xy 167.365857 -164.537791) (xy 167.314528 -164.559603)
			(xy 167.260571 -164.573709) (xy 167.205134 -164.579809) (xy 167.1494 -164.577772) (xy 167.094557 -164.567642)
			(xy 167.041773 -164.549635) (xy 166.992173 -164.524134) (xy 166.946815 -164.491683) (xy 166.906666 -164.452974)
			(xy 166.87258 -164.408831) (xy 166.845284 -164.360196) (xy 166.825361 -164.308105) (xy 166.813235 -164.253668)
			(xy 166.809164 -164.198046) (xy 162.194516 -164.198046) (xy 162.22568 -165.130226) (xy 166.766238 -165.130226)
			(xy 166.770309 -165.074604) (xy 166.782435 -165.020167) (xy 166.802358 -164.968076) (xy 166.829654 -164.919441)
			(xy 166.86374 -164.875298) (xy 166.903889 -164.836589) (xy 166.949247 -164.804138) (xy 166.998847 -164.778637)
			(xy 167.051631 -164.76063) (xy 167.106474 -164.7505) (xy 167.162208 -164.748463) (xy 167.217645 -164.754563)
			(xy 167.271602 -164.768669) (xy 167.322931 -164.790481) (xy 167.370537 -164.819535) (xy 167.413405 -164.85521)
			(xy 167.450622 -164.896747) (xy 167.481395 -164.94326) (xy 167.505067 -164.993757) (xy 167.521135 -165.047164)
			(xy 167.529255 -165.10234) (xy 167.529764 -165.130226) (xy 167.529255 -165.158112) (xy 167.521135 -165.213288)
			(xy 167.505067 -165.266695) (xy 167.481395 -165.317192) (xy 167.450622 -165.363705) (xy 167.413405 -165.405242)
			(xy 167.370537 -165.440917) (xy 167.322931 -165.469971) (xy 167.271602 -165.491783) (xy 167.217645 -165.505889)
			(xy 167.162208 -165.511989) (xy 167.106474 -165.509952) (xy 167.051631 -165.499822) (xy 166.998847 -165.481815)
			(xy 166.949247 -165.456314) (xy 166.903889 -165.423863) (xy 166.86374 -165.385154) (xy 166.829654 -165.341011)
			(xy 166.802358 -165.292376) (xy 166.782435 -165.240285) (xy 166.770309 -165.185848) (xy 166.766238 -165.130226)
			(xy 162.22568 -165.130226) (xy 162.3349 -168.397174) (xy 166.7416 -168.397174) (xy 166.745671 -168.341552)
			(xy 166.757797 -168.287115) (xy 166.77772 -168.235024) (xy 166.805016 -168.186389) (xy 166.839102 -168.142246)
			(xy 166.879251 -168.103537) (xy 166.924609 -168.071086) (xy 166.974209 -168.045585) (xy 167.026993 -168.027578)
			(xy 167.081836 -168.017448) (xy 167.13757 -168.015411) (xy 167.193007 -168.021511) (xy 167.246964 -168.035617)
			(xy 167.298293 -168.057429) (xy 167.345899 -168.086483) (xy 167.388767 -168.122158) (xy 167.425984 -168.163695)
			(xy 167.456757 -168.210208) (xy 167.480429 -168.260705) (xy 167.496497 -168.314112) (xy 167.504617 -168.369288)
			(xy 167.505126 -168.397174) (xy 167.504617 -168.42506) (xy 167.496497 -168.480236) (xy 167.480429 -168.533643)
			(xy 167.456757 -168.58414) (xy 167.425984 -168.630653) (xy 167.388767 -168.67219) (xy 167.345899 -168.707865)
			(xy 167.298293 -168.736919) (xy 167.246964 -168.758731) (xy 167.193007 -168.772837) (xy 167.13757 -168.778937)
			(xy 167.081836 -168.7769) (xy 167.026993 -168.76677) (xy 166.974209 -168.748763) (xy 166.924609 -168.723262)
			(xy 166.879251 -168.690811) (xy 166.839102 -168.652102) (xy 166.805016 -168.607959) (xy 166.77772 -168.559324)
			(xy 166.757797 -168.507233) (xy 166.745671 -168.452796) (xy 166.7416 -168.397174) (xy 162.3349 -168.397174)
			(xy 162.378819 -169.710862) (xy 164.961314 -169.710862) (xy 164.965385 -169.65524) (xy 164.977511 -169.600803)
			(xy 164.997434 -169.548712) (xy 165.02473 -169.500077) (xy 165.058816 -169.455934) (xy 165.098965 -169.417225)
			(xy 165.144323 -169.384774) (xy 165.193923 -169.359273) (xy 165.246707 -169.341266) (xy 165.30155 -169.331136)
			(xy 165.357284 -169.329099) (xy 165.412721 -169.335199) (xy 165.466678 -169.349305) (xy 165.518007 -169.371117)
			(xy 165.565613 -169.400171) (xy 165.608481 -169.435846) (xy 165.645698 -169.477383) (xy 165.676471 -169.523896)
			(xy 165.700143 -169.574393) (xy 165.716211 -169.6278) (xy 165.724331 -169.682976) (xy 165.72484 -169.710862)
			(xy 165.724331 -169.738748) (xy 165.716211 -169.793924) (xy 165.700143 -169.847331) (xy 165.676471 -169.897828)
			(xy 165.645698 -169.944341) (xy 165.608481 -169.985878) (xy 165.565613 -170.021553) (xy 165.518007 -170.050607)
			(xy 165.466678 -170.072419) (xy 165.412721 -170.086525) (xy 165.357284 -170.092625) (xy 165.30155 -170.090588)
			(xy 165.246707 -170.080458) (xy 165.193923 -170.062451) (xy 165.144323 -170.03695) (xy 165.098965 -170.004499)
			(xy 165.058816 -169.96579) (xy 165.02473 -169.921647) (xy 164.997434 -169.873012) (xy 164.977511 -169.820921)
			(xy 164.965385 -169.766484) (xy 164.961314 -169.710862) (xy 162.378819 -169.710862) (xy 162.580054 -175.730154)
			(xy 167.057068 -175.730154) (xy 167.061139 -175.674532) (xy 167.073265 -175.620095) (xy 167.093188 -175.568004)
			(xy 167.120484 -175.519369) (xy 167.15457 -175.475226) (xy 167.194719 -175.436517) (xy 167.240077 -175.404066)
			(xy 167.289677 -175.378565) (xy 167.342461 -175.360558) (xy 167.397304 -175.350428) (xy 167.453038 -175.348391)
			(xy 167.508475 -175.354491) (xy 167.562432 -175.368597) (xy 167.613761 -175.390409) (xy 167.661367 -175.419463)
			(xy 167.704235 -175.455138) (xy 167.741452 -175.496675) (xy 167.772225 -175.543188) (xy 167.795897 -175.593685)
			(xy 167.811965 -175.647092) (xy 167.820085 -175.702268) (xy 167.820594 -175.730154) (xy 167.820085 -175.75804)
			(xy 167.811965 -175.813216) (xy 167.795897 -175.866623) (xy 167.772225 -175.91712) (xy 167.741452 -175.963633)
			(xy 167.704235 -176.00517) (xy 167.661367 -176.040845) (xy 167.613761 -176.069899) (xy 167.562432 -176.091711)
			(xy 167.508475 -176.105817) (xy 167.453038 -176.111917) (xy 167.397304 -176.10988) (xy 167.342461 -176.09975)
			(xy 167.289677 -176.081743) (xy 167.240077 -176.056242) (xy 167.194719 -176.023791) (xy 167.15457 -175.985082)
			(xy 167.120484 -175.940939) (xy 167.093188 -175.892304) (xy 167.073265 -175.840213) (xy 167.061139 -175.785776)
			(xy 167.057068 -175.730154) (xy 162.580054 -175.730154) (xy 163.102036 -191.343534) (xy 163.10281 -191.353278)
			(xy 163.110723 -191.371132) (xy 163.124737 -191.384733) (xy 163.142819 -191.392111) (xy 163.152582 -191.392556)
		)
		(stroke
			(width 0)
			(type solid)
		)
		(fill yes)
		(layer "In11.Cu")
		(net "GND")
	)
	(gr_poly
		(pts
			(xy 281.556968 -223.314514) (xy 281.56729 -223.315017) (xy 281.586954 -223.308723) (xy 281.595068 -223.302322)
			(xy 281.602942 -223.295718) (xy 281.611832 -223.277176) (xy 283.95168 -180.133498) (xy 283.929836 -180.104034)
			(xy 283.917644 -180.10124) (xy 283.889635 -180.09462) (xy 283.835867 -180.074094) (xy 283.785793 -180.045723)
			(xy 283.740549 -180.010151) (xy 283.701164 -179.968185) (xy 283.66853 -179.920779) (xy 283.643389 -179.869008)
			(xy 283.626311 -179.814047) (xy 283.617684 -179.757145) (xy 283.617162 -179.728368) (xy 283.617672 -179.700167)
			(xy 283.625982 -179.644379) (xy 283.642417 -179.590424) (xy 283.666619 -179.539477) (xy 283.698059 -179.49265)
			(xy 283.736051 -179.450962) (xy 283.779769 -179.415324) (xy 283.828258 -179.386513) (xy 283.854144 -179.375308)
			(xy 283.863978 -179.37072) (xy 283.878853 -179.354949) (xy 283.885917 -179.334453) (xy 283.883918 -179.312865)
			(xy 283.879036 -179.303172) (xy 283.87802 -179.301648) (xy 283.876496 -179.299362) (xy 283.860263 -179.275211)
			(xy 283.834533 -179.223022) (xy 283.817039 -179.167526) (xy 283.808187 -179.110016) (xy 283.807662 -179.080922)
			(xy 283.808197 -179.051968) (xy 283.816943 -178.994723) (xy 283.834236 -178.939457) (xy 283.859681 -178.887437)
			(xy 283.892693 -178.839859) (xy 283.932513 -178.797815) (xy 283.978229 -178.762269) (xy 284.003242 -178.747674)
			(xy 284.010515 -178.743175) (xy 284.021805 -178.730343) (xy 284.02829 -178.714529) (xy 284.02915 -178.706018)
			(xy 284.367224 -172.47362) (xy 284.360112 -172.454316) (xy 284.353 -172.446696) (xy 284.328616 -172.41774)
			(xy 284.31987 -172.406967) (xy 284.297789 -172.390184) (xy 284.272002 -172.379972) (xy 284.244417 -172.377086)
			(xy 284.217075 -172.381741) (xy 284.191999 -172.393592) (xy 284.171043 -172.411762) (xy 284.163008 -172.423074)
			(xy 284.147784 -172.445216) (xy 284.112108 -172.485397) (xy 284.071145 -172.520173) (xy 284.025706 -172.548855)
			(xy 283.976691 -172.570875) (xy 283.925071 -172.585797) (xy 283.871867 -172.593326) (xy 283.845 -172.593762)
			(xy 283.817731 -172.593276) (xy 283.763747 -172.585514) (xy 283.711417 -172.570149) (xy 283.661807 -172.547492)
			(xy 283.615926 -172.518006) (xy 283.574709 -172.482291) (xy 283.538994 -172.441074) (xy 283.509508 -172.395193)
			(xy 283.486851 -172.345583) (xy 283.471486 -172.293253) (xy 283.463724 -172.239269) (xy 283.463724 -172.184731)
			(xy 283.471486 -172.130747) (xy 283.486851 -172.078417) (xy 283.509508 -172.028807) (xy 283.538994 -171.982926)
			(xy 283.574709 -171.941709) (xy 283.615926 -171.905994) (xy 283.661807 -171.876508) (xy 283.711417 -171.853851)
			(xy 283.763747 -171.838486) (xy 283.817731 -171.830724) (xy 283.845 -171.830238) (xy 283.874295 -171.830772)
			(xy 283.932196 -171.839729) (xy 283.988047 -171.857431) (xy 284.040536 -171.883462) (xy 284.088429 -171.917211)
			(xy 284.1306 -171.957885) (xy 284.148784 -171.98086) (xy 284.15753 -171.991633) (xy 284.179611 -172.008416)
			(xy 284.205398 -172.018628) (xy 284.232983 -172.021514) (xy 284.260325 -172.016859) (xy 284.285401 -172.005008)
			(xy 284.306357 -171.986838) (xy 284.314392 -171.975526) (xy 284.329095 -171.954125) (xy 284.363382 -171.915132)
			(xy 284.382718 -171.897802) (xy 284.390592 -171.890944) (xy 284.399736 -171.872656) (xy 285.209742 -156.935424)
			(xy 285.191454 -156.907738) (xy 285.17596 -156.901896) (xy 285.149069 -156.891229) (xy 285.0986 -156.862957)
			(xy 285.052972 -156.827397) (xy 285.01323 -156.785361) (xy 284.980283 -156.737812) (xy 284.954885 -156.685837)
			(xy 284.937617 -156.630626) (xy 284.928874 -156.573442) (xy 284.92831 -156.544518) (xy 284.928801 -156.516506)
			(xy 284.936985 -156.461085) (xy 284.953181 -156.407454) (xy 284.977041 -156.356765) (xy 285.008052 -156.310108)
			(xy 285.045548 -156.268484) (xy 285.088725 -156.232786) (xy 285.136655 -156.203781) (xy 285.188309 -156.182092)
			(xy 285.21533 -156.174694) (xy 285.231332 -156.17063) (xy 285.252414 -156.144976) (xy 285.296102 -155.342336)
			(xy 285.293308 -155.340812) (xy 285.261812 -155.334462) (xy 285.260796 -155.334462) (xy 285.234557 -155.329445)
			(xy 285.183716 -155.313042) (xy 285.135659 -155.289711) (xy 285.091324 -155.259906) (xy 285.051579 -155.224212)
			(xy 285.017198 -155.183324) (xy 284.988855 -155.138041) (xy 284.967102 -155.089249) (xy 284.952365 -155.037901)
			(xy 284.944932 -154.984999) (xy 284.944566 -154.958288) (xy 284.945093 -154.929925) (xy 284.953504 -154.873826)
			(xy 284.970124 -154.819589) (xy 284.994588 -154.768408) (xy 285.026356 -154.721412) (xy 285.064729 -154.679634)
			(xy 285.108863 -154.643995) (xy 285.157784 -154.615279) (xy 285.210416 -154.594119) (xy 285.2656 -154.580981)
			(xy 285.293816 -154.57805) (xy 285.319724 -154.575764) (xy 285.323368 -154.57538) (xy 285.330505 -154.573717)
			(xy 285.333948 -154.572462) (xy 285.338012 -154.570938) (xy 285.37408 -153.907998) (xy 285.374187 -153.898176)
			(xy 285.367839 -153.879607) (xy 285.354956 -153.864804) (xy 285.346394 -153.859992) (xy 285.327344 -153.85034)
			(xy 285.320676 -153.847253) (xy 285.306219 -153.844666) (xy 285.298896 -153.84526) (xy 285.29153 -153.846022)
			(xy 285.278322 -153.851356) (xy 285.27248 -153.856182) (xy 285.251986 -153.872245) (xy 285.207473 -153.899258)
			(xy 285.159702 -153.919974) (xy 285.10956 -153.934009) (xy 285.057976 -153.941102) (xy 285.031942 -153.941526)
			(xy 285.004686 -153.941066) (xy 284.950728 -153.933313) (xy 284.898422 -153.91796) (xy 284.848835 -153.895319)
			(xy 284.802974 -153.865851) (xy 284.761774 -153.830155) (xy 284.726074 -153.78896) (xy 284.696601 -153.743102)
			(xy 284.673954 -153.693517) (xy 284.658595 -153.641213) (xy 284.650837 -153.587256) (xy 284.650837 -153.532744)
			(xy 284.658595 -153.478787) (xy 284.673954 -153.426483) (xy 284.696601 -153.376898) (xy 284.726074 -153.33104)
			(xy 284.761774 -153.289845) (xy 284.802974 -153.254149) (xy 284.848835 -153.224681) (xy 284.898422 -153.20204)
			(xy 284.950728 -153.186687) (xy 285.004686 -153.178934) (xy 285.031942 -153.17851) (xy 285.061528 -153.179063)
			(xy 285.119992 -153.18819) (xy 285.176345 -153.206235) (xy 285.229237 -153.232765) (xy 285.277398 -153.267143)
			(xy 285.298896 -153.287476) (xy 285.306104 -153.294035) (xy 285.324033 -153.301631) (xy 285.343501 -153.301992)
			(xy 285.352744 -153.298906) (xy 285.353252 -153.298652) (xy 285.377636 -153.289) (xy 285.386501 -153.285044)
			(xy 285.400637 -153.271762) (xy 285.408882 -153.254205) (xy 285.409894 -153.24455) (xy 285.497524 -151.627332)
			(xy 285.497651 -151.617765) (xy 285.491619 -151.599624) (xy 285.479331 -151.584978) (xy 285.471108 -151.580088)
			(xy 285.441136 -151.563578) (xy 285.43758 -151.5618) (xy 285.428961 -151.557595) (xy 285.409935 -151.55532)
			(xy 285.391413 -151.560226) (xy 285.383478 -151.56561) (xy 285.362662 -151.580227) (xy 285.317911 -151.604404)
			(xy 285.270341 -151.622411) (xy 285.220798 -151.633928) (xy 285.195518 -151.63673) (xy 285.16072 -151.638508)
			(xy 285.153354 -151.638508) (xy 285.126364 -151.637647) (xy 285.073021 -151.629255) (xy 285.021394 -151.613424)
			(xy 284.972516 -151.59047) (xy 284.927364 -151.560852) (xy 284.88684 -151.525163) (xy 284.851754 -151.484115)
			(xy 284.822808 -151.438529) (xy 284.80058 -151.389317) (xy 284.785515 -151.337462) (xy 284.777913 -151.284)
			(xy 284.777434 -151.257) (xy 284.777897 -151.229748) (xy 284.785655 -151.1758) (xy 284.801011 -151.123504)
			(xy 284.823654 -151.073927) (xy 284.853123 -151.028077) (xy 284.888817 -150.986887) (xy 284.93001 -150.951198)
			(xy 284.975864 -150.921734) (xy 285.025444 -150.899096) (xy 285.077741 -150.883746) (xy 285.13169 -150.875994)
			(xy 285.158942 -150.875492) (xy 285.18651 -150.87598) (xy 285.241071 -150.883921) (xy 285.293921 -150.899631)
			(xy 285.34396 -150.922784) (xy 285.390146 -150.952896) (xy 285.411164 -150.970742) (xy 285.412942 -150.972266)
			(xy 285.420311 -150.977689) (xy 285.437683 -150.983391) (xy 285.45595 -150.982623) (xy 285.464504 -150.979378)
			(xy 285.47314 -150.975568) (xy 285.486701 -150.969312) (xy 285.50971 -150.950295) (xy 285.526231 -150.925432)
			(xy 285.534849 -150.896853) (xy 285.534828 -150.867002) (xy 285.526168 -150.838435) (xy 285.518352 -150.825708)
			(xy 285.516828 -150.823676) (xy 285.499073 -150.798825) (xy 285.470874 -150.744651) (xy 285.451678 -150.686673)
			(xy 285.441977 -150.626375) (xy 285.44139 -150.595838) (xy 285.441898 -150.574756) (xy 285.441898 -150.574502)
			(xy 285.442214 -150.559993) (xy 285.435659 -150.531736) (xy 285.421421 -150.506464) (xy 285.400649 -150.486216)
			(xy 285.375021 -150.472628) (xy 285.346606 -150.466797) (xy 285.317698 -150.469193) (xy 285.303976 -150.473918)
			(xy 285.282058 -150.481964) (xy 285.236757 -150.493271) (xy 285.190415 -150.498971) (xy 285.16707 -150.499318)
			(xy 285.13982 -150.49883) (xy 285.085875 -150.49107) (xy 285.033583 -150.475713) (xy 284.984009 -150.45307)
			(xy 284.938162 -150.423603) (xy 284.896974 -150.387912) (xy 284.861285 -150.346722) (xy 284.83182 -150.300873)
			(xy 284.80918 -150.251298) (xy 284.793825 -150.199006) (xy 284.786068 -150.14506) (xy 284.785562 -150.11781)
			(xy 284.785979 -150.092158) (xy 284.79286 -150.041318) (xy 284.806498 -149.991861) (xy 284.826648 -149.94468)
			(xy 284.852944 -149.900629) (xy 284.86862 -149.88032) (xy 284.873954 -149.873462) (xy 284.876494 -149.865842)
			(xy 284.877863 -149.861784) (xy 284.87939 -149.853358) (xy 284.879542 -149.849078) (xy 284.879542 -149.816058)
			(xy 284.890718 -149.816058) (xy 284.890718 -149.763226) (xy 284.890593 -149.758679) (xy 284.88893 -149.749736)
			(xy 284.887416 -149.745446) (xy 284.885638 -149.74062) (xy 284.879542 -149.733508) (xy 284.861898 -149.712578)
			(xy 284.832168 -149.666612) (xy 284.809321 -149.616866) (xy 284.793828 -149.564362) (xy 284.786007 -149.510181)
			(xy 284.785562 -149.48281) (xy 284.786047 -149.455558) (xy 284.793802 -149.401607) (xy 284.809156 -149.349309)
			(xy 284.831796 -149.299729) (xy 284.861262 -149.253875) (xy 284.896953 -149.212681) (xy 284.938143 -149.176986)
			(xy 284.983994 -149.147516) (xy 285.033572 -149.12487) (xy 285.085868 -149.109511) (xy 285.139818 -149.10175)
			(xy 285.16707 -149.101302) (xy 285.16707 -149.101048) (xy 285.197011 -149.101652) (xy 285.256152 -149.111039)
			(xy 285.313104 -149.12954) (xy 285.366472 -149.156702) (xy 285.414946 -149.19186) (xy 285.45734 -149.234152)
			(xy 285.475426 -149.25802) (xy 285.475426 -149.258274) (xy 285.480304 -149.2644) (xy 285.492974 -149.27359)
			(xy 285.500318 -149.276308) (xy 285.507684 -149.278848) (xy 285.523178 -149.279102) (xy 285.538926 -149.274276)
			(xy 285.626302 -149.248114) (xy 285.626556 -149.248114) (xy 285.842456 -145.267172) (xy 285.842456 -145.266664)
			(xy 285.961328 -142.718028) (xy 285.961343 -142.712344) (xy 285.959165 -142.70119) (xy 285.95701 -142.69593)
			(xy 285.953962 -142.68958) (xy 285.946088 -142.679674) (xy 285.9405 -142.67561) (xy 285.919966 -142.660167)
			(xy 285.882836 -142.624656) (xy 285.850807 -142.584483) (xy 285.824459 -142.540375) (xy 285.80427 -142.49313)
			(xy 285.790604 -142.443603) (xy 285.783708 -142.392689) (xy 285.783274 -142.367) (xy 285.783748 -142.339597)
			(xy 285.791592 -142.285356) (xy 285.807119 -142.232796) (xy 285.830008 -142.182999) (xy 285.859789 -142.136991)
			(xy 285.895848 -142.095719) (xy 285.937442 -142.060032) (xy 285.960312 -142.044928) (xy 285.963868 -142.042642)
			(xy 285.965138 -142.04188) (xy 285.968694 -142.038324) (xy 285.976568 -142.028418) (xy 285.988252 -142.008606)
			(xy 285.991258 -142.003141) (xy 285.994848 -141.9912) (xy 285.995364 -141.984984) (xy 286.155638 -138.553698)
			(xy 286.15767 -138.520678) (xy 286.314642 -136.561322) (xy 286.314642 -136.559798) (xy 286.375602 -135.43407)
			(xy 286.375701 -135.423821) (xy 286.368764 -135.404553) (xy 286.36214 -135.396732) (xy 286.33547 -135.36803)
			(xy 286.328256 -135.36172) (xy 286.310499 -135.354544) (xy 286.300926 -135.35406) (xy 286.29864 -135.35406)
			(xy 286.296862 -135.354314) (xy 286.266891 -135.353822) (xy 286.207462 -135.345996) (xy 286.149563 -135.330482)
			(xy 286.094182 -135.307546) (xy 286.042268 -135.27758) (xy 285.994708 -135.241096) (xy 285.952315 -135.198719)
			(xy 285.915813 -135.151172) (xy 285.885828 -135.099269) (xy 285.862872 -135.043897) (xy 285.847337 -134.986003)
			(xy 285.839489 -134.926577) (xy 285.8389 -134.896606) (xy 285.8389 -134.032752) (xy 285.839387 -134.002778)
			(xy 285.847205 -133.943343) (xy 285.862714 -133.885436) (xy 285.885648 -133.83005) (xy 285.915616 -133.77813)
			(xy 285.952104 -133.730567) (xy 285.994489 -133.688173) (xy 286.042044 -133.651674) (xy 286.067754 -133.636258)
			(xy 286.089945 -133.623845) (xy 286.136535 -133.603473) (xy 286.160718 -133.595618) (xy 286.193924 -133.585978)
			(xy 286.26229 -133.575646) (xy 286.296862 -133.575044) (xy 286.330304 -133.575634) (xy 286.396482 -133.58532)
			(xy 286.428688 -133.594348) (xy 286.429196 -133.594348) (xy 286.44342 -133.596634) (xy 286.445198 -133.596634)
			(xy 286.452052 -133.596231) (xy 286.465178 -133.592226) (xy 286.471106 -133.58876) (xy 286.472376 -133.587744)
			(xy 286.504888 -133.565392) (xy 286.509206 -133.56209) (xy 286.513915 -133.557804) (xy 286.521242 -133.547396)
			(xy 286.523684 -133.541516) (xy 286.64789 -132.059426) (xy 286.640524 -132.038852) (xy 286.637476 -132.03555)
			(xy 286.616479 -132.013865) (xy 286.580907 -131.965101) (xy 286.55345 -131.911348) (xy 286.534793 -131.853944)
			(xy 286.529526 -131.824222) (xy 286.526913 -131.810426) (xy 286.515179 -131.784928) (xy 286.496936 -131.763595)
			(xy 286.473569 -131.748045) (xy 286.446847 -131.739455) (xy 286.418795 -131.738476) (xy 286.405066 -131.741418)
			(xy 286.378428 -131.747488) (xy 286.32418 -131.753984) (xy 286.296862 -131.754372) (xy 286.266879 -131.75388)
			(xy 286.207427 -131.746048) (xy 286.149505 -131.730524) (xy 286.094105 -131.707573) (xy 286.042175 -131.677587)
			(xy 285.994602 -131.641081) (xy 285.952201 -131.598677) (xy 285.915697 -131.551102) (xy 285.885715 -131.49917)
			(xy 285.862767 -131.443768) (xy 285.847247 -131.385846) (xy 285.839419 -131.326393) (xy 285.8389 -131.29641)
			(xy 285.8389 -130.43281) (xy 285.839389 -130.402824) (xy 285.847216 -130.343366) (xy 285.862735 -130.285438)
			(xy 285.885683 -130.230031) (xy 285.915667 -130.178093) (xy 285.952173 -130.130513) (xy 285.994577 -130.088104)
			(xy 286.042153 -130.051594) (xy 286.094088 -130.021605) (xy 286.149492 -129.998651) (xy 286.207419 -129.983125)
			(xy 286.266876 -129.975293) (xy 286.296862 -129.974848) (xy 286.297116 -129.974848) (xy 286.324434 -129.975243)
			(xy 286.378682 -129.981732) (xy 286.40532 -129.987802) (xy 286.418562 -129.990554) (xy 286.445587 -129.98976)
			(xy 286.471458 -129.981907) (xy 286.494365 -129.967545) (xy 286.512704 -129.947679) (xy 286.525192 -129.923698)
			(xy 286.52851 -129.910586) (xy 286.529272 -129.907538) (xy 286.534067 -129.879548) (xy 286.550849 -129.825299)
			(xy 286.57548 -129.774134) (xy 286.607418 -129.727182) (xy 286.645959 -129.685478) (xy 286.690251 -129.649943)
			(xy 286.739318 -129.621359) (xy 286.792077 -129.600359) (xy 286.819594 -129.59334) (xy 286.84601 -129.587244)
			(xy 286.855662 -129.581656) (xy 287.25114 -124.864114) (xy 287.301178 -124.24029) (xy 287.302194 -124.22759)
			(xy 287.302194 -124.227336) (xy 287.683194 -119.473472) (xy 287.689544 -119.416322) (xy 287.834324 -118.37289)
			(xy 287.831022 -118.362222) (xy 287.823225 -118.335006) (xy 287.81481 -118.279022) (xy 287.814258 -118.250716)
			(xy 287.814258 -118.250462) (xy 287.814713 -118.222925) (xy 287.822565 -118.168415) (xy 287.838158 -118.115597)
			(xy 287.861171 -118.065562) (xy 287.875726 -118.042182) (xy 287.87852 -118.037864) (xy 287.88233 -118.027704)
			(xy 288.072068 -116.662708) (xy 288.15411 -116.071904) (xy 288.154571 -116.065966) (xy 288.153024 -116.05416)
			(xy 288.151062 -116.048536) (xy 288.14268 -116.026438) (xy 288.136838 -116.01958) (xy 288.120056 -115.998856)
			(xy 288.09179 -115.953637) (xy 288.070082 -115.90493) (xy 288.055352 -115.853679) (xy 288.047886 -115.800878)
			(xy 288.04743 -115.774216) (xy 288.04743 -115.772184) (xy 288.047684 -115.766596) (xy 288.048646 -115.73994)
			(xy 288.057097 -115.687276) (xy 288.072801 -115.636301) (xy 288.09545 -115.58801) (xy 288.124603 -115.543344)
			(xy 288.159693 -115.503173) (xy 288.200035 -115.46828) (xy 288.222182 -115.453414) (xy 288.225738 -115.451128)
			(xy 288.231782 -115.446098) (xy 288.240715 -115.433166) (xy 288.243264 -115.425728) (xy 288.244534 -115.420648)
			(xy 288.509964 -113.511584) (xy 288.634678 -112.61344) (xy 288.634678 -112.613186) (xy 288.634932 -112.611916)
			(xy 288.634932 -112.611662) (xy 288.63544 -112.608106) (xy 288.63544 -112.607598) (xy 288.637726 -112.591342)
			(xy 288.637726 -112.590834) (xy 289.832034 -103.994712) (xy 289.832545 -103.990399) (xy 289.832284 -103.981717)
			(xy 289.831526 -103.97744) (xy 289.828986 -103.964994) (xy 289.827208 -103.960422) (xy 289.8184 -103.938128)
			(xy 289.805773 -103.891885) (xy 289.799021 -103.844427) (xy 289.798252 -103.820468) (xy 289.798252 -103.809038)
			(xy 289.798531 -103.79584) (xy 289.800692 -103.769527) (xy 289.80257 -103.75646) (xy 289.806655 -103.732335)
			(xy 289.820209 -103.685318) (xy 289.839669 -103.640422) (xy 289.864715 -103.598386) (xy 289.879532 -103.578914)
			(xy 289.883342 -103.573834) (xy 289.891978 -103.554276) (xy 289.895026 -103.543862) (xy 289.951414 -103.135938)
			(xy 289.951414 -103.135684) (xy 289.953192 -103.122476) (xy 289.948874 -103.111046) (xy 289.9464 -103.10508)
			(xy 289.938942 -103.09454) (xy 289.934142 -103.090218) (xy 289.913253 -103.072006) (xy 289.876448 -103.030577)
			(xy 289.846031 -102.984254) (xy 289.822643 -102.934014) (xy 289.806778 -102.880916) (xy 289.798771 -102.826081)
			(xy 289.798252 -102.798372) (xy 289.798724 -102.771016) (xy 289.806543 -102.716865) (xy 289.822017 -102.664386)
			(xy 289.844828 -102.614655) (xy 289.874508 -102.568693) (xy 289.910449 -102.527441) (xy 289.951914 -102.491746)
			(xy 289.998052 -102.46234) (xy 290.022788 -102.450646) (xy 290.030916 -102.44709) (xy 290.043108 -102.435406)
			(xy 290.047172 -102.427532) (xy 290.049049 -102.423683) (xy 290.051606 -102.41551) (xy 290.052252 -102.411276)
			(xy 290.073842 -102.25659) (xy 290.082478 -102.193598) (xy 290.082938 -102.187238) (xy 290.081012 -102.174636)
			(xy 290.078668 -102.168706) (xy 290.07435 -102.1588) (xy 290.059364 -102.144576) (xy 290.049204 -102.140766)
			(xy 290.02202 -102.130272) (xy 289.970944 -102.102227) (xy 289.924725 -102.066745) (xy 289.884437 -102.024649)
			(xy 289.851016 -101.976918) (xy 289.825239 -101.924661) (xy 289.807705 -101.869093) (xy 289.798821 -101.811506)
			(xy 289.798252 -101.782372) (xy 289.798764 -101.753782) (xy 289.807303 -101.697242) (xy 289.824186 -101.64261)
			(xy 289.849035 -101.59111) (xy 289.881292 -101.543896) (xy 289.920235 -101.502026) (xy 289.964992 -101.466438)
			(xy 290.014559 -101.43793) (xy 290.067827 -101.417139) (xy 290.123601 -101.404532) (xy 290.152074 -101.40188)
			(xy 290.160735 -101.400977) (xy 290.176723 -101.394106) (xy 290.183316 -101.388418) (xy 290.189666 -101.382576)
			(xy 290.19754 -101.367082) (xy 290.212526 -101.258878) (xy 290.213522 -101.248825) (xy 290.208429 -101.229294)
			(xy 290.20262 -101.221032) (xy 290.15436 -101.157278) (xy 290.15309 -101.1555) (xy 290.136072 -101.145594)
			(xy 290.125912 -101.14407) (xy 290.125658 -101.14407) (xy 290.098734 -101.139747) (xy 290.046405 -101.124412)
			(xy 289.996793 -101.101782) (xy 289.950909 -101.072317) (xy 289.90969 -101.036617) (xy 289.873974 -100.995412)
			(xy 289.844491 -100.94954) (xy 289.82184 -100.899937) (xy 289.806485 -100.847614) (xy 289.798737 -100.793637)
			(xy 289.798252 -100.766372) (xy 289.79874 -100.739121) (xy 289.806499 -100.685174) (xy 289.821856 -100.632881)
			(xy 289.844499 -100.583304) (xy 289.873965 -100.537455) (xy 289.909656 -100.496264) (xy 289.950845 -100.460572)
			(xy 289.996694 -100.431104) (xy 290.046269 -100.408461) (xy 290.098562 -100.393102) (xy 290.152509 -100.385341)
			(xy 290.17976 -100.384864) (xy 290.192628 -100.384999) (xy 290.218304 -100.386778) (xy 290.231068 -100.38842)
			(xy 290.231576 -100.38842) (xy 290.241281 -100.3892) (xy 290.260086 -100.384224) (xy 290.268152 -100.378768)
			(xy 290.26993 -100.377498) (xy 290.32581 -100.33508) (xy 290.333455 -100.328638) (xy 290.343502 -100.311376)
			(xy 290.345368 -100.301552) (xy 291.476684 -92.160852) (xy 291.476938 -92.160344) (xy 291.477954 -92.151962)
			(xy 291.479732 -92.138754) (xy 293.628572 -76.675488) (xy 293.63022 -76.666517) (xy 293.638924 -76.650502)
			(xy 293.65268 -76.638544) (xy 293.669751 -76.632155) (xy 293.678864 -76.6318) (xy 293.68623 -76.6318)
			(xy 293.9415 -74.809858) (xy 293.942525 -74.798977) (xy 293.93635 -74.778036) (xy 293.929562 -74.769472)
			(xy 293.92245 -74.76109) (xy 293.902638 -74.7522) (xy 292.805358 -74.7522) (xy 292.795091 -74.752678)
			(xy 292.776204 -74.760736) (xy 292.761983 -74.775549) (xy 292.75786 -74.784966) (xy 288.91865 -84.9249)
			(xy 288.921698 -84.92998) (xy 288.968942 -84.998814) (xy 288.972585 -85.003817) (xy 288.981838 -85.012031)
			(xy 288.98723 -85.01507) (xy 288.998152 -85.020912) (xy 289.010598 -85.020912) (xy 289.037765 -85.021521)
			(xy 289.091517 -85.029484) (xy 289.143595 -85.044995) (xy 289.192945 -85.067738) (xy 289.238569 -85.097254)
			(xy 289.279543 -85.132944) (xy 289.315038 -85.174088) (xy 289.344336 -85.219852) (xy 289.366844 -85.26931)
			(xy 289.382106 -85.321461) (xy 289.389813 -85.375251) (xy 289.390328 -85.40242) (xy 289.389841 -85.429671)
			(xy 289.382082 -85.483617) (xy 289.366726 -85.535911) (xy 289.344083 -85.585487) (xy 289.314617 -85.631336)
			(xy 289.278926 -85.672526) (xy 289.237736 -85.708217) (xy 289.191887 -85.737683) (xy 289.142311 -85.760326)
			(xy 289.090017 -85.775682) (xy 289.036071 -85.783441) (xy 289.00882 -85.783928) (xy 288.981359 -85.783446)
			(xy 288.927004 -85.775567) (xy 288.874338 -85.759984) (xy 288.824447 -85.737018) (xy 288.778361 -85.707142)
			(xy 288.75736 -85.68944) (xy 288.757106 -85.689186) (xy 288.752418 -85.685299) (xy 288.741634 -85.679652)
			(xy 288.73577 -85.67801) (xy 288.723832 -85.675216) (xy 288.63036 -85.698584) (xy 288.625026 -85.700108)
			(xy 288.457119 -86.143592) (xy 290.59708 -86.143592) (xy 290.601151 -86.08797) (xy 290.613277 -86.033533)
			(xy 290.6332 -85.981442) (xy 290.660496 -85.932807) (xy 290.694582 -85.888664) (xy 290.734731 -85.849955)
			(xy 290.780089 -85.817504) (xy 290.829689 -85.792003) (xy 290.882473 -85.773996) (xy 290.937316 -85.763866)
			(xy 290.99305 -85.761829) (xy 291.048487 -85.767929) (xy 291.102444 -85.782035) (xy 291.153773 -85.803847)
			(xy 291.201379 -85.832901) (xy 291.244247 -85.868576) (xy 291.281464 -85.910113) (xy 291.312237 -85.956626)
			(xy 291.335909 -86.007123) (xy 291.351977 -86.06053) (xy 291.360097 -86.115706) (xy 291.360606 -86.143592)
			(xy 291.360097 -86.171478) (xy 291.351977 -86.226654) (xy 291.335909 -86.280061) (xy 291.312237 -86.330558)
			(xy 291.281464 -86.377071) (xy 291.244247 -86.418608) (xy 291.201379 -86.454283) (xy 291.153773 -86.483337)
			(xy 291.102444 -86.505149) (xy 291.048487 -86.519255) (xy 290.99305 -86.525355) (xy 290.937316 -86.523318)
			(xy 290.882473 -86.513188) (xy 290.829689 -86.495181) (xy 290.780089 -86.46968) (xy 290.734731 -86.437229)
			(xy 290.694582 -86.39852) (xy 290.660496 -86.354377) (xy 290.6332 -86.305742) (xy 290.613277 -86.253651)
			(xy 290.601151 -86.199214) (xy 290.59708 -86.143592) (xy 288.457119 -86.143592) (xy 284.684216 -96.108774)
			(xy 284.682438 -96.1136) (xy 284.49524 -96.813624) (xy 284.498796 -96.83496) (xy 284.504892 -96.844104)
			(xy 284.519484 -96.866844) (xy 284.542806 -96.915582) (xy 284.559019 -96.967123) (xy 284.567798 -97.020436)
			(xy 284.568969 -97.074453) (xy 284.562507 -97.128096) (xy 284.548542 -97.180291) (xy 284.527353 -97.229993)
			(xy 284.499364 -97.27621) (xy 284.465136 -97.318015) (xy 284.425351 -97.354574) (xy 284.380808 -97.385154)
			(xy 284.35681 -97.39757) (xy 284.346904 -97.402396) (xy 284.333188 -97.41916) (xy 284.04312 -98.503486)
			(xy 284.053026 -98.532696) (xy 284.065218 -98.542094) (xy 284.08802 -98.560301) (xy 284.128353 -98.602466)
			(xy 284.161803 -98.650274) (xy 284.187592 -98.702615) (xy 284.205119 -98.758269) (xy 284.213977 -98.815941)
			(xy 284.21457 -98.845116) (xy 284.214094 -98.872641) (xy 284.206195 -98.92712) (xy 284.19055 -98.979898)
			(xy 284.167482 -99.029881) (xy 284.137472 -99.07603) (xy 284.101141 -99.117388) (xy 284.059244 -99.153095)
			(xy 284.01265 -99.182411) (xy 283.962328 -99.204727) (xy 283.909321 -99.21958) (xy 283.882084 -99.223576)
			(xy 283.867606 -99.225608) (xy 283.844746 -99.245674) (xy 283.595773 -100.17633) (xy 285.8389 -100.17633)
			(xy 285.8389 -99.31273) (xy 285.83939 -99.282746) (xy 285.847218 -99.22329) (xy 285.862739 -99.165365)
			(xy 285.885688 -99.109961) (xy 285.915672 -99.058027) (xy 285.952178 -99.010451) (xy 285.994583 -98.968046)
			(xy 286.042159 -98.93154) (xy 286.094093 -98.901556) (xy 286.149497 -98.878607) (xy 286.207422 -98.863086)
			(xy 286.266878 -98.855258) (xy 286.326846 -98.855258) (xy 286.386302 -98.863086) (xy 286.444227 -98.878607)
			(xy 286.499631 -98.901556) (xy 286.551565 -98.93154) (xy 286.599141 -98.968046) (xy 286.641546 -99.010451)
			(xy 286.678052 -99.058027) (xy 286.708036 -99.109961) (xy 286.730985 -99.165365) (xy 286.746506 -99.22329)
			(xy 286.754334 -99.282746) (xy 286.754824 -99.31273) (xy 286.754824 -100.17633) (xy 286.754334 -100.206314)
			(xy 286.746506 -100.26577) (xy 286.730985 -100.323695) (xy 286.708036 -100.379099) (xy 286.678052 -100.431033)
			(xy 286.641546 -100.478609) (xy 286.599141 -100.521014) (xy 286.551565 -100.55752) (xy 286.499631 -100.587504)
			(xy 286.444227 -100.610453) (xy 286.386302 -100.625974) (xy 286.326846 -100.633802) (xy 286.266878 -100.633802)
			(xy 286.207422 -100.625974) (xy 286.149497 -100.610453) (xy 286.094093 -100.587504) (xy 286.042159 -100.55752)
			(xy 285.994583 -100.521014) (xy 285.952178 -100.478609) (xy 285.915672 -100.431033) (xy 285.885688 -100.379099)
			(xy 285.862739 -100.323695) (xy 285.847218 -100.26577) (xy 285.83939 -100.206314) (xy 285.8389 -100.17633)
			(xy 283.595773 -100.17633) (xy 283.114202 -101.976428) (xy 283.9847 -101.976428) (xy 283.9847 -101.112828)
			(xy 283.98519 -101.082844) (xy 283.993018 -101.023388) (xy 284.008539 -100.965463) (xy 284.031488 -100.910059)
			(xy 284.061472 -100.858125) (xy 284.097978 -100.810549) (xy 284.140383 -100.768144) (xy 284.187959 -100.731638)
			(xy 284.239893 -100.701654) (xy 284.295297 -100.678705) (xy 284.353222 -100.663184) (xy 284.412678 -100.655356)
			(xy 284.472646 -100.655356) (xy 284.532102 -100.663184) (xy 284.590027 -100.678705) (xy 284.645431 -100.701654)
			(xy 284.697365 -100.731638) (xy 284.744941 -100.768144) (xy 284.787346 -100.810549) (xy 284.823852 -100.858125)
			(xy 284.853836 -100.910059) (xy 284.876785 -100.965463) (xy 284.892306 -101.023388) (xy 284.900134 -101.082844)
			(xy 284.900624 -101.112828) (xy 284.900624 -101.976428) (xy 284.900134 -102.006412) (xy 284.892306 -102.065868)
			(xy 284.876785 -102.123793) (xy 284.853836 -102.179197) (xy 284.823852 -102.231131) (xy 284.787346 -102.278707)
			(xy 284.744941 -102.321112) (xy 284.697365 -102.357618) (xy 284.645431 -102.387602) (xy 284.590027 -102.410551)
			(xy 284.532102 -102.426072) (xy 284.472646 -102.4339) (xy 284.412678 -102.4339) (xy 284.353222 -102.426072)
			(xy 284.295297 -102.410551) (xy 284.239893 -102.387602) (xy 284.187959 -102.357618) (xy 284.140383 -102.321112)
			(xy 284.097978 -102.278707) (xy 284.061472 -102.231131) (xy 284.031488 -102.179197) (xy 284.008539 -102.123793)
			(xy 283.993018 -102.065868) (xy 283.98519 -102.006412) (xy 283.9847 -101.976428) (xy 283.114202 -101.976428)
			(xy 282.632699 -103.776272) (xy 285.8389 -103.776272) (xy 285.8389 -102.912672) (xy 285.83939 -102.882688)
			(xy 285.847218 -102.823232) (xy 285.862739 -102.765307) (xy 285.885688 -102.709903) (xy 285.915672 -102.657969)
			(xy 285.952178 -102.610393) (xy 285.994583 -102.567988) (xy 286.042159 -102.531482) (xy 286.094093 -102.501498)
			(xy 286.149497 -102.478549) (xy 286.207422 -102.463028) (xy 286.266878 -102.4552) (xy 286.326846 -102.4552)
			(xy 286.386302 -102.463028) (xy 286.444227 -102.478549) (xy 286.499631 -102.501498) (xy 286.551565 -102.531482)
			(xy 286.599141 -102.567988) (xy 286.641546 -102.610393) (xy 286.678052 -102.657969) (xy 286.708036 -102.709903)
			(xy 286.730985 -102.765307) (xy 286.746506 -102.823232) (xy 286.754334 -102.882688) (xy 286.754824 -102.912672)
			(xy 286.754824 -103.776272) (xy 286.754334 -103.806256) (xy 286.746506 -103.865712) (xy 286.730985 -103.923637)
			(xy 286.708036 -103.979041) (xy 286.678052 -104.030975) (xy 286.641546 -104.078551) (xy 286.599141 -104.120956)
			(xy 286.551565 -104.157462) (xy 286.499631 -104.187446) (xy 286.444227 -104.210395) (xy 286.386302 -104.225916)
			(xy 286.326846 -104.233744) (xy 286.266878 -104.233744) (xy 286.207422 -104.225916) (xy 286.149497 -104.210395)
			(xy 286.094093 -104.187446) (xy 286.042159 -104.157462) (xy 285.994583 -104.120956) (xy 285.952178 -104.078551)
			(xy 285.915672 -104.030975) (xy 285.885688 -103.979041) (xy 285.862739 -103.923637) (xy 285.847218 -103.865712)
			(xy 285.83939 -103.806256) (xy 285.8389 -103.776272) (xy 282.632699 -103.776272) (xy 282.151129 -105.57637)
			(xy 283.9847 -105.57637) (xy 283.9847 -104.71277) (xy 283.98519 -104.682786) (xy 283.993018 -104.62333)
			(xy 284.008539 -104.565405) (xy 284.031488 -104.510001) (xy 284.061472 -104.458067) (xy 284.097978 -104.410491)
			(xy 284.140383 -104.368086) (xy 284.187959 -104.33158) (xy 284.239893 -104.301596) (xy 284.295297 -104.278647)
			(xy 284.353222 -104.263126) (xy 284.412678 -104.255298) (xy 284.472646 -104.255298) (xy 284.532102 -104.263126)
			(xy 284.590027 -104.278647) (xy 284.645431 -104.301596) (xy 284.697365 -104.33158) (xy 284.744941 -104.368086)
			(xy 284.787346 -104.410491) (xy 284.823852 -104.458067) (xy 284.853836 -104.510001) (xy 284.876785 -104.565405)
			(xy 284.892306 -104.62333) (xy 284.900134 -104.682786) (xy 284.900624 -104.71277) (xy 284.900624 -105.57637)
			(xy 284.900134 -105.606354) (xy 284.892306 -105.66581) (xy 284.876785 -105.723735) (xy 284.853836 -105.779139)
			(xy 284.823852 -105.831073) (xy 284.787346 -105.878649) (xy 284.744941 -105.921054) (xy 284.697365 -105.95756)
			(xy 284.645431 -105.987544) (xy 284.590027 -106.010493) (xy 284.532102 -106.026014) (xy 284.472646 -106.033842)
			(xy 284.412678 -106.033842) (xy 284.353222 -106.026014) (xy 284.295297 -106.010493) (xy 284.239893 -105.987544)
			(xy 284.187959 -105.95756) (xy 284.140383 -105.921054) (xy 284.097978 -105.878649) (xy 284.061472 -105.831073)
			(xy 284.031488 -105.779139) (xy 284.008539 -105.723735) (xy 283.993018 -105.66581) (xy 283.98519 -105.606354)
			(xy 283.9847 -105.57637) (xy 282.151129 -105.57637) (xy 281.764486 -107.02163) (xy 281.768042 -107.042966)
			(xy 281.772106 -107.049062) (xy 281.781758 -107.057444) (xy 281.791664 -107.06227) (xy 281.815872 -107.074181)
			(xy 281.860961 -107.103808) (xy 281.901426 -107.139493) (xy 281.936458 -107.180523) (xy 281.965361 -107.22608)
			(xy 281.987555 -107.275254) (xy 282.0026 -107.327066) (xy 282.009587 -107.376214) (xy 285.8389 -107.376214)
			(xy 285.8389 -106.512614) (xy 285.83939 -106.48263) (xy 285.847218 -106.423174) (xy 285.862739 -106.365249)
			(xy 285.885688 -106.309845) (xy 285.915672 -106.257911) (xy 285.952178 -106.210335) (xy 285.994583 -106.16793)
			(xy 286.042159 -106.131424) (xy 286.094093 -106.10144) (xy 286.149497 -106.078491) (xy 286.207422 -106.06297)
			(xy 286.266878 -106.055142) (xy 286.326846 -106.055142) (xy 286.386302 -106.06297) (xy 286.444227 -106.078491)
			(xy 286.499631 -106.10144) (xy 286.551565 -106.131424) (xy 286.599141 -106.16793) (xy 286.641546 -106.210335)
			(xy 286.678052 -106.257911) (xy 286.708036 -106.309845) (xy 286.730985 -106.365249) (xy 286.746506 -106.423174)
			(xy 286.754334 -106.48263) (xy 286.754824 -106.512614) (xy 286.754824 -107.376214) (xy 286.754334 -107.406198)
			(xy 286.746506 -107.465654) (xy 286.730985 -107.523579) (xy 286.708036 -107.578983) (xy 286.678052 -107.630917)
			(xy 286.641546 -107.678493) (xy 286.599141 -107.720898) (xy 286.551565 -107.757404) (xy 286.499631 -107.787388)
			(xy 286.444227 -107.810337) (xy 286.386302 -107.825858) (xy 286.326846 -107.833686) (xy 286.266878 -107.833686)
			(xy 286.207422 -107.825858) (xy 286.149497 -107.810337) (xy 286.094093 -107.787388) (xy 286.042159 -107.757404)
			(xy 285.994583 -107.720898) (xy 285.952178 -107.678493) (xy 285.915672 -107.630917) (xy 285.885688 -107.578983)
			(xy 285.862739 -107.523579) (xy 285.847218 -107.465654) (xy 285.83939 -107.406198) (xy 285.8389 -107.376214)
			(xy 282.009587 -107.376214) (xy 282.010194 -107.38048) (xy 282.010612 -107.407456) (xy 282.010152 -107.434711)
			(xy 282.0024 -107.488667) (xy 281.987048 -107.54097) (xy 281.964408 -107.590556) (xy 281.934941 -107.636415)
			(xy 281.899247 -107.677613) (xy 281.858054 -107.713312) (xy 281.812198 -107.742785) (xy 281.762615 -107.765431)
			(xy 281.710314 -107.78079) (xy 281.656359 -107.788548) (xy 281.629104 -107.788964) (xy 281.628342 -107.788964)
			(xy 281.601926 -107.788202) (xy 281.57678 -107.786424) (xy 281.572096 -107.786961) (xy 281.563022 -107.789518)
			(xy 281.558746 -107.791504) (xy 281.188288 -109.176312) (xy 283.9847 -109.176312) (xy 283.9847 -108.312712)
			(xy 283.98519 -108.282728) (xy 283.993018 -108.223272) (xy 284.008539 -108.165347) (xy 284.031488 -108.109943)
			(xy 284.061472 -108.058009) (xy 284.097978 -108.010433) (xy 284.140383 -107.968028) (xy 284.187959 -107.931522)
			(xy 284.239893 -107.901538) (xy 284.295297 -107.878589) (xy 284.353222 -107.863068) (xy 284.412678 -107.85524)
			(xy 284.472646 -107.85524) (xy 284.532102 -107.863068) (xy 284.590027 -107.878589) (xy 284.645431 -107.901538)
			(xy 284.697365 -107.931522) (xy 284.744941 -107.968028) (xy 284.787346 -108.010433) (xy 284.823852 -108.058009)
			(xy 284.853836 -108.109943) (xy 284.876785 -108.165347) (xy 284.892306 -108.223272) (xy 284.900134 -108.282728)
			(xy 284.900624 -108.312712) (xy 284.900624 -109.176312) (xy 284.900134 -109.206296) (xy 284.892306 -109.265752)
			(xy 284.876785 -109.323677) (xy 284.853836 -109.379081) (xy 284.823852 -109.431015) (xy 284.787346 -109.478591)
			(xy 284.744941 -109.520996) (xy 284.697365 -109.557502) (xy 284.645431 -109.587486) (xy 284.590027 -109.610435)
			(xy 284.532102 -109.625956) (xy 284.472646 -109.633784) (xy 284.412678 -109.633784) (xy 284.353222 -109.625956)
			(xy 284.295297 -109.610435) (xy 284.239893 -109.587486) (xy 284.187959 -109.557502) (xy 284.140383 -109.520996)
			(xy 284.097978 -109.478591) (xy 284.061472 -109.431015) (xy 284.031488 -109.379081) (xy 284.008539 -109.323677)
			(xy 283.993018 -109.265752) (xy 283.98519 -109.206296) (xy 283.9847 -109.176312) (xy 281.188288 -109.176312)
			(xy 280.907998 -110.224062) (xy 280.907998 -110.22457) (xy 280.71253 -110.97641) (xy 285.8389 -110.97641)
			(xy 285.8389 -110.11281) (xy 285.83939 -110.082826) (xy 285.847218 -110.02337) (xy 285.862739 -109.965445)
			(xy 285.885688 -109.910041) (xy 285.915672 -109.858107) (xy 285.952178 -109.810531) (xy 285.994583 -109.768126)
			(xy 286.042159 -109.73162) (xy 286.094093 -109.701636) (xy 286.149497 -109.678687) (xy 286.207422 -109.663166)
			(xy 286.266878 -109.655338) (xy 286.326846 -109.655338) (xy 286.386302 -109.663166) (xy 286.444227 -109.678687)
			(xy 286.499631 -109.701636) (xy 286.551565 -109.73162) (xy 286.599141 -109.768126) (xy 286.641546 -109.810531)
			(xy 286.678052 -109.858107) (xy 286.708036 -109.910041) (xy 286.730985 -109.965445) (xy 286.746506 -110.02337)
			(xy 286.754334 -110.082826) (xy 286.754824 -110.11281) (xy 286.754824 -110.97641) (xy 286.754334 -111.006394)
			(xy 286.746506 -111.06585) (xy 286.730985 -111.123775) (xy 286.708036 -111.179179) (xy 286.678052 -111.231113)
			(xy 286.641546 -111.278689) (xy 286.599141 -111.321094) (xy 286.551565 -111.3576) (xy 286.499631 -111.387584)
			(xy 286.444227 -111.410533) (xy 286.386302 -111.426054) (xy 286.326846 -111.433882) (xy 286.266878 -111.433882)
			(xy 286.207422 -111.426054) (xy 286.149497 -111.410533) (xy 286.094093 -111.387584) (xy 286.042159 -111.3576)
			(xy 285.994583 -111.321094) (xy 285.952178 -111.278689) (xy 285.915672 -111.231113) (xy 285.885688 -111.179179)
			(xy 285.862739 -111.123775) (xy 285.847218 -111.06585) (xy 285.83939 -111.006394) (xy 285.8389 -110.97641)
			(xy 280.71253 -110.97641) (xy 280.24453 -112.776508) (xy 283.9847 -112.776508) (xy 283.9847 -111.912908)
			(xy 283.98519 -111.882924) (xy 283.993018 -111.823468) (xy 284.008539 -111.765543) (xy 284.031488 -111.710139)
			(xy 284.061472 -111.658205) (xy 284.097978 -111.610629) (xy 284.140383 -111.568224) (xy 284.187959 -111.531718)
			(xy 284.239893 -111.501734) (xy 284.295297 -111.478785) (xy 284.353222 -111.463264) (xy 284.412678 -111.455436)
			(xy 284.472646 -111.455436) (xy 284.532102 -111.463264) (xy 284.590027 -111.478785) (xy 284.645431 -111.501734)
			(xy 284.697365 -111.531718) (xy 284.744941 -111.568224) (xy 284.787346 -111.610629) (xy 284.823852 -111.658205)
			(xy 284.853836 -111.710139) (xy 284.876785 -111.765543) (xy 284.892306 -111.823468) (xy 284.900134 -111.882924)
			(xy 284.900624 -111.912908) (xy 284.900624 -112.776508) (xy 284.900134 -112.806492) (xy 284.892306 -112.865948)
			(xy 284.876785 -112.923873) (xy 284.853836 -112.979277) (xy 284.823852 -113.031211) (xy 284.787346 -113.078787)
			(xy 284.744941 -113.121192) (xy 284.697365 -113.157698) (xy 284.645431 -113.187682) (xy 284.590027 -113.210631)
			(xy 284.532102 -113.226152) (xy 284.472646 -113.23398) (xy 284.412678 -113.23398) (xy 284.353222 -113.226152)
			(xy 284.295297 -113.210631) (xy 284.239893 -113.187682) (xy 284.187959 -113.157698) (xy 284.140383 -113.121192)
			(xy 284.097978 -113.078787) (xy 284.061472 -113.031211) (xy 284.031488 -112.979277) (xy 284.008539 -112.923873)
			(xy 283.993018 -112.865948) (xy 283.98519 -112.806492) (xy 283.9847 -112.776508) (xy 280.24453 -112.776508)
			(xy 279.41016 -115.985798) (xy 279.408382 -115.992656) (xy 279.42921 -118.38813) (xy 279.429418 -118.394217)
			(xy 279.43237 -118.40603) (xy 279.435052 -118.411498) (xy 279.4508 -118.44147) (xy 279.458674 -118.447566)
			(xy 279.48236 -118.465667) (xy 279.52434 -118.507987) (xy 279.559224 -118.556324) (xy 279.586163 -118.6095)
			(xy 279.6045 -118.666219) (xy 279.613789 -118.725101) (xy 279.614376 -118.754906) (xy 279.613825 -118.78405)
			(xy 279.604967 -118.84166) (xy 279.587456 -118.897254) (xy 279.561701 -118.949543) (xy 279.528298 -118.997309)
			(xy 279.488025 -119.039445) (xy 279.465278 -119.057674) (xy 279.460706 -119.06123) (xy 279.453594 -119.069612)
			(xy 279.451562 -119.073676) (xy 279.440894 -119.093996) (xy 279.438862 -119.098822) (xy 279.437327 -119.102916)
			(xy 279.435533 -119.111474) (xy 279.435306 -119.11584) (xy 279.443607 -120.086374) (xy 285.8389 -120.086374)
			(xy 285.8389 -119.222774) (xy 285.83939 -119.19279) (xy 285.847218 -119.133334) (xy 285.862739 -119.075409)
			(xy 285.885688 -119.020005) (xy 285.915672 -118.968071) (xy 285.952178 -118.920495) (xy 285.994583 -118.87809)
			(xy 286.042159 -118.841584) (xy 286.094093 -118.8116) (xy 286.149497 -118.788651) (xy 286.207422 -118.77313)
			(xy 286.266878 -118.765302) (xy 286.326846 -118.765302) (xy 286.386302 -118.77313) (xy 286.444227 -118.788651)
			(xy 286.499631 -118.8116) (xy 286.551565 -118.841584) (xy 286.599141 -118.87809) (xy 286.641546 -118.920495)
			(xy 286.678052 -118.968071) (xy 286.708036 -119.020005) (xy 286.730985 -119.075409) (xy 286.746506 -119.133334)
			(xy 286.754334 -119.19279) (xy 286.754824 -119.222774) (xy 286.754824 -120.086374) (xy 286.754334 -120.116358)
			(xy 286.746506 -120.175814) (xy 286.730985 -120.233739) (xy 286.708036 -120.289143) (xy 286.678052 -120.341077)
			(xy 286.641546 -120.388653) (xy 286.599141 -120.431058) (xy 286.551565 -120.467564) (xy 286.499631 -120.497548)
			(xy 286.444227 -120.520497) (xy 286.386302 -120.536018) (xy 286.326846 -120.543846) (xy 286.266878 -120.543846)
			(xy 286.207422 -120.536018) (xy 286.149497 -120.520497) (xy 286.094093 -120.497548) (xy 286.042159 -120.467564)
			(xy 285.994583 -120.431058) (xy 285.952178 -120.388653) (xy 285.915672 -120.341077) (xy 285.885688 -120.289143)
			(xy 285.862739 -120.233739) (xy 285.847218 -120.175814) (xy 285.83939 -120.116358) (xy 285.8389 -120.086374)
			(xy 279.443607 -120.086374) (xy 279.444704 -120.214644) (xy 279.445466 -120.220994) (xy 279.447244 -120.230646)
			(xy 279.456642 -120.245886) (xy 279.464516 -120.251982) (xy 279.48739 -120.270145) (xy 279.527866 -120.312252)
			(xy 279.561446 -120.360039) (xy 279.587343 -120.41239) (xy 279.604952 -120.468078) (xy 279.613861 -120.525801)
			(xy 279.614376 -120.555004) (xy 279.613878 -120.582762) (xy 279.605841 -120.637692) (xy 279.589937 -120.69088)
			(xy 279.566501 -120.741206) (xy 279.536027 -120.787609) (xy 279.499156 -120.829112) (xy 279.478232 -120.847358)
			(xy 279.473914 -120.850914) (xy 279.467818 -120.858788) (xy 279.462484 -120.86971) (xy 279.461976 -120.870218)
			(xy 279.45588 -120.883172) (xy 279.45207 -120.894602) (xy 279.451562 -120.896634) (xy 279.4508 -120.903492)
			(xy 279.457658 -121.704354) (xy 279.458166 -121.752614) (xy 279.458166 -121.75363) (xy 279.45842 -121.757948)
			(xy 279.459944 -121.770394) (xy 279.466548 -121.7803) (xy 279.470008 -121.785309) (xy 279.478867 -121.793656)
			(xy 279.484074 -121.79681) (xy 279.484328 -121.79681) (xy 279.509418 -121.811368) (xy 279.555277 -121.846887)
			(xy 279.592889 -121.886472) (xy 283.9847 -121.886472) (xy 283.9847 -121.022872) (xy 283.98519 -120.992888)
			(xy 283.993018 -120.933432) (xy 284.008539 -120.875507) (xy 284.031488 -120.820103) (xy 284.061472 -120.768169)
			(xy 284.097978 -120.720593) (xy 284.140383 -120.678188) (xy 284.187959 -120.641682) (xy 284.239893 -120.611698)
			(xy 284.295297 -120.588749) (xy 284.353222 -120.573228) (xy 284.412678 -120.5654) (xy 284.472646 -120.5654)
			(xy 284.532102 -120.573228) (xy 284.590027 -120.588749) (xy 284.645431 -120.611698) (xy 284.697365 -120.641682)
			(xy 284.744941 -120.678188) (xy 284.787346 -120.720593) (xy 284.823852 -120.768169) (xy 284.853836 -120.820103)
			(xy 284.876785 -120.875507) (xy 284.892306 -120.933432) (xy 284.900134 -120.992888) (xy 284.900624 -121.022872)
			(xy 284.900624 -121.886472) (xy 284.900134 -121.916456) (xy 284.892306 -121.975912) (xy 284.876785 -122.033837)
			(xy 284.853836 -122.089241) (xy 284.823852 -122.141175) (xy 284.787346 -122.188751) (xy 284.744941 -122.231156)
			(xy 284.697365 -122.267662) (xy 284.645431 -122.297646) (xy 284.590027 -122.320595) (xy 284.532102 -122.336116)
			(xy 284.472646 -122.343944) (xy 284.412678 -122.343944) (xy 284.353222 -122.336116) (xy 284.295297 -122.320595)
			(xy 284.239893 -122.297646) (xy 284.187959 -122.267662) (xy 284.140383 -122.231156) (xy 284.097978 -122.188751)
			(xy 284.061472 -122.141175) (xy 284.031488 -122.089241) (xy 284.008539 -122.033837) (xy 283.993018 -121.975912)
			(xy 283.98519 -121.916456) (xy 283.9847 -121.886472) (xy 279.592889 -121.886472) (xy 279.595232 -121.888938)
			(xy 279.628363 -121.936551) (xy 279.653907 -121.988629) (xy 279.671274 -122.043974) (xy 279.680066 -122.101309)
			(xy 279.68067 -122.130312) (xy 279.680177 -122.157978) (xy 279.672185 -122.212731) (xy 279.65637 -122.265756)
			(xy 279.633065 -122.315941) (xy 279.602756 -122.362235) (xy 279.566081 -122.403667) (xy 279.523807 -122.439369)
			(xy 279.500584 -122.454416) (xy 279.494742 -122.457972) (xy 279.490678 -122.46229) (xy 279.483566 -122.471688)
			(xy 279.471374 -122.49277) (xy 279.46985 -122.495564) (xy 279.46749 -122.500655) (xy 279.464802 -122.511549)
			(xy 279.464516 -122.517154) (xy 279.464516 -122.518678) (xy 279.471628 -123.318524) (xy 279.474802 -123.686316)
			(xy 285.8389 -123.686316) (xy 285.8389 -122.822716) (xy 285.83939 -122.792732) (xy 285.847218 -122.733276)
			(xy 285.862739 -122.675351) (xy 285.885688 -122.619947) (xy 285.915672 -122.568013) (xy 285.952178 -122.520437)
			(xy 285.994583 -122.478032) (xy 286.042159 -122.441526) (xy 286.094093 -122.411542) (xy 286.149497 -122.388593)
			(xy 286.207422 -122.373072) (xy 286.266878 -122.365244) (xy 286.326846 -122.365244) (xy 286.386302 -122.373072)
			(xy 286.444227 -122.388593) (xy 286.499631 -122.411542) (xy 286.551565 -122.441526) (xy 286.599141 -122.478032)
			(xy 286.641546 -122.520437) (xy 286.678052 -122.568013) (xy 286.708036 -122.619947) (xy 286.730985 -122.675351)
			(xy 286.746506 -122.733276) (xy 286.754334 -122.792732) (xy 286.754824 -122.822716) (xy 286.754824 -123.686316)
			(xy 286.754334 -123.7163) (xy 286.746506 -123.775756) (xy 286.730985 -123.833681) (xy 286.708036 -123.889085)
			(xy 286.678052 -123.941019) (xy 286.641546 -123.988595) (xy 286.599141 -124.031) (xy 286.551565 -124.067506)
			(xy 286.499631 -124.09749) (xy 286.444227 -124.120439) (xy 286.386302 -124.13596) (xy 286.326846 -124.143788)
			(xy 286.266878 -124.143788) (xy 286.207422 -124.13596) (xy 286.149497 -124.120439) (xy 286.094093 -124.09749)
			(xy 286.042159 -124.067506) (xy 285.994583 -124.031) (xy 285.952178 -123.988595) (xy 285.915672 -123.941019)
			(xy 285.885688 -123.889085) (xy 285.862739 -123.833681) (xy 285.847218 -123.775756) (xy 285.83939 -123.7163)
			(xy 285.8389 -123.686316) (xy 279.474802 -123.686316) (xy 279.490339 -125.486414) (xy 283.9847 -125.486414)
			(xy 283.9847 -124.622814) (xy 283.98519 -124.59283) (xy 283.993018 -124.533374) (xy 284.008539 -124.475449)
			(xy 284.031488 -124.420045) (xy 284.061472 -124.368111) (xy 284.097978 -124.320535) (xy 284.140383 -124.27813)
			(xy 284.187959 -124.241624) (xy 284.239893 -124.21164) (xy 284.295297 -124.188691) (xy 284.353222 -124.17317)
			(xy 284.412678 -124.165342) (xy 284.472646 -124.165342) (xy 284.532102 -124.17317) (xy 284.590027 -124.188691)
			(xy 284.645431 -124.21164) (xy 284.697365 -124.241624) (xy 284.744941 -124.27813) (xy 284.787346 -124.320535)
			(xy 284.823852 -124.368111) (xy 284.853836 -124.420045) (xy 284.876785 -124.475449) (xy 284.892306 -124.533374)
			(xy 284.900134 -124.59283) (xy 284.900624 -124.622814) (xy 284.900624 -125.486414) (xy 284.900134 -125.516398)
			(xy 284.892306 -125.575854) (xy 284.876785 -125.633779) (xy 284.853836 -125.689183) (xy 284.823852 -125.741117)
			(xy 284.787346 -125.788693) (xy 284.744941 -125.831098) (xy 284.697365 -125.867604) (xy 284.645431 -125.897588)
			(xy 284.590027 -125.920537) (xy 284.532102 -125.936058) (xy 284.472646 -125.943886) (xy 284.412678 -125.943886)
			(xy 284.353222 -125.936058) (xy 284.295297 -125.920537) (xy 284.239893 -125.897588) (xy 284.187959 -125.867604)
			(xy 284.140383 -125.831098) (xy 284.097978 -125.788693) (xy 284.061472 -125.741117) (xy 284.031488 -125.689183)
			(xy 284.008539 -125.633779) (xy 283.993018 -125.575854) (xy 283.98519 -125.516398) (xy 283.9847 -125.486414)
			(xy 279.490339 -125.486414) (xy 279.517118 -128.589024) (xy 285.77997 -128.589024) (xy 285.784041 -128.533402)
			(xy 285.796167 -128.478965) (xy 285.81609 -128.426874) (xy 285.843386 -128.378239) (xy 285.877472 -128.334096)
			(xy 285.917621 -128.295387) (xy 285.962979 -128.262936) (xy 286.012579 -128.237435) (xy 286.065363 -128.219428)
			(xy 286.120206 -128.209298) (xy 286.17594 -128.207261) (xy 286.231377 -128.213361) (xy 286.285334 -128.227467)
			(xy 286.336663 -128.249279) (xy 286.384269 -128.278333) (xy 286.427137 -128.314008) (xy 286.464354 -128.355545)
			(xy 286.495127 -128.402058) (xy 286.518799 -128.452555) (xy 286.534867 -128.505962) (xy 286.542987 -128.561138)
			(xy 286.543496 -128.589024) (xy 286.542987 -128.61691) (xy 286.534867 -128.672086) (xy 286.518799 -128.725493)
			(xy 286.495127 -128.77599) (xy 286.464354 -128.822503) (xy 286.427137 -128.86404) (xy 286.384269 -128.899715)
			(xy 286.336663 -128.928769) (xy 286.285334 -128.950581) (xy 286.231377 -128.964687) (xy 286.17594 -128.970787)
			(xy 286.120206 -128.96875) (xy 286.065363 -128.95862) (xy 286.012579 -128.940613) (xy 285.962979 -128.915112)
			(xy 285.917621 -128.882661) (xy 285.877472 -128.843952) (xy 285.843386 -128.799809) (xy 285.81609 -128.751174)
			(xy 285.796167 -128.699083) (xy 285.784041 -128.644646) (xy 285.77997 -128.589024) (xy 279.517118 -128.589024)
			(xy 279.526746 -129.704592) (xy 279.526815 -129.7086) (xy 279.528093 -129.716513) (xy 279.529286 -129.72034)
			(xy 279.531826 -129.727706) (xy 279.536906 -129.73431) (xy 279.555122 -129.759327) (xy 279.584061 -129.814025)
			(xy 279.603786 -129.872678) (xy 279.613781 -129.933747) (xy 279.614376 -129.964688) (xy 279.614376 -129.964942)
			(xy 279.613819 -129.994106) (xy 279.604934 -130.051753) (xy 279.587376 -130.107376) (xy 279.561555 -130.159677)
			(xy 279.545288 -130.18389) (xy 279.54097 -130.19024) (xy 279.533858 -130.21183) (xy 279.53335 -130.2131)
			(xy 279.531318 -130.2258) (xy 279.531318 -130.228086) (xy 279.542494 -131.519422) (xy 279.542571 -131.523165)
			(xy 279.543715 -131.530565) (xy 279.54478 -131.534154) (xy 279.55113 -131.553966) (xy 279.554686 -131.5593)
			(xy 279.568909 -131.58245) (xy 279.591367 -131.631922) (xy 279.606571 -131.684083) (xy 279.614212 -131.737874)
			(xy 279.61463 -131.76504) (xy 279.614188 -131.791271) (xy 279.607002 -131.843238) (xy 279.592783 -131.893736)
			(xy 279.571799 -131.941818) (xy 279.558496 -131.96443) (xy 279.554686 -131.970272) (xy 279.548336 -131.992116)
			(xy 279.546812 -132.002276) (xy 279.556323 -133.096508) (xy 283.9847 -133.096508) (xy 283.9847 -132.232908)
			(xy 283.98519 -132.202924) (xy 283.993018 -132.143468) (xy 284.008539 -132.085543) (xy 284.031488 -132.030139)
			(xy 284.061472 -131.978205) (xy 284.097978 -131.930629) (xy 284.140383 -131.888224) (xy 284.187959 -131.851718)
			(xy 284.239893 -131.821734) (xy 284.295297 -131.798785) (xy 284.353222 -131.783264) (xy 284.412678 -131.775436)
			(xy 284.472646 -131.775436) (xy 284.532102 -131.783264) (xy 284.590027 -131.798785) (xy 284.645431 -131.821734)
			(xy 284.697365 -131.851718) (xy 284.744941 -131.888224) (xy 284.787346 -131.930629) (xy 284.823852 -131.978205)
			(xy 284.853836 -132.030139) (xy 284.876785 -132.085543) (xy 284.892306 -132.143468) (xy 284.900134 -132.202924)
			(xy 284.900624 -132.232908) (xy 284.900624 -133.096508) (xy 284.900134 -133.126492) (xy 284.892306 -133.185948)
			(xy 284.876785 -133.243873) (xy 284.853836 -133.299277) (xy 284.823852 -133.351211) (xy 284.787346 -133.398787)
			(xy 284.744941 -133.441192) (xy 284.697365 -133.477698) (xy 284.645431 -133.507682) (xy 284.590027 -133.530631)
			(xy 284.532102 -133.546152) (xy 284.472646 -133.55398) (xy 284.412678 -133.55398) (xy 284.353222 -133.546152)
			(xy 284.295297 -133.530631) (xy 284.239893 -133.507682) (xy 284.187959 -133.477698) (xy 284.140383 -133.441192)
			(xy 284.097978 -133.398787) (xy 284.061472 -133.351211) (xy 284.031488 -133.299277) (xy 284.008539 -133.243873)
			(xy 283.993018 -133.185948) (xy 283.98519 -133.126492) (xy 283.9847 -133.096508) (xy 279.556323 -133.096508)
			(xy 279.558496 -133.346444) (xy 279.558496 -133.346698) (xy 279.559766 -133.357874) (xy 279.563322 -133.371082)
			(xy 279.56764 -133.382258) (xy 279.57399 -133.393688) (xy 279.586798 -133.420435) (xy 279.604907 -133.476902)
			(xy 279.614077 -133.535488) (xy 279.61463 -133.565138) (xy 279.613998 -133.596894) (xy 279.603488 -133.65953)
			(xy 279.582765 -133.719565) (xy 279.568148 -133.747764) (xy 279.565862 -133.752336) (xy 279.564592 -133.755384)
			(xy 279.561798 -133.7691) (xy 279.587249 -136.69645) (xy 283.9847 -136.69645) (xy 283.9847 -135.83285)
			(xy 283.98519 -135.802866) (xy 283.993018 -135.74341) (xy 284.008539 -135.685485) (xy 284.031488 -135.630081)
			(xy 284.061472 -135.578147) (xy 284.097978 -135.530571) (xy 284.140383 -135.488166) (xy 284.187959 -135.45166)
			(xy 284.239893 -135.421676) (xy 284.295297 -135.398727) (xy 284.353222 -135.383206) (xy 284.412678 -135.375378)
			(xy 284.472646 -135.375378) (xy 284.532102 -135.383206) (xy 284.590027 -135.398727) (xy 284.645431 -135.421676)
			(xy 284.697365 -135.45166) (xy 284.744941 -135.488166) (xy 284.787346 -135.530571) (xy 284.823852 -135.578147)
			(xy 284.853836 -135.630081) (xy 284.876785 -135.685485) (xy 284.892306 -135.74341) (xy 284.900134 -135.802866)
			(xy 284.900624 -135.83285) (xy 284.900624 -136.69645) (xy 284.900134 -136.726434) (xy 284.892306 -136.78589)
			(xy 284.876785 -136.843815) (xy 284.853836 -136.899219) (xy 284.823852 -136.951153) (xy 284.787346 -136.998729)
			(xy 284.744941 -137.041134) (xy 284.697365 -137.07764) (xy 284.645431 -137.107624) (xy 284.590027 -137.130573)
			(xy 284.532102 -137.146094) (xy 284.472646 -137.153922) (xy 284.412678 -137.153922) (xy 284.353222 -137.146094)
			(xy 284.295297 -137.130573) (xy 284.239893 -137.107624) (xy 284.187959 -137.07764) (xy 284.140383 -137.041134)
			(xy 284.097978 -136.998729) (xy 284.061472 -136.951153) (xy 284.031488 -136.899219) (xy 284.008539 -136.843815)
			(xy 283.993018 -136.78589) (xy 283.98519 -136.726434) (xy 283.9847 -136.69645) (xy 279.587249 -136.69645)
			(xy 279.588722 -136.865868) (xy 279.601676 -138.350752) (xy 279.6032 -138.36269) (xy 279.607772 -138.38047)
			(xy 279.610566 -138.385804) (xy 279.624488 -138.413395) (xy 279.644187 -138.47197) (xy 279.654155 -138.532959)
			(xy 279.654762 -138.563858) (xy 279.654762 -138.56462) (xy 279.654762 -138.569192) (xy 279.653802 -138.59918)
			(xy 279.643615 -138.658305) (xy 279.624295 -138.715105) (xy 279.61082 -138.741912) (xy 279.607772 -138.747754)
			(xy 279.604978 -138.759438) (xy 279.610566 -139.397486) (xy 279.611247 -139.408647) (xy 279.620848 -139.428814)
			(xy 279.629108 -139.436348) (xy 279.650513 -139.454564) (xy 279.688255 -139.496211) (xy 279.719477 -139.542946)
			(xy 279.743503 -139.593756) (xy 279.759814 -139.647542) (xy 279.768055 -139.70314) (xy 279.768554 -139.731242)
			(xy 279.768071 -139.758818) (xy 279.760137 -139.813396) (xy 279.744425 -139.866263) (xy 279.721264 -139.916316)
			(xy 279.691136 -139.962512) (xy 279.654669 -140.003887) (xy 279.633934 -140.022072) (xy 279.629722 -140.025883)
			(xy 279.622927 -140.034984) (xy 279.620472 -140.040106) (xy 279.616154 -140.049504) (xy 279.616154 -140.060934)
			(xy 279.616662 -140.120116) (xy 279.616795 -140.125007) (xy 279.617288 -140.127482) (xy 283.80512 -140.127482)
			(xy 283.809191 -140.07186) (xy 283.821317 -140.017423) (xy 283.84124 -139.965332) (xy 283.868536 -139.916697)
			(xy 283.902622 -139.872554) (xy 283.942771 -139.833845) (xy 283.988129 -139.801394) (xy 284.037729 -139.775893)
			(xy 284.090513 -139.757886) (xy 284.145356 -139.747756) (xy 284.20109 -139.745719) (xy 284.256527 -139.751819)
			(xy 284.310484 -139.765925) (xy 284.361813 -139.787737) (xy 284.409419 -139.816791) (xy 284.452287 -139.852466)
			(xy 284.489504 -139.894003) (xy 284.520277 -139.940516) (xy 284.543949 -139.991013) (xy 284.560017 -140.04442)
			(xy 284.568137 -140.099596) (xy 284.568646 -140.127482) (xy 284.568137 -140.155368) (xy 284.560017 -140.210544)
			(xy 284.543949 -140.263951) (xy 284.520277 -140.314448) (xy 284.489504 -140.360961) (xy 284.452287 -140.402498)
			(xy 284.409419 -140.438173) (xy 284.361813 -140.467227) (xy 284.310484 -140.489039) (xy 284.256527 -140.503145)
			(xy 284.20109 -140.509245) (xy 284.145356 -140.507208) (xy 284.090513 -140.497078) (xy 284.037729 -140.479071)
			(xy 283.988129 -140.45357) (xy 283.942771 -140.421119) (xy 283.902622 -140.38241) (xy 283.868536 -140.338267)
			(xy 283.84124 -140.289632) (xy 283.821317 -140.237541) (xy 283.809191 -140.183104) (xy 283.80512 -140.127482)
			(xy 279.617288 -140.127482) (xy 279.618706 -140.134603) (xy 279.620472 -140.139166) (xy 279.630886 -140.164566)
			(xy 279.636982 -140.17117) (xy 279.65579 -140.192431) (xy 279.687561 -140.23947) (xy 279.712022 -140.290691)
			(xy 279.728636 -140.344969) (xy 279.737036 -140.401107) (xy 279.737566 -140.429488) (xy 279.737566 -140.429742)
			(xy 279.73703 -140.458229) (xy 279.72855 -140.514568) (xy 279.711801 -140.569025) (xy 279.687152 -140.620391)
			(xy 279.655151 -140.667529) (xy 279.63622 -140.688822) (xy 279.630632 -140.694918) (xy 279.61971 -140.719048)
			(xy 279.618156 -140.723013) (xy 279.616248 -140.731313) (xy 279.6159 -140.735558) (xy 279.6159 -140.735812)
			(xy 279.574752 -141.361414) (xy 279.574752 -141.365478) (xy 279.579578 -141.85011) (xy 279.579578 -141.851634)
			(xy 279.58034 -141.886432) (xy 279.58034 -141.88694) (xy 279.580199 -141.903783) (xy 279.578928 -141.937445)
			(xy 279.5778 -141.95425) (xy 279.53408 -142.60068) (xy 283.80563 -142.60068) (xy 283.806093 -142.573275)
			(xy 283.813944 -142.51903) (xy 283.829482 -142.466469) (xy 283.852385 -142.416674) (xy 283.882183 -142.370671)
			(xy 283.899864 -142.349728) (xy 283.900118 -142.349474) (xy 283.905682 -142.342372) (xy 283.911942 -142.325467)
			(xy 283.91231 -142.316454) (xy 283.91231 -142.249144) (xy 283.91193 -142.240129) (xy 283.905698 -142.223212)
			(xy 283.900118 -142.216124) (xy 283.89961 -142.215616) (xy 283.881967 -142.194687) (xy 283.852255 -142.148714)
			(xy 283.82942 -142.098965) (xy 283.81393 -142.046464) (xy 283.806103 -141.992287) (xy 283.80563 -141.964918)
			(xy 283.806116 -141.937667) (xy 283.813872 -141.883719) (xy 283.829227 -141.831424) (xy 283.851869 -141.781847)
			(xy 283.881335 -141.735997) (xy 283.917026 -141.694806) (xy 283.958217 -141.659115) (xy 284.004067 -141.629649)
			(xy 284.053644 -141.607007) (xy 284.105939 -141.591652) (xy 284.159887 -141.583896) (xy 284.214389 -141.583896)
			(xy 284.268337 -141.591652) (xy 284.320632 -141.607007) (xy 284.370209 -141.629649) (xy 284.416059 -141.659115)
			(xy 284.45725 -141.694806) (xy 284.492941 -141.735997) (xy 284.522407 -141.781847) (xy 284.545049 -141.831424)
			(xy 284.560404 -141.883719) (xy 284.56816 -141.937667) (xy 284.568646 -141.964918) (xy 284.568187 -141.992323)
			(xy 284.560336 -142.046568) (xy 284.544798 -142.09913) (xy 284.521893 -142.148925) (xy 284.492094 -142.194927)
			(xy 284.474412 -142.21587) (xy 284.474158 -142.216124) (xy 284.46855 -142.223196) (xy 284.462317 -142.240124)
			(xy 284.461966 -142.249144) (xy 284.461966 -142.316454) (xy 284.462352 -142.325468) (xy 284.46858 -142.342385)
			(xy 284.474158 -142.349474) (xy 284.474666 -142.349982) (xy 284.492305 -142.370914) (xy 284.522018 -142.416887)
			(xy 284.544854 -142.466634) (xy 284.560345 -142.519135) (xy 284.568173 -142.573311) (xy 284.568646 -142.60068)
			(xy 284.56816 -142.627931) (xy 284.560404 -142.681879) (xy 284.545049 -142.734174) (xy 284.522407 -142.783751)
			(xy 284.492941 -142.829601) (xy 284.45725 -142.870792) (xy 284.416059 -142.906483) (xy 284.370209 -142.935949)
			(xy 284.320632 -142.958591) (xy 284.268337 -142.973946) (xy 284.214389 -142.981702) (xy 284.159887 -142.981702)
			(xy 284.105939 -142.973946) (xy 284.053644 -142.958591) (xy 284.004067 -142.935949) (xy 283.958217 -142.906483)
			(xy 283.917026 -142.870792) (xy 283.881335 -142.829601) (xy 283.851869 -142.783751) (xy 283.829227 -142.734174)
			(xy 283.813872 -142.681879) (xy 283.806116 -142.627931) (xy 283.80563 -142.60068) (xy 279.53408 -142.60068)
			(xy 279.531572 -142.637764) (xy 279.535382 -142.65275) (xy 279.539446 -142.659608) (xy 279.552985 -142.682344)
			(xy 279.574349 -142.730756) (xy 279.588821 -142.781654) (xy 279.596126 -142.834064) (xy 279.596596 -142.860522)
			(xy 279.596151 -142.886884) (xy 279.588896 -142.939105) (xy 279.574525 -142.989832) (xy 279.553314 -143.0381)
			(xy 279.525664 -143.082991) (xy 279.50922 -143.1036) (xy 279.504648 -143.109188) (xy 279.498806 -143.12392)
			(xy 279.253584 -146.739864) (xy 281.109926 -146.739864) (xy 281.113997 -146.684242) (xy 281.126123 -146.629805)
			(xy 281.146046 -146.577714) (xy 281.173342 -146.529079) (xy 281.207428 -146.484936) (xy 281.247577 -146.446227)
			(xy 281.292935 -146.413776) (xy 281.342535 -146.388275) (xy 281.395319 -146.370268) (xy 281.450162 -146.360138)
			(xy 281.505896 -146.358101) (xy 281.561333 -146.364201) (xy 281.61529 -146.378307) (xy 281.666619 -146.400119)
			(xy 281.714225 -146.429173) (xy 281.757093 -146.464848) (xy 281.79431 -146.506385) (xy 281.825083 -146.552898)
			(xy 281.848755 -146.603395) (xy 281.864823 -146.656802) (xy 281.872943 -146.711978) (xy 281.873452 -146.739864)
			(xy 281.872943 -146.76775) (xy 281.868786 -146.795998) (xy 282.743654 -146.795998) (xy 282.747725 -146.740376)
			(xy 282.759851 -146.685939) (xy 282.779774 -146.633848) (xy 282.80707 -146.585213) (xy 282.841156 -146.54107)
			(xy 282.881305 -146.502361) (xy 282.926663 -146.46991) (xy 282.976263 -146.444409) (xy 283.029047 -146.426402)
			(xy 283.08389 -146.416272) (xy 283.139624 -146.414235) (xy 283.195061 -146.420335) (xy 283.249018 -146.434441)
			(xy 283.300347 -146.456253) (xy 283.347953 -146.485307) (xy 283.390821 -146.520982) (xy 283.428038 -146.562519)
			(xy 283.458811 -146.609032) (xy 283.482483 -146.659529) (xy 283.498551 -146.712936) (xy 283.506671 -146.768112)
			(xy 283.50718 -146.795998) (xy 283.506671 -146.823884) (xy 283.498551 -146.87906) (xy 283.482483 -146.932467)
			(xy 283.458811 -146.982964) (xy 283.428038 -147.029477) (xy 283.390821 -147.071014) (xy 283.347953 -147.106689)
			(xy 283.300347 -147.135743) (xy 283.249018 -147.157555) (xy 283.195061 -147.171661) (xy 283.139624 -147.177761)
			(xy 283.08389 -147.175724) (xy 283.029047 -147.165594) (xy 282.976263 -147.147587) (xy 282.926663 -147.122086)
			(xy 282.881305 -147.089635) (xy 282.841156 -147.050926) (xy 282.80707 -147.006783) (xy 282.779774 -146.958148)
			(xy 282.759851 -146.906057) (xy 282.747725 -146.85162) (xy 282.743654 -146.795998) (xy 281.868786 -146.795998)
			(xy 281.864823 -146.822926) (xy 281.848755 -146.876333) (xy 281.825083 -146.92683) (xy 281.79431 -146.973343)
			(xy 281.757093 -147.01488) (xy 281.714225 -147.050555) (xy 281.666619 -147.079609) (xy 281.61529 -147.101421)
			(xy 281.561333 -147.115527) (xy 281.505896 -147.121627) (xy 281.450162 -147.11959) (xy 281.395319 -147.10946)
			(xy 281.342535 -147.091453) (xy 281.292935 -147.065952) (xy 281.247577 -147.033501) (xy 281.207428 -146.994792)
			(xy 281.173342 -146.950649) (xy 281.146046 -146.902014) (xy 281.126123 -146.849923) (xy 281.113997 -146.795486)
			(xy 281.109926 -146.739864) (xy 279.253584 -146.739864) (xy 278.750376 -154.159966) (xy 283.506924 -154.159966)
			(xy 283.510995 -154.104344) (xy 283.523121 -154.049907) (xy 283.543044 -153.997816) (xy 283.57034 -153.949181)
			(xy 283.604426 -153.905038) (xy 283.644575 -153.866329) (xy 283.689933 -153.833878) (xy 283.739533 -153.808377)
			(xy 283.792317 -153.79037) (xy 283.84716 -153.78024) (xy 283.902894 -153.778203) (xy 283.958331 -153.784303)
			(xy 284.012288 -153.798409) (xy 284.063617 -153.820221) (xy 284.111223 -153.849275) (xy 284.154091 -153.88495)
			(xy 284.191308 -153.926487) (xy 284.222081 -153.973) (xy 284.245753 -154.023497) (xy 284.261821 -154.076904)
			(xy 284.269941 -154.13208) (xy 284.27045 -154.159966) (xy 284.269941 -154.187852) (xy 284.261821 -154.243028)
			(xy 284.245753 -154.296435) (xy 284.222081 -154.346932) (xy 284.191308 -154.393445) (xy 284.154091 -154.434982)
			(xy 284.111223 -154.470657) (xy 284.063617 -154.499711) (xy 284.012288 -154.521523) (xy 283.958331 -154.535629)
			(xy 283.902894 -154.541729) (xy 283.84716 -154.539692) (xy 283.792317 -154.529562) (xy 283.739533 -154.511555)
			(xy 283.689933 -154.486054) (xy 283.644575 -154.453603) (xy 283.604426 -154.414894) (xy 283.57034 -154.370751)
			(xy 283.543044 -154.322116) (xy 283.523121 -154.270025) (xy 283.510995 -154.215588) (xy 283.506924 -154.159966)
			(xy 278.750376 -154.159966) (xy 278.690586 -155.0416) (xy 280.363674 -155.0416) (xy 280.367745 -154.985978)
			(xy 280.379871 -154.931541) (xy 280.399794 -154.87945) (xy 280.42709 -154.830815) (xy 280.461176 -154.786672)
			(xy 280.501325 -154.747963) (xy 280.546683 -154.715512) (xy 280.596283 -154.690011) (xy 280.649067 -154.672004)
			(xy 280.70391 -154.661874) (xy 280.759644 -154.659837) (xy 280.815081 -154.665937) (xy 280.869038 -154.680043)
			(xy 280.920367 -154.701855) (xy 280.967973 -154.730909) (xy 281.010841 -154.766584) (xy 281.048058 -154.808121)
			(xy 281.078831 -154.854634) (xy 281.102503 -154.905131) (xy 281.118571 -154.958538) (xy 281.126691 -155.013714)
			(xy 281.1272 -155.0416) (xy 281.126691 -155.069486) (xy 281.118571 -155.124662) (xy 281.102503 -155.178069)
			(xy 281.078831 -155.228566) (xy 281.048058 -155.275079) (xy 281.010841 -155.316616) (xy 280.967973 -155.352291)
			(xy 280.920367 -155.381345) (xy 280.869038 -155.403157) (xy 280.815081 -155.417263) (xy 280.759644 -155.423363)
			(xy 280.70391 -155.421326) (xy 280.649067 -155.411196) (xy 280.596283 -155.393189) (xy 280.546683 -155.367688)
			(xy 280.501325 -155.335237) (xy 280.461176 -155.296528) (xy 280.42709 -155.252385) (xy 280.399794 -155.20375)
			(xy 280.379871 -155.151659) (xy 280.367745 -155.097222) (xy 280.363674 -155.0416) (xy 278.690586 -155.0416)
			(xy 278.652828 -155.598368) (xy 283.568138 -155.598368) (xy 283.572209 -155.542746) (xy 283.584335 -155.488309)
			(xy 283.604258 -155.436218) (xy 283.631554 -155.387583) (xy 283.66564 -155.34344) (xy 283.705789 -155.304731)
			(xy 283.751147 -155.27228) (xy 283.800747 -155.246779) (xy 283.853531 -155.228772) (xy 283.908374 -155.218642)
			(xy 283.964108 -155.216605) (xy 284.019545 -155.222705) (xy 284.073502 -155.236811) (xy 284.124831 -155.258623)
			(xy 284.172437 -155.287677) (xy 284.215305 -155.323352) (xy 284.252522 -155.364889) (xy 284.283295 -155.411402)
			(xy 284.306967 -155.461899) (xy 284.323035 -155.515306) (xy 284.331155 -155.570482) (xy 284.331664 -155.598368)
			(xy 284.331155 -155.626254) (xy 284.323035 -155.68143) (xy 284.306967 -155.734837) (xy 284.283295 -155.785334)
			(xy 284.252522 -155.831847) (xy 284.215305 -155.873384) (xy 284.172437 -155.909059) (xy 284.124831 -155.938113)
			(xy 284.073502 -155.959925) (xy 284.019545 -155.974031) (xy 283.964108 -155.980131) (xy 283.908374 -155.978094)
			(xy 283.853531 -155.967964) (xy 283.800747 -155.949957) (xy 283.751147 -155.924456) (xy 283.705789 -155.892005)
			(xy 283.66564 -155.853296) (xy 283.631554 -155.809153) (xy 283.604258 -155.760518) (xy 283.584335 -155.708427)
			(xy 283.572209 -155.65399) (xy 283.568138 -155.598368) (xy 278.652828 -155.598368) (xy 278.552782 -157.0736)
			(xy 283.496764 -157.0736) (xy 283.500835 -157.017978) (xy 283.512961 -156.963541) (xy 283.532884 -156.91145)
			(xy 283.56018 -156.862815) (xy 283.594266 -156.818672) (xy 283.634415 -156.779963) (xy 283.679773 -156.747512)
			(xy 283.729373 -156.722011) (xy 283.782157 -156.704004) (xy 283.837 -156.693874) (xy 283.892734 -156.691837)
			(xy 283.948171 -156.697937) (xy 284.002128 -156.712043) (xy 284.053457 -156.733855) (xy 284.101063 -156.762909)
			(xy 284.143931 -156.798584) (xy 284.181148 -156.840121) (xy 284.211921 -156.886634) (xy 284.235593 -156.937131)
			(xy 284.251661 -156.990538) (xy 284.259781 -157.045714) (xy 284.26029 -157.0736) (xy 284.259781 -157.101486)
			(xy 284.251661 -157.156662) (xy 284.235593 -157.210069) (xy 284.211921 -157.260566) (xy 284.181148 -157.307079)
			(xy 284.143931 -157.348616) (xy 284.101063 -157.384291) (xy 284.053457 -157.413345) (xy 284.002128 -157.435157)
			(xy 283.948171 -157.449263) (xy 283.892734 -157.455363) (xy 283.837 -157.453326) (xy 283.782157 -157.443196)
			(xy 283.729373 -157.425189) (xy 283.679773 -157.399688) (xy 283.634415 -157.367237) (xy 283.594266 -157.328528)
			(xy 283.56018 -157.284385) (xy 283.532884 -157.23575) (xy 283.512961 -157.183659) (xy 283.500835 -157.129222)
			(xy 283.496764 -157.0736) (xy 278.552782 -157.0736) (xy 278.418544 -159.053022) (xy 278.420293 -159.061895)
			(xy 278.429145 -159.07765) (xy 278.435816 -159.083756) (xy 278.4983 -159.136334) (xy 278.503016 -159.140094)
			(xy 278.513797 -159.145495) (xy 278.519636 -159.147002) (xy 278.537416 -159.147002) (xy 278.548846 -159.145732)
			(xy 278.59406 -159.135647) (xy 278.685755 -159.122407) (xy 278.778252 -159.117163) (xy 278.870855 -159.119954)
			(xy 278.962869 -159.130761) (xy 279.053599 -159.149501) (xy 279.142364 -159.176033) (xy 279.228496 -159.210159)
			(xy 279.311346 -159.25162) (xy 279.390291 -159.300105) (xy 279.464738 -159.355249) (xy 279.534125 -159.416638)
			(xy 279.597932 -159.483809) (xy 279.655677 -159.556257) (xy 279.706926 -159.633437) (xy 279.751294 -159.714767)
			(xy 279.788447 -159.799637) (xy 279.818104 -159.887408) (xy 279.840044 -159.977418) (xy 279.854101 -160.068991)
			(xy 279.860169 -160.161437) (xy 279.858202 -160.254062) (xy 279.853644 -160.300162) (xy 279.848134 -160.346338)
			(xy 279.83011 -160.437577) (xy 279.804215 -160.526902) (xy 279.770647 -160.613635) (xy 279.72966 -160.697119)
			(xy 279.681564 -160.776719) (xy 279.626724 -160.851833) (xy 279.565557 -160.92189) (xy 279.498526 -160.986359)
			(xy 279.42614 -161.044752) (xy 279.348947 -161.096625) (xy 279.267534 -161.141584) (xy 279.182518 -161.17929)
			(xy 279.094544 -161.209455) (xy 279.004278 -161.231851) (xy 278.912406 -161.246308) (xy 278.819625 -161.252717)
			(xy 278.726638 -161.251029) (xy 278.63415 -161.241256) (xy 278.542864 -161.223473) (xy 278.453471 -161.197814)
			(xy 278.409908 -161.181542) (xy 278.404281 -161.179597) (xy 278.392478 -161.178061) (xy 278.38654 -161.178494)
			(xy 278.374856 -161.179764) (xy 278.295354 -161.23031) (xy 278.2951 -161.230564) (xy 278.293576 -161.23158)
			(xy 278.285804 -161.237589) (xy 278.275107 -161.254046) (xy 278.272748 -161.263584) (xy 278.271986 -161.270188)
			(xy 278.27097 -161.286444) (xy 278.236172 -161.81832) (xy 278.23414 -161.844736) (xy 278.220932 -161.987738)
			(xy 278.220678 -161.994088) (xy 278.294344 -164.198046) (xy 282.909262 -164.198046) (xy 282.913333 -164.142424)
			(xy 282.925459 -164.087987) (xy 282.945382 -164.035896) (xy 282.972678 -163.987261) (xy 283.006764 -163.943118)
			(xy 283.046913 -163.904409) (xy 283.092271 -163.871958) (xy 283.141871 -163.846457) (xy 283.194655 -163.82845)
			(xy 283.249498 -163.81832) (xy 283.305232 -163.816283) (xy 283.360669 -163.822383) (xy 283.414626 -163.836489)
			(xy 283.465955 -163.858301) (xy 283.513561 -163.887355) (xy 283.556429 -163.92303) (xy 283.593646 -163.964567)
			(xy 283.624419 -164.01108) (xy 283.648091 -164.061577) (xy 283.664159 -164.114984) (xy 283.672279 -164.17016)
			(xy 283.672788 -164.198046) (xy 283.672279 -164.225932) (xy 283.664159 -164.281108) (xy 283.648091 -164.334515)
			(xy 283.624419 -164.385012) (xy 283.593646 -164.431525) (xy 283.556429 -164.473062) (xy 283.513561 -164.508737)
			(xy 283.465955 -164.537791) (xy 283.414626 -164.559603) (xy 283.360669 -164.573709) (xy 283.305232 -164.579809)
			(xy 283.249498 -164.577772) (xy 283.194655 -164.567642) (xy 283.141871 -164.549635) (xy 283.092271 -164.524134)
			(xy 283.046913 -164.491683) (xy 283.006764 -164.452974) (xy 282.972678 -164.408831) (xy 282.945382 -164.360196)
			(xy 282.925459 -164.308105) (xy 282.913333 -164.253668) (xy 282.909262 -164.198046) (xy 278.294344 -164.198046)
			(xy 278.325502 -165.130226) (xy 282.866336 -165.130226) (xy 282.870407 -165.074604) (xy 282.882533 -165.020167)
			(xy 282.902456 -164.968076) (xy 282.929752 -164.919441) (xy 282.963838 -164.875298) (xy 283.003987 -164.836589)
			(xy 283.049345 -164.804138) (xy 283.098945 -164.778637) (xy 283.151729 -164.76063) (xy 283.206572 -164.7505)
			(xy 283.262306 -164.748463) (xy 283.317743 -164.754563) (xy 283.3717 -164.768669) (xy 283.423029 -164.790481)
			(xy 283.470635 -164.819535) (xy 283.513503 -164.85521) (xy 283.55072 -164.896747) (xy 283.581493 -164.94326)
			(xy 283.605165 -164.993757) (xy 283.621233 -165.047164) (xy 283.629353 -165.10234) (xy 283.629862 -165.130226)
			(xy 283.629353 -165.158112) (xy 283.621233 -165.213288) (xy 283.605165 -165.266695) (xy 283.581493 -165.317192)
			(xy 283.55072 -165.363705) (xy 283.513503 -165.405242) (xy 283.470635 -165.440917) (xy 283.423029 -165.469971)
			(xy 283.3717 -165.491783) (xy 283.317743 -165.505889) (xy 283.262306 -165.511989) (xy 283.206572 -165.509952)
			(xy 283.151729 -165.499822) (xy 283.098945 -165.481815) (xy 283.049345 -165.456314) (xy 283.003987 -165.423863)
			(xy 282.963838 -165.385154) (xy 282.929752 -165.341011) (xy 282.902456 -165.292376) (xy 282.882533 -165.240285)
			(xy 282.870407 -165.185848) (xy 282.866336 -165.130226) (xy 278.325502 -165.130226) (xy 278.434698 -168.397174)
			(xy 282.841698 -168.397174) (xy 282.845769 -168.341552) (xy 282.857895 -168.287115) (xy 282.877818 -168.235024)
			(xy 282.905114 -168.186389) (xy 282.9392 -168.142246) (xy 282.979349 -168.103537) (xy 283.024707 -168.071086)
			(xy 283.074307 -168.045585) (xy 283.127091 -168.027578) (xy 283.181934 -168.017448) (xy 283.237668 -168.015411)
			(xy 283.293105 -168.021511) (xy 283.347062 -168.035617) (xy 283.398391 -168.057429) (xy 283.445997 -168.086483)
			(xy 283.488865 -168.122158) (xy 283.526082 -168.163695) (xy 283.556855 -168.210208) (xy 283.580527 -168.260705)
			(xy 283.596595 -168.314112) (xy 283.604715 -168.369288) (xy 283.605224 -168.397174) (xy 283.604715 -168.42506)
			(xy 283.596595 -168.480236) (xy 283.580527 -168.533643) (xy 283.556855 -168.58414) (xy 283.526082 -168.630653)
			(xy 283.488865 -168.67219) (xy 283.445997 -168.707865) (xy 283.398391 -168.736919) (xy 283.347062 -168.758731)
			(xy 283.293105 -168.772837) (xy 283.237668 -168.778937) (xy 283.181934 -168.7769) (xy 283.127091 -168.76677)
			(xy 283.074307 -168.748763) (xy 283.024707 -168.723262) (xy 282.979349 -168.690811) (xy 282.9392 -168.652102)
			(xy 282.905114 -168.607959) (xy 282.877818 -168.559324) (xy 282.857895 -168.507233) (xy 282.845769 -168.452796)
			(xy 282.841698 -168.397174) (xy 278.434698 -168.397174) (xy 278.478607 -169.710862) (xy 281.061412 -169.710862)
			(xy 281.065483 -169.65524) (xy 281.077609 -169.600803) (xy 281.097532 -169.548712) (xy 281.124828 -169.500077)
			(xy 281.158914 -169.455934) (xy 281.199063 -169.417225) (xy 281.244421 -169.384774) (xy 281.294021 -169.359273)
			(xy 281.346805 -169.341266) (xy 281.401648 -169.331136) (xy 281.457382 -169.329099) (xy 281.512819 -169.335199)
			(xy 281.566776 -169.349305) (xy 281.618105 -169.371117) (xy 281.665711 -169.400171) (xy 281.708579 -169.435846)
			(xy 281.745796 -169.477383) (xy 281.776569 -169.523896) (xy 281.800241 -169.574393) (xy 281.816309 -169.6278)
			(xy 281.824429 -169.682976) (xy 281.824938 -169.710862) (xy 281.824429 -169.738748) (xy 281.816309 -169.793924)
			(xy 281.800241 -169.847331) (xy 281.776569 -169.897828) (xy 281.745796 -169.944341) (xy 281.708579 -169.985878)
			(xy 281.665711 -170.021553) (xy 281.618105 -170.050607) (xy 281.566776 -170.072419) (xy 281.512819 -170.086525)
			(xy 281.457382 -170.092625) (xy 281.401648 -170.090588) (xy 281.346805 -170.080458) (xy 281.294021 -170.062451)
			(xy 281.244421 -170.03695) (xy 281.199063 -170.004499) (xy 281.158914 -169.96579) (xy 281.124828 -169.921647)
			(xy 281.097532 -169.873012) (xy 281.077609 -169.820921) (xy 281.065483 -169.766484) (xy 281.061412 -169.710862)
			(xy 278.478607 -169.710862) (xy 278.638368 -174.490634) (xy 282.011372 -174.490634) (xy 282.015443 -174.435012)
			(xy 282.027569 -174.380575) (xy 282.047492 -174.328484) (xy 282.074788 -174.279849) (xy 282.108874 -174.235706)
			(xy 282.149023 -174.196997) (xy 282.194381 -174.164546) (xy 282.243981 -174.139045) (xy 282.296765 -174.121038)
			(xy 282.351608 -174.110908) (xy 282.407342 -174.108871) (xy 282.462779 -174.114971) (xy 282.516736 -174.129077)
			(xy 282.568065 -174.150889) (xy 282.615671 -174.179943) (xy 282.658539 -174.215618) (xy 282.695756 -174.257155)
			(xy 282.726529 -174.303668) (xy 282.750201 -174.354165) (xy 282.766269 -174.407572) (xy 282.774389 -174.462748)
			(xy 282.774898 -174.490634) (xy 282.774389 -174.51852) (xy 282.766269 -174.573696) (xy 282.750201 -174.627103)
			(xy 282.726529 -174.6776) (xy 282.695756 -174.724113) (xy 282.658539 -174.76565) (xy 282.615671 -174.801325)
			(xy 282.568065 -174.830379) (xy 282.516736 -174.852191) (xy 282.462779 -174.866297) (xy 282.407342 -174.872397)
			(xy 282.351608 -174.87036) (xy 282.296765 -174.86023) (xy 282.243981 -174.842223) (xy 282.194381 -174.816722)
			(xy 282.149023 -174.784271) (xy 282.108874 -174.745562) (xy 282.074788 -174.701419) (xy 282.047492 -174.652784)
			(xy 282.027569 -174.600693) (xy 282.015443 -174.546256) (xy 282.011372 -174.490634) (xy 278.638368 -174.490634)
			(xy 278.679798 -175.730154) (xy 283.157166 -175.730154) (xy 283.161237 -175.674532) (xy 283.173363 -175.620095)
			(xy 283.193286 -175.568004) (xy 283.220582 -175.519369) (xy 283.254668 -175.475226) (xy 283.294817 -175.436517)
			(xy 283.340175 -175.404066) (xy 283.389775 -175.378565) (xy 283.442559 -175.360558) (xy 283.497402 -175.350428)
			(xy 283.553136 -175.348391) (xy 283.608573 -175.354491) (xy 283.66253 -175.368597) (xy 283.713859 -175.390409)
			(xy 283.761465 -175.419463) (xy 283.804333 -175.455138) (xy 283.84155 -175.496675) (xy 283.872323 -175.543188)
			(xy 283.895995 -175.593685) (xy 283.912063 -175.647092) (xy 283.920183 -175.702268) (xy 283.920692 -175.730154)
			(xy 283.920183 -175.75804) (xy 283.912063 -175.813216) (xy 283.895995 -175.866623) (xy 283.872323 -175.91712)
			(xy 283.84155 -175.963633) (xy 283.804333 -176.00517) (xy 283.761465 -176.040845) (xy 283.713859 -176.069899)
			(xy 283.66253 -176.091711) (xy 283.608573 -176.105817) (xy 283.553136 -176.111917) (xy 283.497402 -176.10988)
			(xy 283.442559 -176.09975) (xy 283.389775 -176.081743) (xy 283.340175 -176.056242) (xy 283.294817 -176.023791)
			(xy 283.254668 -175.985082) (xy 283.220582 -175.940939) (xy 283.193286 -175.892304) (xy 283.173363 -175.840213)
			(xy 283.161237 -175.785776) (xy 283.157166 -175.730154) (xy 278.679798 -175.730154) (xy 280.264616 -223.145096)
			(xy 280.265284 -223.154289) (xy 280.272314 -223.171313) (xy 280.284917 -223.184742) (xy 280.301461 -223.192837)
			(xy 280.31059 -223.194118) (xy 280.52268 -223.214438)
		)
		(stroke
			(width 0)
			(type solid)
		)
		(fill yes)
		(layer "In11.Cu")
		(net "GND")
	)
	(gr_poly
		(pts
			(xy 390.510014 -299.856906) (xy 390.52002 -299.856415) (xy 390.538508 -299.848754) (xy 390.552658 -299.834601)
			(xy 390.560317 -299.816112) (xy 390.560814 -299.806106) (xy 390.560814 -299.798486) (xy 390.558528 -299.790866)
			(xy 390.552032 -299.768695) (xy 390.54501 -299.723033) (xy 390.544558 -299.699934) (xy 390.545026 -299.67594)
			(xy 390.552528 -299.628542) (xy 390.567352 -299.582902) (xy 390.589133 -299.540142) (xy 390.617335 -299.501316)
			(xy 390.651264 -299.467379) (xy 390.690084 -299.439168) (xy 390.732839 -299.417378) (xy 390.778476 -299.402544)
			(xy 390.825872 -299.395031) (xy 390.849866 -299.394626) (xy 390.864049 -299.394811) (xy 390.892288 -299.397482)
			(xy 390.906254 -299.39996) (xy 390.9187 -299.402246) (xy 390.942576 -299.39488) (xy 391.019792 -299.317664)
			(xy 391.027158 -299.293534) (xy 391.024872 -299.281342) (xy 391.022375 -299.267315) (xy 391.019706 -299.238947)
			(xy 391.019538 -299.2247) (xy 391.020024 -299.199884) (xy 391.028053 -299.150905) (xy 391.0439 -299.10387)
			(xy 391.067148 -299.060019) (xy 391.097184 -299.020506) (xy 391.133216 -298.986373) (xy 391.174295 -298.958518)
			(xy 391.21934 -298.937676) (xy 391.267163 -298.924396) (xy 391.316504 -298.919028) (xy 391.366064 -298.921712)
			(xy 391.414537 -298.932379) (xy 391.460646 -298.950747) (xy 391.503176 -298.976332) (xy 391.541006 -299.008461)
			(xy 391.573141 -299.046287) (xy 391.598733 -299.088813) (xy 391.617108 -299.134919) (xy 391.627782 -299.18339)
			(xy 391.63004 -299.224954) (xy 391.969002 -299.224954) (xy 391.972962 -299.1759) (xy 391.984739 -299.128116)
			(xy 392.00403 -299.08284) (xy 392.030333 -299.041244) (xy 392.062968 -299.004407) (xy 392.101089 -298.973282)
			(xy 392.14371 -298.948675) (xy 392.189726 -298.931223) (xy 392.237945 -298.921379) (xy 392.28712 -298.919398)
			(xy 392.335975 -298.92533) (xy 392.383246 -298.939022) (xy 392.427708 -298.96012) (xy 392.468211 -298.988076)
			(xy 392.503704 -299.022168) (xy 392.533269 -299.061512) (xy 392.55614 -299.105089) (xy 392.571724 -299.15177)
			(xy 392.579619 -299.200347) (xy 392.580114 -299.224954) (xy 392.919216 -299.224954) (xy 392.923176 -299.1759)
			(xy 392.934953 -299.128116) (xy 392.954244 -299.08284) (xy 392.980547 -299.041244) (xy 393.013182 -299.004407)
			(xy 393.051303 -298.973282) (xy 393.093924 -298.948675) (xy 393.13994 -298.931223) (xy 393.188159 -298.921379)
			(xy 393.237334 -298.919398) (xy 393.286189 -298.92533) (xy 393.33346 -298.939022) (xy 393.377922 -298.96012)
			(xy 393.418425 -298.988076) (xy 393.453918 -299.022168) (xy 393.483483 -299.061512) (xy 393.506354 -299.105089)
			(xy 393.521938 -299.15177) (xy 393.529833 -299.200347) (xy 393.530328 -299.224954) (xy 393.869176 -299.224954)
			(xy 393.873136 -299.1759) (xy 393.884913 -299.128116) (xy 393.904204 -299.08284) (xy 393.930507 -299.041244)
			(xy 393.963142 -299.004407) (xy 394.001263 -298.973282) (xy 394.043884 -298.948675) (xy 394.0899 -298.931223)
			(xy 394.138119 -298.921379) (xy 394.187294 -298.919398) (xy 394.236149 -298.92533) (xy 394.28342 -298.939022)
			(xy 394.327882 -298.96012) (xy 394.368385 -298.988076) (xy 394.403878 -299.022168) (xy 394.433443 -299.061512)
			(xy 394.456314 -299.105089) (xy 394.471898 -299.15177) (xy 394.479793 -299.200347) (xy 394.480288 -299.224954)
			(xy 394.819136 -299.224954) (xy 394.823096 -299.1759) (xy 394.834873 -299.128116) (xy 394.854164 -299.08284)
			(xy 394.880467 -299.041244) (xy 394.913102 -299.004407) (xy 394.951223 -298.973282) (xy 394.993844 -298.948675)
			(xy 395.03986 -298.931223) (xy 395.088079 -298.921379) (xy 395.137254 -298.919398) (xy 395.186109 -298.92533)
			(xy 395.23338 -298.939022) (xy 395.277842 -298.96012) (xy 395.318345 -298.988076) (xy 395.353838 -299.022168)
			(xy 395.383403 -299.061512) (xy 395.406274 -299.105089) (xy 395.421858 -299.15177) (xy 395.429753 -299.200347)
			(xy 395.430248 -299.224954) (xy 395.429753 -299.249561) (xy 395.421858 -299.298138) (xy 395.406274 -299.344819)
			(xy 395.383403 -299.388396) (xy 395.353838 -299.42774) (xy 395.318345 -299.461832) (xy 395.277842 -299.489788)
			(xy 395.23338 -299.510886) (xy 395.186109 -299.524578) (xy 395.137254 -299.53051) (xy 395.088079 -299.528529)
			(xy 395.03986 -299.518685) (xy 394.993844 -299.501233) (xy 394.951223 -299.476626) (xy 394.913102 -299.445501)
			(xy 394.880467 -299.408664) (xy 394.854164 -299.367068) (xy 394.834873 -299.321792) (xy 394.823096 -299.274008)
			(xy 394.819136 -299.224954) (xy 394.480288 -299.224954) (xy 394.479793 -299.249561) (xy 394.471898 -299.298138)
			(xy 394.456314 -299.344819) (xy 394.433443 -299.388396) (xy 394.403878 -299.42774) (xy 394.368385 -299.461832)
			(xy 394.327882 -299.489788) (xy 394.28342 -299.510886) (xy 394.236149 -299.524578) (xy 394.187294 -299.53051)
			(xy 394.138119 -299.528529) (xy 394.0899 -299.518685) (xy 394.043884 -299.501233) (xy 394.001263 -299.476626)
			(xy 393.963142 -299.445501) (xy 393.930507 -299.408664) (xy 393.904204 -299.367068) (xy 393.884913 -299.321792)
			(xy 393.873136 -299.274008) (xy 393.869176 -299.224954) (xy 393.530328 -299.224954) (xy 393.529833 -299.249561)
			(xy 393.521938 -299.298138) (xy 393.506354 -299.344819) (xy 393.483483 -299.388396) (xy 393.453918 -299.42774)
			(xy 393.418425 -299.461832) (xy 393.377922 -299.489788) (xy 393.33346 -299.510886) (xy 393.286189 -299.524578)
			(xy 393.237334 -299.53051) (xy 393.188159 -299.528529) (xy 393.13994 -299.518685) (xy 393.093924 -299.501233)
			(xy 393.051303 -299.476626) (xy 393.013182 -299.445501) (xy 392.980547 -299.408664) (xy 392.954244 -299.367068)
			(xy 392.934953 -299.321792) (xy 392.923176 -299.274008) (xy 392.919216 -299.224954) (xy 392.580114 -299.224954)
			(xy 392.579619 -299.249561) (xy 392.571724 -299.298138) (xy 392.55614 -299.344819) (xy 392.533269 -299.388396)
			(xy 392.503704 -299.42774) (xy 392.468211 -299.461832) (xy 392.427708 -299.489788) (xy 392.383246 -299.510886)
			(xy 392.335975 -299.524578) (xy 392.28712 -299.53051) (xy 392.237945 -299.528529) (xy 392.189726 -299.518685)
			(xy 392.14371 -299.501233) (xy 392.101089 -299.476626) (xy 392.062968 -299.445501) (xy 392.030333 -299.408664)
			(xy 392.00403 -299.367068) (xy 391.984739 -299.321792) (xy 391.972962 -299.274008) (xy 391.969002 -299.224954)
			(xy 391.63004 -299.224954) (xy 391.630474 -299.23295) (xy 391.625113 -299.282292) (xy 391.61184 -299.330117)
			(xy 391.591005 -299.375165) (xy 391.563156 -299.416248) (xy 391.529028 -299.452286) (xy 391.48952 -299.482327)
			(xy 391.445672 -299.505581) (xy 391.39864 -299.521436) (xy 391.349662 -299.529473) (xy 391.324846 -299.530008)
			(xy 391.310663 -299.529824) (xy 391.282423 -299.527154) (xy 391.268458 -299.524674) (xy 391.256012 -299.522388)
			(xy 391.232136 -299.529754) (xy 391.15492 -299.60697) (xy 391.147554 -299.6311) (xy 391.14984 -299.643292)
			(xy 391.15234 -299.657319) (xy 391.155015 -299.685687) (xy 391.155174 -299.699934) (xy 391.154733 -299.723034)
			(xy 391.147719 -299.768699) (xy 391.141204 -299.790866) (xy 391.138918 -299.798486) (xy 391.138918 -299.806106)
			(xy 391.139339 -299.816125) (xy 391.14701 -299.834637) (xy 391.161183 -299.848803) (xy 391.179699 -299.856466)
			(xy 391.189718 -299.856906) (xy 391.233152 -299.856906) (xy 391.239502 -299.855128) (xy 391.26027 -299.85)
			(xy 391.302695 -299.844523) (xy 391.324084 -299.844206) (xy 391.325608 -299.844206) (xy 391.346996 -299.844528)
			(xy 391.38942 -299.85001) (xy 391.41019 -299.855128) (xy 391.41654 -299.856906) (xy 392.183112 -299.856906)
			(xy 392.189462 -299.855128) (xy 392.210229 -299.849997) (xy 392.252655 -299.844516) (xy 392.274044 -299.844206)
			(xy 392.275568 -299.844206) (xy 392.296957 -299.844526) (xy 392.339382 -299.850002) (xy 392.36015 -299.855128)
			(xy 392.3665 -299.856906) (xy 393.133326 -299.856906) (xy 393.139676 -299.855128) (xy 393.160443 -299.849998)
			(xy 393.202869 -299.844518) (xy 393.224258 -299.844206) (xy 393.225782 -299.844206) (xy 393.247171 -299.844527)
			(xy 393.289595 -299.850005) (xy 393.310364 -299.855128) (xy 393.316714 -299.856906) (xy 394.083286 -299.856906)
			(xy 394.089636 -299.855128) (xy 394.110404 -299.850002) (xy 394.152829 -299.84453) (xy 394.174218 -299.844206)
			(xy 394.175742 -299.844206) (xy 394.197131 -299.844524) (xy 394.239557 -299.849997) (xy 394.260324 -299.855128)
			(xy 394.266674 -299.856906) (xy 395.033246 -299.856906) (xy 395.039596 -299.855128) (xy 395.060364 -299.85)
			(xy 395.102789 -299.844522) (xy 395.124178 -299.844206) (xy 395.125702 -299.844206) (xy 395.147091 -299.844528)
			(xy 395.189515 -299.850009) (xy 395.210284 -299.855128) (xy 395.216634 -299.856906) (xy 395.910308 -299.856906)
			(xy 395.920378 -299.856482) (xy 395.938981 -299.848766) (xy 395.946376 -299.84192) (xy 396.059914 -299.728382)
			(xy 396.060422 -299.727874) (xy 396.067012 -299.720496) (xy 396.074477 -299.702196) (xy 396.0749 -299.692314)
			(xy 396.0749 -299.583602) (xy 396.050008 -299.555154) (xy 396.030958 -299.552614) (xy 396.004831 -299.548615)
			(xy 395.954218 -299.533394) (xy 395.906675 -299.510307) (xy 395.863414 -299.479943) (xy 395.825542 -299.443078)
			(xy 395.794023 -299.400653) (xy 395.769662 -299.353749) (xy 395.753081 -299.303565) (xy 395.744703 -299.251381)
			(xy 395.744192 -299.224954) (xy 395.744705 -299.198969) (xy 395.752841 -299.14764) (xy 395.768906 -299.098216)
			(xy 395.792505 -299.051913) (xy 395.823055 -299.009871) (xy 395.859806 -298.973125) (xy 395.901852 -298.942581)
			(xy 395.948158 -298.918989) (xy 395.997585 -298.902931) (xy 396.048915 -298.894801) (xy 396.0749 -298.894246)
			(xy 396.075408 -298.894246) (xy 396.098183 -298.894625) (xy 396.143304 -298.900865) (xy 396.165324 -298.906692)
			(xy 396.177008 -298.909994) (xy 396.200122 -298.905676) (xy 396.274544 -298.849288) (xy 396.283534 -298.841696)
			(xy 396.294004 -298.820652) (xy 396.29461 -298.808902) (xy 396.29461 -297.740832) (xy 396.294012 -297.729077)
			(xy 396.283551 -297.708023) (xy 396.274544 -297.700446) (xy 396.21206 -297.653202) (xy 396.20532 -297.648533)
			(xy 396.189774 -297.643352) (xy 396.18158 -297.643042) (xy 396.172182 -297.643042) (xy 396.16126 -297.644566)
			(xy 396.155926 -297.645582) (xy 396.136183 -297.650207) (xy 396.095937 -297.655179) (xy 396.075662 -297.655488)
			(xy 396.0749 -297.655488) (xy 396.048911 -297.655005) (xy 395.997574 -297.646873) (xy 395.948141 -297.630811)
			(xy 395.901829 -297.607213) (xy 395.859779 -297.57666) (xy 395.823027 -297.539906) (xy 395.792477 -297.497854)
			(xy 395.768881 -297.451541) (xy 395.752822 -297.402107) (xy 395.744694 -297.350769) (xy 395.744192 -297.32478)
			(xy 395.744741 -297.298269) (xy 395.753247 -297.245932) (xy 395.76999 -297.195622) (xy 395.781784 -297.171872)
			(xy 395.78788 -297.159934) (xy 395.787118 -297.133518) (xy 395.735556 -297.047666) (xy 395.730741 -297.040391)
			(xy 395.717246 -297.029351) (xy 395.700838 -297.023454) (xy 395.692122 -297.023028) (xy 395.507972 -297.023028)
			(xy 395.501817 -297.023193) (xy 395.489866 -297.026137) (xy 395.48435 -297.02887) (xy 395.477809 -297.032615)
			(xy 395.467091 -297.043202) (xy 395.463268 -297.049698) (xy 395.41958 -297.121834) (xy 395.415344 -297.129651)
			(xy 395.411941 -297.147089) (xy 395.414657 -297.164646) (xy 395.418564 -297.172634) (xy 395.41958 -297.174412)
			(xy 395.423136 -297.181778) (xy 395.433384 -297.20421) (xy 395.44786 -297.251352) (xy 395.455173 -297.300122)
			(xy 395.455648 -297.32478) (xy 395.455138 -297.350767) (xy 395.447008 -297.402102) (xy 395.430947 -297.451532)
			(xy 395.407351 -297.497842) (xy 395.376801 -297.53989) (xy 395.34005 -297.576641) (xy 395.298002 -297.607191)
			(xy 395.251692 -297.630787) (xy 395.202262 -297.646848) (xy 395.150927 -297.654978) (xy 395.098953 -297.654978)
			(xy 395.047618 -297.646848) (xy 394.998188 -297.630787) (xy 394.951878 -297.607191) (xy 394.90983 -297.576641)
			(xy 394.873079 -297.53989) (xy 394.842529 -297.497842) (xy 394.818933 -297.451532) (xy 394.802872 -297.402102)
			(xy 394.794742 -297.350767) (xy 394.794232 -297.32478) (xy 394.794782 -297.298269) (xy 394.803289 -297.245933)
			(xy 394.820033 -297.195623) (xy 394.831824 -297.171872) (xy 394.83792 -297.159934) (xy 394.837158 -297.133518)
			(xy 394.785596 -297.047666) (xy 394.780783 -297.040386) (xy 394.76729 -297.029335) (xy 394.75088 -297.023426)
			(xy 394.742162 -297.023028) (xy 394.558012 -297.023028) (xy 394.551859 -297.0232) (xy 394.539915 -297.026157)
			(xy 394.53439 -297.02887) (xy 394.527845 -297.032612) (xy 394.51712 -297.043195) (xy 394.513308 -297.049698)
			(xy 394.46962 -297.121834) (xy 394.465381 -297.12965) (xy 394.461975 -297.147089) (xy 394.464694 -297.164647)
			(xy 394.468604 -297.172634) (xy 394.46962 -297.174412) (xy 394.473176 -297.181778) (xy 394.483426 -297.204209)
			(xy 394.497904 -297.251352) (xy 394.505219 -297.300122) (xy 394.505688 -297.32478) (xy 394.505178 -297.350767)
			(xy 394.497048 -297.402102) (xy 394.480987 -297.451532) (xy 394.457391 -297.497842) (xy 394.426841 -297.53989)
			(xy 394.39009 -297.576641) (xy 394.348042 -297.607191) (xy 394.301732 -297.630787) (xy 394.252302 -297.646848)
			(xy 394.200967 -297.654978) (xy 394.148993 -297.654978) (xy 394.097658 -297.646848) (xy 394.048228 -297.630787)
			(xy 394.001918 -297.607191) (xy 393.95987 -297.576641) (xy 393.923119 -297.53989) (xy 393.892569 -297.497842)
			(xy 393.868973 -297.451532) (xy 393.852912 -297.402102) (xy 393.844782 -297.350767) (xy 393.844272 -297.32478)
			(xy 393.844821 -297.298269) (xy 393.853326 -297.245932) (xy 393.870068 -297.195621) (xy 393.881864 -297.171872)
			(xy 393.88796 -297.159934) (xy 393.887198 -297.133518) (xy 393.835636 -297.047666) (xy 393.830824 -297.040382)
			(xy 393.817333 -297.029321) (xy 393.800923 -297.023399) (xy 393.792202 -297.023028) (xy 393.608052 -297.023028)
			(xy 393.601898 -297.023195) (xy 393.589949 -297.026144) (xy 393.58443 -297.02887) (xy 393.577891 -297.032617)
			(xy 393.567177 -297.043206) (xy 393.563348 -297.049698) (xy 393.51966 -297.121834) (xy 393.515418 -297.12965)
			(xy 393.51201 -297.147089) (xy 393.514731 -297.164648) (xy 393.518644 -297.172634) (xy 393.51966 -297.174412)
			(xy 393.523216 -297.181778) (xy 393.533464 -297.20421) (xy 393.547941 -297.251352) (xy 393.555255 -297.300122)
			(xy 393.555728 -297.32478) (xy 393.555218 -297.350767) (xy 393.547088 -297.402102) (xy 393.531027 -297.451532)
			(xy 393.507431 -297.497842) (xy 393.476881 -297.53989) (xy 393.44013 -297.576641) (xy 393.398082 -297.607191)
			(xy 393.351772 -297.630787) (xy 393.302342 -297.646848) (xy 393.251007 -297.654978) (xy 393.199033 -297.654978)
			(xy 393.147698 -297.646848) (xy 393.098268 -297.630787) (xy 393.051958 -297.607191) (xy 393.00991 -297.576641)
			(xy 392.973159 -297.53989) (xy 392.942609 -297.497842) (xy 392.919013 -297.451532) (xy 392.902952 -297.402102)
			(xy 392.894822 -297.350767) (xy 392.894312 -297.32478) (xy 392.894862 -297.298269) (xy 392.903368 -297.245933)
			(xy 392.920112 -297.195623) (xy 392.931904 -297.171872) (xy 392.938 -297.159934) (xy 392.937238 -297.133518)
			(xy 392.885676 -297.047666) (xy 392.880862 -297.040388) (xy 392.867368 -297.029343) (xy 392.850959 -297.02344)
			(xy 392.842242 -297.023028) (xy 392.657838 -297.023028) (xy 392.651685 -297.023197) (xy 392.639737 -297.026149)
			(xy 392.634216 -297.02887) (xy 392.627669 -297.032609) (xy 392.616939 -297.04319) (xy 392.613134 -297.049698)
			(xy 392.569446 -297.121834) (xy 392.565205 -297.12965) (xy 392.561797 -297.147089) (xy 392.564517 -297.164648)
			(xy 392.56843 -297.172634) (xy 392.569446 -297.174412) (xy 392.573002 -297.181778) (xy 392.583251 -297.20421)
			(xy 392.597729 -297.251352) (xy 392.605043 -297.300122) (xy 392.605514 -297.32478) (xy 392.605004 -297.350767)
			(xy 392.596874 -297.402102) (xy 392.580813 -297.451532) (xy 392.557217 -297.497842) (xy 392.526667 -297.53989)
			(xy 392.489916 -297.576641) (xy 392.447868 -297.607191) (xy 392.401558 -297.630787) (xy 392.352128 -297.646848)
			(xy 392.300793 -297.654978) (xy 392.248819 -297.654978) (xy 392.197484 -297.646848) (xy 392.148054 -297.630787)
			(xy 392.101744 -297.607191) (xy 392.059696 -297.576641) (xy 392.022945 -297.53989) (xy 391.992395 -297.497842)
			(xy 391.968799 -297.451532) (xy 391.952738 -297.402102) (xy 391.944608 -297.350767) (xy 391.944098 -297.32478)
			(xy 391.944647 -297.298269) (xy 391.953153 -297.245932) (xy 391.969896 -297.195622) (xy 391.98169 -297.171872)
			(xy 391.987786 -297.159934) (xy 391.987024 -297.133518) (xy 391.935462 -297.047666) (xy 391.930647 -297.04039)
			(xy 391.917152 -297.029348) (xy 391.900744 -297.02345) (xy 391.892028 -297.023028) (xy 391.679176 -297.023028)
			(xy 391.67033 -297.023422) (xy 391.653696 -297.029455) (xy 391.640088 -297.040765) (xy 391.635234 -297.048174)
			(xy 391.591038 -297.12412) (xy 391.586849 -297.131974) (xy 391.583684 -297.149479) (xy 391.586698 -297.167011)
			(xy 391.590784 -297.17492) (xy 391.603212 -297.1981) (xy 391.620808 -297.247661) (xy 391.629677 -297.299499)
			(xy 391.630154 -297.325796) (xy 391.630154 -297.330622) (xy 391.629181 -297.355561) (xy 391.620125 -297.404638)
			(xy 391.60321 -297.45159) (xy 391.578884 -297.495167) (xy 391.547797 -297.534208) (xy 391.510775 -297.567674)
			(xy 391.468804 -297.594675) (xy 391.423001 -297.614491) (xy 391.374586 -297.626596) (xy 391.324846 -297.630667)
			(xy 391.275106 -297.626596) (xy 391.226691 -297.614491) (xy 391.180888 -297.594675) (xy 391.138917 -297.567674)
			(xy 391.101895 -297.534208) (xy 391.070808 -297.495167) (xy 391.046482 -297.45159) (xy 391.029567 -297.404638)
			(xy 391.020511 -297.355561) (xy 391.019538 -297.330622) (xy 391.019538 -297.325796) (xy 391.019997 -297.299497)
			(xy 391.028845 -297.247651) (xy 391.046468 -297.198096) (xy 391.058908 -297.17492) (xy 391.062974 -297.167005)
			(xy 391.065975 -297.149479) (xy 391.062823 -297.13198) (xy 391.058654 -297.12412) (xy 391.014458 -297.048174)
			(xy 391.009708 -297.040673) (xy 390.996082 -297.02931) (xy 390.979389 -297.023298) (xy 390.970516 -297.023028)
			(xy 390.757918 -297.023028) (xy 390.751765 -297.023199) (xy 390.73982 -297.026155) (xy 390.734296 -297.02887)
			(xy 390.727751 -297.032611) (xy 390.717024 -297.043194) (xy 390.713214 -297.049698) (xy 390.669526 -297.121834)
			(xy 390.665286 -297.12965) (xy 390.66188 -297.147089) (xy 390.664599 -297.164647) (xy 390.66851 -297.172634)
			(xy 390.669526 -297.174412) (xy 390.673082 -297.181778) (xy 390.683331 -297.204209) (xy 390.69781 -297.251352)
			(xy 390.705124 -297.300122) (xy 390.705594 -297.32478) (xy 390.705084 -297.350767) (xy 390.696954 -297.402102)
			(xy 390.680893 -297.451532) (xy 390.657297 -297.497842) (xy 390.626747 -297.53989) (xy 390.589996 -297.576641)
			(xy 390.547948 -297.607191) (xy 390.501638 -297.630787) (xy 390.452208 -297.646848) (xy 390.400873 -297.654978)
			(xy 390.348899 -297.654978) (xy 390.297564 -297.646848) (xy 390.248134 -297.630787) (xy 390.201824 -297.607191)
			(xy 390.159776 -297.576641) (xy 390.123025 -297.53989) (xy 390.092475 -297.497842) (xy 390.068879 -297.451532)
			(xy 390.052818 -297.402102) (xy 390.044688 -297.350767) (xy 390.044178 -297.32478) (xy 390.04468 -297.29858)
			(xy 390.052948 -297.246837) (xy 390.069274 -297.197046) (xy 390.09325 -297.150453) (xy 390.124275 -297.108226)
			(xy 390.161573 -297.071421) (xy 390.182608 -297.055794) (xy 390.191752 -297.04919) (xy 390.202674 -297.029886)
			(xy 390.21004 -296.94124) (xy 390.21036 -296.930155) (xy 390.202718 -296.90936) (xy 390.195308 -296.901108)
			(xy 386.998718 -293.704518) (xy 386.990511 -293.697034) (xy 386.969686 -293.68939) (xy 386.958586 -293.689786)
			(xy 386.86994 -293.697152) (xy 386.850636 -293.708074) (xy 386.844032 -293.717218) (xy 386.828401 -293.73825)
			(xy 386.791605 -293.775555) (xy 386.74938 -293.806583) (xy 386.702786 -293.830555) (xy 386.652991 -293.84687)
			(xy 386.601246 -293.855118) (xy 386.575046 -293.855648) (xy 386.549053 -293.855168) (xy 386.497707 -293.847043)
			(xy 386.448264 -293.830985) (xy 386.401941 -293.807391) (xy 386.35988 -293.77684) (xy 386.323116 -293.740086)
			(xy 386.292554 -293.698032) (xy 386.268948 -293.651716) (xy 386.252877 -293.602277) (xy 386.244738 -293.550933)
			(xy 386.244338 -293.52494) (xy 386.244843 -293.498741) (xy 386.253116 -293.447001) (xy 386.269445 -293.397212)
			(xy 386.293422 -293.350623) (xy 386.324447 -293.308397) (xy 386.361743 -293.271593) (xy 386.382768 -293.255954)
			(xy 386.391912 -293.24935) (xy 386.402834 -293.230046) (xy 386.4102 -293.1414) (xy 386.410531 -293.130311)
			(xy 386.402902 -293.109502) (xy 386.395468 -293.101268) (xy 386.048504 -292.754304) (xy 386.040296 -292.746824)
			(xy 386.019471 -292.739189) (xy 386.008372 -292.739572) (xy 385.93141 -292.745922) (xy 385.920912 -292.747254)
			(xy 385.902281 -292.757236) (xy 385.895342 -292.765226) (xy 385.894072 -292.767004) (xy 385.893564 -292.767766)
			(xy 385.877917 -292.788733) (xy 385.841115 -292.825914) (xy 385.798917 -292.856835) (xy 385.752376 -292.880725)
			(xy 385.702653 -292.896987) (xy 385.650989 -292.905215) (xy 385.624832 -292.905688) (xy 385.598842 -292.905207)
			(xy 385.5475 -292.89708) (xy 385.498063 -292.88102) (xy 385.451747 -292.857424) (xy 385.409692 -292.826872)
			(xy 385.372936 -292.790117) (xy 385.342382 -292.748064) (xy 385.318784 -292.701748) (xy 385.302723 -292.652311)
			(xy 385.294594 -292.60097) (xy 385.294124 -292.57498) (xy 385.294622 -292.548825) (xy 385.302858 -292.497168)
			(xy 385.319122 -292.447451) (xy 385.343009 -292.400913) (xy 385.373922 -292.358715) (xy 385.411092 -292.321909)
			(xy 385.432046 -292.306248) (xy 385.432808 -292.30574) (xy 385.434586 -292.30447) (xy 385.442568 -292.297528)
			(xy 385.452531 -292.278894) (xy 385.45389 -292.268402) (xy 385.46024 -292.19144) (xy 385.46056 -292.180355)
			(xy 385.452918 -292.15956) (xy 385.445508 -292.151308) (xy 385.098544 -291.804344) (xy 385.09034 -291.796852)
			(xy 385.069513 -291.789194) (xy 385.058412 -291.789612) (xy 384.969766 -291.796978) (xy 384.950462 -291.8079)
			(xy 384.943858 -291.817044) (xy 384.92823 -291.838081) (xy 384.891438 -291.875397) (xy 384.849215 -291.906435)
			(xy 384.80262 -291.930416) (xy 384.752823 -291.946739) (xy 384.701074 -291.954994) (xy 384.674872 -291.955474)
			(xy 384.648885 -291.954989) (xy 384.597552 -291.946854) (xy 384.548123 -291.930789) (xy 384.501817 -291.907189)
			(xy 384.459772 -291.876636) (xy 384.423024 -291.839881) (xy 384.392479 -291.797831) (xy 384.368888 -291.751519)
			(xy 384.352832 -291.702088) (xy 384.344706 -291.650753) (xy 384.344164 -291.624766) (xy 384.344667 -291.598567)
			(xy 384.352937 -291.546824) (xy 384.369264 -291.497034) (xy 384.393241 -291.450443) (xy 384.424266 -291.408216)
			(xy 384.461562 -291.371411) (xy 384.482594 -291.35578) (xy 384.491738 -291.349176) (xy 384.50266 -291.329872)
			(xy 384.510026 -291.241226) (xy 384.510342 -291.230142) (xy 384.502695 -291.209353) (xy 384.495294 -291.201094)
			(xy 382.658874 -289.364674) (xy 382.652024 -289.357278) (xy 382.644287 -289.338679) (xy 382.643888 -289.328606)
			(xy 382.643888 -287.513776) (xy 382.643495 -287.504929) (xy 382.637463 -287.488294) (xy 382.626154 -287.474684)
			(xy 382.618742 -287.469834) (xy 382.545336 -287.426654) (xy 382.540599 -287.424089) (xy 382.530356 -287.420761)
			(xy 382.525016 -287.42005) (xy 382.515364 -287.419034) (xy 382.49225 -287.425384) (xy 382.486662 -287.428432)
			(xy 382.458376 -287.443205) (xy 382.398099 -287.464143) (xy 382.335179 -287.474758) (xy 382.303274 -287.475422)
			(xy 382.30302 -287.475422) (xy 382.275765 -287.47496) (xy 382.22181 -287.467206) (xy 382.169508 -287.451851)
			(xy 382.119923 -287.429208) (xy 382.074066 -287.39974) (xy 382.032869 -287.364045) (xy 381.997172 -287.32285)
			(xy 381.967701 -287.276994) (xy 381.945056 -287.227411) (xy 381.929699 -287.17511) (xy 381.921941 -287.121155)
			(xy 381.921941 -287.066645) (xy 381.929699 -287.01269) (xy 381.945056 -286.960389) (xy 381.967701 -286.910806)
			(xy 381.997172 -286.86495) (xy 382.032869 -286.823755) (xy 382.074066 -286.78806) (xy 382.119923 -286.758592)
			(xy 382.169508 -286.735949) (xy 382.22181 -286.720594) (xy 382.275765 -286.71284) (xy 382.30302 -286.712406)
			(xy 382.303274 -286.712406) (xy 382.335176 -286.713075) (xy 382.398089 -286.723719) (xy 382.458364 -286.744649)
			(xy 382.486662 -286.759396) (xy 382.49225 -286.762444) (xy 382.505966 -286.766254) (xy 382.510888 -286.767454)
			(xy 382.520997 -286.76809) (xy 382.526032 -286.767524) (xy 382.536192 -286.766254) (xy 382.618742 -286.717994)
			(xy 382.62617 -286.713231) (xy 382.637471 -286.699697) (xy 382.643482 -286.683122) (xy 382.643888 -286.674306)
			(xy 382.643888 -284.313376) (xy 382.643495 -284.304529) (xy 382.637463 -284.287894) (xy 382.626154 -284.274284)
			(xy 382.618742 -284.269434) (xy 382.545336 -284.226254) (xy 382.540599 -284.223689) (xy 382.530356 -284.220361)
			(xy 382.525016 -284.21965) (xy 382.515364 -284.218634) (xy 382.49225 -284.224984) (xy 382.486662 -284.228032)
			(xy 382.458376 -284.242805) (xy 382.398099 -284.263743) (xy 382.335179 -284.274358) (xy 382.303274 -284.275022)
			(xy 382.30302 -284.275022) (xy 382.275765 -284.27456) (xy 382.22181 -284.266806) (xy 382.169508 -284.251451)
			(xy 382.119923 -284.228808) (xy 382.074066 -284.19934) (xy 382.032869 -284.163645) (xy 381.997172 -284.12245)
			(xy 381.967701 -284.076594) (xy 381.945056 -284.027011) (xy 381.929699 -283.97471) (xy 381.921941 -283.920755)
			(xy 381.921941 -283.866245) (xy 381.929699 -283.81229) (xy 381.945056 -283.759989) (xy 381.967701 -283.710406)
			(xy 381.997172 -283.66455) (xy 382.032869 -283.623355) (xy 382.074066 -283.58766) (xy 382.119923 -283.558192)
			(xy 382.169508 -283.535549) (xy 382.22181 -283.520194) (xy 382.275765 -283.51244) (xy 382.30302 -283.512006)
			(xy 382.303274 -283.512006) (xy 382.335176 -283.512675) (xy 382.398089 -283.523319) (xy 382.458364 -283.544249)
			(xy 382.486662 -283.558996) (xy 382.49225 -283.562044) (xy 382.505966 -283.565854) (xy 382.510888 -283.567054)
			(xy 382.520997 -283.56769) (xy 382.526032 -283.567124) (xy 382.536192 -283.565854) (xy 382.618742 -283.517594)
			(xy 382.62617 -283.512831) (xy 382.637471 -283.499297) (xy 382.643482 -283.482722) (xy 382.643888 -283.473906)
			(xy 382.643888 -281.112976) (xy 382.643495 -281.104129) (xy 382.637463 -281.087494) (xy 382.626154 -281.073884)
			(xy 382.618742 -281.069034) (xy 382.545336 -281.025854) (xy 382.540599 -281.023289) (xy 382.530356 -281.019961)
			(xy 382.525016 -281.01925) (xy 382.515364 -281.018234) (xy 382.49225 -281.024584) (xy 382.486662 -281.027632)
			(xy 382.458376 -281.042405) (xy 382.398099 -281.063343) (xy 382.335179 -281.073958) (xy 382.303274 -281.074622)
			(xy 382.30302 -281.074622) (xy 382.275765 -281.07416) (xy 382.22181 -281.066406) (xy 382.169508 -281.051051)
			(xy 382.119923 -281.028408) (xy 382.074066 -280.99894) (xy 382.032869 -280.963245) (xy 381.997172 -280.92205)
			(xy 381.967701 -280.876194) (xy 381.945056 -280.826611) (xy 381.929699 -280.77431) (xy 381.921941 -280.720355)
			(xy 381.921941 -280.665845) (xy 381.929699 -280.61189) (xy 381.945056 -280.559589) (xy 381.967701 -280.510006)
			(xy 381.997172 -280.46415) (xy 382.032869 -280.422955) (xy 382.074066 -280.38726) (xy 382.119923 -280.357792)
			(xy 382.169508 -280.335149) (xy 382.22181 -280.319794) (xy 382.275765 -280.31204) (xy 382.30302 -280.311606)
			(xy 382.303274 -280.311606) (xy 382.335176 -280.312275) (xy 382.398089 -280.322919) (xy 382.458364 -280.343849)
			(xy 382.486662 -280.358596) (xy 382.49225 -280.361644) (xy 382.505966 -280.365454) (xy 382.510888 -280.366654)
			(xy 382.520997 -280.36729) (xy 382.526032 -280.366724) (xy 382.536192 -280.365454) (xy 382.618742 -280.317194)
			(xy 382.62617 -280.312431) (xy 382.637471 -280.298897) (xy 382.643482 -280.282322) (xy 382.643888 -280.273506)
			(xy 382.643888 -280.044398) (xy 382.643464 -280.034328) (xy 382.635748 -280.015725) (xy 382.628902 -280.00833)
			(xy 382.376172 -279.7556) (xy 382.368772 -279.748758) (xy 382.350174 -279.741034) (xy 382.340104 -279.740614)
			(xy 380.50597 -279.740614) (xy 380.494766 -279.741188) (xy 380.474457 -279.750656) (xy 380.466854 -279.758902)
			(xy 380.40945 -279.82799) (xy 380.403862 -279.84958) (xy 380.405894 -279.86101) (xy 380.408956 -279.878375)
			(xy 380.412261 -279.913483) (xy 380.412498 -279.931114) (xy 380.412012 -279.958365) (xy 380.404256 -280.012313)
			(xy 380.388901 -280.064608) (xy 380.366259 -280.114185) (xy 380.336793 -280.160035) (xy 380.301102 -280.201226)
			(xy 380.259911 -280.236917) (xy 380.214061 -280.266383) (xy 380.164484 -280.289025) (xy 380.112189 -280.30438)
			(xy 380.058241 -280.312136) (xy 380.003739 -280.312136) (xy 379.949791 -280.30438) (xy 379.897496 -280.289025)
			(xy 379.847919 -280.266383) (xy 379.802069 -280.236917) (xy 379.760878 -280.201226) (xy 379.725187 -280.160035)
			(xy 379.695721 -280.114185) (xy 379.673079 -280.064608) (xy 379.657724 -280.012313) (xy 379.649968 -279.958365)
			(xy 379.649482 -279.931114) (xy 379.649482 -279.930352) (xy 379.650131 -279.899107) (xy 379.660342 -279.837456)
			(xy 379.669802 -279.80767) (xy 379.672596 -279.799796) (xy 379.672596 -279.791414) (xy 379.672179 -279.781391)
			(xy 379.664511 -279.76287) (xy 379.650338 -279.748694) (xy 379.631819 -279.741023) (xy 379.621796 -279.740614)
			(xy 379.585728 -279.740614) (xy 379.575704 -279.741029) (xy 379.55718 -279.748694) (xy 379.543002 -279.762868)
			(xy 379.535332 -279.78139) (xy 379.534928 -279.791414) (xy 379.534928 -283.893514) (xy 379.638052 -283.893514)
			(xy 379.638619 -283.864133) (xy 379.647646 -283.806068) (xy 379.665474 -283.750075) (xy 379.691681 -283.69748)
			(xy 379.725646 -283.649528) (xy 379.766565 -283.607354) (xy 379.78969 -283.589222) (xy 379.799088 -283.581856)
			(xy 379.809502 -283.561282) (xy 379.811026 -283.457396) (xy 379.80112 -283.436314) (xy 379.791976 -283.428948)
			(xy 379.770116 -283.410756) (xy 379.731578 -283.368934) (xy 379.699673 -283.321855) (xy 379.675108 -283.270563)
			(xy 379.658427 -283.216193) (xy 379.65 -283.15995) (xy 379.649482 -283.131514) (xy 379.649968 -283.104263)
			(xy 379.657724 -283.050315) (xy 379.673079 -282.99802) (xy 379.695721 -282.948443) (xy 379.725187 -282.902593)
			(xy 379.760878 -282.861402) (xy 379.802069 -282.825711) (xy 379.847919 -282.796245) (xy 379.897496 -282.773603)
			(xy 379.949791 -282.758248) (xy 380.003739 -282.750492) (xy 380.058241 -282.750492) (xy 380.112189 -282.758248)
			(xy 380.164484 -282.773603) (xy 380.214061 -282.796245) (xy 380.259911 -282.825711) (xy 380.301102 -282.861402)
			(xy 380.336793 -282.902593) (xy 380.366259 -282.948443) (xy 380.388901 -282.99802) (xy 380.404256 -283.050315)
			(xy 380.412012 -283.104263) (xy 380.412498 -283.131514) (xy 380.411971 -283.160897) (xy 380.402938 -283.218964)
			(xy 380.385103 -283.274959) (xy 380.358889 -283.327554) (xy 380.324916 -283.375505) (xy 380.283989 -283.417676)
			(xy 380.26086 -283.435806) (xy 380.251462 -283.443172) (xy 380.241048 -283.463746) (xy 380.239524 -283.567632)
			(xy 380.24943 -283.588714) (xy 380.258574 -283.59608) (xy 380.280389 -283.614324) (xy 380.318933 -283.656134)
			(xy 380.350844 -283.703201) (xy 380.375417 -283.754484) (xy 380.392107 -283.808845) (xy 380.400545 -283.865081)
			(xy 380.401068 -283.893514) (xy 381.034542 -283.893514) (xy 381.038613 -283.837892) (xy 381.050739 -283.783455)
			(xy 381.070662 -283.731364) (xy 381.097958 -283.682729) (xy 381.132044 -283.638586) (xy 381.172193 -283.599877)
			(xy 381.217551 -283.567426) (xy 381.267151 -283.541925) (xy 381.319935 -283.523918) (xy 381.374778 -283.513788)
			(xy 381.430512 -283.511751) (xy 381.485949 -283.517851) (xy 381.539906 -283.531957) (xy 381.591235 -283.553769)
			(xy 381.638841 -283.582823) (xy 381.681709 -283.618498) (xy 381.718926 -283.660035) (xy 381.749699 -283.706548)
			(xy 381.773371 -283.757045) (xy 381.789439 -283.810452) (xy 381.797559 -283.865628) (xy 381.798068 -283.893514)
			(xy 381.797559 -283.9214) (xy 381.789439 -283.976576) (xy 381.773371 -284.029983) (xy 381.749699 -284.08048)
			(xy 381.718926 -284.126993) (xy 381.681709 -284.16853) (xy 381.638841 -284.204205) (xy 381.591235 -284.233259)
			(xy 381.539906 -284.255071) (xy 381.485949 -284.269177) (xy 381.430512 -284.275277) (xy 381.374778 -284.27324)
			(xy 381.319935 -284.26311) (xy 381.267151 -284.245103) (xy 381.217551 -284.219602) (xy 381.172193 -284.187151)
			(xy 381.132044 -284.148442) (xy 381.097958 -284.104299) (xy 381.070662 -284.055664) (xy 381.050739 -284.003573)
			(xy 381.038613 -283.949136) (xy 381.034542 -283.893514) (xy 380.401068 -283.893514) (xy 380.400582 -283.920765)
			(xy 380.392826 -283.974713) (xy 380.377471 -284.027008) (xy 380.354829 -284.076585) (xy 380.325363 -284.122435)
			(xy 380.289672 -284.163626) (xy 380.248481 -284.199317) (xy 380.202631 -284.228783) (xy 380.153054 -284.251425)
			(xy 380.100759 -284.26678) (xy 380.046811 -284.274536) (xy 379.992309 -284.274536) (xy 379.938361 -284.26678)
			(xy 379.886066 -284.251425) (xy 379.836489 -284.228783) (xy 379.790639 -284.199317) (xy 379.749448 -284.163626)
			(xy 379.713757 -284.122435) (xy 379.684291 -284.076585) (xy 379.661649 -284.027008) (xy 379.646294 -283.974713)
			(xy 379.638538 -283.920765) (xy 379.638052 -283.893514) (xy 379.534928 -283.893514) (xy 379.534928 -287.093914)
			(xy 379.638052 -287.093914) (xy 379.638619 -287.064533) (xy 379.647646 -287.006468) (xy 379.665474 -286.950475)
			(xy 379.691681 -286.89788) (xy 379.725646 -286.849928) (xy 379.766565 -286.807754) (xy 379.78969 -286.789622)
			(xy 379.799088 -286.782256) (xy 379.809502 -286.761682) (xy 379.811026 -286.657796) (xy 379.80112 -286.636714)
			(xy 379.791976 -286.629348) (xy 379.770116 -286.611156) (xy 379.731578 -286.569334) (xy 379.699673 -286.522255)
			(xy 379.675108 -286.470963) (xy 379.658427 -286.416593) (xy 379.65 -286.36035) (xy 379.649482 -286.331914)
			(xy 379.649968 -286.304663) (xy 379.657724 -286.250715) (xy 379.673079 -286.19842) (xy 379.695721 -286.148843)
			(xy 379.725187 -286.102993) (xy 379.760878 -286.061802) (xy 379.802069 -286.026111) (xy 379.847919 -285.996645)
			(xy 379.897496 -285.974003) (xy 379.949791 -285.958648) (xy 380.003739 -285.950892) (xy 380.058241 -285.950892)
			(xy 380.112189 -285.958648) (xy 380.164484 -285.974003) (xy 380.214061 -285.996645) (xy 380.259911 -286.026111)
			(xy 380.301102 -286.061802) (xy 380.336793 -286.102993) (xy 380.366259 -286.148843) (xy 380.388901 -286.19842)
			(xy 380.404256 -286.250715) (xy 380.412012 -286.304663) (xy 380.412498 -286.331914) (xy 380.411971 -286.361297)
			(xy 380.402938 -286.419364) (xy 380.385103 -286.475359) (xy 380.358889 -286.527954) (xy 380.324916 -286.575905)
			(xy 380.283989 -286.618076) (xy 380.26086 -286.636206) (xy 380.251462 -286.643572) (xy 380.241048 -286.664146)
			(xy 380.239524 -286.768032) (xy 380.24943 -286.789114) (xy 380.258574 -286.79648) (xy 380.280389 -286.814724)
			(xy 380.318933 -286.856534) (xy 380.350844 -286.903601) (xy 380.375417 -286.954884) (xy 380.392107 -287.009245)
			(xy 380.400545 -287.065481) (xy 380.401068 -287.093914) (xy 381.034542 -287.093914) (xy 381.038613 -287.038292)
			(xy 381.050739 -286.983855) (xy 381.070662 -286.931764) (xy 381.097958 -286.883129) (xy 381.132044 -286.838986)
			(xy 381.172193 -286.800277) (xy 381.217551 -286.767826) (xy 381.267151 -286.742325) (xy 381.319935 -286.724318)
			(xy 381.374778 -286.714188) (xy 381.430512 -286.712151) (xy 381.485949 -286.718251) (xy 381.539906 -286.732357)
			(xy 381.591235 -286.754169) (xy 381.638841 -286.783223) (xy 381.681709 -286.818898) (xy 381.718926 -286.860435)
			(xy 381.749699 -286.906948) (xy 381.773371 -286.957445) (xy 381.789439 -287.010852) (xy 381.797559 -287.066028)
			(xy 381.798068 -287.093914) (xy 381.797559 -287.1218) (xy 381.789439 -287.176976) (xy 381.773371 -287.230383)
			(xy 381.749699 -287.28088) (xy 381.718926 -287.327393) (xy 381.681709 -287.36893) (xy 381.638841 -287.404605)
			(xy 381.591235 -287.433659) (xy 381.539906 -287.455471) (xy 381.485949 -287.469577) (xy 381.430512 -287.475677)
			(xy 381.374778 -287.47364) (xy 381.319935 -287.46351) (xy 381.267151 -287.445503) (xy 381.217551 -287.420002)
			(xy 381.172193 -287.387551) (xy 381.132044 -287.348842) (xy 381.097958 -287.304699) (xy 381.070662 -287.256064)
			(xy 381.050739 -287.203973) (xy 381.038613 -287.149536) (xy 381.034542 -287.093914) (xy 380.401068 -287.093914)
			(xy 380.400582 -287.121165) (xy 380.392826 -287.175113) (xy 380.377471 -287.227408) (xy 380.354829 -287.276985)
			(xy 380.325363 -287.322835) (xy 380.289672 -287.364026) (xy 380.248481 -287.399717) (xy 380.202631 -287.429183)
			(xy 380.153054 -287.451825) (xy 380.100759 -287.46718) (xy 380.046811 -287.474936) (xy 379.992309 -287.474936)
			(xy 379.938361 -287.46718) (xy 379.886066 -287.451825) (xy 379.836489 -287.429183) (xy 379.790639 -287.399717)
			(xy 379.749448 -287.364026) (xy 379.713757 -287.322835) (xy 379.684291 -287.276985) (xy 379.661649 -287.227408)
			(xy 379.646294 -287.175113) (xy 379.638538 -287.121165) (xy 379.638052 -287.093914) (xy 379.534928 -287.093914)
			(xy 379.534928 -290.294314) (xy 379.638052 -290.294314) (xy 379.638619 -290.264933) (xy 379.647646 -290.206868)
			(xy 379.665474 -290.150875) (xy 379.691681 -290.09828) (xy 379.725646 -290.050328) (xy 379.766565 -290.008154)
			(xy 379.78969 -289.990022) (xy 379.799088 -289.982656) (xy 379.809502 -289.962082) (xy 379.811026 -289.858196)
			(xy 379.80112 -289.837114) (xy 379.791976 -289.829748) (xy 379.770116 -289.811556) (xy 379.731578 -289.769734)
			(xy 379.699673 -289.722655) (xy 379.675108 -289.671363) (xy 379.658427 -289.616993) (xy 379.65 -289.56075)
			(xy 379.649482 -289.532314) (xy 379.649968 -289.505063) (xy 379.657724 -289.451115) (xy 379.673079 -289.39882)
			(xy 379.695721 -289.349243) (xy 379.725187 -289.303393) (xy 379.760878 -289.262202) (xy 379.802069 -289.226511)
			(xy 379.847919 -289.197045) (xy 379.897496 -289.174403) (xy 379.949791 -289.159048) (xy 380.003739 -289.151292)
			(xy 380.058241 -289.151292) (xy 380.112189 -289.159048) (xy 380.164484 -289.174403) (xy 380.214061 -289.197045)
			(xy 380.259911 -289.226511) (xy 380.301102 -289.262202) (xy 380.336793 -289.303393) (xy 380.366259 -289.349243)
			(xy 380.388901 -289.39882) (xy 380.404256 -289.451115) (xy 380.412012 -289.505063) (xy 380.412498 -289.532314)
			(xy 380.411971 -289.561697) (xy 380.402938 -289.619764) (xy 380.385103 -289.675759) (xy 380.358889 -289.728354)
			(xy 380.324916 -289.776305) (xy 380.283989 -289.818476) (xy 380.26086 -289.836606) (xy 380.251462 -289.843972)
			(xy 380.241048 -289.864546) (xy 380.239524 -289.968432) (xy 380.24943 -289.989514) (xy 380.258574 -289.99688)
			(xy 380.280389 -290.015124) (xy 380.318933 -290.056934) (xy 380.350844 -290.104001) (xy 380.375417 -290.155284)
			(xy 380.392107 -290.209645) (xy 380.400545 -290.265881) (xy 380.401068 -290.294314) (xy 381.034542 -290.294314)
			(xy 381.038613 -290.238692) (xy 381.050739 -290.184255) (xy 381.070662 -290.132164) (xy 381.097958 -290.083529)
			(xy 381.132044 -290.039386) (xy 381.172193 -290.000677) (xy 381.217551 -289.968226) (xy 381.267151 -289.942725)
			(xy 381.319935 -289.924718) (xy 381.374778 -289.914588) (xy 381.430512 -289.912551) (xy 381.485949 -289.918651)
			(xy 381.539906 -289.932757) (xy 381.591235 -289.954569) (xy 381.638841 -289.983623) (xy 381.681709 -290.019298)
			(xy 381.718926 -290.060835) (xy 381.749699 -290.107348) (xy 381.773371 -290.157845) (xy 381.789439 -290.211252)
			(xy 381.797559 -290.266428) (xy 381.798068 -290.294314) (xy 381.921002 -290.294314) (xy 381.925073 -290.238692)
			(xy 381.937199 -290.184255) (xy 381.957122 -290.132164) (xy 381.984418 -290.083529) (xy 382.018504 -290.039386)
			(xy 382.058653 -290.000677) (xy 382.104011 -289.968226) (xy 382.153611 -289.942725) (xy 382.206395 -289.924718)
			(xy 382.261238 -289.914588) (xy 382.316972 -289.912551) (xy 382.372409 -289.918651) (xy 382.426366 -289.932757)
			(xy 382.477695 -289.954569) (xy 382.525301 -289.983623) (xy 382.568169 -290.019298) (xy 382.605386 -290.060835)
			(xy 382.636159 -290.107348) (xy 382.659831 -290.157845) (xy 382.675899 -290.211252) (xy 382.684019 -290.266428)
			(xy 382.684528 -290.294314) (xy 382.684019 -290.3222) (xy 382.675899 -290.377376) (xy 382.659831 -290.430783)
			(xy 382.636159 -290.48128) (xy 382.605386 -290.527793) (xy 382.568169 -290.56933) (xy 382.525301 -290.605005)
			(xy 382.477695 -290.634059) (xy 382.426366 -290.655871) (xy 382.372409 -290.669977) (xy 382.316972 -290.676077)
			(xy 382.261238 -290.67404) (xy 382.206395 -290.66391) (xy 382.153611 -290.645903) (xy 382.104011 -290.620402)
			(xy 382.058653 -290.587951) (xy 382.018504 -290.549242) (xy 381.984418 -290.505099) (xy 381.957122 -290.456464)
			(xy 381.937199 -290.404373) (xy 381.925073 -290.349936) (xy 381.921002 -290.294314) (xy 381.798068 -290.294314)
			(xy 381.797559 -290.3222) (xy 381.789439 -290.377376) (xy 381.773371 -290.430783) (xy 381.749699 -290.48128)
			(xy 381.718926 -290.527793) (xy 381.681709 -290.56933) (xy 381.638841 -290.605005) (xy 381.591235 -290.634059)
			(xy 381.539906 -290.655871) (xy 381.485949 -290.669977) (xy 381.430512 -290.676077) (xy 381.374778 -290.67404)
			(xy 381.319935 -290.66391) (xy 381.267151 -290.645903) (xy 381.217551 -290.620402) (xy 381.172193 -290.587951)
			(xy 381.132044 -290.549242) (xy 381.097958 -290.505099) (xy 381.070662 -290.456464) (xy 381.050739 -290.404373)
			(xy 381.038613 -290.349936) (xy 381.034542 -290.294314) (xy 380.401068 -290.294314) (xy 380.400582 -290.321565)
			(xy 380.392826 -290.375513) (xy 380.377471 -290.427808) (xy 380.354829 -290.477385) (xy 380.325363 -290.523235)
			(xy 380.289672 -290.564426) (xy 380.248481 -290.600117) (xy 380.202631 -290.629583) (xy 380.153054 -290.652225)
			(xy 380.100759 -290.66758) (xy 380.046811 -290.675336) (xy 379.992309 -290.675336) (xy 379.938361 -290.66758)
			(xy 379.886066 -290.652225) (xy 379.836489 -290.629583) (xy 379.790639 -290.600117) (xy 379.749448 -290.564426)
			(xy 379.713757 -290.523235) (xy 379.684291 -290.477385) (xy 379.661649 -290.427808) (xy 379.646294 -290.375513)
			(xy 379.638538 -290.321565) (xy 379.638052 -290.294314) (xy 379.534928 -290.294314) (xy 379.534928 -292.278054)
			(xy 379.535395 -292.287928) (xy 379.542851 -292.306215) (xy 379.549406 -292.313614) (xy 379.54966 -292.313868)
			(xy 379.6792 -292.443408) (xy 379.682502 -292.446601) (xy 379.690039 -292.451848) (xy 379.694186 -292.453822)
			(xy 379.704092 -292.45814) (xy 379.736096 -292.458648) (xy 379.73889 -292.458648) (xy 379.74651 -292.457632)
			(xy 379.754892 -292.455346) (xy 379.779276 -292.445694) (xy 379.78588 -292.44036) (xy 379.806584 -292.423605)
			(xy 379.851759 -292.395395) (xy 379.900419 -292.373742) (xy 379.951618 -292.359068) (xy 380.00436 -292.351659)
			(xy 380.03099 -292.351206) (xy 380.058243 -292.351669) (xy 380.112194 -292.359425) (xy 380.164492 -292.37478)
			(xy 380.214073 -292.397422) (xy 380.259926 -292.42689) (xy 380.301119 -292.462584) (xy 380.336812 -292.503777)
			(xy 380.36628 -292.549631) (xy 380.377856 -292.57498) (xy 384.369068 -292.57498) (xy 384.373028 -292.525926)
			(xy 384.384805 -292.478142) (xy 384.404096 -292.432866) (xy 384.430399 -292.39127) (xy 384.463034 -292.354433)
			(xy 384.501155 -292.323308) (xy 384.543776 -292.298701) (xy 384.589792 -292.281249) (xy 384.638011 -292.271405)
			(xy 384.687186 -292.269424) (xy 384.736041 -292.275356) (xy 384.783312 -292.289048) (xy 384.827774 -292.310146)
			(xy 384.868277 -292.338102) (xy 384.90377 -292.372194) (xy 384.933335 -292.411538) (xy 384.956206 -292.455115)
			(xy 384.97179 -292.501796) (xy 384.979685 -292.550373) (xy 384.98018 -292.57498) (xy 384.979685 -292.599587)
			(xy 384.97179 -292.648164) (xy 384.956206 -292.694845) (xy 384.933335 -292.738422) (xy 384.90377 -292.777766)
			(xy 384.868277 -292.811858) (xy 384.827774 -292.839814) (xy 384.783312 -292.860912) (xy 384.736041 -292.874604)
			(xy 384.687186 -292.880536) (xy 384.638011 -292.878555) (xy 384.589792 -292.868711) (xy 384.543776 -292.851259)
			(xy 384.501155 -292.826652) (xy 384.463034 -292.795527) (xy 384.430399 -292.75869) (xy 384.404096 -292.717094)
			(xy 384.384805 -292.671818) (xy 384.373028 -292.624034) (xy 384.369068 -292.57498) (xy 380.377856 -292.57498)
			(xy 380.388922 -292.599211) (xy 380.404276 -292.65151) (xy 380.412032 -292.705461) (xy 380.412498 -292.732714)
			(xy 380.412752 -292.732714) (xy 380.412303 -292.759438) (xy 380.404848 -292.812362) (xy 380.390086 -292.86373)
			(xy 380.368305 -292.912537) (xy 380.33993 -292.957831) (xy 380.32309 -292.978586) (xy 380.317502 -292.98519)
			(xy 380.308358 -293.009066) (xy 380.30677 -293.013534) (xy 380.305101 -293.022867) (xy 380.305056 -293.027608)
			(xy 380.30531 -293.048944) (xy 380.305883 -293.058867) (xy 380.313592 -293.077166) (xy 380.320296 -293.084504)
			(xy 380.730506 -293.494714) (xy 381.034542 -293.494714) (xy 381.038613 -293.439092) (xy 381.050739 -293.384655)
			(xy 381.070662 -293.332564) (xy 381.097958 -293.283929) (xy 381.132044 -293.239786) (xy 381.172193 -293.201077)
			(xy 381.217551 -293.168626) (xy 381.267151 -293.143125) (xy 381.319935 -293.125118) (xy 381.374778 -293.114988)
			(xy 381.430512 -293.112951) (xy 381.485949 -293.119051) (xy 381.539906 -293.133157) (xy 381.591235 -293.154969)
			(xy 381.638841 -293.184023) (xy 381.681709 -293.219698) (xy 381.718926 -293.261235) (xy 381.749699 -293.307748)
			(xy 381.773371 -293.358245) (xy 381.789439 -293.411652) (xy 381.797559 -293.466828) (xy 381.798068 -293.494714)
			(xy 381.921002 -293.494714) (xy 381.925073 -293.439092) (xy 381.937199 -293.384655) (xy 381.957122 -293.332564)
			(xy 381.984418 -293.283929) (xy 382.018504 -293.239786) (xy 382.058653 -293.201077) (xy 382.104011 -293.168626)
			(xy 382.153611 -293.143125) (xy 382.206395 -293.125118) (xy 382.261238 -293.114988) (xy 382.316972 -293.112951)
			(xy 382.372409 -293.119051) (xy 382.426366 -293.133157) (xy 382.477695 -293.154969) (xy 382.525301 -293.184023)
			(xy 382.568169 -293.219698) (xy 382.605386 -293.261235) (xy 382.636159 -293.307748) (xy 382.659831 -293.358245)
			(xy 382.675899 -293.411652) (xy 382.684019 -293.466828) (xy 382.684528 -293.494714) (xy 382.684019 -293.5226)
			(xy 382.683675 -293.52494) (xy 384.369068 -293.52494) (xy 384.373028 -293.475886) (xy 384.384805 -293.428102)
			(xy 384.404096 -293.382826) (xy 384.430399 -293.34123) (xy 384.463034 -293.304393) (xy 384.501155 -293.273268)
			(xy 384.543776 -293.248661) (xy 384.589792 -293.231209) (xy 384.638011 -293.221365) (xy 384.687186 -293.219384)
			(xy 384.736041 -293.225316) (xy 384.783312 -293.239008) (xy 384.827774 -293.260106) (xy 384.868277 -293.288062)
			(xy 384.90377 -293.322154) (xy 384.933335 -293.361498) (xy 384.956206 -293.405075) (xy 384.97179 -293.451756)
			(xy 384.979685 -293.500333) (xy 384.98018 -293.52494) (xy 385.319028 -293.52494) (xy 385.322988 -293.475886)
			(xy 385.334765 -293.428102) (xy 385.354056 -293.382826) (xy 385.380359 -293.34123) (xy 385.412994 -293.304393)
			(xy 385.451115 -293.273268) (xy 385.493736 -293.248661) (xy 385.539752 -293.231209) (xy 385.587971 -293.221365)
			(xy 385.637146 -293.219384) (xy 385.686001 -293.225316) (xy 385.733272 -293.239008) (xy 385.777734 -293.260106)
			(xy 385.818237 -293.288062) (xy 385.85373 -293.322154) (xy 385.883295 -293.361498) (xy 385.906166 -293.405075)
			(xy 385.92175 -293.451756) (xy 385.929645 -293.500333) (xy 385.93014 -293.52494) (xy 385.929645 -293.549547)
			(xy 385.92175 -293.598124) (xy 385.906166 -293.644805) (xy 385.883295 -293.688382) (xy 385.85373 -293.727726)
			(xy 385.818237 -293.761818) (xy 385.777734 -293.789774) (xy 385.733272 -293.810872) (xy 385.686001 -293.824564)
			(xy 385.637146 -293.830496) (xy 385.587971 -293.828515) (xy 385.539752 -293.818671) (xy 385.493736 -293.801219)
			(xy 385.451115 -293.776612) (xy 385.412994 -293.745487) (xy 385.380359 -293.70865) (xy 385.354056 -293.667054)
			(xy 385.334765 -293.621778) (xy 385.322988 -293.573994) (xy 385.319028 -293.52494) (xy 384.98018 -293.52494)
			(xy 384.979685 -293.549547) (xy 384.97179 -293.598124) (xy 384.956206 -293.644805) (xy 384.933335 -293.688382)
			(xy 384.90377 -293.727726) (xy 384.868277 -293.761818) (xy 384.827774 -293.789774) (xy 384.783312 -293.810872)
			(xy 384.736041 -293.824564) (xy 384.687186 -293.830496) (xy 384.638011 -293.828515) (xy 384.589792 -293.818671)
			(xy 384.543776 -293.801219) (xy 384.501155 -293.776612) (xy 384.463034 -293.745487) (xy 384.430399 -293.70865)
			(xy 384.404096 -293.667054) (xy 384.384805 -293.621778) (xy 384.373028 -293.573994) (xy 384.369068 -293.52494)
			(xy 382.683675 -293.52494) (xy 382.675899 -293.577776) (xy 382.659831 -293.631183) (xy 382.636159 -293.68168)
			(xy 382.605386 -293.728193) (xy 382.568169 -293.76973) (xy 382.525301 -293.805405) (xy 382.477695 -293.834459)
			(xy 382.426366 -293.856271) (xy 382.372409 -293.870377) (xy 382.316972 -293.876477) (xy 382.261238 -293.87444)
			(xy 382.206395 -293.86431) (xy 382.153611 -293.846303) (xy 382.104011 -293.820802) (xy 382.058653 -293.788351)
			(xy 382.018504 -293.749642) (xy 381.984418 -293.705499) (xy 381.957122 -293.656864) (xy 381.937199 -293.604773)
			(xy 381.925073 -293.550336) (xy 381.921002 -293.494714) (xy 381.798068 -293.494714) (xy 381.797559 -293.5226)
			(xy 381.789439 -293.577776) (xy 381.773371 -293.631183) (xy 381.749699 -293.68168) (xy 381.718926 -293.728193)
			(xy 381.681709 -293.76973) (xy 381.638841 -293.805405) (xy 381.591235 -293.834459) (xy 381.539906 -293.856271)
			(xy 381.485949 -293.870377) (xy 381.430512 -293.876477) (xy 381.374778 -293.87444) (xy 381.319935 -293.86431)
			(xy 381.267151 -293.846303) (xy 381.217551 -293.820802) (xy 381.172193 -293.788351) (xy 381.132044 -293.749642)
			(xy 381.097958 -293.705499) (xy 381.070662 -293.656864) (xy 381.050739 -293.604773) (xy 381.038613 -293.550336)
			(xy 381.034542 -293.494714) (xy 380.730506 -293.494714) (xy 381.710692 -294.4749) (xy 384.369068 -294.4749)
			(xy 384.373028 -294.425846) (xy 384.384805 -294.378062) (xy 384.404096 -294.332786) (xy 384.430399 -294.29119)
			(xy 384.463034 -294.254353) (xy 384.501155 -294.223228) (xy 384.543776 -294.198621) (xy 384.589792 -294.181169)
			(xy 384.638011 -294.171325) (xy 384.687186 -294.169344) (xy 384.736041 -294.175276) (xy 384.783312 -294.188968)
			(xy 384.827774 -294.210066) (xy 384.868277 -294.238022) (xy 384.90377 -294.272114) (xy 384.933335 -294.311458)
			(xy 384.956206 -294.355035) (xy 384.97179 -294.401716) (xy 384.979685 -294.450293) (xy 384.98018 -294.4749)
			(xy 385.319028 -294.4749) (xy 385.322988 -294.425846) (xy 385.334765 -294.378062) (xy 385.354056 -294.332786)
			(xy 385.380359 -294.29119) (xy 385.412994 -294.254353) (xy 385.451115 -294.223228) (xy 385.493736 -294.198621)
			(xy 385.539752 -294.181169) (xy 385.587971 -294.171325) (xy 385.637146 -294.169344) (xy 385.686001 -294.175276)
			(xy 385.733272 -294.188968) (xy 385.777734 -294.210066) (xy 385.818237 -294.238022) (xy 385.85373 -294.272114)
			(xy 385.883295 -294.311458) (xy 385.906166 -294.355035) (xy 385.92175 -294.401716) (xy 385.929645 -294.450293)
			(xy 385.93014 -294.4749) (xy 386.269242 -294.4749) (xy 386.273202 -294.425846) (xy 386.284979 -294.378062)
			(xy 386.30427 -294.332786) (xy 386.330573 -294.29119) (xy 386.363208 -294.254353) (xy 386.401329 -294.223228)
			(xy 386.44395 -294.198621) (xy 386.489966 -294.181169) (xy 386.538185 -294.171325) (xy 386.58736 -294.169344)
			(xy 386.636215 -294.175276) (xy 386.683486 -294.188968) (xy 386.727948 -294.210066) (xy 386.768451 -294.238022)
			(xy 386.803944 -294.272114) (xy 386.833509 -294.311458) (xy 386.85638 -294.355035) (xy 386.871964 -294.401716)
			(xy 386.879859 -294.450293) (xy 386.880354 -294.4749) (xy 386.879859 -294.499507) (xy 386.871964 -294.548084)
			(xy 386.85638 -294.594765) (xy 386.833509 -294.638342) (xy 386.803944 -294.677686) (xy 386.768451 -294.711778)
			(xy 386.727948 -294.739734) (xy 386.683486 -294.760832) (xy 386.636215 -294.774524) (xy 386.58736 -294.780456)
			(xy 386.538185 -294.778475) (xy 386.489966 -294.768631) (xy 386.44395 -294.751179) (xy 386.401329 -294.726572)
			(xy 386.363208 -294.695447) (xy 386.330573 -294.65861) (xy 386.30427 -294.617014) (xy 386.284979 -294.571738)
			(xy 386.273202 -294.523954) (xy 386.269242 -294.4749) (xy 385.93014 -294.4749) (xy 385.929645 -294.499507)
			(xy 385.92175 -294.548084) (xy 385.906166 -294.594765) (xy 385.883295 -294.638342) (xy 385.85373 -294.677686)
			(xy 385.818237 -294.711778) (xy 385.777734 -294.739734) (xy 385.733272 -294.760832) (xy 385.686001 -294.774524)
			(xy 385.637146 -294.780456) (xy 385.587971 -294.778475) (xy 385.539752 -294.768631) (xy 385.493736 -294.751179)
			(xy 385.451115 -294.726572) (xy 385.412994 -294.695447) (xy 385.380359 -294.65861) (xy 385.354056 -294.617014)
			(xy 385.334765 -294.571738) (xy 385.322988 -294.523954) (xy 385.319028 -294.4749) (xy 384.98018 -294.4749)
			(xy 384.979685 -294.499507) (xy 384.97179 -294.548084) (xy 384.956206 -294.594765) (xy 384.933335 -294.638342)
			(xy 384.90377 -294.677686) (xy 384.868277 -294.711778) (xy 384.827774 -294.739734) (xy 384.783312 -294.760832)
			(xy 384.736041 -294.774524) (xy 384.687186 -294.780456) (xy 384.638011 -294.778475) (xy 384.589792 -294.768631)
			(xy 384.543776 -294.751179) (xy 384.501155 -294.726572) (xy 384.463034 -294.695447) (xy 384.430399 -294.65861)
			(xy 384.404096 -294.617014) (xy 384.384805 -294.571738) (xy 384.373028 -294.523954) (xy 384.369068 -294.4749)
			(xy 381.710692 -294.4749) (xy 383.610358 -296.374566) (xy 384.369068 -296.374566) (xy 384.373028 -296.325512)
			(xy 384.384805 -296.277728) (xy 384.404096 -296.232452) (xy 384.430399 -296.190856) (xy 384.463034 -296.154019)
			(xy 384.501155 -296.122894) (xy 384.543776 -296.098287) (xy 384.589792 -296.080835) (xy 384.638011 -296.070991)
			(xy 384.687186 -296.06901) (xy 384.736041 -296.074942) (xy 384.783312 -296.088634) (xy 384.827774 -296.109732)
			(xy 384.868277 -296.137688) (xy 384.90377 -296.17178) (xy 384.933335 -296.211124) (xy 384.956206 -296.254701)
			(xy 384.97179 -296.301382) (xy 384.979685 -296.349959) (xy 384.98018 -296.374566) (xy 384.980175 -296.37482)
			(xy 385.319282 -296.37482) (xy 385.323242 -296.325766) (xy 385.335019 -296.277982) (xy 385.35431 -296.232706)
			(xy 385.380613 -296.19111) (xy 385.413248 -296.154273) (xy 385.451369 -296.123148) (xy 385.49399 -296.098541)
			(xy 385.540006 -296.081089) (xy 385.588225 -296.071245) (xy 385.6374 -296.069264) (xy 385.686255 -296.075196)
			(xy 385.733526 -296.088888) (xy 385.777988 -296.109986) (xy 385.818491 -296.137942) (xy 385.853984 -296.172034)
			(xy 385.883549 -296.211378) (xy 385.90642 -296.254955) (xy 385.922004 -296.301636) (xy 385.929899 -296.350213)
			(xy 385.930394 -296.37482) (xy 386.268988 -296.37482) (xy 386.272948 -296.325766) (xy 386.284725 -296.277982)
			(xy 386.304016 -296.232706) (xy 386.330319 -296.19111) (xy 386.362954 -296.154273) (xy 386.401075 -296.123148)
			(xy 386.443696 -296.098541) (xy 386.489712 -296.081089) (xy 386.537931 -296.071245) (xy 386.587106 -296.069264)
			(xy 386.635961 -296.075196) (xy 386.683232 -296.088888) (xy 386.727694 -296.109986) (xy 386.768197 -296.137942)
			(xy 386.80369 -296.172034) (xy 386.833255 -296.211378) (xy 386.856126 -296.254955) (xy 386.87171 -296.301636)
			(xy 386.879605 -296.350213) (xy 386.8801 -296.37482) (xy 387.219202 -296.37482) (xy 387.223162 -296.325766)
			(xy 387.234939 -296.277982) (xy 387.25423 -296.232706) (xy 387.280533 -296.19111) (xy 387.313168 -296.154273)
			(xy 387.351289 -296.123148) (xy 387.39391 -296.098541) (xy 387.439926 -296.081089) (xy 387.488145 -296.071245)
			(xy 387.53732 -296.069264) (xy 387.586175 -296.075196) (xy 387.633446 -296.088888) (xy 387.677908 -296.109986)
			(xy 387.718411 -296.137942) (xy 387.753904 -296.172034) (xy 387.783469 -296.211378) (xy 387.80634 -296.254955)
			(xy 387.821924 -296.301636) (xy 387.829819 -296.350213) (xy 387.830314 -296.37482) (xy 388.169162 -296.37482)
			(xy 388.173122 -296.325766) (xy 388.184899 -296.277982) (xy 388.20419 -296.232706) (xy 388.230493 -296.19111)
			(xy 388.263128 -296.154273) (xy 388.301249 -296.123148) (xy 388.34387 -296.098541) (xy 388.389886 -296.081089)
			(xy 388.438105 -296.071245) (xy 388.48728 -296.069264) (xy 388.536135 -296.075196) (xy 388.583406 -296.088888)
			(xy 388.627868 -296.109986) (xy 388.668371 -296.137942) (xy 388.703864 -296.172034) (xy 388.733429 -296.211378)
			(xy 388.7563 -296.254955) (xy 388.771884 -296.301636) (xy 388.779779 -296.350213) (xy 388.780274 -296.37482)
			(xy 388.779779 -296.399427) (xy 388.771884 -296.448004) (xy 388.7563 -296.494685) (xy 388.733429 -296.538262)
			(xy 388.703864 -296.577606) (xy 388.668371 -296.611698) (xy 388.627868 -296.639654) (xy 388.583406 -296.660752)
			(xy 388.536135 -296.674444) (xy 388.48728 -296.680376) (xy 388.438105 -296.678395) (xy 388.389886 -296.668551)
			(xy 388.34387 -296.651099) (xy 388.301249 -296.626492) (xy 388.263128 -296.595367) (xy 388.230493 -296.55853)
			(xy 388.20419 -296.516934) (xy 388.184899 -296.471658) (xy 388.173122 -296.423874) (xy 388.169162 -296.37482)
			(xy 387.830314 -296.37482) (xy 387.829819 -296.399427) (xy 387.821924 -296.448004) (xy 387.80634 -296.494685)
			(xy 387.783469 -296.538262) (xy 387.753904 -296.577606) (xy 387.718411 -296.611698) (xy 387.677908 -296.639654)
			(xy 387.633446 -296.660752) (xy 387.586175 -296.674444) (xy 387.53732 -296.680376) (xy 387.488145 -296.678395)
			(xy 387.439926 -296.668551) (xy 387.39391 -296.651099) (xy 387.351289 -296.626492) (xy 387.313168 -296.595367)
			(xy 387.280533 -296.55853) (xy 387.25423 -296.516934) (xy 387.234939 -296.471658) (xy 387.223162 -296.423874)
			(xy 387.219202 -296.37482) (xy 386.8801 -296.37482) (xy 386.879605 -296.399427) (xy 386.87171 -296.448004)
			(xy 386.856126 -296.494685) (xy 386.833255 -296.538262) (xy 386.80369 -296.577606) (xy 386.768197 -296.611698)
			(xy 386.727694 -296.639654) (xy 386.683232 -296.660752) (xy 386.635961 -296.674444) (xy 386.587106 -296.680376)
			(xy 386.537931 -296.678395) (xy 386.489712 -296.668551) (xy 386.443696 -296.651099) (xy 386.401075 -296.626492)
			(xy 386.362954 -296.595367) (xy 386.330319 -296.55853) (xy 386.304016 -296.516934) (xy 386.284725 -296.471658)
			(xy 386.272948 -296.423874) (xy 386.268988 -296.37482) (xy 385.930394 -296.37482) (xy 385.929899 -296.399427)
			(xy 385.922004 -296.448004) (xy 385.90642 -296.494685) (xy 385.883549 -296.538262) (xy 385.853984 -296.577606)
			(xy 385.818491 -296.611698) (xy 385.777988 -296.639654) (xy 385.733526 -296.660752) (xy 385.686255 -296.674444)
			(xy 385.6374 -296.680376) (xy 385.588225 -296.678395) (xy 385.540006 -296.668551) (xy 385.49399 -296.651099)
			(xy 385.451369 -296.626492) (xy 385.413248 -296.595367) (xy 385.380613 -296.55853) (xy 385.35431 -296.516934)
			(xy 385.335019 -296.471658) (xy 385.323242 -296.423874) (xy 385.319282 -296.37482) (xy 384.980175 -296.37482)
			(xy 384.979685 -296.399173) (xy 384.97179 -296.44775) (xy 384.956206 -296.494431) (xy 384.933335 -296.538008)
			(xy 384.90377 -296.577352) (xy 384.868277 -296.611444) (xy 384.827774 -296.6394) (xy 384.783312 -296.660498)
			(xy 384.736041 -296.67419) (xy 384.687186 -296.680122) (xy 384.638011 -296.678141) (xy 384.589792 -296.668297)
			(xy 384.543776 -296.650845) (xy 384.501155 -296.626238) (xy 384.463034 -296.595113) (xy 384.430399 -296.558276)
			(xy 384.404096 -296.51668) (xy 384.384805 -296.471404) (xy 384.373028 -296.42362) (xy 384.369068 -296.374566)
			(xy 383.610358 -296.374566) (xy 384.31216 -297.076368) (xy 384.312668 -297.076876) (xy 384.319779 -297.083292)
			(xy 384.337401 -297.090752) (xy 384.346958 -297.091354) (xy 384.426714 -297.093386) (xy 384.444748 -297.086528)
			(xy 384.452114 -297.079924) (xy 384.470484 -297.063843) (xy 384.511067 -297.036704) (xy 384.555196 -297.015821)
			(xy 384.601914 -297.001648) (xy 384.650207 -296.994493) (xy 384.674618 -296.994072) (xy 385.624578 -296.994072)
			(xy 385.65057 -296.994554) (xy 385.701914 -297.002683) (xy 385.751355 -297.018744) (xy 385.797674 -297.042342)
			(xy 385.839731 -297.072895) (xy 385.87649 -297.109652) (xy 385.907047 -297.151707) (xy 385.930648 -297.198025)
			(xy 385.946712 -297.247464) (xy 385.954845 -297.298808) (xy 385.954845 -297.32478) (xy 386.268988 -297.32478)
			(xy 386.272948 -297.275726) (xy 386.284725 -297.227942) (xy 386.304016 -297.182666) (xy 386.330319 -297.14107)
			(xy 386.362954 -297.104233) (xy 386.401075 -297.073108) (xy 386.443696 -297.048501) (xy 386.489712 -297.031049)
			(xy 386.537931 -297.021205) (xy 386.587106 -297.019224) (xy 386.635961 -297.025156) (xy 386.683232 -297.038848)
			(xy 386.727694 -297.059946) (xy 386.768197 -297.087902) (xy 386.80369 -297.121994) (xy 386.833255 -297.161338)
			(xy 386.856126 -297.204915) (xy 386.87171 -297.251596) (xy 386.879605 -297.300173) (xy 386.8801 -297.32478)
			(xy 387.219202 -297.32478) (xy 387.223162 -297.275726) (xy 387.234939 -297.227942) (xy 387.25423 -297.182666)
			(xy 387.280533 -297.14107) (xy 387.313168 -297.104233) (xy 387.351289 -297.073108) (xy 387.39391 -297.048501)
			(xy 387.439926 -297.031049) (xy 387.488145 -297.021205) (xy 387.53732 -297.019224) (xy 387.586175 -297.025156)
			(xy 387.633446 -297.038848) (xy 387.677908 -297.059946) (xy 387.718411 -297.087902) (xy 387.753904 -297.121994)
			(xy 387.783469 -297.161338) (xy 387.80634 -297.204915) (xy 387.821924 -297.251596) (xy 387.829819 -297.300173)
			(xy 387.830314 -297.32478) (xy 387.829819 -297.349387) (xy 387.821924 -297.397964) (xy 387.80634 -297.444645)
			(xy 387.783469 -297.488222) (xy 387.753904 -297.527566) (xy 387.718411 -297.561658) (xy 387.677908 -297.589614)
			(xy 387.633446 -297.610712) (xy 387.586175 -297.624404) (xy 387.53732 -297.630336) (xy 387.488145 -297.628355)
			(xy 387.439926 -297.618511) (xy 387.39391 -297.601059) (xy 387.351289 -297.576452) (xy 387.313168 -297.545327)
			(xy 387.280533 -297.50849) (xy 387.25423 -297.466894) (xy 387.234939 -297.421618) (xy 387.223162 -297.373834)
			(xy 387.219202 -297.32478) (xy 386.8801 -297.32478) (xy 386.879605 -297.349387) (xy 386.87171 -297.397964)
			(xy 386.856126 -297.444645) (xy 386.833255 -297.488222) (xy 386.80369 -297.527566) (xy 386.768197 -297.561658)
			(xy 386.727694 -297.589614) (xy 386.683232 -297.610712) (xy 386.635961 -297.624404) (xy 386.587106 -297.630336)
			(xy 386.537931 -297.628355) (xy 386.489712 -297.618511) (xy 386.443696 -297.601059) (xy 386.401075 -297.576452)
			(xy 386.362954 -297.545327) (xy 386.330319 -297.50849) (xy 386.304016 -297.466894) (xy 386.284725 -297.421618)
			(xy 386.272948 -297.373834) (xy 386.268988 -297.32478) (xy 385.954845 -297.32478) (xy 385.954845 -297.350792)
			(xy 385.946712 -297.402136) (xy 385.930648 -297.451575) (xy 385.907047 -297.497893) (xy 385.87649 -297.539948)
			(xy 385.839731 -297.576705) (xy 385.797674 -297.607258) (xy 385.751355 -297.630856) (xy 385.701914 -297.646917)
			(xy 385.65057 -297.655046) (xy 385.624578 -297.655488) (xy 385.013962 -297.655488) (xy 385.00392 -297.655919)
			(xy 384.985376 -297.663633) (xy 384.971205 -297.677866) (xy 384.966972 -297.686984) (xy 384.96113 -297.701462)
			(xy 384.966972 -297.73118) (xy 385.26212 -298.026328) (xy 385.262628 -298.026836) (xy 385.269744 -298.033237)
			(xy 385.287368 -298.040667) (xy 385.296918 -298.041314) (xy 385.366768 -298.043092) (xy 385.376435 -298.042902)
			(xy 385.394568 -298.036234) (xy 385.402074 -298.030138) (xy 385.402328 -298.029884) (xy 385.420677 -298.013817)
			(xy 385.461212 -297.986697) (xy 385.505289 -297.96582) (xy 385.551953 -297.95164) (xy 385.600193 -297.944463)
			(xy 385.624578 -297.944032) (xy 385.650567 -297.944514) (xy 385.701906 -297.952642) (xy 385.751341 -297.968703)
			(xy 385.797654 -297.9923) (xy 385.839706 -298.022853) (xy 385.876459 -298.059608) (xy 385.907009 -298.101661)
			(xy 385.930604 -298.147976) (xy 385.946662 -298.197411) (xy 385.954788 -298.248751) (xy 385.955286 -298.27474)
			(xy 386.268988 -298.27474) (xy 386.272948 -298.225686) (xy 386.284725 -298.177902) (xy 386.304016 -298.132626)
			(xy 386.330319 -298.09103) (xy 386.362954 -298.054193) (xy 386.401075 -298.023068) (xy 386.443696 -297.998461)
			(xy 386.489712 -297.981009) (xy 386.537931 -297.971165) (xy 386.587106 -297.969184) (xy 386.635961 -297.975116)
			(xy 386.683232 -297.988808) (xy 386.727694 -298.009906) (xy 386.768197 -298.037862) (xy 386.80369 -298.071954)
			(xy 386.833255 -298.111298) (xy 386.856126 -298.154875) (xy 386.87171 -298.201556) (xy 386.879605 -298.250133)
			(xy 386.8801 -298.27474) (xy 386.879605 -298.299347) (xy 386.87171 -298.347924) (xy 386.856126 -298.394605)
			(xy 386.833255 -298.438182) (xy 386.80369 -298.477526) (xy 386.768197 -298.511618) (xy 386.727694 -298.539574)
			(xy 386.683232 -298.560672) (xy 386.635961 -298.574364) (xy 386.587106 -298.580296) (xy 386.537931 -298.578315)
			(xy 386.489712 -298.568471) (xy 386.443696 -298.551019) (xy 386.401075 -298.526412) (xy 386.362954 -298.495287)
			(xy 386.330319 -298.45845) (xy 386.304016 -298.416854) (xy 386.284725 -298.371578) (xy 386.272948 -298.323794)
			(xy 386.268988 -298.27474) (xy 385.955286 -298.27474) (xy 385.954854 -298.299127) (xy 385.947695 -298.347372)
			(xy 385.933522 -298.394041) (xy 385.912644 -298.43812) (xy 385.885515 -298.478651) (xy 385.869434 -298.49699)
			(xy 385.86918 -298.497244) (xy 385.863015 -298.50471) (xy 385.85634 -298.522869) (xy 385.856226 -298.53255)
			(xy 385.858004 -298.6024) (xy 385.85851 -298.610113) (xy 385.863557 -298.624714) (xy 385.86791 -298.631102)
			(xy 385.870196 -298.634404) (xy 386.212334 -298.976542) (xy 386.212842 -298.97705) (xy 386.21996 -298.983447)
			(xy 386.237583 -298.990871) (xy 386.247132 -298.991528) (xy 386.316982 -298.993306) (xy 386.326655 -298.993131)
			(xy 386.34481 -298.986487) (xy 386.352288 -298.980352) (xy 386.352542 -298.980098) (xy 386.370891 -298.964031)
			(xy 386.411426 -298.936911) (xy 386.455503 -298.916036) (xy 386.502167 -298.901857) (xy 386.550407 -298.894681)
			(xy 386.574792 -298.894246) (xy 386.600781 -298.894755) (xy 386.652119 -298.902884) (xy 386.701554 -298.918944)
			(xy 386.747868 -298.942539) (xy 386.789921 -298.973087) (xy 386.826677 -299.009838) (xy 386.857233 -299.051886)
			(xy 386.880835 -299.098196) (xy 386.896903 -299.147628) (xy 386.905041 -299.198965) (xy 386.9055 -299.224954)
			(xy 386.905339 -299.238608) (xy 386.903053 -299.265821) (xy 386.900928 -299.27931) (xy 386.898896 -299.291248)
			(xy 386.906008 -299.313854) (xy 386.97916 -299.390308) (xy 387.001258 -299.398182) (xy 387.01345 -299.396912)
			(xy 387.022557 -299.395856) (xy 387.040858 -299.39471) (xy 387.050026 -299.394626) (xy 387.05913 -299.394723)
			(xy 387.077303 -299.395866) (xy 387.086348 -299.396912) (xy 387.098286 -299.398182) (xy 387.120638 -299.390308)
			(xy 387.193536 -299.313854) (xy 387.200648 -299.291248) (xy 387.198616 -299.27931) (xy 387.196488 -299.265822)
			(xy 387.194202 -299.238608) (xy 387.194044 -299.224954) (xy 387.194558 -299.198949) (xy 387.2027 -299.147581)
			(xy 387.218778 -299.09812) (xy 387.242394 -299.051781) (xy 387.272968 -299.009708) (xy 387.309747 -298.972935)
			(xy 387.351826 -298.942367) (xy 387.398168 -298.918758) (xy 387.447632 -298.902688) (xy 387.499001 -298.894554)
			(xy 387.525006 -298.893992) (xy 387.56971 -298.893992) (xy 387.580368 -298.89353) (xy 387.599832 -298.884844)
			(xy 387.607302 -298.877228) (xy 387.665214 -298.813474) (xy 387.671818 -298.793154) (xy 387.670802 -298.782486)
			(xy 387.669024 -298.74972) (xy 387.669187 -298.736066) (xy 387.671477 -298.708854) (xy 387.673596 -298.695364)
			(xy 387.675628 -298.683426) (xy 387.66877 -298.66082) (xy 387.595618 -298.584366) (xy 387.57352 -298.576492)
			(xy 387.561328 -298.577762) (xy 387.552284 -298.57881) (xy 387.53411 -298.579954) (xy 387.525006 -298.580048)
			(xy 387.500181 -298.579562) (xy 387.451185 -298.571531) (xy 387.404134 -298.555678) (xy 387.360268 -298.532422)
			(xy 387.320742 -298.502375) (xy 387.286598 -298.466329) (xy 387.258736 -298.425234) (xy 387.237889 -298.380173)
			(xy 387.224608 -298.332333) (xy 387.219241 -298.282974) (xy 387.221931 -298.233397) (xy 387.232606 -298.184908)
			(xy 387.250985 -298.138786) (xy 387.276584 -298.096244) (xy 387.308729 -298.058404) (xy 387.346572 -298.026264)
			(xy 387.389116 -298.00067) (xy 387.435241 -297.982296) (xy 387.483731 -297.971626) (xy 387.533308 -297.968942)
			(xy 387.582666 -297.974314) (xy 387.630505 -297.987601) (xy 387.675564 -298.008453) (xy 387.716656 -298.03632)
			(xy 387.752698 -298.070468) (xy 387.78274 -298.109997) (xy 387.805991 -298.153866) (xy 387.821839 -298.200918)
			(xy 387.829865 -298.249915) (xy 387.830314 -298.27474) (xy 387.830216 -298.283844) (xy 387.829072 -298.302017)
			(xy 387.828028 -298.311062) (xy 387.826758 -298.323254) (xy 387.834632 -298.345352) (xy 387.911086 -298.418504)
			(xy 387.933692 -298.425362) (xy 387.94563 -298.42333) (xy 387.959123 -298.421263) (xy 387.986336 -298.4191)
			(xy 387.999986 -298.419012) (xy 388.070344 -298.419012) (xy 388.08103 -298.418498) (xy 388.100508 -298.409692)
			(xy 388.107936 -298.401994) (xy 388.165848 -298.337732) (xy 388.172452 -298.317666) (xy 388.171436 -298.306744)
			(xy 388.169658 -298.27474) (xy 388.17018 -298.249485) (xy 388.178493 -298.199663) (xy 388.194894 -298.151889)
			(xy 388.218935 -298.107466) (xy 388.249959 -298.067606) (xy 388.287121 -298.033396) (xy 388.329407 -298.00577)
			(xy 388.375663 -297.98548) (xy 388.424628 -297.97308) (xy 388.474966 -297.968909) (xy 388.525304 -297.97308)
			(xy 388.574269 -297.98548) (xy 388.620525 -298.00577) (xy 388.662811 -298.033396) (xy 388.699973 -298.067606)
			(xy 388.730997 -298.107466) (xy 388.755038 -298.151889) (xy 388.771439 -298.199663) (xy 388.779752 -298.249485)
			(xy 388.780274 -298.27474) (xy 388.778496 -298.306744) (xy 388.77748 -298.317666) (xy 388.784084 -298.337732)
			(xy 388.841996 -298.401994) (xy 388.849508 -298.409579) (xy 388.868932 -298.418381) (xy 388.879588 -298.419012)
			(xy 388.949946 -298.419012) (xy 388.963595 -298.419111) (xy 388.990808 -298.421274) (xy 389.004302 -298.42333)
			(xy 389.01624 -298.425362) (xy 389.038846 -298.418504) (xy 389.1153 -298.345352) (xy 389.123174 -298.323254)
			(xy 389.121904 -298.311062) (xy 389.120854 -298.302018) (xy 389.119708 -298.283844) (xy 389.119618 -298.27474)
			(xy 389.12014 -298.249485) (xy 389.128453 -298.199663) (xy 389.144854 -298.151889) (xy 389.168895 -298.107466)
			(xy 389.199919 -298.067606) (xy 389.237081 -298.033396) (xy 389.279367 -298.00577) (xy 389.325623 -297.98548)
			(xy 389.374588 -297.97308) (xy 389.424926 -297.968909) (xy 389.475264 -297.97308) (xy 389.524229 -297.98548)
			(xy 389.570485 -298.00577) (xy 389.612771 -298.033396) (xy 389.649933 -298.067606) (xy 389.680957 -298.107466)
			(xy 389.704998 -298.151889) (xy 389.721399 -298.199663) (xy 389.729712 -298.249485) (xy 389.730234 -298.27474)
			(xy 389.73005 -298.288923) (xy 389.727382 -298.317163) (xy 389.7249 -298.331128) (xy 389.722614 -298.343574)
			(xy 389.72998 -298.367196) (xy 389.80745 -298.444666) (xy 389.831072 -298.452032) (xy 389.843518 -298.449746)
			(xy 389.857483 -298.447261) (xy 389.885723 -298.444589) (xy 389.899906 -298.444412) (xy 389.914088 -298.444599)
			(xy 389.942328 -298.447273) (xy 389.956294 -298.449746) (xy 389.96874 -298.452032) (xy 389.992362 -298.444666)
			(xy 390.069832 -298.367196) (xy 390.077198 -298.343574) (xy 390.074912 -298.331128) (xy 390.072425 -298.317163)
			(xy 390.069749 -298.288923) (xy 390.069578 -298.27474) (xy 390.070061 -298.249917) (xy 390.078086 -298.200924)
			(xy 390.093933 -298.153875) (xy 390.117182 -298.11001) (xy 390.147223 -298.070484) (xy 390.183262 -298.036339)
			(xy 390.22435 -298.008475) (xy 390.269406 -297.987625) (xy 390.317241 -297.974339) (xy 390.366596 -297.968968)
			(xy 390.416169 -297.971652) (xy 390.464655 -297.982321) (xy 390.510776 -298.000695) (xy 390.553316 -298.026287)
			(xy 390.591156 -298.058426) (xy 390.623297 -298.096263) (xy 390.648894 -298.138801) (xy 390.667271 -298.18492)
			(xy 390.677944 -298.233405) (xy 390.680186 -298.27474) (xy 391.019042 -298.27474) (xy 391.023002 -298.225686)
			(xy 391.034779 -298.177902) (xy 391.05407 -298.132626) (xy 391.080373 -298.09103) (xy 391.113008 -298.054193)
			(xy 391.151129 -298.023068) (xy 391.19375 -297.998461) (xy 391.239766 -297.981009) (xy 391.287985 -297.971165)
			(xy 391.33716 -297.969184) (xy 391.386015 -297.975116) (xy 391.433286 -297.988808) (xy 391.477748 -298.009906)
			(xy 391.518251 -298.037862) (xy 391.553744 -298.071954) (xy 391.583309 -298.111298) (xy 391.60618 -298.154875)
			(xy 391.621764 -298.201556) (xy 391.629659 -298.250133) (xy 391.630154 -298.27474) (xy 391.969002 -298.27474)
			(xy 391.972962 -298.225686) (xy 391.984739 -298.177902) (xy 392.00403 -298.132626) (xy 392.030333 -298.09103)
			(xy 392.062968 -298.054193) (xy 392.101089 -298.023068) (xy 392.14371 -297.998461) (xy 392.189726 -297.981009)
			(xy 392.237945 -297.971165) (xy 392.28712 -297.969184) (xy 392.335975 -297.975116) (xy 392.383246 -297.988808)
			(xy 392.427708 -298.009906) (xy 392.468211 -298.037862) (xy 392.503704 -298.071954) (xy 392.533269 -298.111298)
			(xy 392.55614 -298.154875) (xy 392.571724 -298.201556) (xy 392.579619 -298.250133) (xy 392.580114 -298.27474)
			(xy 392.919216 -298.27474) (xy 392.923176 -298.225686) (xy 392.934953 -298.177902) (xy 392.954244 -298.132626)
			(xy 392.980547 -298.09103) (xy 393.013182 -298.054193) (xy 393.051303 -298.023068) (xy 393.093924 -297.998461)
			(xy 393.13994 -297.981009) (xy 393.188159 -297.971165) (xy 393.237334 -297.969184) (xy 393.286189 -297.975116)
			(xy 393.33346 -297.988808) (xy 393.377922 -298.009906) (xy 393.418425 -298.037862) (xy 393.453918 -298.071954)
			(xy 393.483483 -298.111298) (xy 393.506354 -298.154875) (xy 393.521938 -298.201556) (xy 393.529833 -298.250133)
			(xy 393.530328 -298.27474) (xy 393.869176 -298.27474) (xy 393.873136 -298.225686) (xy 393.884913 -298.177902)
			(xy 393.904204 -298.132626) (xy 393.930507 -298.09103) (xy 393.963142 -298.054193) (xy 394.001263 -298.023068)
			(xy 394.043884 -297.998461) (xy 394.0899 -297.981009) (xy 394.138119 -297.971165) (xy 394.187294 -297.969184)
			(xy 394.236149 -297.975116) (xy 394.28342 -297.988808) (xy 394.327882 -298.009906) (xy 394.368385 -298.037862)
			(xy 394.403878 -298.071954) (xy 394.433443 -298.111298) (xy 394.456314 -298.154875) (xy 394.471898 -298.201556)
			(xy 394.479793 -298.250133) (xy 394.480288 -298.27474) (xy 394.479793 -298.299347) (xy 394.471898 -298.347924)
			(xy 394.456314 -298.394605) (xy 394.433443 -298.438182) (xy 394.403878 -298.477526) (xy 394.368385 -298.511618)
			(xy 394.327882 -298.539574) (xy 394.28342 -298.560672) (xy 394.236149 -298.574364) (xy 394.187294 -298.580296)
			(xy 394.138119 -298.578315) (xy 394.0899 -298.568471) (xy 394.043884 -298.551019) (xy 394.001263 -298.526412)
			(xy 393.963142 -298.495287) (xy 393.930507 -298.45845) (xy 393.904204 -298.416854) (xy 393.884913 -298.371578)
			(xy 393.873136 -298.323794) (xy 393.869176 -298.27474) (xy 393.530328 -298.27474) (xy 393.529833 -298.299347)
			(xy 393.521938 -298.347924) (xy 393.506354 -298.394605) (xy 393.483483 -298.438182) (xy 393.453918 -298.477526)
			(xy 393.418425 -298.511618) (xy 393.377922 -298.539574) (xy 393.33346 -298.560672) (xy 393.286189 -298.574364)
			(xy 393.237334 -298.580296) (xy 393.188159 -298.578315) (xy 393.13994 -298.568471) (xy 393.093924 -298.551019)
			(xy 393.051303 -298.526412) (xy 393.013182 -298.495287) (xy 392.980547 -298.45845) (xy 392.954244 -298.416854)
			(xy 392.934953 -298.371578) (xy 392.923176 -298.323794) (xy 392.919216 -298.27474) (xy 392.580114 -298.27474)
			(xy 392.579619 -298.299347) (xy 392.571724 -298.347924) (xy 392.55614 -298.394605) (xy 392.533269 -298.438182)
			(xy 392.503704 -298.477526) (xy 392.468211 -298.511618) (xy 392.427708 -298.539574) (xy 392.383246 -298.560672)
			(xy 392.335975 -298.574364) (xy 392.28712 -298.580296) (xy 392.237945 -298.578315) (xy 392.189726 -298.568471)
			(xy 392.14371 -298.551019) (xy 392.101089 -298.526412) (xy 392.062968 -298.495287) (xy 392.030333 -298.45845)
			(xy 392.00403 -298.416854) (xy 391.984739 -298.371578) (xy 391.972962 -298.323794) (xy 391.969002 -298.27474)
			(xy 391.630154 -298.27474) (xy 391.629659 -298.299347) (xy 391.621764 -298.347924) (xy 391.60618 -298.394605)
			(xy 391.583309 -298.438182) (xy 391.553744 -298.477526) (xy 391.518251 -298.511618) (xy 391.477748 -298.539574)
			(xy 391.433286 -298.560672) (xy 391.386015 -298.574364) (xy 391.33716 -298.580296) (xy 391.287985 -298.578315)
			(xy 391.239766 -298.568471) (xy 391.19375 -298.551019) (xy 391.151129 -298.526412) (xy 391.113008 -298.495287)
			(xy 391.080373 -298.45845) (xy 391.05407 -298.416854) (xy 391.034779 -298.371578) (xy 391.023002 -298.323794)
			(xy 391.019042 -298.27474) (xy 390.680186 -298.27474) (xy 390.680633 -298.282978) (xy 390.675266 -298.332333)
			(xy 390.661984 -298.38017) (xy 390.641138 -298.425227) (xy 390.613277 -298.466318) (xy 390.579135 -298.50236)
			(xy 390.539612 -298.532404) (xy 390.495749 -298.555657) (xy 390.448701 -298.571507) (xy 390.399709 -298.579537)
			(xy 390.374886 -298.580048) (xy 390.360704 -298.579861) (xy 390.332465 -298.577186) (xy 390.318498 -298.574714)
			(xy 390.306052 -298.572428) (xy 390.28243 -298.579794) (xy 390.20496 -298.657264) (xy 390.197594 -298.680886)
			(xy 390.19988 -298.693332) (xy 390.202364 -298.707297) (xy 390.205034 -298.735537) (xy 390.205214 -298.74972)
			(xy 390.204742 -298.77371) (xy 390.197233 -298.8211) (xy 390.182404 -298.866732) (xy 390.16062 -298.909482)
			(xy 390.132416 -298.948298) (xy 390.098488 -298.982225) (xy 390.05967 -299.010427) (xy 390.016919 -299.03221)
			(xy 389.971286 -299.047037) (xy 389.923896 -299.054543) (xy 389.899906 -299.055028) (xy 389.890738 -299.054936)
			(xy 389.872438 -299.053793) (xy 389.86333 -299.052742) (xy 389.851392 -299.051472) (xy 389.82904 -299.059346)
			(xy 389.756142 -299.1358) (xy 389.74903 -299.158406) (xy 389.751062 -299.170344) (xy 389.753199 -299.183895)
			(xy 389.755486 -299.211236) (xy 389.755634 -299.224954) (xy 389.755634 -299.225208) (xy 389.755109 -299.252819)
			(xy 389.745986 -299.30728) (xy 389.727929 -299.359465) (xy 389.701441 -299.407918) (xy 389.684768 -299.429932)
			(xy 389.679688 -299.436282) (xy 389.67283 -299.454824) (xy 389.669889 -299.464407) (xy 389.670806 -299.484411)
			(xy 389.674608 -299.493686) (xy 389.70331 -299.5549) (xy 389.707696 -299.563326) (xy 389.721461 -299.576398)
			(xy 389.739038 -299.583571) (xy 389.748522 -299.58411) (xy 389.749792 -299.58411) (xy 389.794056 -299.584661)
			(xy 389.882204 -299.592873) (xy 389.969229 -299.609128) (xy 390.054398 -299.633289) (xy 390.136995 -299.665153)
			(xy 390.216324 -299.704451) (xy 390.291719 -299.750853) (xy 390.362544 -299.803969) (xy 390.395714 -299.833284)
			(xy 390.40181 -299.838618) (xy 390.415526 -299.844714) (xy 390.427972 -299.848524) (xy 390.459722 -299.855128)
			(xy 390.466072 -299.856906)
		)
		(stroke
			(width 0)
			(type solid)
		)
		(fill yes)
		(layer "In11.Cu")
		(net "SYSPLL_VDDA18_PEX3")
	)
	(gr_poly
		(pts
			(xy 397.12392 -233.239818) (xy 397.133548 -233.239346) (xy 397.151413 -233.232146) (xy 397.165375 -233.218877)
			(xy 397.173475 -233.201402) (xy 397.174466 -233.191812) (xy 400.051778 -180.133498) (xy 400.029934 -180.104034)
			(xy 400.017742 -180.10124) (xy 399.989733 -180.09462) (xy 399.935965 -180.074093) (xy 399.885891 -180.045722)
			(xy 399.840648 -180.01015) (xy 399.801263 -179.968185) (xy 399.768629 -179.920778) (xy 399.743488 -179.869007)
			(xy 399.726411 -179.814047) (xy 399.717784 -179.757144) (xy 399.71726 -179.728368) (xy 399.71777 -179.700167)
			(xy 399.72608 -179.644379) (xy 399.742515 -179.590424) (xy 399.766717 -179.539477) (xy 399.798156 -179.492649)
			(xy 399.836149 -179.450962) (xy 399.879867 -179.415324) (xy 399.928355 -179.386512) (xy 399.954242 -179.375308)
			(xy 399.964076 -179.37072) (xy 399.978952 -179.354949) (xy 399.986016 -179.334453) (xy 399.984017 -179.312865)
			(xy 399.979134 -179.303172) (xy 399.978118 -179.301648) (xy 399.976594 -179.299362) (xy 399.960361 -179.275211)
			(xy 399.934631 -179.223022) (xy 399.917137 -179.167526) (xy 399.908285 -179.110016) (xy 399.90776 -179.080922)
			(xy 399.908295 -179.051968) (xy 399.917041 -178.994723) (xy 399.934334 -178.939456) (xy 399.959779 -178.887437)
			(xy 399.99279 -178.839859) (xy 400.032611 -178.797814) (xy 400.078327 -178.762268) (xy 400.10334 -178.747674)
			(xy 400.110613 -178.743176) (xy 400.121903 -178.730343) (xy 400.128389 -178.714529) (xy 400.129248 -178.706018)
			(xy 400.462496 -172.562266) (xy 400.458178 -172.551852) (xy 400.449418 -172.529084) (xy 400.437096 -172.481883)
			(xy 400.430891 -172.433496) (xy 400.430492 -172.409104) (xy 400.431121 -172.377825) (xy 400.441332 -172.316107)
			(xy 400.46148 -172.256882) (xy 400.475704 -172.229018) (xy 400.478498 -172.223938) (xy 400.481292 -172.213524)
			(xy 401.30984 -156.935424) (xy 401.291552 -156.907738) (xy 401.276058 -156.901896) (xy 401.249167 -156.891229)
			(xy 401.198698 -156.862957) (xy 401.153071 -156.827396) (xy 401.113329 -156.785361) (xy 401.080382 -156.737811)
			(xy 401.054984 -156.685837) (xy 401.037716 -156.630626) (xy 401.028973 -156.573442) (xy 401.028408 -156.544518)
			(xy 401.028899 -156.516506) (xy 401.037083 -156.461084) (xy 401.053279 -156.407453) (xy 401.077139 -156.356765)
			(xy 401.108149 -156.310108) (xy 401.145646 -156.268483) (xy 401.188822 -156.232785) (xy 401.236753 -156.20378)
			(xy 401.288407 -156.18209) (xy 401.315428 -156.174694) (xy 401.33143 -156.17063) (xy 401.352512 -156.144976)
			(xy 401.3962 -155.342336) (xy 401.393406 -155.340812) (xy 401.35302 -155.332938) (xy 401.327292 -155.32745)
			(xy 401.277544 -155.310346) (xy 401.230616 -155.286573) (xy 401.187397 -155.256581) (xy 401.148705 -155.22094)
			(xy 401.115273 -155.180323) (xy 401.087735 -155.135501) (xy 401.066612 -155.087322) (xy 401.052304 -155.036699)
			(xy 401.045082 -154.984591) (xy 401.044664 -154.958288) (xy 401.045191 -154.929925) (xy 401.053602 -154.873825)
			(xy 401.070222 -154.819588) (xy 401.094686 -154.768408) (xy 401.126454 -154.721411) (xy 401.164827 -154.679633)
			(xy 401.20896 -154.643994) (xy 401.257882 -154.615278) (xy 401.310514 -154.594118) (xy 401.365698 -154.580979)
			(xy 401.393914 -154.57805) (xy 401.425156 -154.57551) (xy 401.43811 -154.570176) (xy 401.473924 -153.907998)
			(xy 401.474031 -153.898174) (xy 401.467686 -153.879601) (xy 401.454809 -153.864789) (xy 401.446238 -153.859992)
			(xy 401.426934 -153.85034) (xy 401.420276 -153.84721) (xy 401.405824 -153.844492) (xy 401.398486 -153.845006)
			(xy 401.392136 -153.845768) (xy 401.378674 -153.851356) (xy 401.372578 -153.856182) (xy 401.352084 -153.872244)
			(xy 401.307571 -153.899258) (xy 401.2598 -153.919974) (xy 401.209658 -153.934008) (xy 401.158074 -153.9411)
			(xy 401.13204 -153.941526) (xy 401.104784 -153.941066) (xy 401.050826 -153.933313) (xy 400.998521 -153.91796)
			(xy 400.948933 -153.895318) (xy 400.903073 -153.86585) (xy 400.861874 -153.830155) (xy 400.826174 -153.788959)
			(xy 400.796701 -153.743102) (xy 400.774054 -153.693517) (xy 400.758695 -153.641213) (xy 400.750937 -153.587256)
			(xy 400.750937 -153.532744) (xy 400.758695 -153.478787) (xy 400.774054 -153.426483) (xy 400.796701 -153.376898)
			(xy 400.826174 -153.331041) (xy 400.861874 -153.289845) (xy 400.903073 -153.25415) (xy 400.948933 -153.224682)
			(xy 400.998521 -153.20204) (xy 401.050826 -153.186687) (xy 401.104784 -153.178934) (xy 401.13204 -153.17851)
			(xy 401.161626 -153.179063) (xy 401.22009 -153.18819) (xy 401.276444 -153.206235) (xy 401.329335 -153.232764)
			(xy 401.377497 -153.267142) (xy 401.398994 -153.287476) (xy 401.399502 -153.287984) (xy 401.406394 -153.294098)
			(xy 401.423303 -153.301373) (xy 401.441693 -153.30218) (xy 401.450556 -153.299668) (xy 401.477988 -153.288746)
			(xy 401.486818 -153.284774) (xy 401.500873 -153.271477) (xy 401.509026 -153.25393) (xy 401.509992 -153.244296)
			(xy 401.597622 -151.627332) (xy 401.597705 -151.617774) (xy 401.591644 -151.59966) (xy 401.579408 -151.584992)
			(xy 401.571206 -151.580088) (xy 401.537678 -151.562054) (xy 401.531257 -151.558787) (xy 401.517192 -151.555694)
			(xy 401.509992 -151.555958) (xy 401.502626 -151.556466) (xy 401.489418 -151.561292) (xy 401.483576 -151.56561)
			(xy 401.459633 -151.582317) (xy 401.407727 -151.609041) (xy 401.35236 -151.62756) (xy 401.294821 -151.637441)
			(xy 401.265644 -151.638508) (xy 401.253452 -151.638508) (xy 401.226462 -151.637647) (xy 401.173119 -151.629255)
			(xy 401.121493 -151.613423) (xy 401.072615 -151.590469) (xy 401.027463 -151.560852) (xy 400.986939 -151.525162)
			(xy 400.951853 -151.484114) (xy 400.922907 -151.438529) (xy 400.90068 -151.389316) (xy 400.885615 -151.337461)
			(xy 400.878013 -151.284) (xy 400.877532 -151.257) (xy 400.877995 -151.229748) (xy 400.885753 -151.175799)
			(xy 400.901109 -151.123504) (xy 400.923752 -151.073926) (xy 400.953221 -151.028076) (xy 400.988915 -150.986887)
			(xy 401.030108 -150.951197) (xy 401.075961 -150.921733) (xy 401.125541 -150.899095) (xy 401.177839 -150.883744)
			(xy 401.231788 -150.875993) (xy 401.25904 -150.875492) (xy 401.286608 -150.87598) (xy 401.341169 -150.883921)
			(xy 401.394019 -150.899631) (xy 401.444058 -150.922783) (xy 401.490245 -150.952895) (xy 401.511262 -150.970742)
			(xy 401.516596 -150.975568) (xy 401.52955 -150.981664) (xy 401.536916 -150.98268) (xy 401.543937 -150.983581)
			(xy 401.557986 -150.981897) (xy 401.564602 -150.979378) (xy 401.60575 -150.961852) (xy 401.618704 -150.956264)
			(xy 401.635468 -150.932642) (xy 401.9423 -145.272506) (xy 401.9423 -145.271998) (xy 402.061426 -142.716758)
			(xy 402.060938 -142.705254) (xy 402.051007 -142.684504) (xy 402.042376 -142.67688) (xy 402.021634 -142.661455)
			(xy 401.984104 -142.625912) (xy 401.951715 -142.585628) (xy 401.925059 -142.541342) (xy 401.904625 -142.493863)
			(xy 401.890786 -142.44406) (xy 401.883796 -142.392845) (xy 401.883372 -142.367) (xy 401.883844 -142.339608)
			(xy 401.891674 -142.285386) (xy 401.907172 -142.23284) (xy 401.930022 -142.183048) (xy 401.959753 -142.137033)
			(xy 401.995755 -142.09574) (xy 402.037289 -142.060016) (xy 402.060156 -142.044928) (xy 402.065236 -142.04188)
			(xy 402.073364 -142.033244) (xy 402.08835 -142.008606) (xy 402.091394 -142.003089) (xy 402.094984 -141.991014)
			(xy 402.095462 -141.98473) (xy 402.255736 -138.553698) (xy 402.257768 -138.520678) (xy 402.41474 -136.561322)
			(xy 402.41474 -136.559798) (xy 402.4757 -135.43407) (xy 402.475799 -135.423821) (xy 402.468862 -135.404553)
			(xy 402.462238 -135.396732) (xy 402.435822 -135.368284) (xy 402.428524 -135.361839) (xy 402.410496 -135.354533)
			(xy 402.40077 -135.35406) (xy 402.39696 -135.35406) (xy 402.366994 -135.353588) (xy 402.307575 -135.34576)
			(xy 402.249686 -135.330243) (xy 402.194318 -135.307303) (xy 402.142417 -135.277332) (xy 402.094873 -135.240843)
			(xy 402.052499 -135.19846) (xy 402.016019 -135.150909) (xy 401.986058 -135.099003) (xy 401.963128 -135.043631)
			(xy 401.947622 -134.985739) (xy 401.939806 -134.926318) (xy 401.939252 -134.896352) (xy 401.939252 -134.032752)
			(xy 401.939745 -134.002785) (xy 401.947573 -133.943366) (xy 401.963089 -133.885476) (xy 401.986028 -133.830106)
			(xy 402.015997 -133.778204) (xy 402.052483 -133.730656) (xy 402.094862 -133.688277) (xy 402.14241 -133.651792)
			(xy 402.194313 -133.621824) (xy 402.249683 -133.598887) (xy 402.307574 -133.583372) (xy 402.366993 -133.575545)
			(xy 402.39696 -133.575044) (xy 402.430467 -133.575594) (xy 402.496776 -133.585288) (xy 402.52904 -133.594348)
			(xy 402.53031 -133.594856) (xy 402.531834 -133.59511) (xy 402.539962 -133.59765) (xy 402.551138 -133.596126)
			(xy 402.55677 -133.595083) (xy 402.567414 -133.59086) (xy 402.57222 -133.587744) (xy 402.58238 -133.580886)
			(xy 402.604986 -133.565392) (xy 402.605748 -133.564884) (xy 402.611874 -133.560201) (xy 402.621182 -133.547917)
			(xy 402.624036 -133.540754) (xy 402.747226 -132.07111) (xy 402.747629 -132.06023) (xy 402.740382 -132.039719)
			(xy 402.733256 -132.031486) (xy 402.733002 -132.031232) (xy 402.712865 -132.009781) (xy 402.678768 -131.961836)
			(xy 402.652434 -131.909225) (xy 402.634489 -131.853195) (xy 402.62937 -131.824222) (xy 402.627846 -131.813808)
			(xy 402.616416 -131.795774) (xy 402.545296 -131.74853) (xy 402.536253 -131.743106) (xy 402.515515 -131.739414)
			(xy 402.505164 -131.741418) (xy 402.50491 -131.741418) (xy 402.486106 -131.745806) (xy 402.447955 -131.751781)
			(xy 402.42871 -131.753356) (xy 402.39696 -131.754372) (xy 402.367005 -131.75388) (xy 402.307609 -131.746058)
			(xy 402.249741 -131.730553) (xy 402.194391 -131.70763) (xy 402.142506 -131.67768) (xy 402.094971 -131.641217)
			(xy 402.052601 -131.598863) (xy 402.016119 -131.551343) (xy 401.986149 -131.499468) (xy 401.963205 -131.444127)
			(xy 401.947677 -131.386266) (xy 401.939832 -131.326872) (xy 401.939252 -131.296918) (xy 401.939252 -130.864864)
			(xy 401.938998 -130.43281) (xy 401.939487 -130.402835) (xy 401.947307 -130.343397) (xy 401.962816 -130.285488)
			(xy 401.985749 -130.230097) (xy 402.015712 -130.178172) (xy 402.052194 -130.1306) (xy 402.094571 -130.088195)
			(xy 402.142119 -130.051681) (xy 402.194024 -130.021683) (xy 402.249399 -129.998714) (xy 402.307299 -129.983167)
			(xy 402.366731 -129.975307) (xy 402.396706 -129.974848) (xy 402.397214 -129.974848) (xy 402.424532 -129.975242)
			(xy 402.47878 -129.981732) (xy 402.505418 -129.987802) (xy 402.515832 -129.990342) (xy 402.536406 -129.986786)
			(xy 402.61667 -129.933446) (xy 402.6281 -129.915666) (xy 402.628608 -129.912364) (xy 402.634027 -129.878916)
			(xy 402.655106 -129.814525) (xy 402.670518 -129.784348) (xy 402.683704 -129.760813) (xy 402.715687 -129.71737)
			(xy 402.753461 -129.678855) (xy 402.796276 -129.646036) (xy 402.84328 -129.619562) (xy 402.89354 -129.599962)
			(xy 402.919692 -129.59334) (xy 402.945854 -129.587244) (xy 402.95576 -129.581656) (xy 403.348952 -124.892562)
			(xy 403.401276 -124.24029) (xy 403.4028 -124.223272) (xy 403.4028 -124.222002) (xy 403.783292 -119.473472)
			(xy 403.789642 -119.416322) (xy 403.924008 -118.448582) (xy 403.924262 -118.443756) (xy 403.914864 -118.414546)
			(xy 403.9108 -118.40845) (xy 403.895265 -118.38463) (xy 403.87067 -118.333357) (xy 403.853968 -118.278998)
			(xy 403.845528 -118.222761) (xy 403.845014 -118.194328) (xy 403.845014 -118.194074) (xy 403.845526 -118.165764)
			(xy 403.853895 -118.109765) (xy 403.87046 -118.055622) (xy 403.894855 -118.004526) (xy 403.926543 -117.957604)
			(xy 403.964827 -117.915888) (xy 403.986492 -117.897656) (xy 403.986746 -117.897656) (xy 403.991826 -117.893338)
			(xy 403.994366 -117.891306) (xy 403.998684 -117.883432) (xy 404.000935 -117.87927) (xy 404.004007 -117.87032)
			(xy 404.00478 -117.865652) (xy 404.251922 -116.089938) (xy 404.252488 -116.084504) (xy 404.251592 -116.073616)
			(xy 404.250144 -116.068348) (xy 404.24735 -116.058696) (xy 404.239984 -116.050314) (xy 404.222698 -116.029474)
			(xy 404.193568 -115.983834) (xy 404.171181 -115.934536) (xy 404.155988 -115.882567) (xy 404.148292 -115.828973)
			(xy 404.147782 -115.801902) (xy 404.147782 -115.801394) (xy 404.148241 -115.774529) (xy 404.155778 -115.72133)
			(xy 404.170703 -115.669714) (xy 404.192721 -115.620702) (xy 404.221396 -115.575262) (xy 404.256161 -115.534295)
			(xy 404.296329 -115.498609) (xy 404.31847 -115.483386) (xy 404.323088 -115.480102) (xy 404.330902 -115.471898)
			(xy 404.333964 -115.46713) (xy 404.339044 -115.459002) (xy 404.734776 -112.61344) (xy 404.73503 -112.612678)
			(xy 404.735538 -112.607598) (xy 404.737824 -112.591342) (xy 404.737824 -112.590834) (xy 405.932894 -103.990394)
			(xy 405.933148 -103.984806) (xy 405.929084 -103.964994) (xy 405.927814 -103.961946) (xy 405.918494 -103.938604)
			(xy 405.905377 -103.890086) (xy 405.898752 -103.840264) (xy 405.89835 -103.815134) (xy 405.89835 -103.81488)
			(xy 405.89835 -103.814372) (xy 405.898955 -103.782656) (xy 405.909424 -103.720097) (xy 405.919178 -103.689912)
			(xy 405.930139 -103.660188) (xy 405.960397 -103.604534) (xy 405.979376 -103.579168) (xy 405.980392 -103.577898)
			(xy 405.98344 -103.574088) (xy 405.991568 -103.555546) (xy 405.995378 -103.542084) (xy 406.051766 -103.133398)
			(xy 406.052143 -103.121131) (xy 406.042846 -103.098458) (xy 406.033986 -103.089964) (xy 406.013137 -103.071754)
			(xy 405.976405 -103.030343) (xy 405.946048 -102.984055) (xy 405.922704 -102.933863) (xy 405.906865 -102.880823)
			(xy 405.898863 -102.826049) (xy 405.89835 -102.798372) (xy 405.898822 -102.771016) (xy 405.906641 -102.716865)
			(xy 405.922115 -102.664386) (xy 405.944925 -102.614655) (xy 405.974606 -102.568692) (xy 406.010547 -102.52744)
			(xy 406.052012 -102.491745) (xy 406.09815 -102.462339) (xy 406.122886 -102.450646) (xy 406.13057 -102.446814)
			(xy 406.143007 -102.434991) (xy 406.150856 -102.41973) (xy 406.15235 -102.411276) (xy 406.165812 -102.314248)
			(xy 406.182576 -102.192582) (xy 406.182871 -102.18197) (xy 406.175858 -102.16196) (xy 406.161364 -102.146483)
			(xy 406.151842 -102.141782) (xy 406.124405 -102.131444) (xy 406.072832 -102.103559) (xy 406.026132 -102.068112)
			(xy 405.985405 -102.025938) (xy 405.95161 -101.978028) (xy 405.925543 -101.925512) (xy 405.907818 -101.869626)
			(xy 405.898852 -101.811687) (xy 405.89835 -101.782372) (xy 405.89887 -101.753662) (xy 405.907477 -101.69689)
			(xy 405.924491 -101.642048) (xy 405.949529 -101.590373) (xy 405.982025 -101.543033) (xy 406.021247 -101.501095)
			(xy 406.066309 -101.465506) (xy 406.116194 -101.43707) (xy 406.169776 -101.416427) (xy 406.225845 -101.404044)
			(xy 406.254458 -101.401626) (xy 406.254712 -101.401626) (xy 406.269952 -101.40061) (xy 406.296114 -101.375972)
			(xy 406.312878 -101.255576) (xy 406.313126 -101.246409) (xy 406.307917 -101.22884) (xy 406.302718 -101.221286)
			(xy 406.302718 -101.221032) (xy 406.258522 -101.162358) (xy 406.252669 -101.155688) (xy 406.237449 -101.146584)
			(xy 406.228804 -101.144578) (xy 406.22601 -101.14407) (xy 406.199075 -101.139757) (xy 406.146723 -101.124439)
			(xy 406.097086 -101.101821) (xy 406.051177 -101.072364) (xy 406.009931 -101.036668) (xy 405.974189 -100.995462)
			(xy 405.944681 -100.949585) (xy 405.922008 -100.899973) (xy 405.906633 -100.847637) (xy 405.898867 -100.793646)
			(xy 405.89835 -100.766372) (xy 405.898838 -100.739121) (xy 405.906597 -100.685174) (xy 405.921954 -100.63288)
			(xy 405.944596 -100.583304) (xy 405.974063 -100.537454) (xy 406.009754 -100.496264) (xy 406.050943 -100.460571)
			(xy 406.096792 -100.431103) (xy 406.146367 -100.408459) (xy 406.19866 -100.3931) (xy 406.252607 -100.385339)
			(xy 406.279858 -100.384864) (xy 406.292726 -100.384999) (xy 406.318402 -100.386778) (xy 406.331166 -100.38842)
			(xy 406.341326 -100.38969) (xy 406.35047 -100.387404) (xy 406.355324 -100.386054) (xy 406.364406 -100.381699)
			(xy 406.368504 -100.378768) (xy 406.38222 -100.368354) (xy 406.425908 -100.33508) (xy 406.433554 -100.328638)
			(xy 406.443601 -100.311377) (xy 406.445466 -100.301552) (xy 407.576782 -92.160852) (xy 407.577036 -92.160344)
			(xy 407.577798 -92.154502) (xy 407.578052 -92.151962) (xy 407.57983 -92.138754) (xy 408.183842 -87.790528)
			(xy 408.184713 -87.781835) (xy 408.181194 -87.764734) (xy 408.172107 -87.749826) (xy 408.165554 -87.744046)
			(xy 408.120088 -87.707724) (xy 408.095704 -87.688166) (xy 408.085187 -87.681211) (xy 408.060263 -87.677615)
			(xy 408.048206 -87.681308) (xy 408.047952 -87.681308) (xy 408.015935 -87.692417) (xy 407.949245 -87.704425)
			(xy 407.915364 -87.705184) (xy 407.888116 -87.704695) (xy 407.834176 -87.696935) (xy 407.781889 -87.681578)
			(xy 407.732319 -87.658936) (xy 407.686476 -87.629471) (xy 407.645293 -87.593782) (xy 407.609608 -87.552595)
			(xy 407.580147 -87.506749) (xy 407.55751 -87.457178) (xy 407.542157 -87.404889) (xy 407.534402 -87.350948)
			(xy 407.534402 -87.296452) (xy 407.542157 -87.242511) (xy 407.55751 -87.190222) (xy 407.580147 -87.140651)
			(xy 407.609608 -87.094805) (xy 407.645293 -87.053618) (xy 407.686476 -87.017929) (xy 407.732319 -86.988464)
			(xy 407.781889 -86.965822) (xy 407.834176 -86.950465) (xy 407.888116 -86.942705) (xy 407.915364 -86.942168)
			(xy 407.915364 -86.941914) (xy 407.945511 -86.942476) (xy 408.005056 -86.951952) (xy 408.062365 -86.970688)
			(xy 408.116007 -86.998216) (xy 408.140662 -87.015574) (xy 408.147697 -87.02034) (xy 408.163928 -87.025336)
			(xy 408.1809 -87.024723) (xy 408.188922 -87.021924) (xy 408.27071 -86.98738) (xy 408.281586 -86.982036)
			(xy 408.29711 -86.963474) (xy 408.300428 -86.95182) (xy 408.30119 -86.947756) (xy 408.585162 -84.90331)
			(xy 408.586153 -84.891623) (xy 408.57874 -84.869396) (xy 408.570938 -84.860638) (xy 408.528012 -84.817458)
			(xy 408.513534 -84.80298) (xy 408.509328 -84.79895) (xy 408.499445 -84.792792) (xy 408.493976 -84.790788)
			(xy 408.483054 -84.786978) (xy 408.470862 -84.788756) (xy 408.457594 -84.790469) (xy 408.430899 -84.79225)
			(xy 408.417522 -84.792312) (xy 408.390316 -84.79176) (xy 408.336474 -84.78389) (xy 408.284297 -84.768451)
			(xy 408.234842 -84.745754) (xy 408.189114 -84.716261) (xy 408.14804 -84.68057) (xy 408.112454 -84.639406)
			(xy 408.083078 -84.593602) (xy 408.060508 -84.54409) (xy 408.045202 -84.491873) (xy 408.03747 -84.438011)
			(xy 408.03703 -84.410804) (xy 408.037506 -84.383689) (xy 408.045183 -84.330006) (xy 408.060384 -84.277951)
			(xy 408.082801 -84.228572) (xy 408.111984 -84.182865) (xy 408.147344 -84.141749) (xy 408.18817 -84.106055)
			(xy 408.233637 -84.0765) (xy 408.282832 -84.05368) (xy 408.334761 -84.038055) (xy 408.38838 -84.02994)
			(xy 408.41549 -84.029296) (xy 408.419046 -84.029296) (xy 408.445237 -84.029748) (xy 408.497121 -84.036958)
			(xy 408.547527 -84.051207) (xy 408.5717 -84.0613) (xy 408.577139 -84.063527) (xy 408.588684 -84.065713)
			(xy 408.59456 -84.065618) (xy 408.606244 -84.06511) (xy 408.690064 -84.01812) (xy 408.698491 -84.012231)
			(xy 408.710155 -83.995323) (xy 408.71267 -83.985354) (xy 409.139136 -80.91805) (xy 409.72867 -76.675488)
			(xy 409.730318 -76.666517) (xy 409.739021 -76.650501) (xy 409.752778 -76.638543) (xy 409.769849 -76.632153)
			(xy 409.778962 -76.6318) (xy 409.786328 -76.6318) (xy 410.041598 -74.809858) (xy 410.042623 -74.798977)
			(xy 410.036448 -74.778036) (xy 410.02966 -74.769472) (xy 410.022548 -74.76109) (xy 410.002736 -74.7522)
			(xy 408.905456 -74.7522) (xy 408.895189 -74.752678) (xy 408.876303 -74.760737) (xy 408.862082 -74.77555)
			(xy 408.857958 -74.784966) (xy 404.900384 -85.237574) (xy 404.906734 -85.246972) (xy 404.969472 -85.312504)
			(xy 404.96998 -85.313012) (xy 404.972774 -85.315806) (xy 404.97788 -85.32066) (xy 404.990119 -85.327628)
			(xy 404.996904 -85.329522) (xy 405.004016 -85.3313) (xy 405.017986 -85.330792) (xy 405.025352 -85.328252)
			(xy 405.054958 -85.318887) (xy 405.116226 -85.308804) (xy 405.147272 -85.308186) (xy 405.14905 -85.308186)
			(xy 405.176229 -85.308777) (xy 405.230009 -85.316712) (xy 405.282119 -85.332201) (xy 405.331502 -85.35493)
			(xy 405.377158 -85.384439) (xy 405.418164 -85.420129) (xy 405.453688 -85.461279) (xy 405.483012 -85.507055)
			(xy 405.505541 -85.556529) (xy 405.520818 -85.608701) (xy 405.528536 -85.662513) (xy 405.529034 -85.689694)
			(xy 405.528549 -85.716946) (xy 405.520793 -85.770896) (xy 405.505439 -85.823193) (xy 405.482798 -85.872773)
			(xy 405.453332 -85.918626) (xy 405.417641 -85.959819) (xy 405.376451 -85.995513) (xy 405.330601 -86.024983)
			(xy 405.281023 -86.047627) (xy 405.228727 -86.062986) (xy 405.174778 -86.070746) (xy 405.147526 -86.071202)
			(xy 405.119755 -86.070703) (xy 405.064799 -86.062653) (xy 405.011591 -86.046718) (xy 404.961256 -86.023236)
			(xy 404.914858 -85.992703) (xy 404.873379 -85.955765) (xy 404.837694 -85.913203) (xy 404.82266 -85.889846)
			(xy 404.819358 -85.884512) (xy 404.810468 -85.875876) (xy 404.772622 -85.853778) (xy 404.77059 -85.854032)
			(xy 404.674832 -85.861398) (xy 404.663148 -85.864192) (xy 404.219322 -87.036402) (xy 404.775668 -87.036402)
			(xy 404.779739 -86.98078) (xy 404.791865 -86.926343) (xy 404.811788 -86.874252) (xy 404.839084 -86.825617)
			(xy 404.87317 -86.781474) (xy 404.913319 -86.742765) (xy 404.958677 -86.710314) (xy 405.008277 -86.684813)
			(xy 405.061061 -86.666806) (xy 405.115904 -86.656676) (xy 405.171638 -86.654639) (xy 405.227075 -86.660739)
			(xy 405.281032 -86.674845) (xy 405.332361 -86.696657) (xy 405.379967 -86.725711) (xy 405.422835 -86.761386)
			(xy 405.460052 -86.802923) (xy 405.490825 -86.849436) (xy 405.514497 -86.899933) (xy 405.530565 -86.95334)
			(xy 405.538685 -87.008516) (xy 405.539194 -87.036402) (xy 405.538685 -87.064288) (xy 405.530565 -87.119464)
			(xy 405.514497 -87.172871) (xy 405.490825 -87.223368) (xy 405.460052 -87.269881) (xy 405.422835 -87.311418)
			(xy 405.379967 -87.347093) (xy 405.332361 -87.376147) (xy 405.281032 -87.397959) (xy 405.227075 -87.412065)
			(xy 405.171638 -87.418165) (xy 405.115904 -87.416128) (xy 405.061061 -87.405998) (xy 405.008277 -87.387991)
			(xy 404.958677 -87.36249) (xy 404.913319 -87.330039) (xy 404.87317 -87.29133) (xy 404.839084 -87.247187)
			(xy 404.811788 -87.198552) (xy 404.791865 -87.146461) (xy 404.779739 -87.092024) (xy 404.775668 -87.036402)
			(xy 404.219322 -87.036402) (xy 403.41909 -89.149936) (xy 404.612346 -89.149936) (xy 404.616417 -89.094314)
			(xy 404.628543 -89.039877) (xy 404.648466 -88.987786) (xy 404.675762 -88.939151) (xy 404.709848 -88.895008)
			(xy 404.749997 -88.856299) (xy 404.795355 -88.823848) (xy 404.844955 -88.798347) (xy 404.897739 -88.78034)
			(xy 404.952582 -88.77021) (xy 405.008316 -88.768173) (xy 405.063753 -88.774273) (xy 405.11771 -88.788379)
			(xy 405.169039 -88.810191) (xy 405.216645 -88.839245) (xy 405.259513 -88.87492) (xy 405.29673 -88.916457)
			(xy 405.327503 -88.96297) (xy 405.351175 -89.013467) (xy 405.367243 -89.066874) (xy 405.375363 -89.12205)
			(xy 405.375872 -89.149936) (xy 405.37558 -89.165938) (xy 406.561034 -89.165938) (xy 406.565105 -89.110316)
			(xy 406.577231 -89.055879) (xy 406.597154 -89.003788) (xy 406.62445 -88.955153) (xy 406.658536 -88.91101)
			(xy 406.698685 -88.872301) (xy 406.744043 -88.83985) (xy 406.793643 -88.814349) (xy 406.846427 -88.796342)
			(xy 406.90127 -88.786212) (xy 406.957004 -88.784175) (xy 407.012441 -88.790275) (xy 407.066398 -88.804381)
			(xy 407.117727 -88.826193) (xy 407.165333 -88.855247) (xy 407.208201 -88.890922) (xy 407.245418 -88.932459)
			(xy 407.276191 -88.978972) (xy 407.299863 -89.029469) (xy 407.315931 -89.082876) (xy 407.324051 -89.138052)
			(xy 407.32456 -89.165938) (xy 407.324051 -89.193824) (xy 407.315931 -89.249) (xy 407.299863 -89.302407)
			(xy 407.276191 -89.352904) (xy 407.245418 -89.399417) (xy 407.208201 -89.440954) (xy 407.165333 -89.476629)
			(xy 407.117727 -89.505683) (xy 407.066398 -89.527495) (xy 407.012441 -89.541601) (xy 406.957004 -89.547701)
			(xy 406.90127 -89.545664) (xy 406.846427 -89.535534) (xy 406.793643 -89.517527) (xy 406.744043 -89.492026)
			(xy 406.698685 -89.459575) (xy 406.658536 -89.420866) (xy 406.62445 -89.376723) (xy 406.597154 -89.328088)
			(xy 406.577231 -89.275997) (xy 406.565105 -89.22156) (xy 406.561034 -89.165938) (xy 405.37558 -89.165938)
			(xy 405.375363 -89.177822) (xy 405.367243 -89.232998) (xy 405.351175 -89.286405) (xy 405.327503 -89.336902)
			(xy 405.29673 -89.383415) (xy 405.259513 -89.424952) (xy 405.216645 -89.460627) (xy 405.169039 -89.489681)
			(xy 405.11771 -89.511493) (xy 405.063753 -89.525599) (xy 405.008316 -89.531699) (xy 404.952582 -89.529662)
			(xy 404.897739 -89.519532) (xy 404.844955 -89.501525) (xy 404.795355 -89.476024) (xy 404.749997 -89.443573)
			(xy 404.709848 -89.404864) (xy 404.675762 -89.360721) (xy 404.648466 -89.312086) (xy 404.628543 -89.259995)
			(xy 404.616417 -89.205558) (xy 404.612346 -89.149936) (xy 403.41909 -89.149936) (xy 401.04859 -95.410782)
			(xy 405.066244 -95.410782) (xy 405.070315 -95.35516) (xy 405.082441 -95.300723) (xy 405.102364 -95.248632)
			(xy 405.12966 -95.199997) (xy 405.163746 -95.155854) (xy 405.203895 -95.117145) (xy 405.249253 -95.084694)
			(xy 405.298853 -95.059193) (xy 405.351637 -95.041186) (xy 405.40648 -95.031056) (xy 405.462214 -95.029019)
			(xy 405.517651 -95.035119) (xy 405.571608 -95.049225) (xy 405.622937 -95.071037) (xy 405.670543 -95.100091)
			(xy 405.713411 -95.135766) (xy 405.750628 -95.177303) (xy 405.781401 -95.223816) (xy 405.805073 -95.274313)
			(xy 405.821141 -95.32772) (xy 405.829261 -95.382896) (xy 405.82977 -95.410782) (xy 405.829261 -95.438668)
			(xy 405.821141 -95.493844) (xy 405.805073 -95.547251) (xy 405.781401 -95.597748) (xy 405.750628 -95.644261)
			(xy 405.713411 -95.685798) (xy 405.670543 -95.721473) (xy 405.622937 -95.750527) (xy 405.571608 -95.772339)
			(xy 405.517651 -95.786445) (xy 405.462214 -95.792545) (xy 405.40648 -95.790508) (xy 405.351637 -95.780378)
			(xy 405.298853 -95.762371) (xy 405.249253 -95.73687) (xy 405.203895 -95.704419) (xy 405.163746 -95.66571)
			(xy 405.12966 -95.621567) (xy 405.102364 -95.572932) (xy 405.082441 -95.520841) (xy 405.070315 -95.466404)
			(xy 405.066244 -95.410782) (xy 401.04859 -95.410782) (xy 400.784314 -96.108774) (xy 400.782536 -96.1136)
			(xy 400.69016 -96.45904) (xy 405.137618 -96.45904) (xy 405.141689 -96.403418) (xy 405.153815 -96.348981)
			(xy 405.173738 -96.29689) (xy 405.201034 -96.248255) (xy 405.23512 -96.204112) (xy 405.275269 -96.165403)
			(xy 405.320627 -96.132952) (xy 405.370227 -96.107451) (xy 405.423011 -96.089444) (xy 405.477854 -96.079314)
			(xy 405.533588 -96.077277) (xy 405.589025 -96.083377) (xy 405.642982 -96.097483) (xy 405.694311 -96.119295)
			(xy 405.741917 -96.148349) (xy 405.784785 -96.184024) (xy 405.822002 -96.225561) (xy 405.852775 -96.272074)
			(xy 405.876447 -96.322571) (xy 405.892515 -96.375978) (xy 405.900635 -96.431154) (xy 405.901144 -96.45904)
			(xy 405.900635 -96.486926) (xy 405.892515 -96.542102) (xy 405.876447 -96.595509) (xy 405.852775 -96.646006)
			(xy 405.822002 -96.692519) (xy 405.784785 -96.734056) (xy 405.741917 -96.769731) (xy 405.694311 -96.798785)
			(xy 405.642982 -96.820597) (xy 405.589025 -96.834703) (xy 405.533588 -96.840803) (xy 405.477854 -96.838766)
			(xy 405.423011 -96.828636) (xy 405.370227 -96.810629) (xy 405.320627 -96.785128) (xy 405.275269 -96.752677)
			(xy 405.23512 -96.713968) (xy 405.201034 -96.669825) (xy 405.173738 -96.62119) (xy 405.153815 -96.569099)
			(xy 405.141689 -96.514662) (xy 405.137618 -96.45904) (xy 400.69016 -96.45904) (xy 400.595338 -96.813624)
			(xy 400.598894 -96.83496) (xy 400.60499 -96.844104) (xy 400.620119 -96.867725) (xy 400.644034 -96.918462)
			(xy 400.66027 -96.972152) (xy 400.668478 -97.02764) (xy 400.668998 -97.055686) (xy 400.668538 -97.082181)
			(xy 400.661197 -97.13466) (xy 400.646667 -97.185619) (xy 400.625228 -97.234078) (xy 400.597291 -97.279105)
			(xy 400.563395 -97.319836) (xy 400.524191 -97.355486) (xy 400.480432 -97.385371) (xy 400.456908 -97.39757)
			(xy 400.447002 -97.402396) (xy 400.433286 -97.41916) (xy 400.143218 -98.50374) (xy 400.153124 -98.53295)
			(xy 400.159728 -98.53803) (xy 400.183319 -98.556164) (xy 400.225112 -98.598512) (xy 400.25983 -98.646832)
			(xy 400.286631 -98.699952) (xy 400.304867 -98.756588) (xy 400.314095 -98.815367) (xy 400.314668 -98.845116)
			(xy 400.314192 -98.87264) (xy 400.306293 -98.92712) (xy 400.290648 -98.979898) (xy 400.26758 -99.029881)
			(xy 400.23757 -99.07603) (xy 400.201239 -99.117387) (xy 400.159342 -99.153094) (xy 400.112748 -99.18241)
			(xy 400.062426 -99.204726) (xy 400.009418 -99.219579) (xy 399.982182 -99.223576) (xy 399.967704 -99.225608)
			(xy 399.944844 -99.245674) (xy 399.695885 -100.17633) (xy 401.939252 -100.17633) (xy 401.939252 -99.31273)
			(xy 401.939742 -99.282762) (xy 401.947565 -99.22334) (xy 401.963078 -99.165447) (xy 401.986014 -99.110074)
			(xy 402.015981 -99.058168) (xy 402.052468 -99.010618) (xy 402.094848 -98.968238) (xy 402.142398 -98.931751)
			(xy 402.194304 -98.901784) (xy 402.249677 -98.878848) (xy 402.30757 -98.863335) (xy 402.366992 -98.855512)
			(xy 402.426928 -98.855512) (xy 402.48635 -98.863335) (xy 402.544243 -98.878848) (xy 402.599616 -98.901784)
			(xy 402.651522 -98.931751) (xy 402.699072 -98.968238) (xy 402.741452 -99.010618) (xy 402.777939 -99.058168)
			(xy 402.807906 -99.110074) (xy 402.830842 -99.165447) (xy 402.846355 -99.22334) (xy 402.854178 -99.282762)
			(xy 402.854668 -99.31273) (xy 402.854668 -100.17633) (xy 402.854178 -100.206298) (xy 402.846355 -100.26572)
			(xy 402.830842 -100.323613) (xy 402.807906 -100.378986) (xy 402.777939 -100.430892) (xy 402.741452 -100.478442)
			(xy 402.699072 -100.520822) (xy 402.651522 -100.557309) (xy 402.599616 -100.587276) (xy 402.544243 -100.610212)
			(xy 402.48635 -100.625725) (xy 402.426928 -100.633548) (xy 402.366992 -100.633548) (xy 402.30757 -100.625725)
			(xy 402.249677 -100.610212) (xy 402.194304 -100.587276) (xy 402.142398 -100.557309) (xy 402.094848 -100.520822)
			(xy 402.052468 -100.478442) (xy 402.015981 -100.430892) (xy 401.986014 -100.378986) (xy 401.963078 -100.323613)
			(xy 401.947565 -100.26572) (xy 401.939742 -100.206298) (xy 401.939252 -100.17633) (xy 399.695885 -100.17633)
			(xy 399.214342 -101.976428) (xy 400.085052 -101.976428) (xy 400.085052 -101.112828) (xy 400.085542 -101.08286)
			(xy 400.093365 -101.023438) (xy 400.108878 -100.965545) (xy 400.131814 -100.910172) (xy 400.161781 -100.858266)
			(xy 400.198268 -100.810716) (xy 400.240648 -100.768336) (xy 400.288198 -100.731849) (xy 400.340104 -100.701882)
			(xy 400.395477 -100.678946) (xy 400.45337 -100.663433) (xy 400.512792 -100.65561) (xy 400.572728 -100.65561)
			(xy 400.63215 -100.663433) (xy 400.690043 -100.678946) (xy 400.745416 -100.701882) (xy 400.797322 -100.731849)
			(xy 400.844872 -100.768336) (xy 400.887252 -100.810716) (xy 400.923739 -100.858266) (xy 400.953706 -100.910172)
			(xy 400.976642 -100.965545) (xy 400.992155 -101.023438) (xy 400.999978 -101.08286) (xy 401.000468 -101.112828)
			(xy 401.000468 -101.976428) (xy 400.999978 -102.006396) (xy 400.992155 -102.065818) (xy 400.976642 -102.123711)
			(xy 400.953706 -102.179084) (xy 400.923739 -102.23099) (xy 400.887252 -102.27854) (xy 400.844872 -102.32092)
			(xy 400.797322 -102.357407) (xy 400.745416 -102.387374) (xy 400.690043 -102.41031) (xy 400.63215 -102.425823)
			(xy 400.572728 -102.433646) (xy 400.512792 -102.433646) (xy 400.45337 -102.425823) (xy 400.395477 -102.41031)
			(xy 400.340104 -102.387374) (xy 400.288198 -102.357407) (xy 400.240648 -102.32092) (xy 400.198268 -102.27854)
			(xy 400.161781 -102.23099) (xy 400.131814 -102.179084) (xy 400.108878 -102.123711) (xy 400.093365 -102.065818)
			(xy 400.085542 -102.006396) (xy 400.085052 -101.976428) (xy 399.214342 -101.976428) (xy 398.732867 -103.776272)
			(xy 401.939252 -103.776272) (xy 401.939252 -102.912672) (xy 401.939742 -102.882704) (xy 401.947565 -102.823282)
			(xy 401.963078 -102.765389) (xy 401.986014 -102.710016) (xy 402.015981 -102.65811) (xy 402.052468 -102.61056)
			(xy 402.094848 -102.56818) (xy 402.142398 -102.531693) (xy 402.194304 -102.501726) (xy 402.249677 -102.47879)
			(xy 402.30757 -102.463277) (xy 402.366992 -102.455454) (xy 402.426928 -102.455454) (xy 402.48635 -102.463277)
			(xy 402.544243 -102.47879) (xy 402.599616 -102.501726) (xy 402.651522 -102.531693) (xy 402.699072 -102.56818)
			(xy 402.741452 -102.61056) (xy 402.777939 -102.65811) (xy 402.807906 -102.710016) (xy 402.830842 -102.765389)
			(xy 402.846355 -102.823282) (xy 402.854178 -102.882704) (xy 402.854668 -102.912672) (xy 402.854668 -103.776272)
			(xy 402.854178 -103.80624) (xy 402.846355 -103.865662) (xy 402.830842 -103.923555) (xy 402.807906 -103.978928)
			(xy 402.777939 -104.030834) (xy 402.741452 -104.078384) (xy 402.699072 -104.120764) (xy 402.651522 -104.157251)
			(xy 402.599616 -104.187218) (xy 402.544243 -104.210154) (xy 402.48635 -104.225667) (xy 402.426928 -104.23349)
			(xy 402.366992 -104.23349) (xy 402.30757 -104.225667) (xy 402.249677 -104.210154) (xy 402.194304 -104.187218)
			(xy 402.142398 -104.157251) (xy 402.094848 -104.120764) (xy 402.052468 -104.078384) (xy 402.015981 -104.030834)
			(xy 401.986014 -103.978928) (xy 401.963078 -103.923555) (xy 401.947565 -103.865662) (xy 401.939742 -103.80624)
			(xy 401.939252 -103.776272) (xy 398.732867 -103.776272) (xy 398.251324 -105.57637) (xy 400.085052 -105.57637)
			(xy 400.085052 -104.71277) (xy 400.085542 -104.682802) (xy 400.093365 -104.62338) (xy 400.108878 -104.565487)
			(xy 400.131814 -104.510114) (xy 400.161781 -104.458208) (xy 400.198268 -104.410658) (xy 400.240648 -104.368278)
			(xy 400.288198 -104.331791) (xy 400.340104 -104.301824) (xy 400.395477 -104.278888) (xy 400.45337 -104.263375)
			(xy 400.512792 -104.255552) (xy 400.572728 -104.255552) (xy 400.63215 -104.263375) (xy 400.690043 -104.278888)
			(xy 400.745416 -104.301824) (xy 400.797322 -104.331791) (xy 400.844872 -104.368278) (xy 400.887252 -104.410658)
			(xy 400.923739 -104.458208) (xy 400.953706 -104.510114) (xy 400.976642 -104.565487) (xy 400.992155 -104.62338)
			(xy 400.999978 -104.682802) (xy 401.000468 -104.71277) (xy 401.000468 -105.57637) (xy 400.999978 -105.606338)
			(xy 400.992155 -105.66576) (xy 400.976642 -105.723653) (xy 400.953706 -105.779026) (xy 400.923739 -105.830932)
			(xy 400.887252 -105.878482) (xy 400.844872 -105.920862) (xy 400.797322 -105.957349) (xy 400.745416 -105.987316)
			(xy 400.690043 -106.010252) (xy 400.63215 -106.025765) (xy 400.572728 -106.033588) (xy 400.512792 -106.033588)
			(xy 400.45337 -106.025765) (xy 400.395477 -106.010252) (xy 400.340104 -105.987316) (xy 400.288198 -105.957349)
			(xy 400.240648 -105.920862) (xy 400.198268 -105.878482) (xy 400.161781 -105.830932) (xy 400.131814 -105.779026)
			(xy 400.108878 -105.723653) (xy 400.093365 -105.66576) (xy 400.085542 -105.606338) (xy 400.085052 -105.57637)
			(xy 398.251324 -105.57637) (xy 397.858996 -107.042966) (xy 397.866616 -107.049824) (xy 397.891762 -107.062016)
			(xy 397.89227 -107.062524) (xy 397.916429 -107.074454) (xy 397.961418 -107.104099) (xy 398.001789 -107.13978)
			(xy 398.036737 -107.180788) (xy 398.065566 -107.226304) (xy 398.087704 -107.275425) (xy 398.102709 -107.327173)
			(xy 398.109672 -107.376214) (xy 401.939252 -107.376214) (xy 401.939252 -106.512614) (xy 401.939742 -106.482646)
			(xy 401.947565 -106.423224) (xy 401.963078 -106.365331) (xy 401.986014 -106.309958) (xy 402.015981 -106.258052)
			(xy 402.052468 -106.210502) (xy 402.094848 -106.168122) (xy 402.142398 -106.131635) (xy 402.194304 -106.101668)
			(xy 402.249677 -106.078732) (xy 402.30757 -106.063219) (xy 402.366992 -106.055396) (xy 402.426928 -106.055396)
			(xy 402.48635 -106.063219) (xy 402.544243 -106.078732) (xy 402.599616 -106.101668) (xy 402.651522 -106.131635)
			(xy 402.699072 -106.168122) (xy 402.741452 -106.210502) (xy 402.777939 -106.258052) (xy 402.807906 -106.309958)
			(xy 402.830842 -106.365331) (xy 402.846355 -106.423224) (xy 402.854178 -106.482646) (xy 402.854668 -106.512614)
			(xy 402.854668 -107.376214) (xy 402.854178 -107.406182) (xy 402.846355 -107.465604) (xy 402.830842 -107.523497)
			(xy 402.807906 -107.57887) (xy 402.777939 -107.630776) (xy 402.741452 -107.678326) (xy 402.699072 -107.720706)
			(xy 402.651522 -107.757193) (xy 402.599616 -107.78716) (xy 402.544243 -107.810096) (xy 402.48635 -107.825609)
			(xy 402.426928 -107.833432) (xy 402.366992 -107.833432) (xy 402.30757 -107.825609) (xy 402.249677 -107.810096)
			(xy 402.194304 -107.78716) (xy 402.142398 -107.757193) (xy 402.094848 -107.720706) (xy 402.052468 -107.678326)
			(xy 402.015981 -107.630776) (xy 401.986014 -107.57887) (xy 401.963078 -107.523497) (xy 401.947565 -107.465604)
			(xy 401.939742 -107.406182) (xy 401.939252 -107.376214) (xy 398.109672 -107.376214) (xy 398.110283 -107.380516)
			(xy 398.11071 -107.407456) (xy 398.11025 -107.434711) (xy 398.102498 -107.488667) (xy 398.087146 -107.54097)
			(xy 398.064506 -107.590556) (xy 398.035039 -107.636415) (xy 397.999345 -107.677613) (xy 397.958151 -107.713311)
			(xy 397.912296 -107.742784) (xy 397.862713 -107.765429) (xy 397.810412 -107.780788) (xy 397.756457 -107.788546)
			(xy 397.729202 -107.788964) (xy 397.72844 -107.788964) (xy 397.69415 -107.78744) (xy 397.693134 -107.78744)
			(xy 397.679164 -107.786424) (xy 397.67389 -107.786732) (xy 397.663644 -107.789296) (xy 397.658844 -107.791504)
			(xy 397.28829 -109.176312) (xy 400.085052 -109.176312) (xy 400.085052 -108.312712) (xy 400.085542 -108.282744)
			(xy 400.093365 -108.223322) (xy 400.108878 -108.165429) (xy 400.131814 -108.110056) (xy 400.161781 -108.05815)
			(xy 400.198268 -108.0106) (xy 400.240648 -107.96822) (xy 400.288198 -107.931733) (xy 400.340104 -107.901766)
			(xy 400.395477 -107.87883) (xy 400.45337 -107.863317) (xy 400.512792 -107.855494) (xy 400.572728 -107.855494)
			(xy 400.63215 -107.863317) (xy 400.690043 -107.87883) (xy 400.745416 -107.901766) (xy 400.797322 -107.931733)
			(xy 400.844872 -107.96822) (xy 400.887252 -108.0106) (xy 400.923739 -108.05815) (xy 400.953706 -108.110056)
			(xy 400.976642 -108.165429) (xy 400.992155 -108.223322) (xy 400.999978 -108.282744) (xy 401.000468 -108.312712)
			(xy 401.000468 -109.176312) (xy 400.999978 -109.20628) (xy 400.992155 -109.265702) (xy 400.976642 -109.323595)
			(xy 400.953706 -109.378968) (xy 400.923739 -109.430874) (xy 400.887252 -109.478424) (xy 400.844872 -109.520804)
			(xy 400.797322 -109.557291) (xy 400.745416 -109.587258) (xy 400.690043 -109.610194) (xy 400.63215 -109.625707)
			(xy 400.572728 -109.63353) (xy 400.512792 -109.63353) (xy 400.45337 -109.625707) (xy 400.395477 -109.610194)
			(xy 400.340104 -109.587258) (xy 400.288198 -109.557291) (xy 400.240648 -109.520804) (xy 400.198268 -109.478424)
			(xy 400.161781 -109.430874) (xy 400.131814 -109.378968) (xy 400.108878 -109.323595) (xy 400.093365 -109.265702)
			(xy 400.085542 -109.20628) (xy 400.085052 -109.176312) (xy 397.28829 -109.176312) (xy 397.007588 -110.225332)
			(xy 397.007588 -110.22584) (xy 396.812474 -110.97641) (xy 401.939252 -110.97641) (xy 401.939252 -110.11281)
			(xy 401.939742 -110.082842) (xy 401.947565 -110.02342) (xy 401.963078 -109.965527) (xy 401.986014 -109.910154)
			(xy 402.015981 -109.858248) (xy 402.052468 -109.810698) (xy 402.094848 -109.768318) (xy 402.142398 -109.731831)
			(xy 402.194304 -109.701864) (xy 402.249677 -109.678928) (xy 402.30757 -109.663415) (xy 402.366992 -109.655592)
			(xy 402.426928 -109.655592) (xy 402.48635 -109.663415) (xy 402.544243 -109.678928) (xy 402.599616 -109.701864)
			(xy 402.651522 -109.731831) (xy 402.699072 -109.768318) (xy 402.741452 -109.810698) (xy 402.777939 -109.858248)
			(xy 402.807906 -109.910154) (xy 402.830842 -109.965527) (xy 402.846355 -110.02342) (xy 402.854178 -110.082842)
			(xy 402.854668 -110.11281) (xy 402.854668 -110.97641) (xy 402.854178 -111.006378) (xy 402.846355 -111.0658)
			(xy 402.830842 -111.123693) (xy 402.807906 -111.179066) (xy 402.777939 -111.230972) (xy 402.741452 -111.278522)
			(xy 402.699072 -111.320902) (xy 402.651522 -111.357389) (xy 402.599616 -111.387356) (xy 402.544243 -111.410292)
			(xy 402.48635 -111.425805) (xy 402.426928 -111.433628) (xy 402.366992 -111.433628) (xy 402.30757 -111.425805)
			(xy 402.249677 -111.410292) (xy 402.194304 -111.387356) (xy 402.142398 -111.357389) (xy 402.094848 -111.320902)
			(xy 402.052468 -111.278522) (xy 402.015981 -111.230972) (xy 401.986014 -111.179066) (xy 401.963078 -111.123693)
			(xy 401.947565 -111.0658) (xy 401.939742 -111.006378) (xy 401.939252 -110.97641) (xy 396.812474 -110.97641)
			(xy 396.344529 -112.776508) (xy 400.085052 -112.776508) (xy 400.085052 -111.912908) (xy 400.085542 -111.88294)
			(xy 400.093365 -111.823518) (xy 400.108878 -111.765625) (xy 400.131814 -111.710252) (xy 400.161781 -111.658346)
			(xy 400.198268 -111.610796) (xy 400.240648 -111.568416) (xy 400.288198 -111.531929) (xy 400.340104 -111.501962)
			(xy 400.395477 -111.479026) (xy 400.45337 -111.463513) (xy 400.512792 -111.45569) (xy 400.572728 -111.45569)
			(xy 400.63215 -111.463513) (xy 400.690043 -111.479026) (xy 400.745416 -111.501962) (xy 400.797322 -111.531929)
			(xy 400.844872 -111.568416) (xy 400.887252 -111.610796) (xy 400.923739 -111.658346) (xy 400.953706 -111.710252)
			(xy 400.976642 -111.765625) (xy 400.992155 -111.823518) (xy 400.999978 -111.88294) (xy 401.000468 -111.912908)
			(xy 401.000468 -112.776508) (xy 400.999978 -112.806476) (xy 400.992155 -112.865898) (xy 400.976642 -112.923791)
			(xy 400.953706 -112.979164) (xy 400.923739 -113.03107) (xy 400.887252 -113.07862) (xy 400.844872 -113.121)
			(xy 400.797322 -113.157487) (xy 400.745416 -113.187454) (xy 400.690043 -113.21039) (xy 400.63215 -113.225903)
			(xy 400.572728 -113.233726) (xy 400.512792 -113.233726) (xy 400.45337 -113.225903) (xy 400.395477 -113.21039)
			(xy 400.340104 -113.187454) (xy 400.288198 -113.157487) (xy 400.240648 -113.121) (xy 400.198268 -113.07862)
			(xy 400.161781 -113.03107) (xy 400.131814 -112.979164) (xy 400.108878 -112.923791) (xy 400.093365 -112.865898)
			(xy 400.085542 -112.806476) (xy 400.085052 -112.776508) (xy 396.344529 -112.776508) (xy 395.510258 -115.985798)
			(xy 395.510004 -115.987068) (xy 395.50848 -115.997228) (xy 395.529308 -118.402354) (xy 395.530372 -118.414127)
			(xy 395.541757 -118.434807) (xy 395.551152 -118.441978) (xy 395.572414 -118.457333) (xy 395.610923 -118.49294)
			(xy 395.644193 -118.533484) (xy 395.671597 -118.578203) (xy 395.692618 -118.626254) (xy 395.706861 -118.676731)
			(xy 395.714056 -118.728682) (xy 395.714474 -118.754906) (xy 395.713923 -118.78405) (xy 395.705065 -118.84166)
			(xy 395.687554 -118.897254) (xy 395.661799 -118.949542) (xy 395.628396 -118.997309) (xy 395.588122 -119.039445)
			(xy 395.565376 -119.057674) (xy 395.56309 -119.059198) (xy 395.560296 -119.061484) (xy 395.556232 -119.064532)
			(xy 395.540992 -119.09425) (xy 395.538366 -119.099797) (xy 395.535544 -119.111736) (xy 395.535404 -119.117872)
			(xy 395.543705 -120.086374) (xy 401.939252 -120.086374) (xy 401.939252 -119.222774) (xy 401.939742 -119.192806)
			(xy 401.947565 -119.133384) (xy 401.963078 -119.075491) (xy 401.986014 -119.020118) (xy 402.015981 -118.968212)
			(xy 402.052468 -118.920662) (xy 402.094848 -118.878282) (xy 402.142398 -118.841795) (xy 402.194304 -118.811828)
			(xy 402.249677 -118.788892) (xy 402.30757 -118.773379) (xy 402.366992 -118.765556) (xy 402.426928 -118.765556)
			(xy 402.48635 -118.773379) (xy 402.544243 -118.788892) (xy 402.599616 -118.811828) (xy 402.651522 -118.841795)
			(xy 402.699072 -118.878282) (xy 402.741452 -118.920662) (xy 402.777939 -118.968212) (xy 402.807906 -119.020118)
			(xy 402.830842 -119.075491) (xy 402.846355 -119.133384) (xy 402.854178 -119.192806) (xy 402.854668 -119.222774)
			(xy 402.854668 -120.086374) (xy 402.854178 -120.116342) (xy 402.846355 -120.175764) (xy 402.830842 -120.233657)
			(xy 402.807906 -120.28903) (xy 402.777939 -120.340936) (xy 402.741452 -120.388486) (xy 402.699072 -120.430866)
			(xy 402.651522 -120.467353) (xy 402.599616 -120.49732) (xy 402.544243 -120.520256) (xy 402.48635 -120.535769)
			(xy 402.426928 -120.543592) (xy 402.366992 -120.543592) (xy 402.30757 -120.535769) (xy 402.249677 -120.520256)
			(xy 402.194304 -120.49732) (xy 402.142398 -120.467353) (xy 402.094848 -120.430866) (xy 402.052468 -120.388486)
			(xy 402.015981 -120.340936) (xy 401.986014 -120.28903) (xy 401.963078 -120.233657) (xy 401.947565 -120.175764)
			(xy 401.939742 -120.116342) (xy 401.939252 -120.086374) (xy 395.543705 -120.086374) (xy 395.544802 -120.21439)
			(xy 395.545896 -120.224846) (xy 395.555349 -120.243598) (xy 395.56309 -120.250712) (xy 395.564614 -120.251982)
			(xy 395.587488 -120.270145) (xy 395.627965 -120.312251) (xy 395.661544 -120.360039) (xy 395.687442 -120.41239)
			(xy 395.705051 -120.468078) (xy 395.713959 -120.525801) (xy 395.714474 -120.555004) (xy 395.713976 -120.582762)
			(xy 395.705939 -120.637692) (xy 395.690035 -120.69088) (xy 395.666599 -120.741206) (xy 395.636125 -120.787609)
			(xy 395.599254 -120.829112) (xy 395.57833 -120.847358) (xy 395.575536 -120.849644) (xy 395.57325 -120.851422)
			(xy 395.569948 -120.854216) (xy 395.555978 -120.883172) (xy 395.553603 -120.888451) (xy 395.55104 -120.899737)
			(xy 395.550898 -120.905524) (xy 395.558264 -121.752614) (xy 395.558264 -121.753122) (xy 395.558728 -121.761973)
			(xy 395.565027 -121.778529) (xy 395.576611 -121.791931) (xy 395.584172 -121.796556) (xy 395.584426 -121.79681)
			(xy 395.609517 -121.811367) (xy 395.655376 -121.846887) (xy 395.692989 -121.886472) (xy 400.085052 -121.886472)
			(xy 400.085052 -121.022872) (xy 400.085542 -120.992904) (xy 400.093365 -120.933482) (xy 400.108878 -120.875589)
			(xy 400.131814 -120.820216) (xy 400.161781 -120.76831) (xy 400.198268 -120.72076) (xy 400.240648 -120.67838)
			(xy 400.288198 -120.641893) (xy 400.340104 -120.611926) (xy 400.395477 -120.58899) (xy 400.45337 -120.573477)
			(xy 400.512792 -120.565654) (xy 400.572728 -120.565654) (xy 400.63215 -120.573477) (xy 400.690043 -120.58899)
			(xy 400.745416 -120.611926) (xy 400.797322 -120.641893) (xy 400.844872 -120.67838) (xy 400.887252 -120.72076)
			(xy 400.923739 -120.76831) (xy 400.953706 -120.820216) (xy 400.976642 -120.875589) (xy 400.992155 -120.933482)
			(xy 400.999978 -120.992904) (xy 401.000468 -121.022872) (xy 401.000468 -121.886472) (xy 400.999978 -121.91644)
			(xy 400.992155 -121.975862) (xy 400.976642 -122.033755) (xy 400.953706 -122.089128) (xy 400.923739 -122.141034)
			(xy 400.887252 -122.188584) (xy 400.844872 -122.230964) (xy 400.797322 -122.267451) (xy 400.745416 -122.297418)
			(xy 400.690043 -122.320354) (xy 400.63215 -122.335867) (xy 400.572728 -122.34369) (xy 400.512792 -122.34369)
			(xy 400.45337 -122.335867) (xy 400.395477 -122.320354) (xy 400.340104 -122.297418) (xy 400.288198 -122.267451)
			(xy 400.240648 -122.230964) (xy 400.198268 -122.188584) (xy 400.161781 -122.141034) (xy 400.131814 -122.089128)
			(xy 400.108878 -122.033755) (xy 400.093365 -121.975862) (xy 400.085542 -121.91644) (xy 400.085052 -121.886472)
			(xy 395.692989 -121.886472) (xy 395.695331 -121.888937) (xy 395.728462 -121.93655) (xy 395.754005 -121.988629)
			(xy 395.771373 -122.043974) (xy 395.780165 -122.101309) (xy 395.780768 -122.130312) (xy 395.780689 -122.14305)
			(xy 395.779035 -122.168471) (xy 395.777466 -122.181112) (xy 395.773242 -122.208832) (xy 395.757722 -122.262714)
			(xy 395.734484 -122.313744) (xy 395.704027 -122.360824) (xy 395.667008 -122.402939) (xy 395.624225 -122.439183)
			(xy 395.600682 -122.454416) (xy 395.600428 -122.45467) (xy 395.595277 -122.458084) (xy 395.586669 -122.466946)
			(xy 395.58341 -122.472196) (xy 395.571472 -122.49277) (xy 395.568269 -122.498759) (xy 395.564806 -122.511888)
			(xy 395.564614 -122.518678) (xy 395.571726 -123.318524) (xy 395.574913 -123.686316) (xy 401.939252 -123.686316)
			(xy 401.939252 -122.822716) (xy 401.939742 -122.792748) (xy 401.947565 -122.733326) (xy 401.963078 -122.675433)
			(xy 401.986014 -122.62006) (xy 402.015981 -122.568154) (xy 402.052468 -122.520604) (xy 402.094848 -122.478224)
			(xy 402.142398 -122.441737) (xy 402.194304 -122.41177) (xy 402.249677 -122.388834) (xy 402.30757 -122.373321)
			(xy 402.366992 -122.365498) (xy 402.426928 -122.365498) (xy 402.48635 -122.373321) (xy 402.544243 -122.388834)
			(xy 402.599616 -122.41177) (xy 402.651522 -122.441737) (xy 402.699072 -122.478224) (xy 402.741452 -122.520604)
			(xy 402.777939 -122.568154) (xy 402.807906 -122.62006) (xy 402.830842 -122.675433) (xy 402.846355 -122.733326)
			(xy 402.854178 -122.792748) (xy 402.854668 -122.822716) (xy 402.854668 -123.686316) (xy 402.854178 -123.716284)
			(xy 402.846355 -123.775706) (xy 402.830842 -123.833599) (xy 402.807906 -123.888972) (xy 402.777939 -123.940878)
			(xy 402.741452 -123.988428) (xy 402.699072 -124.030808) (xy 402.651522 -124.067295) (xy 402.599616 -124.097262)
			(xy 402.544243 -124.120198) (xy 402.48635 -124.135711) (xy 402.426928 -124.143534) (xy 402.366992 -124.143534)
			(xy 402.30757 -124.135711) (xy 402.249677 -124.120198) (xy 402.194304 -124.097262) (xy 402.142398 -124.067295)
			(xy 402.094848 -124.030808) (xy 402.052468 -123.988428) (xy 402.015981 -123.940878) (xy 401.986014 -123.888972)
			(xy 401.963078 -123.833599) (xy 401.947565 -123.775706) (xy 401.939742 -123.716284) (xy 401.939252 -123.686316)
			(xy 395.574913 -123.686316) (xy 395.590514 -125.486414) (xy 400.085052 -125.486414) (xy 400.085052 -124.622814)
			(xy 400.085542 -124.592846) (xy 400.093365 -124.533424) (xy 400.108878 -124.475531) (xy 400.131814 -124.420158)
			(xy 400.161781 -124.368252) (xy 400.198268 -124.320702) (xy 400.240648 -124.278322) (xy 400.288198 -124.241835)
			(xy 400.340104 -124.211868) (xy 400.395477 -124.188932) (xy 400.45337 -124.173419) (xy 400.512792 -124.165596)
			(xy 400.572728 -124.165596) (xy 400.63215 -124.173419) (xy 400.690043 -124.188932) (xy 400.745416 -124.211868)
			(xy 400.797322 -124.241835) (xy 400.844872 -124.278322) (xy 400.887252 -124.320702) (xy 400.923739 -124.368252)
			(xy 400.953706 -124.420158) (xy 400.976642 -124.475531) (xy 400.992155 -124.533424) (xy 400.999978 -124.592846)
			(xy 401.000468 -124.622814) (xy 401.000468 -125.486414) (xy 400.999978 -125.516382) (xy 400.992155 -125.575804)
			(xy 400.976642 -125.633697) (xy 400.953706 -125.68907) (xy 400.923739 -125.740976) (xy 400.887252 -125.788526)
			(xy 400.844872 -125.830906) (xy 400.797322 -125.867393) (xy 400.745416 -125.89736) (xy 400.690043 -125.920296)
			(xy 400.63215 -125.935809) (xy 400.572728 -125.943632) (xy 400.512792 -125.943632) (xy 400.45337 -125.935809)
			(xy 400.395477 -125.920296) (xy 400.340104 -125.89736) (xy 400.288198 -125.867393) (xy 400.240648 -125.830906)
			(xy 400.198268 -125.788526) (xy 400.161781 -125.740976) (xy 400.131814 -125.68907) (xy 400.108878 -125.633697)
			(xy 400.093365 -125.575804) (xy 400.085542 -125.516382) (xy 400.085052 -125.486414) (xy 395.590514 -125.486414)
			(xy 395.627098 -129.70764) (xy 395.627911 -129.714905) (xy 395.63306 -129.72858) (xy 395.637258 -129.734564)
			(xy 395.655405 -129.759575) (xy 395.684229 -129.814231) (xy 395.703884 -129.872813) (xy 395.713859 -129.933793)
			(xy 395.714474 -129.964688) (xy 395.714474 -129.964942) (xy 395.713931 -129.994382) (xy 395.704888 -130.052564)
			(xy 395.687008 -130.108664) (xy 395.660716 -130.161348) (xy 395.644116 -130.185668) (xy 395.641068 -130.19024)
			(xy 395.633956 -130.21183) (xy 395.632758 -130.215786) (xy 395.631484 -130.223953) (xy 395.631416 -130.228086)
			(xy 395.642592 -131.519676) (xy 395.642687 -131.523355) (xy 395.643829 -131.530626) (xy 395.644878 -131.534154)
			(xy 395.650974 -131.55422) (xy 395.651228 -131.554474) (xy 395.666148 -131.577968) (xy 395.689764 -131.628363)
			(xy 395.705814 -131.681652) (xy 395.713959 -131.736706) (xy 395.714474 -131.764532) (xy 395.714474 -131.765294)
			(xy 395.714017 -131.791493) (xy 395.706813 -131.843393) (xy 395.692592 -131.893824) (xy 395.671623 -131.941843)
			(xy 395.65834 -131.96443) (xy 395.654784 -131.970272) (xy 395.648942 -131.990084) (xy 395.647962 -131.993686)
			(xy 395.646946 -132.001083) (xy 395.64691 -132.004816) (xy 395.656417 -133.096508) (xy 400.085052 -133.096508)
			(xy 400.085052 -132.232908) (xy 400.085542 -132.20294) (xy 400.093365 -132.143518) (xy 400.108878 -132.085625)
			(xy 400.131814 -132.030252) (xy 400.161781 -131.978346) (xy 400.198268 -131.930796) (xy 400.240648 -131.888416)
			(xy 400.288198 -131.851929) (xy 400.340104 -131.821962) (xy 400.395477 -131.799026) (xy 400.45337 -131.783513)
			(xy 400.512792 -131.77569) (xy 400.572728 -131.77569) (xy 400.63215 -131.783513) (xy 400.690043 -131.799026)
			(xy 400.745416 -131.821962) (xy 400.797322 -131.851929) (xy 400.844872 -131.888416) (xy 400.887252 -131.930796)
			(xy 400.923739 -131.978346) (xy 400.953706 -132.030252) (xy 400.976642 -132.085625) (xy 400.992155 -132.143518)
			(xy 400.999978 -132.20294) (xy 401.000468 -132.232908) (xy 401.000468 -133.096508) (xy 400.999978 -133.126476)
			(xy 400.992155 -133.185898) (xy 400.976642 -133.243791) (xy 400.953706 -133.299164) (xy 400.923739 -133.35107)
			(xy 400.887252 -133.39862) (xy 400.844872 -133.441) (xy 400.797322 -133.477487) (xy 400.745416 -133.507454)
			(xy 400.690043 -133.53039) (xy 400.63215 -133.545903) (xy 400.572728 -133.553726) (xy 400.512792 -133.553726)
			(xy 400.45337 -133.545903) (xy 400.395477 -133.53039) (xy 400.340104 -133.507454) (xy 400.288198 -133.477487)
			(xy 400.240648 -133.441) (xy 400.198268 -133.39862) (xy 400.161781 -133.35107) (xy 400.131814 -133.299164)
			(xy 400.108878 -133.243791) (xy 400.093365 -133.185898) (xy 400.085542 -133.126476) (xy 400.085052 -133.096508)
			(xy 395.656417 -133.096508) (xy 395.658594 -133.346444) (xy 395.660118 -133.35889) (xy 395.664944 -133.376924)
			(xy 395.667992 -133.382512) (xy 395.682627 -133.410658) (xy 395.703357 -133.470609) (xy 395.71386 -133.533167)
			(xy 395.714474 -133.564884) (xy 395.714474 -133.565138) (xy 395.713836 -133.596758) (xy 395.703382 -133.659127)
			(xy 395.682798 -133.718924) (xy 395.668246 -133.747002) (xy 395.668246 -133.747256) (xy 395.66469 -133.755384)
			(xy 395.663373 -133.759514) (xy 395.661971 -133.768068) (xy 395.661896 -133.772402) (xy 395.687366 -136.69645)
			(xy 400.085052 -136.69645) (xy 400.085052 -135.83285) (xy 400.085542 -135.802882) (xy 400.093365 -135.74346)
			(xy 400.108878 -135.685567) (xy 400.131814 -135.630194) (xy 400.161781 -135.578288) (xy 400.198268 -135.530738)
			(xy 400.240648 -135.488358) (xy 400.288198 -135.451871) (xy 400.340104 -135.421904) (xy 400.395477 -135.398968)
			(xy 400.45337 -135.383455) (xy 400.512792 -135.375632) (xy 400.572728 -135.375632) (xy 400.63215 -135.383455)
			(xy 400.690043 -135.398968) (xy 400.745416 -135.421904) (xy 400.797322 -135.451871) (xy 400.844872 -135.488358)
			(xy 400.887252 -135.530738) (xy 400.923739 -135.578288) (xy 400.953706 -135.630194) (xy 400.976642 -135.685567)
			(xy 400.992155 -135.74346) (xy 400.999978 -135.802882) (xy 401.000468 -135.83285) (xy 401.000468 -136.69645)
			(xy 400.999978 -136.726418) (xy 400.992155 -136.78584) (xy 400.976642 -136.843733) (xy 400.953706 -136.899106)
			(xy 400.923739 -136.951012) (xy 400.887252 -136.998562) (xy 400.844872 -137.040942) (xy 400.797322 -137.077429)
			(xy 400.745416 -137.107396) (xy 400.690043 -137.130332) (xy 400.63215 -137.145845) (xy 400.572728 -137.153668)
			(xy 400.512792 -137.153668) (xy 400.45337 -137.145845) (xy 400.395477 -137.130332) (xy 400.340104 -137.107396)
			(xy 400.288198 -137.077429) (xy 400.240648 -137.040942) (xy 400.198268 -136.998562) (xy 400.161781 -136.951012)
			(xy 400.131814 -136.899106) (xy 400.108878 -136.843733) (xy 400.093365 -136.78584) (xy 400.085542 -136.726418)
			(xy 400.085052 -136.69645) (xy 395.687366 -136.69645) (xy 395.701774 -138.350498) (xy 395.703298 -138.362944)
			(xy 395.70787 -138.38047) (xy 395.710664 -138.385804) (xy 395.724625 -138.413517) (xy 395.744356 -138.472346)
			(xy 395.754293 -138.533594) (xy 395.75486 -138.56462) (xy 395.75486 -138.571478) (xy 395.75434 -138.588425)
			(xy 395.750655 -138.622131) (xy 395.747494 -138.638788) (xy 395.741664 -138.665543) (xy 395.723433 -138.717174)
			(xy 395.711172 -138.741658) (xy 395.709648 -138.744198) (xy 395.708124 -138.7475) (xy 395.705076 -138.759184)
			(xy 395.710664 -139.397486) (xy 395.711345 -139.408647) (xy 395.720946 -139.428814) (xy 395.729206 -139.436348)
			(xy 395.750611 -139.454564) (xy 395.788353 -139.496211) (xy 395.819575 -139.542946) (xy 395.843602 -139.593756)
			(xy 395.859912 -139.647542) (xy 395.868154 -139.70314) (xy 395.868652 -139.731242) (xy 395.868169 -139.758818)
			(xy 395.860235 -139.813396) (xy 395.844523 -139.866263) (xy 395.821362 -139.916316) (xy 395.791233 -139.962511)
			(xy 395.754766 -140.003886) (xy 395.734032 -140.022072) (xy 395.730984 -140.024612) (xy 395.724175 -140.032092)
			(xy 395.716587 -140.050824) (xy 395.716252 -140.060934) (xy 395.716506 -140.087096) (xy 395.71676 -140.132562)
			(xy 395.717518 -140.140765) (xy 395.723603 -140.156062) (xy 395.728698 -140.162534) (xy 395.744642 -140.179275)
			(xy 395.77279 -140.215951) (xy 395.784832 -140.235686) (xy 395.797375 -140.257798) (xy 395.81714 -140.304635)
			(xy 395.83051 -140.353682) (xy 395.837249 -140.40407) (xy 395.837664 -140.429488) (xy 395.837664 -140.429742)
			(xy 395.837128 -140.458229) (xy 395.828648 -140.514568) (xy 395.811899 -140.569025) (xy 395.78725 -140.620391)
			(xy 395.755249 -140.667528) (xy 395.736318 -140.688822) (xy 395.733561 -140.691913) (xy 395.728968 -140.698805)
			(xy 395.727174 -140.702538) (xy 395.720062 -140.718286) (xy 395.718366 -140.722482) (xy 395.716319 -140.731298)
			(xy 395.715998 -140.735812) (xy 395.715278 -140.746734) (xy 400.39493 -140.746734) (xy 400.399001 -140.691112)
			(xy 400.411127 -140.636675) (xy 400.43105 -140.584584) (xy 400.458346 -140.535949) (xy 400.492432 -140.491806)
			(xy 400.532581 -140.453097) (xy 400.577939 -140.420646) (xy 400.627539 -140.395145) (xy 400.680323 -140.377138)
			(xy 400.735166 -140.367008) (xy 400.7909 -140.364971) (xy 400.846337 -140.371071) (xy 400.900294 -140.385177)
			(xy 400.951623 -140.406989) (xy 400.999229 -140.436043) (xy 401.042097 -140.471718) (xy 401.079314 -140.513255)
			(xy 401.110087 -140.559768) (xy 401.133759 -140.610265) (xy 401.149827 -140.663672) (xy 401.157947 -140.718848)
			(xy 401.158456 -140.746734) (xy 401.157947 -140.77462) (xy 401.149827 -140.829796) (xy 401.133759 -140.883203)
			(xy 401.110087 -140.9337) (xy 401.079314 -140.980213) (xy 401.042097 -141.02175) (xy 400.999229 -141.057425)
			(xy 400.951623 -141.086479) (xy 400.900294 -141.108291) (xy 400.846337 -141.122397) (xy 400.7909 -141.128497)
			(xy 400.735166 -141.12646) (xy 400.680323 -141.11633) (xy 400.627539 -141.098323) (xy 400.577939 -141.072822)
			(xy 400.532581 -141.040371) (xy 400.492432 -141.001662) (xy 400.458346 -140.957519) (xy 400.43105 -140.908884)
			(xy 400.411127 -140.856793) (xy 400.399001 -140.802356) (xy 400.39493 -140.746734) (xy 395.715278 -140.746734)
			(xy 395.67485 -141.360398) (xy 395.67485 -141.364462) (xy 395.67993 -141.876526) (xy 395.680184 -141.886686)
			(xy 395.680184 -141.88694) (xy 395.680108 -141.903781) (xy 395.678964 -141.937443) (xy 395.677898 -141.95425)
			(xy 395.633879 -142.60068) (xy 399.905728 -142.60068) (xy 399.906192 -142.573275) (xy 399.914043 -142.519031)
			(xy 399.92958 -142.466469) (xy 399.952483 -142.416674) (xy 399.982281 -142.370671) (xy 399.999962 -142.349728)
			(xy 400.000216 -142.349474) (xy 400.00578 -142.342372) (xy 400.01204 -142.325467) (xy 400.012408 -142.316454)
			(xy 400.012408 -142.249144) (xy 400.012028 -142.240129) (xy 400.005796 -142.223212) (xy 400.000216 -142.216124)
			(xy 399.999708 -142.215616) (xy 399.982064 -142.194688) (xy 399.952353 -142.148714) (xy 399.929518 -142.098966)
			(xy 399.914028 -142.046464) (xy 399.906201 -141.992287) (xy 399.905728 -141.964918) (xy 399.906214 -141.937667)
			(xy 399.91397 -141.883719) (xy 399.929325 -141.831424) (xy 399.951967 -141.781847) (xy 399.981433 -141.735997)
			(xy 400.017124 -141.694806) (xy 400.058315 -141.659115) (xy 400.104165 -141.629649) (xy 400.153742 -141.607007)
			(xy 400.206037 -141.591652) (xy 400.259985 -141.583896) (xy 400.314487 -141.583896) (xy 400.368435 -141.591652)
			(xy 400.42073 -141.607007) (xy 400.470307 -141.629649) (xy 400.516157 -141.659115) (xy 400.557348 -141.694806)
			(xy 400.593039 -141.735997) (xy 400.622505 -141.781847) (xy 400.645147 -141.831424) (xy 400.660502 -141.883719)
			(xy 400.668258 -141.937667) (xy 400.668744 -141.964918) (xy 400.668286 -141.992323) (xy 400.660434 -142.046568)
			(xy 400.644896 -142.09913) (xy 400.621992 -142.148925) (xy 400.592192 -142.194927) (xy 400.57451 -142.21587)
			(xy 400.574256 -142.216124) (xy 400.568648 -142.223196) (xy 400.562415 -142.240124) (xy 400.562064 -142.249144)
			(xy 400.562064 -142.316454) (xy 400.562451 -142.325468) (xy 400.568679 -142.342384) (xy 400.574256 -142.349474)
			(xy 400.574764 -142.349982) (xy 400.592403 -142.370915) (xy 400.622116 -142.416887) (xy 400.644952 -142.466634)
			(xy 400.660443 -142.519135) (xy 400.668271 -142.573311) (xy 400.668744 -142.60068) (xy 400.668258 -142.627931)
			(xy 400.660502 -142.681879) (xy 400.645147 -142.734174) (xy 400.622505 -142.783751) (xy 400.593039 -142.829601)
			(xy 400.557348 -142.870792) (xy 400.516157 -142.906483) (xy 400.470307 -142.935949) (xy 400.42073 -142.958591)
			(xy 400.368435 -142.973946) (xy 400.314487 -142.981702) (xy 400.259985 -142.981702) (xy 400.206037 -142.973946)
			(xy 400.153742 -142.958591) (xy 400.104165 -142.935949) (xy 400.058315 -142.906483) (xy 400.017124 -142.870792)
			(xy 399.981433 -142.829601) (xy 399.951967 -142.783751) (xy 399.929325 -142.734174) (xy 399.91397 -142.681879)
			(xy 399.906214 -142.627931) (xy 399.905728 -142.60068) (xy 395.633879 -142.60068) (xy 395.631924 -142.629382)
			(xy 395.631709 -142.637323) (xy 395.635592 -142.652717) (xy 395.639544 -142.659608) (xy 395.653083 -142.682344)
			(xy 395.674447 -142.730756) (xy 395.68892 -142.781654) (xy 395.696225 -142.834064) (xy 395.696694 -142.860522)
			(xy 395.696694 -142.86103) (xy 395.696207 -142.888068) (xy 395.68854 -142.9416) (xy 395.673393 -142.993513)
			(xy 395.651068 -143.042767) (xy 395.622013 -143.088376) (xy 395.604746 -143.109188) (xy 395.598904 -143.116046)
			(xy 395.353196 -146.739864) (xy 397.210024 -146.739864) (xy 397.214095 -146.684242) (xy 397.226221 -146.629805)
			(xy 397.246144 -146.577714) (xy 397.27344 -146.529079) (xy 397.307526 -146.484936) (xy 397.347675 -146.446227)
			(xy 397.393033 -146.413776) (xy 397.442633 -146.388275) (xy 397.495417 -146.370268) (xy 397.55026 -146.360138)
			(xy 397.605994 -146.358101) (xy 397.661431 -146.364201) (xy 397.715388 -146.378307) (xy 397.766717 -146.400119)
			(xy 397.814323 -146.429173) (xy 397.857191 -146.464848) (xy 397.894408 -146.506385) (xy 397.925181 -146.552898)
			(xy 397.948853 -146.603395) (xy 397.964921 -146.656802) (xy 397.973041 -146.711978) (xy 397.97355 -146.739864)
			(xy 397.973041 -146.76775) (xy 397.968884 -146.795998) (xy 398.843752 -146.795998) (xy 398.847823 -146.740376)
			(xy 398.859949 -146.685939) (xy 398.879872 -146.633848) (xy 398.907168 -146.585213) (xy 398.941254 -146.54107)
			(xy 398.981403 -146.502361) (xy 399.026761 -146.46991) (xy 399.076361 -146.444409) (xy 399.129145 -146.426402)
			(xy 399.183988 -146.416272) (xy 399.239722 -146.414235) (xy 399.295159 -146.420335) (xy 399.349116 -146.434441)
			(xy 399.400445 -146.456253) (xy 399.448051 -146.485307) (xy 399.490919 -146.520982) (xy 399.528136 -146.562519)
			(xy 399.558909 -146.609032) (xy 399.582581 -146.659529) (xy 399.598649 -146.712936) (xy 399.606769 -146.768112)
			(xy 399.607278 -146.795998) (xy 399.606769 -146.823884) (xy 399.598649 -146.87906) (xy 399.582581 -146.932467)
			(xy 399.558909 -146.982964) (xy 399.528136 -147.029477) (xy 399.490919 -147.071014) (xy 399.448051 -147.106689)
			(xy 399.400445 -147.135743) (xy 399.349116 -147.157555) (xy 399.295159 -147.171661) (xy 399.239722 -147.177761)
			(xy 399.183988 -147.175724) (xy 399.129145 -147.165594) (xy 399.076361 -147.147587) (xy 399.026761 -147.122086)
			(xy 398.981403 -147.089635) (xy 398.941254 -147.050926) (xy 398.907168 -147.006783) (xy 398.879872 -146.958148)
			(xy 398.859949 -146.906057) (xy 398.847823 -146.85162) (xy 398.843752 -146.795998) (xy 397.968884 -146.795998)
			(xy 397.964921 -146.822926) (xy 397.948853 -146.876333) (xy 397.925181 -146.92683) (xy 397.894408 -146.973343)
			(xy 397.857191 -147.01488) (xy 397.814323 -147.050555) (xy 397.766717 -147.079609) (xy 397.715388 -147.101421)
			(xy 397.661431 -147.115527) (xy 397.605994 -147.121627) (xy 397.55026 -147.11959) (xy 397.495417 -147.10946)
			(xy 397.442633 -147.091453) (xy 397.393033 -147.065952) (xy 397.347675 -147.033501) (xy 397.307526 -146.994792)
			(xy 397.27344 -146.950649) (xy 397.246144 -146.902014) (xy 397.226221 -146.849923) (xy 397.214095 -146.795486)
			(xy 397.210024 -146.739864) (xy 395.353196 -146.739864) (xy 394.850086 -154.159966) (xy 399.607022 -154.159966)
			(xy 399.611093 -154.104344) (xy 399.623219 -154.049907) (xy 399.643142 -153.997816) (xy 399.670438 -153.949181)
			(xy 399.704524 -153.905038) (xy 399.744673 -153.866329) (xy 399.790031 -153.833878) (xy 399.839631 -153.808377)
			(xy 399.892415 -153.79037) (xy 399.947258 -153.78024) (xy 400.002992 -153.778203) (xy 400.058429 -153.784303)
			(xy 400.112386 -153.798409) (xy 400.163715 -153.820221) (xy 400.211321 -153.849275) (xy 400.254189 -153.88495)
			(xy 400.291406 -153.926487) (xy 400.322179 -153.973) (xy 400.345851 -154.023497) (xy 400.361919 -154.076904)
			(xy 400.370039 -154.13208) (xy 400.370548 -154.159966) (xy 400.370039 -154.187852) (xy 400.361919 -154.243028)
			(xy 400.345851 -154.296435) (xy 400.322179 -154.346932) (xy 400.291406 -154.393445) (xy 400.254189 -154.434982)
			(xy 400.211321 -154.470657) (xy 400.163715 -154.499711) (xy 400.112386 -154.521523) (xy 400.058429 -154.535629)
			(xy 400.002992 -154.541729) (xy 399.947258 -154.539692) (xy 399.892415 -154.529562) (xy 399.839631 -154.511555)
			(xy 399.790031 -154.486054) (xy 399.744673 -154.453603) (xy 399.704524 -154.414894) (xy 399.670438 -154.370751)
			(xy 399.643142 -154.322116) (xy 399.623219 -154.270025) (xy 399.611093 -154.215588) (xy 399.607022 -154.159966)
			(xy 394.850086 -154.159966) (xy 394.790308 -155.0416) (xy 396.463772 -155.0416) (xy 396.467843 -154.985978)
			(xy 396.479969 -154.931541) (xy 396.499892 -154.87945) (xy 396.527188 -154.830815) (xy 396.561274 -154.786672)
			(xy 396.601423 -154.747963) (xy 396.646781 -154.715512) (xy 396.696381 -154.690011) (xy 396.749165 -154.672004)
			(xy 396.804008 -154.661874) (xy 396.859742 -154.659837) (xy 396.915179 -154.665937) (xy 396.969136 -154.680043)
			(xy 397.020465 -154.701855) (xy 397.068071 -154.730909) (xy 397.110939 -154.766584) (xy 397.148156 -154.808121)
			(xy 397.178929 -154.854634) (xy 397.202601 -154.905131) (xy 397.218669 -154.958538) (xy 397.226789 -155.013714)
			(xy 397.227298 -155.0416) (xy 397.226789 -155.069486) (xy 397.218669 -155.124662) (xy 397.202601 -155.178069)
			(xy 397.178929 -155.228566) (xy 397.148156 -155.275079) (xy 397.110939 -155.316616) (xy 397.068071 -155.352291)
			(xy 397.020465 -155.381345) (xy 396.969136 -155.403157) (xy 396.915179 -155.417263) (xy 396.859742 -155.423363)
			(xy 396.804008 -155.421326) (xy 396.749165 -155.411196) (xy 396.696381 -155.393189) (xy 396.646781 -155.367688)
			(xy 396.601423 -155.335237) (xy 396.561274 -155.296528) (xy 396.527188 -155.252385) (xy 396.499892 -155.20375)
			(xy 396.479969 -155.151659) (xy 396.467843 -155.097222) (xy 396.463772 -155.0416) (xy 394.790308 -155.0416)
			(xy 394.752557 -155.598368) (xy 399.668236 -155.598368) (xy 399.672307 -155.542746) (xy 399.684433 -155.488309)
			(xy 399.704356 -155.436218) (xy 399.731652 -155.387583) (xy 399.765738 -155.34344) (xy 399.805887 -155.304731)
			(xy 399.851245 -155.27228) (xy 399.900845 -155.246779) (xy 399.953629 -155.228772) (xy 400.008472 -155.218642)
			(xy 400.064206 -155.216605) (xy 400.119643 -155.222705) (xy 400.1736 -155.236811) (xy 400.224929 -155.258623)
			(xy 400.272535 -155.287677) (xy 400.315403 -155.323352) (xy 400.35262 -155.364889) (xy 400.383393 -155.411402)
			(xy 400.407065 -155.461899) (xy 400.423133 -155.515306) (xy 400.431253 -155.570482) (xy 400.431762 -155.598368)
			(xy 400.431253 -155.626254) (xy 400.423133 -155.68143) (xy 400.407065 -155.734837) (xy 400.383393 -155.785334)
			(xy 400.35262 -155.831847) (xy 400.315403 -155.873384) (xy 400.272535 -155.909059) (xy 400.224929 -155.938113)
			(xy 400.1736 -155.959925) (xy 400.119643 -155.974031) (xy 400.064206 -155.980131) (xy 400.008472 -155.978094)
			(xy 399.953629 -155.967964) (xy 399.900845 -155.949957) (xy 399.851245 -155.924456) (xy 399.805887 -155.892005)
			(xy 399.765738 -155.853296) (xy 399.731652 -155.809153) (xy 399.704356 -155.760518) (xy 399.684433 -155.708427)
			(xy 399.672307 -155.65399) (xy 399.668236 -155.598368) (xy 394.752557 -155.598368) (xy 394.652531 -157.0736)
			(xy 399.596862 -157.0736) (xy 399.600933 -157.017978) (xy 399.613059 -156.963541) (xy 399.632982 -156.91145)
			(xy 399.660278 -156.862815) (xy 399.694364 -156.818672) (xy 399.734513 -156.779963) (xy 399.779871 -156.747512)
			(xy 399.829471 -156.722011) (xy 399.882255 -156.704004) (xy 399.937098 -156.693874) (xy 399.992832 -156.691837)
			(xy 400.048269 -156.697937) (xy 400.102226 -156.712043) (xy 400.153555 -156.733855) (xy 400.201161 -156.762909)
			(xy 400.244029 -156.798584) (xy 400.281246 -156.840121) (xy 400.312019 -156.886634) (xy 400.335691 -156.937131)
			(xy 400.351759 -156.990538) (xy 400.359879 -157.045714) (xy 400.360388 -157.0736) (xy 400.359879 -157.101486)
			(xy 400.351759 -157.156662) (xy 400.335691 -157.210069) (xy 400.312019 -157.260566) (xy 400.281246 -157.307079)
			(xy 400.244029 -157.348616) (xy 400.201161 -157.384291) (xy 400.153555 -157.413345) (xy 400.102226 -157.435157)
			(xy 400.048269 -157.449263) (xy 399.992832 -157.455363) (xy 399.937098 -157.453326) (xy 399.882255 -157.443196)
			(xy 399.829471 -157.425189) (xy 399.779871 -157.399688) (xy 399.734513 -157.367237) (xy 399.694364 -157.328528)
			(xy 399.660278 -157.284385) (xy 399.632982 -157.23575) (xy 399.613059 -157.183659) (xy 399.600933 -157.129222)
			(xy 399.596862 -157.0736) (xy 394.652531 -157.0736) (xy 394.518388 -159.052006) (xy 394.520042 -159.060979)
			(xy 394.528766 -159.076989) (xy 394.535406 -159.083248) (xy 394.535914 -159.083756) (xy 394.598398 -159.136588)
			(xy 394.603116 -159.140345) (xy 394.613897 -159.145741) (xy 394.619734 -159.147256) (xy 394.631164 -159.149796)
			(xy 394.643102 -159.147002) (xy 394.688566 -159.136581) (xy 394.780819 -159.122773) (xy 394.873925 -159.11707)
			(xy 394.967173 -159.119514) (xy 395.059853 -159.130087) (xy 395.151256 -159.148708) (xy 395.240685 -159.175235)
			(xy 395.327457 -159.209466) (xy 395.410912 -159.251139) (xy 395.49041 -159.299937) (xy 395.565347 -159.355487)
			(xy 395.627293 -159.4104) (xy 399.99742 -159.4104) (xy 400.001491 -159.354778) (xy 400.013617 -159.300341)
			(xy 400.03354 -159.24825) (xy 400.060836 -159.199615) (xy 400.094922 -159.155472) (xy 400.135071 -159.116763)
			(xy 400.180429 -159.084312) (xy 400.230029 -159.058811) (xy 400.282813 -159.040804) (xy 400.337656 -159.030674)
			(xy 400.39339 -159.028637) (xy 400.448827 -159.034737) (xy 400.502784 -159.048843) (xy 400.554113 -159.070655)
			(xy 400.601719 -159.099709) (xy 400.644587 -159.135384) (xy 400.681804 -159.176921) (xy 400.712577 -159.223434)
			(xy 400.736249 -159.273931) (xy 400.752317 -159.327338) (xy 400.760437 -159.382514) (xy 400.760946 -159.4104)
			(xy 400.760437 -159.438286) (xy 400.752317 -159.493462) (xy 400.736249 -159.546869) (xy 400.712577 -159.597366)
			(xy 400.681804 -159.643879) (xy 400.644587 -159.685416) (xy 400.601719 -159.721091) (xy 400.554113 -159.750145)
			(xy 400.502784 -159.771957) (xy 400.448827 -159.786063) (xy 400.39339 -159.792163) (xy 400.337656 -159.790126)
			(xy 400.282813 -159.779996) (xy 400.230029 -159.761989) (xy 400.180429 -159.736488) (xy 400.135071 -159.704037)
			(xy 400.094922 -159.665328) (xy 400.060836 -159.621185) (xy 400.03354 -159.57255) (xy 400.013617 -159.520459)
			(xy 400.001491 -159.466022) (xy 399.99742 -159.4104) (xy 395.627293 -159.4104) (xy 395.635149 -159.417364)
			(xy 395.699285 -159.485098) (xy 395.757264 -159.558171) (xy 395.808645 -159.636025) (xy 395.853035 -159.718066)
			(xy 395.890096 -159.803669) (xy 395.905228 -159.847788) (xy 395.91941 -159.891943) (xy 395.940975 -159.982148)
			(xy 395.954632 -160.073884) (xy 395.960277 -160.16646) (xy 395.957867 -160.259176) (xy 395.947421 -160.351333)
			(xy 395.929018 -160.442236) (xy 395.925301 -160.454848) (xy 400.19554 -160.454848) (xy 400.199611 -160.399226)
			(xy 400.211737 -160.344789) (xy 400.23166 -160.292698) (xy 400.258956 -160.244063) (xy 400.293042 -160.19992)
			(xy 400.333191 -160.161211) (xy 400.378549 -160.12876) (xy 400.428149 -160.103259) (xy 400.480933 -160.085252)
			(xy 400.535776 -160.075122) (xy 400.59151 -160.073085) (xy 400.646947 -160.079185) (xy 400.700904 -160.093291)
			(xy 400.752233 -160.115103) (xy 400.799839 -160.144157) (xy 400.842707 -160.179832) (xy 400.879924 -160.221369)
			(xy 400.910697 -160.267882) (xy 400.934369 -160.318379) (xy 400.950437 -160.371786) (xy 400.958557 -160.426962)
			(xy 400.959066 -160.454848) (xy 400.958557 -160.482734) (xy 400.950437 -160.53791) (xy 400.934369 -160.591317)
			(xy 400.910697 -160.641814) (xy 400.879924 -160.688327) (xy 400.842707 -160.729864) (xy 400.799839 -160.765539)
			(xy 400.752233 -160.794593) (xy 400.700904 -160.816405) (xy 400.646947 -160.830511) (xy 400.59151 -160.836611)
			(xy 400.535776 -160.834574) (xy 400.480933 -160.824444) (xy 400.428149 -160.806437) (xy 400.378549 -160.780936)
			(xy 400.333191 -160.748485) (xy 400.293042 -160.709776) (xy 400.258956 -160.665633) (xy 400.23166 -160.616998)
			(xy 400.211737 -160.564907) (xy 400.199611 -160.51047) (xy 400.19554 -160.454848) (xy 395.925301 -160.454848)
			(xy 395.902796 -160.5312) (xy 395.868953 -160.617552) (xy 395.827745 -160.700642) (xy 395.779483 -160.779843)
			(xy 395.72453 -160.854558) (xy 395.663301 -160.924222) (xy 395.596258 -160.98831) (xy 395.523906 -161.046339)
			(xy 395.446793 -161.097871) (xy 395.365498 -161.142517) (xy 395.280636 -161.179941) (xy 395.192847 -161.20986)
			(xy 395.102793 -161.232048) (xy 395.011153 -161.246338) (xy 394.918619 -161.252622) (xy 394.825888 -161.250853)
			(xy 394.733661 -161.241045) (xy 394.642633 -161.22327) (xy 394.55349 -161.197664) (xy 394.510006 -161.181542)
			(xy 394.504164 -161.179256) (xy 394.49248 -161.177986) (xy 394.486638 -161.178494) (xy 394.48078 -161.17925)
			(xy 394.469616 -161.183095) (xy 394.46454 -161.186114) (xy 394.395452 -161.23031) (xy 394.394436 -161.231072)
			(xy 394.385073 -161.238077) (xy 394.373415 -161.258318) (xy 394.372084 -161.269934) (xy 394.33627 -161.81832)
			(xy 394.334238 -161.844736) (xy 394.32103 -161.987738) (xy 394.320776 -161.994088) (xy 394.389713 -164.056314)
			(xy 399.637502 -164.056314) (xy 399.641573 -164.000692) (xy 399.653699 -163.946255) (xy 399.673622 -163.894164)
			(xy 399.700918 -163.845529) (xy 399.735004 -163.801386) (xy 399.775153 -163.762677) (xy 399.820511 -163.730226)
			(xy 399.870111 -163.704725) (xy 399.922895 -163.686718) (xy 399.977738 -163.676588) (xy 400.033472 -163.674551)
			(xy 400.088909 -163.680651) (xy 400.142866 -163.694757) (xy 400.194195 -163.716569) (xy 400.241801 -163.745623)
			(xy 400.284669 -163.781298) (xy 400.321886 -163.822835) (xy 400.352659 -163.869348) (xy 400.376331 -163.919845)
			(xy 400.392399 -163.973252) (xy 400.400519 -164.028428) (xy 400.401028 -164.056314) (xy 400.400519 -164.0842)
			(xy 400.392399 -164.139376) (xy 400.376331 -164.192783) (xy 400.352659 -164.24328) (xy 400.321886 -164.289793)
			(xy 400.284669 -164.33133) (xy 400.241801 -164.367005) (xy 400.194195 -164.396059) (xy 400.142866 -164.417871)
			(xy 400.088909 -164.431977) (xy 400.033472 -164.438077) (xy 399.977738 -164.43604) (xy 399.922895 -164.42591)
			(xy 399.870111 -164.407903) (xy 399.820511 -164.382402) (xy 399.775153 -164.349951) (xy 399.735004 -164.311242)
			(xy 399.700918 -164.267099) (xy 399.673622 -164.218464) (xy 399.653699 -164.166373) (xy 399.641573 -164.111936)
			(xy 399.637502 -164.056314) (xy 394.389713 -164.056314) (xy 394.425637 -165.130988) (xy 397.044162 -165.130988)
			(xy 397.048233 -165.075366) (xy 397.060359 -165.020929) (xy 397.080282 -164.968838) (xy 397.107578 -164.920203)
			(xy 397.141664 -164.87606) (xy 397.181813 -164.837351) (xy 397.227171 -164.8049) (xy 397.276771 -164.779399)
			(xy 397.329555 -164.761392) (xy 397.384398 -164.751262) (xy 397.440132 -164.749225) (xy 397.495569 -164.755325)
			(xy 397.549526 -164.769431) (xy 397.600855 -164.791243) (xy 397.648461 -164.820297) (xy 397.691329 -164.855972)
			(xy 397.728546 -164.897509) (xy 397.758325 -164.94252) (xy 398.877534 -164.94252) (xy 398.881605 -164.886898)
			(xy 398.893731 -164.832461) (xy 398.913654 -164.78037) (xy 398.94095 -164.731735) (xy 398.975036 -164.687592)
			(xy 399.015185 -164.648883) (xy 399.060543 -164.616432) (xy 399.110143 -164.590931) (xy 399.162927 -164.572924)
			(xy 399.21777 -164.562794) (xy 399.273504 -164.560757) (xy 399.328941 -164.566857) (xy 399.382898 -164.580963)
			(xy 399.434227 -164.602775) (xy 399.481833 -164.631829) (xy 399.524701 -164.667504) (xy 399.561918 -164.709041)
			(xy 399.592691 -164.755554) (xy 399.616363 -164.806051) (xy 399.632431 -164.859458) (xy 399.640551 -164.914634)
			(xy 399.64106 -164.94252) (xy 399.640551 -164.970406) (xy 399.632431 -165.025582) (xy 399.616363 -165.078989)
			(xy 399.592691 -165.129486) (xy 399.561918 -165.175999) (xy 399.524701 -165.217536) (xy 399.481833 -165.253211)
			(xy 399.434227 -165.282265) (xy 399.382898 -165.304077) (xy 399.328941 -165.318183) (xy 399.273504 -165.324283)
			(xy 399.21777 -165.322246) (xy 399.162927 -165.312116) (xy 399.110143 -165.294109) (xy 399.060543 -165.268608)
			(xy 399.015185 -165.236157) (xy 398.975036 -165.197448) (xy 398.94095 -165.153305) (xy 398.913654 -165.10467)
			(xy 398.893731 -165.052579) (xy 398.881605 -164.998142) (xy 398.877534 -164.94252) (xy 397.758325 -164.94252)
			(xy 397.759319 -164.944022) (xy 397.782991 -164.994519) (xy 397.799059 -165.047926) (xy 397.807179 -165.103102)
			(xy 397.807688 -165.130988) (xy 397.807179 -165.158874) (xy 397.799059 -165.21405) (xy 397.782991 -165.267457)
			(xy 397.759319 -165.317954) (xy 397.728546 -165.364467) (xy 397.691329 -165.406004) (xy 397.648461 -165.441679)
			(xy 397.600855 -165.470733) (xy 397.549526 -165.492545) (xy 397.495569 -165.506651) (xy 397.440132 -165.512751)
			(xy 397.384398 -165.510714) (xy 397.329555 -165.500584) (xy 397.276771 -165.482577) (xy 397.227171 -165.457076)
			(xy 397.181813 -165.424625) (xy 397.141664 -165.385916) (xy 397.107578 -165.341773) (xy 397.080282 -165.293138)
			(xy 397.060359 -165.241047) (xy 397.048233 -165.18661) (xy 397.044162 -165.130988) (xy 394.425637 -165.130988)
			(xy 394.53482 -168.397174) (xy 398.941796 -168.397174) (xy 398.945867 -168.341552) (xy 398.957993 -168.287115)
			(xy 398.977916 -168.235024) (xy 399.005212 -168.186389) (xy 399.039298 -168.142246) (xy 399.079447 -168.103537)
			(xy 399.124805 -168.071086) (xy 399.174405 -168.045585) (xy 399.227189 -168.027578) (xy 399.282032 -168.017448)
			(xy 399.337766 -168.015411) (xy 399.393203 -168.021511) (xy 399.44716 -168.035617) (xy 399.498489 -168.057429)
			(xy 399.546095 -168.086483) (xy 399.588963 -168.122158) (xy 399.62618 -168.163695) (xy 399.656953 -168.210208)
			(xy 399.680625 -168.260705) (xy 399.696693 -168.314112) (xy 399.704813 -168.369288) (xy 399.705322 -168.397174)
			(xy 399.704813 -168.42506) (xy 399.696693 -168.480236) (xy 399.680625 -168.533643) (xy 399.656953 -168.58414)
			(xy 399.62618 -168.630653) (xy 399.588963 -168.67219) (xy 399.546095 -168.707865) (xy 399.498489 -168.736919)
			(xy 399.44716 -168.758731) (xy 399.393203 -168.772837) (xy 399.337766 -168.778937) (xy 399.282032 -168.7769)
			(xy 399.227189 -168.76677) (xy 399.174405 -168.748763) (xy 399.124805 -168.723262) (xy 399.079447 -168.690811)
			(xy 399.039298 -168.652102) (xy 399.005212 -168.607959) (xy 398.977916 -168.559324) (xy 398.957993 -168.507233)
			(xy 398.945867 -168.452796) (xy 398.941796 -168.397174) (xy 394.53482 -168.397174) (xy 394.555826 -169.02557)
			(xy 396.25219 -169.02557) (xy 396.256261 -168.969948) (xy 396.268387 -168.915511) (xy 396.28831 -168.86342)
			(xy 396.315606 -168.814785) (xy 396.349692 -168.770642) (xy 396.389841 -168.731933) (xy 396.435199 -168.699482)
			(xy 396.484799 -168.673981) (xy 396.537583 -168.655974) (xy 396.592426 -168.645844) (xy 396.64816 -168.643807)
			(xy 396.703597 -168.649907) (xy 396.757554 -168.664013) (xy 396.808883 -168.685825) (xy 396.856489 -168.714879)
			(xy 396.899357 -168.750554) (xy 396.936574 -168.792091) (xy 396.967347 -168.838604) (xy 396.991019 -168.889101)
			(xy 397.007087 -168.942508) (xy 397.015207 -168.997684) (xy 397.015716 -169.02557) (xy 397.015207 -169.053456)
			(xy 397.007087 -169.108632) (xy 396.991019 -169.162039) (xy 396.967347 -169.212536) (xy 396.936574 -169.259049)
			(xy 396.899357 -169.300586) (xy 396.856489 -169.336261) (xy 396.808883 -169.365315) (xy 396.757554 -169.387127)
			(xy 396.703597 -169.401233) (xy 396.64816 -169.407333) (xy 396.592426 -169.405296) (xy 396.537583 -169.395166)
			(xy 396.484799 -169.377159) (xy 396.435199 -169.351658) (xy 396.389841 -169.319207) (xy 396.349692 -169.280498)
			(xy 396.315606 -169.236355) (xy 396.28831 -169.18772) (xy 396.268387 -169.135629) (xy 396.256261 -169.081192)
			(xy 396.25219 -169.02557) (xy 394.555826 -169.02557) (xy 394.578734 -169.710862) (xy 397.16151 -169.710862)
			(xy 397.165581 -169.65524) (xy 397.177707 -169.600803) (xy 397.19763 -169.548712) (xy 397.224926 -169.500077)
			(xy 397.259012 -169.455934) (xy 397.299161 -169.417225) (xy 397.344519 -169.384774) (xy 397.394119 -169.359273)
			(xy 397.446903 -169.341266) (xy 397.501746 -169.331136) (xy 397.55748 -169.329099) (xy 397.612917 -169.335199)
			(xy 397.666874 -169.349305) (xy 397.718203 -169.371117) (xy 397.765809 -169.400171) (xy 397.808677 -169.435846)
			(xy 397.845894 -169.477383) (xy 397.876667 -169.523896) (xy 397.900339 -169.574393) (xy 397.916407 -169.6278)
			(xy 397.924527 -169.682976) (xy 397.925036 -169.710862) (xy 397.924527 -169.738748) (xy 397.916407 -169.793924)
			(xy 397.900339 -169.847331) (xy 397.876667 -169.897828) (xy 397.845894 -169.944341) (xy 397.808677 -169.985878)
			(xy 397.765809 -170.021553) (xy 397.718203 -170.050607) (xy 397.666874 -170.072419) (xy 397.612917 -170.086525)
			(xy 397.55748 -170.092625) (xy 397.501746 -170.090588) (xy 397.446903 -170.080458) (xy 397.394119 -170.062451)
			(xy 397.344519 -170.03695) (xy 397.299161 -170.004499) (xy 397.259012 -169.96579) (xy 397.224926 -169.921647)
			(xy 397.19763 -169.873012) (xy 397.177707 -169.820921) (xy 397.165581 -169.766484) (xy 397.16151 -169.710862)
			(xy 394.578734 -169.710862) (xy 394.654794 -171.986194) (xy 398.254218 -171.986194) (xy 398.258289 -171.930572)
			(xy 398.270415 -171.876135) (xy 398.290338 -171.824044) (xy 398.317634 -171.775409) (xy 398.35172 -171.731266)
			(xy 398.391869 -171.692557) (xy 398.437227 -171.660106) (xy 398.486827 -171.634605) (xy 398.539611 -171.616598)
			(xy 398.594454 -171.606468) (xy 398.650188 -171.604431) (xy 398.705625 -171.610531) (xy 398.759582 -171.624637)
			(xy 398.810911 -171.646449) (xy 398.858517 -171.675503) (xy 398.901385 -171.711178) (xy 398.938602 -171.752715)
			(xy 398.969375 -171.799228) (xy 398.993047 -171.849725) (xy 399.009115 -171.903132) (xy 399.017235 -171.958308)
			(xy 399.017744 -171.986194) (xy 399.017235 -172.01408) (xy 399.009115 -172.069256) (xy 398.993047 -172.122663)
			(xy 398.969375 -172.17316) (xy 398.938602 -172.219673) (xy 398.901385 -172.26121) (xy 398.858517 -172.296885)
			(xy 398.810911 -172.325939) (xy 398.759582 -172.347751) (xy 398.705625 -172.361857) (xy 398.650188 -172.367957)
			(xy 398.594454 -172.36592) (xy 398.539611 -172.35579) (xy 398.486827 -172.337783) (xy 398.437227 -172.312282)
			(xy 398.391869 -172.279831) (xy 398.35172 -172.241122) (xy 398.317634 -172.196979) (xy 398.290338 -172.148344)
			(xy 398.270415 -172.096253) (xy 398.258289 -172.041816) (xy 398.254218 -171.986194) (xy 394.654794 -171.986194)
			(xy 394.738513 -174.490634) (xy 398.11147 -174.490634) (xy 398.115541 -174.435012) (xy 398.127667 -174.380575)
			(xy 398.14759 -174.328484) (xy 398.174886 -174.279849) (xy 398.208972 -174.235706) (xy 398.249121 -174.196997)
			(xy 398.294479 -174.164546) (xy 398.344079 -174.139045) (xy 398.396863 -174.121038) (xy 398.451706 -174.110908)
			(xy 398.50744 -174.108871) (xy 398.562877 -174.114971) (xy 398.616834 -174.129077) (xy 398.668163 -174.150889)
			(xy 398.715769 -174.179943) (xy 398.758637 -174.215618) (xy 398.795854 -174.257155) (xy 398.826627 -174.303668)
			(xy 398.850299 -174.354165) (xy 398.866367 -174.407572) (xy 398.874487 -174.462748) (xy 398.874996 -174.490634)
			(xy 398.874487 -174.51852) (xy 398.866367 -174.573696) (xy 398.850299 -174.627103) (xy 398.826627 -174.6776)
			(xy 398.795854 -174.724113) (xy 398.758637 -174.76565) (xy 398.715769 -174.801325) (xy 398.668163 -174.830379)
			(xy 398.616834 -174.852191) (xy 398.562877 -174.866297) (xy 398.50744 -174.872397) (xy 398.451706 -174.87036)
			(xy 398.396863 -174.86023) (xy 398.344079 -174.842223) (xy 398.294479 -174.816722) (xy 398.249121 -174.784271)
			(xy 398.208972 -174.745562) (xy 398.174886 -174.701419) (xy 398.14759 -174.652784) (xy 398.127667 -174.600693)
			(xy 398.115541 -174.546256) (xy 398.11147 -174.490634) (xy 394.738513 -174.490634) (xy 396.700756 -233.190796)
			(xy 396.70154 -233.20053) (xy 396.709465 -233.21836) (xy 396.723478 -233.231938) (xy 396.741548 -233.239298)
			(xy 396.751302 -233.239818)
		)
		(stroke
			(width 0)
			(type solid)
		)
		(fill yes)
		(layer "In11.Cu")
		(net "GND")
	)
	(gr_poly
		(pts
			(xy 23.954232 -417.201604) (xy 23.961835 -417.200085) (xy 23.975662 -417.193093) (xy 23.98141 -417.187888)
			(xy 26.361644 -414.807654) (xy 26.368489 -414.800256) (xy 26.376216 -414.781657) (xy 26.37663 -414.771586)
			(xy 26.37663 -394.752576) (xy 26.35758 -394.72616) (xy 26.341832 -394.720826) (xy 26.340308 -394.720318)
			(xy 26.018744 -394.591286) (xy 26.00452 -394.585444) (xy 26.004012 -394.58519) (xy 25.648158 -394.442696)
			(xy 25.633934 -394.428726) (xy 25.630378 -394.420598) (xy 25.62987 -394.419328) (xy 25.623774 -394.405104)
			(xy 25.623774 -394.404596) (xy 25.578816 -394.29944) (xy 25.574436 -394.290457) (xy 25.560197 -394.276462)
			(xy 25.55113 -394.272262) (xy 25.538176 -394.267182) (xy 25.431496 -394.22451) (xy 24.965914 -394.038328)
			(xy 24.959564 -394.035788) (xy 24.950166 -394.031724) (xy 24.949658 -394.031724) (xy 24.910542 -394.015976)
			(xy 24.79802 -393.970764) (xy 24.793543 -393.968868) (xy 24.785354 -393.963628) (xy 24.781764 -393.96035)
			(xy 24.661876 -393.84605) (xy 24.661622 -393.845796) (xy 24.6507 -393.835636) (xy 24.643334 -393.828524)
			(xy 24.635749 -393.821811) (xy 24.616886 -393.814477) (xy 24.606758 -393.8143) (xy 24.485092 -393.817348)
			(xy 24.48433 -393.816586) (xy 24.483568 -393.816586) (xy 24.19858 -393.544552) (xy 24.198326 -393.544298)
			(xy 24.187404 -393.534138) (xy 24.142192 -393.490958) (xy 24.095964 -393.447016) (xy 24.054308 -393.407392)
			(xy 24.014938 -393.40663) (xy 23.999952 -393.419584) (xy 23.978966 -393.437429) (xy 23.932825 -393.467521)
			(xy 23.882835 -393.490663) (xy 23.830037 -393.506372) (xy 23.775527 -393.514323) (xy 23.747984 -393.514834)
			(xy 23.720714 -393.514369) (xy 23.666731 -393.506605) (xy 23.614402 -393.491237) (xy 23.564792 -393.468578)
			(xy 23.518913 -393.43909) (xy 23.477697 -393.403372) (xy 23.441984 -393.362152) (xy 23.4125 -393.316269)
			(xy 23.389847 -393.266657) (xy 23.374485 -393.214326) (xy 23.366727 -393.160342) (xy 23.366222 -393.133072)
			(xy 23.366667 -393.107296) (xy 23.373641 -393.056217) (xy 23.387418 -393.006539) (xy 23.407748 -392.959164)
			(xy 23.434263 -392.914953) (xy 23.450042 -392.894566) (xy 23.462234 -392.879072) (xy 23.459694 -392.839702)
			(xy 23.42642 -392.807952) (xy 23.41118 -392.793474) (xy 23.400766 -392.783568) (xy 23.355554 -392.740388)
			(xy 23.105364 -392.502136) (xy 23.105364 -392.501628) (xy 23.080726 -392.478006) (xy 23.080472 -392.477752)
			(xy 23.068534 -392.466322) (xy 23.06828 -392.466068) (xy 22.910292 -392.315192) (xy 22.910038 -392.315192)
			(xy 22.865588 -392.272774) (xy 22.620732 -392.03884) (xy 22.620224 -392.038332) (xy 22.614382 -392.032998)
			(xy 22.590252 -392.009884) (xy 22.589998 -392.009884) (xy 22.490684 -391.915142) (xy 22.294342 -391.72769)
			(xy 22.284944 -391.718546) (xy 22.28469 -391.718292) (xy 22.005544 -391.4521) (xy 21.99767 -391.434066)
			(xy 21.997416 -391.425938) (xy 21.997416 -391.423398) (xy 21.99513 -391.32256) (xy 21.994387 -391.312568)
			(xy 21.986279 -391.294268) (xy 21.979382 -391.287) (xy 20.988528 -390.341358) (xy 20.985881 -390.338739)
			(xy 20.981297 -390.33287) (xy 20.979384 -390.329674) (xy 20.954746 -390.28624) (xy 20.918678 -390.223248)
			(xy 20.918424 -390.222994) (xy 20.911312 -390.210548) (xy 20.911312 -390.210294) (xy 20.619974 -389.69823)
			(xy 20.616926 -389.694674) (xy 20.584004 -389.654867) (xy 20.525676 -389.569603) (xy 20.476495 -389.478755)
			(xy 20.456144 -389.431276) (xy 20.42541 -389.357362) (xy 20.422616 -389.35152) (xy 18.7452 -386.404358)
			(xy 18.744946 -386.404104) (xy 18.730722 -386.378958) (xy 18.730468 -386.378196) (xy 18.692368 -386.311394)
			(xy 18.681192 -386.291582) (xy 18.679922 -386.287264) (xy 18.679414 -386.28574) (xy 18.679414 -386.285232)
			(xy 18.650966 -386.176774) (xy 18.650966 -386.17652) (xy 18.648172 -386.16636) (xy 12.494768 -362.71835)
			(xy 12.49426 -362.71581) (xy 12.493498 -362.707174) (xy 12.493498 -341.674704) (xy 12.49303 -341.660515)
			(xy 12.485222 -341.633231) (xy 12.470206 -341.60915) (xy 12.449143 -341.590132) (xy 12.423659 -341.577644)
			(xy 12.395723 -341.572651) (xy 12.367492 -341.575539) (xy 12.341145 -341.586085) (xy 12.329668 -341.59444)
			(xy 12.309509 -341.609546) (xy 12.265977 -341.634893) (xy 12.219491 -341.6543) (xy 12.170858 -341.66743)
			(xy 12.120921 -341.674054) (xy 12.095734 -341.67445) (xy 12.068463 -341.673987) (xy 12.014476 -341.666225)
			(xy 11.962143 -341.650859) (xy 11.91253 -341.628202) (xy 11.866646 -341.598715) (xy 11.825425 -341.562997)
			(xy 11.789708 -341.521777) (xy 11.76022 -341.475894) (xy 11.737562 -341.426281) (xy 11.722196 -341.373948)
			(xy 11.714433 -341.319961) (xy 11.714433 -341.265419) (xy 11.722196 -341.211432) (xy 11.737562 -341.159099)
			(xy 11.76022 -341.109486) (xy 11.789708 -341.063603) (xy 11.825425 -341.022383) (xy 11.866646 -340.986665)
			(xy 11.91253 -340.957178) (xy 11.962143 -340.934521) (xy 12.014476 -340.919155) (xy 12.068463 -340.911393)
			(xy 12.095734 -340.910926) (xy 12.12092 -340.911331) (xy 12.170855 -340.917956) (xy 12.219486 -340.931088)
			(xy 12.265968 -340.950497) (xy 12.309497 -340.975848) (xy 12.329668 -340.990936) (xy 12.341168 -340.999253)
			(xy 12.367509 -341.009788) (xy 12.395732 -341.012671) (xy 12.42366 -341.00768) (xy 12.449137 -340.9952)
			(xy 12.470199 -340.976193) (xy 12.48522 -340.952127) (xy 12.493043 -340.924857) (xy 12.493498 -340.910672)
			(xy 12.493498 -338.192618) (xy 12.493936 -338.182554) (xy 12.501671 -338.163971) (xy 12.508484 -338.15655)
			(xy 12.989306 -337.675728) (xy 12.996704 -337.66888) (xy 13.015302 -337.661143) (xy 13.025374 -337.660742)
			(xy 13.918438 -337.660742) (xy 13.92682 -337.65998) (xy 13.934423 -337.658462) (xy 13.948251 -337.651469)
			(xy 13.953998 -337.646264) (xy 16.655288 -334.944974) (xy 16.662132 -334.937575) (xy 16.669858 -334.918976)
			(xy 16.670274 -334.908906) (xy 16.670274 -319.198244) (xy 16.670707 -319.188178) (xy 16.678432 -319.169586)
			(xy 16.68526 -319.162176) (xy 17.037304 -318.810132) (xy 17.044139 -318.80273) (xy 17.051848 -318.784132)
			(xy 17.05229 -318.774064) (xy 17.05229 -308.14645) (xy 17.051528 -308.142132) (xy 17.049496 -308.130194)
			(xy 17.040606 -308.105556) (xy 17.035526 -308.098952) (xy 17.018227 -308.076341) (xy 16.989823 -308.027004)
			(xy 16.96907 -307.973992) (xy 16.95643 -307.918483) (xy 16.952184 -307.861713) (xy 16.956427 -307.804942)
			(xy 16.969063 -307.749432) (xy 16.989812 -307.696419) (xy 17.018213 -307.64708) (xy 17.035526 -307.62448)
			(xy 17.040606 -307.617876) (xy 17.049242 -307.594) (xy 17.05229 -307.585618) (xy 17.05229 -302.997362)
			(xy 17.052156 -302.991432) (xy 17.049449 -302.979885) (xy 17.046956 -302.974502) (xy 17.008967 -302.898003)
			(xy 16.939652 -302.741876) (xy 16.878092 -302.582532) (xy 16.824437 -302.420355) (xy 16.778814 -302.255738)
			(xy 16.741336 -302.089078) (xy 16.712091 -301.920778) (xy 16.691152 -301.751245) (xy 16.678568 -301.580887)
			(xy 16.67437 -301.410116) (xy 16.678569 -301.239346) (xy 16.691153 -301.068988) (xy 16.712092 -300.899455)
			(xy 16.741337 -300.731155) (xy 16.778816 -300.564495) (xy 16.824439 -300.399878) (xy 16.878095 -300.237702)
			(xy 16.939655 -300.078358) (xy 17.00897 -299.922231) (xy 17.046956 -299.84573) (xy 17.049496 -299.840396)
			(xy 17.05229 -299.828966) (xy 17.05229 -299.616876) (xy 17.04467 -299.59808) (xy 17.037304 -299.590968)
			(xy 16.353536 -298.9072) (xy 16.346424 -298.899834) (xy 16.327628 -298.892214) (xy 3.439922 -298.892214)
			(xy 3.421126 -298.899834) (xy 3.414014 -298.9072) (xy 2.989326 -299.331888) (xy 2.98196 -299.339)
			(xy 2.97434 -299.357796) (xy 2.97434 -304.457354) (xy 7.652256 -304.457354) (xy 7.656327 -304.401732)
			(xy 7.668453 -304.347295) (xy 7.688376 -304.295204) (xy 7.715672 -304.246569) (xy 7.749758 -304.202426)
			(xy 7.789907 -304.163717) (xy 7.835265 -304.131266) (xy 7.884865 -304.105765) (xy 7.937649 -304.087758)
			(xy 7.992492 -304.077628) (xy 8.048226 -304.075591) (xy 8.103663 -304.081691) (xy 8.15762 -304.095797)
			(xy 8.208949 -304.117609) (xy 8.256555 -304.146663) (xy 8.299423 -304.182338) (xy 8.33664 -304.223875)
			(xy 8.367413 -304.270388) (xy 8.391085 -304.320885) (xy 8.407153 -304.374292) (xy 8.415273 -304.429468)
			(xy 8.415782 -304.457354) (xy 8.415273 -304.48524) (xy 8.41306 -304.50028) (xy 14.926308 -304.50028)
			(xy 14.930379 -304.444658) (xy 14.942505 -304.390221) (xy 14.962428 -304.33813) (xy 14.989724 -304.289495)
			(xy 15.02381 -304.245352) (xy 15.063959 -304.206643) (xy 15.109317 -304.174192) (xy 15.158917 -304.148691)
			(xy 15.211701 -304.130684) (xy 15.266544 -304.120554) (xy 15.322278 -304.118517) (xy 15.377715 -304.124617)
			(xy 15.431672 -304.138723) (xy 15.483001 -304.160535) (xy 15.530607 -304.189589) (xy 15.573475 -304.225264)
			(xy 15.610692 -304.266801) (xy 15.641465 -304.313314) (xy 15.665137 -304.363811) (xy 15.681205 -304.417218)
			(xy 15.689325 -304.472394) (xy 15.689834 -304.50028) (xy 15.689325 -304.528166) (xy 15.681205 -304.583342)
			(xy 15.665137 -304.636749) (xy 15.641465 -304.687246) (xy 15.610692 -304.733759) (xy 15.573475 -304.775296)
			(xy 15.530607 -304.810971) (xy 15.483001 -304.840025) (xy 15.431672 -304.861837) (xy 15.377715 -304.875943)
			(xy 15.322278 -304.882043) (xy 15.266544 -304.880006) (xy 15.211701 -304.869876) (xy 15.158917 -304.851869)
			(xy 15.109317 -304.826368) (xy 15.063959 -304.793917) (xy 15.02381 -304.755208) (xy 14.989724 -304.711065)
			(xy 14.962428 -304.66243) (xy 14.942505 -304.610339) (xy 14.930379 -304.555902) (xy 14.926308 -304.50028)
			(xy 8.41306 -304.50028) (xy 8.407153 -304.540416) (xy 8.391085 -304.593823) (xy 8.367413 -304.64432)
			(xy 8.33664 -304.690833) (xy 8.299423 -304.73237) (xy 8.256555 -304.768045) (xy 8.208949 -304.797099)
			(xy 8.15762 -304.818911) (xy 8.103663 -304.833017) (xy 8.048226 -304.839117) (xy 7.992492 -304.83708)
			(xy 7.937649 -304.82695) (xy 7.884865 -304.808943) (xy 7.835265 -304.783442) (xy 7.789907 -304.750991)
			(xy 7.749758 -304.712282) (xy 7.715672 -304.668139) (xy 7.688376 -304.619504) (xy 7.668453 -304.567413)
			(xy 7.656327 -304.512976) (xy 7.652256 -304.457354) (xy 2.97434 -304.457354) (xy 2.97434 -305.159664)
			(xy 12.577824 -305.159664) (xy 12.581895 -305.104042) (xy 12.594021 -305.049605) (xy 12.613944 -304.997514)
			(xy 12.64124 -304.948879) (xy 12.675326 -304.904736) (xy 12.715475 -304.866027) (xy 12.760833 -304.833576)
			(xy 12.810433 -304.808075) (xy 12.863217 -304.790068) (xy 12.91806 -304.779938) (xy 12.973794 -304.777901)
			(xy 13.029231 -304.784001) (xy 13.083188 -304.798107) (xy 13.134517 -304.819919) (xy 13.182123 -304.848973)
			(xy 13.224991 -304.884648) (xy 13.262208 -304.926185) (xy 13.292981 -304.972698) (xy 13.316653 -305.023195)
			(xy 13.332721 -305.076602) (xy 13.340841 -305.131778) (xy 13.34135 -305.159664) (xy 13.340841 -305.18755)
			(xy 13.332721 -305.242726) (xy 13.316653 -305.296133) (xy 13.292981 -305.34663) (xy 13.262208 -305.393143)
			(xy 13.224991 -305.43468) (xy 13.182123 -305.470355) (xy 13.134517 -305.499409) (xy 13.083188 -305.521221)
			(xy 13.029231 -305.535327) (xy 12.973794 -305.541427) (xy 12.91806 -305.53939) (xy 12.863217 -305.52926)
			(xy 12.810433 -305.511253) (xy 12.760833 -305.485752) (xy 12.715475 -305.453301) (xy 12.675326 -305.414592)
			(xy 12.64124 -305.370449) (xy 12.613944 -305.321814) (xy 12.594021 -305.269723) (xy 12.581895 -305.215286)
			(xy 12.577824 -305.159664) (xy 2.97434 -305.159664) (xy 2.97434 -306.115466) (xy 13.635734 -306.115466)
			(xy 13.639805 -306.059844) (xy 13.651931 -306.005407) (xy 13.671854 -305.953316) (xy 13.69915 -305.904681)
			(xy 13.733236 -305.860538) (xy 13.773385 -305.821829) (xy 13.818743 -305.789378) (xy 13.868343 -305.763877)
			(xy 13.921127 -305.74587) (xy 13.97597 -305.73574) (xy 14.031704 -305.733703) (xy 14.087141 -305.739803)
			(xy 14.141098 -305.753909) (xy 14.192427 -305.775721) (xy 14.240033 -305.804775) (xy 14.282901 -305.84045)
			(xy 14.320118 -305.881987) (xy 14.350891 -305.9285) (xy 14.374563 -305.978997) (xy 14.390631 -306.032404)
			(xy 14.398751 -306.08758) (xy 14.39926 -306.115466) (xy 14.398751 -306.143352) (xy 14.390631 -306.198528)
			(xy 14.374563 -306.251935) (xy 14.350891 -306.302432) (xy 14.320118 -306.348945) (xy 14.282901 -306.390482)
			(xy 14.240033 -306.426157) (xy 14.192427 -306.455211) (xy 14.141098 -306.477023) (xy 14.087141 -306.491129)
			(xy 14.031704 -306.497229) (xy 13.97597 -306.495192) (xy 13.921127 -306.485062) (xy 13.868343 -306.467055)
			(xy 13.818743 -306.441554) (xy 13.773385 -306.409103) (xy 13.733236 -306.370394) (xy 13.69915 -306.326251)
			(xy 13.671854 -306.277616) (xy 13.651931 -306.225525) (xy 13.639805 -306.171088) (xy 13.635734 -306.115466)
			(xy 2.97434 -306.115466) (xy 2.97434 -306.731416) (xy 15.643858 -306.731416) (xy 15.647929 -306.675794)
			(xy 15.660055 -306.621357) (xy 15.679978 -306.569266) (xy 15.707274 -306.520631) (xy 15.74136 -306.476488)
			(xy 15.781509 -306.437779) (xy 15.826867 -306.405328) (xy 15.876467 -306.379827) (xy 15.929251 -306.36182)
			(xy 15.984094 -306.35169) (xy 16.039828 -306.349653) (xy 16.095265 -306.355753) (xy 16.149222 -306.369859)
			(xy 16.200551 -306.391671) (xy 16.248157 -306.420725) (xy 16.291025 -306.4564) (xy 16.328242 -306.497937)
			(xy 16.359015 -306.54445) (xy 16.382687 -306.594947) (xy 16.398755 -306.648354) (xy 16.406875 -306.70353)
			(xy 16.407384 -306.731416) (xy 16.406875 -306.759302) (xy 16.398755 -306.814478) (xy 16.382687 -306.867885)
			(xy 16.359015 -306.918382) (xy 16.328242 -306.964895) (xy 16.291025 -307.006432) (xy 16.248157 -307.042107)
			(xy 16.200551 -307.071161) (xy 16.149222 -307.092973) (xy 16.095265 -307.107079) (xy 16.039828 -307.113179)
			(xy 15.984094 -307.111142) (xy 15.929251 -307.101012) (xy 15.876467 -307.083005) (xy 15.826867 -307.057504)
			(xy 15.781509 -307.025053) (xy 15.74136 -306.986344) (xy 15.707274 -306.942201) (xy 15.679978 -306.893566)
			(xy 15.660055 -306.841475) (xy 15.647929 -306.787038) (xy 15.643858 -306.731416) (xy 2.97434 -306.731416)
			(xy 2.97434 -307.621686) (xy 12.02385 -307.621686) (xy 12.027921 -307.566064) (xy 12.040047 -307.511627)
			(xy 12.05997 -307.459536) (xy 12.087266 -307.410901) (xy 12.121352 -307.366758) (xy 12.161501 -307.328049)
			(xy 12.206859 -307.295598) (xy 12.256459 -307.270097) (xy 12.309243 -307.25209) (xy 12.364086 -307.24196)
			(xy 12.41982 -307.239923) (xy 12.475257 -307.246023) (xy 12.529214 -307.260129) (xy 12.580543 -307.281941)
			(xy 12.628149 -307.310995) (xy 12.671017 -307.34667) (xy 12.708234 -307.388207) (xy 12.739007 -307.43472)
			(xy 12.750091 -307.458364) (xy 13.739366 -307.458364) (xy 13.743437 -307.402742) (xy 13.755563 -307.348305)
			(xy 13.775486 -307.296214) (xy 13.802782 -307.247579) (xy 13.836868 -307.203436) (xy 13.877017 -307.164727)
			(xy 13.922375 -307.132276) (xy 13.971975 -307.106775) (xy 14.024759 -307.088768) (xy 14.079602 -307.078638)
			(xy 14.135336 -307.076601) (xy 14.190773 -307.082701) (xy 14.24473 -307.096807) (xy 14.296059 -307.118619)
			(xy 14.343665 -307.147673) (xy 14.386533 -307.183348) (xy 14.42375 -307.224885) (xy 14.454523 -307.271398)
			(xy 14.478195 -307.321895) (xy 14.494263 -307.375302) (xy 14.502383 -307.430478) (xy 14.502892 -307.458364)
			(xy 14.502383 -307.48625) (xy 14.494263 -307.541426) (xy 14.478195 -307.594833) (xy 14.454523 -307.64533)
			(xy 14.42375 -307.691843) (xy 14.386533 -307.73338) (xy 14.343665 -307.769055) (xy 14.296059 -307.798109)
			(xy 14.24473 -307.819921) (xy 14.190773 -307.834027) (xy 14.135336 -307.840127) (xy 14.079602 -307.83809)
			(xy 14.024759 -307.82796) (xy 13.971975 -307.809953) (xy 13.922375 -307.784452) (xy 13.877017 -307.752001)
			(xy 13.836868 -307.713292) (xy 13.802782 -307.669149) (xy 13.775486 -307.620514) (xy 13.755563 -307.568423)
			(xy 13.743437 -307.513986) (xy 13.739366 -307.458364) (xy 12.750091 -307.458364) (xy 12.762679 -307.485217)
			(xy 12.778747 -307.538624) (xy 12.786867 -307.5938) (xy 12.787376 -307.621686) (xy 12.786867 -307.649572)
			(xy 12.778747 -307.704748) (xy 12.762679 -307.758155) (xy 12.739007 -307.808652) (xy 12.708234 -307.855165)
			(xy 12.671017 -307.896702) (xy 12.628149 -307.932377) (xy 12.580543 -307.961431) (xy 12.529214 -307.983243)
			(xy 12.475257 -307.997349) (xy 12.41982 -308.003449) (xy 12.364086 -308.001412) (xy 12.309243 -307.991282)
			(xy 12.256459 -307.973275) (xy 12.206859 -307.947774) (xy 12.161501 -307.915323) (xy 12.121352 -307.876614)
			(xy 12.087266 -307.832471) (xy 12.05997 -307.783836) (xy 12.040047 -307.731745) (xy 12.027921 -307.677308)
			(xy 12.02385 -307.621686) (xy 2.97434 -307.621686) (xy 2.97434 -307.802026) (xy 2.974822 -307.812773)
			(xy 2.983646 -307.832371) (xy 2.991358 -307.839872) (xy 3.056382 -307.897784) (xy 3.076702 -307.904134)
			(xy 3.087878 -307.902864) (xy 3.190563 -307.891547) (xy 3.396816 -307.879472) (xy 3.50012 -307.878734)
			(xy 3.58417 -307.879234) (xy 3.75208 -307.887233) (xy 3.919419 -307.903212) (xy 4.085809 -307.927135)
			(xy 4.250871 -307.958948) (xy 4.414233 -307.998579) (xy 4.575524 -308.045939) (xy 4.734379 -308.100919)
			(xy 4.890438 -308.163395) (xy 5.043348 -308.233227) (xy 5.192761 -308.310255) (xy 5.33834 -308.394305)
			(xy 5.479756 -308.485187) (xy 5.616686 -308.582695) (xy 5.748822 -308.686608) (xy 5.875864 -308.79669)
			(xy 5.997524 -308.912692) (xy 6.013096 -308.929024) (xy 13.201648 -308.929024) (xy 13.205719 -308.873402)
			(xy 13.217845 -308.818965) (xy 13.237768 -308.766874) (xy 13.265064 -308.718239) (xy 13.29915 -308.674096)
			(xy 13.339299 -308.635387) (xy 13.384657 -308.602936) (xy 13.434257 -308.577435) (xy 13.487041 -308.559428)
			(xy 13.541884 -308.549298) (xy 13.597618 -308.547261) (xy 13.653055 -308.553361) (xy 13.707012 -308.567467)
			(xy 13.758341 -308.589279) (xy 13.805947 -308.618333) (xy 13.848815 -308.654008) (xy 13.886032 -308.695545)
			(xy 13.916805 -308.742058) (xy 13.940477 -308.792555) (xy 13.956545 -308.845962) (xy 13.964665 -308.901138)
			(xy 13.965174 -308.929024) (xy 13.964665 -308.95691) (xy 13.956545 -309.012086) (xy 13.940477 -309.065493)
			(xy 13.916805 -309.11599) (xy 13.886032 -309.162503) (xy 13.848815 -309.20404) (xy 13.805947 -309.239715)
			(xy 13.758341 -309.268769) (xy 13.707012 -309.290581) (xy 13.653055 -309.304687) (xy 13.597618 -309.310787)
			(xy 13.541884 -309.30875) (xy 13.487041 -309.29862) (xy 13.434257 -309.280613) (xy 13.384657 -309.255112)
			(xy 13.339299 -309.222661) (xy 13.29915 -309.183952) (xy 13.265064 -309.139809) (xy 13.237768 -309.091174)
			(xy 13.217845 -309.039083) (xy 13.205719 -308.984646) (xy 13.201648 -308.929024) (xy 6.013096 -308.929024)
			(xy 6.113526 -309.034352) (xy 6.223608 -309.161394) (xy 6.327521 -309.29353) (xy 6.425029 -309.43046)
			(xy 6.515911 -309.571876) (xy 6.599961 -309.717455) (xy 6.676989 -309.866868) (xy 6.746821 -310.019778)
			(xy 6.809297 -310.175837) (xy 6.864277 -310.334692) (xy 6.911637 -310.495983) (xy 6.951268 -310.659345)
			(xy 6.983081 -310.824407) (xy 7.007004 -310.990797) (xy 7.022983 -311.158136) (xy 7.030982 -311.326046)
			(xy 7.030982 -311.494146) (xy 7.022983 -311.662056) (xy 7.007004 -311.829395) (xy 6.983081 -311.995785)
			(xy 6.951268 -312.160847) (xy 6.911637 -312.324209) (xy 6.864277 -312.4855) (xy 6.809297 -312.644355)
			(xy 6.746821 -312.800414) (xy 6.676989 -312.953324) (xy 6.599961 -313.102737) (xy 6.515911 -313.248316)
			(xy 6.425029 -313.389732) (xy 6.327521 -313.526662) (xy 6.223608 -313.658798) (xy 6.113526 -313.78584)
			(xy 5.997524 -313.9075) (xy 5.875864 -314.023502) (xy 5.748822 -314.133584) (xy 5.616686 -314.237497)
			(xy 5.479756 -314.335005) (xy 5.33834 -314.425887) (xy 5.192761 -314.509937) (xy 5.043348 -314.586965)
			(xy 4.890438 -314.656797) (xy 4.734379 -314.719273) (xy 4.575524 -314.774253) (xy 4.414233 -314.821613)
			(xy 4.250871 -314.861244) (xy 4.085809 -314.893057) (xy 3.919419 -314.91698) (xy 3.75208 -314.932959)
			(xy 3.58417 -314.940958) (xy 3.50012 -314.941458) (xy 3.396817 -314.940708) (xy 3.190563 -314.928638)
			(xy 3.087878 -314.917328) (xy 3.076702 -314.916058) (xy 3.056382 -314.922408) (xy 2.991358 -314.98032)
			(xy 2.983744 -314.987888) (xy 2.974957 -315.007447) (xy 2.97434 -315.018166) (xy 2.97434 -315.788802)
			(xy 2.973915 -315.798871) (xy 2.966193 -315.817469) (xy 2.959354 -315.82487) (xy 1.742694 -317.04153)
			(xy 1.735328 -317.048642) (xy 1.727708 -317.067438) (xy 1.727708 -318.52997) (xy 10.590784 -318.52997)
			(xy 10.591212 -318.502598) (xy 10.599036 -318.448417) (xy 10.614533 -318.395912) (xy 10.637383 -318.346166)
			(xy 10.667118 -318.300202) (xy 10.684764 -318.279272) (xy 10.69086 -318.27216) (xy 10.69721 -318.255142)
			(xy 10.69721 -318.169798) (xy 10.69086 -318.15278) (xy 10.684764 -318.145668) (xy 10.667138 -318.124726)
			(xy 10.637425 -318.078755) (xy 10.614587 -318.02901) (xy 10.599093 -317.976512) (xy 10.591261 -317.922338)
			(xy 10.590784 -317.89497) (xy 10.59125 -317.867718) (xy 10.59901 -317.81377) (xy 10.614369 -317.761476)
			(xy 10.637013 -317.711899) (xy 10.666482 -317.666049) (xy 10.702175 -317.624859) (xy 10.743367 -317.589168)
			(xy 10.789218 -317.559702) (xy 10.838796 -317.537061) (xy 10.891092 -317.521706) (xy 10.94504 -317.513948)
			(xy 10.972292 -317.513462) (xy 10.999663 -317.513918) (xy 11.053843 -317.521736) (xy 11.106347 -317.537226)
			(xy 11.156093 -317.560071) (xy 11.202059 -317.589799) (xy 11.22299 -317.607442) (xy 11.230102 -317.613538)
			(xy 11.24712 -317.619888) (xy 11.332464 -317.619888) (xy 11.349482 -317.613538) (xy 11.356594 -317.607442)
			(xy 11.377527 -317.589801) (xy 11.423495 -317.560077) (xy 11.473241 -317.537231) (xy 11.525743 -317.521735)
			(xy 11.579921 -317.513906) (xy 11.634663 -317.513906) (xy 11.688841 -317.521735) (xy 11.741343 -317.537231)
			(xy 11.791089 -317.560077) (xy 11.837057 -317.589801) (xy 11.85799 -317.607442) (xy 11.865102 -317.613538)
			(xy 11.88212 -317.619888) (xy 11.967464 -317.619888) (xy 11.984482 -317.613538) (xy 11.991594 -317.607442)
			(xy 12.012523 -317.589799) (xy 12.058496 -317.560086) (xy 12.108244 -317.53725) (xy 12.160746 -317.52176)
			(xy 12.214922 -317.513934) (xy 12.242292 -317.513462) (xy 12.269542 -317.513985) (xy 12.323487 -317.52174)
			(xy 12.375779 -317.537092) (xy 12.425354 -317.55973) (xy 12.471203 -317.589193) (xy 12.512393 -317.624881)
			(xy 12.548084 -317.666067) (xy 12.577551 -317.711913) (xy 12.600194 -317.761486) (xy 12.615552 -317.813776)
			(xy 12.623312 -317.86772) (xy 12.6238 -317.89497) (xy 12.623316 -317.92234) (xy 12.615503 -317.976518)
			(xy 12.600018 -318.029021) (xy 12.57718 -318.078768) (xy 12.547459 -318.124736) (xy 12.52982 -318.145668)
			(xy 12.523724 -318.15278) (xy 12.517374 -318.169798) (xy 12.517374 -318.255142) (xy 12.523724 -318.27216)
			(xy 12.52982 -318.279272) (xy 12.547463 -318.300201) (xy 12.577173 -318.346175) (xy 12.600008 -318.395923)
			(xy 12.615498 -318.448425) (xy 12.623326 -318.502601) (xy 12.6238 -318.52997) (xy 12.623317 -318.557222)
			(xy 12.615564 -318.611173) (xy 12.600211 -318.663471) (xy 12.577571 -318.713052) (xy 12.548106 -318.758905)
			(xy 12.512414 -318.800099) (xy 12.471223 -318.835793) (xy 12.425371 -318.865261) (xy 12.375792 -318.887903)
			(xy 12.323495 -318.903259) (xy 12.269544 -318.911015) (xy 12.242292 -318.911478) (xy 12.214921 -318.911022)
			(xy 12.160742 -318.903203) (xy 12.108238 -318.887711) (xy 12.058491 -318.864867) (xy 12.012525 -318.83514)
			(xy 11.991594 -318.817498) (xy 11.984482 -318.811402) (xy 11.967464 -318.805052) (xy 11.88212 -318.805052)
			(xy 11.865102 -318.811402) (xy 11.85799 -318.817498) (xy 11.837057 -318.835139) (xy 11.791089 -318.864863)
			(xy 11.741343 -318.887709) (xy 11.688841 -318.903205) (xy 11.634663 -318.911034) (xy 11.579921 -318.911034)
			(xy 11.525743 -318.903205) (xy 11.473241 -318.887709) (xy 11.423495 -318.864863) (xy 11.377527 -318.835139)
			(xy 11.356594 -318.817498) (xy 11.349482 -318.811402) (xy 11.332464 -318.805052) (xy 11.24712 -318.805052)
			(xy 11.230102 -318.811402) (xy 11.22299 -318.817498) (xy 11.202072 -318.835155) (xy 11.156096 -318.864864)
			(xy 11.106344 -318.887697) (xy 11.053841 -318.903184) (xy 10.999662 -318.911007) (xy 10.972292 -318.911478)
			(xy 10.945038 -318.911052) (xy 10.891084 -318.903293) (xy 10.838783 -318.887935) (xy 10.789201 -318.865289)
			(xy 10.743347 -318.835817) (xy 10.702153 -318.80012) (xy 10.66646 -318.758923) (xy 10.636993 -318.713065)
			(xy 10.614352 -318.663481) (xy 10.598999 -318.611179) (xy 10.591245 -318.557224) (xy 10.590784 -318.52997)
			(xy 1.727708 -318.52997) (xy 1.727708 -323.153278) (xy 14.462504 -323.153278) (xy 14.466575 -323.097656)
			(xy 14.478701 -323.043219) (xy 14.498624 -322.991128) (xy 14.52592 -322.942493) (xy 14.560006 -322.89835)
			(xy 14.600155 -322.859641) (xy 14.645513 -322.82719) (xy 14.695113 -322.801689) (xy 14.747897 -322.783682)
			(xy 14.80274 -322.773552) (xy 14.858474 -322.771515) (xy 14.913911 -322.777615) (xy 14.967868 -322.791721)
			(xy 15.019197 -322.813533) (xy 15.066803 -322.842587) (xy 15.109671 -322.878262) (xy 15.146888 -322.919799)
			(xy 15.177661 -322.966312) (xy 15.201333 -323.016809) (xy 15.217401 -323.070216) (xy 15.225521 -323.125392)
			(xy 15.22603 -323.153278) (xy 15.225521 -323.181164) (xy 15.217401 -323.23634) (xy 15.201333 -323.289747)
			(xy 15.177661 -323.340244) (xy 15.146888 -323.386757) (xy 15.109671 -323.428294) (xy 15.066803 -323.463969)
			(xy 15.019197 -323.493023) (xy 14.967868 -323.514835) (xy 14.913911 -323.528941) (xy 14.858474 -323.535041)
			(xy 14.80274 -323.533004) (xy 14.747897 -323.522874) (xy 14.695113 -323.504867) (xy 14.645513 -323.479366)
			(xy 14.600155 -323.446915) (xy 14.560006 -323.408206) (xy 14.52592 -323.364063) (xy 14.498624 -323.315428)
			(xy 14.478701 -323.263337) (xy 14.466575 -323.2089) (xy 14.462504 -323.153278) (xy 1.727708 -323.153278)
			(xy 1.727708 -348.976496) (xy 4.708641 -348.976496) (xy 4.708641 -348.847356) (xy 4.716591 -348.718461)
			(xy 4.732461 -348.590301) (xy 4.75619 -348.46336) (xy 4.787689 -348.338121) (xy 4.826838 -348.215058)
			(xy 4.873489 -348.094639) (xy 4.927464 -347.97732) (xy 4.988559 -347.863546) (xy 5.056542 -347.753749)
			(xy 5.131156 -347.648346) (xy 5.212117 -347.547736) (xy 5.299117 -347.452301) (xy 5.391828 -347.362402)
			(xy 5.489898 -347.278381) (xy 5.592953 -347.200557) (xy 5.700604 -347.129225) (xy 5.812443 -347.064655)
			(xy 5.928044 -347.007093) (xy 6.046969 -346.956756) (xy 6.168768 -346.913836) (xy 6.292978 -346.878495)
			(xy 6.419127 -346.850868) (xy 6.546739 -346.831059) (xy 6.675328 -346.819143) (xy 6.804406 -346.815167)
			(xy 6.933484 -346.819143) (xy 7.062073 -346.831059) (xy 7.189685 -346.850868) (xy 7.315834 -346.878495)
			(xy 7.440044 -346.913836) (xy 7.561843 -346.956756) (xy 7.680768 -347.007093) (xy 7.796369 -347.064655)
			(xy 7.908208 -347.129225) (xy 8.015859 -347.200557) (xy 8.118914 -347.278381) (xy 8.216984 -347.362402)
			(xy 8.309695 -347.452301) (xy 8.396695 -347.547736) (xy 8.477656 -347.648346) (xy 8.55227 -347.753749)
			(xy 8.620253 -347.863546) (xy 8.681348 -347.97732) (xy 8.735323 -348.094639) (xy 8.781974 -348.215058)
			(xy 8.821123 -348.338121) (xy 8.852622 -348.46336) (xy 8.876351 -348.590301) (xy 8.892221 -348.718461)
			(xy 8.900171 -348.847356) (xy 8.900668 -348.911926) (xy 8.900171 -348.976496) (xy 8.892221 -349.105391)
			(xy 8.876351 -349.233551) (xy 8.852622 -349.360492) (xy 8.821123 -349.485731) (xy 8.781974 -349.608794)
			(xy 8.735323 -349.729213) (xy 8.681348 -349.846532) (xy 8.620253 -349.960306) (xy 8.55227 -350.070103)
			(xy 8.477656 -350.175506) (xy 8.396695 -350.276116) (xy 8.309695 -350.371551) (xy 8.216984 -350.46145)
			(xy 8.118914 -350.545471) (xy 8.015859 -350.623295) (xy 7.908208 -350.694627) (xy 7.796369 -350.759197)
			(xy 7.680768 -350.816759) (xy 7.561843 -350.867096) (xy 7.440044 -350.910016) (xy 7.315834 -350.945357)
			(xy 7.189685 -350.972984) (xy 7.062073 -350.992793) (xy 6.933484 -351.004709) (xy 6.804406 -351.008686)
			(xy 6.675328 -351.004709) (xy 6.546739 -350.992793) (xy 6.419127 -350.972984) (xy 6.292978 -350.945357)
			(xy 6.168768 -350.910016) (xy 6.046969 -350.867096) (xy 5.928044 -350.816759) (xy 5.812443 -350.759197)
			(xy 5.700604 -350.694627) (xy 5.592953 -350.623295) (xy 5.489898 -350.545471) (xy 5.391828 -350.46145)
			(xy 5.299117 -350.371551) (xy 5.212117 -350.276116) (xy 5.131156 -350.175506) (xy 5.056542 -350.070103)
			(xy 4.988559 -349.960306) (xy 4.927464 -349.846532) (xy 4.873489 -349.729213) (xy 4.826838 -349.608794)
			(xy 4.787689 -349.485731) (xy 4.75619 -349.360492) (xy 4.732461 -349.233551) (xy 4.716591 -349.105391)
			(xy 4.708641 -348.976496) (xy 1.727708 -348.976496) (xy 1.727708 -365.288322) (xy 2.818128 -365.288322)
			(xy 2.822199 -365.2327) (xy 2.834325 -365.178263) (xy 2.854248 -365.126172) (xy 2.881544 -365.077537)
			(xy 2.91563 -365.033394) (xy 2.955779 -364.994685) (xy 3.001137 -364.962234) (xy 3.050737 -364.936733)
			(xy 3.103521 -364.918726) (xy 3.158364 -364.908596) (xy 3.214098 -364.906559) (xy 3.269535 -364.912659)
			(xy 3.323492 -364.926765) (xy 3.374821 -364.948577) (xy 3.422427 -364.977631) (xy 3.465295 -365.013306)
			(xy 3.502512 -365.054843) (xy 3.533285 -365.101356) (xy 3.556957 -365.151853) (xy 3.573025 -365.20526)
			(xy 3.581145 -365.260436) (xy 3.581654 -365.288322) (xy 3.581145 -365.316208) (xy 3.573025 -365.371384)
			(xy 3.56676 -365.392208) (xy 7.202932 -365.392208) (xy 7.203418 -365.364957) (xy 7.211174 -365.311009)
			(xy 7.226529 -365.258714) (xy 7.249171 -365.209137) (xy 7.278637 -365.163287) (xy 7.314328 -365.122096)
			(xy 7.355519 -365.086405) (xy 7.401369 -365.056939) (xy 7.450946 -365.034297) (xy 7.503241 -365.018942)
			(xy 7.557189 -365.011186) (xy 7.611691 -365.011186) (xy 7.665639 -365.018942) (xy 7.717934 -365.034297)
			(xy 7.767511 -365.056939) (xy 7.813361 -365.086405) (xy 7.854552 -365.122096) (xy 7.890243 -365.163287)
			(xy 7.919709 -365.209137) (xy 7.942351 -365.258714) (xy 7.957706 -365.311009) (xy 7.965462 -365.364957)
			(xy 7.965948 -365.392208) (xy 7.965512 -365.418628) (xy 7.958226 -365.470963) (xy 7.94378 -365.521791)
			(xy 7.922453 -365.570135) (xy 7.894652 -365.61507) (xy 7.86091 -365.655735) (xy 7.821875 -365.691348)
			(xy 7.80034 -365.70666) (xy 7.788863 -365.715046) (xy 7.770739 -365.736932) (xy 7.759346 -365.762963)
			(xy 7.755566 -365.791126) (xy 7.759691 -365.819241) (xy 7.771402 -365.845131) (xy 7.789793 -365.866792)
			(xy 7.801356 -365.875062) (xy 7.823355 -365.890327) (xy 7.863301 -365.925982) (xy 7.897866 -365.966875)
			(xy 7.926371 -366.012201) (xy 7.948254 -366.061069) (xy 7.963087 -366.112518) (xy 7.970576 -366.165536)
			(xy 7.971028 -366.192308) (xy 7.970542 -366.219559) (xy 7.962786 -366.273507) (xy 7.947431 -366.325802)
			(xy 7.924789 -366.375379) (xy 7.895323 -366.421229) (xy 7.859632 -366.46242) (xy 7.818441 -366.498111)
			(xy 7.772591 -366.527577) (xy 7.723014 -366.550219) (xy 7.670719 -366.565574) (xy 7.616771 -366.57333)
			(xy 7.562269 -366.57333) (xy 7.508321 -366.565574) (xy 7.456026 -366.550219) (xy 7.406449 -366.527577)
			(xy 7.360599 -366.498111) (xy 7.319408 -366.46242) (xy 7.283717 -366.421229) (xy 7.254251 -366.375379)
			(xy 7.231609 -366.325802) (xy 7.216254 -366.273507) (xy 7.208498 -366.219559) (xy 7.208012 -366.192308)
			(xy 7.208434 -366.165887) (xy 7.215719 -366.11355) (xy 7.230165 -366.062722) (xy 7.251495 -366.014376)
			(xy 7.279298 -365.969441) (xy 7.313043 -365.928777) (xy 7.352082 -365.893166) (xy 7.37362 -365.877856)
			(xy 7.385086 -365.869453) (xy 7.403216 -365.847574) (xy 7.414615 -365.821545) (xy 7.418399 -365.793383)
			(xy 7.414275 -365.765268) (xy 7.402562 -365.739379) (xy 7.384168 -365.717721) (xy 7.372604 -365.709454)
			(xy 7.350584 -365.694217) (xy 7.31064 -365.658556) (xy 7.276077 -365.617658) (xy 7.247575 -365.572327)
			(xy 7.225695 -365.523455) (xy 7.210867 -365.472002) (xy 7.203382 -365.418981) (xy 7.202932 -365.392208)
			(xy 3.56676 -365.392208) (xy 3.556957 -365.424791) (xy 3.533285 -365.475288) (xy 3.502512 -365.521801)
			(xy 3.465295 -365.563338) (xy 3.422427 -365.599013) (xy 3.374821 -365.628067) (xy 3.323492 -365.649879)
			(xy 3.269535 -365.663985) (xy 3.214098 -365.670085) (xy 3.158364 -365.668048) (xy 3.103521 -365.657918)
			(xy 3.050737 -365.639911) (xy 3.001137 -365.61441) (xy 2.955779 -365.581959) (xy 2.91563 -365.54325)
			(xy 2.881544 -365.499107) (xy 2.854248 -365.450472) (xy 2.834325 -365.398381) (xy 2.822199 -365.343944)
			(xy 2.818128 -365.288322) (xy 1.727708 -365.288322) (xy 1.727708 -368.23269) (xy 5.613144 -368.23269)
			(xy 5.617215 -368.177068) (xy 5.629341 -368.122631) (xy 5.649264 -368.07054) (xy 5.67656 -368.021905)
			(xy 5.710646 -367.977762) (xy 5.750795 -367.939053) (xy 5.796153 -367.906602) (xy 5.845753 -367.881101)
			(xy 5.898537 -367.863094) (xy 5.95338 -367.852964) (xy 6.009114 -367.850927) (xy 6.064551 -367.857027)
			(xy 6.118508 -367.871133) (xy 6.169837 -367.892945) (xy 6.217443 -367.921999) (xy 6.260311 -367.957674)
			(xy 6.297528 -367.999211) (xy 6.328301 -368.045724) (xy 6.351973 -368.096221) (xy 6.368041 -368.149628)
			(xy 6.376161 -368.204804) (xy 6.37667 -368.23269) (xy 6.376161 -368.260576) (xy 6.368041 -368.315752)
			(xy 6.351973 -368.369159) (xy 6.328301 -368.419656) (xy 6.297528 -368.466169) (xy 6.260311 -368.507706)
			(xy 6.217443 -368.543381) (xy 6.169837 -368.572435) (xy 6.118508 -368.594247) (xy 6.064551 -368.608353)
			(xy 6.009114 -368.614453) (xy 5.95338 -368.612416) (xy 5.898537 -368.602286) (xy 5.845753 -368.584279)
			(xy 5.796153 -368.558778) (xy 5.750795 -368.526327) (xy 5.710646 -368.487618) (xy 5.67656 -368.443475)
			(xy 5.649264 -368.39484) (xy 5.629341 -368.342749) (xy 5.617215 -368.288312) (xy 5.613144 -368.23269)
			(xy 1.727708 -368.23269) (xy 1.727708 -372.100847) (xy 8.642336 -372.100847) (xy 8.642336 -372.040913)
			(xy 8.650159 -371.981491) (xy 8.665671 -371.923598) (xy 8.688607 -371.868226) (xy 8.718575 -371.81632)
			(xy 8.755061 -371.768771) (xy 8.797441 -371.726391) (xy 8.84499 -371.689905) (xy 8.896896 -371.659937)
			(xy 8.952268 -371.637001) (xy 9.010161 -371.621489) (xy 9.069583 -371.613666) (xy 9.09955 -371.613176)
			(xy 9.96315 -371.613176) (xy 9.993118 -371.613658) (xy 10.052541 -371.621481) (xy 10.110435 -371.636994)
			(xy 10.165808 -371.65993) (xy 10.217714 -371.689898) (xy 10.265264 -371.726385) (xy 10.307645 -371.768766)
			(xy 10.344132 -371.816316) (xy 10.3741 -371.868222) (xy 10.397036 -371.923595) (xy 10.412549 -371.981489)
			(xy 10.420372 -372.040912) (xy 10.420372 -372.100848) (xy 10.412549 -372.160271) (xy 10.397036 -372.218165)
			(xy 10.3741 -372.273538) (xy 10.344132 -372.325444) (xy 10.307645 -372.372994) (xy 10.265264 -372.415375)
			(xy 10.217714 -372.451862) (xy 10.165808 -372.48183) (xy 10.110435 -372.504766) (xy 10.052541 -372.520279)
			(xy 9.993118 -372.528102) (xy 9.96315 -372.528592) (xy 9.09955 -372.528592) (xy 9.069583 -372.528094)
			(xy 9.010161 -372.520271) (xy 8.952268 -372.504759) (xy 8.896896 -372.481823) (xy 8.84499 -372.451855)
			(xy 8.797441 -372.415369) (xy 8.755061 -372.372989) (xy 8.718575 -372.32544) (xy 8.688607 -372.273534)
			(xy 8.665671 -372.218162) (xy 8.650159 -372.160269) (xy 8.642336 -372.100847) (xy 1.727708 -372.100847)
			(xy 1.727708 -372.921784) (xy 3.759198 -372.921784) (xy 3.763269 -372.866162) (xy 3.775395 -372.811725)
			(xy 3.795318 -372.759634) (xy 3.822614 -372.710999) (xy 3.8567 -372.666856) (xy 3.896849 -372.628147)
			(xy 3.942207 -372.595696) (xy 3.991807 -372.570195) (xy 4.044591 -372.552188) (xy 4.099434 -372.542058)
			(xy 4.155168 -372.540021) (xy 4.210605 -372.546121) (xy 4.264562 -372.560227) (xy 4.315891 -372.582039)
			(xy 4.363497 -372.611093) (xy 4.406365 -372.646768) (xy 4.443582 -372.688305) (xy 4.474355 -372.734818)
			(xy 4.498027 -372.785315) (xy 4.514095 -372.838722) (xy 4.522215 -372.893898) (xy 4.522724 -372.921784)
			(xy 4.522215 -372.94967) (xy 4.514095 -373.004846) (xy 4.498027 -373.058253) (xy 4.474355 -373.10875)
			(xy 4.443582 -373.155263) (xy 4.406365 -373.1968) (xy 4.363497 -373.232475) (xy 4.315891 -373.261529)
			(xy 4.264562 -373.283341) (xy 4.210605 -373.297447) (xy 4.155168 -373.303547) (xy 4.099434 -373.30151)
			(xy 4.044591 -373.29138) (xy 3.991807 -373.273373) (xy 3.942207 -373.247872) (xy 3.896849 -373.215421)
			(xy 3.8567 -373.176712) (xy 3.822614 -373.132569) (xy 3.795318 -373.083934) (xy 3.775395 -373.031843)
			(xy 3.763269 -372.977406) (xy 3.759198 -372.921784) (xy 1.727708 -372.921784) (xy 1.727708 -379.540516)
			(xy 2.180588 -379.540516) (xy 2.184659 -379.484894) (xy 2.196785 -379.430457) (xy 2.216708 -379.378366)
			(xy 2.244004 -379.329731) (xy 2.27809 -379.285588) (xy 2.318239 -379.246879) (xy 2.363597 -379.214428)
			(xy 2.413197 -379.188927) (xy 2.465981 -379.17092) (xy 2.520824 -379.16079) (xy 2.576558 -379.158753)
			(xy 2.631995 -379.164853) (xy 2.685952 -379.178959) (xy 2.737281 -379.200771) (xy 2.784887 -379.229825)
			(xy 2.827755 -379.2655) (xy 2.864972 -379.307037) (xy 2.895745 -379.35355) (xy 2.919417 -379.404047)
			(xy 2.935485 -379.457454) (xy 2.943605 -379.51263) (xy 2.944114 -379.540516) (xy 3.653788 -379.540516)
			(xy 3.657859 -379.484894) (xy 3.669985 -379.430457) (xy 3.689908 -379.378366) (xy 3.717204 -379.329731)
			(xy 3.75129 -379.285588) (xy 3.791439 -379.246879) (xy 3.836797 -379.214428) (xy 3.886397 -379.188927)
			(xy 3.939181 -379.17092) (xy 3.994024 -379.16079) (xy 4.049758 -379.158753) (xy 4.105195 -379.164853)
			(xy 4.159152 -379.178959) (xy 4.210481 -379.200771) (xy 4.258087 -379.229825) (xy 4.300955 -379.2655)
			(xy 4.338172 -379.307037) (xy 4.368945 -379.35355) (xy 4.392617 -379.404047) (xy 4.408685 -379.457454)
			(xy 4.416805 -379.51263) (xy 4.417314 -379.540516) (xy 4.416805 -379.568402) (xy 4.408685 -379.623578)
			(xy 4.392617 -379.676985) (xy 4.368945 -379.727482) (xy 4.338172 -379.773995) (xy 4.300955 -379.815532)
			(xy 4.258087 -379.851207) (xy 4.210481 -379.880261) (xy 4.159152 -379.902073) (xy 4.105195 -379.916179)
			(xy 4.049758 -379.922279) (xy 3.994024 -379.920242) (xy 3.939181 -379.910112) (xy 3.886397 -379.892105)
			(xy 3.836797 -379.866604) (xy 3.791439 -379.834153) (xy 3.75129 -379.795444) (xy 3.717204 -379.751301)
			(xy 3.689908 -379.702666) (xy 3.669985 -379.650575) (xy 3.657859 -379.596138) (xy 3.653788 -379.540516)
			(xy 2.944114 -379.540516) (xy 2.943605 -379.568402) (xy 2.935485 -379.623578) (xy 2.919417 -379.676985)
			(xy 2.895745 -379.727482) (xy 2.864972 -379.773995) (xy 2.827755 -379.815532) (xy 2.784887 -379.851207)
			(xy 2.737281 -379.880261) (xy 2.685952 -379.902073) (xy 2.631995 -379.916179) (xy 2.576558 -379.922279)
			(xy 2.520824 -379.920242) (xy 2.465981 -379.910112) (xy 2.413197 -379.892105) (xy 2.363597 -379.866604)
			(xy 2.318239 -379.834153) (xy 2.27809 -379.795444) (xy 2.244004 -379.751301) (xy 2.216708 -379.702666)
			(xy 2.196785 -379.650575) (xy 2.184659 -379.596138) (xy 2.180588 -379.540516) (xy 1.727708 -379.540516)
			(xy 1.727708 -379.767084) (xy 1.751076 -379.795278) (xy 1.769364 -379.79858) (xy 1.79739 -379.804203)
			(xy 1.851523 -379.822557) (xy 1.902402 -379.848609) (xy 1.948937 -379.881801) (xy 1.990135 -379.921424)
			(xy 2.025115 -379.966632) (xy 2.053129 -380.016457) (xy 2.073578 -380.069834) (xy 2.086025 -380.125622)
			(xy 2.090203 -380.18263) (xy 2.086025 -380.239637) (xy 2.073578 -380.295426) (xy 2.053129 -380.348803)
			(xy 2.025115 -380.398628) (xy 1.990136 -380.443835) (xy 1.948938 -380.483459) (xy 1.902402 -380.516651)
			(xy 1.851524 -380.542703) (xy 1.797391 -380.561057) (xy 1.769364 -380.566676) (xy 1.751076 -380.569978)
			(xy 1.727708 -380.598172) (xy 1.727708 -380.909576) (xy 1.727947 -380.917606) (xy 1.732865 -380.93289)
			(xy 1.73736 -380.939548) (xy 1.758188 -380.967996) (xy 1.77038 -380.97714) (xy 1.777492 -380.97968)
			(xy 1.803641 -380.989614) (xy 1.852943 -381.016039) (xy 1.89786 -381.049375) (xy 1.937431 -381.08891)
			(xy 1.97081 -381.133796) (xy 1.99728 -381.183073) (xy 2.016275 -381.235686) (xy 2.02739 -381.290507)
			(xy 2.030384 -381.346364) (xy 2.030162 -381.348742) (xy 8.047988 -381.348742) (xy 8.052059 -381.29312)
			(xy 8.064185 -381.238683) (xy 8.084108 -381.186592) (xy 8.111404 -381.137957) (xy 8.14549 -381.093814)
			(xy 8.185639 -381.055105) (xy 8.230997 -381.022654) (xy 8.280597 -380.997153) (xy 8.333381 -380.979146)
			(xy 8.388224 -380.969016) (xy 8.443958 -380.966979) (xy 8.499395 -380.973079) (xy 8.553352 -380.987185)
			(xy 8.604681 -381.008997) (xy 8.652287 -381.038051) (xy 8.695155 -381.073726) (xy 8.732372 -381.115263)
			(xy 8.763145 -381.161776) (xy 8.786817 -381.212273) (xy 8.802885 -381.26568) (xy 8.811005 -381.320856)
			(xy 8.811458 -381.345694) (xy 9.548112 -381.345694) (xy 9.552183 -381.290072) (xy 9.564309 -381.235635)
			(xy 9.584232 -381.183544) (xy 9.611528 -381.134909) (xy 9.645614 -381.090766) (xy 9.685763 -381.052057)
			(xy 9.731121 -381.019606) (xy 9.780721 -380.994105) (xy 9.833505 -380.976098) (xy 9.888348 -380.965968)
			(xy 9.944082 -380.963931) (xy 9.999519 -380.970031) (xy 10.053476 -380.984137) (xy 10.104805 -381.005949)
			(xy 10.152411 -381.035003) (xy 10.195279 -381.070678) (xy 10.232496 -381.112215) (xy 10.263269 -381.158728)
			(xy 10.286941 -381.209225) (xy 10.303009 -381.262632) (xy 10.311129 -381.317808) (xy 10.311638 -381.345694)
			(xy 10.311517 -381.352298) (xy 11.832588 -381.352298) (xy 11.836659 -381.296676) (xy 11.848785 -381.242239)
			(xy 11.868708 -381.190148) (xy 11.896004 -381.141513) (xy 11.93009 -381.09737) (xy 11.970239 -381.058661)
			(xy 12.015597 -381.02621) (xy 12.065197 -381.000709) (xy 12.117981 -380.982702) (xy 12.172824 -380.972572)
			(xy 12.228558 -380.970535) (xy 12.283995 -380.976635) (xy 12.337952 -380.990741) (xy 12.389281 -381.012553)
			(xy 12.436887 -381.041607) (xy 12.479755 -381.077282) (xy 12.516972 -381.118819) (xy 12.547745 -381.165332)
			(xy 12.571417 -381.215829) (xy 12.587485 -381.269236) (xy 12.595605 -381.324412) (xy 12.596114 -381.352298)
			(xy 12.595605 -381.380184) (xy 12.590812 -381.41275) (xy 13.548104 -381.41275) (xy 13.552175 -381.357128)
			(xy 13.564301 -381.302691) (xy 13.584224 -381.2506) (xy 13.61152 -381.201965) (xy 13.645606 -381.157822)
			(xy 13.685755 -381.119113) (xy 13.731113 -381.086662) (xy 13.780713 -381.061161) (xy 13.833497 -381.043154)
			(xy 13.88834 -381.033024) (xy 13.944074 -381.030987) (xy 13.999511 -381.037087) (xy 14.053468 -381.051193)
			(xy 14.104797 -381.073005) (xy 14.152403 -381.102059) (xy 14.195271 -381.137734) (xy 14.232488 -381.179271)
			(xy 14.263261 -381.225784) (xy 14.286933 -381.276281) (xy 14.303001 -381.329688) (xy 14.311121 -381.384864)
			(xy 14.31163 -381.41275) (xy 14.311121 -381.440636) (xy 14.303001 -381.495812) (xy 14.286933 -381.549219)
			(xy 14.263261 -381.599716) (xy 14.232488 -381.646229) (xy 14.195271 -381.687766) (xy 14.152403 -381.723441)
			(xy 14.104797 -381.752495) (xy 14.053468 -381.774307) (xy 13.999511 -381.788413) (xy 13.944074 -381.794513)
			(xy 13.88834 -381.792476) (xy 13.833497 -381.782346) (xy 13.780713 -381.764339) (xy 13.731113 -381.738838)
			(xy 13.685755 -381.706387) (xy 13.645606 -381.667678) (xy 13.61152 -381.623535) (xy 13.584224 -381.5749)
			(xy 13.564301 -381.522809) (xy 13.552175 -381.468372) (xy 13.548104 -381.41275) (xy 12.590812 -381.41275)
			(xy 12.587485 -381.43536) (xy 12.571417 -381.488767) (xy 12.547745 -381.539264) (xy 12.516972 -381.585777)
			(xy 12.479755 -381.627314) (xy 12.436887 -381.662989) (xy 12.389281 -381.692043) (xy 12.337952 -381.713855)
			(xy 12.283995 -381.727961) (xy 12.228558 -381.734061) (xy 12.172824 -381.732024) (xy 12.117981 -381.721894)
			(xy 12.065197 -381.703887) (xy 12.015597 -381.678386) (xy 11.970239 -381.645935) (xy 11.93009 -381.607226)
			(xy 11.896004 -381.563083) (xy 11.868708 -381.514448) (xy 11.848785 -381.462357) (xy 11.836659 -381.40792)
			(xy 11.832588 -381.352298) (xy 10.311517 -381.352298) (xy 10.311129 -381.37358) (xy 10.303009 -381.428756)
			(xy 10.286941 -381.482163) (xy 10.263269 -381.53266) (xy 10.232496 -381.579173) (xy 10.195279 -381.62071)
			(xy 10.152411 -381.656385) (xy 10.104805 -381.685439) (xy 10.053476 -381.707251) (xy 9.999519 -381.721357)
			(xy 9.944082 -381.727457) (xy 9.888348 -381.72542) (xy 9.833505 -381.71529) (xy 9.780721 -381.697283)
			(xy 9.731121 -381.671782) (xy 9.685763 -381.639331) (xy 9.645614 -381.600622) (xy 9.611528 -381.556479)
			(xy 9.584232 -381.507844) (xy 9.564309 -381.455753) (xy 9.552183 -381.401316) (xy 9.548112 -381.345694)
			(xy 8.811458 -381.345694) (xy 8.811514 -381.348742) (xy 8.811005 -381.376628) (xy 8.802885 -381.431804)
			(xy 8.786817 -381.485211) (xy 8.763145 -381.535708) (xy 8.732372 -381.582221) (xy 8.695155 -381.623758)
			(xy 8.652287 -381.659433) (xy 8.604681 -381.688487) (xy 8.553352 -381.710299) (xy 8.499395 -381.724405)
			(xy 8.443958 -381.730505) (xy 8.388224 -381.728468) (xy 8.333381 -381.718338) (xy 8.280597 -381.700331)
			(xy 8.230997 -381.67483) (xy 8.185639 -381.642379) (xy 8.14549 -381.60367) (xy 8.111404 -381.559527)
			(xy 8.084108 -381.510892) (xy 8.064185 -381.458801) (xy 8.052059 -381.404364) (xy 8.047988 -381.348742)
			(xy 2.030162 -381.348742) (xy 2.025195 -381.402059) (xy 2.011934 -381.456401) (xy 1.990884 -381.508225)
			(xy 1.962497 -381.556423) (xy 1.927379 -381.599963) (xy 1.886284 -381.637911) (xy 1.84009 -381.669455)
			(xy 1.789788 -381.693921) (xy 1.763268 -381.702818) (xy 1.763014 -381.702818) (xy 1.752898 -381.706536)
			(xy 1.736846 -381.720888) (xy 1.728099 -381.740564) (xy 1.727708 -381.751332) (xy 1.727708 -381.847852)
			(xy 1.728174 -381.857726) (xy 1.735627 -381.876015) (xy 1.742186 -381.883412) (xy 1.74244 -381.883666)
			(xy 1.753108 -381.894334) (xy 1.763014 -381.898144) (xy 1.787886 -381.908462) (xy 1.834694 -381.93508)
			(xy 1.877297 -381.96801) (xy 1.91485 -382.0066) (xy 1.946609 -382.050084) (xy 1.971943 -382.097598)
			(xy 1.99035 -382.148201) (xy 2.001464 -382.200888) (xy 2.005064 -382.254614) (xy 2.00108 -382.308313)
			(xy 1.989591 -382.36092) (xy 1.970823 -382.41139) (xy 1.945151 -382.458723) (xy 1.913082 -382.501979)
			(xy 1.875254 -382.540299) (xy 1.832417 -382.572925) (xy 1.785421 -382.599208) (xy 1.760474 -382.609344)
			(xy 1.759966 -382.609344) (xy 1.759966 -382.609598) (xy 1.75302 -382.612556) (xy 1.74113 -382.621848)
			(xy 1.736598 -382.627886) (xy 1.736598 -382.62814) (xy 1.732483 -382.634591) (xy 1.727944 -382.649195)
			(xy 1.727708 -382.656842) (xy 1.727708 -383.246884) (xy 4.633212 -383.246884) (xy 4.637283 -383.191262)
			(xy 4.649409 -383.136825) (xy 4.669332 -383.084734) (xy 4.696628 -383.036099) (xy 4.730714 -382.991956)
			(xy 4.770863 -382.953247) (xy 4.816221 -382.920796) (xy 4.865821 -382.895295) (xy 4.918605 -382.877288)
			(xy 4.973448 -382.867158) (xy 5.029182 -382.865121) (xy 5.084619 -382.871221) (xy 5.138576 -382.885327)
			(xy 5.189905 -382.907139) (xy 5.237511 -382.936193) (xy 5.280379 -382.971868) (xy 5.317596 -383.013405)
			(xy 5.348369 -383.059918) (xy 5.372041 -383.110415) (xy 5.388109 -383.163822) (xy 5.396229 -383.218998)
			(xy 5.396738 -383.246884) (xy 5.396229 -383.27477) (xy 5.388109 -383.329946) (xy 5.372041 -383.383353)
			(xy 5.348369 -383.43385) (xy 5.317596 -383.480363) (xy 5.280379 -383.5219) (xy 5.237511 -383.557575)
			(xy 5.189905 -383.586629) (xy 5.138576 -383.608441) (xy 5.084619 -383.622547) (xy 5.029182 -383.628647)
			(xy 4.973448 -383.62661) (xy 4.918605 -383.61648) (xy 4.865821 -383.598473) (xy 4.816221 -383.572972)
			(xy 4.770863 -383.540521) (xy 4.730714 -383.501812) (xy 4.696628 -383.457669) (xy 4.669332 -383.409034)
			(xy 4.649409 -383.356943) (xy 4.637283 -383.302506) (xy 4.633212 -383.246884) (xy 1.727708 -383.246884)
			(xy 1.727708 -384.746754) (xy 14.91564 -384.746754) (xy 14.919711 -384.691132) (xy 14.931837 -384.636695)
			(xy 14.95176 -384.584604) (xy 14.979056 -384.535969) (xy 15.013142 -384.491826) (xy 15.053291 -384.453117)
			(xy 15.098649 -384.420666) (xy 15.148249 -384.395165) (xy 15.201033 -384.377158) (xy 15.255876 -384.367028)
			(xy 15.31161 -384.364991) (xy 15.367047 -384.371091) (xy 15.421004 -384.385197) (xy 15.472333 -384.407009)
			(xy 15.519939 -384.436063) (xy 15.562807 -384.471738) (xy 15.600024 -384.513275) (xy 15.630797 -384.559788)
			(xy 15.654469 -384.610285) (xy 15.670537 -384.663692) (xy 15.678657 -384.718868) (xy 15.679166 -384.746754)
			(xy 15.678657 -384.77464) (xy 15.670537 -384.829816) (xy 15.654469 -384.883223) (xy 15.630797 -384.93372)
			(xy 15.600024 -384.980233) (xy 15.562807 -385.02177) (xy 15.519939 -385.057445) (xy 15.472333 -385.086499)
			(xy 15.421004 -385.108311) (xy 15.367047 -385.122417) (xy 15.31161 -385.128517) (xy 15.255876 -385.12648)
			(xy 15.201033 -385.11635) (xy 15.148249 -385.098343) (xy 15.098649 -385.072842) (xy 15.053291 -385.040391)
			(xy 15.013142 -385.001682) (xy 14.979056 -384.957539) (xy 14.95176 -384.908904) (xy 14.931837 -384.856813)
			(xy 14.919711 -384.802376) (xy 14.91564 -384.746754) (xy 1.727708 -384.746754) (xy 1.727708 -386.246878)
			(xy 4.662168 -386.246878) (xy 4.666239 -386.191256) (xy 4.678365 -386.136819) (xy 4.698288 -386.084728)
			(xy 4.725584 -386.036093) (xy 4.75967 -385.99195) (xy 4.799819 -385.953241) (xy 4.845177 -385.92079)
			(xy 4.894777 -385.895289) (xy 4.947561 -385.877282) (xy 5.002404 -385.867152) (xy 5.058138 -385.865115)
			(xy 5.113575 -385.871215) (xy 5.167532 -385.885321) (xy 5.218861 -385.907133) (xy 5.266467 -385.936187)
			(xy 5.309335 -385.971862) (xy 5.346552 -386.013399) (xy 5.377325 -386.059912) (xy 5.400997 -386.110409)
			(xy 5.417065 -386.163816) (xy 5.425185 -386.218992) (xy 5.425694 -386.246878) (xy 5.425185 -386.274764)
			(xy 5.417065 -386.32994) (xy 5.400997 -386.383347) (xy 5.377325 -386.433844) (xy 5.346552 -386.480357)
			(xy 5.309335 -386.521894) (xy 5.266467 -386.557569) (xy 5.218861 -386.586623) (xy 5.167532 -386.608435)
			(xy 5.113575 -386.622541) (xy 5.058138 -386.628641) (xy 5.002404 -386.626604) (xy 4.947561 -386.616474)
			(xy 4.894777 -386.598467) (xy 4.845177 -386.572966) (xy 4.799819 -386.540515) (xy 4.75967 -386.501806)
			(xy 4.725584 -386.457663) (xy 4.698288 -386.409028) (xy 4.678365 -386.356937) (xy 4.666239 -386.3025)
			(xy 4.662168 -386.246878) (xy 1.727708 -386.246878) (xy 1.727708 -386.988558) (xy 1.728236 -387.003903)
			(xy 1.737348 -387.033211) (xy 1.754743 -387.058496) (xy 1.778856 -387.077483) (xy 1.807516 -387.088464)
			(xy 1.838143 -387.090449) (xy 1.853184 -387.087364) (xy 1.859788 -387.085332) (xy 1.886559 -387.07519)
			(xy 1.942007 -387.060943) (xy 1.998804 -387.053759) (xy 2.027428 -387.053328) (xy 2.057408 -387.053798)
			(xy 2.116854 -387.061626) (xy 2.174769 -387.07715) (xy 2.230161 -387.100103) (xy 2.282083 -387.130092)
			(xy 2.329643 -387.166604) (xy 2.37203 -387.209013) (xy 2.408516 -387.256594) (xy 2.438477 -387.308531)
			(xy 2.4614 -387.363936) (xy 2.476892 -387.421859) (xy 2.484689 -387.48131) (xy 2.485136 -387.51129)
			(xy 2.485136 -388.21233) (xy 14.92834 -388.21233) (xy 14.932411 -388.156708) (xy 14.944537 -388.102271)
			(xy 14.96446 -388.05018) (xy 14.991756 -388.001545) (xy 15.025842 -387.957402) (xy 15.065991 -387.918693)
			(xy 15.111349 -387.886242) (xy 15.160949 -387.860741) (xy 15.213733 -387.842734) (xy 15.268576 -387.832604)
			(xy 15.32431 -387.830567) (xy 15.379747 -387.836667) (xy 15.433704 -387.850773) (xy 15.485033 -387.872585)
			(xy 15.532639 -387.901639) (xy 15.575507 -387.937314) (xy 15.612724 -387.978851) (xy 15.643497 -388.025364)
			(xy 15.667169 -388.075861) (xy 15.683237 -388.129268) (xy 15.691357 -388.184444) (xy 15.691866 -388.21233)
			(xy 15.691357 -388.240216) (xy 15.683237 -388.295392) (xy 15.667169 -388.348799) (xy 15.643497 -388.399296)
			(xy 15.612724 -388.445809) (xy 15.575507 -388.487346) (xy 15.532639 -388.523021) (xy 15.485033 -388.552075)
			(xy 15.433704 -388.573887) (xy 15.379747 -388.587993) (xy 15.32431 -388.594093) (xy 15.268576 -388.592056)
			(xy 15.213733 -388.581926) (xy 15.160949 -388.563919) (xy 15.111349 -388.538418) (xy 15.065991 -388.505967)
			(xy 15.025842 -388.467258) (xy 14.991756 -388.423115) (xy 14.96446 -388.37448) (xy 14.944537 -388.322389)
			(xy 14.932411 -388.267952) (xy 14.92834 -388.21233) (xy 2.485136 -388.21233) (xy 2.485136 -388.37489)
			(xy 2.484647 -388.404864) (xy 2.476825 -388.464299) (xy 2.461315 -388.522205) (xy 2.438381 -388.577593)
			(xy 2.408417 -388.629515) (xy 2.371935 -388.677083) (xy 2.329557 -388.719484) (xy 2.294054 -388.746746)
			(xy 4.630672 -388.746746) (xy 4.634743 -388.691124) (xy 4.646869 -388.636687) (xy 4.666792 -388.584596)
			(xy 4.694088 -388.535961) (xy 4.728174 -388.491818) (xy 4.768323 -388.453109) (xy 4.813681 -388.420658)
			(xy 4.863281 -388.395157) (xy 4.916065 -388.37715) (xy 4.970908 -388.36702) (xy 5.026642 -388.364983)
			(xy 5.082079 -388.371083) (xy 5.136036 -388.385189) (xy 5.187365 -388.407001) (xy 5.234971 -388.436055)
			(xy 5.277839 -388.47173) (xy 5.315056 -388.513267) (xy 5.345829 -388.55978) (xy 5.369501 -388.610277)
			(xy 5.385569 -388.663684) (xy 5.393689 -388.71886) (xy 5.394198 -388.746746) (xy 5.393689 -388.774632)
			(xy 5.385569 -388.829808) (xy 5.369501 -388.883215) (xy 5.345829 -388.933712) (xy 5.315056 -388.980225)
			(xy 5.277839 -389.021762) (xy 5.234971 -389.057437) (xy 5.187365 -389.086491) (xy 5.136036 -389.108303)
			(xy 5.082079 -389.122409) (xy 5.026642 -389.128509) (xy 4.970908 -389.126472) (xy 4.916065 -389.116342)
			(xy 4.863281 -389.098335) (xy 4.813681 -389.072834) (xy 4.768323 -389.040383) (xy 4.728174 -389.001674)
			(xy 4.694088 -388.957531) (xy 4.666792 -388.908896) (xy 4.646869 -388.856805) (xy 4.634743 -388.802368)
			(xy 4.630672 -388.746746) (xy 2.294054 -388.746746) (xy 2.28201 -388.755994) (xy 2.230105 -388.785987)
			(xy 2.17473 -388.808951) (xy 2.116832 -388.824494) (xy 2.057402 -388.83235) (xy 2.027428 -388.832852)
			(xy 1.998803 -388.832422) (xy 1.942006 -388.825243) (xy 1.886557 -388.810995) (xy 1.859788 -388.800848)
			(xy 1.853184 -388.798816) (xy 1.838139 -388.795719) (xy 1.807499 -388.797687) (xy 1.778824 -388.808661)
			(xy 1.754699 -388.827653) (xy 1.737299 -388.852949) (xy 1.728192 -388.88227) (xy 1.727708 -388.897622)
			(xy 1.727708 -389.720836) (xy 4.413248 -389.720836) (xy 4.417319 -389.665214) (xy 4.429445 -389.610777)
			(xy 4.449368 -389.558686) (xy 4.476664 -389.510051) (xy 4.51075 -389.465908) (xy 4.550899 -389.427199)
			(xy 4.596257 -389.394748) (xy 4.645857 -389.369247) (xy 4.698641 -389.35124) (xy 4.753484 -389.34111)
			(xy 4.809218 -389.339073) (xy 4.864655 -389.345173) (xy 4.918612 -389.359279) (xy 4.969941 -389.381091)
			(xy 5.017547 -389.410145) (xy 5.060415 -389.44582) (xy 5.097632 -389.487357) (xy 5.128405 -389.53387)
			(xy 5.152077 -389.584367) (xy 5.168145 -389.637774) (xy 5.176265 -389.69295) (xy 5.176774 -389.720836)
			(xy 5.176301 -389.746744) (xy 14.934944 -389.746744) (xy 14.939015 -389.691122) (xy 14.951141 -389.636685)
			(xy 14.971064 -389.584594) (xy 14.99836 -389.535959) (xy 15.032446 -389.491816) (xy 15.072595 -389.453107)
			(xy 15.117953 -389.420656) (xy 15.167553 -389.395155) (xy 15.220337 -389.377148) (xy 15.27518 -389.367018)
			(xy 15.330914 -389.364981) (xy 15.386351 -389.371081) (xy 15.440308 -389.385187) (xy 15.491637 -389.406999)
			(xy 15.539243 -389.436053) (xy 15.582111 -389.471728) (xy 15.619328 -389.513265) (xy 15.650101 -389.559778)
			(xy 15.673773 -389.610275) (xy 15.689841 -389.663682) (xy 15.697961 -389.718858) (xy 15.69847 -389.746744)
			(xy 15.697961 -389.77463) (xy 15.689841 -389.829806) (xy 15.673773 -389.883213) (xy 15.650101 -389.93371)
			(xy 15.619328 -389.980223) (xy 15.582111 -390.02176) (xy 15.539243 -390.057435) (xy 15.491637 -390.086489)
			(xy 15.440308 -390.108301) (xy 15.386351 -390.122407) (xy 15.330914 -390.128507) (xy 15.27518 -390.12647)
			(xy 15.220337 -390.11634) (xy 15.167553 -390.098333) (xy 15.117953 -390.072832) (xy 15.072595 -390.040381)
			(xy 15.032446 -390.001672) (xy 14.99836 -389.957529) (xy 14.971064 -389.908894) (xy 14.951141 -389.856803)
			(xy 14.939015 -389.802366) (xy 14.934944 -389.746744) (xy 5.176301 -389.746744) (xy 5.176265 -389.748722)
			(xy 5.168145 -389.803898) (xy 5.152077 -389.857305) (xy 5.128405 -389.907802) (xy 5.097632 -389.954315)
			(xy 5.060415 -389.995852) (xy 5.017547 -390.031527) (xy 4.969941 -390.060581) (xy 4.918612 -390.082393)
			(xy 4.864655 -390.096499) (xy 4.809218 -390.102599) (xy 4.753484 -390.100562) (xy 4.698641 -390.090432)
			(xy 4.645857 -390.072425) (xy 4.596257 -390.046924) (xy 4.550899 -390.014473) (xy 4.51075 -389.975764)
			(xy 4.476664 -389.931621) (xy 4.449368 -389.882986) (xy 4.429445 -389.830895) (xy 4.417319 -389.776458)
			(xy 4.413248 -389.720836) (xy 1.727708 -389.720836) (xy 1.727708 -390.35863) (xy 1.728164 -390.368445)
			(xy 1.735549 -390.386632) (xy 1.749225 -390.400714) (xy 1.767189 -390.408627) (xy 1.776984 -390.40943)
			(xy 1.804976 -390.410762) (xy 1.860142 -390.420613) (xy 1.913275 -390.438424) (xy 1.963232 -390.463812)
			(xy 2.00894 -390.496233) (xy 2.049416 -390.534989) (xy 2.08379 -390.579246) (xy 2.111324 -390.628054)
			(xy 2.131424 -390.680364) (xy 2.14366 -390.73505) (xy 2.147768 -390.790938) (xy 2.14366 -390.846826)
			(xy 2.131424 -390.901512) (xy 2.111324 -390.953822) (xy 2.08379 -391.00263) (xy 2.049416 -391.046887)
			(xy 2.00894 -391.085643) (xy 1.963232 -391.118064) (xy 1.913275 -391.143452) (xy 1.860142 -391.161263)
			(xy 1.804976 -391.171114) (xy 1.776984 -391.172446) (xy 1.767181 -391.173191) (xy 1.749209 -391.181116)
			(xy 1.735535 -391.195217) (xy 1.728166 -391.213425) (xy 1.727708 -391.223246) (xy 1.727708 -391.614914)
			(xy 13.80693 -391.614914) (xy 13.811001 -391.559292) (xy 13.823127 -391.504855) (xy 13.84305 -391.452764)
			(xy 13.870346 -391.404129) (xy 13.904432 -391.359986) (xy 13.944581 -391.321277) (xy 13.989939 -391.288826)
			(xy 14.039539 -391.263325) (xy 14.092323 -391.245318) (xy 14.147166 -391.235188) (xy 14.2029 -391.233151)
			(xy 14.258337 -391.239251) (xy 14.312294 -391.253357) (xy 14.363623 -391.275169) (xy 14.411229 -391.304223)
			(xy 14.454097 -391.339898) (xy 14.491314 -391.381435) (xy 14.522087 -391.427948) (xy 14.545759 -391.478445)
			(xy 14.561827 -391.531852) (xy 14.569947 -391.587028) (xy 14.570456 -391.614914) (xy 14.569947 -391.6428)
			(xy 14.566986 -391.66292) (xy 16.249394 -391.66292) (xy 16.253465 -391.607298) (xy 16.265591 -391.552861)
			(xy 16.285514 -391.50077) (xy 16.31281 -391.452135) (xy 16.346896 -391.407992) (xy 16.387045 -391.369283)
			(xy 16.432403 -391.336832) (xy 16.482003 -391.311331) (xy 16.534787 -391.293324) (xy 16.58963 -391.283194)
			(xy 16.645364 -391.281157) (xy 16.700801 -391.287257) (xy 16.754758 -391.301363) (xy 16.806087 -391.323175)
			(xy 16.853693 -391.352229) (xy 16.896561 -391.387904) (xy 16.933778 -391.429441) (xy 16.964551 -391.475954)
			(xy 16.988223 -391.526451) (xy 17.004291 -391.579858) (xy 17.012411 -391.635034) (xy 17.01292 -391.66292)
			(xy 17.012411 -391.690806) (xy 17.004291 -391.745982) (xy 16.988223 -391.799389) (xy 16.964551 -391.849886)
			(xy 16.933778 -391.896399) (xy 16.896561 -391.937936) (xy 16.853693 -391.973611) (xy 16.806087 -392.002665)
			(xy 16.754758 -392.024477) (xy 16.700801 -392.038583) (xy 16.645364 -392.044683) (xy 16.58963 -392.042646)
			(xy 16.534787 -392.032516) (xy 16.482003 -392.014509) (xy 16.432403 -391.989008) (xy 16.387045 -391.956557)
			(xy 16.346896 -391.917848) (xy 16.31281 -391.873705) (xy 16.285514 -391.82507) (xy 16.265591 -391.772979)
			(xy 16.253465 -391.718542) (xy 16.249394 -391.66292) (xy 14.566986 -391.66292) (xy 14.561827 -391.697976)
			(xy 14.545759 -391.751383) (xy 14.522087 -391.80188) (xy 14.491314 -391.848393) (xy 14.454097 -391.88993)
			(xy 14.411229 -391.925605) (xy 14.363623 -391.954659) (xy 14.312294 -391.976471) (xy 14.258337 -391.990577)
			(xy 14.2029 -391.996677) (xy 14.147166 -391.99464) (xy 14.092323 -391.98451) (xy 14.039539 -391.966503)
			(xy 13.989939 -391.941002) (xy 13.944581 -391.908551) (xy 13.904432 -391.869842) (xy 13.870346 -391.825699)
			(xy 13.84305 -391.777064) (xy 13.823127 -391.724973) (xy 13.811001 -391.670536) (xy 13.80693 -391.614914)
			(xy 1.727708 -391.614914) (xy 1.727708 -394.307314) (xy 1.728349 -394.318699) (xy 1.738189 -394.339236)
			(xy 1.755905 -394.353545) (xy 1.766824 -394.356844) (xy 1.795822 -394.364292) (xy 1.851529 -394.386225)
			(xy 1.903611 -394.415752) (xy 1.951038 -394.452289) (xy 1.980375 -394.48232) (xy 2.2512 -394.48232)
			(xy 2.255271 -394.426698) (xy 2.267397 -394.372261) (xy 2.28732 -394.32017) (xy 2.314616 -394.271535)
			(xy 2.348702 -394.227392) (xy 2.388851 -394.188683) (xy 2.434209 -394.156232) (xy 2.483809 -394.130731)
			(xy 2.536593 -394.112724) (xy 2.591436 -394.102594) (xy 2.64717 -394.100557) (xy 2.702607 -394.106657)
			(xy 2.756564 -394.120763) (xy 2.807893 -394.142575) (xy 2.855499 -394.171629) (xy 2.898367 -394.207304)
			(xy 2.935584 -394.248841) (xy 2.966357 -394.295354) (xy 2.990029 -394.345851) (xy 3.006097 -394.399258)
			(xy 3.014217 -394.454434) (xy 3.014726 -394.48232) (xy 3.014217 -394.510206) (xy 3.006097 -394.565382)
			(xy 2.990029 -394.618789) (xy 2.966357 -394.669286) (xy 2.935584 -394.715799) (xy 2.900811 -394.754608)
			(xy 5.302756 -394.754608) (xy 5.306827 -394.698986) (xy 5.318953 -394.644549) (xy 5.338876 -394.592458)
			(xy 5.366172 -394.543823) (xy 5.400258 -394.49968) (xy 5.440407 -394.460971) (xy 5.485765 -394.42852)
			(xy 5.535365 -394.403019) (xy 5.588149 -394.385012) (xy 5.642992 -394.374882) (xy 5.698726 -394.372845)
			(xy 5.754163 -394.378945) (xy 5.80812 -394.393051) (xy 5.859449 -394.414863) (xy 5.907055 -394.443917)
			(xy 5.949923 -394.479592) (xy 5.98714 -394.521129) (xy 6.017913 -394.567642) (xy 6.041585 -394.618139)
			(xy 6.057653 -394.671546) (xy 6.065773 -394.726722) (xy 6.066282 -394.754608) (xy 6.066212 -394.758418)
			(xy 6.280656 -394.758418) (xy 6.284727 -394.702796) (xy 6.296853 -394.648359) (xy 6.316776 -394.596268)
			(xy 6.344072 -394.547633) (xy 6.378158 -394.50349) (xy 6.418307 -394.464781) (xy 6.463665 -394.43233)
			(xy 6.513265 -394.406829) (xy 6.566049 -394.388822) (xy 6.620892 -394.378692) (xy 6.676626 -394.376655)
			(xy 6.732063 -394.382755) (xy 6.78602 -394.396861) (xy 6.837349 -394.418673) (xy 6.884955 -394.447727)
			(xy 6.927823 -394.483402) (xy 6.96504 -394.524939) (xy 6.995813 -394.571452) (xy 7.019485 -394.621949)
			(xy 7.035553 -394.675356) (xy 7.043673 -394.730532) (xy 7.044182 -394.758418) (xy 7.043673 -394.786304)
			(xy 7.035553 -394.84148) (xy 7.019485 -394.894887) (xy 6.995813 -394.945384) (xy 6.96504 -394.991897)
			(xy 6.927823 -395.033434) (xy 6.884955 -395.069109) (xy 6.837349 -395.098163) (xy 6.78602 -395.119975)
			(xy 6.732063 -395.134081) (xy 6.676626 -395.140181) (xy 6.620892 -395.138144) (xy 6.566049 -395.128014)
			(xy 6.513265 -395.110007) (xy 6.463665 -395.084506) (xy 6.418307 -395.052055) (xy 6.378158 -395.013346)
			(xy 6.344072 -394.969203) (xy 6.316776 -394.920568) (xy 6.296853 -394.868477) (xy 6.284727 -394.81404)
			(xy 6.280656 -394.758418) (xy 6.066212 -394.758418) (xy 6.065773 -394.782494) (xy 6.057653 -394.83767)
			(xy 6.041585 -394.891077) (xy 6.017913 -394.941574) (xy 5.98714 -394.988087) (xy 5.949923 -395.029624)
			(xy 5.907055 -395.065299) (xy 5.859449 -395.094353) (xy 5.80812 -395.116165) (xy 5.754163 -395.130271)
			(xy 5.698726 -395.136371) (xy 5.642992 -395.134334) (xy 5.588149 -395.124204) (xy 5.535365 -395.106197)
			(xy 5.485765 -395.080696) (xy 5.440407 -395.048245) (xy 5.400258 -395.009536) (xy 5.366172 -394.965393)
			(xy 5.338876 -394.916758) (xy 5.318953 -394.864667) (xy 5.306827 -394.81023) (xy 5.302756 -394.754608)
			(xy 2.900811 -394.754608) (xy 2.898367 -394.757336) (xy 2.855499 -394.793011) (xy 2.807893 -394.822065)
			(xy 2.756564 -394.843877) (xy 2.702607 -394.857983) (xy 2.64717 -394.864083) (xy 2.591436 -394.862046)
			(xy 2.536593 -394.851916) (xy 2.483809 -394.833909) (xy 2.434209 -394.808408) (xy 2.388851 -394.775957)
			(xy 2.348702 -394.737248) (xy 2.314616 -394.693105) (xy 2.28732 -394.64447) (xy 2.267397 -394.592379)
			(xy 2.255271 -394.537942) (xy 2.2512 -394.48232) (xy 1.980375 -394.48232) (xy 1.992874 -394.495115)
			(xy 2.028292 -394.543384) (xy 2.056592 -394.596142) (xy 2.077216 -394.652347) (xy 2.089755 -394.710889)
			(xy 2.093963 -394.77061) (xy 2.089755 -394.830331) (xy 2.077216 -394.888873) (xy 2.056592 -394.945078)
			(xy 2.028292 -394.997836) (xy 1.992874 -395.046105) (xy 1.951038 -395.088931) (xy 1.903611 -395.125468)
			(xy 1.851529 -395.154995) (xy 1.795822 -395.176928) (xy 1.766824 -395.184376) (xy 1.755868 -395.187596)
			(xy 1.738117 -395.20191) (xy 1.735825 -395.206728) (xy 10.019536 -395.206728) (xy 10.023607 -395.151106)
			(xy 10.035733 -395.096669) (xy 10.055656 -395.044578) (xy 10.082952 -394.995943) (xy 10.117038 -394.9518)
			(xy 10.157187 -394.913091) (xy 10.202545 -394.88064) (xy 10.252145 -394.855139) (xy 10.304929 -394.837132)
			(xy 10.359772 -394.827002) (xy 10.415506 -394.824965) (xy 10.470943 -394.831065) (xy 10.5249 -394.845171)
			(xy 10.576229 -394.866983) (xy 10.623835 -394.896037) (xy 10.666703 -394.931712) (xy 10.70392 -394.973249)
			(xy 10.734693 -395.019762) (xy 10.758365 -395.070259) (xy 10.774433 -395.123666) (xy 10.782553 -395.178842)
			(xy 10.78302 -395.204442) (xy 11.574778 -395.204442) (xy 11.578849 -395.14882) (xy 11.590975 -395.094383)
			(xy 11.610898 -395.042292) (xy 11.638194 -394.993657) (xy 11.67228 -394.949514) (xy 11.712429 -394.910805)
			(xy 11.757787 -394.878354) (xy 11.807387 -394.852853) (xy 11.860171 -394.834846) (xy 11.915014 -394.824716)
			(xy 11.970748 -394.822679) (xy 12.026185 -394.828779) (xy 12.080142 -394.842885) (xy 12.131471 -394.864697)
			(xy 12.179077 -394.893751) (xy 12.221945 -394.929426) (xy 12.259162 -394.970963) (xy 12.289935 -395.017476)
			(xy 12.313607 -395.067973) (xy 12.329675 -395.12138) (xy 12.337795 -395.176556) (xy 12.338151 -395.19606)
			(xy 15.04772 -395.19606) (xy 15.051791 -395.140438) (xy 15.063917 -395.086001) (xy 15.08384 -395.03391)
			(xy 15.111136 -394.985275) (xy 15.145222 -394.941132) (xy 15.185371 -394.902423) (xy 15.230729 -394.869972)
			(xy 15.280329 -394.844471) (xy 15.333113 -394.826464) (xy 15.387956 -394.816334) (xy 15.44369 -394.814297)
			(xy 15.499127 -394.820397) (xy 15.553084 -394.834503) (xy 15.604413 -394.856315) (xy 15.652019 -394.885369)
			(xy 15.694887 -394.921044) (xy 15.732104 -394.962581) (xy 15.762877 -395.009094) (xy 15.786549 -395.059591)
			(xy 15.802617 -395.112998) (xy 15.810737 -395.168174) (xy 15.811246 -395.19606) (xy 16.06372 -395.19606)
			(xy 16.067791 -395.140438) (xy 16.079917 -395.086001) (xy 16.09984 -395.03391) (xy 16.127136 -394.985275)
			(xy 16.161222 -394.941132) (xy 16.201371 -394.902423) (xy 16.246729 -394.869972) (xy 16.296329 -394.844471)
			(xy 16.349113 -394.826464) (xy 16.403956 -394.816334) (xy 16.45969 -394.814297) (xy 16.515127 -394.820397)
			(xy 16.569084 -394.834503) (xy 16.620413 -394.856315) (xy 16.668019 -394.885369) (xy 16.710887 -394.921044)
			(xy 16.748104 -394.962581) (xy 16.778877 -395.009094) (xy 16.802549 -395.059591) (xy 16.818617 -395.112998)
			(xy 16.826737 -395.168174) (xy 16.827246 -395.19606) (xy 16.826737 -395.223946) (xy 16.818617 -395.279122)
			(xy 16.802549 -395.332529) (xy 16.778877 -395.383026) (xy 16.748104 -395.429539) (xy 16.710887 -395.471076)
			(xy 16.668019 -395.506751) (xy 16.620413 -395.535805) (xy 16.569084 -395.557617) (xy 16.515127 -395.571723)
			(xy 16.45969 -395.577823) (xy 16.403956 -395.575786) (xy 16.349113 -395.565656) (xy 16.296329 -395.547649)
			(xy 16.246729 -395.522148) (xy 16.201371 -395.489697) (xy 16.161222 -395.450988) (xy 16.127136 -395.406845)
			(xy 16.09984 -395.35821) (xy 16.079917 -395.306119) (xy 16.067791 -395.251682) (xy 16.06372 -395.19606)
			(xy 15.811246 -395.19606) (xy 15.810737 -395.223946) (xy 15.802617 -395.279122) (xy 15.786549 -395.332529)
			(xy 15.762877 -395.383026) (xy 15.732104 -395.429539) (xy 15.694887 -395.471076) (xy 15.652019 -395.506751)
			(xy 15.604413 -395.535805) (xy 15.553084 -395.557617) (xy 15.499127 -395.571723) (xy 15.44369 -395.577823)
			(xy 15.387956 -395.575786) (xy 15.333113 -395.565656) (xy 15.280329 -395.547649) (xy 15.230729 -395.522148)
			(xy 15.185371 -395.489697) (xy 15.145222 -395.450988) (xy 15.111136 -395.406845) (xy 15.08384 -395.35821)
			(xy 15.063917 -395.306119) (xy 15.051791 -395.251682) (xy 15.04772 -395.19606) (xy 12.338151 -395.19606)
			(xy 12.338304 -395.204442) (xy 12.337795 -395.232328) (xy 12.329675 -395.287504) (xy 12.313607 -395.340911)
			(xy 12.289935 -395.391408) (xy 12.259162 -395.437921) (xy 12.221945 -395.479458) (xy 12.179077 -395.515133)
			(xy 12.131471 -395.544187) (xy 12.080142 -395.565999) (xy 12.026185 -395.580105) (xy 11.970748 -395.586205)
			(xy 11.915014 -395.584168) (xy 11.860171 -395.574038) (xy 11.807387 -395.556031) (xy 11.757787 -395.53053)
			(xy 11.712429 -395.498079) (xy 11.67228 -395.45937) (xy 11.638194 -395.415227) (xy 11.610898 -395.366592)
			(xy 11.590975 -395.314501) (xy 11.578849 -395.260064) (xy 11.574778 -395.204442) (xy 10.78302 -395.204442)
			(xy 10.783062 -395.206728) (xy 10.782553 -395.234614) (xy 10.774433 -395.28979) (xy 10.758365 -395.343197)
			(xy 10.734693 -395.393694) (xy 10.70392 -395.440207) (xy 10.666703 -395.481744) (xy 10.623835 -395.517419)
			(xy 10.576229 -395.546473) (xy 10.5249 -395.568285) (xy 10.470943 -395.582391) (xy 10.415506 -395.588491)
			(xy 10.359772 -395.586454) (xy 10.304929 -395.576324) (xy 10.252145 -395.558317) (xy 10.202545 -395.532816)
			(xy 10.157187 -395.500365) (xy 10.117038 -395.461656) (xy 10.082952 -395.417513) (xy 10.055656 -395.368878)
			(xy 10.035733 -395.316787) (xy 10.023607 -395.26235) (xy 10.019536 -395.206728) (xy 1.735825 -395.206728)
			(xy 1.728321 -395.222502) (xy 1.727708 -395.233906) (xy 1.727708 -398.164722) (xy 3.141726 -398.164722)
			(xy 3.141726 -398.035362) (xy 3.149849 -397.906256) (xy 3.166062 -397.777916) (xy 3.190302 -397.650846)
			(xy 3.222472 -397.52555) (xy 3.262447 -397.40252) (xy 3.310068 -397.282244) (xy 3.365147 -397.165195)
			(xy 3.427467 -397.051835) (xy 3.496782 -396.942612) (xy 3.572818 -396.837957) (xy 3.655276 -396.738283)
			(xy 3.743829 -396.643983) (xy 3.838129 -396.55543) (xy 3.937803 -396.472972) (xy 4.042458 -396.396936)
			(xy 4.151681 -396.327621) (xy 4.265041 -396.265301) (xy 4.38209 -396.210222) (xy 4.502366 -396.162601)
			(xy 4.625396 -396.122626) (xy 4.750692 -396.090456) (xy 4.877762 -396.066216) (xy 5.006102 -396.050003)
			(xy 5.135208 -396.04188) (xy 5.199888 -396.041372) (xy 6.800088 -396.041372) (xy 6.864769 -396.041866)
			(xy 6.993875 -396.049988) (xy 7.122217 -396.066201) (xy 7.249287 -396.090441) (xy 7.374584 -396.122612)
			(xy 7.497614 -396.162587) (xy 7.617892 -396.210208) (xy 7.734942 -396.265287) (xy 7.848302 -396.327608)
			(xy 7.957526 -396.396923) (xy 8.062181 -396.47296) (xy 8.161856 -396.555418) (xy 8.256157 -396.643972)
			(xy 8.344711 -396.738272) (xy 8.427169 -396.837947) (xy 8.503206 -396.942603) (xy 8.572521 -397.051826)
			(xy 8.634842 -397.165187) (xy 8.689921 -397.282236) (xy 8.737543 -397.402514) (xy 8.777518 -397.525544)
			(xy 8.809688 -397.650841) (xy 8.833928 -397.777911) (xy 8.850142 -397.906253) (xy 8.858264 -398.035359)
			(xy 8.858264 -398.164721) (xy 8.850142 -398.293827) (xy 8.833928 -398.422169) (xy 8.809688 -398.549239)
			(xy 8.777518 -398.674536) (xy 8.737543 -398.797566) (xy 8.689921 -398.917844) (xy 8.634842 -399.034893)
			(xy 8.572521 -399.148254) (xy 8.503206 -399.257477) (xy 8.427169 -399.362133) (xy 8.344711 -399.461808)
			(xy 8.256157 -399.556108) (xy 8.161856 -399.644662) (xy 8.062181 -399.72712) (xy 7.957526 -399.803157)
			(xy 7.848302 -399.872472) (xy 7.734942 -399.934793) (xy 7.617892 -399.989872) (xy 7.497614 -400.037493)
			(xy 7.374584 -400.077468) (xy 7.249287 -400.109639) (xy 7.122217 -400.133879) (xy 6.993875 -400.150092)
			(xy 6.864769 -400.158214) (xy 6.800088 -400.158712) (xy 5.199888 -400.158712) (xy 5.135208 -400.158204)
			(xy 5.006102 -400.150081) (xy 4.877762 -400.133868) (xy 4.750692 -400.109628) (xy 4.625396 -400.077458)
			(xy 4.502366 -400.037483) (xy 4.38209 -399.989862) (xy 4.265041 -399.934783) (xy 4.151681 -399.872463)
			(xy 4.042458 -399.803148) (xy 3.937803 -399.727112) (xy 3.838129 -399.644654) (xy 3.743829 -399.556101)
			(xy 3.655276 -399.461801) (xy 3.572818 -399.362127) (xy 3.496782 -399.257472) (xy 3.427467 -399.148249)
			(xy 3.365147 -399.034889) (xy 3.310068 -398.91784) (xy 3.262447 -398.797564) (xy 3.222472 -398.674534)
			(xy 3.190302 -398.549238) (xy 3.166062 -398.422168) (xy 3.149849 -398.293828) (xy 3.141726 -398.164722)
			(xy 1.727708 -398.164722) (xy 1.727708 -402.232191) (xy 13.656034 -402.232191) (xy 13.656034 -402.177689)
			(xy 13.66379 -402.123741) (xy 13.679145 -402.071446) (xy 13.701786 -402.021868) (xy 13.731253 -401.976018)
			(xy 13.766944 -401.934827) (xy 13.808134 -401.899135) (xy 13.853985 -401.869668) (xy 13.903562 -401.847027)
			(xy 13.955857 -401.831671) (xy 14.009805 -401.823914) (xy 14.037056 -401.823428) (xy 14.063373 -401.823855)
			(xy 14.115509 -401.831079) (xy 14.166158 -401.845397) (xy 14.21436 -401.866536) (xy 14.259201 -401.894096)
			(xy 14.299831 -401.927555) (xy 14.31798 -401.946618) (xy 14.325505 -401.954016) (xy 14.344782 -401.962542)
			(xy 14.355318 -401.963128) (xy 14.429994 -401.963128) (xy 14.440544 -401.962601) (xy 14.459839 -401.954063)
			(xy 14.467332 -401.946618) (xy 14.485455 -401.927527) (xy 14.526077 -401.894049) (xy 14.57092 -401.86648)
			(xy 14.61913 -401.845343) (xy 14.66979 -401.831041) (xy 14.721936 -401.823847) (xy 14.748256 -401.823428)
			(xy 14.774573 -401.823855) (xy 14.826709 -401.831079) (xy 14.877358 -401.845397) (xy 14.92556 -401.866536)
			(xy 14.970401 -401.894096) (xy 15.011031 -401.927555) (xy 15.02918 -401.946618) (xy 15.036705 -401.954016)
			(xy 15.055982 -401.962542) (xy 15.066518 -401.963128) (xy 15.141194 -401.963128) (xy 15.151744 -401.962601)
			(xy 15.171039 -401.954063) (xy 15.178532 -401.946618) (xy 15.196655 -401.927527) (xy 15.237277 -401.894049)
			(xy 15.28212 -401.86648) (xy 15.33033 -401.845343) (xy 15.38099 -401.831041) (xy 15.433136 -401.823847)
			(xy 15.459456 -401.823428) (xy 15.486709 -401.823899) (xy 15.54066 -401.831655) (xy 15.592957 -401.847011)
			(xy 15.642537 -401.869653) (xy 15.688391 -401.899121) (xy 15.729583 -401.934814) (xy 15.765277 -401.976006)
			(xy 15.794745 -402.021859) (xy 15.817388 -402.071439) (xy 15.832744 -402.123737) (xy 15.840501 -402.177687)
			(xy 15.840501 -402.232193) (xy 15.832744 -402.286143) (xy 15.817388 -402.338441) (xy 15.794745 -402.388021)
			(xy 15.765277 -402.433874) (xy 15.729583 -402.475066) (xy 15.688391 -402.510759) (xy 15.642537 -402.540227)
			(xy 15.592957 -402.562869) (xy 15.54066 -402.578225) (xy 15.486709 -402.585981) (xy 15.459456 -402.586444)
			(xy 15.43314 -402.585986) (xy 15.381007 -402.578765) (xy 15.33036 -402.564452) (xy 15.282158 -402.543318)
			(xy 15.237316 -402.515765) (xy 15.196683 -402.482313) (xy 15.178532 -402.463254) (xy 15.170993 -402.455873)
			(xy 15.151727 -402.447335) (xy 15.141194 -402.446744) (xy 15.066518 -402.446744) (xy 15.055966 -402.447256)
			(xy 15.03667 -402.455802) (xy 15.02918 -402.463254) (xy 15.011046 -402.482334) (xy 14.970426 -402.515814)
			(xy 14.925586 -402.543386) (xy 14.877378 -402.564524) (xy 14.82672 -402.578828) (xy 14.774576 -402.586025)
			(xy 14.748256 -402.586444) (xy 14.72194 -402.585986) (xy 14.669807 -402.578765) (xy 14.61916 -402.564452)
			(xy 14.570958 -402.543318) (xy 14.526116 -402.515765) (xy 14.485483 -402.482313) (xy 14.467332 -402.463254)
			(xy 14.459793 -402.455873) (xy 14.440527 -402.447335) (xy 14.429994 -402.446744) (xy 14.355318 -402.446744)
			(xy 14.344766 -402.447256) (xy 14.32547 -402.455802) (xy 14.31798 -402.463254) (xy 14.299846 -402.482334)
			(xy 14.259226 -402.515814) (xy 14.214386 -402.543386) (xy 14.166178 -402.564524) (xy 14.11552 -402.578828)
			(xy 14.063376 -402.586025) (xy 14.037056 -402.586444) (xy 14.009805 -402.585966) (xy 13.955857 -402.578209)
			(xy 13.903562 -402.562853) (xy 13.853985 -402.540212) (xy 13.808134 -402.510745) (xy 13.766944 -402.475053)
			(xy 13.731253 -402.433862) (xy 13.701786 -402.388012) (xy 13.679145 -402.338434) (xy 13.66379 -402.286139)
			(xy 13.656034 -402.232191) (xy 1.727708 -402.232191) (xy 1.727708 -404.501858) (xy 17.351246 -404.501858)
			(xy 17.355317 -404.446236) (xy 17.367443 -404.391799) (xy 17.387366 -404.339708) (xy 17.414662 -404.291073)
			(xy 17.448748 -404.24693) (xy 17.488897 -404.208221) (xy 17.534255 -404.17577) (xy 17.583855 -404.150269)
			(xy 17.636639 -404.132262) (xy 17.691482 -404.122132) (xy 17.747216 -404.120095) (xy 17.802653 -404.126195)
			(xy 17.85661 -404.140301) (xy 17.907939 -404.162113) (xy 17.955545 -404.191167) (xy 17.998413 -404.226842)
			(xy 18.03563 -404.268379) (xy 18.066403 -404.314892) (xy 18.090075 -404.365389) (xy 18.106143 -404.418796)
			(xy 18.114263 -404.473972) (xy 18.114772 -404.501858) (xy 18.114263 -404.529744) (xy 18.106143 -404.58492)
			(xy 18.094299 -404.624286) (xy 18.644868 -404.624286) (xy 18.648939 -404.568664) (xy 18.661065 -404.514227)
			(xy 18.680988 -404.462136) (xy 18.708284 -404.413501) (xy 18.74237 -404.369358) (xy 18.782519 -404.330649)
			(xy 18.827877 -404.298198) (xy 18.877477 -404.272697) (xy 18.930261 -404.25469) (xy 18.985104 -404.24456)
			(xy 19.040838 -404.242523) (xy 19.096275 -404.248623) (xy 19.150232 -404.262729) (xy 19.201561 -404.284541)
			(xy 19.249167 -404.313595) (xy 19.292035 -404.34927) (xy 19.329252 -404.390807) (xy 19.360025 -404.43732)
			(xy 19.383697 -404.487817) (xy 19.399765 -404.541224) (xy 19.407885 -404.5964) (xy 19.408394 -404.624286)
			(xy 19.407885 -404.652172) (xy 19.399765 -404.707348) (xy 19.383697 -404.760755) (xy 19.360025 -404.811252)
			(xy 19.329252 -404.857765) (xy 19.292035 -404.899302) (xy 19.249167 -404.934977) (xy 19.201561 -404.964031)
			(xy 19.150232 -404.985843) (xy 19.096275 -404.999949) (xy 19.040838 -405.006049) (xy 18.985104 -405.004012)
			(xy 18.930261 -404.993882) (xy 18.877477 -404.975875) (xy 18.827877 -404.950374) (xy 18.782519 -404.917923)
			(xy 18.74237 -404.879214) (xy 18.708284 -404.835071) (xy 18.680988 -404.786436) (xy 18.661065 -404.734345)
			(xy 18.648939 -404.679908) (xy 18.644868 -404.624286) (xy 18.094299 -404.624286) (xy 18.090075 -404.638327)
			(xy 18.066403 -404.688824) (xy 18.03563 -404.735337) (xy 17.998413 -404.776874) (xy 17.955545 -404.812549)
			(xy 17.907939 -404.841603) (xy 17.85661 -404.863415) (xy 17.802653 -404.877521) (xy 17.747216 -404.883621)
			(xy 17.691482 -404.881584) (xy 17.636639 -404.871454) (xy 17.583855 -404.853447) (xy 17.534255 -404.827946)
			(xy 17.488897 -404.795495) (xy 17.448748 -404.756786) (xy 17.414662 -404.712643) (xy 17.387366 -404.664008)
			(xy 17.367443 -404.611917) (xy 17.355317 -404.55748) (xy 17.351246 -404.501858) (xy 1.727708 -404.501858)
			(xy 1.727708 -410.248608) (xy 14.998698 -410.248608) (xy 15.002769 -410.192986) (xy 15.014895 -410.138549)
			(xy 15.034818 -410.086458) (xy 15.062114 -410.037823) (xy 15.0962 -409.99368) (xy 15.136349 -409.954971)
			(xy 15.181707 -409.92252) (xy 15.231307 -409.897019) (xy 15.284091 -409.879012) (xy 15.338934 -409.868882)
			(xy 15.394668 -409.866845) (xy 15.450105 -409.872945) (xy 15.504062 -409.887051) (xy 15.555391 -409.908863)
			(xy 15.602997 -409.937917) (xy 15.645865 -409.973592) (xy 15.683082 -410.015129) (xy 15.713855 -410.061642)
			(xy 15.737527 -410.112139) (xy 15.753595 -410.165546) (xy 15.761715 -410.220722) (xy 15.762224 -410.248608)
			(xy 15.761715 -410.276494) (xy 15.753595 -410.33167) (xy 15.737527 -410.385077) (xy 15.713855 -410.435574)
			(xy 15.683082 -410.482087) (xy 15.645865 -410.523624) (xy 15.602997 -410.559299) (xy 15.555391 -410.588353)
			(xy 15.504062 -410.610165) (xy 15.450105 -410.624271) (xy 15.394668 -410.630371) (xy 15.338934 -410.628334)
			(xy 15.284091 -410.618204) (xy 15.231307 -410.600197) (xy 15.181707 -410.574696) (xy 15.136349 -410.542245)
			(xy 15.0962 -410.503536) (xy 15.062114 -410.459393) (xy 15.034818 -410.410758) (xy 15.014895 -410.358667)
			(xy 15.002769 -410.30423) (xy 14.998698 -410.248608) (xy 1.727708 -410.248608) (xy 1.727708 -412.752286)
			(xy 17.883122 -412.752286) (xy 17.887193 -412.696664) (xy 17.899319 -412.642227) (xy 17.919242 -412.590136)
			(xy 17.946538 -412.541501) (xy 17.980624 -412.497358) (xy 18.020773 -412.458649) (xy 18.066131 -412.426198)
			(xy 18.115731 -412.400697) (xy 18.168515 -412.38269) (xy 18.223358 -412.37256) (xy 18.279092 -412.370523)
			(xy 18.334529 -412.376623) (xy 18.388486 -412.390729) (xy 18.439815 -412.412541) (xy 18.487421 -412.441595)
			(xy 18.530289 -412.47727) (xy 18.567506 -412.518807) (xy 18.598279 -412.56532) (xy 18.621951 -412.615817)
			(xy 18.638019 -412.669224) (xy 18.646139 -412.7244) (xy 18.646648 -412.752286) (xy 18.646139 -412.780172)
			(xy 18.638019 -412.835348) (xy 18.621951 -412.888755) (xy 18.598527 -412.938722) (xy 19.503896 -412.938722)
			(xy 19.507967 -412.8831) (xy 19.520093 -412.828663) (xy 19.540016 -412.776572) (xy 19.567312 -412.727937)
			(xy 19.601398 -412.683794) (xy 19.641547 -412.645085) (xy 19.686905 -412.612634) (xy 19.736505 -412.587133)
			(xy 19.789289 -412.569126) (xy 19.844132 -412.558996) (xy 19.899866 -412.556959) (xy 19.955303 -412.563059)
			(xy 20.00926 -412.577165) (xy 20.060589 -412.598977) (xy 20.108195 -412.628031) (xy 20.151063 -412.663706)
			(xy 20.1683 -412.682944) (xy 20.874988 -412.682944) (xy 20.879059 -412.627322) (xy 20.891185 -412.572885)
			(xy 20.911108 -412.520794) (xy 20.938404 -412.472159) (xy 20.97249 -412.428016) (xy 21.012639 -412.389307)
			(xy 21.057997 -412.356856) (xy 21.107597 -412.331355) (xy 21.160381 -412.313348) (xy 21.215224 -412.303218)
			(xy 21.270958 -412.301181) (xy 21.326395 -412.307281) (xy 21.380352 -412.321387) (xy 21.431681 -412.343199)
			(xy 21.479287 -412.372253) (xy 21.522155 -412.407928) (xy 21.559372 -412.449465) (xy 21.590145 -412.495978)
			(xy 21.613817 -412.546475) (xy 21.629885 -412.599882) (xy 21.638005 -412.655058) (xy 21.638514 -412.682944)
			(xy 21.638005 -412.71083) (xy 21.629885 -412.766006) (xy 21.613817 -412.819413) (xy 21.590145 -412.86991)
			(xy 21.559372 -412.916423) (xy 21.522155 -412.95796) (xy 21.479287 -412.993635) (xy 21.431681 -413.022689)
			(xy 21.380352 -413.044501) (xy 21.326395 -413.058607) (xy 21.270958 -413.064707) (xy 21.215224 -413.06267)
			(xy 21.160381 -413.05254) (xy 21.107597 -413.034533) (xy 21.057997 -413.009032) (xy 21.012639 -412.976581)
			(xy 20.97249 -412.937872) (xy 20.938404 -412.893729) (xy 20.911108 -412.845094) (xy 20.891185 -412.793003)
			(xy 20.879059 -412.738566) (xy 20.874988 -412.682944) (xy 20.1683 -412.682944) (xy 20.18828 -412.705243)
			(xy 20.219053 -412.751756) (xy 20.242725 -412.802253) (xy 20.258793 -412.85566) (xy 20.266913 -412.910836)
			(xy 20.267422 -412.938722) (xy 20.266913 -412.966608) (xy 20.258793 -413.021784) (xy 20.242725 -413.075191)
			(xy 20.219053 -413.125688) (xy 20.18828 -413.172201) (xy 20.151063 -413.213738) (xy 20.108195 -413.249413)
			(xy 20.060589 -413.278467) (xy 20.00926 -413.300279) (xy 19.955303 -413.314385) (xy 19.899866 -413.320485)
			(xy 19.844132 -413.318448) (xy 19.789289 -413.308318) (xy 19.736505 -413.290311) (xy 19.686905 -413.26481)
			(xy 19.641547 -413.232359) (xy 19.601398 -413.19365) (xy 19.567312 -413.149507) (xy 19.540016 -413.100872)
			(xy 19.520093 -413.048781) (xy 19.507967 -412.994344) (xy 19.503896 -412.938722) (xy 18.598527 -412.938722)
			(xy 18.598279 -412.939252) (xy 18.567506 -412.985765) (xy 18.530289 -413.027302) (xy 18.487421 -413.062977)
			(xy 18.439815 -413.092031) (xy 18.388486 -413.113843) (xy 18.334529 -413.127949) (xy 18.279092 -413.134049)
			(xy 18.223358 -413.132012) (xy 18.168515 -413.121882) (xy 18.115731 -413.103875) (xy 18.066131 -413.078374)
			(xy 18.020773 -413.045923) (xy 17.980624 -413.007214) (xy 17.946538 -412.963071) (xy 17.919242 -412.914436)
			(xy 17.899319 -412.862345) (xy 17.887193 -412.807908) (xy 17.883122 -412.752286) (xy 1.727708 -412.752286)
			(xy 1.727708 -414.985454) (xy 17.471896 -414.985454) (xy 17.475967 -414.929832) (xy 17.488093 -414.875395)
			(xy 17.508016 -414.823304) (xy 17.535312 -414.774669) (xy 17.569398 -414.730526) (xy 17.609547 -414.691817)
			(xy 17.654905 -414.659366) (xy 17.704505 -414.633865) (xy 17.757289 -414.615858) (xy 17.812132 -414.605728)
			(xy 17.867866 -414.603691) (xy 17.923303 -414.609791) (xy 17.97726 -414.623897) (xy 18.028589 -414.645709)
			(xy 18.076195 -414.674763) (xy 18.119063 -414.710438) (xy 18.15628 -414.751975) (xy 18.187053 -414.798488)
			(xy 18.210725 -414.848985) (xy 18.226793 -414.902392) (xy 18.234913 -414.957568) (xy 18.235422 -414.985454)
			(xy 19.503896 -414.985454) (xy 19.507967 -414.929832) (xy 19.520093 -414.875395) (xy 19.540016 -414.823304)
			(xy 19.567312 -414.774669) (xy 19.601398 -414.730526) (xy 19.641547 -414.691817) (xy 19.686905 -414.659366)
			(xy 19.736505 -414.633865) (xy 19.789289 -414.615858) (xy 19.844132 -414.605728) (xy 19.899866 -414.603691)
			(xy 19.955303 -414.609791) (xy 20.00926 -414.623897) (xy 20.060589 -414.645709) (xy 20.108195 -414.674763)
			(xy 20.151063 -414.710438) (xy 20.18828 -414.751975) (xy 20.219053 -414.798488) (xy 20.242725 -414.848985)
			(xy 20.258793 -414.902392) (xy 20.266913 -414.957568) (xy 20.267422 -414.985454) (xy 20.519896 -414.985454)
			(xy 20.523967 -414.929832) (xy 20.536093 -414.875395) (xy 20.556016 -414.823304) (xy 20.583312 -414.774669)
			(xy 20.617398 -414.730526) (xy 20.657547 -414.691817) (xy 20.702905 -414.659366) (xy 20.752505 -414.633865)
			(xy 20.805289 -414.615858) (xy 20.860132 -414.605728) (xy 20.915866 -414.603691) (xy 20.971303 -414.609791)
			(xy 21.02526 -414.623897) (xy 21.076589 -414.645709) (xy 21.124195 -414.674763) (xy 21.167063 -414.710438)
			(xy 21.20428 -414.751975) (xy 21.235053 -414.798488) (xy 21.258725 -414.848985) (xy 21.274793 -414.902392)
			(xy 21.282913 -414.957568) (xy 21.283422 -414.985454) (xy 21.282913 -415.01334) (xy 21.274793 -415.068516)
			(xy 21.258725 -415.121923) (xy 21.235053 -415.17242) (xy 21.20428 -415.218933) (xy 21.167063 -415.26047)
			(xy 21.124195 -415.296145) (xy 21.076589 -415.325199) (xy 21.02526 -415.347011) (xy 20.971303 -415.361117)
			(xy 20.915866 -415.367217) (xy 20.860132 -415.36518) (xy 20.805289 -415.35505) (xy 20.752505 -415.337043)
			(xy 20.702905 -415.311542) (xy 20.657547 -415.279091) (xy 20.617398 -415.240382) (xy 20.583312 -415.196239)
			(xy 20.556016 -415.147604) (xy 20.536093 -415.095513) (xy 20.523967 -415.041076) (xy 20.519896 -414.985454)
			(xy 20.267422 -414.985454) (xy 20.266913 -415.01334) (xy 20.258793 -415.068516) (xy 20.242725 -415.121923)
			(xy 20.219053 -415.17242) (xy 20.18828 -415.218933) (xy 20.151063 -415.26047) (xy 20.108195 -415.296145)
			(xy 20.060589 -415.325199) (xy 20.00926 -415.347011) (xy 19.955303 -415.361117) (xy 19.899866 -415.367217)
			(xy 19.844132 -415.36518) (xy 19.789289 -415.35505) (xy 19.736505 -415.337043) (xy 19.686905 -415.311542)
			(xy 19.641547 -415.279091) (xy 19.601398 -415.240382) (xy 19.567312 -415.196239) (xy 19.540016 -415.147604)
			(xy 19.520093 -415.095513) (xy 19.507967 -415.041076) (xy 19.503896 -414.985454) (xy 18.235422 -414.985454)
			(xy 18.234913 -415.01334) (xy 18.226793 -415.068516) (xy 18.210725 -415.121923) (xy 18.187053 -415.17242)
			(xy 18.15628 -415.218933) (xy 18.119063 -415.26047) (xy 18.076195 -415.296145) (xy 18.028589 -415.325199)
			(xy 17.97726 -415.347011) (xy 17.923303 -415.361117) (xy 17.867866 -415.367217) (xy 17.812132 -415.36518)
			(xy 17.757289 -415.35505) (xy 17.704505 -415.337043) (xy 17.654905 -415.311542) (xy 17.609547 -415.279091)
			(xy 17.569398 -415.240382) (xy 17.535312 -415.196239) (xy 17.508016 -415.147604) (xy 17.488093 -415.095513)
			(xy 17.475967 -415.041076) (xy 17.471896 -414.985454) (xy 1.727708 -414.985454) (xy 1.727708 -416.405314)
			(xy 1.728134 -416.415383) (xy 1.735853 -416.433983) (xy 1.742694 -416.441382) (xy 2.488692 -417.18738)
			(xy 2.496089 -417.19423) (xy 2.514687 -417.20197) (xy 2.52476 -417.202366) (xy 23.94585 -417.202366)
		)
		(stroke
			(width 0)
			(type solid)
		)
		(fill yes)
		(layer "In11.Cu")
		(net "GND")
	)
	(gr_poly
		(pts
			(xy 139.595352 -301.515272) (xy 139.605343 -301.514743) (xy 139.623785 -301.507038) (xy 139.631166 -301.500286)
			(xy 141.795754 -299.335698) (xy 141.818768 -299.313363) (xy 141.868921 -299.273389) (xy 141.89583 -299.255942)
			(xy 141.904171 -299.250154) (xy 141.915764 -299.233508) (xy 141.919942 -299.213658) (xy 141.918436 -299.203618)
			(xy 141.915469 -299.1865) (xy 141.912294 -299.151902) (xy 141.912086 -299.13453) (xy 141.912086 -299.130212)
			(xy 141.912795 -299.103114) (xy 141.920929 -299.049521) (xy 141.936567 -298.99762) (xy 141.959394 -298.948454)
			(xy 141.988949 -298.903014) (xy 142.024638 -298.862215) (xy 142.065743 -298.826878) (xy 142.111436 -298.797714)
			(xy 142.160796 -298.775311) (xy 142.21283 -298.760121) (xy 142.266491 -298.752447) (xy 142.293594 -298.752006)
			(xy 142.320127 -298.752469) (xy 142.372678 -298.759835) (xy 142.423703 -298.77441) (xy 142.472215 -298.795916)
			(xy 142.51728 -298.823935) (xy 142.558028 -298.857929) (xy 142.593673 -298.89724) (xy 142.623527 -298.941111)
			(xy 142.647015 -298.988695) (xy 142.663682 -299.039075) (xy 142.673209 -299.091278) (xy 142.674848 -299.117766)
			(xy 142.67561 -299.13834) (xy 142.705074 -299.16628) (xy 143.3576 -299.16628) (xy 143.387064 -299.13834)
			(xy 143.387826 -299.117766) (xy 143.389377 -299.091269) (xy 143.398896 -299.039053) (xy 143.415562 -298.988661)
			(xy 143.439051 -298.941066) (xy 143.468912 -298.897186) (xy 143.504567 -298.857869) (xy 143.545328 -298.823874)
			(xy 143.590408 -298.795858) (xy 143.638937 -298.774362) (xy 143.689976 -298.759799) (xy 143.742542 -298.752453)
			(xy 143.76908 -298.752006) (xy 143.794131 -298.752383) (xy 143.843804 -298.758909) (xy 143.892194 -298.771892)
			(xy 143.938463 -298.791107) (xy 143.960342 -298.803314) (xy 143.97228 -298.810426) (xy 143.999204 -298.810426)
			(xy 144.080992 -298.763436) (xy 144.091406 -298.755308) (xy 144.09801 -298.748704) (xy 144.104867 -298.74131)
			(xy 144.112617 -298.722711) (xy 144.112996 -298.712636) (xy 144.112996 -296.350944) (xy 144.112661 -296.342053)
			(xy 144.106575 -296.325346) (xy 144.095127 -296.311741) (xy 144.087596 -296.307002) (xy 143.999204 -296.256202)
			(xy 143.97228 -296.256202) (xy 143.960342 -296.26306) (xy 143.938471 -296.275295) (xy 143.892206 -296.294559)
			(xy 143.843817 -296.307602) (xy 143.794137 -296.314198) (xy 143.76908 -296.314622) (xy 143.741829 -296.314135)
			(xy 143.687881 -296.306376) (xy 143.635587 -296.291018) (xy 143.58601 -296.268375) (xy 143.540161 -296.238907)
			(xy 143.498971 -296.203214) (xy 143.463281 -296.162023) (xy 143.433815 -296.116172) (xy 143.411175 -296.066594)
			(xy 143.39582 -296.014299) (xy 143.388064 -295.960351) (xy 143.388064 -295.905849) (xy 143.39582 -295.851901)
			(xy 143.411175 -295.799606) (xy 143.433815 -295.750028) (xy 143.463281 -295.704177) (xy 143.498971 -295.662986)
			(xy 143.540161 -295.627293) (xy 143.58601 -295.597825) (xy 143.635587 -295.575182) (xy 143.687881 -295.559824)
			(xy 143.741829 -295.552065) (xy 143.76908 -295.551606) (xy 143.794131 -295.551983) (xy 143.843804 -295.558509)
			(xy 143.892194 -295.571492) (xy 143.938463 -295.590707) (xy 143.960342 -295.602914) (xy 143.97228 -295.610026)
			(xy 143.999204 -295.610026) (xy 144.080992 -295.563036) (xy 144.091406 -295.554908) (xy 144.09801 -295.548304)
			(xy 144.104867 -295.54091) (xy 144.112617 -295.522311) (xy 144.112996 -295.512236) (xy 144.112996 -293.150544)
			(xy 144.112661 -293.141653) (xy 144.106575 -293.124946) (xy 144.095127 -293.111341) (xy 144.087596 -293.106602)
			(xy 143.999204 -293.055802) (xy 143.97228 -293.055802) (xy 143.960342 -293.06266) (xy 143.938471 -293.074895)
			(xy 143.892206 -293.094159) (xy 143.843817 -293.107202) (xy 143.794137 -293.113798) (xy 143.76908 -293.114222)
			(xy 143.741829 -293.113735) (xy 143.687881 -293.105976) (xy 143.635587 -293.090618) (xy 143.58601 -293.067975)
			(xy 143.540161 -293.038507) (xy 143.498971 -293.002814) (xy 143.463281 -292.961623) (xy 143.433815 -292.915772)
			(xy 143.411175 -292.866194) (xy 143.39582 -292.813899) (xy 143.388064 -292.759951) (xy 143.388064 -292.705449)
			(xy 143.39582 -292.651501) (xy 143.411175 -292.599206) (xy 143.433815 -292.549628) (xy 143.463281 -292.503777)
			(xy 143.498971 -292.462586) (xy 143.540161 -292.426893) (xy 143.58601 -292.397425) (xy 143.635587 -292.374782)
			(xy 143.687881 -292.359424) (xy 143.741829 -292.351665) (xy 143.76908 -292.351206) (xy 143.794131 -292.351583)
			(xy 143.843804 -292.358109) (xy 143.892194 -292.371092) (xy 143.938463 -292.390307) (xy 143.960342 -292.402514)
			(xy 143.97228 -292.409626) (xy 143.999204 -292.409626) (xy 144.080992 -292.362636) (xy 144.091406 -292.354508)
			(xy 144.09801 -292.347904) (xy 144.104867 -292.34051) (xy 144.112617 -292.321911) (xy 144.112996 -292.311836)
			(xy 144.112996 -289.950144) (xy 144.112661 -289.941253) (xy 144.106575 -289.924546) (xy 144.095127 -289.910941)
			(xy 144.087596 -289.906202) (xy 143.999204 -289.855402) (xy 143.97228 -289.855402) (xy 143.960342 -289.86226)
			(xy 143.938471 -289.874495) (xy 143.892206 -289.893759) (xy 143.843817 -289.906802) (xy 143.794137 -289.913398)
			(xy 143.76908 -289.913822) (xy 143.741829 -289.913335) (xy 143.687881 -289.905576) (xy 143.635587 -289.890218)
			(xy 143.58601 -289.867575) (xy 143.540161 -289.838107) (xy 143.498971 -289.802414) (xy 143.463281 -289.761223)
			(xy 143.433815 -289.715372) (xy 143.411175 -289.665794) (xy 143.39582 -289.613499) (xy 143.388064 -289.559551)
			(xy 143.388064 -289.505049) (xy 143.39582 -289.451101) (xy 143.411175 -289.398806) (xy 143.433815 -289.349228)
			(xy 143.463281 -289.303377) (xy 143.498971 -289.262186) (xy 143.540161 -289.226493) (xy 143.58601 -289.197025)
			(xy 143.635587 -289.174382) (xy 143.687881 -289.159024) (xy 143.741829 -289.151265) (xy 143.76908 -289.150806)
			(xy 143.794131 -289.151183) (xy 143.843804 -289.157709) (xy 143.892194 -289.170692) (xy 143.938463 -289.189907)
			(xy 143.960342 -289.202114) (xy 143.97228 -289.209226) (xy 143.999204 -289.209226) (xy 144.080992 -289.162236)
			(xy 144.091406 -289.154108) (xy 144.09801 -289.147504) (xy 144.104867 -289.14011) (xy 144.112617 -289.121511)
			(xy 144.112996 -289.111436) (xy 144.112996 -286.749744) (xy 144.112661 -286.740853) (xy 144.106575 -286.724146)
			(xy 144.095127 -286.710541) (xy 144.087596 -286.705802) (xy 143.999204 -286.655002) (xy 143.97228 -286.655002)
			(xy 143.960342 -286.66186) (xy 143.938471 -286.674095) (xy 143.892206 -286.693359) (xy 143.843817 -286.706402)
			(xy 143.794137 -286.712998) (xy 143.76908 -286.713422) (xy 143.741829 -286.712935) (xy 143.687881 -286.705176)
			(xy 143.635587 -286.689818) (xy 143.58601 -286.667175) (xy 143.540161 -286.637707) (xy 143.498971 -286.602014)
			(xy 143.463281 -286.560823) (xy 143.433815 -286.514972) (xy 143.411175 -286.465394) (xy 143.39582 -286.413099)
			(xy 143.388064 -286.359151) (xy 143.388064 -286.304649) (xy 143.39582 -286.250701) (xy 143.411175 -286.198406)
			(xy 143.433815 -286.148828) (xy 143.463281 -286.102977) (xy 143.498971 -286.061786) (xy 143.540161 -286.026093)
			(xy 143.58601 -285.996625) (xy 143.635587 -285.973982) (xy 143.687881 -285.958624) (xy 143.741829 -285.950865)
			(xy 143.76908 -285.950406) (xy 143.794131 -285.950783) (xy 143.843804 -285.957309) (xy 143.892194 -285.970292)
			(xy 143.938463 -285.989507) (xy 143.960342 -286.001714) (xy 143.97228 -286.008826) (xy 143.999204 -286.008826)
			(xy 144.080992 -285.961836) (xy 144.091406 -285.953708) (xy 144.09801 -285.947104) (xy 144.104867 -285.93971)
			(xy 144.112617 -285.921111) (xy 144.112996 -285.911036) (xy 144.112996 -283.549344) (xy 144.112661 -283.540453)
			(xy 144.106575 -283.523746) (xy 144.095127 -283.510141) (xy 144.087596 -283.505402) (xy 143.999204 -283.454602)
			(xy 143.97228 -283.454602) (xy 143.960342 -283.46146) (xy 143.938471 -283.473695) (xy 143.892206 -283.492959)
			(xy 143.843817 -283.506002) (xy 143.794137 -283.512598) (xy 143.76908 -283.513022) (xy 143.741829 -283.512535)
			(xy 143.687881 -283.504776) (xy 143.635587 -283.489418) (xy 143.58601 -283.466775) (xy 143.540161 -283.437307)
			(xy 143.498971 -283.401614) (xy 143.463281 -283.360423) (xy 143.433815 -283.314572) (xy 143.411175 -283.264994)
			(xy 143.39582 -283.212699) (xy 143.388064 -283.158751) (xy 143.388064 -283.104249) (xy 143.39582 -283.050301)
			(xy 143.411175 -282.998006) (xy 143.433815 -282.948428) (xy 143.463281 -282.902577) (xy 143.498971 -282.861386)
			(xy 143.540161 -282.825693) (xy 143.58601 -282.796225) (xy 143.635587 -282.773582) (xy 143.687881 -282.758224)
			(xy 143.741829 -282.750465) (xy 143.76908 -282.750006) (xy 143.794131 -282.750383) (xy 143.843804 -282.756909)
			(xy 143.892194 -282.769892) (xy 143.938463 -282.789107) (xy 143.960342 -282.801314) (xy 143.97228 -282.808426)
			(xy 143.999204 -282.808426) (xy 144.080992 -282.761436) (xy 144.091406 -282.753308) (xy 144.09801 -282.746704)
			(xy 144.104867 -282.73931) (xy 144.112617 -282.720711) (xy 144.112996 -282.710636) (xy 144.112996 -280.348944)
			(xy 144.112661 -280.340053) (xy 144.106575 -280.323346) (xy 144.095127 -280.309741) (xy 144.087596 -280.305002)
			(xy 143.999204 -280.254202) (xy 143.97228 -280.254202) (xy 143.960342 -280.26106) (xy 143.938471 -280.273295)
			(xy 143.892206 -280.292559) (xy 143.843817 -280.305602) (xy 143.794137 -280.312198) (xy 143.76908 -280.312622)
			(xy 143.741829 -280.312135) (xy 143.687881 -280.304376) (xy 143.635587 -280.289018) (xy 143.58601 -280.266375)
			(xy 143.540161 -280.236907) (xy 143.498971 -280.201214) (xy 143.463281 -280.160023) (xy 143.433815 -280.114172)
			(xy 143.411175 -280.064594) (xy 143.39582 -280.012299) (xy 143.388064 -279.958351) (xy 143.388064 -279.903849)
			(xy 143.39582 -279.849901) (xy 143.411175 -279.797606) (xy 143.433815 -279.748028) (xy 143.463281 -279.702177)
			(xy 143.498971 -279.660986) (xy 143.540161 -279.625293) (xy 143.58601 -279.595825) (xy 143.635587 -279.573182)
			(xy 143.687881 -279.557824) (xy 143.741829 -279.550065) (xy 143.76908 -279.549606) (xy 143.794131 -279.549983)
			(xy 143.843804 -279.556509) (xy 143.892194 -279.569492) (xy 143.938463 -279.588707) (xy 143.960342 -279.600914)
			(xy 143.97228 -279.608026) (xy 143.999204 -279.608026) (xy 144.080992 -279.561036) (xy 144.091406 -279.552908)
			(xy 144.09801 -279.546304) (xy 144.104867 -279.53891) (xy 144.112617 -279.520311) (xy 144.112996 -279.510236)
			(xy 144.112996 -275.532088) (xy 144.105376 -275.513292) (xy 144.09801 -275.50618) (xy 143.891 -275.29917)
			(xy 143.881856 -275.29536) (xy 143.79331 -275.257206) (xy 143.619028 -275.174684) (xy 143.448219 -275.085195)
			(xy 143.281162 -274.988885) (xy 143.118128 -274.88591) (xy 142.959384 -274.776438) (xy 142.805187 -274.660648)
			(xy 142.65579 -274.538728) (xy 142.511436 -274.410878) (xy 142.37236 -274.277305) (xy 142.238788 -274.138228)
			(xy 142.110939 -273.993872) (xy 141.989021 -273.844474) (xy 141.873233 -273.690276) (xy 141.763763 -273.53153)
			(xy 141.66079 -273.368495) (xy 141.564481 -273.201437) (xy 141.474994 -273.030627) (xy 141.392474 -272.856345)
			(xy 141.354302 -272.767806) (xy 141.350492 -272.758662) (xy 140.59535 -272.00352) (xy 140.588511 -271.99612)
			(xy 140.580797 -271.977521) (xy 140.580364 -271.967452) (xy 140.580364 -268.781276) (xy 140.580793 -268.771209)
			(xy 140.588521 -268.752617) (xy 140.59535 -268.745208) (xy 147.228814 -262.111744) (xy 147.229322 -262.111236)
			(xy 147.235906 -262.103856) (xy 147.243357 -262.085556) (xy 147.2438 -262.075676) (xy 147.2438 -259.659628)
			(xy 147.242784 -259.654294) (xy 147.239007 -259.63502) (xy 147.234939 -259.595954) (xy 147.234656 -259.576316)
			(xy 147.234913 -259.556676) (xy 147.238989 -259.517609) (xy 147.242784 -259.498338) (xy 147.2438 -259.493004)
			(xy 147.2438 -258.143756) (xy 147.244231 -258.133689) (xy 147.251957 -258.115097) (xy 147.258786 -258.107688)
			(xy 150.855172 -254.511302) (xy 150.862022 -254.503905) (xy 150.869761 -254.485307) (xy 150.870158 -254.475234)
			(xy 150.870158 -253.910084) (xy 150.86943 -253.897837) (xy 150.85815 -253.876092) (xy 150.848568 -253.868428)
			(xy 150.769828 -253.813564) (xy 150.745444 -253.810262) (xy 150.733506 -253.81458) (xy 150.701841 -253.825476)
			(xy 150.635922 -253.837237) (xy 150.602442 -253.837948) (xy 150.575184 -253.837488) (xy 150.521223 -253.829735)
			(xy 150.468915 -253.814381) (xy 150.419324 -253.791738) (xy 150.373461 -253.762268) (xy 150.332259 -253.726571)
			(xy 150.296557 -253.685373) (xy 150.267082 -253.639513) (xy 150.244434 -253.589925) (xy 150.229074 -253.537618)
			(xy 150.221315 -253.483658) (xy 150.221315 -253.429142) (xy 150.229074 -253.375182) (xy 150.244434 -253.322875)
			(xy 150.267082 -253.273287) (xy 150.296557 -253.227427) (xy 150.332259 -253.186229) (xy 150.373461 -253.150532)
			(xy 150.419324 -253.121062) (xy 150.468915 -253.098419) (xy 150.521223 -253.083065) (xy 150.575184 -253.075312)
			(xy 150.602442 -253.074932) (xy 150.635918 -253.075679) (xy 150.701833 -253.087436) (xy 150.733506 -253.0983)
			(xy 150.745444 -253.102618) (xy 150.769828 -253.099316) (xy 150.848568 -253.044452) (xy 150.858201 -253.03683)
			(xy 150.86949 -253.01506) (xy 150.870158 -253.002796) (xy 150.870158 -251.612146) (xy 150.869444 -251.599892)
			(xy 150.858178 -251.578124) (xy 150.848568 -251.57049) (xy 150.769828 -251.515626) (xy 150.745444 -251.512324)
			(xy 150.733506 -251.516642) (xy 150.701841 -251.527537) (xy 150.635921 -251.539296) (xy 150.602442 -251.54001)
			(xy 150.575187 -251.53955) (xy 150.521231 -251.531797) (xy 150.468928 -251.516445) (xy 150.419342 -251.493805)
			(xy 150.373484 -251.464338) (xy 150.332286 -251.428644) (xy 150.296588 -251.38745) (xy 150.267115 -251.341594)
			(xy 150.24447 -251.292011) (xy 150.229112 -251.23971) (xy 150.221353 -251.185755) (xy 150.221353 -251.131245)
			(xy 150.229112 -251.07729) (xy 150.24447 -251.024989) (xy 150.267115 -250.975406) (xy 150.296588 -250.92955)
			(xy 150.332286 -250.888356) (xy 150.373484 -250.852662) (xy 150.419342 -250.823195) (xy 150.468928 -250.800555)
			(xy 150.521231 -250.785203) (xy 150.575187 -250.77745) (xy 150.602442 -250.776994) (xy 150.635918 -250.777742)
			(xy 150.701832 -250.789501) (xy 150.733506 -250.800362) (xy 150.745444 -250.80468) (xy 150.769828 -250.801378)
			(xy 150.848568 -250.746514) (xy 150.858195 -250.73889) (xy 150.869468 -250.71712) (xy 150.870158 -250.704858)
			(xy 150.870158 -237.74019) (xy 150.869732 -237.730122) (xy 150.86201 -237.711524) (xy 150.855172 -237.704122)
			(xy 150.18766 -237.03661) (xy 150.18026 -237.029769) (xy 150.161662 -237.022047) (xy 150.151592 -237.021624)
			(xy 145.930366 -237.021624) (xy 145.920299 -237.022054) (xy 145.901706 -237.02978) (xy 145.894298 -237.03661)
			(xy 145.41373 -237.517178) (xy 145.922744 -237.517178) (xy 145.926815 -237.461556) (xy 145.938941 -237.407119)
			(xy 145.958864 -237.355028) (xy 145.98616 -237.306393) (xy 146.020246 -237.26225) (xy 146.060395 -237.223541)
			(xy 146.105753 -237.19109) (xy 146.155353 -237.165589) (xy 146.208137 -237.147582) (xy 146.26298 -237.137452)
			(xy 146.318714 -237.135415) (xy 146.374151 -237.141515) (xy 146.428108 -237.155621) (xy 146.479437 -237.177433)
			(xy 146.527043 -237.206487) (xy 146.569911 -237.242162) (xy 146.607128 -237.283699) (xy 146.637901 -237.330212)
			(xy 146.661573 -237.380709) (xy 146.677641 -237.434116) (xy 146.685761 -237.489292) (xy 146.68627 -237.517178)
			(xy 146.685761 -237.545064) (xy 146.677641 -237.60024) (xy 146.661573 -237.653647) (xy 146.637901 -237.704144)
			(xy 146.607128 -237.750657) (xy 146.569911 -237.792194) (xy 146.527043 -237.827869) (xy 146.479437 -237.856923)
			(xy 146.428108 -237.878735) (xy 146.374151 -237.892841) (xy 146.318714 -237.898941) (xy 146.26298 -237.896904)
			(xy 146.208137 -237.886774) (xy 146.155353 -237.868767) (xy 146.105753 -237.843266) (xy 146.060395 -237.810815)
			(xy 146.020246 -237.772106) (xy 145.98616 -237.727963) (xy 145.958864 -237.679328) (xy 145.938941 -237.627237)
			(xy 145.926815 -237.5728) (xy 145.922744 -237.517178) (xy 145.41373 -237.517178) (xy 145.304256 -237.626652)
			(xy 145.297412 -237.634051) (xy 145.289687 -237.652649) (xy 145.28927 -237.66272) (xy 145.28927 -238.642652)
			(xy 145.289876 -238.655077) (xy 145.301442 -238.677069) (xy 145.311368 -238.684562) (xy 145.391378 -238.738918)
			(xy 145.41627 -238.741712) (xy 145.428208 -238.73714) (xy 145.450566 -238.728704) (xy 145.496857 -238.716835)
			(xy 145.544268 -238.710851) (xy 145.568162 -238.71047) (xy 145.595418 -238.71093) (xy 145.649376 -238.718683)
			(xy 145.701682 -238.734037) (xy 145.75127 -238.756679) (xy 145.79713 -238.786147) (xy 145.83833 -238.821843)
			(xy 145.87403 -238.863039) (xy 145.903503 -238.908897) (xy 145.92615 -238.958482) (xy 145.935516 -238.990378)
			(xy 146.405344 -238.990378) (xy 146.409415 -238.934756) (xy 146.421541 -238.880319) (xy 146.441464 -238.828228)
			(xy 146.46876 -238.779593) (xy 146.502846 -238.73545) (xy 146.542995 -238.696741) (xy 146.588353 -238.66429)
			(xy 146.637953 -238.638789) (xy 146.690737 -238.620782) (xy 146.74558 -238.610652) (xy 146.801314 -238.608615)
			(xy 146.856751 -238.614715) (xy 146.910708 -238.628821) (xy 146.962037 -238.650633) (xy 147.009643 -238.679687)
			(xy 147.052511 -238.715362) (xy 147.089728 -238.756899) (xy 147.120501 -238.803412) (xy 147.144173 -238.853909)
			(xy 147.160241 -238.907316) (xy 147.168361 -238.962492) (xy 147.16887 -238.990378) (xy 147.370544 -238.990378)
			(xy 147.374615 -238.934756) (xy 147.386741 -238.880319) (xy 147.406664 -238.828228) (xy 147.43396 -238.779593)
			(xy 147.468046 -238.73545) (xy 147.508195 -238.696741) (xy 147.553553 -238.66429) (xy 147.603153 -238.638789)
			(xy 147.655937 -238.620782) (xy 147.71078 -238.610652) (xy 147.766514 -238.608615) (xy 147.821951 -238.614715)
			(xy 147.875908 -238.628821) (xy 147.927237 -238.650633) (xy 147.974843 -238.679687) (xy 148.017711 -238.715362)
			(xy 148.054928 -238.756899) (xy 148.085701 -238.803412) (xy 148.109373 -238.853909) (xy 148.125441 -238.907316)
			(xy 148.133561 -238.962492) (xy 148.13407 -238.990378) (xy 148.133561 -239.018264) (xy 148.125441 -239.07344)
			(xy 148.109373 -239.126847) (xy 148.085701 -239.177344) (xy 148.054928 -239.223857) (xy 148.017711 -239.265394)
			(xy 147.974843 -239.301069) (xy 147.927237 -239.330123) (xy 147.875908 -239.351935) (xy 147.821951 -239.366041)
			(xy 147.766514 -239.372141) (xy 147.71078 -239.370104) (xy 147.655937 -239.359974) (xy 147.603153 -239.341967)
			(xy 147.553553 -239.316466) (xy 147.508195 -239.284015) (xy 147.468046 -239.245306) (xy 147.43396 -239.201163)
			(xy 147.406664 -239.152528) (xy 147.386741 -239.100437) (xy 147.374615 -239.046) (xy 147.370544 -238.990378)
			(xy 147.16887 -238.990378) (xy 147.168361 -239.018264) (xy 147.160241 -239.07344) (xy 147.144173 -239.126847)
			(xy 147.120501 -239.177344) (xy 147.089728 -239.223857) (xy 147.052511 -239.265394) (xy 147.009643 -239.301069)
			(xy 146.962037 -239.330123) (xy 146.910708 -239.351935) (xy 146.856751 -239.366041) (xy 146.801314 -239.372141)
			(xy 146.74558 -239.370104) (xy 146.690737 -239.359974) (xy 146.637953 -239.341967) (xy 146.588353 -239.316466)
			(xy 146.542995 -239.284015) (xy 146.502846 -239.245306) (xy 146.46876 -239.201163) (xy 146.441464 -239.152528)
			(xy 146.421541 -239.100437) (xy 146.409415 -239.046) (xy 146.405344 -238.990378) (xy 145.935516 -238.990378)
			(xy 145.941509 -239.010786) (xy 145.949267 -239.064744) (xy 145.949267 -239.119256) (xy 145.941509 -239.173214)
			(xy 145.92615 -239.225518) (xy 145.903503 -239.275103) (xy 145.87403 -239.320961) (xy 145.83833 -239.362157)
			(xy 145.79713 -239.397853) (xy 145.75127 -239.427321) (xy 145.701682 -239.449963) (xy 145.649376 -239.465317)
			(xy 145.595418 -239.47307) (xy 145.568162 -239.473486) (xy 145.544269 -239.473096) (xy 145.496861 -239.467099)
			(xy 145.45057 -239.455239) (xy 145.428208 -239.446816) (xy 145.41627 -239.442244) (xy 145.391378 -239.445038)
			(xy 145.311368 -239.499394) (xy 145.301478 -239.506923) (xy 145.289906 -239.52889) (xy 145.28927 -239.541304)
			(xy 145.28927 -242.038378) (xy 149.377144 -242.038378) (xy 149.381215 -241.982756) (xy 149.393341 -241.928319)
			(xy 149.413264 -241.876228) (xy 149.44056 -241.827593) (xy 149.474646 -241.78345) (xy 149.514795 -241.744741)
			(xy 149.560153 -241.71229) (xy 149.609753 -241.686789) (xy 149.662537 -241.668782) (xy 149.71738 -241.658652)
			(xy 149.773114 -241.656615) (xy 149.828551 -241.662715) (xy 149.882508 -241.676821) (xy 149.933837 -241.698633)
			(xy 149.981443 -241.727687) (xy 150.024311 -241.763362) (xy 150.061528 -241.804899) (xy 150.092301 -241.851412)
			(xy 150.115973 -241.901909) (xy 150.132041 -241.955316) (xy 150.140161 -242.010492) (xy 150.14067 -242.038378)
			(xy 150.140161 -242.066264) (xy 150.132041 -242.12144) (xy 150.115973 -242.174847) (xy 150.092301 -242.225344)
			(xy 150.061528 -242.271857) (xy 150.024311 -242.313394) (xy 149.981443 -242.349069) (xy 149.933837 -242.378123)
			(xy 149.882508 -242.399935) (xy 149.828551 -242.414041) (xy 149.773114 -242.420141) (xy 149.71738 -242.418104)
			(xy 149.662537 -242.407974) (xy 149.609753 -242.389967) (xy 149.560153 -242.364466) (xy 149.514795 -242.332015)
			(xy 149.474646 -242.293306) (xy 149.44056 -242.249163) (xy 149.413264 -242.200528) (xy 149.393341 -242.148437)
			(xy 149.381215 -242.094) (xy 149.377144 -242.038378) (xy 145.28927 -242.038378) (xy 145.28927 -242.444778)
			(xy 146.252944 -242.444778) (xy 146.257015 -242.389156) (xy 146.269141 -242.334719) (xy 146.289064 -242.282628)
			(xy 146.31636 -242.233993) (xy 146.350446 -242.18985) (xy 146.390595 -242.151141) (xy 146.435953 -242.11869)
			(xy 146.485553 -242.093189) (xy 146.538337 -242.075182) (xy 146.59318 -242.065052) (xy 146.648914 -242.063015)
			(xy 146.704351 -242.069115) (xy 146.758308 -242.083221) (xy 146.809637 -242.105033) (xy 146.857243 -242.134087)
			(xy 146.900111 -242.169762) (xy 146.937328 -242.211299) (xy 146.968101 -242.257812) (xy 146.991773 -242.308309)
			(xy 147.007841 -242.361716) (xy 147.015961 -242.416892) (xy 147.01647 -242.444778) (xy 147.421344 -242.444778)
			(xy 147.425415 -242.389156) (xy 147.437541 -242.334719) (xy 147.457464 -242.282628) (xy 147.48476 -242.233993)
			(xy 147.518846 -242.18985) (xy 147.558995 -242.151141) (xy 147.604353 -242.11869) (xy 147.653953 -242.093189)
			(xy 147.706737 -242.075182) (xy 147.76158 -242.065052) (xy 147.817314 -242.063015) (xy 147.872751 -242.069115)
			(xy 147.926708 -242.083221) (xy 147.978037 -242.105033) (xy 148.025643 -242.134087) (xy 148.068511 -242.169762)
			(xy 148.105728 -242.211299) (xy 148.136501 -242.257812) (xy 148.160173 -242.308309) (xy 148.176241 -242.361716)
			(xy 148.184361 -242.416892) (xy 148.18487 -242.444778) (xy 148.184361 -242.472664) (xy 148.176241 -242.52784)
			(xy 148.160173 -242.581247) (xy 148.136501 -242.631744) (xy 148.105728 -242.678257) (xy 148.068511 -242.719794)
			(xy 148.025643 -242.755469) (xy 147.978037 -242.784523) (xy 147.926708 -242.806335) (xy 147.872751 -242.820441)
			(xy 147.817314 -242.826541) (xy 147.76158 -242.824504) (xy 147.706737 -242.814374) (xy 147.653953 -242.796367)
			(xy 147.604353 -242.770866) (xy 147.558995 -242.738415) (xy 147.518846 -242.699706) (xy 147.48476 -242.655563)
			(xy 147.457464 -242.606928) (xy 147.437541 -242.554837) (xy 147.425415 -242.5004) (xy 147.421344 -242.444778)
			(xy 147.01647 -242.444778) (xy 147.015961 -242.472664) (xy 147.007841 -242.52784) (xy 146.991773 -242.581247)
			(xy 146.968101 -242.631744) (xy 146.937328 -242.678257) (xy 146.900111 -242.719794) (xy 146.857243 -242.755469)
			(xy 146.809637 -242.784523) (xy 146.758308 -242.806335) (xy 146.704351 -242.820441) (xy 146.648914 -242.826541)
			(xy 146.59318 -242.824504) (xy 146.538337 -242.814374) (xy 146.485553 -242.796367) (xy 146.435953 -242.770866)
			(xy 146.390595 -242.738415) (xy 146.350446 -242.699706) (xy 146.31636 -242.655563) (xy 146.289064 -242.606928)
			(xy 146.269141 -242.554837) (xy 146.257015 -242.5004) (xy 146.252944 -242.444778) (xy 145.28927 -242.444778)
			(xy 145.28927 -242.993418) (xy 145.292318 -243.0018) (xy 145.30277 -243.032963) (xy 145.309666 -243.072666)
			(xy 149.923498 -243.072666) (xy 149.927569 -243.017044) (xy 149.939695 -242.962607) (xy 149.959618 -242.910516)
			(xy 149.986914 -242.861881) (xy 150.021 -242.817738) (xy 150.061149 -242.779029) (xy 150.106507 -242.746578)
			(xy 150.156107 -242.721077) (xy 150.208891 -242.70307) (xy 150.263734 -242.69294) (xy 150.319468 -242.690903)
			(xy 150.374905 -242.697003) (xy 150.428862 -242.711109) (xy 150.480191 -242.732921) (xy 150.527797 -242.761975)
			(xy 150.570665 -242.79765) (xy 150.607882 -242.839187) (xy 150.638655 -242.8857) (xy 150.662327 -242.936197)
			(xy 150.678395 -242.989604) (xy 150.686515 -243.04478) (xy 150.687024 -243.072666) (xy 150.686515 -243.100552)
			(xy 150.678395 -243.155728) (xy 150.662327 -243.209135) (xy 150.638655 -243.259632) (xy 150.607882 -243.306145)
			(xy 150.570665 -243.347682) (xy 150.527797 -243.383357) (xy 150.480191 -243.412411) (xy 150.428862 -243.434223)
			(xy 150.374905 -243.448329) (xy 150.319468 -243.454429) (xy 150.263734 -243.452392) (xy 150.208891 -243.442262)
			(xy 150.156107 -243.424255) (xy 150.106507 -243.398754) (xy 150.061149 -243.366303) (xy 150.021 -243.327594)
			(xy 149.986914 -243.283451) (xy 149.959618 -243.234816) (xy 149.939695 -243.182725) (xy 149.927569 -243.128288)
			(xy 149.923498 -243.072666) (xy 145.309666 -243.072666) (xy 145.314017 -243.097716) (xy 145.31467 -243.130578)
			(xy 145.314208 -243.157831) (xy 145.306454 -243.211782) (xy 145.291099 -243.26408) (xy 145.268457 -243.313661)
			(xy 145.238989 -243.359514) (xy 145.203295 -243.400706) (xy 145.162101 -243.436399) (xy 145.116247 -243.465865)
			(xy 145.066665 -243.488505) (xy 145.014367 -243.503857) (xy 144.960415 -243.511609) (xy 144.933162 -243.512086)
			(xy 144.919268 -243.51195) (xy 144.891555 -243.509918) (xy 144.87779 -243.508022) (xy 144.865852 -243.506244)
			(xy 144.842992 -243.513864) (xy 144.057878 -244.298978) (xy 148.488144 -244.298978) (xy 148.492215 -244.243356)
			(xy 148.504341 -244.188919) (xy 148.524264 -244.136828) (xy 148.55156 -244.088193) (xy 148.585646 -244.04405)
			(xy 148.625795 -244.005341) (xy 148.671153 -243.97289) (xy 148.720753 -243.947389) (xy 148.773537 -243.929382)
			(xy 148.82838 -243.919252) (xy 148.884114 -243.917215) (xy 148.939551 -243.923315) (xy 148.993508 -243.937421)
			(xy 149.044837 -243.959233) (xy 149.092443 -243.988287) (xy 149.135311 -244.023962) (xy 149.172528 -244.065499)
			(xy 149.203301 -244.112012) (xy 149.226973 -244.162509) (xy 149.243041 -244.215916) (xy 149.251161 -244.271092)
			(xy 149.25167 -244.298978) (xy 149.251161 -244.326864) (xy 149.243041 -244.38204) (xy 149.226973 -244.435447)
			(xy 149.203301 -244.485944) (xy 149.172528 -244.532457) (xy 149.135311 -244.573994) (xy 149.092443 -244.609669)
			(xy 149.044837 -244.638723) (xy 148.993508 -244.660535) (xy 148.939551 -244.674641) (xy 148.884114 -244.680741)
			(xy 148.82838 -244.678704) (xy 148.773537 -244.668574) (xy 148.720753 -244.650567) (xy 148.671153 -244.625066)
			(xy 148.625795 -244.592615) (xy 148.585646 -244.553906) (xy 148.55156 -244.509763) (xy 148.524264 -244.461128)
			(xy 148.504341 -244.409037) (xy 148.492215 -244.3546) (xy 148.488144 -244.298978) (xy 144.057878 -244.298978)
			(xy 143.138604 -245.218252) (xy 145.388281 -245.218252) (xy 145.388281 -245.163748) (xy 145.396039 -245.109798)
			(xy 145.411395 -245.057501) (xy 145.434038 -245.007922) (xy 145.463507 -244.962071) (xy 145.499201 -244.92088)
			(xy 145.540395 -244.885189) (xy 145.586249 -244.855724) (xy 145.635829 -244.833085) (xy 145.688127 -244.817732)
			(xy 145.742078 -244.809979) (xy 145.76933 -244.809518) (xy 145.798608 -244.810047) (xy 145.856478 -244.818979)
			(xy 145.912301 -244.836657) (xy 145.964763 -244.862667) (xy 146.012628 -244.896395) (xy 146.054771 -244.937049)
			(xy 146.090199 -244.983671) (xy 146.10461 -245.009162) (xy 146.112291 -245.022351) (xy 146.134062 -245.043725)
			(xy 146.161171 -245.057724) (xy 146.191203 -245.0631) (xy 146.221485 -245.059374) (xy 146.249318 -245.046879)
			(xy 146.272226 -245.026728) (xy 146.280632 -245.013988) (xy 146.296318 -244.989429) (xy 146.333706 -244.944732)
			(xy 146.377188 -244.905938) (xy 146.425842 -244.873869) (xy 146.478637 -244.849204) (xy 146.534454 -244.832467)
			(xy 146.59211 -244.824012) (xy 146.621246 -244.823488) (xy 146.649785 -244.82394) (xy 146.706283 -244.832069)
			(xy 146.761048 -244.848155) (xy 146.812967 -244.871871) (xy 146.860982 -244.902734) (xy 146.904117 -244.940115)
			(xy 146.941494 -244.983255) (xy 146.972351 -245.031274) (xy 146.996061 -245.083195) (xy 147.012141 -245.137962)
			(xy 147.020263 -245.194461) (xy 147.020263 -245.251539) (xy 147.012141 -245.308038) (xy 146.996061 -245.362805)
			(xy 146.972351 -245.414726) (xy 146.941494 -245.462745) (xy 146.904117 -245.505885) (xy 146.860982 -245.543266)
			(xy 146.812967 -245.574129) (xy 146.761048 -245.597845) (xy 146.706283 -245.613931) (xy 146.649785 -245.62206)
			(xy 146.621246 -245.622572) (xy 146.593878 -245.622091) (xy 146.539653 -245.614618) (xy 146.486955 -245.599817)
			(xy 146.436769 -245.577966) (xy 146.390032 -245.549473) (xy 146.347619 -245.514871) (xy 146.310322 -245.474808)
			(xy 146.278839 -245.430031) (xy 146.2659 -245.40591) (xy 146.258422 -245.39264) (xy 146.237097 -245.370913)
			(xy 146.21032 -245.356427) (xy 146.180465 -245.350467) (xy 146.150179 -245.353562) (xy 146.122146 -245.365437)
			(xy 146.098852 -245.385039) (xy 146.090132 -245.397528) (xy 146.074965 -245.420149) (xy 146.039275 -245.461285)
			(xy 145.998097 -245.496928) (xy 145.95227 -245.526354) (xy 145.902725 -245.548964) (xy 145.850467 -245.564299)
			(xy 145.79656 -245.572048) (xy 145.76933 -245.572534) (xy 145.742078 -245.572021) (xy 145.688127 -245.564268)
			(xy 145.635829 -245.548915) (xy 145.586249 -245.526276) (xy 145.540395 -245.496811) (xy 145.499201 -245.46112)
			(xy 145.463507 -245.419929) (xy 145.434038 -245.374078) (xy 145.411395 -245.324499) (xy 145.396039 -245.272202)
			(xy 145.388281 -245.218252) (xy 143.138604 -245.218252) (xy 139.304014 -249.052842) (xy 141.076424 -249.052842)
			(xy 141.080495 -248.99722) (xy 141.092621 -248.942783) (xy 141.112544 -248.890692) (xy 141.13984 -248.842057)
			(xy 141.173926 -248.797914) (xy 141.214075 -248.759205) (xy 141.259433 -248.726754) (xy 141.309033 -248.701253)
			(xy 141.361817 -248.683246) (xy 141.41666 -248.673116) (xy 141.472394 -248.671079) (xy 141.527831 -248.677179)
			(xy 141.581788 -248.691285) (xy 141.633117 -248.713097) (xy 141.680723 -248.742151) (xy 141.723591 -248.777826)
			(xy 141.760808 -248.819363) (xy 141.791581 -248.865876) (xy 141.815253 -248.916373) (xy 141.831321 -248.96978)
			(xy 141.839441 -249.024956) (xy 141.839579 -249.032522) (xy 142.092424 -249.032522) (xy 142.096495 -248.9769)
			(xy 142.108621 -248.922463) (xy 142.128544 -248.870372) (xy 142.15584 -248.821737) (xy 142.189926 -248.777594)
			(xy 142.230075 -248.738885) (xy 142.275433 -248.706434) (xy 142.325033 -248.680933) (xy 142.377817 -248.662926)
			(xy 142.43266 -248.652796) (xy 142.488394 -248.650759) (xy 142.543831 -248.656859) (xy 142.597788 -248.670965)
			(xy 142.649117 -248.692777) (xy 142.696723 -248.721831) (xy 142.739591 -248.757506) (xy 142.776808 -248.799043)
			(xy 142.807581 -248.845556) (xy 142.831253 -248.896053) (xy 142.847321 -248.94946) (xy 142.855441 -249.004636)
			(xy 142.85595 -249.032522) (xy 142.855441 -249.060408) (xy 142.847321 -249.115584) (xy 142.831253 -249.168991)
			(xy 142.807581 -249.219488) (xy 142.776808 -249.266001) (xy 142.739591 -249.307538) (xy 142.696723 -249.343213)
			(xy 142.649117 -249.372267) (xy 142.597788 -249.394079) (xy 142.543831 -249.408185) (xy 142.488394 -249.414285)
			(xy 142.43266 -249.412248) (xy 142.377817 -249.402118) (xy 142.325033 -249.384111) (xy 142.275433 -249.35861)
			(xy 142.230075 -249.326159) (xy 142.189926 -249.28745) (xy 142.15584 -249.243307) (xy 142.128544 -249.194672)
			(xy 142.108621 -249.142581) (xy 142.096495 -249.088144) (xy 142.092424 -249.032522) (xy 141.839579 -249.032522)
			(xy 141.83995 -249.052842) (xy 141.839441 -249.080728) (xy 141.831321 -249.135904) (xy 141.815253 -249.189311)
			(xy 141.791581 -249.239808) (xy 141.760808 -249.286321) (xy 141.723591 -249.327858) (xy 141.680723 -249.363533)
			(xy 141.633117 -249.392587) (xy 141.581788 -249.414399) (xy 141.527831 -249.428505) (xy 141.472394 -249.434605)
			(xy 141.41666 -249.432568) (xy 141.361817 -249.422438) (xy 141.309033 -249.404431) (xy 141.259433 -249.37893)
			(xy 141.214075 -249.346479) (xy 141.173926 -249.30777) (xy 141.13984 -249.263627) (xy 141.112544 -249.214992)
			(xy 141.092621 -249.162901) (xy 141.080495 -249.108464) (xy 141.076424 -249.052842) (xy 139.304014 -249.052842)
			(xy 137.198354 -251.158502) (xy 140.060424 -251.158502) (xy 140.064495 -251.10288) (xy 140.076621 -251.048443)
			(xy 140.096544 -250.996352) (xy 140.12384 -250.947717) (xy 140.157926 -250.903574) (xy 140.198075 -250.864865)
			(xy 140.243433 -250.832414) (xy 140.293033 -250.806913) (xy 140.345817 -250.788906) (xy 140.40066 -250.778776)
			(xy 140.456394 -250.776739) (xy 140.511831 -250.782839) (xy 140.565788 -250.796945) (xy 140.617117 -250.818757)
			(xy 140.664723 -250.847811) (xy 140.707591 -250.883486) (xy 140.744808 -250.925023) (xy 140.775581 -250.971536)
			(xy 140.799253 -251.022033) (xy 140.815321 -251.07544) (xy 140.823441 -251.130616) (xy 140.82395 -251.158502)
			(xy 141.076424 -251.158502) (xy 141.080495 -251.10288) (xy 141.092621 -251.048443) (xy 141.112544 -250.996352)
			(xy 141.13984 -250.947717) (xy 141.173926 -250.903574) (xy 141.214075 -250.864865) (xy 141.259433 -250.832414)
			(xy 141.309033 -250.806913) (xy 141.361817 -250.788906) (xy 141.41666 -250.778776) (xy 141.472394 -250.776739)
			(xy 141.527831 -250.782839) (xy 141.581788 -250.796945) (xy 141.633117 -250.818757) (xy 141.680723 -250.847811)
			(xy 141.723591 -250.883486) (xy 141.760808 -250.925023) (xy 141.791581 -250.971536) (xy 141.815253 -251.022033)
			(xy 141.831321 -251.07544) (xy 141.839441 -251.130616) (xy 141.83995 -251.158502) (xy 142.092424 -251.158502)
			(xy 142.096495 -251.10288) (xy 142.108621 -251.048443) (xy 142.128544 -250.996352) (xy 142.15584 -250.947717)
			(xy 142.189926 -250.903574) (xy 142.230075 -250.864865) (xy 142.275433 -250.832414) (xy 142.325033 -250.806913)
			(xy 142.377817 -250.788906) (xy 142.43266 -250.778776) (xy 142.488394 -250.776739) (xy 142.543831 -250.782839)
			(xy 142.597788 -250.796945) (xy 142.649117 -250.818757) (xy 142.696723 -250.847811) (xy 142.739591 -250.883486)
			(xy 142.776808 -250.925023) (xy 142.807581 -250.971536) (xy 142.831253 -251.022033) (xy 142.847321 -251.07544)
			(xy 142.855441 -251.130616) (xy 142.85595 -251.158502) (xy 143.108424 -251.158502) (xy 143.112495 -251.10288)
			(xy 143.124621 -251.048443) (xy 143.144544 -250.996352) (xy 143.17184 -250.947717) (xy 143.205926 -250.903574)
			(xy 143.246075 -250.864865) (xy 143.291433 -250.832414) (xy 143.341033 -250.806913) (xy 143.393817 -250.788906)
			(xy 143.44866 -250.778776) (xy 143.504394 -250.776739) (xy 143.559831 -250.782839) (xy 143.613788 -250.796945)
			(xy 143.665117 -250.818757) (xy 143.712723 -250.847811) (xy 143.755591 -250.883486) (xy 143.792808 -250.925023)
			(xy 143.823581 -250.971536) (xy 143.847253 -251.022033) (xy 143.863321 -251.07544) (xy 143.871441 -251.130616)
			(xy 143.87195 -251.158502) (xy 144.124424 -251.158502) (xy 144.128495 -251.10288) (xy 144.140621 -251.048443)
			(xy 144.160544 -250.996352) (xy 144.18784 -250.947717) (xy 144.221926 -250.903574) (xy 144.262075 -250.864865)
			(xy 144.307433 -250.832414) (xy 144.357033 -250.806913) (xy 144.409817 -250.788906) (xy 144.46466 -250.778776)
			(xy 144.520394 -250.776739) (xy 144.575831 -250.782839) (xy 144.629788 -250.796945) (xy 144.681117 -250.818757)
			(xy 144.728723 -250.847811) (xy 144.771591 -250.883486) (xy 144.808808 -250.925023) (xy 144.839581 -250.971536)
			(xy 144.863253 -251.022033) (xy 144.879321 -251.07544) (xy 144.887441 -251.130616) (xy 144.88795 -251.158502)
			(xy 145.140424 -251.158502) (xy 145.144495 -251.10288) (xy 145.156621 -251.048443) (xy 145.176544 -250.996352)
			(xy 145.20384 -250.947717) (xy 145.237926 -250.903574) (xy 145.278075 -250.864865) (xy 145.323433 -250.832414)
			(xy 145.373033 -250.806913) (xy 145.425817 -250.788906) (xy 145.48066 -250.778776) (xy 145.536394 -250.776739)
			(xy 145.591831 -250.782839) (xy 145.645788 -250.796945) (xy 145.697117 -250.818757) (xy 145.744723 -250.847811)
			(xy 145.787591 -250.883486) (xy 145.824808 -250.925023) (xy 145.855581 -250.971536) (xy 145.879253 -251.022033)
			(xy 145.895321 -251.07544) (xy 145.903441 -251.130616) (xy 145.90395 -251.158502) (xy 146.156424 -251.158502)
			(xy 146.160495 -251.10288) (xy 146.172621 -251.048443) (xy 146.192544 -250.996352) (xy 146.21984 -250.947717)
			(xy 146.253926 -250.903574) (xy 146.294075 -250.864865) (xy 146.339433 -250.832414) (xy 146.389033 -250.806913)
			(xy 146.441817 -250.788906) (xy 146.49666 -250.778776) (xy 146.552394 -250.776739) (xy 146.607831 -250.782839)
			(xy 146.661788 -250.796945) (xy 146.713117 -250.818757) (xy 146.760723 -250.847811) (xy 146.803591 -250.883486)
			(xy 146.840808 -250.925023) (xy 146.871581 -250.971536) (xy 146.895253 -251.022033) (xy 146.911321 -251.07544)
			(xy 146.919441 -251.130616) (xy 146.91995 -251.158502) (xy 147.172424 -251.158502) (xy 147.176495 -251.10288)
			(xy 147.188621 -251.048443) (xy 147.208544 -250.996352) (xy 147.23584 -250.947717) (xy 147.269926 -250.903574)
			(xy 147.310075 -250.864865) (xy 147.355433 -250.832414) (xy 147.405033 -250.806913) (xy 147.457817 -250.788906)
			(xy 147.51266 -250.778776) (xy 147.568394 -250.776739) (xy 147.623831 -250.782839) (xy 147.677788 -250.796945)
			(xy 147.729117 -250.818757) (xy 147.776723 -250.847811) (xy 147.819591 -250.883486) (xy 147.856808 -250.925023)
			(xy 147.887581 -250.971536) (xy 147.911253 -251.022033) (xy 147.927321 -251.07544) (xy 147.935441 -251.130616)
			(xy 147.93595 -251.158502) (xy 148.188424 -251.158502) (xy 148.192495 -251.10288) (xy 148.204621 -251.048443)
			(xy 148.224544 -250.996352) (xy 148.25184 -250.947717) (xy 148.285926 -250.903574) (xy 148.326075 -250.864865)
			(xy 148.371433 -250.832414) (xy 148.421033 -250.806913) (xy 148.473817 -250.788906) (xy 148.52866 -250.778776)
			(xy 148.584394 -250.776739) (xy 148.639831 -250.782839) (xy 148.693788 -250.796945) (xy 148.745117 -250.818757)
			(xy 148.792723 -250.847811) (xy 148.835591 -250.883486) (xy 148.872808 -250.925023) (xy 148.903581 -250.971536)
			(xy 148.927253 -251.022033) (xy 148.943321 -251.07544) (xy 148.951441 -251.130616) (xy 148.95195 -251.158502)
			(xy 149.204424 -251.158502) (xy 149.208495 -251.10288) (xy 149.220621 -251.048443) (xy 149.240544 -250.996352)
			(xy 149.26784 -250.947717) (xy 149.301926 -250.903574) (xy 149.342075 -250.864865) (xy 149.387433 -250.832414)
			(xy 149.437033 -250.806913) (xy 149.489817 -250.788906) (xy 149.54466 -250.778776) (xy 149.600394 -250.776739)
			(xy 149.655831 -250.782839) (xy 149.709788 -250.796945) (xy 149.761117 -250.818757) (xy 149.808723 -250.847811)
			(xy 149.851591 -250.883486) (xy 149.888808 -250.925023) (xy 149.919581 -250.971536) (xy 149.943253 -251.022033)
			(xy 149.959321 -251.07544) (xy 149.967441 -251.130616) (xy 149.96795 -251.158502) (xy 149.967441 -251.186388)
			(xy 149.959321 -251.241564) (xy 149.943253 -251.294971) (xy 149.919581 -251.345468) (xy 149.888808 -251.391981)
			(xy 149.851591 -251.433518) (xy 149.808723 -251.469193) (xy 149.761117 -251.498247) (xy 149.709788 -251.520059)
			(xy 149.655831 -251.534165) (xy 149.600394 -251.540265) (xy 149.54466 -251.538228) (xy 149.489817 -251.528098)
			(xy 149.437033 -251.510091) (xy 149.387433 -251.48459) (xy 149.342075 -251.452139) (xy 149.301926 -251.41343)
			(xy 149.26784 -251.369287) (xy 149.240544 -251.320652) (xy 149.220621 -251.268561) (xy 149.208495 -251.214124)
			(xy 149.204424 -251.158502) (xy 148.95195 -251.158502) (xy 148.951441 -251.186388) (xy 148.943321 -251.241564)
			(xy 148.927253 -251.294971) (xy 148.903581 -251.345468) (xy 148.872808 -251.391981) (xy 148.835591 -251.433518)
			(xy 148.792723 -251.469193) (xy 148.745117 -251.498247) (xy 148.693788 -251.520059) (xy 148.639831 -251.534165)
			(xy 148.584394 -251.540265) (xy 148.52866 -251.538228) (xy 148.473817 -251.528098) (xy 148.421033 -251.510091)
			(xy 148.371433 -251.48459) (xy 148.326075 -251.452139) (xy 148.285926 -251.41343) (xy 148.25184 -251.369287)
			(xy 148.224544 -251.320652) (xy 148.204621 -251.268561) (xy 148.192495 -251.214124) (xy 148.188424 -251.158502)
			(xy 147.93595 -251.158502) (xy 147.935441 -251.186388) (xy 147.927321 -251.241564) (xy 147.911253 -251.294971)
			(xy 147.887581 -251.345468) (xy 147.856808 -251.391981) (xy 147.819591 -251.433518) (xy 147.776723 -251.469193)
			(xy 147.729117 -251.498247) (xy 147.677788 -251.520059) (xy 147.623831 -251.534165) (xy 147.568394 -251.540265)
			(xy 147.51266 -251.538228) (xy 147.457817 -251.528098) (xy 147.405033 -251.510091) (xy 147.355433 -251.48459)
			(xy 147.310075 -251.452139) (xy 147.269926 -251.41343) (xy 147.23584 -251.369287) (xy 147.208544 -251.320652)
			(xy 147.188621 -251.268561) (xy 147.176495 -251.214124) (xy 147.172424 -251.158502) (xy 146.91995 -251.158502)
			(xy 146.919441 -251.186388) (xy 146.911321 -251.241564) (xy 146.895253 -251.294971) (xy 146.871581 -251.345468)
			(xy 146.840808 -251.391981) (xy 146.803591 -251.433518) (xy 146.760723 -251.469193) (xy 146.713117 -251.498247)
			(xy 146.661788 -251.520059) (xy 146.607831 -251.534165) (xy 146.552394 -251.540265) (xy 146.49666 -251.538228)
			(xy 146.441817 -251.528098) (xy 146.389033 -251.510091) (xy 146.339433 -251.48459) (xy 146.294075 -251.452139)
			(xy 146.253926 -251.41343) (xy 146.21984 -251.369287) (xy 146.192544 -251.320652) (xy 146.172621 -251.268561)
			(xy 146.160495 -251.214124) (xy 146.156424 -251.158502) (xy 145.90395 -251.158502) (xy 145.903441 -251.186388)
			(xy 145.895321 -251.241564) (xy 145.879253 -251.294971) (xy 145.855581 -251.345468) (xy 145.824808 -251.391981)
			(xy 145.787591 -251.433518) (xy 145.744723 -251.469193) (xy 145.697117 -251.498247) (xy 145.645788 -251.520059)
			(xy 145.591831 -251.534165) (xy 145.536394 -251.540265) (xy 145.48066 -251.538228) (xy 145.425817 -251.528098)
			(xy 145.373033 -251.510091) (xy 145.323433 -251.48459) (xy 145.278075 -251.452139) (xy 145.237926 -251.41343)
			(xy 145.20384 -251.369287) (xy 145.176544 -251.320652) (xy 145.156621 -251.268561) (xy 145.144495 -251.214124)
			(xy 145.140424 -251.158502) (xy 144.88795 -251.158502) (xy 144.887441 -251.186388) (xy 144.879321 -251.241564)
			(xy 144.863253 -251.294971) (xy 144.839581 -251.345468) (xy 144.808808 -251.391981) (xy 144.771591 -251.433518)
			(xy 144.728723 -251.469193) (xy 144.681117 -251.498247) (xy 144.629788 -251.520059) (xy 144.575831 -251.534165)
			(xy 144.520394 -251.540265) (xy 144.46466 -251.538228) (xy 144.409817 -251.528098) (xy 144.357033 -251.510091)
			(xy 144.307433 -251.48459) (xy 144.262075 -251.452139) (xy 144.221926 -251.41343) (xy 144.18784 -251.369287)
			(xy 144.160544 -251.320652) (xy 144.140621 -251.268561) (xy 144.128495 -251.214124) (xy 144.124424 -251.158502)
			(xy 143.87195 -251.158502) (xy 143.871441 -251.186388) (xy 143.863321 -251.241564) (xy 143.847253 -251.294971)
			(xy 143.823581 -251.345468) (xy 143.792808 -251.391981) (xy 143.755591 -251.433518) (xy 143.712723 -251.469193)
			(xy 143.665117 -251.498247) (xy 143.613788 -251.520059) (xy 143.559831 -251.534165) (xy 143.504394 -251.540265)
			(xy 143.44866 -251.538228) (xy 143.393817 -251.528098) (xy 143.341033 -251.510091) (xy 143.291433 -251.48459)
			(xy 143.246075 -251.452139) (xy 143.205926 -251.41343) (xy 143.17184 -251.369287) (xy 143.144544 -251.320652)
			(xy 143.124621 -251.268561) (xy 143.112495 -251.214124) (xy 143.108424 -251.158502) (xy 142.85595 -251.158502)
			(xy 142.855441 -251.186388) (xy 142.847321 -251.241564) (xy 142.831253 -251.294971) (xy 142.807581 -251.345468)
			(xy 142.776808 -251.391981) (xy 142.739591 -251.433518) (xy 142.696723 -251.469193) (xy 142.649117 -251.498247)
			(xy 142.597788 -251.520059) (xy 142.543831 -251.534165) (xy 142.488394 -251.540265) (xy 142.43266 -251.538228)
			(xy 142.377817 -251.528098) (xy 142.325033 -251.510091) (xy 142.275433 -251.48459) (xy 142.230075 -251.452139)
			(xy 142.189926 -251.41343) (xy 142.15584 -251.369287) (xy 142.128544 -251.320652) (xy 142.108621 -251.268561)
			(xy 142.096495 -251.214124) (xy 142.092424 -251.158502) (xy 141.83995 -251.158502) (xy 141.839441 -251.186388)
			(xy 141.831321 -251.241564) (xy 141.815253 -251.294971) (xy 141.791581 -251.345468) (xy 141.760808 -251.391981)
			(xy 141.723591 -251.433518) (xy 141.680723 -251.469193) (xy 141.633117 -251.498247) (xy 141.581788 -251.520059)
			(xy 141.527831 -251.534165) (xy 141.472394 -251.540265) (xy 141.41666 -251.538228) (xy 141.361817 -251.528098)
			(xy 141.309033 -251.510091) (xy 141.259433 -251.48459) (xy 141.214075 -251.452139) (xy 141.173926 -251.41343)
			(xy 141.13984 -251.369287) (xy 141.112544 -251.320652) (xy 141.092621 -251.268561) (xy 141.080495 -251.214124)
			(xy 141.076424 -251.158502) (xy 140.82395 -251.158502) (xy 140.823441 -251.186388) (xy 140.815321 -251.241564)
			(xy 140.799253 -251.294971) (xy 140.775581 -251.345468) (xy 140.744808 -251.391981) (xy 140.707591 -251.433518)
			(xy 140.664723 -251.469193) (xy 140.617117 -251.498247) (xy 140.565788 -251.520059) (xy 140.511831 -251.534165)
			(xy 140.456394 -251.540265) (xy 140.40066 -251.538228) (xy 140.345817 -251.528098) (xy 140.293033 -251.510091)
			(xy 140.243433 -251.48459) (xy 140.198075 -251.452139) (xy 140.157926 -251.41343) (xy 140.12384 -251.369287)
			(xy 140.096544 -251.320652) (xy 140.076621 -251.268561) (xy 140.064495 -251.214124) (xy 140.060424 -251.158502)
			(xy 137.198354 -251.158502) (xy 137.070084 -251.286772) (xy 137.06324 -251.29417) (xy 137.055518 -251.31277)
			(xy 137.055098 -251.32284) (xy 137.055098 -253.620778) (xy 137.487404 -253.620778) (xy 137.491475 -253.565156)
			(xy 137.503601 -253.510719) (xy 137.523524 -253.458628) (xy 137.55082 -253.409993) (xy 137.584906 -253.36585)
			(xy 137.625055 -253.327141) (xy 137.670413 -253.29469) (xy 137.720013 -253.269189) (xy 137.772797 -253.251182)
			(xy 137.82764 -253.241052) (xy 137.883374 -253.239015) (xy 137.938811 -253.245115) (xy 137.992768 -253.259221)
			(xy 138.044097 -253.281033) (xy 138.091703 -253.310087) (xy 138.134571 -253.345762) (xy 138.171788 -253.387299)
			(xy 138.202561 -253.433812) (xy 138.213169 -253.45644) (xy 140.060424 -253.45644) (xy 140.064495 -253.400818)
			(xy 140.076621 -253.346381) (xy 140.096544 -253.29429) (xy 140.12384 -253.245655) (xy 140.157926 -253.201512)
			(xy 140.198075 -253.162803) (xy 140.243433 -253.130352) (xy 140.293033 -253.104851) (xy 140.345817 -253.086844)
			(xy 140.40066 -253.076714) (xy 140.456394 -253.074677) (xy 140.511831 -253.080777) (xy 140.565788 -253.094883)
			(xy 140.617117 -253.116695) (xy 140.664723 -253.145749) (xy 140.707591 -253.181424) (xy 140.744808 -253.222961)
			(xy 140.775581 -253.269474) (xy 140.799253 -253.319971) (xy 140.815321 -253.373378) (xy 140.823441 -253.428554)
			(xy 140.82395 -253.45644) (xy 141.076424 -253.45644) (xy 141.080495 -253.400818) (xy 141.092621 -253.346381)
			(xy 141.112544 -253.29429) (xy 141.13984 -253.245655) (xy 141.173926 -253.201512) (xy 141.214075 -253.162803)
			(xy 141.259433 -253.130352) (xy 141.309033 -253.104851) (xy 141.361817 -253.086844) (xy 141.41666 -253.076714)
			(xy 141.472394 -253.074677) (xy 141.527831 -253.080777) (xy 141.581788 -253.094883) (xy 141.633117 -253.116695)
			(xy 141.680723 -253.145749) (xy 141.723591 -253.181424) (xy 141.760808 -253.222961) (xy 141.791581 -253.269474)
			(xy 141.815253 -253.319971) (xy 141.831321 -253.373378) (xy 141.839441 -253.428554) (xy 141.83995 -253.45644)
			(xy 142.092424 -253.45644) (xy 142.096495 -253.400818) (xy 142.108621 -253.346381) (xy 142.128544 -253.29429)
			(xy 142.15584 -253.245655) (xy 142.189926 -253.201512) (xy 142.230075 -253.162803) (xy 142.275433 -253.130352)
			(xy 142.325033 -253.104851) (xy 142.377817 -253.086844) (xy 142.43266 -253.076714) (xy 142.488394 -253.074677)
			(xy 142.543831 -253.080777) (xy 142.597788 -253.094883) (xy 142.649117 -253.116695) (xy 142.696723 -253.145749)
			(xy 142.739591 -253.181424) (xy 142.776808 -253.222961) (xy 142.807581 -253.269474) (xy 142.831253 -253.319971)
			(xy 142.847321 -253.373378) (xy 142.855441 -253.428554) (xy 142.85595 -253.45644) (xy 143.108424 -253.45644)
			(xy 143.112495 -253.400818) (xy 143.124621 -253.346381) (xy 143.144544 -253.29429) (xy 143.17184 -253.245655)
			(xy 143.205926 -253.201512) (xy 143.246075 -253.162803) (xy 143.291433 -253.130352) (xy 143.341033 -253.104851)
			(xy 143.393817 -253.086844) (xy 143.44866 -253.076714) (xy 143.504394 -253.074677) (xy 143.559831 -253.080777)
			(xy 143.613788 -253.094883) (xy 143.665117 -253.116695) (xy 143.712723 -253.145749) (xy 143.755591 -253.181424)
			(xy 143.792808 -253.222961) (xy 143.823581 -253.269474) (xy 143.847253 -253.319971) (xy 143.863321 -253.373378)
			(xy 143.871441 -253.428554) (xy 143.87195 -253.45644) (xy 144.124424 -253.45644) (xy 144.128495 -253.400818)
			(xy 144.140621 -253.346381) (xy 144.160544 -253.29429) (xy 144.18784 -253.245655) (xy 144.221926 -253.201512)
			(xy 144.262075 -253.162803) (xy 144.307433 -253.130352) (xy 144.357033 -253.104851) (xy 144.409817 -253.086844)
			(xy 144.46466 -253.076714) (xy 144.520394 -253.074677) (xy 144.575831 -253.080777) (xy 144.629788 -253.094883)
			(xy 144.681117 -253.116695) (xy 144.728723 -253.145749) (xy 144.771591 -253.181424) (xy 144.808808 -253.222961)
			(xy 144.839581 -253.269474) (xy 144.863253 -253.319971) (xy 144.879321 -253.373378) (xy 144.887441 -253.428554)
			(xy 144.88795 -253.45644) (xy 145.140424 -253.45644) (xy 145.144495 -253.400818) (xy 145.156621 -253.346381)
			(xy 145.176544 -253.29429) (xy 145.20384 -253.245655) (xy 145.237926 -253.201512) (xy 145.278075 -253.162803)
			(xy 145.323433 -253.130352) (xy 145.373033 -253.104851) (xy 145.425817 -253.086844) (xy 145.48066 -253.076714)
			(xy 145.536394 -253.074677) (xy 145.591831 -253.080777) (xy 145.645788 -253.094883) (xy 145.697117 -253.116695)
			(xy 145.744723 -253.145749) (xy 145.787591 -253.181424) (xy 145.824808 -253.222961) (xy 145.855581 -253.269474)
			(xy 145.879253 -253.319971) (xy 145.895321 -253.373378) (xy 145.903441 -253.428554) (xy 145.90395 -253.45644)
			(xy 146.156424 -253.45644) (xy 146.160495 -253.400818) (xy 146.172621 -253.346381) (xy 146.192544 -253.29429)
			(xy 146.21984 -253.245655) (xy 146.253926 -253.201512) (xy 146.294075 -253.162803) (xy 146.339433 -253.130352)
			(xy 146.389033 -253.104851) (xy 146.441817 -253.086844) (xy 146.49666 -253.076714) (xy 146.552394 -253.074677)
			(xy 146.607831 -253.080777) (xy 146.661788 -253.094883) (xy 146.713117 -253.116695) (xy 146.760723 -253.145749)
			(xy 146.803591 -253.181424) (xy 146.840808 -253.222961) (xy 146.871581 -253.269474) (xy 146.895253 -253.319971)
			(xy 146.911321 -253.373378) (xy 146.919441 -253.428554) (xy 146.91995 -253.45644) (xy 147.172424 -253.45644)
			(xy 147.176495 -253.400818) (xy 147.188621 -253.346381) (xy 147.208544 -253.29429) (xy 147.23584 -253.245655)
			(xy 147.269926 -253.201512) (xy 147.310075 -253.162803) (xy 147.355433 -253.130352) (xy 147.405033 -253.104851)
			(xy 147.457817 -253.086844) (xy 147.51266 -253.076714) (xy 147.568394 -253.074677) (xy 147.623831 -253.080777)
			(xy 147.677788 -253.094883) (xy 147.729117 -253.116695) (xy 147.776723 -253.145749) (xy 147.819591 -253.181424)
			(xy 147.856808 -253.222961) (xy 147.887581 -253.269474) (xy 147.911253 -253.319971) (xy 147.927321 -253.373378)
			(xy 147.935441 -253.428554) (xy 147.93595 -253.45644) (xy 148.188424 -253.45644) (xy 148.192495 -253.400818)
			(xy 148.204621 -253.346381) (xy 148.224544 -253.29429) (xy 148.25184 -253.245655) (xy 148.285926 -253.201512)
			(xy 148.326075 -253.162803) (xy 148.371433 -253.130352) (xy 148.421033 -253.104851) (xy 148.473817 -253.086844)
			(xy 148.52866 -253.076714) (xy 148.584394 -253.074677) (xy 148.639831 -253.080777) (xy 148.693788 -253.094883)
			(xy 148.745117 -253.116695) (xy 148.792723 -253.145749) (xy 148.835591 -253.181424) (xy 148.872808 -253.222961)
			(xy 148.903581 -253.269474) (xy 148.927253 -253.319971) (xy 148.943321 -253.373378) (xy 148.951441 -253.428554)
			(xy 148.95195 -253.45644) (xy 149.204424 -253.45644) (xy 149.208495 -253.400818) (xy 149.220621 -253.346381)
			(xy 149.240544 -253.29429) (xy 149.26784 -253.245655) (xy 149.301926 -253.201512) (xy 149.342075 -253.162803)
			(xy 149.387433 -253.130352) (xy 149.437033 -253.104851) (xy 149.489817 -253.086844) (xy 149.54466 -253.076714)
			(xy 149.600394 -253.074677) (xy 149.655831 -253.080777) (xy 149.709788 -253.094883) (xy 149.761117 -253.116695)
			(xy 149.808723 -253.145749) (xy 149.851591 -253.181424) (xy 149.888808 -253.222961) (xy 149.919581 -253.269474)
			(xy 149.943253 -253.319971) (xy 149.959321 -253.373378) (xy 149.967441 -253.428554) (xy 149.96795 -253.45644)
			(xy 149.967441 -253.484326) (xy 149.959321 -253.539502) (xy 149.943253 -253.592909) (xy 149.919581 -253.643406)
			(xy 149.888808 -253.689919) (xy 149.851591 -253.731456) (xy 149.808723 -253.767131) (xy 149.761117 -253.796185)
			(xy 149.709788 -253.817997) (xy 149.655831 -253.832103) (xy 149.600394 -253.838203) (xy 149.54466 -253.836166)
			(xy 149.489817 -253.826036) (xy 149.437033 -253.808029) (xy 149.387433 -253.782528) (xy 149.342075 -253.750077)
			(xy 149.301926 -253.711368) (xy 149.26784 -253.667225) (xy 149.240544 -253.61859) (xy 149.220621 -253.566499)
			(xy 149.208495 -253.512062) (xy 149.204424 -253.45644) (xy 148.95195 -253.45644) (xy 148.951441 -253.484326)
			(xy 148.943321 -253.539502) (xy 148.927253 -253.592909) (xy 148.903581 -253.643406) (xy 148.872808 -253.689919)
			(xy 148.835591 -253.731456) (xy 148.792723 -253.767131) (xy 148.745117 -253.796185) (xy 148.693788 -253.817997)
			(xy 148.639831 -253.832103) (xy 148.584394 -253.838203) (xy 148.52866 -253.836166) (xy 148.473817 -253.826036)
			(xy 148.421033 -253.808029) (xy 148.371433 -253.782528) (xy 148.326075 -253.750077) (xy 148.285926 -253.711368)
			(xy 148.25184 -253.667225) (xy 148.224544 -253.61859) (xy 148.204621 -253.566499) (xy 148.192495 -253.512062)
			(xy 148.188424 -253.45644) (xy 147.93595 -253.45644) (xy 147.935441 -253.484326) (xy 147.927321 -253.539502)
			(xy 147.911253 -253.592909) (xy 147.887581 -253.643406) (xy 147.856808 -253.689919) (xy 147.819591 -253.731456)
			(xy 147.776723 -253.767131) (xy 147.729117 -253.796185) (xy 147.677788 -253.817997) (xy 147.623831 -253.832103)
			(xy 147.568394 -253.838203) (xy 147.51266 -253.836166) (xy 147.457817 -253.826036) (xy 147.405033 -253.808029)
			(xy 147.355433 -253.782528) (xy 147.310075 -253.750077) (xy 147.269926 -253.711368) (xy 147.23584 -253.667225)
			(xy 147.208544 -253.61859) (xy 147.188621 -253.566499) (xy 147.176495 -253.512062) (xy 147.172424 -253.45644)
			(xy 146.91995 -253.45644) (xy 146.919441 -253.484326) (xy 146.911321 -253.539502) (xy 146.895253 -253.592909)
			(xy 146.871581 -253.643406) (xy 146.840808 -253.689919) (xy 146.803591 -253.731456) (xy 146.760723 -253.767131)
			(xy 146.713117 -253.796185) (xy 146.661788 -253.817997) (xy 146.607831 -253.832103) (xy 146.552394 -253.838203)
			(xy 146.49666 -253.836166) (xy 146.441817 -253.826036) (xy 146.389033 -253.808029) (xy 146.339433 -253.782528)
			(xy 146.294075 -253.750077) (xy 146.253926 -253.711368) (xy 146.21984 -253.667225) (xy 146.192544 -253.61859)
			(xy 146.172621 -253.566499) (xy 146.160495 -253.512062) (xy 146.156424 -253.45644) (xy 145.90395 -253.45644)
			(xy 145.903441 -253.484326) (xy 145.895321 -253.539502) (xy 145.879253 -253.592909) (xy 145.855581 -253.643406)
			(xy 145.824808 -253.689919) (xy 145.787591 -253.731456) (xy 145.744723 -253.767131) (xy 145.697117 -253.796185)
			(xy 145.645788 -253.817997) (xy 145.591831 -253.832103) (xy 145.536394 -253.838203) (xy 145.48066 -253.836166)
			(xy 145.425817 -253.826036) (xy 145.373033 -253.808029) (xy 145.323433 -253.782528) (xy 145.278075 -253.750077)
			(xy 145.237926 -253.711368) (xy 145.20384 -253.667225) (xy 145.176544 -253.61859) (xy 145.156621 -253.566499)
			(xy 145.144495 -253.512062) (xy 145.140424 -253.45644) (xy 144.88795 -253.45644) (xy 144.887441 -253.484326)
			(xy 144.879321 -253.539502) (xy 144.863253 -253.592909) (xy 144.839581 -253.643406) (xy 144.808808 -253.689919)
			(xy 144.771591 -253.731456) (xy 144.728723 -253.767131) (xy 144.681117 -253.796185) (xy 144.629788 -253.817997)
			(xy 144.575831 -253.832103) (xy 144.520394 -253.838203) (xy 144.46466 -253.836166) (xy 144.409817 -253.826036)
			(xy 144.357033 -253.808029) (xy 144.307433 -253.782528) (xy 144.262075 -253.750077) (xy 144.221926 -253.711368)
			(xy 144.18784 -253.667225) (xy 144.160544 -253.61859) (xy 144.140621 -253.566499) (xy 144.128495 -253.512062)
			(xy 144.124424 -253.45644) (xy 143.87195 -253.45644) (xy 143.871441 -253.484326) (xy 143.863321 -253.539502)
			(xy 143.847253 -253.592909) (xy 143.823581 -253.643406) (xy 143.792808 -253.689919) (xy 143.755591 -253.731456)
			(xy 143.712723 -253.767131) (xy 143.665117 -253.796185) (xy 143.613788 -253.817997) (xy 143.559831 -253.832103)
			(xy 143.504394 -253.838203) (xy 143.44866 -253.836166) (xy 143.393817 -253.826036) (xy 143.341033 -253.808029)
			(xy 143.291433 -253.782528) (xy 143.246075 -253.750077) (xy 143.205926 -253.711368) (xy 143.17184 -253.667225)
			(xy 143.144544 -253.61859) (xy 143.124621 -253.566499) (xy 143.112495 -253.512062) (xy 143.108424 -253.45644)
			(xy 142.85595 -253.45644) (xy 142.855441 -253.484326) (xy 142.847321 -253.539502) (xy 142.831253 -253.592909)
			(xy 142.807581 -253.643406) (xy 142.776808 -253.689919) (xy 142.739591 -253.731456) (xy 142.696723 -253.767131)
			(xy 142.649117 -253.796185) (xy 142.597788 -253.817997) (xy 142.543831 -253.832103) (xy 142.488394 -253.838203)
			(xy 142.43266 -253.836166) (xy 142.377817 -253.826036) (xy 142.325033 -253.808029) (xy 142.275433 -253.782528)
			(xy 142.230075 -253.750077) (xy 142.189926 -253.711368) (xy 142.15584 -253.667225) (xy 142.128544 -253.61859)
			(xy 142.108621 -253.566499) (xy 142.096495 -253.512062) (xy 142.092424 -253.45644) (xy 141.83995 -253.45644)
			(xy 141.839441 -253.484326) (xy 141.831321 -253.539502) (xy 141.815253 -253.592909) (xy 141.791581 -253.643406)
			(xy 141.760808 -253.689919) (xy 141.723591 -253.731456) (xy 141.680723 -253.767131) (xy 141.633117 -253.796185)
			(xy 141.581788 -253.817997) (xy 141.527831 -253.832103) (xy 141.472394 -253.838203) (xy 141.41666 -253.836166)
			(xy 141.361817 -253.826036) (xy 141.309033 -253.808029) (xy 141.259433 -253.782528) (xy 141.214075 -253.750077)
			(xy 141.173926 -253.711368) (xy 141.13984 -253.667225) (xy 141.112544 -253.61859) (xy 141.092621 -253.566499)
			(xy 141.080495 -253.512062) (xy 141.076424 -253.45644) (xy 140.82395 -253.45644) (xy 140.823441 -253.484326)
			(xy 140.815321 -253.539502) (xy 140.799253 -253.592909) (xy 140.775581 -253.643406) (xy 140.744808 -253.689919)
			(xy 140.707591 -253.731456) (xy 140.664723 -253.767131) (xy 140.617117 -253.796185) (xy 140.565788 -253.817997)
			(xy 140.511831 -253.832103) (xy 140.456394 -253.838203) (xy 140.40066 -253.836166) (xy 140.345817 -253.826036)
			(xy 140.293033 -253.808029) (xy 140.243433 -253.782528) (xy 140.198075 -253.750077) (xy 140.157926 -253.711368)
			(xy 140.12384 -253.667225) (xy 140.096544 -253.61859) (xy 140.076621 -253.566499) (xy 140.064495 -253.512062)
			(xy 140.060424 -253.45644) (xy 138.213169 -253.45644) (xy 138.226233 -253.484309) (xy 138.242301 -253.537716)
			(xy 138.250421 -253.592892) (xy 138.25093 -253.620778) (xy 138.250421 -253.648664) (xy 138.242301 -253.70384)
			(xy 138.226233 -253.757247) (xy 138.202561 -253.807744) (xy 138.171788 -253.854257) (xy 138.134571 -253.895794)
			(xy 138.091703 -253.931469) (xy 138.044097 -253.960523) (xy 137.992768 -253.982335) (xy 137.938811 -253.996441)
			(xy 137.883374 -254.002541) (xy 137.82764 -254.000504) (xy 137.772797 -253.990374) (xy 137.720013 -253.972367)
			(xy 137.670413 -253.946866) (xy 137.625055 -253.914415) (xy 137.584906 -253.875706) (xy 137.55082 -253.831563)
			(xy 137.523524 -253.782928) (xy 137.503601 -253.730837) (xy 137.491475 -253.6764) (xy 137.487404 -253.620778)
			(xy 137.055098 -253.620778) (xy 137.055098 -255.910588) (xy 137.976608 -255.910588) (xy 137.980679 -255.854966)
			(xy 137.992805 -255.800529) (xy 138.012728 -255.748438) (xy 138.040024 -255.699803) (xy 138.07411 -255.65566)
			(xy 138.114259 -255.616951) (xy 138.159617 -255.5845) (xy 138.209217 -255.558999) (xy 138.262001 -255.540992)
			(xy 138.316844 -255.530862) (xy 138.372578 -255.528825) (xy 138.428015 -255.534925) (xy 138.481972 -255.549031)
			(xy 138.533301 -255.570843) (xy 138.580907 -255.599897) (xy 138.623775 -255.635572) (xy 138.660992 -255.677109)
			(xy 138.671803 -255.69345) (xy 138.865595 -255.69345) (xy 138.865595 -255.63895) (xy 138.873352 -255.585003)
			(xy 138.888707 -255.53271) (xy 138.911347 -255.483135) (xy 138.940813 -255.437286) (xy 138.976504 -255.396097)
			(xy 139.017694 -255.360407) (xy 139.063543 -255.330943) (xy 139.11312 -255.308303) (xy 139.165413 -255.29295)
			(xy 139.21936 -255.285195) (xy 139.24661 -255.284732) (xy 139.275563 -255.285266) (xy 139.332804 -255.294025)
			(xy 139.388066 -255.311326) (xy 139.440082 -255.336772) (xy 139.487661 -255.36978) (xy 139.52971 -255.409593)
			(xy 139.565266 -255.455299) (xy 139.579858 -255.480312) (xy 139.587594 -255.493222) (xy 139.609263 -255.514091)
			(xy 139.636073 -255.527742) (xy 139.665697 -255.532988) (xy 139.695565 -255.529375) (xy 139.723083 -255.517216)
			(xy 139.745865 -255.497567) (xy 139.754356 -255.485138) (xy 139.769465 -255.462161) (xy 139.805167 -255.420337)
			(xy 139.846503 -255.38407) (xy 139.892616 -255.354112) (xy 139.942551 -255.331082) (xy 139.995275 -255.315459)
			(xy 140.049695 -255.307565) (xy 140.07719 -255.307084) (xy 140.104443 -255.307563) (xy 140.158394 -255.315318)
			(xy 140.210692 -255.330673) (xy 140.260272 -255.353315) (xy 140.306125 -255.382782) (xy 140.347318 -255.418475)
			(xy 140.383012 -255.459667) (xy 140.412481 -255.505519) (xy 140.435123 -255.555099) (xy 140.45048 -255.607397)
			(xy 140.458237 -255.661347) (xy 140.458237 -255.715853) (xy 140.45048 -255.769803) (xy 140.435123 -255.822101)
			(xy 140.412481 -255.871681) (xy 140.383012 -255.917533) (xy 140.347318 -255.958725) (xy 140.306125 -255.994418)
			(xy 140.260272 -256.023885) (xy 140.210692 -256.046527) (xy 140.158394 -256.061882) (xy 140.104443 -256.069637)
			(xy 140.07719 -256.0701) (xy 140.048235 -256.069601) (xy 139.990991 -256.06084) (xy 139.935727 -256.043535)
			(xy 139.883709 -256.018084) (xy 139.836131 -255.98507) (xy 139.794083 -255.94525) (xy 139.758531 -255.899537)
			(xy 139.743942 -255.87452) (xy 139.736204 -255.861615) (xy 139.71453 -255.840759) (xy 139.687721 -255.827118)
			(xy 139.658103 -255.821876) (xy 139.628241 -255.825486) (xy 139.600725 -255.837636) (xy 139.57794 -255.857272)
			(xy 139.569444 -255.869694) (xy 139.554345 -255.892679) (xy 139.51864 -255.934501) (xy 139.477303 -255.970766)
			(xy 139.431188 -256.000723) (xy 139.381251 -256.023751) (xy 139.328526 -256.039374) (xy 139.274105 -256.047267)
			(xy 139.24661 -256.047748) (xy 139.21936 -256.047205) (xy 139.165413 -256.03945) (xy 139.11312 -256.024097)
			(xy 139.063543 -256.001457) (xy 139.017694 -255.971993) (xy 138.976504 -255.936303) (xy 138.940813 -255.895114)
			(xy 138.911347 -255.849265) (xy 138.888707 -255.79969) (xy 138.873352 -255.747397) (xy 138.865595 -255.69345)
			(xy 138.671803 -255.69345) (xy 138.691765 -255.723622) (xy 138.715437 -255.774119) (xy 138.731505 -255.827526)
			(xy 138.739625 -255.882702) (xy 138.740134 -255.910588) (xy 138.739625 -255.938474) (xy 138.731505 -255.99365)
			(xy 138.715437 -256.047057) (xy 138.691765 -256.097554) (xy 138.691107 -256.098548) (xy 143.98193 -256.098548)
			(xy 143.986001 -256.042926) (xy 143.998127 -255.988489) (xy 144.01805 -255.936398) (xy 144.045346 -255.887763)
			(xy 144.079432 -255.84362) (xy 144.119581 -255.804911) (xy 144.164939 -255.77246) (xy 144.214539 -255.746959)
			(xy 144.267323 -255.728952) (xy 144.322166 -255.718822) (xy 144.3779 -255.716785) (xy 144.433337 -255.722885)
			(xy 144.487294 -255.736991) (xy 144.538623 -255.758803) (xy 144.586229 -255.787857) (xy 144.629097 -255.823532)
			(xy 144.666314 -255.865069) (xy 144.697087 -255.911582) (xy 144.720759 -255.962079) (xy 144.736827 -256.015486)
			(xy 144.744947 -256.070662) (xy 144.745456 -256.098548) (xy 144.744947 -256.126434) (xy 144.736827 -256.18161)
			(xy 144.720759 -256.235017) (xy 144.697087 -256.285514) (xy 144.666314 -256.332027) (xy 144.629097 -256.373564)
			(xy 144.626271 -256.375916) (xy 144.86966 -256.375916) (xy 144.873731 -256.320294) (xy 144.885857 -256.265857)
			(xy 144.90578 -256.213766) (xy 144.933076 -256.165131) (xy 144.967162 -256.120988) (xy 145.007311 -256.082279)
			(xy 145.052669 -256.049828) (xy 145.102269 -256.024327) (xy 145.155053 -256.00632) (xy 145.209896 -255.99619)
			(xy 145.26563 -255.994153) (xy 145.321067 -256.000253) (xy 145.375024 -256.014359) (xy 145.426353 -256.036171)
			(xy 145.473959 -256.065225) (xy 145.516827 -256.1009) (xy 145.554044 -256.142437) (xy 145.584817 -256.18895)
			(xy 145.608489 -256.239447) (xy 145.624557 -256.292854) (xy 145.632677 -256.34803) (xy 145.633186 -256.375916)
			(xy 146.345146 -256.375916) (xy 146.349217 -256.320294) (xy 146.361343 -256.265857) (xy 146.381266 -256.213766)
			(xy 146.408562 -256.165131) (xy 146.442648 -256.120988) (xy 146.482797 -256.082279) (xy 146.528155 -256.049828)
			(xy 146.577755 -256.024327) (xy 146.630539 -256.00632) (xy 146.685382 -255.99619) (xy 146.741116 -255.994153)
			(xy 146.796553 -256.000253) (xy 146.85051 -256.014359) (xy 146.901839 -256.036171) (xy 146.949445 -256.065225)
			(xy 146.992313 -256.1009) (xy 147.02953 -256.142437) (xy 147.060303 -256.18895) (xy 147.083975 -256.239447)
			(xy 147.100043 -256.292854) (xy 147.108163 -256.34803) (xy 147.108672 -256.375916) (xy 147.234146 -256.375916)
			(xy 147.238217 -256.320294) (xy 147.250343 -256.265857) (xy 147.270266 -256.213766) (xy 147.297562 -256.165131)
			(xy 147.331648 -256.120988) (xy 147.371797 -256.082279) (xy 147.417155 -256.049828) (xy 147.466755 -256.024327)
			(xy 147.519539 -256.00632) (xy 147.574382 -255.99619) (xy 147.630116 -255.994153) (xy 147.685553 -256.000253)
			(xy 147.73951 -256.014359) (xy 147.790839 -256.036171) (xy 147.838445 -256.065225) (xy 147.881313 -256.1009)
			(xy 147.91853 -256.142437) (xy 147.949303 -256.18895) (xy 147.972975 -256.239447) (xy 147.989043 -256.292854)
			(xy 147.997163 -256.34803) (xy 147.997672 -256.375916) (xy 147.997163 -256.403802) (xy 147.989043 -256.458978)
			(xy 147.972975 -256.512385) (xy 147.949303 -256.562882) (xy 147.91853 -256.609395) (xy 147.881313 -256.650932)
			(xy 147.838445 -256.686607) (xy 147.790839 -256.715661) (xy 147.73951 -256.737473) (xy 147.685553 -256.751579)
			(xy 147.630116 -256.757679) (xy 147.574382 -256.755642) (xy 147.519539 -256.745512) (xy 147.466755 -256.727505)
			(xy 147.417155 -256.702004) (xy 147.371797 -256.669553) (xy 147.331648 -256.630844) (xy 147.297562 -256.586701)
			(xy 147.270266 -256.538066) (xy 147.250343 -256.485975) (xy 147.238217 -256.431538) (xy 147.234146 -256.375916)
			(xy 147.108672 -256.375916) (xy 147.108163 -256.403802) (xy 147.100043 -256.458978) (xy 147.083975 -256.512385)
			(xy 147.060303 -256.562882) (xy 147.02953 -256.609395) (xy 146.992313 -256.650932) (xy 146.949445 -256.686607)
			(xy 146.901839 -256.715661) (xy 146.85051 -256.737473) (xy 146.796553 -256.751579) (xy 146.741116 -256.757679)
			(xy 146.685382 -256.755642) (xy 146.630539 -256.745512) (xy 146.577755 -256.727505) (xy 146.528155 -256.702004)
			(xy 146.482797 -256.669553) (xy 146.442648 -256.630844) (xy 146.408562 -256.586701) (xy 146.381266 -256.538066)
			(xy 146.361343 -256.485975) (xy 146.349217 -256.431538) (xy 146.345146 -256.375916) (xy 145.633186 -256.375916)
			(xy 145.632677 -256.403802) (xy 145.624557 -256.458978) (xy 145.608489 -256.512385) (xy 145.584817 -256.562882)
			(xy 145.554044 -256.609395) (xy 145.516827 -256.650932) (xy 145.473959 -256.686607) (xy 145.426353 -256.715661)
			(xy 145.375024 -256.737473) (xy 145.321067 -256.751579) (xy 145.26563 -256.757679) (xy 145.209896 -256.755642)
			(xy 145.155053 -256.745512) (xy 145.102269 -256.727505) (xy 145.052669 -256.702004) (xy 145.007311 -256.669553)
			(xy 144.967162 -256.630844) (xy 144.933076 -256.586701) (xy 144.90578 -256.538066) (xy 144.885857 -256.485975)
			(xy 144.873731 -256.431538) (xy 144.86966 -256.375916) (xy 144.626271 -256.375916) (xy 144.586229 -256.409239)
			(xy 144.538623 -256.438293) (xy 144.487294 -256.460105) (xy 144.433337 -256.474211) (xy 144.3779 -256.480311)
			(xy 144.322166 -256.478274) (xy 144.267323 -256.468144) (xy 144.214539 -256.450137) (xy 144.164939 -256.424636)
			(xy 144.119581 -256.392185) (xy 144.079432 -256.353476) (xy 144.045346 -256.309333) (xy 144.01805 -256.260698)
			(xy 143.998127 -256.208607) (xy 143.986001 -256.15417) (xy 143.98193 -256.098548) (xy 138.691107 -256.098548)
			(xy 138.660992 -256.144067) (xy 138.623775 -256.185604) (xy 138.580907 -256.221279) (xy 138.533301 -256.250333)
			(xy 138.481972 -256.272145) (xy 138.428015 -256.286251) (xy 138.372578 -256.292351) (xy 138.316844 -256.290314)
			(xy 138.262001 -256.280184) (xy 138.209217 -256.262177) (xy 138.159617 -256.236676) (xy 138.114259 -256.204225)
			(xy 138.07411 -256.165516) (xy 138.040024 -256.121373) (xy 138.012728 -256.072738) (xy 137.992805 -256.020647)
			(xy 137.980679 -255.96621) (xy 137.976608 -255.910588) (xy 137.055098 -255.910588) (xy 137.055098 -256.987548)
			(xy 143.98193 -256.987548) (xy 143.986001 -256.931926) (xy 143.998127 -256.877489) (xy 144.01805 -256.825398)
			(xy 144.045346 -256.776763) (xy 144.079432 -256.73262) (xy 144.119581 -256.693911) (xy 144.164939 -256.66146)
			(xy 144.214539 -256.635959) (xy 144.267323 -256.617952) (xy 144.322166 -256.607822) (xy 144.3779 -256.605785)
			(xy 144.433337 -256.611885) (xy 144.487294 -256.625991) (xy 144.538623 -256.647803) (xy 144.586229 -256.676857)
			(xy 144.629097 -256.712532) (xy 144.666314 -256.754069) (xy 144.697087 -256.800582) (xy 144.720759 -256.851079)
			(xy 144.736827 -256.904486) (xy 144.744947 -256.959662) (xy 144.745456 -256.987548) (xy 144.744947 -257.015434)
			(xy 144.736827 -257.07061) (xy 144.720759 -257.124017) (xy 144.697087 -257.174514) (xy 144.666314 -257.221027)
			(xy 144.629097 -257.262564) (xy 144.586229 -257.298239) (xy 144.538623 -257.327293) (xy 144.487294 -257.349105)
			(xy 144.433337 -257.363211) (xy 144.3779 -257.369311) (xy 144.322166 -257.367274) (xy 144.267323 -257.357144)
			(xy 144.214539 -257.339137) (xy 144.164939 -257.313636) (xy 144.119581 -257.281185) (xy 144.079432 -257.242476)
			(xy 144.045346 -257.198333) (xy 144.01805 -257.149698) (xy 143.998127 -257.097607) (xy 143.986001 -257.04317)
			(xy 143.98193 -256.987548) (xy 137.055098 -256.987548) (xy 137.055098 -257.474212) (xy 138.071858 -257.474212)
			(xy 138.075929 -257.41859) (xy 138.088055 -257.364153) (xy 138.107978 -257.312062) (xy 138.135274 -257.263427)
			(xy 138.16936 -257.219284) (xy 138.209509 -257.180575) (xy 138.254867 -257.148124) (xy 138.304467 -257.122623)
			(xy 138.357251 -257.104616) (xy 138.412094 -257.094486) (xy 138.467828 -257.092449) (xy 138.523265 -257.098549)
			(xy 138.577222 -257.112655) (xy 138.628551 -257.134467) (xy 138.676157 -257.163521) (xy 138.719025 -257.199196)
			(xy 138.756242 -257.240733) (xy 138.787015 -257.287246) (xy 138.810687 -257.337743) (xy 138.826755 -257.39115)
			(xy 138.834875 -257.446326) (xy 138.835384 -257.474212) (xy 138.834875 -257.502098) (xy 138.826755 -257.557274)
			(xy 138.810687 -257.610681) (xy 138.787015 -257.661178) (xy 138.756242 -257.707691) (xy 138.719025 -257.749228)
			(xy 138.676157 -257.784903) (xy 138.628551 -257.813957) (xy 138.577222 -257.835769) (xy 138.523265 -257.849875)
			(xy 138.467828 -257.855975) (xy 138.412094 -257.853938) (xy 138.357251 -257.843808) (xy 138.304467 -257.825801)
			(xy 138.254867 -257.8003) (xy 138.209509 -257.767849) (xy 138.16936 -257.72914) (xy 138.135274 -257.684997)
			(xy 138.107978 -257.636362) (xy 138.088055 -257.584271) (xy 138.075929 -257.529834) (xy 138.071858 -257.474212)
			(xy 137.055098 -257.474212) (xy 137.055098 -258.266692) (xy 137.054958 -258.271582) (xy 137.053032 -258.281171)
			(xy 137.051288 -258.285742) (xy 137.047478 -258.295394) (xy 137.047478 -258.665472) (xy 137.226546 -258.665472)
			(xy 137.230617 -258.60985) (xy 137.242743 -258.555413) (xy 137.262666 -258.503322) (xy 137.289962 -258.454687)
			(xy 137.324048 -258.410544) (xy 137.364197 -258.371835) (xy 137.409555 -258.339384) (xy 137.459155 -258.313883)
			(xy 137.511939 -258.295876) (xy 137.566782 -258.285746) (xy 137.622516 -258.283709) (xy 137.677953 -258.289809)
			(xy 137.73191 -258.303915) (xy 137.783239 -258.325727) (xy 137.830845 -258.354781) (xy 137.873713 -258.390456)
			(xy 137.91093 -258.431993) (xy 137.941703 -258.478506) (xy 137.965375 -258.529003) (xy 137.981443 -258.58241)
			(xy 137.989563 -258.637586) (xy 137.989789 -258.649978) (xy 139.02639 -258.649978) (xy 139.030461 -258.594356)
			(xy 139.042587 -258.539919) (xy 139.06251 -258.487828) (xy 139.089806 -258.439193) (xy 139.123892 -258.39505)
			(xy 139.164041 -258.356341) (xy 139.209399 -258.32389) (xy 139.258999 -258.298389) (xy 139.311783 -258.280382)
			(xy 139.366626 -258.270252) (xy 139.42236 -258.268215) (xy 139.477797 -258.274315) (xy 139.531754 -258.288421)
			(xy 139.583083 -258.310233) (xy 139.630689 -258.339287) (xy 139.673557 -258.374962) (xy 139.710774 -258.416499)
			(xy 139.741547 -258.463012) (xy 139.765219 -258.513509) (xy 139.781287 -258.566916) (xy 139.789407 -258.622092)
			(xy 139.789916 -258.649978) (xy 139.789407 -258.677864) (xy 139.787455 -258.691126) (xy 140.510766 -258.691126)
			(xy 140.514837 -258.635504) (xy 140.526963 -258.581067) (xy 140.546886 -258.528976) (xy 140.574182 -258.480341)
			(xy 140.608268 -258.436198) (xy 140.648417 -258.397489) (xy 140.693775 -258.365038) (xy 140.743375 -258.339537)
			(xy 140.796159 -258.32153) (xy 140.851002 -258.3114) (xy 140.906736 -258.309363) (xy 140.962173 -258.315463)
			(xy 141.01613 -258.329569) (xy 141.067459 -258.351381) (xy 141.115065 -258.380435) (xy 141.157933 -258.41611)
			(xy 141.19515 -258.457647) (xy 141.225923 -258.50416) (xy 141.249595 -258.554657) (xy 141.265663 -258.608064)
			(xy 141.273783 -258.66324) (xy 141.274292 -258.691126) (xy 141.273783 -258.719012) (xy 141.265663 -258.774188)
			(xy 141.249595 -258.827595) (xy 141.225923 -258.878092) (xy 141.19515 -258.924605) (xy 141.157933 -258.966142)
			(xy 141.115065 -259.001817) (xy 141.067459 -259.030871) (xy 141.01613 -259.052683) (xy 140.962173 -259.066789)
			(xy 140.906736 -259.072889) (xy 140.851002 -259.070852) (xy 140.796159 -259.060722) (xy 140.743375 -259.042715)
			(xy 140.693775 -259.017214) (xy 140.648417 -258.984763) (xy 140.608268 -258.946054) (xy 140.574182 -258.901911)
			(xy 140.546886 -258.853276) (xy 140.526963 -258.801185) (xy 140.514837 -258.746748) (xy 140.510766 -258.691126)
			(xy 139.787455 -258.691126) (xy 139.781287 -258.73304) (xy 139.765219 -258.786447) (xy 139.741547 -258.836944)
			(xy 139.710774 -258.883457) (xy 139.673557 -258.924994) (xy 139.630689 -258.960669) (xy 139.583083 -258.989723)
			(xy 139.531754 -259.011535) (xy 139.477797 -259.025641) (xy 139.42236 -259.031741) (xy 139.366626 -259.029704)
			(xy 139.311783 -259.019574) (xy 139.258999 -259.001567) (xy 139.209399 -258.976066) (xy 139.164041 -258.943615)
			(xy 139.123892 -258.904906) (xy 139.089806 -258.860763) (xy 139.06251 -258.812128) (xy 139.042587 -258.760037)
			(xy 139.030461 -258.7056) (xy 139.02639 -258.649978) (xy 137.989789 -258.649978) (xy 137.990072 -258.665472)
			(xy 137.989563 -258.693358) (xy 137.981443 -258.748534) (xy 137.965375 -258.801941) (xy 137.941703 -258.852438)
			(xy 137.91093 -258.898951) (xy 137.873713 -258.940488) (xy 137.830845 -258.976163) (xy 137.783239 -259.005217)
			(xy 137.73191 -259.027029) (xy 137.677953 -259.041135) (xy 137.622516 -259.047235) (xy 137.566782 -259.045198)
			(xy 137.511939 -259.035068) (xy 137.459155 -259.017061) (xy 137.409555 -258.99156) (xy 137.364197 -258.959109)
			(xy 137.324048 -258.9204) (xy 137.289962 -258.876257) (xy 137.262666 -258.827622) (xy 137.242743 -258.775531)
			(xy 137.230617 -258.721094) (xy 137.226546 -258.665472) (xy 137.047478 -258.665472) (xy 137.047478 -259.576316)
			(xy 146.345146 -259.576316) (xy 146.349217 -259.520694) (xy 146.361343 -259.466257) (xy 146.381266 -259.414166)
			(xy 146.408562 -259.365531) (xy 146.442648 -259.321388) (xy 146.482797 -259.282679) (xy 146.528155 -259.250228)
			(xy 146.577755 -259.224727) (xy 146.630539 -259.20672) (xy 146.685382 -259.19659) (xy 146.741116 -259.194553)
			(xy 146.796553 -259.200653) (xy 146.85051 -259.214759) (xy 146.901839 -259.236571) (xy 146.949445 -259.265625)
			(xy 146.992313 -259.3013) (xy 147.02953 -259.342837) (xy 147.060303 -259.38935) (xy 147.083975 -259.439847)
			(xy 147.100043 -259.493254) (xy 147.108163 -259.54843) (xy 147.108672 -259.576316) (xy 147.108163 -259.604202)
			(xy 147.100043 -259.659378) (xy 147.083975 -259.712785) (xy 147.060303 -259.763282) (xy 147.02953 -259.809795)
			(xy 146.992313 -259.851332) (xy 146.949445 -259.887007) (xy 146.901839 -259.916061) (xy 146.85051 -259.937873)
			(xy 146.796553 -259.951979) (xy 146.741116 -259.958079) (xy 146.685382 -259.956042) (xy 146.630539 -259.945912)
			(xy 146.577755 -259.927905) (xy 146.528155 -259.902404) (xy 146.482797 -259.869953) (xy 146.442648 -259.831244)
			(xy 146.408562 -259.787101) (xy 146.381266 -259.738466) (xy 146.361343 -259.686375) (xy 146.349217 -259.631938)
			(xy 146.345146 -259.576316) (xy 137.047478 -259.576316) (xy 137.047478 -260.027674) (xy 138.191746 -260.027674)
			(xy 138.195817 -259.972052) (xy 138.207943 -259.917615) (xy 138.227866 -259.865524) (xy 138.255162 -259.816889)
			(xy 138.289248 -259.772746) (xy 138.329397 -259.734037) (xy 138.374755 -259.701586) (xy 138.424355 -259.676085)
			(xy 138.477139 -259.658078) (xy 138.531982 -259.647948) (xy 138.587716 -259.645911) (xy 138.643153 -259.652011)
			(xy 138.69711 -259.666117) (xy 138.748439 -259.687929) (xy 138.796045 -259.716983) (xy 138.838913 -259.752658)
			(xy 138.87613 -259.794195) (xy 138.906903 -259.840708) (xy 138.930575 -259.891205) (xy 138.946643 -259.944612)
			(xy 138.954763 -259.999788) (xy 138.955272 -260.027674) (xy 138.954763 -260.05556) (xy 138.95255 -260.0706)
			(xy 139.742924 -260.0706) (xy 139.746995 -260.014978) (xy 139.759121 -259.960541) (xy 139.779044 -259.90845)
			(xy 139.80634 -259.859815) (xy 139.840426 -259.815672) (xy 139.880575 -259.776963) (xy 139.925933 -259.744512)
			(xy 139.975533 -259.719011) (xy 140.028317 -259.701004) (xy 140.08316 -259.690874) (xy 140.138894 -259.688837)
			(xy 140.194331 -259.694937) (xy 140.248288 -259.709043) (xy 140.299617 -259.730855) (xy 140.347223 -259.759909)
			(xy 140.390091 -259.795584) (xy 140.427308 -259.837121) (xy 140.458081 -259.883634) (xy 140.481753 -259.934131)
			(xy 140.497821 -259.987538) (xy 140.505941 -260.042714) (xy 140.50645 -260.0706) (xy 140.505972 -260.096762)
			(xy 143.758918 -260.096762) (xy 143.762989 -260.04114) (xy 143.775115 -259.986703) (xy 143.795038 -259.934612)
			(xy 143.822334 -259.885977) (xy 143.85642 -259.841834) (xy 143.896569 -259.803125) (xy 143.941927 -259.770674)
			(xy 143.991527 -259.745173) (xy 144.044311 -259.727166) (xy 144.099154 -259.717036) (xy 144.154888 -259.714999)
			(xy 144.210325 -259.721099) (xy 144.264282 -259.735205) (xy 144.315611 -259.757017) (xy 144.363217 -259.786071)
			(xy 144.406085 -259.821746) (xy 144.443302 -259.863283) (xy 144.474075 -259.909796) (xy 144.497747 -259.960293)
			(xy 144.513815 -260.0137) (xy 144.521935 -260.068876) (xy 144.522444 -260.096762) (xy 144.521935 -260.124648)
			(xy 144.513815 -260.179824) (xy 144.497747 -260.233231) (xy 144.474075 -260.283728) (xy 144.443302 -260.330241)
			(xy 144.406085 -260.371778) (xy 144.363217 -260.407453) (xy 144.315611 -260.436507) (xy 144.264282 -260.458319)
			(xy 144.210325 -260.472425) (xy 144.154888 -260.478525) (xy 144.099154 -260.476488) (xy 144.044311 -260.466358)
			(xy 143.991527 -260.448351) (xy 143.941927 -260.42285) (xy 143.896569 -260.390399) (xy 143.85642 -260.35169)
			(xy 143.822334 -260.307547) (xy 143.795038 -260.258912) (xy 143.775115 -260.206821) (xy 143.762989 -260.152384)
			(xy 143.758918 -260.096762) (xy 140.505972 -260.096762) (xy 140.505941 -260.098486) (xy 140.497821 -260.153662)
			(xy 140.481753 -260.207069) (xy 140.458081 -260.257566) (xy 140.427308 -260.304079) (xy 140.390091 -260.345616)
			(xy 140.347223 -260.381291) (xy 140.299617 -260.410345) (xy 140.248288 -260.432157) (xy 140.194331 -260.446263)
			(xy 140.138894 -260.452363) (xy 140.08316 -260.450326) (xy 140.028317 -260.440196) (xy 139.975533 -260.422189)
			(xy 139.925933 -260.396688) (xy 139.880575 -260.364237) (xy 139.840426 -260.325528) (xy 139.80634 -260.281385)
			(xy 139.779044 -260.23275) (xy 139.759121 -260.180659) (xy 139.746995 -260.126222) (xy 139.742924 -260.0706)
			(xy 138.95255 -260.0706) (xy 138.946643 -260.110736) (xy 138.930575 -260.164143) (xy 138.906903 -260.21464)
			(xy 138.87613 -260.261153) (xy 138.838913 -260.30269) (xy 138.796045 -260.338365) (xy 138.748439 -260.367419)
			(xy 138.69711 -260.389231) (xy 138.643153 -260.403337) (xy 138.587716 -260.409437) (xy 138.531982 -260.4074)
			(xy 138.477139 -260.39727) (xy 138.424355 -260.379263) (xy 138.374755 -260.353762) (xy 138.329397 -260.321311)
			(xy 138.289248 -260.282602) (xy 138.255162 -260.238459) (xy 138.227866 -260.189824) (xy 138.207943 -260.137733)
			(xy 138.195817 -260.083296) (xy 138.191746 -260.027674) (xy 137.047478 -260.027674) (xy 137.047478 -261.79025)
			(xy 141.61948 -261.79025) (xy 141.61948 -261.73575) (xy 141.627236 -261.681804) (xy 141.64259 -261.629512)
			(xy 141.665229 -261.579936) (xy 141.694693 -261.534087) (xy 141.730382 -261.492898) (xy 141.771569 -261.457206)
			(xy 141.817417 -261.42774) (xy 141.866991 -261.405097) (xy 141.919283 -261.38974) (xy 141.973228 -261.381981)
			(xy 142.000478 -261.381494) (xy 142.029396 -261.381992) (xy 142.08657 -261.39072) (xy 142.141771 -261.40798)
			(xy 142.193733 -261.433375) (xy 142.241266 -261.466324) (xy 142.28328 -261.506071) (xy 142.301468 -261.52856)
			(xy 142.309038 -261.537313) (xy 142.329791 -261.547499) (xy 142.341346 -261.548118) (xy 142.42161 -261.548118)
			(xy 142.433178 -261.547547) (xy 142.453948 -261.537352) (xy 142.461488 -261.52856) (xy 142.479676 -261.506074)
			(xy 142.521697 -261.466341) (xy 142.569233 -261.433403) (xy 142.621195 -261.408016) (xy 142.676393 -261.390759)
			(xy 142.733562 -261.38203) (xy 142.762478 -261.381494) (xy 142.789732 -261.381952) (xy 142.843686 -261.389706)
			(xy 142.895986 -261.405061) (xy 142.94557 -261.427702) (xy 142.991426 -261.457169) (xy 143.032621 -261.492863)
			(xy 143.068317 -261.534057) (xy 143.097788 -261.579911) (xy 143.120432 -261.629493) (xy 143.135789 -261.681793)
			(xy 143.143547 -261.735746) (xy 143.143547 -261.790254) (xy 143.135789 -261.844207) (xy 143.120432 -261.896507)
			(xy 143.097788 -261.946089) (xy 143.068317 -261.991943) (xy 143.032621 -262.033137) (xy 142.991426 -262.068831)
			(xy 142.94557 -262.098298) (xy 142.895986 -262.120939) (xy 142.843686 -262.136294) (xy 142.789732 -262.144048)
			(xy 142.762478 -262.14451) (xy 142.733561 -262.14397) (xy 142.67639 -262.13525) (xy 142.62119 -262.117999)
			(xy 142.569227 -262.092611) (xy 142.521693 -262.05967) (xy 142.479677 -262.019929) (xy 142.461488 -261.997444)
			(xy 142.453937 -261.988672) (xy 142.43317 -261.978496) (xy 142.42161 -261.977886) (xy 142.341346 -261.977886)
			(xy 142.329782 -261.978488) (xy 142.309011 -261.988661) (xy 142.301468 -261.997444) (xy 142.283306 -262.019952)
			(xy 142.241279 -262.059684) (xy 142.193738 -262.092618) (xy 142.141771 -262.118002) (xy 142.086569 -262.135254)
			(xy 142.029396 -262.143978) (xy 142.000478 -262.14451) (xy 141.973228 -262.144019) (xy 141.919283 -262.13626)
			(xy 141.866991 -262.120903) (xy 141.817417 -262.09826) (xy 141.771569 -262.068794) (xy 141.730382 -262.033102)
			(xy 141.694693 -261.991913) (xy 141.665229 -261.946064) (xy 141.64259 -261.896488) (xy 141.627236 -261.844196)
			(xy 141.61948 -261.79025) (xy 137.047478 -261.79025) (xy 137.047478 -262.912352) (xy 141.268956 -262.912352)
			(xy 141.273027 -262.85673) (xy 141.285153 -262.802293) (xy 141.305076 -262.750202) (xy 141.332372 -262.701567)
			(xy 141.366458 -262.657424) (xy 141.406607 -262.618715) (xy 141.451965 -262.586264) (xy 141.501565 -262.560763)
			(xy 141.554349 -262.542756) (xy 141.609192 -262.532626) (xy 141.664926 -262.530589) (xy 141.720363 -262.536689)
			(xy 141.77432 -262.550795) (xy 141.825649 -262.572607) (xy 141.873255 -262.601661) (xy 141.916123 -262.637336)
			(xy 141.95334 -262.678873) (xy 141.984113 -262.725386) (xy 142.007785 -262.775883) (xy 142.023853 -262.82929)
			(xy 142.031973 -262.884466) (xy 142.032482 -262.912352) (xy 142.032417 -262.915908) (xy 143.242536 -262.915908)
			(xy 143.246607 -262.860286) (xy 143.258733 -262.805849) (xy 143.278656 -262.753758) (xy 143.305952 -262.705123)
			(xy 143.340038 -262.66098) (xy 143.380187 -262.622271) (xy 143.425545 -262.58982) (xy 143.475145 -262.564319)
			(xy 143.527929 -262.546312) (xy 143.582772 -262.536182) (xy 143.638506 -262.534145) (xy 143.693943 -262.540245)
			(xy 143.7479 -262.554351) (xy 143.799229 -262.576163) (xy 143.846835 -262.605217) (xy 143.889703 -262.640892)
			(xy 143.92692 -262.682429) (xy 143.957693 -262.728942) (xy 143.981365 -262.779439) (xy 143.997433 -262.832846)
			(xy 144.005553 -262.888022) (xy 144.006062 -262.915908) (xy 144.005553 -262.943794) (xy 143.997433 -262.99897)
			(xy 143.981365 -263.052377) (xy 143.957693 -263.102874) (xy 143.92692 -263.149387) (xy 143.889703 -263.190924)
			(xy 143.846835 -263.226599) (xy 143.799229 -263.255653) (xy 143.7479 -263.277465) (xy 143.693943 -263.291571)
			(xy 143.638506 -263.297671) (xy 143.582772 -263.295634) (xy 143.527929 -263.285504) (xy 143.475145 -263.267497)
			(xy 143.425545 -263.241996) (xy 143.380187 -263.209545) (xy 143.340038 -263.170836) (xy 143.305952 -263.126693)
			(xy 143.278656 -263.078058) (xy 143.258733 -263.025967) (xy 143.246607 -262.97153) (xy 143.242536 -262.915908)
			(xy 142.032417 -262.915908) (xy 142.031973 -262.940238) (xy 142.023853 -262.995414) (xy 142.007785 -263.048821)
			(xy 141.984113 -263.099318) (xy 141.95334 -263.145831) (xy 141.916123 -263.187368) (xy 141.873255 -263.223043)
			(xy 141.825649 -263.252097) (xy 141.77432 -263.273909) (xy 141.720363 -263.288015) (xy 141.664926 -263.294115)
			(xy 141.609192 -263.292078) (xy 141.554349 -263.281948) (xy 141.501565 -263.263941) (xy 141.451965 -263.23844)
			(xy 141.406607 -263.205989) (xy 141.366458 -263.16728) (xy 141.332372 -263.123137) (xy 141.305076 -263.074502)
			(xy 141.285153 -263.022411) (xy 141.273027 -262.967974) (xy 141.268956 -262.912352) (xy 137.047478 -262.912352)
			(xy 137.047478 -272.669508) (xy 137.047632 -272.675231) (xy 137.050207 -272.686385) (xy 137.052558 -272.691606)
			(xy 137.055098 -272.69694) (xy 137.080244 -272.729198) (xy 137.08761 -272.734024) (xy 137.094722 -272.738596)
			(xy 137.102596 -272.740628) (xy 137.182139 -272.761877) (xy 137.339262 -272.81113) (xy 137.4938 -272.867979)
			(xy 137.645384 -272.932288) (xy 137.793656 -273.003905) (xy 137.938263 -273.082659) (xy 138.078863 -273.168365)
			(xy 138.21512 -273.260817) (xy 138.346712 -273.359798) (xy 138.473326 -273.46507) (xy 138.594662 -273.576386)
			(xy 138.710431 -273.69348) (xy 138.820359 -273.816075) (xy 138.924185 -273.943879) (xy 139.021661 -274.076588)
			(xy 139.112558 -274.213889) (xy 139.196658 -274.355454) (xy 139.273762 -274.500948) (xy 139.343687 -274.650025)
			(xy 139.406267 -274.802332) (xy 139.461354 -274.957506) (xy 139.508817 -275.115179) (xy 139.548542 -275.274977)
			(xy 139.580436 -275.436521) (xy 139.604423 -275.599426) (xy 139.620446 -275.763307) (xy 139.628467 -275.927773)
			(xy 139.628467 -276.092435) (xy 139.620446 -276.256901) (xy 139.604422 -276.420782) (xy 139.580435 -276.583687)
			(xy 139.54854 -276.745231) (xy 139.508814 -276.905029) (xy 139.461352 -277.062702) (xy 139.406265 -277.217876)
			(xy 139.343684 -277.370182) (xy 139.273758 -277.519259) (xy 139.196654 -277.664753) (xy 139.112553 -277.806318)
			(xy 139.021657 -277.943618) (xy 138.92418 -278.076328) (xy 138.820354 -278.204131) (xy 138.710426 -278.326726)
			(xy 138.594656 -278.443819) (xy 138.47332 -278.555135) (xy 138.346706 -278.660407) (xy 138.215113 -278.759387)
			(xy 138.078856 -278.85184) (xy 137.938256 -278.937545) (xy 137.793649 -279.016299) (xy 137.645377 -279.087915)
			(xy 137.493792 -279.152224) (xy 137.339255 -279.209073) (xy 137.182131 -279.258326) (xy 137.102596 -279.279604)
			(xy 137.094722 -279.281636) (xy 137.08761 -279.286208) (xy 137.080244 -279.291034) (xy 137.0584 -279.318974)
			(xy 137.05459 -279.324562) (xy 137.054336 -279.324816) (xy 137.051166 -279.330752) (xy 137.047686 -279.343745)
			(xy 137.047478 -279.35047) (xy 137.047478 -279.931114) (xy 141.911576 -279.931114) (xy 141.915647 -279.875492)
			(xy 141.927773 -279.821055) (xy 141.947696 -279.768964) (xy 141.974992 -279.720329) (xy 142.009078 -279.676186)
			(xy 142.049227 -279.637477) (xy 142.094585 -279.605026) (xy 142.144185 -279.579525) (xy 142.196969 -279.561518)
			(xy 142.251812 -279.551388) (xy 142.307546 -279.549351) (xy 142.362983 -279.555451) (xy 142.41694 -279.569557)
			(xy 142.468269 -279.591369) (xy 142.515875 -279.620423) (xy 142.558743 -279.656098) (xy 142.59596 -279.697635)
			(xy 142.626733 -279.744148) (xy 142.650405 -279.794645) (xy 142.666473 -279.848052) (xy 142.674593 -279.903228)
			(xy 142.675102 -279.931114) (xy 142.674593 -279.959) (xy 142.666473 -280.014176) (xy 142.650405 -280.067583)
			(xy 142.626733 -280.11808) (xy 142.59596 -280.164593) (xy 142.558743 -280.20613) (xy 142.515875 -280.241805)
			(xy 142.468269 -280.270859) (xy 142.41694 -280.292671) (xy 142.362983 -280.306777) (xy 142.307546 -280.312877)
			(xy 142.251812 -280.31084) (xy 142.196969 -280.30071) (xy 142.144185 -280.282703) (xy 142.094585 -280.257202)
			(xy 142.049227 -280.224751) (xy 142.009078 -280.186042) (xy 141.974992 -280.141899) (xy 141.947696 -280.093264)
			(xy 141.927773 -280.041173) (xy 141.915647 -279.986736) (xy 141.911576 -279.931114) (xy 137.047478 -279.931114)
			(xy 137.047478 -283.131514) (xy 141.911576 -283.131514) (xy 141.915647 -283.075892) (xy 141.927773 -283.021455)
			(xy 141.947696 -282.969364) (xy 141.974992 -282.920729) (xy 142.009078 -282.876586) (xy 142.049227 -282.837877)
			(xy 142.094585 -282.805426) (xy 142.144185 -282.779925) (xy 142.196969 -282.761918) (xy 142.251812 -282.751788)
			(xy 142.307546 -282.749751) (xy 142.362983 -282.755851) (xy 142.41694 -282.769957) (xy 142.468269 -282.791769)
			(xy 142.515875 -282.820823) (xy 142.558743 -282.856498) (xy 142.59596 -282.898035) (xy 142.626733 -282.944548)
			(xy 142.650405 -282.995045) (xy 142.666473 -283.048452) (xy 142.674593 -283.103628) (xy 142.675102 -283.131514)
			(xy 142.674593 -283.1594) (xy 142.666473 -283.214576) (xy 142.650405 -283.267983) (xy 142.626733 -283.31848)
			(xy 142.59596 -283.364993) (xy 142.558743 -283.40653) (xy 142.515875 -283.442205) (xy 142.468269 -283.471259)
			(xy 142.41694 -283.493071) (xy 142.362983 -283.507177) (xy 142.307546 -283.513277) (xy 142.251812 -283.51124)
			(xy 142.196969 -283.50111) (xy 142.144185 -283.483103) (xy 142.094585 -283.457602) (xy 142.049227 -283.425151)
			(xy 142.009078 -283.386442) (xy 141.974992 -283.342299) (xy 141.947696 -283.293664) (xy 141.927773 -283.241573)
			(xy 141.915647 -283.187136) (xy 141.911576 -283.131514) (xy 137.047478 -283.131514) (xy 137.047478 -284.061154)
			(xy 140.967204 -284.061154) (xy 140.971275 -284.005532) (xy 140.983401 -283.951095) (xy 141.003324 -283.899004)
			(xy 141.03062 -283.850369) (xy 141.064706 -283.806226) (xy 141.104855 -283.767517) (xy 141.150213 -283.735066)
			(xy 141.199813 -283.709565) (xy 141.252597 -283.691558) (xy 141.30744 -283.681428) (xy 141.363174 -283.679391)
			(xy 141.418611 -283.685491) (xy 141.472568 -283.699597) (xy 141.523897 -283.721409) (xy 141.571503 -283.750463)
			(xy 141.614371 -283.786138) (xy 141.651588 -283.827675) (xy 141.682361 -283.874188) (xy 141.706033 -283.924685)
			(xy 141.722101 -283.978092) (xy 141.730221 -284.033268) (xy 141.73073 -284.061154) (xy 141.730221 -284.08904)
			(xy 141.722101 -284.144216) (xy 141.706033 -284.197623) (xy 141.682361 -284.24812) (xy 141.651588 -284.294633)
			(xy 141.614371 -284.33617) (xy 141.571503 -284.371845) (xy 141.523897 -284.400899) (xy 141.472568 -284.422711)
			(xy 141.418611 -284.436817) (xy 141.363174 -284.442917) (xy 141.30744 -284.44088) (xy 141.252597 -284.43075)
			(xy 141.199813 -284.412743) (xy 141.150213 -284.387242) (xy 141.104855 -284.354791) (xy 141.064706 -284.316082)
			(xy 141.03062 -284.271939) (xy 141.003324 -284.223304) (xy 140.983401 -284.171213) (xy 140.971275 -284.116776)
			(xy 140.967204 -284.061154) (xy 137.047478 -284.061154) (xy 137.047478 -286.331914) (xy 141.911576 -286.331914)
			(xy 141.915647 -286.276292) (xy 141.927773 -286.221855) (xy 141.947696 -286.169764) (xy 141.974992 -286.121129)
			(xy 142.009078 -286.076986) (xy 142.049227 -286.038277) (xy 142.094585 -286.005826) (xy 142.144185 -285.980325)
			(xy 142.196969 -285.962318) (xy 142.251812 -285.952188) (xy 142.307546 -285.950151) (xy 142.362983 -285.956251)
			(xy 142.41694 -285.970357) (xy 142.468269 -285.992169) (xy 142.515875 -286.021223) (xy 142.558743 -286.056898)
			(xy 142.59596 -286.098435) (xy 142.626733 -286.144948) (xy 142.650405 -286.195445) (xy 142.666473 -286.248852)
			(xy 142.674593 -286.304028) (xy 142.675102 -286.331914) (xy 142.674593 -286.3598) (xy 142.666473 -286.414976)
			(xy 142.650405 -286.468383) (xy 142.626733 -286.51888) (xy 142.59596 -286.565393) (xy 142.558743 -286.60693)
			(xy 142.515875 -286.642605) (xy 142.468269 -286.671659) (xy 142.41694 -286.693471) (xy 142.362983 -286.707577)
			(xy 142.307546 -286.713677) (xy 142.251812 -286.71164) (xy 142.196969 -286.70151) (xy 142.144185 -286.683503)
			(xy 142.094585 -286.658002) (xy 142.049227 -286.625551) (xy 142.009078 -286.586842) (xy 141.974992 -286.542699)
			(xy 141.947696 -286.494064) (xy 141.927773 -286.441973) (xy 141.915647 -286.387536) (xy 141.911576 -286.331914)
			(xy 137.047478 -286.331914) (xy 137.047478 -289.532314) (xy 141.911576 -289.532314) (xy 141.915647 -289.476692)
			(xy 141.927773 -289.422255) (xy 141.947696 -289.370164) (xy 141.974992 -289.321529) (xy 142.009078 -289.277386)
			(xy 142.049227 -289.238677) (xy 142.094585 -289.206226) (xy 142.144185 -289.180725) (xy 142.196969 -289.162718)
			(xy 142.251812 -289.152588) (xy 142.307546 -289.150551) (xy 142.362983 -289.156651) (xy 142.41694 -289.170757)
			(xy 142.468269 -289.192569) (xy 142.515875 -289.221623) (xy 142.558743 -289.257298) (xy 142.59596 -289.298835)
			(xy 142.626733 -289.345348) (xy 142.650405 -289.395845) (xy 142.666473 -289.449252) (xy 142.674593 -289.504428)
			(xy 142.675102 -289.532314) (xy 142.674593 -289.5602) (xy 142.666473 -289.615376) (xy 142.650405 -289.668783)
			(xy 142.626733 -289.71928) (xy 142.59596 -289.765793) (xy 142.558743 -289.80733) (xy 142.515875 -289.843005)
			(xy 142.468269 -289.872059) (xy 142.41694 -289.893871) (xy 142.362983 -289.907977) (xy 142.307546 -289.914077)
			(xy 142.251812 -289.91204) (xy 142.196969 -289.90191) (xy 142.144185 -289.883903) (xy 142.094585 -289.858402)
			(xy 142.049227 -289.825951) (xy 142.009078 -289.787242) (xy 141.974992 -289.743099) (xy 141.947696 -289.694464)
			(xy 141.927773 -289.642373) (xy 141.915647 -289.587936) (xy 141.911576 -289.532314) (xy 137.047478 -289.532314)
			(xy 137.047478 -292.732714) (xy 141.911576 -292.732714) (xy 141.915647 -292.677092) (xy 141.927773 -292.622655)
			(xy 141.947696 -292.570564) (xy 141.974992 -292.521929) (xy 142.009078 -292.477786) (xy 142.049227 -292.439077)
			(xy 142.094585 -292.406626) (xy 142.144185 -292.381125) (xy 142.196969 -292.363118) (xy 142.251812 -292.352988)
			(xy 142.307546 -292.350951) (xy 142.362983 -292.357051) (xy 142.41694 -292.371157) (xy 142.468269 -292.392969)
			(xy 142.515875 -292.422023) (xy 142.558743 -292.457698) (xy 142.59596 -292.499235) (xy 142.626733 -292.545748)
			(xy 142.650405 -292.596245) (xy 142.666473 -292.649652) (xy 142.674593 -292.704828) (xy 142.675102 -292.732714)
			(xy 142.674593 -292.7606) (xy 142.666473 -292.815776) (xy 142.650405 -292.869183) (xy 142.626733 -292.91968)
			(xy 142.59596 -292.966193) (xy 142.558743 -293.00773) (xy 142.515875 -293.043405) (xy 142.468269 -293.072459)
			(xy 142.41694 -293.094271) (xy 142.362983 -293.108377) (xy 142.307546 -293.114477) (xy 142.251812 -293.11244)
			(xy 142.196969 -293.10231) (xy 142.144185 -293.084303) (xy 142.094585 -293.058802) (xy 142.049227 -293.026351)
			(xy 142.009078 -292.987642) (xy 141.974992 -292.943499) (xy 141.947696 -292.894864) (xy 141.927773 -292.842773)
			(xy 141.915647 -292.788336) (xy 141.911576 -292.732714) (xy 137.047478 -292.732714) (xy 137.047478 -295.933114)
			(xy 141.911576 -295.933114) (xy 141.915647 -295.877492) (xy 141.927773 -295.823055) (xy 141.947696 -295.770964)
			(xy 141.974992 -295.722329) (xy 142.009078 -295.678186) (xy 142.049227 -295.639477) (xy 142.094585 -295.607026)
			(xy 142.144185 -295.581525) (xy 142.196969 -295.563518) (xy 142.251812 -295.553388) (xy 142.307546 -295.551351)
			(xy 142.362983 -295.557451) (xy 142.41694 -295.571557) (xy 142.468269 -295.593369) (xy 142.515875 -295.622423)
			(xy 142.558743 -295.658098) (xy 142.59596 -295.699635) (xy 142.626733 -295.746148) (xy 142.650405 -295.796645)
			(xy 142.666473 -295.850052) (xy 142.674593 -295.905228) (xy 142.675102 -295.933114) (xy 142.674593 -295.961)
			(xy 142.666473 -296.016176) (xy 142.650405 -296.069583) (xy 142.626733 -296.12008) (xy 142.59596 -296.166593)
			(xy 142.558743 -296.20813) (xy 142.515875 -296.243805) (xy 142.468269 -296.272859) (xy 142.41694 -296.294671)
			(xy 142.362983 -296.308777) (xy 142.307546 -296.314877) (xy 142.251812 -296.31284) (xy 142.196969 -296.30271)
			(xy 142.144185 -296.284703) (xy 142.094585 -296.259202) (xy 142.049227 -296.226751) (xy 142.009078 -296.188042)
			(xy 141.974992 -296.143899) (xy 141.947696 -296.095264) (xy 141.927773 -296.043173) (xy 141.915647 -295.988736)
			(xy 141.911576 -295.933114) (xy 137.047478 -295.933114) (xy 137.047478 -300.813724) (xy 137.047938 -300.823601)
			(xy 137.055381 -300.8419) (xy 137.061956 -300.849284) (xy 137.06221 -300.849538) (xy 137.712958 -301.500286)
			(xy 137.713466 -301.500794) (xy 137.72085 -301.50737) (xy 137.739148 -301.514809) (xy 137.749026 -301.515272)
		)
		(stroke
			(width 0)
			(type solid)
		)
		(fill yes)
		(layer "In11.Cu")
		(net "P1V8_PLL0_PEX1")
	)
	(gr_poly
		(pts
			(xy 348.541848 -224.642934) (xy 348.55097 -224.642611) (xy 348.568082 -224.636296) (xy 348.581867 -224.624352)
			(xy 348.586552 -224.616518) (xy 348.60103 -224.589848) (xy 348.606488 -224.57849) (xy 348.60674 -224.553321)
			(xy 348.601538 -224.541842) (xy 348.589403 -224.517835) (xy 348.572211 -224.466869) (xy 348.563467 -224.413796)
			(xy 348.56293 -224.386902) (xy 348.56344 -224.360915) (xy 348.57157 -224.30958) (xy 348.587631 -224.26015)
			(xy 348.611227 -224.21384) (xy 348.641777 -224.171792) (xy 348.678528 -224.135041) (xy 348.720576 -224.104491)
			(xy 348.766886 -224.080895) (xy 348.816316 -224.064834) (xy 348.867651 -224.056704) (xy 348.919625 -224.056704)
			(xy 348.97096 -224.064834) (xy 349.02039 -224.080895) (xy 349.0667 -224.104491) (xy 349.108748 -224.135041)
			(xy 349.145499 -224.171792) (xy 349.176049 -224.21384) (xy 349.199645 -224.26015) (xy 349.215706 -224.30958)
			(xy 349.223836 -224.360915) (xy 349.224346 -224.386902) (xy 349.223677 -224.417122) (xy 349.212687 -224.476553)
			(xy 349.202502 -224.505012) (xy 349.19793 -224.51695) (xy 349.200978 -224.541588) (xy 349.255588 -224.620836)
			(xy 349.263116 -224.630727) (xy 349.285083 -224.642301) (xy 349.297498 -224.642934) (xy 350.089724 -224.642934)
			(xy 350.102136 -224.642309) (xy 350.124086 -224.630712) (xy 350.131634 -224.620836) (xy 350.186244 -224.541588)
			(xy 350.189292 -224.51695) (xy 350.18472 -224.505012) (xy 350.174553 -224.476548) (xy 350.163554 -224.41712)
			(xy 350.162876 -224.386902) (xy 350.163386 -224.360915) (xy 350.171516 -224.30958) (xy 350.187577 -224.26015)
			(xy 350.211173 -224.21384) (xy 350.241723 -224.171792) (xy 350.278474 -224.135041) (xy 350.320522 -224.104491)
			(xy 350.366832 -224.080895) (xy 350.416262 -224.064834) (xy 350.467597 -224.056704) (xy 350.519571 -224.056704)
			(xy 350.570906 -224.064834) (xy 350.620336 -224.080895) (xy 350.666646 -224.104491) (xy 350.708694 -224.135041)
			(xy 350.745445 -224.171792) (xy 350.775995 -224.21384) (xy 350.799591 -224.26015) (xy 350.815652 -224.30958)
			(xy 350.823782 -224.360915) (xy 350.824292 -224.386902) (xy 350.823623 -224.417122) (xy 350.812634 -224.476553)
			(xy 350.802448 -224.505012) (xy 350.797876 -224.51695) (xy 350.800924 -224.541588) (xy 350.855534 -224.620836)
			(xy 350.863059 -224.630736) (xy 350.885025 -224.642333) (xy 350.897444 -224.642934) (xy 350.941894 -224.642934)
			(xy 350.951012 -224.642603) (xy 350.968111 -224.636278) (xy 350.981883 -224.624331) (xy 350.986598 -224.616518)
			(xy 351.001076 -224.589848) (xy 351.006538 -224.578491) (xy 351.006791 -224.55332) (xy 351.001584 -224.541842)
			(xy 350.989448 -224.517836) (xy 350.972253 -224.466869) (xy 350.963508 -224.413796) (xy 350.962976 -224.386902)
			(xy 350.963486 -224.360915) (xy 350.971616 -224.30958) (xy 350.987677 -224.26015) (xy 351.011273 -224.21384)
			(xy 351.041823 -224.171792) (xy 351.078574 -224.135041) (xy 351.120622 -224.104491) (xy 351.166932 -224.080895)
			(xy 351.216362 -224.064834) (xy 351.267697 -224.056704) (xy 351.319671 -224.056704) (xy 351.371006 -224.064834)
			(xy 351.420436 -224.080895) (xy 351.466746 -224.104491) (xy 351.508794 -224.135041) (xy 351.545545 -224.171792)
			(xy 351.576095 -224.21384) (xy 351.599691 -224.26015) (xy 351.615752 -224.30958) (xy 351.623882 -224.360915)
			(xy 351.624392 -224.386902) (xy 351.623723 -224.417122) (xy 351.612734 -224.476553) (xy 351.602548 -224.505012)
			(xy 351.597976 -224.51695) (xy 351.601024 -224.541588) (xy 351.655634 -224.620836) (xy 351.663159 -224.630736)
			(xy 351.685125 -224.642333) (xy 351.697544 -224.642934) (xy 352.822256 -224.642934) (xy 352.83232 -224.642499)
			(xy 352.850904 -224.634763) (xy 352.858324 -224.627948) (xy 352.891852 -224.59442) (xy 352.896932 -224.590102)
			(xy 352.980498 -224.526094) (xy 352.985578 -224.521522) (xy 354.179378 -223.327722) (xy 354.179886 -223.327214)
			(xy 354.18646 -223.31983) (xy 354.193893 -223.301531) (xy 354.194364 -223.291654) (xy 354.194364 -222.845376)
			(xy 354.194244 -222.840828) (xy 354.19259 -222.831881) (xy 354.191062 -222.827596) (xy 354.182172 -222.80372)
			(xy 354.176838 -222.797116) (xy 354.16116 -222.777262) (xy 354.134629 -222.734189) (xy 354.114023 -222.687986)
			(xy 354.099707 -222.639465) (xy 354.09193 -222.589478) (xy 354.090986 -222.564198) (xy 354.090986 -222.558356)
			(xy 354.090986 -222.555816) (xy 354.091395 -222.529684) (xy 354.098493 -222.477906) (xy 354.1126 -222.427584)
			(xy 354.13345 -222.379661) (xy 354.160654 -222.335037) (xy 354.176838 -222.314516) (xy 354.182172 -222.307912)
			(xy 354.191062 -222.284036) (xy 354.192586 -222.279749) (xy 354.194255 -222.270805) (xy 354.194364 -222.266256)
			(xy 354.194364 -213.946232) (xy 354.193928 -213.936168) (xy 354.186192 -213.917585) (xy 354.179378 -213.910164)
			(xy 353.771454 -213.50224) (xy 353.764342 -213.494874) (xy 353.745546 -213.487254) (xy 351.510854 -213.487254)
			(xy 351.492312 -213.479634) (xy 351.486724 -213.474046) (xy 351.471484 -213.474046) (xy 351.465332 -213.474221)
			(xy 351.453392 -213.477185) (xy 351.447862 -213.479888) (xy 351.423955 -213.491893) (xy 351.373229 -213.508876)
			(xy 351.320431 -213.517479) (xy 351.266937 -213.517479) (xy 351.214139 -213.508876) (xy 351.163413 -213.491893)
			(xy 351.139506 -213.479888) (xy 351.134172 -213.477094) (xy 351.122234 -213.474046) (xy 350.665034 -213.474046)
			(xy 350.653096 -213.477094) (xy 350.647762 -213.479888) (xy 350.623855 -213.491893) (xy 350.573129 -213.508876)
			(xy 350.520331 -213.517479) (xy 350.466837 -213.517479) (xy 350.414039 -213.508876) (xy 350.363313 -213.491893)
			(xy 350.339406 -213.479888) (xy 350.334072 -213.477094) (xy 350.322134 -213.474046) (xy 349.865188 -213.474046)
			(xy 349.85325 -213.477094) (xy 349.847916 -213.479888) (xy 349.824009 -213.491893) (xy 349.773283 -213.508876)
			(xy 349.720485 -213.517479) (xy 349.666991 -213.517479) (xy 349.614193 -213.508876) (xy 349.563467 -213.491893)
			(xy 349.53956 -213.479888) (xy 349.534226 -213.477094) (xy 349.522288 -213.474046) (xy 349.065088 -213.474046)
			(xy 349.05315 -213.477094) (xy 349.047562 -213.479888) (xy 349.019876 -213.492842) (xy 349.010478 -213.496652)
			(xy 348.989904 -213.517226) (xy 348.981462 -213.526523) (xy 348.974147 -213.550514) (xy 348.975934 -213.562946)
			(xy 348.994476 -213.658196) (xy 349.010478 -213.677754) (xy 349.022162 -213.68258) (xy 349.044316 -213.692405)
			(xy 349.085726 -213.717581) (xy 349.123024 -213.748524) (xy 349.155414 -213.784573) (xy 349.182204 -213.824957)
			(xy 349.202823 -213.868814) (xy 349.216829 -213.915209) (xy 349.223924 -213.963149) (xy 349.224346 -213.98738)
			(xy 349.223838 -214.013367) (xy 350.163386 -214.013367) (xy 350.163386 -213.961393) (xy 350.171516 -213.910058)
			(xy 350.187577 -213.860628) (xy 350.211173 -213.814318) (xy 350.241723 -213.77227) (xy 350.278474 -213.735519)
			(xy 350.320522 -213.704969) (xy 350.366832 -213.681373) (xy 350.416262 -213.665312) (xy 350.467597 -213.657182)
			(xy 350.519571 -213.657182) (xy 350.570906 -213.665312) (xy 350.620336 -213.681373) (xy 350.666646 -213.704969)
			(xy 350.708694 -213.735519) (xy 350.745445 -213.77227) (xy 350.775995 -213.814318) (xy 350.799591 -213.860628)
			(xy 350.815652 -213.910058) (xy 350.823782 -213.961393) (xy 350.824292 -213.98738) (xy 350.823782 -214.013367)
			(xy 350.963486 -214.013367) (xy 350.963486 -213.961393) (xy 350.971616 -213.910058) (xy 350.987677 -213.860628)
			(xy 351.011273 -213.814318) (xy 351.041823 -213.77227) (xy 351.078574 -213.735519) (xy 351.120622 -213.704969)
			(xy 351.166932 -213.681373) (xy 351.216362 -213.665312) (xy 351.267697 -213.657182) (xy 351.319671 -213.657182)
			(xy 351.371006 -213.665312) (xy 351.420436 -213.681373) (xy 351.466746 -213.704969) (xy 351.508794 -213.735519)
			(xy 351.545545 -213.77227) (xy 351.576095 -213.814318) (xy 351.599691 -213.860628) (xy 351.615752 -213.910058)
			(xy 351.623882 -213.961393) (xy 351.624392 -213.98738) (xy 351.623882 -214.013367) (xy 351.615752 -214.064702)
			(xy 351.599691 -214.114132) (xy 351.576095 -214.160442) (xy 351.545545 -214.20249) (xy 351.508794 -214.239241)
			(xy 351.466746 -214.269791) (xy 351.420436 -214.293387) (xy 351.371006 -214.309448) (xy 351.319671 -214.317578)
			(xy 351.267697 -214.317578) (xy 351.216362 -214.309448) (xy 351.166932 -214.293387) (xy 351.120622 -214.269791)
			(xy 351.078574 -214.239241) (xy 351.041823 -214.20249) (xy 351.011273 -214.160442) (xy 350.987677 -214.114132)
			(xy 350.971616 -214.064702) (xy 350.963486 -214.013367) (xy 350.823782 -214.013367) (xy 350.815652 -214.064702)
			(xy 350.799591 -214.114132) (xy 350.775995 -214.160442) (xy 350.745445 -214.20249) (xy 350.708694 -214.239241)
			(xy 350.666646 -214.269791) (xy 350.620336 -214.293387) (xy 350.570906 -214.309448) (xy 350.519571 -214.317578)
			(xy 350.467597 -214.317578) (xy 350.416262 -214.309448) (xy 350.366832 -214.293387) (xy 350.320522 -214.269791)
			(xy 350.278474 -214.239241) (xy 350.241723 -214.20249) (xy 350.211173 -214.160442) (xy 350.187577 -214.114132)
			(xy 350.171516 -214.064702) (xy 350.163386 -214.013367) (xy 349.223838 -214.013367) (xy 349.223838 -214.013369)
			(xy 349.21571 -214.064708) (xy 349.199651 -214.114144) (xy 349.176057 -214.160459) (xy 349.145508 -214.202513)
			(xy 349.108757 -214.239271) (xy 349.066709 -214.269827) (xy 349.020398 -214.293429) (xy 348.970965 -214.309497)
			(xy 348.919627 -214.317633) (xy 348.893638 -214.318088) (xy 348.869404 -214.317667) (xy 348.821453 -214.3106)
			(xy 348.775047 -214.296611) (xy 348.73118 -214.276) (xy 348.690789 -214.249208) (xy 348.654741 -214.216809)
			(xy 348.623806 -214.179496) (xy 348.598648 -214.138068) (xy 348.588838 -214.115904) (xy 348.584012 -214.10422)
			(xy 348.564454 -214.088218) (xy 348.469204 -214.069676) (xy 348.456781 -214.067941) (xy 348.43282 -214.075268)
			(xy 348.423484 -214.083646) (xy 348.403164 -214.103966) (xy 348.399354 -214.113364) (xy 348.388951 -214.137329)
			(xy 348.361711 -214.181907) (xy 348.327802 -214.221648) (xy 348.288068 -214.255566) (xy 348.243497 -214.282816)
			(xy 348.219522 -214.293196) (xy 348.210124 -214.297006) (xy 348.190058 -214.317072) (xy 348.181597 -214.326364)
			(xy 348.174249 -214.350362) (xy 348.176088 -214.362792) (xy 348.19463 -214.458042) (xy 348.210378 -214.4776)
			(xy 348.222316 -214.48268) (xy 348.244447 -214.4925) (xy 348.285811 -214.517661) (xy 348.323067 -214.548582)
			(xy 348.355419 -214.584602) (xy 348.382176 -214.624952) (xy 348.402767 -214.668771) (xy 348.416753 -214.715123)
			(xy 348.423834 -214.763018) (xy 348.424246 -214.787226) (xy 348.423735 -214.813213) (xy 348.56344 -214.813213)
			(xy 348.56344 -214.761239) (xy 348.57157 -214.709904) (xy 348.587631 -214.660474) (xy 348.611227 -214.614164)
			(xy 348.641777 -214.572116) (xy 348.678528 -214.535365) (xy 348.720576 -214.504815) (xy 348.766886 -214.481219)
			(xy 348.816316 -214.465158) (xy 348.867651 -214.457028) (xy 348.919625 -214.457028) (xy 348.97096 -214.465158)
			(xy 349.02039 -214.481219) (xy 349.0667 -214.504815) (xy 349.108748 -214.535365) (xy 349.145499 -214.572116)
			(xy 349.176049 -214.614164) (xy 349.199645 -214.660474) (xy 349.215706 -214.709904) (xy 349.223836 -214.761239)
			(xy 349.224346 -214.787226) (xy 349.223836 -214.813213) (xy 349.36354 -214.813213) (xy 349.36354 -214.761239)
			(xy 349.37167 -214.709904) (xy 349.387731 -214.660474) (xy 349.411327 -214.614164) (xy 349.441877 -214.572116)
			(xy 349.478628 -214.535365) (xy 349.520676 -214.504815) (xy 349.566986 -214.481219) (xy 349.616416 -214.465158)
			(xy 349.667751 -214.457028) (xy 349.719725 -214.457028) (xy 349.77106 -214.465158) (xy 349.82049 -214.481219)
			(xy 349.8668 -214.504815) (xy 349.908848 -214.535365) (xy 349.945599 -214.572116) (xy 349.976149 -214.614164)
			(xy 349.999745 -214.660474) (xy 350.015806 -214.709904) (xy 350.023936 -214.761239) (xy 350.024446 -214.787226)
			(xy 350.023936 -214.813213) (xy 350.163386 -214.813213) (xy 350.163386 -214.761239) (xy 350.171516 -214.709904)
			(xy 350.187577 -214.660474) (xy 350.211173 -214.614164) (xy 350.241723 -214.572116) (xy 350.278474 -214.535365)
			(xy 350.320522 -214.504815) (xy 350.366832 -214.481219) (xy 350.416262 -214.465158) (xy 350.467597 -214.457028)
			(xy 350.519571 -214.457028) (xy 350.570906 -214.465158) (xy 350.620336 -214.481219) (xy 350.666646 -214.504815)
			(xy 350.708694 -214.535365) (xy 350.745445 -214.572116) (xy 350.775995 -214.614164) (xy 350.799591 -214.660474)
			(xy 350.815652 -214.709904) (xy 350.823782 -214.761239) (xy 350.824292 -214.787226) (xy 350.823782 -214.813213)
			(xy 350.963486 -214.813213) (xy 350.963486 -214.761239) (xy 350.971616 -214.709904) (xy 350.987677 -214.660474)
			(xy 351.011273 -214.614164) (xy 351.041823 -214.572116) (xy 351.078574 -214.535365) (xy 351.120622 -214.504815)
			(xy 351.166932 -214.481219) (xy 351.216362 -214.465158) (xy 351.267697 -214.457028) (xy 351.319671 -214.457028)
			(xy 351.371006 -214.465158) (xy 351.420436 -214.481219) (xy 351.466746 -214.504815) (xy 351.508794 -214.535365)
			(xy 351.545545 -214.572116) (xy 351.576095 -214.614164) (xy 351.599691 -214.660474) (xy 351.615752 -214.709904)
			(xy 351.623882 -214.761239) (xy 351.624392 -214.787226) (xy 351.623882 -214.813213) (xy 351.615752 -214.864548)
			(xy 351.599691 -214.913978) (xy 351.576095 -214.960288) (xy 351.545545 -215.002336) (xy 351.508794 -215.039087)
			(xy 351.466746 -215.069637) (xy 351.420436 -215.093233) (xy 351.371006 -215.109294) (xy 351.319671 -215.117424)
			(xy 351.267697 -215.117424) (xy 351.216362 -215.109294) (xy 351.166932 -215.093233) (xy 351.120622 -215.069637)
			(xy 351.078574 -215.039087) (xy 351.041823 -215.002336) (xy 351.011273 -214.960288) (xy 350.987677 -214.913978)
			(xy 350.971616 -214.864548) (xy 350.963486 -214.813213) (xy 350.823782 -214.813213) (xy 350.815652 -214.864548)
			(xy 350.799591 -214.913978) (xy 350.775995 -214.960288) (xy 350.745445 -215.002336) (xy 350.708694 -215.039087)
			(xy 350.666646 -215.069637) (xy 350.620336 -215.093233) (xy 350.570906 -215.109294) (xy 350.519571 -215.117424)
			(xy 350.467597 -215.117424) (xy 350.416262 -215.109294) (xy 350.366832 -215.093233) (xy 350.320522 -215.069637)
			(xy 350.278474 -215.039087) (xy 350.241723 -215.002336) (xy 350.211173 -214.960288) (xy 350.187577 -214.913978)
			(xy 350.171516 -214.864548) (xy 350.163386 -214.813213) (xy 350.023936 -214.813213) (xy 350.015806 -214.864548)
			(xy 349.999745 -214.913978) (xy 349.976149 -214.960288) (xy 349.945599 -215.002336) (xy 349.908848 -215.039087)
			(xy 349.8668 -215.069637) (xy 349.82049 -215.093233) (xy 349.77106 -215.109294) (xy 349.719725 -215.117424)
			(xy 349.667751 -215.117424) (xy 349.616416 -215.109294) (xy 349.566986 -215.093233) (xy 349.520676 -215.069637)
			(xy 349.478628 -215.039087) (xy 349.441877 -215.002336) (xy 349.411327 -214.960288) (xy 349.387731 -214.913978)
			(xy 349.37167 -214.864548) (xy 349.36354 -214.813213) (xy 349.223836 -214.813213) (xy 349.215706 -214.864548)
			(xy 349.199645 -214.913978) (xy 349.176049 -214.960288) (xy 349.145499 -215.002336) (xy 349.108748 -215.039087)
			(xy 349.0667 -215.069637) (xy 349.02039 -215.093233) (xy 348.97096 -215.109294) (xy 348.919625 -215.117424)
			(xy 348.867651 -215.117424) (xy 348.816316 -215.109294) (xy 348.766886 -215.093233) (xy 348.720576 -215.069637)
			(xy 348.678528 -215.039087) (xy 348.641777 -215.002336) (xy 348.611227 -214.960288) (xy 348.587631 -214.913978)
			(xy 348.57157 -214.864548) (xy 348.56344 -214.813213) (xy 348.423735 -214.813213) (xy 348.415601 -214.864546)
			(xy 348.399538 -214.913976) (xy 348.375942 -214.960285) (xy 348.345392 -215.002332) (xy 348.308642 -215.039084)
			(xy 348.266595 -215.069635) (xy 348.220287 -215.093234) (xy 348.170858 -215.109298) (xy 348.119525 -215.117434)
			(xy 348.093538 -215.117934) (xy 348.069328 -215.117514) (xy 348.021427 -215.110455) (xy 347.975067 -215.096484)
			(xy 347.931242 -215.075899) (xy 347.890889 -215.049141) (xy 347.854871 -215.016781) (xy 347.82396 -214.979513)
			(xy 347.798816 -214.938135) (xy 347.788992 -214.916004) (xy 347.783912 -214.904066) (xy 347.764354 -214.888318)
			(xy 347.669104 -214.869776) (xy 347.656681 -214.868041) (xy 347.63272 -214.875368) (xy 347.623384 -214.883746)
			(xy 347.603318 -214.903812) (xy 347.599508 -214.91321) (xy 347.589101 -214.937171) (xy 347.561855 -214.981741)
			(xy 347.527942 -215.021473) (xy 347.488205 -215.055381) (xy 347.443632 -215.082621) (xy 347.419676 -215.093042)
			(xy 347.410278 -215.096852) (xy 347.389958 -215.117172) (xy 347.381497 -215.126464) (xy 347.374149 -215.150462)
			(xy 347.375988 -215.162892) (xy 347.39453 -215.258142) (xy 347.410532 -215.2777) (xy 347.422216 -215.282526)
			(xy 347.444371 -215.29235) (xy 347.485781 -215.317524) (xy 347.52308 -215.348466) (xy 347.55547 -215.384515)
			(xy 347.582259 -215.4249) (xy 347.602875 -215.468759) (xy 347.616877 -215.515154) (xy 347.623967 -215.563095)
			(xy 347.6244 -215.587326) (xy 347.623889 -215.613312) (xy 347.623889 -215.613313) (xy 347.76334 -215.613313)
			(xy 347.76334 -215.561339) (xy 347.77147 -215.510004) (xy 347.787531 -215.460574) (xy 347.811127 -215.414264)
			(xy 347.841677 -215.372216) (xy 347.878428 -215.335465) (xy 347.920476 -215.304915) (xy 347.966786 -215.281319)
			(xy 348.016216 -215.265258) (xy 348.067551 -215.257128) (xy 348.119525 -215.257128) (xy 348.17086 -215.265258)
			(xy 348.22029 -215.281319) (xy 348.2666 -215.304915) (xy 348.308648 -215.335465) (xy 348.345399 -215.372216)
			(xy 348.375949 -215.414264) (xy 348.399545 -215.460574) (xy 348.415606 -215.510004) (xy 348.423736 -215.561339)
			(xy 348.424246 -215.587326) (xy 348.423736 -215.613313) (xy 348.56344 -215.613313) (xy 348.56344 -215.561339)
			(xy 348.57157 -215.510004) (xy 348.587631 -215.460574) (xy 348.611227 -215.414264) (xy 348.641777 -215.372216)
			(xy 348.678528 -215.335465) (xy 348.720576 -215.304915) (xy 348.766886 -215.281319) (xy 348.816316 -215.265258)
			(xy 348.867651 -215.257128) (xy 348.919625 -215.257128) (xy 348.97096 -215.265258) (xy 349.02039 -215.281319)
			(xy 349.0667 -215.304915) (xy 349.108748 -215.335465) (xy 349.145499 -215.372216) (xy 349.176049 -215.414264)
			(xy 349.199645 -215.460574) (xy 349.215706 -215.510004) (xy 349.223836 -215.561339) (xy 349.224346 -215.587326)
			(xy 349.223836 -215.613313) (xy 349.36354 -215.613313) (xy 349.36354 -215.561339) (xy 349.37167 -215.510004)
			(xy 349.387731 -215.460574) (xy 349.411327 -215.414264) (xy 349.441877 -215.372216) (xy 349.478628 -215.335465)
			(xy 349.520676 -215.304915) (xy 349.566986 -215.281319) (xy 349.616416 -215.265258) (xy 349.667751 -215.257128)
			(xy 349.719725 -215.257128) (xy 349.77106 -215.265258) (xy 349.82049 -215.281319) (xy 349.8668 -215.304915)
			(xy 349.908848 -215.335465) (xy 349.945599 -215.372216) (xy 349.976149 -215.414264) (xy 349.999745 -215.460574)
			(xy 350.015806 -215.510004) (xy 350.023936 -215.561339) (xy 350.024446 -215.587326) (xy 350.023936 -215.613313)
			(xy 350.163386 -215.613313) (xy 350.163386 -215.561339) (xy 350.171516 -215.510004) (xy 350.187577 -215.460574)
			(xy 350.211173 -215.414264) (xy 350.241723 -215.372216) (xy 350.278474 -215.335465) (xy 350.320522 -215.304915)
			(xy 350.366832 -215.281319) (xy 350.416262 -215.265258) (xy 350.467597 -215.257128) (xy 350.519571 -215.257128)
			(xy 350.570906 -215.265258) (xy 350.620336 -215.281319) (xy 350.666646 -215.304915) (xy 350.708694 -215.335465)
			(xy 350.745445 -215.372216) (xy 350.775995 -215.414264) (xy 350.799591 -215.460574) (xy 350.815652 -215.510004)
			(xy 350.823782 -215.561339) (xy 350.824292 -215.587326) (xy 350.823782 -215.613313) (xy 350.815652 -215.664648)
			(xy 350.799591 -215.714078) (xy 350.775995 -215.760388) (xy 350.745445 -215.802436) (xy 350.708694 -215.839187)
			(xy 350.666646 -215.869737) (xy 350.620336 -215.893333) (xy 350.570906 -215.909394) (xy 350.519571 -215.917524)
			(xy 350.467597 -215.917524) (xy 350.416262 -215.909394) (xy 350.366832 -215.893333) (xy 350.320522 -215.869737)
			(xy 350.278474 -215.839187) (xy 350.241723 -215.802436) (xy 350.211173 -215.760388) (xy 350.187577 -215.714078)
			(xy 350.171516 -215.664648) (xy 350.163386 -215.613313) (xy 350.023936 -215.613313) (xy 350.015806 -215.664648)
			(xy 349.999745 -215.714078) (xy 349.976149 -215.760388) (xy 349.945599 -215.802436) (xy 349.908848 -215.839187)
			(xy 349.8668 -215.869737) (xy 349.82049 -215.893333) (xy 349.77106 -215.909394) (xy 349.719725 -215.917524)
			(xy 349.667751 -215.917524) (xy 349.616416 -215.909394) (xy 349.566986 -215.893333) (xy 349.520676 -215.869737)
			(xy 349.478628 -215.839187) (xy 349.441877 -215.802436) (xy 349.411327 -215.760388) (xy 349.387731 -215.714078)
			(xy 349.37167 -215.664648) (xy 349.36354 -215.613313) (xy 349.223836 -215.613313) (xy 349.215706 -215.664648)
			(xy 349.199645 -215.714078) (xy 349.176049 -215.760388) (xy 349.145499 -215.802436) (xy 349.108748 -215.839187)
			(xy 349.0667 -215.869737) (xy 349.02039 -215.893333) (xy 348.97096 -215.909394) (xy 348.919625 -215.917524)
			(xy 348.867651 -215.917524) (xy 348.816316 -215.909394) (xy 348.766886 -215.893333) (xy 348.720576 -215.869737)
			(xy 348.678528 -215.839187) (xy 348.641777 -215.802436) (xy 348.611227 -215.760388) (xy 348.587631 -215.714078)
			(xy 348.57157 -215.664648) (xy 348.56344 -215.613313) (xy 348.423736 -215.613313) (xy 348.415606 -215.664648)
			(xy 348.399545 -215.714078) (xy 348.375949 -215.760388) (xy 348.345399 -215.802436) (xy 348.308648 -215.839187)
			(xy 348.2666 -215.869737) (xy 348.22029 -215.893333) (xy 348.17086 -215.909394) (xy 348.119525 -215.917524)
			(xy 348.067551 -215.917524) (xy 348.016216 -215.909394) (xy 347.966786 -215.893333) (xy 347.920476 -215.869737)
			(xy 347.878428 -215.839187) (xy 347.841677 -215.802436) (xy 347.811127 -215.760388) (xy 347.787531 -215.714078)
			(xy 347.77147 -215.664648) (xy 347.76334 -215.613313) (xy 347.623889 -215.613313) (xy 347.615755 -215.664642)
			(xy 347.599691 -215.714069) (xy 347.576094 -215.760374) (xy 347.545544 -215.802418) (xy 347.508792 -215.839166)
			(xy 347.466745 -215.869712) (xy 347.420438 -215.893304) (xy 347.371009 -215.909363) (xy 347.319678 -215.917491)
			(xy 347.293692 -215.918034) (xy 347.269456 -215.917616) (xy 347.221503 -215.910555) (xy 347.175093 -215.89657)
			(xy 347.131222 -215.875961) (xy 347.090828 -215.849169) (xy 347.054778 -215.816769) (xy 347.023843 -215.779453)
			(xy 346.998685 -215.738022) (xy 346.988892 -215.71585) (xy 346.984066 -215.704166) (xy 346.964508 -215.688164)
			(xy 346.869258 -215.669622) (xy 346.856831 -215.667873) (xy 346.832856 -215.675188) (xy 346.823538 -215.683592)
			(xy 346.803218 -215.703912) (xy 346.799408 -215.71331) (xy 346.789001 -215.737271) (xy 346.761755 -215.781841)
			(xy 346.727842 -215.821573) (xy 346.688105 -215.855481) (xy 346.643532 -215.882721) (xy 346.619576 -215.893142)
			(xy 346.610178 -215.896952) (xy 346.590112 -215.917018) (xy 346.581667 -215.926315) (xy 346.574348 -215.950306)
			(xy 346.576142 -215.962738) (xy 346.594684 -216.057988) (xy 346.610432 -216.077546) (xy 346.62237 -216.082626)
			(xy 346.644501 -216.092445) (xy 346.685867 -216.117604) (xy 346.723123 -216.148524) (xy 346.755475 -216.184544)
			(xy 346.782231 -216.224895) (xy 346.80282 -216.268715) (xy 346.816801 -216.315068) (xy 346.823877 -216.362964)
			(xy 346.8243 -216.387172) (xy 346.823819 -216.413159) (xy 346.963494 -216.413159) (xy 346.963494 -216.361185)
			(xy 346.971624 -216.30985) (xy 346.987685 -216.26042) (xy 347.011281 -216.21411) (xy 347.041831 -216.172062)
			(xy 347.078582 -216.135311) (xy 347.12063 -216.104761) (xy 347.16694 -216.081165) (xy 347.21637 -216.065104)
			(xy 347.267705 -216.056974) (xy 347.319679 -216.056974) (xy 347.371014 -216.065104) (xy 347.420444 -216.081165)
			(xy 347.466754 -216.104761) (xy 347.508802 -216.135311) (xy 347.545553 -216.172062) (xy 347.576103 -216.21411)
			(xy 347.599699 -216.26042) (xy 347.61576 -216.30985) (xy 347.62389 -216.361185) (xy 347.6244 -216.387172)
			(xy 347.62389 -216.413159) (xy 347.76334 -216.413159) (xy 347.76334 -216.361185) (xy 347.77147 -216.30985)
			(xy 347.787531 -216.26042) (xy 347.811127 -216.21411) (xy 347.841677 -216.172062) (xy 347.878428 -216.135311)
			(xy 347.920476 -216.104761) (xy 347.966786 -216.081165) (xy 348.016216 -216.065104) (xy 348.067551 -216.056974)
			(xy 348.119525 -216.056974) (xy 348.17086 -216.065104) (xy 348.22029 -216.081165) (xy 348.2666 -216.104761)
			(xy 348.308648 -216.135311) (xy 348.345399 -216.172062) (xy 348.375949 -216.21411) (xy 348.399545 -216.26042)
			(xy 348.415606 -216.30985) (xy 348.423736 -216.361185) (xy 348.424246 -216.387172) (xy 348.423736 -216.413159)
			(xy 348.56344 -216.413159) (xy 348.56344 -216.361185) (xy 348.57157 -216.30985) (xy 348.587631 -216.26042)
			(xy 348.611227 -216.21411) (xy 348.641777 -216.172062) (xy 348.678528 -216.135311) (xy 348.720576 -216.104761)
			(xy 348.766886 -216.081165) (xy 348.816316 -216.065104) (xy 348.867651 -216.056974) (xy 348.919625 -216.056974)
			(xy 348.97096 -216.065104) (xy 349.02039 -216.081165) (xy 349.0667 -216.104761) (xy 349.108748 -216.135311)
			(xy 349.145499 -216.172062) (xy 349.176049 -216.21411) (xy 349.199645 -216.26042) (xy 349.215706 -216.30985)
			(xy 349.223836 -216.361185) (xy 349.224346 -216.387172) (xy 349.223836 -216.413159) (xy 349.36354 -216.413159)
			(xy 349.36354 -216.361185) (xy 349.37167 -216.30985) (xy 349.387731 -216.26042) (xy 349.411327 -216.21411)
			(xy 349.441877 -216.172062) (xy 349.478628 -216.135311) (xy 349.520676 -216.104761) (xy 349.566986 -216.081165)
			(xy 349.616416 -216.065104) (xy 349.667751 -216.056974) (xy 349.719725 -216.056974) (xy 349.77106 -216.065104)
			(xy 349.82049 -216.081165) (xy 349.8668 -216.104761) (xy 349.908848 -216.135311) (xy 349.945599 -216.172062)
			(xy 349.976149 -216.21411) (xy 349.999745 -216.26042) (xy 350.015806 -216.30985) (xy 350.023936 -216.361185)
			(xy 350.024446 -216.387172) (xy 350.023936 -216.413159) (xy 350.163386 -216.413159) (xy 350.163386 -216.361185)
			(xy 350.171516 -216.30985) (xy 350.187577 -216.26042) (xy 350.211173 -216.21411) (xy 350.241723 -216.172062)
			(xy 350.278474 -216.135311) (xy 350.320522 -216.104761) (xy 350.366832 -216.081165) (xy 350.416262 -216.065104)
			(xy 350.467597 -216.056974) (xy 350.519571 -216.056974) (xy 350.570906 -216.065104) (xy 350.620336 -216.081165)
			(xy 350.666646 -216.104761) (xy 350.708694 -216.135311) (xy 350.745445 -216.172062) (xy 350.775995 -216.21411)
			(xy 350.799591 -216.26042) (xy 350.815652 -216.30985) (xy 350.823782 -216.361185) (xy 350.824292 -216.387172)
			(xy 350.823782 -216.413159) (xy 350.963486 -216.413159) (xy 350.963486 -216.361185) (xy 350.971616 -216.30985)
			(xy 350.987677 -216.26042) (xy 351.011273 -216.21411) (xy 351.041823 -216.172062) (xy 351.078574 -216.135311)
			(xy 351.120622 -216.104761) (xy 351.166932 -216.081165) (xy 351.216362 -216.065104) (xy 351.267697 -216.056974)
			(xy 351.319671 -216.056974) (xy 351.371006 -216.065104) (xy 351.420436 -216.081165) (xy 351.466746 -216.104761)
			(xy 351.508794 -216.135311) (xy 351.545545 -216.172062) (xy 351.576095 -216.21411) (xy 351.599691 -216.26042)
			(xy 351.615752 -216.30985) (xy 351.623882 -216.361185) (xy 351.624392 -216.387172) (xy 351.623882 -216.413159)
			(xy 351.615752 -216.464494) (xy 351.599691 -216.513924) (xy 351.576095 -216.560234) (xy 351.545545 -216.602282)
			(xy 351.508794 -216.639033) (xy 351.466746 -216.669583) (xy 351.420436 -216.693179) (xy 351.371006 -216.70924)
			(xy 351.319671 -216.71737) (xy 351.267697 -216.71737) (xy 351.216362 -216.70924) (xy 351.166932 -216.693179)
			(xy 351.120622 -216.669583) (xy 351.078574 -216.639033) (xy 351.041823 -216.602282) (xy 351.011273 -216.560234)
			(xy 350.987677 -216.513924) (xy 350.971616 -216.464494) (xy 350.963486 -216.413159) (xy 350.823782 -216.413159)
			(xy 350.815652 -216.464494) (xy 350.799591 -216.513924) (xy 350.775995 -216.560234) (xy 350.745445 -216.602282)
			(xy 350.708694 -216.639033) (xy 350.666646 -216.669583) (xy 350.620336 -216.693179) (xy 350.570906 -216.70924)
			(xy 350.519571 -216.71737) (xy 350.467597 -216.71737) (xy 350.416262 -216.70924) (xy 350.366832 -216.693179)
			(xy 350.320522 -216.669583) (xy 350.278474 -216.639033) (xy 350.241723 -216.602282) (xy 350.211173 -216.560234)
			(xy 350.187577 -216.513924) (xy 350.171516 -216.464494) (xy 350.163386 -216.413159) (xy 350.023936 -216.413159)
			(xy 350.015806 -216.464494) (xy 349.999745 -216.513924) (xy 349.976149 -216.560234) (xy 349.945599 -216.602282)
			(xy 349.908848 -216.639033) (xy 349.8668 -216.669583) (xy 349.82049 -216.693179) (xy 349.77106 -216.70924)
			(xy 349.719725 -216.71737) (xy 349.667751 -216.71737) (xy 349.616416 -216.70924) (xy 349.566986 -216.693179)
			(xy 349.520676 -216.669583) (xy 349.478628 -216.639033) (xy 349.441877 -216.602282) (xy 349.411327 -216.560234)
			(xy 349.387731 -216.513924) (xy 349.37167 -216.464494) (xy 349.36354 -216.413159) (xy 349.223836 -216.413159)
			(xy 349.215706 -216.464494) (xy 349.199645 -216.513924) (xy 349.176049 -216.560234) (xy 349.145499 -216.602282)
			(xy 349.108748 -216.639033) (xy 349.0667 -216.669583) (xy 349.02039 -216.693179) (xy 348.97096 -216.70924)
			(xy 348.919625 -216.71737) (xy 348.867651 -216.71737) (xy 348.816316 -216.70924) (xy 348.766886 -216.693179)
			(xy 348.720576 -216.669583) (xy 348.678528 -216.639033) (xy 348.641777 -216.602282) (xy 348.611227 -216.560234)
			(xy 348.587631 -216.513924) (xy 348.57157 -216.464494) (xy 348.56344 -216.413159) (xy 348.423736 -216.413159)
			(xy 348.415606 -216.464494) (xy 348.399545 -216.513924) (xy 348.375949 -216.560234) (xy 348.345399 -216.602282)
			(xy 348.308648 -216.639033) (xy 348.2666 -216.669583) (xy 348.22029 -216.693179) (xy 348.17086 -216.70924)
			(xy 348.119525 -216.71737) (xy 348.067551 -216.71737) (xy 348.016216 -216.70924) (xy 347.966786 -216.693179)
			(xy 347.920476 -216.669583) (xy 347.878428 -216.639033) (xy 347.841677 -216.602282) (xy 347.811127 -216.560234)
			(xy 347.787531 -216.513924) (xy 347.77147 -216.464494) (xy 347.76334 -216.413159) (xy 347.62389 -216.413159)
			(xy 347.61576 -216.464494) (xy 347.599699 -216.513924) (xy 347.576103 -216.560234) (xy 347.545553 -216.602282)
			(xy 347.508802 -216.639033) (xy 347.466754 -216.669583) (xy 347.420444 -216.693179) (xy 347.371014 -216.70924)
			(xy 347.319679 -216.71737) (xy 347.267705 -216.71737) (xy 347.21637 -216.70924) (xy 347.16694 -216.693179)
			(xy 347.12063 -216.669583) (xy 347.078582 -216.639033) (xy 347.041831 -216.602282) (xy 347.011281 -216.560234)
			(xy 346.987685 -216.513924) (xy 346.971624 -216.464494) (xy 346.963494 -216.413159) (xy 346.823819 -216.413159)
			(xy 346.823819 -216.413162) (xy 346.815691 -216.464504) (xy 346.799631 -216.513942) (xy 346.776035 -216.560258)
			(xy 346.745483 -216.602313) (xy 346.708728 -216.63907) (xy 346.666675 -216.669624) (xy 346.62036 -216.693224)
			(xy 346.570923 -216.709286) (xy 346.519582 -216.717417) (xy 346.493592 -216.71788) (xy 346.46938 -216.717464)
			(xy 346.421471 -216.710412) (xy 346.375104 -216.696448) (xy 346.33127 -216.675868) (xy 346.290908 -216.649113)
			(xy 346.25488 -216.616757) (xy 346.223958 -216.57949) (xy 346.198804 -216.538112) (xy 346.189046 -216.51595)
			(xy 346.183966 -216.504012) (xy 346.164408 -216.488264) (xy 346.069158 -216.469722) (xy 346.056731 -216.467973)
			(xy 346.032756 -216.475288) (xy 346.023438 -216.483692) (xy 346.003372 -216.503758) (xy 345.999562 -216.513156)
			(xy 345.989159 -216.537122) (xy 345.96192 -216.581701) (xy 345.928013 -216.621444) (xy 345.888279 -216.655364)
			(xy 345.843708 -216.682616) (xy 345.81973 -216.692988) (xy 345.810332 -216.696798) (xy 345.607894 -216.899236)
			(xy 345.602814 -216.903554) (xy 345.519248 -216.967562) (xy 345.514168 -216.972134) (xy 345.368626 -217.117676)
			(xy 345.36126 -217.124788) (xy 345.35364 -217.143584) (xy 345.35364 -217.213259) (xy 346.163394 -217.213259)
			(xy 346.163394 -217.161285) (xy 346.171524 -217.10995) (xy 346.187585 -217.06052) (xy 346.211181 -217.01421)
			(xy 346.241731 -216.972162) (xy 346.278482 -216.935411) (xy 346.32053 -216.904861) (xy 346.36684 -216.881265)
			(xy 346.41627 -216.865204) (xy 346.467605 -216.857074) (xy 346.519579 -216.857074) (xy 346.570914 -216.865204)
			(xy 346.620344 -216.881265) (xy 346.666654 -216.904861) (xy 346.708702 -216.935411) (xy 346.745453 -216.972162)
			(xy 346.776003 -217.01421) (xy 346.799599 -217.06052) (xy 346.81566 -217.10995) (xy 346.82379 -217.161285)
			(xy 346.8243 -217.187272) (xy 346.82379 -217.213259) (xy 346.963494 -217.213259) (xy 346.963494 -217.161285)
			(xy 346.971624 -217.10995) (xy 346.987685 -217.06052) (xy 347.011281 -217.01421) (xy 347.041831 -216.972162)
			(xy 347.078582 -216.935411) (xy 347.12063 -216.904861) (xy 347.16694 -216.881265) (xy 347.21637 -216.865204)
			(xy 347.267705 -216.857074) (xy 347.319679 -216.857074) (xy 347.371014 -216.865204) (xy 347.420444 -216.881265)
			(xy 347.466754 -216.904861) (xy 347.508802 -216.935411) (xy 347.545553 -216.972162) (xy 347.576103 -217.01421)
			(xy 347.599699 -217.06052) (xy 347.61576 -217.10995) (xy 347.62389 -217.161285) (xy 347.6244 -217.187272)
			(xy 347.62389 -217.213259) (xy 347.76334 -217.213259) (xy 347.76334 -217.161285) (xy 347.77147 -217.10995)
			(xy 347.787531 -217.06052) (xy 347.811127 -217.01421) (xy 347.841677 -216.972162) (xy 347.878428 -216.935411)
			(xy 347.920476 -216.904861) (xy 347.966786 -216.881265) (xy 348.016216 -216.865204) (xy 348.067551 -216.857074)
			(xy 348.119525 -216.857074) (xy 348.17086 -216.865204) (xy 348.22029 -216.881265) (xy 348.2666 -216.904861)
			(xy 348.308648 -216.935411) (xy 348.345399 -216.972162) (xy 348.375949 -217.01421) (xy 348.399545 -217.06052)
			(xy 348.415606 -217.10995) (xy 348.423736 -217.161285) (xy 348.424246 -217.187272) (xy 348.423741 -217.213005)
			(xy 348.563694 -217.213005) (xy 348.563694 -217.161031) (xy 348.571824 -217.109696) (xy 348.587885 -217.060266)
			(xy 348.611481 -217.013956) (xy 348.642031 -216.971908) (xy 348.678782 -216.935157) (xy 348.72083 -216.904607)
			(xy 348.76714 -216.881011) (xy 348.81657 -216.86495) (xy 348.867905 -216.85682) (xy 348.919879 -216.85682)
			(xy 348.971214 -216.86495) (xy 349.020644 -216.881011) (xy 349.066954 -216.904607) (xy 349.109002 -216.935157)
			(xy 349.145753 -216.971908) (xy 349.176303 -217.013956) (xy 349.199899 -217.060266) (xy 349.21596 -217.109696)
			(xy 349.22409 -217.161031) (xy 349.2246 -217.187018) (xy 349.22409 -217.213005) (xy 349.22405 -217.213259)
			(xy 349.36354 -217.213259) (xy 349.36354 -217.161285) (xy 349.37167 -217.10995) (xy 349.387731 -217.06052)
			(xy 349.411327 -217.01421) (xy 349.441877 -216.972162) (xy 349.478628 -216.935411) (xy 349.520676 -216.904861)
			(xy 349.566986 -216.881265) (xy 349.616416 -216.865204) (xy 349.667751 -216.857074) (xy 349.719725 -216.857074)
			(xy 349.77106 -216.865204) (xy 349.82049 -216.881265) (xy 349.8668 -216.904861) (xy 349.908848 -216.935411)
			(xy 349.945599 -216.972162) (xy 349.976149 -217.01421) (xy 349.999745 -217.06052) (xy 350.015806 -217.10995)
			(xy 350.023936 -217.161285) (xy 350.024446 -217.187272) (xy 350.023936 -217.213259) (xy 350.163386 -217.213259)
			(xy 350.163386 -217.161285) (xy 350.171516 -217.10995) (xy 350.187577 -217.06052) (xy 350.211173 -217.01421)
			(xy 350.241723 -216.972162) (xy 350.278474 -216.935411) (xy 350.320522 -216.904861) (xy 350.366832 -216.881265)
			(xy 350.416262 -216.865204) (xy 350.467597 -216.857074) (xy 350.519571 -216.857074) (xy 350.570906 -216.865204)
			(xy 350.620336 -216.881265) (xy 350.666646 -216.904861) (xy 350.708694 -216.935411) (xy 350.745445 -216.972162)
			(xy 350.775995 -217.01421) (xy 350.799591 -217.06052) (xy 350.815652 -217.10995) (xy 350.823782 -217.161285)
			(xy 350.824292 -217.187272) (xy 350.823782 -217.213259) (xy 350.815652 -217.264594) (xy 350.799591 -217.314024)
			(xy 350.775995 -217.360334) (xy 350.745445 -217.402382) (xy 350.708694 -217.439133) (xy 350.666646 -217.469683)
			(xy 350.620336 -217.493279) (xy 350.570906 -217.50934) (xy 350.519571 -217.51747) (xy 350.467597 -217.51747)
			(xy 350.416262 -217.50934) (xy 350.366832 -217.493279) (xy 350.320522 -217.469683) (xy 350.278474 -217.439133)
			(xy 350.241723 -217.402382) (xy 350.211173 -217.360334) (xy 350.187577 -217.314024) (xy 350.171516 -217.264594)
			(xy 350.163386 -217.213259) (xy 350.023936 -217.213259) (xy 350.015806 -217.264594) (xy 349.999745 -217.314024)
			(xy 349.976149 -217.360334) (xy 349.945599 -217.402382) (xy 349.908848 -217.439133) (xy 349.8668 -217.469683)
			(xy 349.82049 -217.493279) (xy 349.77106 -217.50934) (xy 349.719725 -217.51747) (xy 349.667751 -217.51747)
			(xy 349.616416 -217.50934) (xy 349.566986 -217.493279) (xy 349.520676 -217.469683) (xy 349.478628 -217.439133)
			(xy 349.441877 -217.402382) (xy 349.411327 -217.360334) (xy 349.387731 -217.314024) (xy 349.37167 -217.264594)
			(xy 349.36354 -217.213259) (xy 349.22405 -217.213259) (xy 349.21596 -217.26434) (xy 349.199899 -217.31377)
			(xy 349.176303 -217.36008) (xy 349.145753 -217.402128) (xy 349.109002 -217.438879) (xy 349.066954 -217.469429)
			(xy 349.020644 -217.493025) (xy 348.971214 -217.509086) (xy 348.919879 -217.517216) (xy 348.867905 -217.517216)
			(xy 348.81657 -217.509086) (xy 348.76714 -217.493025) (xy 348.72083 -217.469429) (xy 348.678782 -217.438879)
			(xy 348.642031 -217.402128) (xy 348.611481 -217.36008) (xy 348.587885 -217.31377) (xy 348.571824 -217.26434)
			(xy 348.563694 -217.213005) (xy 348.423741 -217.213005) (xy 348.423736 -217.213259) (xy 348.415606 -217.264594)
			(xy 348.399545 -217.314024) (xy 348.375949 -217.360334) (xy 348.345399 -217.402382) (xy 348.308648 -217.439133)
			(xy 348.2666 -217.469683) (xy 348.22029 -217.493279) (xy 348.17086 -217.50934) (xy 348.119525 -217.51747)
			(xy 348.067551 -217.51747) (xy 348.016216 -217.50934) (xy 347.966786 -217.493279) (xy 347.920476 -217.469683)
			(xy 347.878428 -217.439133) (xy 347.841677 -217.402382) (xy 347.811127 -217.360334) (xy 347.787531 -217.314024)
			(xy 347.77147 -217.264594) (xy 347.76334 -217.213259) (xy 347.62389 -217.213259) (xy 347.61576 -217.264594)
			(xy 347.599699 -217.314024) (xy 347.576103 -217.360334) (xy 347.545553 -217.402382) (xy 347.508802 -217.439133)
			(xy 347.466754 -217.469683) (xy 347.420444 -217.493279) (xy 347.371014 -217.50934) (xy 347.319679 -217.51747)
			(xy 347.267705 -217.51747) (xy 347.21637 -217.50934) (xy 347.16694 -217.493279) (xy 347.12063 -217.469683)
			(xy 347.078582 -217.439133) (xy 347.041831 -217.402382) (xy 347.011281 -217.360334) (xy 346.987685 -217.314024)
			(xy 346.971624 -217.264594) (xy 346.963494 -217.213259) (xy 346.82379 -217.213259) (xy 346.81566 -217.264594)
			(xy 346.799599 -217.314024) (xy 346.776003 -217.360334) (xy 346.745453 -217.402382) (xy 346.708702 -217.439133)
			(xy 346.666654 -217.469683) (xy 346.620344 -217.493279) (xy 346.570914 -217.50934) (xy 346.519579 -217.51747)
			(xy 346.467605 -217.51747) (xy 346.41627 -217.50934) (xy 346.36684 -217.493279) (xy 346.32053 -217.469683)
			(xy 346.278482 -217.439133) (xy 346.241731 -217.402382) (xy 346.211181 -217.360334) (xy 346.187585 -217.314024)
			(xy 346.171524 -217.264594) (xy 346.163394 -217.213259) (xy 345.35364 -217.213259) (xy 345.35364 -218.013359)
			(xy 346.163394 -218.013359) (xy 346.163394 -217.961385) (xy 346.171524 -217.91005) (xy 346.187585 -217.86062)
			(xy 346.211181 -217.81431) (xy 346.241731 -217.772262) (xy 346.278482 -217.735511) (xy 346.32053 -217.704961)
			(xy 346.36684 -217.681365) (xy 346.41627 -217.665304) (xy 346.467605 -217.657174) (xy 346.519579 -217.657174)
			(xy 346.570914 -217.665304) (xy 346.620344 -217.681365) (xy 346.666654 -217.704961) (xy 346.708702 -217.735511)
			(xy 346.745453 -217.772262) (xy 346.776003 -217.81431) (xy 346.799599 -217.86062) (xy 346.81566 -217.91005)
			(xy 346.82379 -217.961385) (xy 346.8243 -217.987372) (xy 346.82379 -218.013359) (xy 346.963494 -218.013359)
			(xy 346.963494 -217.961385) (xy 346.971624 -217.91005) (xy 346.987685 -217.86062) (xy 347.011281 -217.81431)
			(xy 347.041831 -217.772262) (xy 347.078582 -217.735511) (xy 347.12063 -217.704961) (xy 347.16694 -217.681365)
			(xy 347.21637 -217.665304) (xy 347.267705 -217.657174) (xy 347.319679 -217.657174) (xy 347.371014 -217.665304)
			(xy 347.420444 -217.681365) (xy 347.466754 -217.704961) (xy 347.508802 -217.735511) (xy 347.545553 -217.772262)
			(xy 347.576103 -217.81431) (xy 347.599699 -217.86062) (xy 347.61576 -217.91005) (xy 347.62389 -217.961385)
			(xy 347.6244 -217.987372) (xy 347.62389 -218.013359) (xy 347.76334 -218.013359) (xy 347.76334 -217.961385)
			(xy 347.77147 -217.91005) (xy 347.787531 -217.86062) (xy 347.811127 -217.81431) (xy 347.841677 -217.772262)
			(xy 347.878428 -217.735511) (xy 347.920476 -217.704961) (xy 347.966786 -217.681365) (xy 348.016216 -217.665304)
			(xy 348.067551 -217.657174) (xy 348.119525 -217.657174) (xy 348.17086 -217.665304) (xy 348.22029 -217.681365)
			(xy 348.2666 -217.704961) (xy 348.308648 -217.735511) (xy 348.345399 -217.772262) (xy 348.375949 -217.81431)
			(xy 348.399545 -217.86062) (xy 348.415606 -217.91005) (xy 348.423736 -217.961385) (xy 348.424246 -217.987372)
			(xy 348.423736 -218.013359) (xy 348.56344 -218.013359) (xy 348.56344 -217.961385) (xy 348.57157 -217.91005)
			(xy 348.587631 -217.86062) (xy 348.611227 -217.81431) (xy 348.641777 -217.772262) (xy 348.678528 -217.735511)
			(xy 348.720576 -217.704961) (xy 348.766886 -217.681365) (xy 348.816316 -217.665304) (xy 348.867651 -217.657174)
			(xy 348.919625 -217.657174) (xy 348.97096 -217.665304) (xy 349.02039 -217.681365) (xy 349.0667 -217.704961)
			(xy 349.108748 -217.735511) (xy 349.145499 -217.772262) (xy 349.176049 -217.81431) (xy 349.199645 -217.86062)
			(xy 349.215706 -217.91005) (xy 349.223836 -217.961385) (xy 349.224346 -217.987372) (xy 349.223836 -218.013359)
			(xy 349.36354 -218.013359) (xy 349.36354 -217.961385) (xy 349.37167 -217.91005) (xy 349.387731 -217.86062)
			(xy 349.411327 -217.81431) (xy 349.441877 -217.772262) (xy 349.478628 -217.735511) (xy 349.520676 -217.704961)
			(xy 349.566986 -217.681365) (xy 349.616416 -217.665304) (xy 349.667751 -217.657174) (xy 349.719725 -217.657174)
			(xy 349.77106 -217.665304) (xy 349.82049 -217.681365) (xy 349.8668 -217.704961) (xy 349.908848 -217.735511)
			(xy 349.945599 -217.772262) (xy 349.976149 -217.81431) (xy 349.999745 -217.86062) (xy 350.015806 -217.91005)
			(xy 350.023936 -217.961385) (xy 350.024446 -217.987372) (xy 350.023936 -218.013359) (xy 350.163386 -218.013359)
			(xy 350.163386 -217.961385) (xy 350.171516 -217.91005) (xy 350.187577 -217.86062) (xy 350.211173 -217.81431)
			(xy 350.241723 -217.772262) (xy 350.278474 -217.735511) (xy 350.320522 -217.704961) (xy 350.366832 -217.681365)
			(xy 350.416262 -217.665304) (xy 350.467597 -217.657174) (xy 350.519571 -217.657174) (xy 350.570906 -217.665304)
			(xy 350.620336 -217.681365) (xy 350.666646 -217.704961) (xy 350.708694 -217.735511) (xy 350.745445 -217.772262)
			(xy 350.775995 -217.81431) (xy 350.799591 -217.86062) (xy 350.815652 -217.91005) (xy 350.823782 -217.961385)
			(xy 350.824292 -217.987372) (xy 350.823782 -218.013359) (xy 350.963486 -218.013359) (xy 350.963486 -217.961385)
			(xy 350.971616 -217.91005) (xy 350.987677 -217.86062) (xy 351.011273 -217.81431) (xy 351.041823 -217.772262)
			(xy 351.078574 -217.735511) (xy 351.120622 -217.704961) (xy 351.166932 -217.681365) (xy 351.216362 -217.665304)
			(xy 351.267697 -217.657174) (xy 351.319671 -217.657174) (xy 351.371006 -217.665304) (xy 351.420436 -217.681365)
			(xy 351.466746 -217.704961) (xy 351.508794 -217.735511) (xy 351.545545 -217.772262) (xy 351.576095 -217.81431)
			(xy 351.599691 -217.86062) (xy 351.615752 -217.91005) (xy 351.623882 -217.961385) (xy 351.624392 -217.987372)
			(xy 351.623882 -218.013359) (xy 351.615752 -218.064694) (xy 351.599691 -218.114124) (xy 351.576095 -218.160434)
			(xy 351.545545 -218.202482) (xy 351.508794 -218.239233) (xy 351.466746 -218.269783) (xy 351.420436 -218.293379)
			(xy 351.371006 -218.30944) (xy 351.319671 -218.31757) (xy 351.267697 -218.31757) (xy 351.216362 -218.30944)
			(xy 351.166932 -218.293379) (xy 351.120622 -218.269783) (xy 351.078574 -218.239233) (xy 351.041823 -218.202482)
			(xy 351.011273 -218.160434) (xy 350.987677 -218.114124) (xy 350.971616 -218.064694) (xy 350.963486 -218.013359)
			(xy 350.823782 -218.013359) (xy 350.815652 -218.064694) (xy 350.799591 -218.114124) (xy 350.775995 -218.160434)
			(xy 350.745445 -218.202482) (xy 350.708694 -218.239233) (xy 350.666646 -218.269783) (xy 350.620336 -218.293379)
			(xy 350.570906 -218.30944) (xy 350.519571 -218.31757) (xy 350.467597 -218.31757) (xy 350.416262 -218.30944)
			(xy 350.366832 -218.293379) (xy 350.320522 -218.269783) (xy 350.278474 -218.239233) (xy 350.241723 -218.202482)
			(xy 350.211173 -218.160434) (xy 350.187577 -218.114124) (xy 350.171516 -218.064694) (xy 350.163386 -218.013359)
			(xy 350.023936 -218.013359) (xy 350.015806 -218.064694) (xy 349.999745 -218.114124) (xy 349.976149 -218.160434)
			(xy 349.945599 -218.202482) (xy 349.908848 -218.239233) (xy 349.8668 -218.269783) (xy 349.82049 -218.293379)
			(xy 349.77106 -218.30944) (xy 349.719725 -218.31757) (xy 349.667751 -218.31757) (xy 349.616416 -218.30944)
			(xy 349.566986 -218.293379) (xy 349.520676 -218.269783) (xy 349.478628 -218.239233) (xy 349.441877 -218.202482)
			(xy 349.411327 -218.160434) (xy 349.387731 -218.114124) (xy 349.37167 -218.064694) (xy 349.36354 -218.013359)
			(xy 349.223836 -218.013359) (xy 349.215706 -218.064694) (xy 349.199645 -218.114124) (xy 349.176049 -218.160434)
			(xy 349.145499 -218.202482) (xy 349.108748 -218.239233) (xy 349.0667 -218.269783) (xy 349.02039 -218.293379)
			(xy 348.97096 -218.30944) (xy 348.919625 -218.31757) (xy 348.867651 -218.31757) (xy 348.816316 -218.30944)
			(xy 348.766886 -218.293379) (xy 348.720576 -218.269783) (xy 348.678528 -218.239233) (xy 348.641777 -218.202482)
			(xy 348.611227 -218.160434) (xy 348.587631 -218.114124) (xy 348.57157 -218.064694) (xy 348.56344 -218.013359)
			(xy 348.423736 -218.013359) (xy 348.415606 -218.064694) (xy 348.399545 -218.114124) (xy 348.375949 -218.160434)
			(xy 348.345399 -218.202482) (xy 348.308648 -218.239233) (xy 348.2666 -218.269783) (xy 348.22029 -218.293379)
			(xy 348.17086 -218.30944) (xy 348.119525 -218.31757) (xy 348.067551 -218.31757) (xy 348.016216 -218.30944)
			(xy 347.966786 -218.293379) (xy 347.920476 -218.269783) (xy 347.878428 -218.239233) (xy 347.841677 -218.202482)
			(xy 347.811127 -218.160434) (xy 347.787531 -218.114124) (xy 347.77147 -218.064694) (xy 347.76334 -218.013359)
			(xy 347.62389 -218.013359) (xy 347.61576 -218.064694) (xy 347.599699 -218.114124) (xy 347.576103 -218.160434)
			(xy 347.545553 -218.202482) (xy 347.508802 -218.239233) (xy 347.466754 -218.269783) (xy 347.420444 -218.293379)
			(xy 347.371014 -218.30944) (xy 347.319679 -218.31757) (xy 347.267705 -218.31757) (xy 347.21637 -218.30944)
			(xy 347.16694 -218.293379) (xy 347.12063 -218.269783) (xy 347.078582 -218.239233) (xy 347.041831 -218.202482)
			(xy 347.011281 -218.160434) (xy 346.987685 -218.114124) (xy 346.971624 -218.064694) (xy 346.963494 -218.013359)
			(xy 346.82379 -218.013359) (xy 346.81566 -218.064694) (xy 346.799599 -218.114124) (xy 346.776003 -218.160434)
			(xy 346.745453 -218.202482) (xy 346.708702 -218.239233) (xy 346.666654 -218.269783) (xy 346.620344 -218.293379)
			(xy 346.570914 -218.30944) (xy 346.519579 -218.31757) (xy 346.467605 -218.31757) (xy 346.41627 -218.30944)
			(xy 346.36684 -218.293379) (xy 346.32053 -218.269783) (xy 346.278482 -218.239233) (xy 346.241731 -218.202482)
			(xy 346.211181 -218.160434) (xy 346.187585 -218.114124) (xy 346.171524 -218.064694) (xy 346.163394 -218.013359)
			(xy 345.35364 -218.013359) (xy 345.35364 -218.813205) (xy 346.163394 -218.813205) (xy 346.163394 -218.761231)
			(xy 346.171524 -218.709896) (xy 346.187585 -218.660466) (xy 346.211181 -218.614156) (xy 346.241731 -218.572108)
			(xy 346.278482 -218.535357) (xy 346.32053 -218.504807) (xy 346.36684 -218.481211) (xy 346.41627 -218.46515)
			(xy 346.467605 -218.45702) (xy 346.519579 -218.45702) (xy 346.570914 -218.46515) (xy 346.620344 -218.481211)
			(xy 346.666654 -218.504807) (xy 346.708702 -218.535357) (xy 346.745453 -218.572108) (xy 346.776003 -218.614156)
			(xy 346.799599 -218.660466) (xy 346.81566 -218.709896) (xy 346.82379 -218.761231) (xy 346.8243 -218.787218)
			(xy 346.82379 -218.813205) (xy 346.963494 -218.813205) (xy 346.963494 -218.761231) (xy 346.971624 -218.709896)
			(xy 346.987685 -218.660466) (xy 347.011281 -218.614156) (xy 347.041831 -218.572108) (xy 347.078582 -218.535357)
			(xy 347.12063 -218.504807) (xy 347.16694 -218.481211) (xy 347.21637 -218.46515) (xy 347.267705 -218.45702)
			(xy 347.319679 -218.45702) (xy 347.371014 -218.46515) (xy 347.420444 -218.481211) (xy 347.466754 -218.504807)
			(xy 347.508802 -218.535357) (xy 347.545553 -218.572108) (xy 347.576103 -218.614156) (xy 347.599699 -218.660466)
			(xy 347.61576 -218.709896) (xy 347.62389 -218.761231) (xy 347.6244 -218.787218) (xy 347.62389 -218.813205)
			(xy 348.56344 -218.813205) (xy 348.56344 -218.761231) (xy 348.57157 -218.709896) (xy 348.587631 -218.660466)
			(xy 348.611227 -218.614156) (xy 348.641777 -218.572108) (xy 348.678528 -218.535357) (xy 348.720576 -218.504807)
			(xy 348.766886 -218.481211) (xy 348.816316 -218.46515) (xy 348.867651 -218.45702) (xy 348.919625 -218.45702)
			(xy 348.97096 -218.46515) (xy 349.02039 -218.481211) (xy 349.0667 -218.504807) (xy 349.108748 -218.535357)
			(xy 349.145499 -218.572108) (xy 349.176049 -218.614156) (xy 349.199645 -218.660466) (xy 349.215706 -218.709896)
			(xy 349.223836 -218.761231) (xy 349.224346 -218.787218) (xy 349.223836 -218.813205) (xy 349.36354 -218.813205)
			(xy 349.36354 -218.761231) (xy 349.37167 -218.709896) (xy 349.387731 -218.660466) (xy 349.411327 -218.614156)
			(xy 349.441877 -218.572108) (xy 349.478628 -218.535357) (xy 349.520676 -218.504807) (xy 349.566986 -218.481211)
			(xy 349.616416 -218.46515) (xy 349.667751 -218.45702) (xy 349.719725 -218.45702) (xy 349.77106 -218.46515)
			(xy 349.82049 -218.481211) (xy 349.8668 -218.504807) (xy 349.908848 -218.535357) (xy 349.945599 -218.572108)
			(xy 349.976149 -218.614156) (xy 349.999745 -218.660466) (xy 350.015806 -218.709896) (xy 350.023936 -218.761231)
			(xy 350.024446 -218.787218) (xy 350.023936 -218.813205) (xy 350.163386 -218.813205) (xy 350.163386 -218.761231)
			(xy 350.171516 -218.709896) (xy 350.187577 -218.660466) (xy 350.211173 -218.614156) (xy 350.241723 -218.572108)
			(xy 350.278474 -218.535357) (xy 350.320522 -218.504807) (xy 350.366832 -218.481211) (xy 350.416262 -218.46515)
			(xy 350.467597 -218.45702) (xy 350.519571 -218.45702) (xy 350.570906 -218.46515) (xy 350.620336 -218.481211)
			(xy 350.666646 -218.504807) (xy 350.708694 -218.535357) (xy 350.745445 -218.572108) (xy 350.775995 -218.614156)
			(xy 350.799591 -218.660466) (xy 350.815652 -218.709896) (xy 350.823782 -218.761231) (xy 350.824292 -218.787218)
			(xy 350.823782 -218.813205) (xy 350.963486 -218.813205) (xy 350.963486 -218.761231) (xy 350.971616 -218.709896)
			(xy 350.987677 -218.660466) (xy 351.011273 -218.614156) (xy 351.041823 -218.572108) (xy 351.078574 -218.535357)
			(xy 351.120622 -218.504807) (xy 351.166932 -218.481211) (xy 351.216362 -218.46515) (xy 351.267697 -218.45702)
			(xy 351.319671 -218.45702) (xy 351.371006 -218.46515) (xy 351.420436 -218.481211) (xy 351.466746 -218.504807)
			(xy 351.508794 -218.535357) (xy 351.545545 -218.572108) (xy 351.576095 -218.614156) (xy 351.599691 -218.660466)
			(xy 351.615752 -218.709896) (xy 351.623882 -218.761231) (xy 351.624392 -218.787218) (xy 351.623882 -218.813205)
			(xy 351.615752 -218.86454) (xy 351.599691 -218.91397) (xy 351.576095 -218.96028) (xy 351.545545 -219.002328)
			(xy 351.508794 -219.039079) (xy 351.466746 -219.069629) (xy 351.420436 -219.093225) (xy 351.371006 -219.109286)
			(xy 351.319671 -219.117416) (xy 351.267697 -219.117416) (xy 351.216362 -219.109286) (xy 351.166932 -219.093225)
			(xy 351.120622 -219.069629) (xy 351.078574 -219.039079) (xy 351.041823 -219.002328) (xy 351.011273 -218.96028)
			(xy 350.987677 -218.91397) (xy 350.971616 -218.86454) (xy 350.963486 -218.813205) (xy 350.823782 -218.813205)
			(xy 350.815652 -218.86454) (xy 350.799591 -218.91397) (xy 350.775995 -218.96028) (xy 350.745445 -219.002328)
			(xy 350.708694 -219.039079) (xy 350.666646 -219.069629) (xy 350.620336 -219.093225) (xy 350.570906 -219.109286)
			(xy 350.519571 -219.117416) (xy 350.467597 -219.117416) (xy 350.416262 -219.109286) (xy 350.366832 -219.093225)
			(xy 350.320522 -219.069629) (xy 350.278474 -219.039079) (xy 350.241723 -219.002328) (xy 350.211173 -218.96028)
			(xy 350.187577 -218.91397) (xy 350.171516 -218.86454) (xy 350.163386 -218.813205) (xy 350.023936 -218.813205)
			(xy 350.015806 -218.86454) (xy 349.999745 -218.91397) (xy 349.976149 -218.96028) (xy 349.945599 -219.002328)
			(xy 349.908848 -219.039079) (xy 349.8668 -219.069629) (xy 349.82049 -219.093225) (xy 349.77106 -219.109286)
			(xy 349.719725 -219.117416) (xy 349.667751 -219.117416) (xy 349.616416 -219.109286) (xy 349.566986 -219.093225)
			(xy 349.520676 -219.069629) (xy 349.478628 -219.039079) (xy 349.441877 -219.002328) (xy 349.411327 -218.96028)
			(xy 349.387731 -218.91397) (xy 349.37167 -218.86454) (xy 349.36354 -218.813205) (xy 349.223836 -218.813205)
			(xy 349.215706 -218.86454) (xy 349.199645 -218.91397) (xy 349.176049 -218.96028) (xy 349.145499 -219.002328)
			(xy 349.108748 -219.039079) (xy 349.0667 -219.069629) (xy 349.02039 -219.093225) (xy 348.97096 -219.109286)
			(xy 348.919625 -219.117416) (xy 348.867651 -219.117416) (xy 348.816316 -219.109286) (xy 348.766886 -219.093225)
			(xy 348.720576 -219.069629) (xy 348.678528 -219.039079) (xy 348.641777 -219.002328) (xy 348.611227 -218.96028)
			(xy 348.587631 -218.91397) (xy 348.57157 -218.86454) (xy 348.56344 -218.813205) (xy 347.62389 -218.813205)
			(xy 347.61576 -218.86454) (xy 347.599699 -218.91397) (xy 347.576103 -218.96028) (xy 347.545553 -219.002328)
			(xy 347.508802 -219.039079) (xy 347.466754 -219.069629) (xy 347.420444 -219.093225) (xy 347.371014 -219.109286)
			(xy 347.319679 -219.117416) (xy 347.267705 -219.117416) (xy 347.21637 -219.109286) (xy 347.16694 -219.093225)
			(xy 347.12063 -219.069629) (xy 347.078582 -219.039079) (xy 347.041831 -219.002328) (xy 347.011281 -218.96028)
			(xy 346.987685 -218.91397) (xy 346.971624 -218.86454) (xy 346.963494 -218.813205) (xy 346.82379 -218.813205)
			(xy 346.81566 -218.86454) (xy 346.799599 -218.91397) (xy 346.776003 -218.96028) (xy 346.745453 -219.002328)
			(xy 346.708702 -219.039079) (xy 346.666654 -219.069629) (xy 346.620344 -219.093225) (xy 346.570914 -219.109286)
			(xy 346.519579 -219.117416) (xy 346.467605 -219.117416) (xy 346.41627 -219.109286) (xy 346.36684 -219.093225)
			(xy 346.32053 -219.069629) (xy 346.278482 -219.039079) (xy 346.241731 -219.002328) (xy 346.211181 -218.96028)
			(xy 346.187585 -218.91397) (xy 346.171524 -218.86454) (xy 346.163394 -218.813205) (xy 345.35364 -218.813205)
			(xy 345.35364 -220.412897) (xy 346.163394 -220.412897) (xy 346.163394 -220.360923) (xy 346.171524 -220.309588)
			(xy 346.187585 -220.260158) (xy 346.211181 -220.213848) (xy 346.241731 -220.1718) (xy 346.278482 -220.135049)
			(xy 346.32053 -220.104499) (xy 346.36684 -220.080903) (xy 346.41627 -220.064842) (xy 346.467605 -220.056712)
			(xy 346.519579 -220.056712) (xy 346.570914 -220.064842) (xy 346.620344 -220.080903) (xy 346.666654 -220.104499)
			(xy 346.708702 -220.135049) (xy 346.745453 -220.1718) (xy 346.776003 -220.213848) (xy 346.799599 -220.260158)
			(xy 346.81566 -220.309588) (xy 346.82379 -220.360923) (xy 346.8243 -220.38691) (xy 346.82379 -220.412897)
			(xy 346.963494 -220.412897) (xy 346.963494 -220.360923) (xy 346.971624 -220.309588) (xy 346.987685 -220.260158)
			(xy 347.011281 -220.213848) (xy 347.041831 -220.1718) (xy 347.078582 -220.135049) (xy 347.12063 -220.104499)
			(xy 347.16694 -220.080903) (xy 347.21637 -220.064842) (xy 347.267705 -220.056712) (xy 347.319679 -220.056712)
			(xy 347.371014 -220.064842) (xy 347.420444 -220.080903) (xy 347.466754 -220.104499) (xy 347.508802 -220.135049)
			(xy 347.545553 -220.1718) (xy 347.576103 -220.213848) (xy 347.599699 -220.260158) (xy 347.61576 -220.309588)
			(xy 347.62389 -220.360923) (xy 347.6244 -220.38691) (xy 347.62389 -220.412897) (xy 347.76334 -220.412897)
			(xy 347.76334 -220.360923) (xy 347.77147 -220.309588) (xy 347.787531 -220.260158) (xy 347.811127 -220.213848)
			(xy 347.841677 -220.1718) (xy 347.878428 -220.135049) (xy 347.920476 -220.104499) (xy 347.966786 -220.080903)
			(xy 348.016216 -220.064842) (xy 348.067551 -220.056712) (xy 348.119525 -220.056712) (xy 348.17086 -220.064842)
			(xy 348.22029 -220.080903) (xy 348.2666 -220.104499) (xy 348.308648 -220.135049) (xy 348.345399 -220.1718)
			(xy 348.375949 -220.213848) (xy 348.399545 -220.260158) (xy 348.415606 -220.309588) (xy 348.423736 -220.360923)
			(xy 348.424246 -220.38691) (xy 348.423736 -220.412897) (xy 348.56344 -220.412897) (xy 348.56344 -220.360923)
			(xy 348.57157 -220.309588) (xy 348.587631 -220.260158) (xy 348.611227 -220.213848) (xy 348.641777 -220.1718)
			(xy 348.678528 -220.135049) (xy 348.720576 -220.104499) (xy 348.766886 -220.080903) (xy 348.816316 -220.064842)
			(xy 348.867651 -220.056712) (xy 348.919625 -220.056712) (xy 348.97096 -220.064842) (xy 349.02039 -220.080903)
			(xy 349.0667 -220.104499) (xy 349.108748 -220.135049) (xy 349.145499 -220.1718) (xy 349.176049 -220.213848)
			(xy 349.199645 -220.260158) (xy 349.215706 -220.309588) (xy 349.223836 -220.360923) (xy 349.224346 -220.38691)
			(xy 349.223836 -220.412897) (xy 349.36354 -220.412897) (xy 349.36354 -220.360923) (xy 349.37167 -220.309588)
			(xy 349.387731 -220.260158) (xy 349.411327 -220.213848) (xy 349.441877 -220.1718) (xy 349.478628 -220.135049)
			(xy 349.520676 -220.104499) (xy 349.566986 -220.080903) (xy 349.616416 -220.064842) (xy 349.667751 -220.056712)
			(xy 349.719725 -220.056712) (xy 349.77106 -220.064842) (xy 349.82049 -220.080903) (xy 349.8668 -220.104499)
			(xy 349.908848 -220.135049) (xy 349.945599 -220.1718) (xy 349.976149 -220.213848) (xy 349.999745 -220.260158)
			(xy 350.015806 -220.309588) (xy 350.023936 -220.360923) (xy 350.024446 -220.38691) (xy 350.023936 -220.412897)
			(xy 350.163386 -220.412897) (xy 350.163386 -220.360923) (xy 350.171516 -220.309588) (xy 350.187577 -220.260158)
			(xy 350.211173 -220.213848) (xy 350.241723 -220.1718) (xy 350.278474 -220.135049) (xy 350.320522 -220.104499)
			(xy 350.366832 -220.080903) (xy 350.416262 -220.064842) (xy 350.467597 -220.056712) (xy 350.519571 -220.056712)
			(xy 350.570906 -220.064842) (xy 350.620336 -220.080903) (xy 350.666646 -220.104499) (xy 350.708694 -220.135049)
			(xy 350.745445 -220.1718) (xy 350.775995 -220.213848) (xy 350.799591 -220.260158) (xy 350.815652 -220.309588)
			(xy 350.823782 -220.360923) (xy 350.824292 -220.38691) (xy 350.823782 -220.412897) (xy 350.815652 -220.464232)
			(xy 350.799591 -220.513662) (xy 350.775995 -220.559972) (xy 350.745445 -220.60202) (xy 350.708694 -220.638771)
			(xy 350.666646 -220.669321) (xy 350.620336 -220.692917) (xy 350.570906 -220.708978) (xy 350.519571 -220.717108)
			(xy 350.467597 -220.717108) (xy 350.416262 -220.708978) (xy 350.366832 -220.692917) (xy 350.320522 -220.669321)
			(xy 350.278474 -220.638771) (xy 350.241723 -220.60202) (xy 350.211173 -220.559972) (xy 350.187577 -220.513662)
			(xy 350.171516 -220.464232) (xy 350.163386 -220.412897) (xy 350.023936 -220.412897) (xy 350.015806 -220.464232)
			(xy 349.999745 -220.513662) (xy 349.976149 -220.559972) (xy 349.945599 -220.60202) (xy 349.908848 -220.638771)
			(xy 349.8668 -220.669321) (xy 349.82049 -220.692917) (xy 349.77106 -220.708978) (xy 349.719725 -220.717108)
			(xy 349.667751 -220.717108) (xy 349.616416 -220.708978) (xy 349.566986 -220.692917) (xy 349.520676 -220.669321)
			(xy 349.478628 -220.638771) (xy 349.441877 -220.60202) (xy 349.411327 -220.559972) (xy 349.387731 -220.513662)
			(xy 349.37167 -220.464232) (xy 349.36354 -220.412897) (xy 349.223836 -220.412897) (xy 349.215706 -220.464232)
			(xy 349.199645 -220.513662) (xy 349.176049 -220.559972) (xy 349.145499 -220.60202) (xy 349.108748 -220.638771)
			(xy 349.0667 -220.669321) (xy 349.02039 -220.692917) (xy 348.97096 -220.708978) (xy 348.919625 -220.717108)
			(xy 348.867651 -220.717108) (xy 348.816316 -220.708978) (xy 348.766886 -220.692917) (xy 348.720576 -220.669321)
			(xy 348.678528 -220.638771) (xy 348.641777 -220.60202) (xy 348.611227 -220.559972) (xy 348.587631 -220.513662)
			(xy 348.57157 -220.464232) (xy 348.56344 -220.412897) (xy 348.423736 -220.412897) (xy 348.415606 -220.464232)
			(xy 348.399545 -220.513662) (xy 348.375949 -220.559972) (xy 348.345399 -220.60202) (xy 348.308648 -220.638771)
			(xy 348.2666 -220.669321) (xy 348.22029 -220.692917) (xy 348.17086 -220.708978) (xy 348.119525 -220.717108)
			(xy 348.067551 -220.717108) (xy 348.016216 -220.708978) (xy 347.966786 -220.692917) (xy 347.920476 -220.669321)
			(xy 347.878428 -220.638771) (xy 347.841677 -220.60202) (xy 347.811127 -220.559972) (xy 347.787531 -220.513662)
			(xy 347.77147 -220.464232) (xy 347.76334 -220.412897) (xy 347.62389 -220.412897) (xy 347.61576 -220.464232)
			(xy 347.599699 -220.513662) (xy 347.576103 -220.559972) (xy 347.545553 -220.60202) (xy 347.508802 -220.638771)
			(xy 347.466754 -220.669321) (xy 347.420444 -220.692917) (xy 347.371014 -220.708978) (xy 347.319679 -220.717108)
			(xy 347.267705 -220.717108) (xy 347.21637 -220.708978) (xy 347.16694 -220.692917) (xy 347.12063 -220.669321)
			(xy 347.078582 -220.638771) (xy 347.041831 -220.60202) (xy 347.011281 -220.559972) (xy 346.987685 -220.513662)
			(xy 346.971624 -220.464232) (xy 346.963494 -220.412897) (xy 346.82379 -220.412897) (xy 346.81566 -220.464232)
			(xy 346.799599 -220.513662) (xy 346.776003 -220.559972) (xy 346.745453 -220.60202) (xy 346.708702 -220.638771)
			(xy 346.666654 -220.669321) (xy 346.620344 -220.692917) (xy 346.570914 -220.708978) (xy 346.519579 -220.717108)
			(xy 346.467605 -220.717108) (xy 346.41627 -220.708978) (xy 346.36684 -220.692917) (xy 346.32053 -220.669321)
			(xy 346.278482 -220.638771) (xy 346.241731 -220.60202) (xy 346.211181 -220.559972) (xy 346.187585 -220.513662)
			(xy 346.171524 -220.464232) (xy 346.163394 -220.412897) (xy 345.35364 -220.412897) (xy 345.35364 -221.212743)
			(xy 346.163394 -221.212743) (xy 346.163394 -221.160769) (xy 346.171524 -221.109434) (xy 346.187585 -221.060004)
			(xy 346.211181 -221.013694) (xy 346.241731 -220.971646) (xy 346.278482 -220.934895) (xy 346.32053 -220.904345)
			(xy 346.36684 -220.880749) (xy 346.41627 -220.864688) (xy 346.467605 -220.856558) (xy 346.519579 -220.856558)
			(xy 346.570914 -220.864688) (xy 346.620344 -220.880749) (xy 346.666654 -220.904345) (xy 346.708702 -220.934895)
			(xy 346.745453 -220.971646) (xy 346.776003 -221.013694) (xy 346.799599 -221.060004) (xy 346.81566 -221.109434)
			(xy 346.82379 -221.160769) (xy 346.8243 -221.186756) (xy 346.82379 -221.212743) (xy 346.963494 -221.212743)
			(xy 346.963494 -221.160769) (xy 346.971624 -221.109434) (xy 346.987685 -221.060004) (xy 347.011281 -221.013694)
			(xy 347.041831 -220.971646) (xy 347.078582 -220.934895) (xy 347.12063 -220.904345) (xy 347.16694 -220.880749)
			(xy 347.21637 -220.864688) (xy 347.267705 -220.856558) (xy 347.319679 -220.856558) (xy 347.371014 -220.864688)
			(xy 347.420444 -220.880749) (xy 347.466754 -220.904345) (xy 347.508802 -220.934895) (xy 347.545553 -220.971646)
			(xy 347.576103 -221.013694) (xy 347.599699 -221.060004) (xy 347.61576 -221.109434) (xy 347.62389 -221.160769)
			(xy 347.6244 -221.186756) (xy 347.62389 -221.212743) (xy 347.76334 -221.212743) (xy 347.76334 -221.160769)
			(xy 347.77147 -221.109434) (xy 347.787531 -221.060004) (xy 347.811127 -221.013694) (xy 347.841677 -220.971646)
			(xy 347.878428 -220.934895) (xy 347.920476 -220.904345) (xy 347.966786 -220.880749) (xy 348.016216 -220.864688)
			(xy 348.067551 -220.856558) (xy 348.119525 -220.856558) (xy 348.17086 -220.864688) (xy 348.22029 -220.880749)
			(xy 348.2666 -220.904345) (xy 348.308648 -220.934895) (xy 348.345399 -220.971646) (xy 348.375949 -221.013694)
			(xy 348.399545 -221.060004) (xy 348.415606 -221.109434) (xy 348.423736 -221.160769) (xy 348.424246 -221.186756)
			(xy 348.423736 -221.212743) (xy 348.56344 -221.212743) (xy 348.56344 -221.160769) (xy 348.57157 -221.109434)
			(xy 348.587631 -221.060004) (xy 348.611227 -221.013694) (xy 348.641777 -220.971646) (xy 348.678528 -220.934895)
			(xy 348.720576 -220.904345) (xy 348.766886 -220.880749) (xy 348.816316 -220.864688) (xy 348.867651 -220.856558)
			(xy 348.919625 -220.856558) (xy 348.97096 -220.864688) (xy 349.02039 -220.880749) (xy 349.0667 -220.904345)
			(xy 349.108748 -220.934895) (xy 349.145499 -220.971646) (xy 349.176049 -221.013694) (xy 349.199645 -221.060004)
			(xy 349.215706 -221.109434) (xy 349.223836 -221.160769) (xy 349.224346 -221.186756) (xy 349.223836 -221.212743)
			(xy 349.36354 -221.212743) (xy 349.36354 -221.160769) (xy 349.37167 -221.109434) (xy 349.387731 -221.060004)
			(xy 349.411327 -221.013694) (xy 349.441877 -220.971646) (xy 349.478628 -220.934895) (xy 349.520676 -220.904345)
			(xy 349.566986 -220.880749) (xy 349.616416 -220.864688) (xy 349.667751 -220.856558) (xy 349.719725 -220.856558)
			(xy 349.77106 -220.864688) (xy 349.82049 -220.880749) (xy 349.8668 -220.904345) (xy 349.908848 -220.934895)
			(xy 349.945599 -220.971646) (xy 349.976149 -221.013694) (xy 349.999745 -221.060004) (xy 350.015806 -221.109434)
			(xy 350.023936 -221.160769) (xy 350.024446 -221.186756) (xy 350.023936 -221.212743) (xy 350.163386 -221.212743)
			(xy 350.163386 -221.160769) (xy 350.171516 -221.109434) (xy 350.187577 -221.060004) (xy 350.211173 -221.013694)
			(xy 350.241723 -220.971646) (xy 350.278474 -220.934895) (xy 350.320522 -220.904345) (xy 350.366832 -220.880749)
			(xy 350.416262 -220.864688) (xy 350.467597 -220.856558) (xy 350.519571 -220.856558) (xy 350.570906 -220.864688)
			(xy 350.620336 -220.880749) (xy 350.666646 -220.904345) (xy 350.708694 -220.934895) (xy 350.745445 -220.971646)
			(xy 350.775995 -221.013694) (xy 350.799591 -221.060004) (xy 350.815652 -221.109434) (xy 350.823782 -221.160769)
			(xy 350.824292 -221.186756) (xy 350.823782 -221.212743) (xy 350.963486 -221.212743) (xy 350.963486 -221.160769)
			(xy 350.971616 -221.109434) (xy 350.987677 -221.060004) (xy 351.011273 -221.013694) (xy 351.041823 -220.971646)
			(xy 351.078574 -220.934895) (xy 351.120622 -220.904345) (xy 351.166932 -220.880749) (xy 351.216362 -220.864688)
			(xy 351.267697 -220.856558) (xy 351.319671 -220.856558) (xy 351.371006 -220.864688) (xy 351.420436 -220.880749)
			(xy 351.466746 -220.904345) (xy 351.508794 -220.934895) (xy 351.545545 -220.971646) (xy 351.576095 -221.013694)
			(xy 351.599691 -221.060004) (xy 351.615752 -221.109434) (xy 351.623882 -221.160769) (xy 351.624392 -221.186756)
			(xy 351.623882 -221.212743) (xy 351.615752 -221.264078) (xy 351.599691 -221.313508) (xy 351.576095 -221.359818)
			(xy 351.545545 -221.401866) (xy 351.508794 -221.438617) (xy 351.466746 -221.469167) (xy 351.420436 -221.492763)
			(xy 351.371006 -221.508824) (xy 351.319671 -221.516954) (xy 351.267697 -221.516954) (xy 351.216362 -221.508824)
			(xy 351.166932 -221.492763) (xy 351.120622 -221.469167) (xy 351.078574 -221.438617) (xy 351.041823 -221.401866)
			(xy 351.011273 -221.359818) (xy 350.987677 -221.313508) (xy 350.971616 -221.264078) (xy 350.963486 -221.212743)
			(xy 350.823782 -221.212743) (xy 350.815652 -221.264078) (xy 350.799591 -221.313508) (xy 350.775995 -221.359818)
			(xy 350.745445 -221.401866) (xy 350.708694 -221.438617) (xy 350.666646 -221.469167) (xy 350.620336 -221.492763)
			(xy 350.570906 -221.508824) (xy 350.519571 -221.516954) (xy 350.467597 -221.516954) (xy 350.416262 -221.508824)
			(xy 350.366832 -221.492763) (xy 350.320522 -221.469167) (xy 350.278474 -221.438617) (xy 350.241723 -221.401866)
			(xy 350.211173 -221.359818) (xy 350.187577 -221.313508) (xy 350.171516 -221.264078) (xy 350.163386 -221.212743)
			(xy 350.023936 -221.212743) (xy 350.015806 -221.264078) (xy 349.999745 -221.313508) (xy 349.976149 -221.359818)
			(xy 349.945599 -221.401866) (xy 349.908848 -221.438617) (xy 349.8668 -221.469167) (xy 349.82049 -221.492763)
			(xy 349.77106 -221.508824) (xy 349.719725 -221.516954) (xy 349.667751 -221.516954) (xy 349.616416 -221.508824)
			(xy 349.566986 -221.492763) (xy 349.520676 -221.469167) (xy 349.478628 -221.438617) (xy 349.441877 -221.401866)
			(xy 349.411327 -221.359818) (xy 349.387731 -221.313508) (xy 349.37167 -221.264078) (xy 349.36354 -221.212743)
			(xy 349.223836 -221.212743) (xy 349.215706 -221.264078) (xy 349.199645 -221.313508) (xy 349.176049 -221.359818)
			(xy 349.145499 -221.401866) (xy 349.108748 -221.438617) (xy 349.0667 -221.469167) (xy 349.02039 -221.492763)
			(xy 348.97096 -221.508824) (xy 348.919625 -221.516954) (xy 348.867651 -221.516954) (xy 348.816316 -221.508824)
			(xy 348.766886 -221.492763) (xy 348.720576 -221.469167) (xy 348.678528 -221.438617) (xy 348.641777 -221.401866)
			(xy 348.611227 -221.359818) (xy 348.587631 -221.313508) (xy 348.57157 -221.264078) (xy 348.56344 -221.212743)
			(xy 348.423736 -221.212743) (xy 348.415606 -221.264078) (xy 348.399545 -221.313508) (xy 348.375949 -221.359818)
			(xy 348.345399 -221.401866) (xy 348.308648 -221.438617) (xy 348.2666 -221.469167) (xy 348.22029 -221.492763)
			(xy 348.17086 -221.508824) (xy 348.119525 -221.516954) (xy 348.067551 -221.516954) (xy 348.016216 -221.508824)
			(xy 347.966786 -221.492763) (xy 347.920476 -221.469167) (xy 347.878428 -221.438617) (xy 347.841677 -221.401866)
			(xy 347.811127 -221.359818) (xy 347.787531 -221.313508) (xy 347.77147 -221.264078) (xy 347.76334 -221.212743)
			(xy 347.62389 -221.212743) (xy 347.61576 -221.264078) (xy 347.599699 -221.313508) (xy 347.576103 -221.359818)
			(xy 347.545553 -221.401866) (xy 347.508802 -221.438617) (xy 347.466754 -221.469167) (xy 347.420444 -221.492763)
			(xy 347.371014 -221.508824) (xy 347.319679 -221.516954) (xy 347.267705 -221.516954) (xy 347.21637 -221.508824)
			(xy 347.16694 -221.492763) (xy 347.12063 -221.469167) (xy 347.078582 -221.438617) (xy 347.041831 -221.401866)
			(xy 347.011281 -221.359818) (xy 346.987685 -221.313508) (xy 346.971624 -221.264078) (xy 346.963494 -221.212743)
			(xy 346.82379 -221.212743) (xy 346.81566 -221.264078) (xy 346.799599 -221.313508) (xy 346.776003 -221.359818)
			(xy 346.745453 -221.401866) (xy 346.708702 -221.438617) (xy 346.666654 -221.469167) (xy 346.620344 -221.492763)
			(xy 346.570914 -221.508824) (xy 346.519579 -221.516954) (xy 346.467605 -221.516954) (xy 346.41627 -221.508824)
			(xy 346.36684 -221.492763) (xy 346.32053 -221.469167) (xy 346.278482 -221.438617) (xy 346.241731 -221.401866)
			(xy 346.211181 -221.359818) (xy 346.187585 -221.313508) (xy 346.171524 -221.264078) (xy 346.163394 -221.212743)
			(xy 345.35364 -221.212743) (xy 345.35364 -222.012843) (xy 346.163394 -222.012843) (xy 346.163394 -221.960869)
			(xy 346.171524 -221.909534) (xy 346.187585 -221.860104) (xy 346.211181 -221.813794) (xy 346.241731 -221.771746)
			(xy 346.278482 -221.734995) (xy 346.32053 -221.704445) (xy 346.36684 -221.680849) (xy 346.41627 -221.664788)
			(xy 346.467605 -221.656658) (xy 346.519579 -221.656658) (xy 346.570914 -221.664788) (xy 346.620344 -221.680849)
			(xy 346.666654 -221.704445) (xy 346.708702 -221.734995) (xy 346.745453 -221.771746) (xy 346.776003 -221.813794)
			(xy 346.799599 -221.860104) (xy 346.81566 -221.909534) (xy 346.82379 -221.960869) (xy 346.8243 -221.986856)
			(xy 346.82379 -222.012843) (xy 346.963494 -222.012843) (xy 346.963494 -221.960869) (xy 346.971624 -221.909534)
			(xy 346.987685 -221.860104) (xy 347.011281 -221.813794) (xy 347.041831 -221.771746) (xy 347.078582 -221.734995)
			(xy 347.12063 -221.704445) (xy 347.16694 -221.680849) (xy 347.21637 -221.664788) (xy 347.267705 -221.656658)
			(xy 347.319679 -221.656658) (xy 347.371014 -221.664788) (xy 347.420444 -221.680849) (xy 347.466754 -221.704445)
			(xy 347.508802 -221.734995) (xy 347.545553 -221.771746) (xy 347.576103 -221.813794) (xy 347.599699 -221.860104)
			(xy 347.61576 -221.909534) (xy 347.62389 -221.960869) (xy 347.6244 -221.986856) (xy 347.62389 -222.012843)
			(xy 347.76334 -222.012843) (xy 347.76334 -221.960869) (xy 347.77147 -221.909534) (xy 347.787531 -221.860104)
			(xy 347.811127 -221.813794) (xy 347.841677 -221.771746) (xy 347.878428 -221.734995) (xy 347.920476 -221.704445)
			(xy 347.966786 -221.680849) (xy 348.016216 -221.664788) (xy 348.067551 -221.656658) (xy 348.119525 -221.656658)
			(xy 348.17086 -221.664788) (xy 348.22029 -221.680849) (xy 348.2666 -221.704445) (xy 348.308648 -221.734995)
			(xy 348.345399 -221.771746) (xy 348.375949 -221.813794) (xy 348.399545 -221.860104) (xy 348.415606 -221.909534)
			(xy 348.423736 -221.960869) (xy 348.424246 -221.986856) (xy 348.423736 -222.012843) (xy 348.423696 -222.013097)
			(xy 348.563694 -222.013097) (xy 348.563694 -221.961123) (xy 348.571824 -221.909788) (xy 348.587885 -221.860358)
			(xy 348.611481 -221.814048) (xy 348.642031 -221.772) (xy 348.678782 -221.735249) (xy 348.72083 -221.704699)
			(xy 348.76714 -221.681103) (xy 348.81657 -221.665042) (xy 348.867905 -221.656912) (xy 348.919879 -221.656912)
			(xy 348.971214 -221.665042) (xy 349.020644 -221.681103) (xy 349.066954 -221.704699) (xy 349.109002 -221.735249)
			(xy 349.145753 -221.772) (xy 349.176303 -221.814048) (xy 349.199899 -221.860358) (xy 349.21596 -221.909788)
			(xy 349.22409 -221.961123) (xy 349.2246 -221.98711) (xy 349.224095 -222.012843) (xy 349.36354 -222.012843)
			(xy 349.36354 -221.960869) (xy 349.37167 -221.909534) (xy 349.387731 -221.860104) (xy 349.411327 -221.813794)
			(xy 349.441877 -221.771746) (xy 349.478628 -221.734995) (xy 349.520676 -221.704445) (xy 349.566986 -221.680849)
			(xy 349.616416 -221.664788) (xy 349.667751 -221.656658) (xy 349.719725 -221.656658) (xy 349.77106 -221.664788)
			(xy 349.82049 -221.680849) (xy 349.8668 -221.704445) (xy 349.908848 -221.734995) (xy 349.945599 -221.771746)
			(xy 349.976149 -221.813794) (xy 349.999745 -221.860104) (xy 350.015806 -221.909534) (xy 350.023936 -221.960869)
			(xy 350.024446 -221.986856) (xy 350.023936 -222.012843) (xy 350.163386 -222.012843) (xy 350.163386 -221.960869)
			(xy 350.171516 -221.909534) (xy 350.187577 -221.860104) (xy 350.211173 -221.813794) (xy 350.241723 -221.771746)
			(xy 350.278474 -221.734995) (xy 350.320522 -221.704445) (xy 350.366832 -221.680849) (xy 350.416262 -221.664788)
			(xy 350.467597 -221.656658) (xy 350.519571 -221.656658) (xy 350.570906 -221.664788) (xy 350.620336 -221.680849)
			(xy 350.666646 -221.704445) (xy 350.708694 -221.734995) (xy 350.745445 -221.771746) (xy 350.775995 -221.813794)
			(xy 350.799591 -221.860104) (xy 350.815652 -221.909534) (xy 350.823782 -221.960869) (xy 350.824292 -221.986856)
			(xy 350.823782 -222.012843) (xy 350.963486 -222.012843) (xy 350.963486 -221.960869) (xy 350.971616 -221.909534)
			(xy 350.987677 -221.860104) (xy 351.011273 -221.813794) (xy 351.041823 -221.771746) (xy 351.078574 -221.734995)
			(xy 351.120622 -221.704445) (xy 351.166932 -221.680849) (xy 351.216362 -221.664788) (xy 351.267697 -221.656658)
			(xy 351.319671 -221.656658) (xy 351.371006 -221.664788) (xy 351.420436 -221.680849) (xy 351.466746 -221.704445)
			(xy 351.508794 -221.734995) (xy 351.545545 -221.771746) (xy 351.576095 -221.813794) (xy 351.599691 -221.860104)
			(xy 351.610365 -221.892954) (xy 352.064753 -221.892954) (xy 352.064753 -221.838446) (xy 352.072511 -221.784492)
			(xy 352.087869 -221.732192) (xy 352.110513 -221.682609) (xy 352.139984 -221.636755) (xy 352.175681 -221.595561)
			(xy 352.216877 -221.559867) (xy 352.262734 -221.5304) (xy 352.312318 -221.507759) (xy 352.364619 -221.492405)
			(xy 352.418574 -221.484651) (xy 352.445828 -221.48419) (xy 352.47415 -221.48471) (xy 352.530171 -221.4931)
			(xy 352.584337 -221.509676) (xy 352.635458 -221.534076) (xy 352.682412 -221.565762) (xy 352.703638 -221.58452)
			(xy 352.711004 -221.591124) (xy 352.72853 -221.597982) (xy 352.817938 -221.596966) (xy 352.835464 -221.589854)
			(xy 352.842576 -221.582996) (xy 352.864001 -221.56327) (xy 352.911742 -221.529916) (xy 352.963995 -221.504201)
			(xy 353.019547 -221.48672) (xy 353.077109 -221.477879) (xy 353.106228 -221.477332) (xy 353.133481 -221.47774)
			(xy 353.187431 -221.4855) (xy 353.239728 -221.50086) (xy 353.289307 -221.523505) (xy 353.335159 -221.552975)
			(xy 353.37635 -221.58867) (xy 353.412042 -221.629864) (xy 353.441509 -221.675718) (xy 353.46415 -221.725298)
			(xy 353.479506 -221.777596) (xy 353.487262 -221.831547) (xy 353.487262 -221.886053) (xy 353.479506 -221.940004)
			(xy 353.46415 -221.992302) (xy 353.441509 -222.041882) (xy 353.412042 -222.087736) (xy 353.37635 -222.12893)
			(xy 353.335159 -222.164625) (xy 353.289307 -222.194095) (xy 353.239728 -222.21674) (xy 353.187431 -222.2321)
			(xy 353.133481 -222.23986) (xy 353.106228 -222.240348) (xy 353.077906 -222.239811) (xy 353.021886 -222.231427)
			(xy 352.96772 -222.214856) (xy 352.916598 -222.19046) (xy 352.869644 -222.158776) (xy 352.848418 -222.140018)
			(xy 352.841052 -222.133414) (xy 352.823526 -222.126556) (xy 352.734118 -222.127572) (xy 352.716592 -222.134684)
			(xy 352.70948 -222.141542) (xy 352.688037 -222.161249) (xy 352.640301 -222.194603) (xy 352.588052 -222.220322)
			(xy 352.532505 -222.237808) (xy 352.474945 -222.246656) (xy 352.445828 -222.247206) (xy 352.418574 -222.246749)
			(xy 352.364619 -222.238995) (xy 352.312318 -222.223641) (xy 352.262734 -222.201) (xy 352.216877 -222.171533)
			(xy 352.175681 -222.135839) (xy 352.139984 -222.094645) (xy 352.110513 -222.048791) (xy 352.087869 -221.999208)
			(xy 352.072511 -221.946908) (xy 352.064753 -221.892954) (xy 351.610365 -221.892954) (xy 351.615752 -221.909534)
			(xy 351.623882 -221.960869) (xy 351.624392 -221.986856) (xy 351.623882 -222.012843) (xy 351.615752 -222.064178)
			(xy 351.599691 -222.113608) (xy 351.576095 -222.159918) (xy 351.545545 -222.201966) (xy 351.508794 -222.238717)
			(xy 351.466746 -222.269267) (xy 351.420436 -222.292863) (xy 351.371006 -222.308924) (xy 351.319671 -222.317054)
			(xy 351.267697 -222.317054) (xy 351.216362 -222.308924) (xy 351.166932 -222.292863) (xy 351.120622 -222.269267)
			(xy 351.078574 -222.238717) (xy 351.041823 -222.201966) (xy 351.011273 -222.159918) (xy 350.987677 -222.113608)
			(xy 350.971616 -222.064178) (xy 350.963486 -222.012843) (xy 350.823782 -222.012843) (xy 350.815652 -222.064178)
			(xy 350.799591 -222.113608) (xy 350.775995 -222.159918) (xy 350.745445 -222.201966) (xy 350.708694 -222.238717)
			(xy 350.666646 -222.269267) (xy 350.620336 -222.292863) (xy 350.570906 -222.308924) (xy 350.519571 -222.317054)
			(xy 350.467597 -222.317054) (xy 350.416262 -222.308924) (xy 350.366832 -222.292863) (xy 350.320522 -222.269267)
			(xy 350.278474 -222.238717) (xy 350.241723 -222.201966) (xy 350.211173 -222.159918) (xy 350.187577 -222.113608)
			(xy 350.171516 -222.064178) (xy 350.163386 -222.012843) (xy 350.023936 -222.012843) (xy 350.015806 -222.064178)
			(xy 349.999745 -222.113608) (xy 349.976149 -222.159918) (xy 349.945599 -222.201966) (xy 349.908848 -222.238717)
			(xy 349.8668 -222.269267) (xy 349.82049 -222.292863) (xy 349.77106 -222.308924) (xy 349.719725 -222.317054)
			(xy 349.667751 -222.317054) (xy 349.616416 -222.308924) (xy 349.566986 -222.292863) (xy 349.520676 -222.269267)
			(xy 349.478628 -222.238717) (xy 349.441877 -222.201966) (xy 349.411327 -222.159918) (xy 349.387731 -222.113608)
			(xy 349.37167 -222.064178) (xy 349.36354 -222.012843) (xy 349.224095 -222.012843) (xy 349.22409 -222.013097)
			(xy 349.21596 -222.064432) (xy 349.199899 -222.113862) (xy 349.176303 -222.160172) (xy 349.145753 -222.20222)
			(xy 349.109002 -222.238971) (xy 349.066954 -222.269521) (xy 349.020644 -222.293117) (xy 348.971214 -222.309178)
			(xy 348.919879 -222.317308) (xy 348.867905 -222.317308) (xy 348.81657 -222.309178) (xy 348.76714 -222.293117)
			(xy 348.72083 -222.269521) (xy 348.678782 -222.238971) (xy 348.642031 -222.20222) (xy 348.611481 -222.160172)
			(xy 348.587885 -222.113862) (xy 348.571824 -222.064432) (xy 348.563694 -222.013097) (xy 348.423696 -222.013097)
			(xy 348.415606 -222.064178) (xy 348.399545 -222.113608) (xy 348.375949 -222.159918) (xy 348.345399 -222.201966)
			(xy 348.308648 -222.238717) (xy 348.2666 -222.269267) (xy 348.22029 -222.292863) (xy 348.17086 -222.308924)
			(xy 348.119525 -222.317054) (xy 348.067551 -222.317054) (xy 348.016216 -222.308924) (xy 347.966786 -222.292863)
			(xy 347.920476 -222.269267) (xy 347.878428 -222.238717) (xy 347.841677 -222.201966) (xy 347.811127 -222.159918)
			(xy 347.787531 -222.113608) (xy 347.77147 -222.064178) (xy 347.76334 -222.012843) (xy 347.62389 -222.012843)
			(xy 347.61576 -222.064178) (xy 347.599699 -222.113608) (xy 347.576103 -222.159918) (xy 347.545553 -222.201966)
			(xy 347.508802 -222.238717) (xy 347.466754 -222.269267) (xy 347.420444 -222.292863) (xy 347.371014 -222.308924)
			(xy 347.319679 -222.317054) (xy 347.267705 -222.317054) (xy 347.21637 -222.308924) (xy 347.16694 -222.292863)
			(xy 347.12063 -222.269267) (xy 347.078582 -222.238717) (xy 347.041831 -222.201966) (xy 347.011281 -222.159918)
			(xy 346.987685 -222.113608) (xy 346.971624 -222.064178) (xy 346.963494 -222.012843) (xy 346.82379 -222.012843)
			(xy 346.81566 -222.064178) (xy 346.799599 -222.113608) (xy 346.776003 -222.159918) (xy 346.745453 -222.201966)
			(xy 346.708702 -222.238717) (xy 346.666654 -222.269267) (xy 346.620344 -222.292863) (xy 346.570914 -222.308924)
			(xy 346.519579 -222.317054) (xy 346.467605 -222.317054) (xy 346.41627 -222.308924) (xy 346.36684 -222.292863)
			(xy 346.32053 -222.269267) (xy 346.278482 -222.238717) (xy 346.241731 -222.201966) (xy 346.211181 -222.159918)
			(xy 346.187585 -222.113608) (xy 346.171524 -222.064178) (xy 346.163394 -222.012843) (xy 345.35364 -222.012843)
			(xy 345.35364 -222.18142) (xy 345.354068 -222.191488) (xy 345.361792 -222.210083) (xy 345.368626 -222.217488)
			(xy 345.605862 -222.454724) (xy 345.62923 -222.462344) (xy 345.641422 -222.460312) (xy 345.654416 -222.458377)
			(xy 345.680609 -222.456342) (xy 345.693746 -222.456248) (xy 345.719732 -222.456761) (xy 345.771064 -222.464897)
			(xy 345.820491 -222.480961) (xy 345.866797 -222.504559) (xy 345.908843 -222.535109) (xy 345.945592 -222.571859)
			(xy 345.976142 -222.613905) (xy 345.999739 -222.660211) (xy 346.015804 -222.709638) (xy 346.023939 -222.76097)
			(xy 346.024454 -222.786956) (xy 346.024345 -222.800092) (xy 346.022314 -222.826285) (xy 346.02039 -222.83928)
			(xy 346.018358 -222.851472) (xy 346.025978 -222.87484) (xy 346.096336 -222.945198) (xy 346.103702 -222.952038)
			(xy 346.122235 -222.95978) (xy 346.142319 -222.95978) (xy 346.160852 -222.952038) (xy 346.168218 -222.945198)
			(xy 346.178378 -222.934784) (xy 346.184982 -222.906844) (xy 346.18041 -222.892874) (xy 346.172254 -222.867156)
			(xy 346.163442 -222.81393) (xy 346.162884 -222.786956) (xy 346.163397 -222.760969) (xy 346.171534 -222.709635)
			(xy 346.187601 -222.660207) (xy 346.211203 -222.6139) (xy 346.241758 -222.571856) (xy 346.278513 -222.535108)
			(xy 346.320565 -222.504563) (xy 346.366877 -222.480972) (xy 346.416309 -222.464916) (xy 346.467645 -222.456791)
			(xy 346.519619 -222.456796) (xy 346.570953 -222.464931) (xy 346.620382 -222.480997) (xy 346.66669 -222.504597)
			(xy 346.708735 -222.53515) (xy 346.745484 -222.571904) (xy 346.776031 -222.613955) (xy 346.799623 -222.660266)
			(xy 346.815681 -222.709698) (xy 346.823808 -222.761033) (xy 346.823805 -222.812943) (xy 346.963494 -222.812943)
			(xy 346.963494 -222.760969) (xy 346.971624 -222.709634) (xy 346.987685 -222.660204) (xy 347.011281 -222.613894)
			(xy 347.041831 -222.571846) (xy 347.078582 -222.535095) (xy 347.12063 -222.504545) (xy 347.16694 -222.480949)
			(xy 347.21637 -222.464888) (xy 347.267705 -222.456758) (xy 347.319679 -222.456758) (xy 347.371014 -222.464888)
			(xy 347.420444 -222.480949) (xy 347.466754 -222.504545) (xy 347.508802 -222.535095) (xy 347.545553 -222.571846)
			(xy 347.576103 -222.613894) (xy 347.599699 -222.660204) (xy 347.61576 -222.709634) (xy 347.62389 -222.760969)
			(xy 347.6244 -222.786956) (xy 347.62389 -222.812943) (xy 347.76334 -222.812943) (xy 347.76334 -222.760969)
			(xy 347.77147 -222.709634) (xy 347.787531 -222.660204) (xy 347.811127 -222.613894) (xy 347.841677 -222.571846)
			(xy 347.878428 -222.535095) (xy 347.920476 -222.504545) (xy 347.966786 -222.480949) (xy 348.016216 -222.464888)
			(xy 348.067551 -222.456758) (xy 348.119525 -222.456758) (xy 348.17086 -222.464888) (xy 348.22029 -222.480949)
			(xy 348.2666 -222.504545) (xy 348.308648 -222.535095) (xy 348.345399 -222.571846) (xy 348.375949 -222.613894)
			(xy 348.399545 -222.660204) (xy 348.415606 -222.709634) (xy 348.423736 -222.760969) (xy 348.424246 -222.786956)
			(xy 348.423736 -222.812943) (xy 348.56344 -222.812943) (xy 348.56344 -222.760969) (xy 348.57157 -222.709634)
			(xy 348.587631 -222.660204) (xy 348.611227 -222.613894) (xy 348.641777 -222.571846) (xy 348.678528 -222.535095)
			(xy 348.720576 -222.504545) (xy 348.766886 -222.480949) (xy 348.816316 -222.464888) (xy 348.867651 -222.456758)
			(xy 348.919625 -222.456758) (xy 348.97096 -222.464888) (xy 349.02039 -222.480949) (xy 349.0667 -222.504545)
			(xy 349.108748 -222.535095) (xy 349.145499 -222.571846) (xy 349.176049 -222.613894) (xy 349.199645 -222.660204)
			(xy 349.215706 -222.709634) (xy 349.223836 -222.760969) (xy 349.224346 -222.786956) (xy 349.223836 -222.812943)
			(xy 349.36354 -222.812943) (xy 349.36354 -222.760969) (xy 349.37167 -222.709634) (xy 349.387731 -222.660204)
			(xy 349.411327 -222.613894) (xy 349.441877 -222.571846) (xy 349.478628 -222.535095) (xy 349.520676 -222.504545)
			(xy 349.566986 -222.480949) (xy 349.616416 -222.464888) (xy 349.667751 -222.456758) (xy 349.719725 -222.456758)
			(xy 349.77106 -222.464888) (xy 349.82049 -222.480949) (xy 349.8668 -222.504545) (xy 349.908848 -222.535095)
			(xy 349.945599 -222.571846) (xy 349.976149 -222.613894) (xy 349.999745 -222.660204) (xy 350.015806 -222.709634)
			(xy 350.023936 -222.760969) (xy 350.024446 -222.786956) (xy 350.023936 -222.812943) (xy 350.163386 -222.812943)
			(xy 350.163386 -222.760969) (xy 350.171516 -222.709634) (xy 350.187577 -222.660204) (xy 350.211173 -222.613894)
			(xy 350.241723 -222.571846) (xy 350.278474 -222.535095) (xy 350.320522 -222.504545) (xy 350.366832 -222.480949)
			(xy 350.416262 -222.464888) (xy 350.467597 -222.456758) (xy 350.519571 -222.456758) (xy 350.570906 -222.464888)
			(xy 350.620336 -222.480949) (xy 350.666646 -222.504545) (xy 350.708694 -222.535095) (xy 350.745445 -222.571846)
			(xy 350.775995 -222.613894) (xy 350.799591 -222.660204) (xy 350.815652 -222.709634) (xy 350.823782 -222.760969)
			(xy 350.824292 -222.786956) (xy 350.823782 -222.812943) (xy 350.963486 -222.812943) (xy 350.963486 -222.760969)
			(xy 350.971616 -222.709634) (xy 350.987677 -222.660204) (xy 351.011273 -222.613894) (xy 351.041823 -222.571846)
			(xy 351.078574 -222.535095) (xy 351.120622 -222.504545) (xy 351.166932 -222.480949) (xy 351.216362 -222.464888)
			(xy 351.267697 -222.456758) (xy 351.319671 -222.456758) (xy 351.371006 -222.464888) (xy 351.420436 -222.480949)
			(xy 351.466746 -222.504545) (xy 351.508794 -222.535095) (xy 351.545545 -222.571846) (xy 351.576095 -222.613894)
			(xy 351.599691 -222.660204) (xy 351.615752 -222.709634) (xy 351.623882 -222.760969) (xy 351.624392 -222.786956)
			(xy 351.623882 -222.812943) (xy 351.615752 -222.864278) (xy 351.599691 -222.913708) (xy 351.576095 -222.960018)
			(xy 351.545545 -223.002066) (xy 351.508794 -223.038817) (xy 351.466746 -223.069367) (xy 351.420436 -223.092963)
			(xy 351.371006 -223.109024) (xy 351.319671 -223.117154) (xy 351.267697 -223.117154) (xy 351.216362 -223.109024)
			(xy 351.166932 -223.092963) (xy 351.120622 -223.069367) (xy 351.078574 -223.038817) (xy 351.041823 -223.002066)
			(xy 351.011273 -222.960018) (xy 350.987677 -222.913708) (xy 350.971616 -222.864278) (xy 350.963486 -222.812943)
			(xy 350.823782 -222.812943) (xy 350.815652 -222.864278) (xy 350.799591 -222.913708) (xy 350.775995 -222.960018)
			(xy 350.745445 -223.002066) (xy 350.708694 -223.038817) (xy 350.666646 -223.069367) (xy 350.620336 -223.092963)
			(xy 350.570906 -223.109024) (xy 350.519571 -223.117154) (xy 350.467597 -223.117154) (xy 350.416262 -223.109024)
			(xy 350.366832 -223.092963) (xy 350.320522 -223.069367) (xy 350.278474 -223.038817) (xy 350.241723 -223.002066)
			(xy 350.211173 -222.960018) (xy 350.187577 -222.913708) (xy 350.171516 -222.864278) (xy 350.163386 -222.812943)
			(xy 350.023936 -222.812943) (xy 350.015806 -222.864278) (xy 349.999745 -222.913708) (xy 349.976149 -222.960018)
			(xy 349.945599 -223.002066) (xy 349.908848 -223.038817) (xy 349.8668 -223.069367) (xy 349.82049 -223.092963)
			(xy 349.77106 -223.109024) (xy 349.719725 -223.117154) (xy 349.667751 -223.117154) (xy 349.616416 -223.109024)
			(xy 349.566986 -223.092963) (xy 349.520676 -223.069367) (xy 349.478628 -223.038817) (xy 349.441877 -223.002066)
			(xy 349.411327 -222.960018) (xy 349.387731 -222.913708) (xy 349.37167 -222.864278) (xy 349.36354 -222.812943)
			(xy 349.223836 -222.812943) (xy 349.215706 -222.864278) (xy 349.199645 -222.913708) (xy 349.176049 -222.960018)
			(xy 349.145499 -223.002066) (xy 349.108748 -223.038817) (xy 349.0667 -223.069367) (xy 349.02039 -223.092963)
			(xy 348.97096 -223.109024) (xy 348.919625 -223.117154) (xy 348.867651 -223.117154) (xy 348.816316 -223.109024)
			(xy 348.766886 -223.092963) (xy 348.720576 -223.069367) (xy 348.678528 -223.038817) (xy 348.641777 -223.002066)
			(xy 348.611227 -222.960018) (xy 348.587631 -222.913708) (xy 348.57157 -222.864278) (xy 348.56344 -222.812943)
			(xy 348.423736 -222.812943) (xy 348.415606 -222.864278) (xy 348.399545 -222.913708) (xy 348.375949 -222.960018)
			(xy 348.345399 -223.002066) (xy 348.308648 -223.038817) (xy 348.2666 -223.069367) (xy 348.22029 -223.092963)
			(xy 348.17086 -223.109024) (xy 348.119525 -223.117154) (xy 348.067551 -223.117154) (xy 348.016216 -223.109024)
			(xy 347.966786 -223.092963) (xy 347.920476 -223.069367) (xy 347.878428 -223.038817) (xy 347.841677 -223.002066)
			(xy 347.811127 -222.960018) (xy 347.787531 -222.913708) (xy 347.77147 -222.864278) (xy 347.76334 -222.812943)
			(xy 347.62389 -222.812943) (xy 347.61576 -222.864278) (xy 347.599699 -222.913708) (xy 347.576103 -222.960018)
			(xy 347.545553 -223.002066) (xy 347.508802 -223.038817) (xy 347.466754 -223.069367) (xy 347.420444 -223.092963)
			(xy 347.371014 -223.109024) (xy 347.319679 -223.117154) (xy 347.267705 -223.117154) (xy 347.21637 -223.109024)
			(xy 347.16694 -223.092963) (xy 347.12063 -223.069367) (xy 347.078582 -223.038817) (xy 347.041831 -223.002066)
			(xy 347.011281 -222.960018) (xy 346.987685 -222.913708) (xy 346.971624 -222.864278) (xy 346.963494 -222.812943)
			(xy 346.823805 -222.812943) (xy 346.823805 -222.813007) (xy 346.815671 -222.864341) (xy 346.799608 -222.913771)
			(xy 346.77601 -222.960079) (xy 346.745458 -223.002126) (xy 346.708705 -223.038876) (xy 346.666655 -223.069424)
			(xy 346.620345 -223.093019) (xy 346.570914 -223.109078) (xy 346.519579 -223.117207) (xy 346.493592 -223.117664)
			(xy 346.466617 -223.11711) (xy 346.413391 -223.1083) (xy 346.387674 -223.100138) (xy 346.373704 -223.095566)
			(xy 346.345764 -223.10217) (xy 346.33535 -223.11233) (xy 346.328509 -223.119698) (xy 346.320762 -223.138235)
			(xy 346.320754 -223.158325) (xy 346.328486 -223.176868) (xy 346.33535 -223.184212) (xy 346.405708 -223.25457)
			(xy 346.429076 -223.26219) (xy 346.441268 -223.260158) (xy 346.454262 -223.258226) (xy 346.480456 -223.256194)
			(xy 346.493592 -223.256094) (xy 346.519582 -223.256577) (xy 346.570921 -223.264707) (xy 346.620357 -223.280768)
			(xy 346.666671 -223.304366) (xy 346.708723 -223.334918) (xy 346.745478 -223.371672) (xy 346.776031 -223.413724)
			(xy 346.799629 -223.460038) (xy 346.815692 -223.509473) (xy 346.823823 -223.560812) (xy 346.8243 -223.586802)
			(xy 346.824189 -223.599938) (xy 346.822155 -223.626131) (xy 346.820236 -223.639126) (xy 346.818204 -223.651318)
			(xy 346.825824 -223.674686) (xy 346.896436 -223.745298) (xy 346.903802 -223.752138) (xy 346.922335 -223.75988)
			(xy 346.942419 -223.75988) (xy 346.960952 -223.752138) (xy 346.968318 -223.745298) (xy 346.978732 -223.735138)
			(xy 346.985336 -223.706944) (xy 346.98051 -223.693228) (xy 346.972326 -223.667386) (xy 346.963522 -223.613903)
			(xy 346.962984 -223.586802) (xy 346.963467 -223.560812) (xy 346.971598 -223.509472) (xy 346.987661 -223.460036)
			(xy 347.011259 -223.413721) (xy 347.041812 -223.371668) (xy 347.078568 -223.334913) (xy 347.12062 -223.304359)
			(xy 347.166935 -223.280761) (xy 347.216371 -223.264698) (xy 347.267711 -223.256567) (xy 347.319691 -223.256567)
			(xy 347.371031 -223.264699) (xy 347.420467 -223.280762) (xy 347.466782 -223.304361) (xy 347.508834 -223.334914)
			(xy 347.54559 -223.37167) (xy 347.576142 -223.413723) (xy 347.59974 -223.460038) (xy 347.615802 -223.509474)
			(xy 347.623933 -223.560815) (xy 347.623932 -223.612789) (xy 347.76334 -223.612789) (xy 347.76334 -223.560815)
			(xy 347.77147 -223.50948) (xy 347.787531 -223.46005) (xy 347.811127 -223.41374) (xy 347.841677 -223.371692)
			(xy 347.878428 -223.334941) (xy 347.920476 -223.304391) (xy 347.966786 -223.280795) (xy 348.016216 -223.264734)
			(xy 348.067551 -223.256604) (xy 348.119525 -223.256604) (xy 348.17086 -223.264734) (xy 348.22029 -223.280795)
			(xy 348.2666 -223.304391) (xy 348.308648 -223.334941) (xy 348.345399 -223.371692) (xy 348.375949 -223.41374)
			(xy 348.399545 -223.46005) (xy 348.415606 -223.50948) (xy 348.423736 -223.560815) (xy 348.424246 -223.586802)
			(xy 348.423736 -223.612789) (xy 348.56344 -223.612789) (xy 348.56344 -223.560815) (xy 348.57157 -223.50948)
			(xy 348.587631 -223.46005) (xy 348.611227 -223.41374) (xy 348.641777 -223.371692) (xy 348.678528 -223.334941)
			(xy 348.720576 -223.304391) (xy 348.766886 -223.280795) (xy 348.816316 -223.264734) (xy 348.867651 -223.256604)
			(xy 348.919625 -223.256604) (xy 348.97096 -223.264734) (xy 349.02039 -223.280795) (xy 349.0667 -223.304391)
			(xy 349.108748 -223.334941) (xy 349.145499 -223.371692) (xy 349.176049 -223.41374) (xy 349.199645 -223.46005)
			(xy 349.215706 -223.50948) (xy 349.223836 -223.560815) (xy 349.224346 -223.586802) (xy 349.223836 -223.612789)
			(xy 349.36354 -223.612789) (xy 349.36354 -223.560815) (xy 349.37167 -223.50948) (xy 349.387731 -223.46005)
			(xy 349.411327 -223.41374) (xy 349.441877 -223.371692) (xy 349.478628 -223.334941) (xy 349.520676 -223.304391)
			(xy 349.566986 -223.280795) (xy 349.616416 -223.264734) (xy 349.667751 -223.256604) (xy 349.719725 -223.256604)
			(xy 349.77106 -223.264734) (xy 349.82049 -223.280795) (xy 349.8668 -223.304391) (xy 349.908848 -223.334941)
			(xy 349.945599 -223.371692) (xy 349.976149 -223.41374) (xy 349.999745 -223.46005) (xy 350.015806 -223.50948)
			(xy 350.023936 -223.560815) (xy 350.024446 -223.586802) (xy 350.023936 -223.612789) (xy 350.163386 -223.612789)
			(xy 350.163386 -223.560815) (xy 350.171516 -223.50948) (xy 350.187577 -223.46005) (xy 350.211173 -223.41374)
			(xy 350.241723 -223.371692) (xy 350.278474 -223.334941) (xy 350.320522 -223.304391) (xy 350.366832 -223.280795)
			(xy 350.416262 -223.264734) (xy 350.467597 -223.256604) (xy 350.519571 -223.256604) (xy 350.570906 -223.264734)
			(xy 350.620336 -223.280795) (xy 350.666646 -223.304391) (xy 350.708694 -223.334941) (xy 350.745445 -223.371692)
			(xy 350.775995 -223.41374) (xy 350.799591 -223.46005) (xy 350.815652 -223.50948) (xy 350.823782 -223.560815)
			(xy 350.824292 -223.586802) (xy 350.823782 -223.612789) (xy 350.963486 -223.612789) (xy 350.963486 -223.560815)
			(xy 350.971616 -223.50948) (xy 350.987677 -223.46005) (xy 351.011273 -223.41374) (xy 351.041823 -223.371692)
			(xy 351.078574 -223.334941) (xy 351.120622 -223.304391) (xy 351.166932 -223.280795) (xy 351.216362 -223.264734)
			(xy 351.267697 -223.256604) (xy 351.319671 -223.256604) (xy 351.371006 -223.264734) (xy 351.420436 -223.280795)
			(xy 351.466746 -223.304391) (xy 351.508794 -223.334941) (xy 351.545545 -223.371692) (xy 351.576095 -223.41374)
			(xy 351.599691 -223.46005) (xy 351.615752 -223.50948) (xy 351.623882 -223.560815) (xy 351.624392 -223.586802)
			(xy 351.623882 -223.612789) (xy 351.615752 -223.664124) (xy 351.599691 -223.713554) (xy 351.576095 -223.759864)
			(xy 351.545545 -223.801912) (xy 351.508794 -223.838663) (xy 351.466746 -223.869213) (xy 351.420436 -223.892809)
			(xy 351.371006 -223.90887) (xy 351.319671 -223.917) (xy 351.267697 -223.917) (xy 351.216362 -223.90887)
			(xy 351.166932 -223.892809) (xy 351.120622 -223.869213) (xy 351.078574 -223.838663) (xy 351.041823 -223.801912)
			(xy 351.011273 -223.759864) (xy 350.987677 -223.713554) (xy 350.971616 -223.664124) (xy 350.963486 -223.612789)
			(xy 350.823782 -223.612789) (xy 350.815652 -223.664124) (xy 350.799591 -223.713554) (xy 350.775995 -223.759864)
			(xy 350.745445 -223.801912) (xy 350.708694 -223.838663) (xy 350.666646 -223.869213) (xy 350.620336 -223.892809)
			(xy 350.570906 -223.90887) (xy 350.519571 -223.917) (xy 350.467597 -223.917) (xy 350.416262 -223.90887)
			(xy 350.366832 -223.892809) (xy 350.320522 -223.869213) (xy 350.278474 -223.838663) (xy 350.241723 -223.801912)
			(xy 350.211173 -223.759864) (xy 350.187577 -223.713554) (xy 350.171516 -223.664124) (xy 350.163386 -223.612789)
			(xy 350.023936 -223.612789) (xy 350.015806 -223.664124) (xy 349.999745 -223.713554) (xy 349.976149 -223.759864)
			(xy 349.945599 -223.801912) (xy 349.908848 -223.838663) (xy 349.8668 -223.869213) (xy 349.82049 -223.892809)
			(xy 349.77106 -223.90887) (xy 349.719725 -223.917) (xy 349.667751 -223.917) (xy 349.616416 -223.90887)
			(xy 349.566986 -223.892809) (xy 349.520676 -223.869213) (xy 349.478628 -223.838663) (xy 349.441877 -223.801912)
			(xy 349.411327 -223.759864) (xy 349.387731 -223.713554) (xy 349.37167 -223.664124) (xy 349.36354 -223.612789)
			(xy 349.223836 -223.612789) (xy 349.215706 -223.664124) (xy 349.199645 -223.713554) (xy 349.176049 -223.759864)
			(xy 349.145499 -223.801912) (xy 349.108748 -223.838663) (xy 349.0667 -223.869213) (xy 349.02039 -223.892809)
			(xy 348.97096 -223.90887) (xy 348.919625 -223.917) (xy 348.867651 -223.917) (xy 348.816316 -223.90887)
			(xy 348.766886 -223.892809) (xy 348.720576 -223.869213) (xy 348.678528 -223.838663) (xy 348.641777 -223.801912)
			(xy 348.611227 -223.759864) (xy 348.587631 -223.713554) (xy 348.57157 -223.664124) (xy 348.56344 -223.612789)
			(xy 348.423736 -223.612789) (xy 348.415606 -223.664124) (xy 348.399545 -223.713554) (xy 348.375949 -223.759864)
			(xy 348.345399 -223.801912) (xy 348.308648 -223.838663) (xy 348.2666 -223.869213) (xy 348.22029 -223.892809)
			(xy 348.17086 -223.90887) (xy 348.119525 -223.917) (xy 348.067551 -223.917) (xy 348.016216 -223.90887)
			(xy 347.966786 -223.892809) (xy 347.920476 -223.869213) (xy 347.878428 -223.838663) (xy 347.841677 -223.801912)
			(xy 347.811127 -223.759864) (xy 347.787531 -223.713554) (xy 347.77147 -223.664124) (xy 347.76334 -223.612789)
			(xy 347.623932 -223.612789) (xy 347.623932 -223.612795) (xy 347.6158 -223.664135) (xy 347.599737 -223.713571)
			(xy 347.576137 -223.759885) (xy 347.545584 -223.801937) (xy 347.508827 -223.838692) (xy 347.466774 -223.869244)
			(xy 347.420459 -223.892842) (xy 347.371022 -223.908903) (xy 347.319682 -223.917033) (xy 347.293692 -223.91751)
			(xy 347.266589 -223.916987) (xy 347.213106 -223.908176) (xy 347.187266 -223.899984) (xy 347.17355 -223.895158)
			(xy 347.145356 -223.901762) (xy 347.135196 -223.912176) (xy 347.128359 -223.919541) (xy 347.120622 -223.938072)
			(xy 347.120627 -223.958152) (xy 347.128372 -223.976679) (xy 347.135196 -223.984058) (xy 347.205808 -224.05467)
			(xy 347.229176 -224.06229) (xy 347.241368 -224.060258) (xy 347.254362 -224.058326) (xy 347.280556 -224.056294)
			(xy 347.293692 -224.056194) (xy 347.319682 -224.056677) (xy 347.371021 -224.064807) (xy 347.420457 -224.080868)
			(xy 347.466771 -224.104466) (xy 347.508823 -224.135018) (xy 347.545578 -224.171772) (xy 347.576131 -224.213824)
			(xy 347.599729 -224.260138) (xy 347.615792 -224.309573) (xy 347.623923 -224.360912) (xy 347.6244 -224.386902)
			(xy 347.624289 -224.400038) (xy 347.622255 -224.426231) (xy 347.620336 -224.439226) (xy 347.618304 -224.451418)
			(xy 347.625924 -224.474786) (xy 347.696282 -224.545144) (xy 347.703648 -224.551984) (xy 347.722181 -224.559726)
			(xy 347.742265 -224.559726) (xy 347.760798 -224.551984) (xy 347.768164 -224.545144) (xy 347.778324 -224.53473)
			(xy 347.784928 -224.50679) (xy 347.780356 -224.49282) (xy 347.772205 -224.467101) (xy 347.763404 -224.413876)
			(xy 347.76283 -224.386902) (xy 347.76334 -224.360915) (xy 347.77147 -224.30958) (xy 347.787531 -224.26015)
			(xy 347.811127 -224.21384) (xy 347.841677 -224.171792) (xy 347.878428 -224.135041) (xy 347.920476 -224.104491)
			(xy 347.966786 -224.080895) (xy 348.016216 -224.064834) (xy 348.067551 -224.056704) (xy 348.119525 -224.056704)
			(xy 348.17086 -224.064834) (xy 348.22029 -224.080895) (xy 348.2666 -224.104491) (xy 348.308648 -224.135041)
			(xy 348.345399 -224.171792) (xy 348.375949 -224.21384) (xy 348.399545 -224.26015) (xy 348.415606 -224.30958)
			(xy 348.423736 -224.360915) (xy 348.424246 -224.386902) (xy 348.423577 -224.417122) (xy 348.412587 -224.476553)
			(xy 348.402402 -224.505012) (xy 348.39783 -224.51695) (xy 348.400878 -224.541588) (xy 348.455488 -224.620836)
			(xy 348.463016 -224.630727) (xy 348.484983 -224.642301) (xy 348.497398 -224.642934)
		)
		(stroke
			(width 0)
			(type solid)
		)
		(fill yes)
		(layer "In11.Cu")
		(net "P3V3_FPGA_VCCIO1")
	)
	(gr_poly
		(pts
			(xy 393.753086 -296.570908) (xy 393.764505 -296.570278) (xy 393.785087 -296.560383) (xy 393.79271 -296.551858)
			(xy 393.849606 -296.480992) (xy 393.854686 -296.45864) (xy 393.852146 -296.44721) (xy 393.848439 -296.429343)
			(xy 393.844487 -296.393066) (xy 393.844272 -296.37482) (xy 393.844782 -296.348833) (xy 393.852912 -296.297498)
			(xy 393.868973 -296.248068) (xy 393.892569 -296.201758) (xy 393.923119 -296.15971) (xy 393.95987 -296.122959)
			(xy 394.001918 -296.092409) (xy 394.048228 -296.068813) (xy 394.097658 -296.052752) (xy 394.148993 -296.044622)
			(xy 394.200967 -296.044622) (xy 394.252302 -296.052752) (xy 394.301732 -296.068813) (xy 394.348042 -296.092409)
			(xy 394.39009 -296.122959) (xy 394.426841 -296.15971) (xy 394.457391 -296.201758) (xy 394.480987 -296.248068)
			(xy 394.497048 -296.297498) (xy 394.505178 -296.348833) (xy 394.505688 -296.37482) (xy 394.50549 -296.393067)
			(xy 394.501545 -296.429347) (xy 394.497814 -296.44721) (xy 394.495274 -296.45864) (xy 394.500354 -296.480992)
			(xy 394.55725 -296.551858) (xy 394.564879 -296.560378) (xy 394.585456 -296.570288) (xy 394.596874 -296.570908)
			(xy 394.703046 -296.570908) (xy 394.714469 -296.570286) (xy 394.735064 -296.560401) (xy 394.74267 -296.551858)
			(xy 394.799566 -296.480992) (xy 394.804646 -296.45864) (xy 394.802106 -296.44721) (xy 394.798399 -296.429343)
			(xy 394.794448 -296.393066) (xy 394.794232 -296.37482) (xy 394.794742 -296.348833) (xy 394.802872 -296.297498)
			(xy 394.818933 -296.248068) (xy 394.842529 -296.201758) (xy 394.873079 -296.15971) (xy 394.90983 -296.122959)
			(xy 394.951878 -296.092409) (xy 394.998188 -296.068813) (xy 395.047618 -296.052752) (xy 395.098953 -296.044622)
			(xy 395.150927 -296.044622) (xy 395.202262 -296.052752) (xy 395.251692 -296.068813) (xy 395.298002 -296.092409)
			(xy 395.34005 -296.122959) (xy 395.376801 -296.15971) (xy 395.407351 -296.201758) (xy 395.430947 -296.248068)
			(xy 395.447008 -296.297498) (xy 395.455138 -296.348833) (xy 395.455648 -296.37482) (xy 395.45545 -296.393067)
			(xy 395.451506 -296.429347) (xy 395.447774 -296.44721) (xy 395.445234 -296.45864) (xy 395.450314 -296.480992)
			(xy 395.50721 -296.551858) (xy 395.514843 -296.560368) (xy 395.53542 -296.570254) (xy 395.546834 -296.570908)
			(xy 396.11808 -296.570908) (xy 396.127952 -296.570437) (xy 396.146236 -296.562979) (xy 396.15364 -296.55643)
			(xy 396.153894 -296.556176) (xy 396.378684 -296.331386) (xy 396.379192 -296.330878) (xy 396.385775 -296.323497)
			(xy 396.393231 -296.305198) (xy 396.39367 -296.295318) (xy 396.39367 -294.91051) (xy 396.393248 -294.90044)
			(xy 396.385533 -294.881835) (xy 396.378684 -294.874442) (xy 396.283434 -294.779192) (xy 396.277547 -294.773797)
			(xy 396.263319 -294.766566) (xy 396.255494 -294.764968) (xy 396.25524 -294.764968) (xy 396.24743 -294.764075)
			(xy 396.23191 -294.766527) (xy 396.22476 -294.769794) (xy 396.224506 -294.769794) (xy 396.201193 -294.781062)
			(xy 396.151933 -294.797009) (xy 396.100789 -294.805081) (xy 396.0749 -294.805608) (xy 396.047572 -294.805045)
			(xy 395.993659 -294.796058) (xy 395.941958 -294.778329) (xy 395.893875 -294.75234) (xy 395.871954 -294.736012)
			(xy 395.865604 -294.731186) (xy 395.842236 -294.722804) (xy 395.838057 -294.721395) (xy 395.829373 -294.719864)
			(xy 395.824964 -294.719756) (xy 395.374876 -294.719756) (xy 395.370465 -294.719842) (xy 395.361777 -294.721372)
			(xy 395.357604 -294.722804) (xy 395.334236 -294.731186) (xy 395.327886 -294.736012) (xy 395.305964 -294.752338)
			(xy 395.257881 -294.778327) (xy 395.206181 -294.796056) (xy 395.152268 -294.805043) (xy 395.097612 -294.805043)
			(xy 395.043699 -294.796056) (xy 394.991999 -294.778327) (xy 394.943916 -294.752338) (xy 394.921994 -294.736012)
			(xy 394.915644 -294.731186) (xy 394.892276 -294.722804) (xy 394.888098 -294.721391) (xy 394.879413 -294.719854)
			(xy 394.875004 -294.719756) (xy 394.424916 -294.719756) (xy 394.420506 -294.719847) (xy 394.411821 -294.721387)
			(xy 394.407644 -294.722804) (xy 394.384276 -294.731186) (xy 394.377926 -294.736012) (xy 394.356003 -294.752337)
			(xy 394.307921 -294.778323) (xy 394.25622 -294.796049) (xy 394.202308 -294.805033) (xy 394.17498 -294.805608)
			(xy 394.149869 -294.805147) (xy 394.100223 -294.797563) (xy 394.052295 -294.782558) (xy 394.007189 -294.760476)
			(xy 393.96594 -294.731826) (xy 393.9295 -294.697267) (xy 393.898706 -294.657594) (xy 393.874266 -294.613719)
			(xy 393.856744 -294.566654) (xy 393.846542 -294.517479) (xy 393.84478 -294.492426) (xy 393.844272 -294.482774)
			(xy 393.836652 -294.465756) (xy 393.58189 -294.211248) (xy 393.578842 -294.211248) (xy 393.503912 -294.133016)
			(xy 393.50315 -294.132254) (xy 392.284204 -292.913308) (xy 392.267186 -292.905688) (xy 392.257534 -292.90518)
			(xy 392.230648 -292.903241) (xy 392.177989 -292.891733) (xy 392.127895 -292.871834) (xy 392.081691 -292.844074)
			(xy 392.040603 -292.809187) (xy 392.005717 -292.768097) (xy 391.977959 -292.721892) (xy 391.958063 -292.671797)
			(xy 391.946557 -292.619138) (xy 391.944606 -292.592252) (xy 391.944098 -292.5826) (xy 391.936478 -292.565582)
			(xy 391.33399 -291.963094) (xy 391.316972 -291.955474) (xy 391.30732 -291.954966) (xy 391.28046 -291.953013)
			(xy 391.227857 -291.941489) (xy 391.177817 -291.921593) (xy 391.131663 -291.89385) (xy 391.090614 -291.858995)
			(xy 391.055757 -291.817948) (xy 391.028013 -291.771794) (xy 391.008114 -291.721755) (xy 390.996588 -291.669152)
			(xy 390.994646 -291.642292) (xy 390.994138 -291.63264) (xy 390.986518 -291.615622) (xy 390.38403 -291.013134)
			(xy 390.367012 -291.005514) (xy 390.35736 -291.005006) (xy 390.330502 -291.003049) (xy 390.277904 -290.991518)
			(xy 390.22787 -290.971618) (xy 390.18172 -290.943873) (xy 390.140676 -290.909018) (xy 390.105822 -290.867973)
			(xy 390.078079 -290.821823) (xy 390.058179 -290.771788) (xy 390.04665 -290.719189) (xy 390.044686 -290.692332)
			(xy 390.044178 -290.68268) (xy 390.036558 -290.665662) (xy 389.43407 -290.063174) (xy 389.417052 -290.055554)
			(xy 389.4074 -290.055046) (xy 389.380539 -290.053092) (xy 389.327934 -290.041567) (xy 389.277891 -290.02167)
			(xy 389.231733 -289.993928) (xy 389.190679 -289.959074) (xy 389.155816 -289.918029) (xy 389.128063 -289.871877)
			(xy 389.108155 -289.821839) (xy 389.096618 -289.769236) (xy 389.094726 -289.742372) (xy 389.094218 -289.73272)
			(xy 389.086598 -289.715702) (xy 388.48411 -289.113214) (xy 388.467092 -289.105594) (xy 388.45744 -289.105086)
			(xy 388.430584 -289.103128) (xy 388.37799 -289.091594) (xy 388.327959 -289.071691) (xy 388.281814 -289.043945)
			(xy 388.240775 -289.009089) (xy 388.205925 -288.968045) (xy 388.178186 -288.921896) (xy 388.158291 -288.871862)
			(xy 388.146766 -288.819266) (xy 388.144766 -288.792412) (xy 388.144258 -288.78276) (xy 388.136638 -288.765742)
			(xy 386.58419 -287.213294) (xy 386.567172 -287.205674) (xy 386.55752 -287.205166) (xy 386.532474 -287.203366)
			(xy 386.483313 -287.193148) (xy 386.436262 -287.175617) (xy 386.392401 -287.151175) (xy 386.352738 -287.120383)
			(xy 386.318186 -287.08395) (xy 386.289538 -287.042713) (xy 386.267453 -286.997619) (xy 386.252438 -286.949705)
			(xy 386.244838 -286.900072) (xy 386.244338 -286.874966) (xy 386.24486 -286.84852) (xy 386.253279 -286.796303)
			(xy 386.269899 -286.746091) (xy 386.294296 -286.699162) (xy 386.325848 -286.656712) (xy 386.363751 -286.619823)
			(xy 386.407041 -286.589433) (xy 386.454613 -286.566318) (xy 386.479796 -286.558228) (xy 386.495798 -286.553402)
			(xy 386.515864 -286.526478) (xy 386.515864 -286.27324) (xy 386.495798 -286.246316) (xy 386.479796 -286.24149)
			(xy 386.45462 -286.233379) (xy 386.407037 -286.210284) (xy 386.363738 -286.179909) (xy 386.325825 -286.14303)
			(xy 386.294266 -286.100586) (xy 386.269865 -286.05366) (xy 386.253244 -286.003449) (xy 386.244828 -285.951232)
			(xy 386.24483 -285.898341) (xy 386.253251 -285.846124) (xy 386.269876 -285.795914) (xy 386.294281 -285.74899)
			(xy 386.325843 -285.706549) (xy 386.363759 -285.669673) (xy 386.407061 -285.639302) (xy 386.454645 -285.616211)
			(xy 386.479796 -285.608014) (xy 386.495798 -285.603188) (xy 386.515864 -285.576264) (xy 386.515864 -285.32328)
			(xy 386.495798 -285.296356) (xy 386.479796 -285.29153) (xy 386.454617 -285.283419) (xy 386.407028 -285.260323)
			(xy 386.363722 -285.229946) (xy 386.325804 -285.193064) (xy 386.29424 -285.150616) (xy 386.269834 -285.103686)
			(xy 386.25321 -285.053469) (xy 386.24479 -285.001246) (xy 386.244791 -284.948349) (xy 386.253211 -284.896126)
			(xy 386.269836 -284.84591) (xy 386.294242 -284.79898) (xy 386.325807 -284.756533) (xy 386.363726 -284.719651)
			(xy 386.407032 -284.689275) (xy 386.454621 -284.666179) (xy 386.479796 -284.658054) (xy 386.495798 -284.653228)
			(xy 386.515864 -284.626304) (xy 386.515864 -284.37332) (xy 386.495798 -284.346396) (xy 386.479796 -284.34157)
			(xy 386.454613 -284.333459) (xy 386.407018 -284.310362) (xy 386.363707 -284.279983) (xy 386.325783 -284.243098)
			(xy 386.294213 -284.200647) (xy 386.269803 -284.153711) (xy 386.253175 -284.103489) (xy 386.244753 -284.051261)
			(xy 386.244752 -283.998358) (xy 386.253171 -283.946129) (xy 386.269796 -283.895906) (xy 386.294203 -283.848969)
			(xy 386.325771 -283.806516) (xy 386.363693 -283.769629) (xy 386.407003 -283.739248) (xy 386.454596 -283.716148)
			(xy 386.479796 -283.708094) (xy 386.495798 -283.703268) (xy 386.515864 -283.676344) (xy 386.515864 -283.42336)
			(xy 386.495798 -283.396436) (xy 386.479796 -283.39161) (xy 386.454618 -283.383499) (xy 386.407033 -283.360403)
			(xy 386.36373 -283.330028) (xy 386.325815 -283.293147) (xy 386.294253 -283.250701) (xy 386.269849 -283.203773)
			(xy 386.253227 -283.153559) (xy 386.244809 -283.101339) (xy 386.24481 -283.048445) (xy 386.253231 -282.996225)
			(xy 386.269856 -282.946012) (xy 386.294261 -282.899085) (xy 386.325825 -282.856641) (xy 386.363743 -282.819762)
			(xy 386.407047 -282.789388) (xy 386.454633 -282.766295) (xy 386.479796 -282.758134) (xy 386.495798 -282.753308)
			(xy 386.515864 -282.726384) (xy 386.515864 -282.4734) (xy 386.495798 -282.446476) (xy 386.479796 -282.44165)
			(xy 386.454615 -282.433539) (xy 386.407023 -282.410442) (xy 386.363715 -282.380065) (xy 386.325793 -282.343181)
			(xy 386.294226 -282.300732) (xy 386.269819 -282.253799) (xy 386.253192 -282.203579) (xy 386.244772 -282.151354)
			(xy 386.244771 -282.098453) (xy 386.253191 -282.046228) (xy 386.269816 -281.996008) (xy 386.294223 -281.949074)
			(xy 386.325789 -281.906624) (xy 386.363709 -281.86974) (xy 386.407017 -281.839361) (xy 386.454608 -281.816264)
			(xy 386.479796 -281.808174) (xy 386.495798 -281.803348) (xy 386.515864 -281.776424) (xy 386.515864 -281.52344)
			(xy 386.495798 -281.496516) (xy 386.479796 -281.49169) (xy 386.45462 -281.483579) (xy 386.407037 -281.460484)
			(xy 386.363738 -281.430109) (xy 386.325825 -281.39323) (xy 386.294266 -281.350786) (xy 386.269865 -281.30386)
			(xy 386.253244 -281.253649) (xy 386.244828 -281.201432) (xy 386.24483 -281.148541) (xy 386.253251 -281.096324)
			(xy 386.269876 -281.046114) (xy 386.294281 -280.99919) (xy 386.325843 -280.956749) (xy 386.363759 -280.919873)
			(xy 386.407061 -280.889502) (xy 386.454645 -280.866411) (xy 386.479796 -280.858214) (xy 386.495798 -280.853388)
			(xy 386.515864 -280.826464) (xy 386.515864 -280.573226) (xy 386.495798 -280.546302) (xy 386.479796 -280.541476)
			(xy 386.454613 -280.533365) (xy 386.407017 -280.510267) (xy 386.363704 -280.479889) (xy 386.32578 -280.443003)
			(xy 386.294209 -280.400551) (xy 386.269799 -280.353615) (xy 386.25317 -280.303392) (xy 386.244747 -280.251163)
			(xy 386.244746 -280.198259) (xy 386.253165 -280.146029) (xy 386.26979 -280.095805) (xy 386.294198 -280.048867)
			(xy 386.325765 -280.006413) (xy 386.363688 -279.969525) (xy 386.406998 -279.939144) (xy 386.454592 -279.916043)
			(xy 386.479796 -279.908) (xy 386.495798 -279.903174) (xy 386.515864 -279.87625) (xy 386.515864 -279.623266)
			(xy 386.495798 -279.596342) (xy 386.479796 -279.591516) (xy 386.454618 -279.583405) (xy 386.407031 -279.560309)
			(xy 386.363728 -279.529933) (xy 386.325811 -279.493052) (xy 386.294249 -279.450606) (xy 386.269845 -279.403677)
			(xy 386.253222 -279.353462) (xy 386.244803 -279.301241) (xy 386.244804 -279.248346) (xy 386.253225 -279.196126)
			(xy 386.26985 -279.145911) (xy 386.294256 -279.098983) (xy 386.32582 -279.056538) (xy 386.363738 -279.019659)
			(xy 386.407042 -278.989284) (xy 386.454629 -278.96619) (xy 386.479796 -278.95804) (xy 386.495798 -278.953214)
			(xy 386.515864 -278.92629) (xy 386.515864 -278.673306) (xy 386.495798 -278.646382) (xy 386.479796 -278.641556)
			(xy 386.454614 -278.633445) (xy 386.407022 -278.610348) (xy 386.363712 -278.57997) (xy 386.32579 -278.543086)
			(xy 386.294222 -278.500636) (xy 386.269814 -278.453703) (xy 386.253187 -278.403482) (xy 386.244766 -278.351256)
			(xy 386.244765 -278.298355) (xy 386.253185 -278.246128) (xy 386.26981 -278.195907) (xy 386.294217 -278.148973)
			(xy 386.325783 -278.106522) (xy 386.363704 -278.069636) (xy 386.407013 -278.039257) (xy 386.454605 -278.016159)
			(xy 386.479796 -278.00808) (xy 386.495798 -278.003254) (xy 386.515864 -277.97633) (xy 386.515864 -277.723346)
			(xy 386.495798 -277.696422) (xy 386.479796 -277.691596) (xy 386.454619 -277.683485) (xy 386.407036 -277.66039)
			(xy 386.363736 -277.630015) (xy 386.325822 -277.593135) (xy 386.294262 -277.550691) (xy 386.26986 -277.503764)
			(xy 386.253239 -277.453552) (xy 386.244822 -277.401334) (xy 386.244824 -277.348442) (xy 386.253245 -277.296225)
			(xy 386.26987 -277.246013) (xy 386.294275 -277.199089) (xy 386.325838 -277.156647) (xy 386.363754 -277.11977)
			(xy 386.407057 -277.089398) (xy 386.454642 -277.066306) (xy 386.479796 -277.05812) (xy 386.495798 -277.053294)
			(xy 386.515864 -277.02637) (xy 386.515864 -276.773386) (xy 386.495798 -276.746462) (xy 386.479796 -276.741636)
			(xy 386.454616 -276.733525) (xy 386.407027 -276.710429) (xy 386.36372 -276.680052) (xy 386.325801 -276.643169)
			(xy 386.294236 -276.600721) (xy 386.269829 -276.55379) (xy 386.253204 -276.503572) (xy 386.244785 -276.451348)
			(xy 386.244785 -276.39845) (xy 386.253205 -276.346227) (xy 386.26983 -276.296009) (xy 386.294236 -276.249078)
			(xy 386.325802 -276.20663) (xy 386.363721 -276.169747) (xy 386.407028 -276.139371) (xy 386.454617 -276.116275)
			(xy 386.479796 -276.10816) (xy 386.495798 -276.103334) (xy 386.515864 -276.07641) (xy 386.515864 -275.823426)
			(xy 386.495798 -275.796502) (xy 386.479796 -275.791676) (xy 386.454613 -275.783565) (xy 386.407017 -275.760467)
			(xy 386.363704 -275.730089) (xy 386.32578 -275.693203) (xy 386.294209 -275.650751) (xy 386.269799 -275.603815)
			(xy 386.25317 -275.553592) (xy 386.244747 -275.501363) (xy 386.244746 -275.448459) (xy 386.253165 -275.396229)
			(xy 386.26979 -275.346005) (xy 386.294198 -275.299067) (xy 386.325765 -275.256613) (xy 386.363688 -275.219725)
			(xy 386.406998 -275.189344) (xy 386.454592 -275.166243) (xy 386.479796 -275.1582) (xy 386.495798 -275.153374)
			(xy 386.515864 -275.12645) (xy 386.515864 -274.873466) (xy 386.495798 -274.846542) (xy 386.479796 -274.841716)
			(xy 386.454618 -274.833605) (xy 386.407031 -274.810509) (xy 386.363728 -274.780133) (xy 386.325811 -274.743252)
			(xy 386.294249 -274.700806) (xy 386.269845 -274.653877) (xy 386.253222 -274.603662) (xy 386.244803 -274.551441)
			(xy 386.244804 -274.498546) (xy 386.253225 -274.446326) (xy 386.26985 -274.396111) (xy 386.294256 -274.349183)
			(xy 386.32582 -274.306738) (xy 386.363738 -274.269859) (xy 386.407042 -274.239484) (xy 386.454629 -274.21639)
			(xy 386.479796 -274.20824) (xy 386.495798 -274.203414) (xy 386.515864 -274.17649) (xy 386.515864 -273.923252)
			(xy 386.495798 -273.896328) (xy 386.479796 -273.891502) (xy 386.454607 -273.883403) (xy 386.406998 -273.860325)
			(xy 386.363672 -273.82996) (xy 386.325733 -273.793084) (xy 386.294151 -273.750636) (xy 386.269732 -273.703701)
			(xy 386.253098 -273.653476) (xy 386.244675 -273.601243) (xy 386.244676 -273.548336) (xy 386.253103 -273.496104)
			(xy 386.26974 -273.44588) (xy 386.294162 -273.398946) (xy 386.325747 -273.356501) (xy 386.363688 -273.319627)
			(xy 386.407016 -273.289265) (xy 386.454627 -273.26619) (xy 386.479796 -273.258026) (xy 386.495798 -273.2532)
			(xy 386.515864 -273.226276) (xy 386.515864 -272.973292) (xy 386.495798 -272.946368) (xy 386.479796 -272.941542)
			(xy 386.454616 -272.933431) (xy 386.407025 -272.910334) (xy 386.363718 -272.879957) (xy 386.325798 -272.843074)
			(xy 386.294232 -272.800625) (xy 386.269825 -272.753694) (xy 386.253199 -272.703475) (xy 386.244779 -272.651251)
			(xy 386.244779 -272.598352) (xy 386.253199 -272.546127) (xy 386.269824 -272.495909) (xy 386.29423 -272.448976)
			(xy 386.325796 -272.406528) (xy 386.363716 -272.369644) (xy 386.407023 -272.339267) (xy 386.454613 -272.31617)
			(xy 386.479796 -272.308066) (xy 386.495798 -272.30324) (xy 386.515864 -272.276316) (xy 386.515864 -265.986514)
			(xy 386.51434 -265.984736) (xy 386.51434 -265.037824) (xy 386.515864 -265.036554) (xy 386.515864 -264.768838)
			(xy 386.494782 -264.74166) (xy 386.477764 -264.737342) (xy 386.450774 -264.729915) (xy 386.399165 -264.70824)
			(xy 386.351276 -264.679256) (xy 386.308137 -264.643584) (xy 386.270674 -264.601992) (xy 386.239691 -264.555372)
			(xy 386.215854 -264.504724) (xy 386.199673 -264.451137) (xy 386.191498 -264.39576) (xy 386.190998 -264.367772)
			(xy 386.191544 -264.338407) (xy 386.200543 -264.28037) (xy 386.21831 -264.224392) (xy 386.230876 -264.197846)
			(xy 386.232885 -264.193578) (xy 386.235442 -264.184501) (xy 386.235956 -264.179812) (xy 386.238838 -264.153149)
			(xy 386.251125 -264.100948) (xy 386.270597 -264.05098) (xy 386.296872 -264.00423) (xy 386.329431 -263.961617)
			(xy 386.367635 -263.923981) (xy 386.41073 -263.892063) (xy 386.457868 -263.866491) (xy 386.482844 -263.856724)
			(xy 386.49783 -263.851136) (xy 386.515864 -263.825228) (xy 386.515864 -263.412224) (xy 386.49783 -263.386316)
			(xy 386.48259 -263.380728) (xy 386.456985 -263.370899) (xy 386.408668 -263.344946) (xy 386.364566 -263.312341)
			(xy 386.325589 -263.273756) (xy 386.292539 -263.229986) (xy 386.266099 -263.181935) (xy 386.246814 -263.130592)
			(xy 386.23508 -263.077016) (xy 386.231141 -263.022312) (xy 386.235077 -262.967607) (xy 386.246807 -262.914031)
			(xy 386.266089 -262.862686) (xy 386.292527 -262.814633) (xy 386.325573 -262.770862) (xy 386.364549 -262.732274)
			(xy 386.408648 -262.699666) (xy 386.456964 -262.673711) (xy 386.48259 -262.66394) (xy 386.49783 -262.658352)
			(xy 386.515864 -262.632444) (xy 386.515864 -260.743446) (xy 386.515356 -260.743192) (xy 386.515356 -260.712204)
			(xy 386.514881 -260.702237) (xy 386.507307 -260.683799) (xy 386.500624 -260.67639) (xy 385.682744 -259.85851)
			(xy 385.675632 -259.851144) (xy 385.656836 -259.843524) (xy 383.281936 -259.843524) (xy 383.272413 -259.843917)
			(xy 383.254664 -259.850826) (xy 383.247392 -259.856986) (xy 383.226154 -259.87584) (xy 383.17914 -259.907696)
			(xy 383.127921 -259.932225) (xy 383.07363 -259.948887) (xy 383.017469 -259.95731) (xy 382.960679 -259.95731)
			(xy 382.904518 -259.948887) (xy 382.850227 -259.932225) (xy 382.799008 -259.907696) (xy 382.751994 -259.87584)
			(xy 382.730756 -259.856986) (xy 382.723496 -259.850804) (xy 382.705741 -259.843893) (xy 382.696212 -259.843524)
			(xy 382.523746 -259.843524) (xy 382.513681 -259.843958) (xy 382.495093 -259.851688) (xy 382.487678 -259.85851)
			(xy 382.29159 -260.054598) (xy 382.284224 -260.06171) (xy 382.276604 -260.080506) (xy 382.276604 -260.338316)
			(xy 384.879086 -260.338316) (xy 384.883157 -260.282694) (xy 384.895283 -260.228257) (xy 384.915206 -260.176166)
			(xy 384.942502 -260.127531) (xy 384.976588 -260.083388) (xy 385.016737 -260.044679) (xy 385.062095 -260.012228)
			(xy 385.111695 -259.986727) (xy 385.164479 -259.96872) (xy 385.219322 -259.95859) (xy 385.275056 -259.956553)
			(xy 385.330493 -259.962653) (xy 385.38445 -259.976759) (xy 385.435779 -259.998571) (xy 385.483385 -260.027625)
			(xy 385.526253 -260.0633) (xy 385.56347 -260.104837) (xy 385.594243 -260.15135) (xy 385.617915 -260.201847)
			(xy 385.633983 -260.255254) (xy 385.642103 -260.31043) (xy 385.642612 -260.338316) (xy 385.642103 -260.366202)
			(xy 385.633983 -260.421378) (xy 385.617915 -260.474785) (xy 385.594243 -260.525282) (xy 385.56347 -260.571795)
			(xy 385.526253 -260.613332) (xy 385.483385 -260.649007) (xy 385.435779 -260.678061) (xy 385.38445 -260.699873)
			(xy 385.330493 -260.713979) (xy 385.275056 -260.720079) (xy 385.219322 -260.718042) (xy 385.164479 -260.707912)
			(xy 385.111695 -260.689905) (xy 385.062095 -260.664404) (xy 385.016737 -260.631953) (xy 384.976588 -260.593244)
			(xy 384.942502 -260.549101) (xy 384.915206 -260.500466) (xy 384.895283 -260.448375) (xy 384.883157 -260.393938)
			(xy 384.879086 -260.338316) (xy 382.276604 -260.338316) (xy 382.276604 -262.676386) (xy 382.278128 -262.682482)
			(xy 382.283144 -262.704621) (xy 382.28849 -262.7497) (xy 382.288796 -262.772398) (xy 382.288796 -262.772906)
			(xy 382.288471 -262.795603) (xy 382.283125 -262.84068) (xy 382.278128 -262.862822) (xy 382.276604 -262.868918)
			(xy 382.276604 -264.683748) (xy 382.27707 -264.693623) (xy 382.284521 -264.711913) (xy 382.291082 -264.719308)
			(xy 382.291336 -264.719562) (xy 382.939798 -265.368024) (xy 382.946641 -265.375424) (xy 382.954367 -265.394022)
			(xy 382.954784 -265.404092) (xy 382.954784 -267.578078) (xy 385.153152 -267.578078) (xy 385.157223 -267.522456)
			(xy 385.169349 -267.468019) (xy 385.189272 -267.415928) (xy 385.216568 -267.367293) (xy 385.250654 -267.32315)
			(xy 385.290803 -267.284441) (xy 385.336161 -267.25199) (xy 385.385761 -267.226489) (xy 385.438545 -267.208482)
			(xy 385.493388 -267.198352) (xy 385.549122 -267.196315) (xy 385.604559 -267.202415) (xy 385.658516 -267.216521)
			(xy 385.709845 -267.238333) (xy 385.757451 -267.267387) (xy 385.800319 -267.303062) (xy 385.837536 -267.344599)
			(xy 385.868309 -267.391112) (xy 385.891981 -267.441609) (xy 385.908049 -267.495016) (xy 385.916169 -267.550192)
			(xy 385.916678 -267.578078) (xy 385.916169 -267.605964) (xy 385.908049 -267.66114) (xy 385.891981 -267.714547)
			(xy 385.868309 -267.765044) (xy 385.837536 -267.811557) (xy 385.800319 -267.853094) (xy 385.757451 -267.888769)
			(xy 385.709845 -267.917823) (xy 385.658516 -267.939635) (xy 385.604559 -267.953741) (xy 385.549122 -267.959841)
			(xy 385.493388 -267.957804) (xy 385.438545 -267.947674) (xy 385.385761 -267.929667) (xy 385.336161 -267.904166)
			(xy 385.290803 -267.871715) (xy 385.250654 -267.833006) (xy 385.216568 -267.788863) (xy 385.189272 -267.740228)
			(xy 385.169349 -267.688137) (xy 385.157223 -267.6337) (xy 385.153152 -267.578078) (xy 382.954784 -267.578078)
			(xy 382.954784 -273.388328) (xy 382.954355 -273.398396) (xy 382.946632 -273.416991) (xy 382.939798 -273.424396)
			(xy 382.913128 -273.451066) (xy 382.905762 -273.458178) (xy 382.898142 -273.476974) (xy 382.898142 -273.574764)
			(xy 385.319028 -273.574764) (xy 385.322988 -273.52571) (xy 385.334765 -273.477926) (xy 385.354056 -273.43265)
			(xy 385.380359 -273.391054) (xy 385.412994 -273.354217) (xy 385.451115 -273.323092) (xy 385.493736 -273.298485)
			(xy 385.539752 -273.281033) (xy 385.587971 -273.271189) (xy 385.637146 -273.269208) (xy 385.686001 -273.27514)
			(xy 385.733272 -273.288832) (xy 385.777734 -273.30993) (xy 385.818237 -273.337886) (xy 385.85373 -273.371978)
			(xy 385.883295 -273.411322) (xy 385.906166 -273.454899) (xy 385.92175 -273.50158) (xy 385.929645 -273.550157)
			(xy 385.93014 -273.574764) (xy 385.929645 -273.599371) (xy 385.92175 -273.647948) (xy 385.906166 -273.694629)
			(xy 385.883295 -273.738206) (xy 385.85373 -273.77755) (xy 385.818237 -273.811642) (xy 385.777734 -273.839598)
			(xy 385.733272 -273.860696) (xy 385.686001 -273.874388) (xy 385.637146 -273.88032) (xy 385.587971 -273.878339)
			(xy 385.539752 -273.868495) (xy 385.493736 -273.851043) (xy 385.451115 -273.826436) (xy 385.412994 -273.795311)
			(xy 385.380359 -273.758474) (xy 385.354056 -273.716878) (xy 385.334765 -273.671602) (xy 385.322988 -273.623818)
			(xy 385.319028 -273.574764) (xy 382.898142 -273.574764) (xy 382.898142 -274.524724) (xy 385.319028 -274.524724)
			(xy 385.322988 -274.47567) (xy 385.334765 -274.427886) (xy 385.354056 -274.38261) (xy 385.380359 -274.341014)
			(xy 385.412994 -274.304177) (xy 385.451115 -274.273052) (xy 385.493736 -274.248445) (xy 385.539752 -274.230993)
			(xy 385.587971 -274.221149) (xy 385.637146 -274.219168) (xy 385.686001 -274.2251) (xy 385.733272 -274.238792)
			(xy 385.777734 -274.25989) (xy 385.818237 -274.287846) (xy 385.85373 -274.321938) (xy 385.883295 -274.361282)
			(xy 385.906166 -274.404859) (xy 385.92175 -274.45154) (xy 385.929645 -274.500117) (xy 385.93014 -274.524724)
			(xy 385.929645 -274.549331) (xy 385.92175 -274.597908) (xy 385.906166 -274.644589) (xy 385.883295 -274.688166)
			(xy 385.85373 -274.72751) (xy 385.818237 -274.761602) (xy 385.777734 -274.789558) (xy 385.733272 -274.810656)
			(xy 385.686001 -274.824348) (xy 385.637146 -274.83028) (xy 385.587971 -274.828299) (xy 385.539752 -274.818455)
			(xy 385.493736 -274.801003) (xy 385.451115 -274.776396) (xy 385.412994 -274.745271) (xy 385.380359 -274.708434)
			(xy 385.354056 -274.666838) (xy 385.334765 -274.621562) (xy 385.322988 -274.573778) (xy 385.319028 -274.524724)
			(xy 382.898142 -274.524724) (xy 382.898142 -275.474938) (xy 384.369068 -275.474938) (xy 384.373028 -275.425884)
			(xy 384.384805 -275.3781) (xy 384.404096 -275.332824) (xy 384.430399 -275.291228) (xy 384.463034 -275.254391)
			(xy 384.501155 -275.223266) (xy 384.543776 -275.198659) (xy 384.589792 -275.181207) (xy 384.638011 -275.171363)
			(xy 384.687186 -275.169382) (xy 384.736041 -275.175314) (xy 384.783312 -275.189006) (xy 384.827774 -275.210104)
			(xy 384.868277 -275.23806) (xy 384.90377 -275.272152) (xy 384.933335 -275.311496) (xy 384.956206 -275.355073)
			(xy 384.97179 -275.401754) (xy 384.979685 -275.450331) (xy 384.98018 -275.474938) (xy 385.319028 -275.474938)
			(xy 385.322988 -275.425884) (xy 385.334765 -275.3781) (xy 385.354056 -275.332824) (xy 385.380359 -275.291228)
			(xy 385.412994 -275.254391) (xy 385.451115 -275.223266) (xy 385.493736 -275.198659) (xy 385.539752 -275.181207)
			(xy 385.587971 -275.171363) (xy 385.637146 -275.169382) (xy 385.686001 -275.175314) (xy 385.733272 -275.189006)
			(xy 385.777734 -275.210104) (xy 385.818237 -275.23806) (xy 385.85373 -275.272152) (xy 385.883295 -275.311496)
			(xy 385.906166 -275.355073) (xy 385.92175 -275.401754) (xy 385.929645 -275.450331) (xy 385.93014 -275.474938)
			(xy 385.929645 -275.499545) (xy 385.92175 -275.548122) (xy 385.906166 -275.594803) (xy 385.883295 -275.63838)
			(xy 385.85373 -275.677724) (xy 385.818237 -275.711816) (xy 385.777734 -275.739772) (xy 385.733272 -275.76087)
			(xy 385.686001 -275.774562) (xy 385.637146 -275.780494) (xy 385.587971 -275.778513) (xy 385.539752 -275.768669)
			(xy 385.493736 -275.751217) (xy 385.451115 -275.72661) (xy 385.412994 -275.695485) (xy 385.380359 -275.658648)
			(xy 385.354056 -275.617052) (xy 385.334765 -275.571776) (xy 385.322988 -275.523992) (xy 385.319028 -275.474938)
			(xy 384.98018 -275.474938) (xy 384.979685 -275.499545) (xy 384.97179 -275.548122) (xy 384.956206 -275.594803)
			(xy 384.933335 -275.63838) (xy 384.90377 -275.677724) (xy 384.868277 -275.711816) (xy 384.827774 -275.739772)
			(xy 384.783312 -275.76087) (xy 384.736041 -275.774562) (xy 384.687186 -275.780494) (xy 384.638011 -275.778513)
			(xy 384.589792 -275.768669) (xy 384.543776 -275.751217) (xy 384.501155 -275.72661) (xy 384.463034 -275.695485)
			(xy 384.430399 -275.658648) (xy 384.404096 -275.617052) (xy 384.384805 -275.571776) (xy 384.373028 -275.523992)
			(xy 384.369068 -275.474938) (xy 382.898142 -275.474938) (xy 382.898142 -276.424898) (xy 384.369068 -276.424898)
			(xy 384.373028 -276.375844) (xy 384.384805 -276.32806) (xy 384.404096 -276.282784) (xy 384.430399 -276.241188)
			(xy 384.463034 -276.204351) (xy 384.501155 -276.173226) (xy 384.543776 -276.148619) (xy 384.589792 -276.131167)
			(xy 384.638011 -276.121323) (xy 384.687186 -276.119342) (xy 384.736041 -276.125274) (xy 384.783312 -276.138966)
			(xy 384.827774 -276.160064) (xy 384.868277 -276.18802) (xy 384.90377 -276.222112) (xy 384.933335 -276.261456)
			(xy 384.956206 -276.305033) (xy 384.97179 -276.351714) (xy 384.979685 -276.400291) (xy 384.98018 -276.424898)
			(xy 385.319028 -276.424898) (xy 385.322988 -276.375844) (xy 385.334765 -276.32806) (xy 385.354056 -276.282784)
			(xy 385.380359 -276.241188) (xy 385.412994 -276.204351) (xy 385.451115 -276.173226) (xy 385.493736 -276.148619)
			(xy 385.539752 -276.131167) (xy 385.587971 -276.121323) (xy 385.637146 -276.119342) (xy 385.686001 -276.125274)
			(xy 385.733272 -276.138966) (xy 385.777734 -276.160064) (xy 385.818237 -276.18802) (xy 385.85373 -276.222112)
			(xy 385.883295 -276.261456) (xy 385.906166 -276.305033) (xy 385.92175 -276.351714) (xy 385.929645 -276.400291)
			(xy 385.93014 -276.424898) (xy 385.929645 -276.449505) (xy 385.92175 -276.498082) (xy 385.906166 -276.544763)
			(xy 385.883295 -276.58834) (xy 385.85373 -276.627684) (xy 385.818237 -276.661776) (xy 385.777734 -276.689732)
			(xy 385.733272 -276.71083) (xy 385.686001 -276.724522) (xy 385.637146 -276.730454) (xy 385.587971 -276.728473)
			(xy 385.539752 -276.718629) (xy 385.493736 -276.701177) (xy 385.451115 -276.67657) (xy 385.412994 -276.645445)
			(xy 385.380359 -276.608608) (xy 385.354056 -276.567012) (xy 385.334765 -276.521736) (xy 385.322988 -276.473952)
			(xy 385.319028 -276.424898) (xy 384.98018 -276.424898) (xy 384.979685 -276.449505) (xy 384.97179 -276.498082)
			(xy 384.956206 -276.544763) (xy 384.933335 -276.58834) (xy 384.90377 -276.627684) (xy 384.868277 -276.661776)
			(xy 384.827774 -276.689732) (xy 384.783312 -276.71083) (xy 384.736041 -276.724522) (xy 384.687186 -276.730454)
			(xy 384.638011 -276.728473) (xy 384.589792 -276.718629) (xy 384.543776 -276.701177) (xy 384.501155 -276.67657)
			(xy 384.463034 -276.645445) (xy 384.430399 -276.608608) (xy 384.404096 -276.567012) (xy 384.384805 -276.521736)
			(xy 384.373028 -276.473952) (xy 384.369068 -276.424898) (xy 382.898142 -276.424898) (xy 382.898142 -277.374858)
			(xy 384.369068 -277.374858) (xy 384.373028 -277.325804) (xy 384.384805 -277.27802) (xy 384.404096 -277.232744)
			(xy 384.430399 -277.191148) (xy 384.463034 -277.154311) (xy 384.501155 -277.123186) (xy 384.543776 -277.098579)
			(xy 384.589792 -277.081127) (xy 384.638011 -277.071283) (xy 384.687186 -277.069302) (xy 384.736041 -277.075234)
			(xy 384.783312 -277.088926) (xy 384.827774 -277.110024) (xy 384.868277 -277.13798) (xy 384.90377 -277.172072)
			(xy 384.933335 -277.211416) (xy 384.956206 -277.254993) (xy 384.97179 -277.301674) (xy 384.979685 -277.350251)
			(xy 384.98018 -277.374858) (xy 385.319028 -277.374858) (xy 385.322988 -277.325804) (xy 385.334765 -277.27802)
			(xy 385.354056 -277.232744) (xy 385.380359 -277.191148) (xy 385.412994 -277.154311) (xy 385.451115 -277.123186)
			(xy 385.493736 -277.098579) (xy 385.539752 -277.081127) (xy 385.587971 -277.071283) (xy 385.637146 -277.069302)
			(xy 385.686001 -277.075234) (xy 385.733272 -277.088926) (xy 385.777734 -277.110024) (xy 385.818237 -277.13798)
			(xy 385.85373 -277.172072) (xy 385.883295 -277.211416) (xy 385.906166 -277.254993) (xy 385.92175 -277.301674)
			(xy 385.929645 -277.350251) (xy 385.93014 -277.374858) (xy 385.929645 -277.399465) (xy 385.92175 -277.448042)
			(xy 385.906166 -277.494723) (xy 385.883295 -277.5383) (xy 385.85373 -277.577644) (xy 385.818237 -277.611736)
			(xy 385.777734 -277.639692) (xy 385.733272 -277.66079) (xy 385.686001 -277.674482) (xy 385.637146 -277.680414)
			(xy 385.587971 -277.678433) (xy 385.539752 -277.668589) (xy 385.493736 -277.651137) (xy 385.451115 -277.62653)
			(xy 385.412994 -277.595405) (xy 385.380359 -277.558568) (xy 385.354056 -277.516972) (xy 385.334765 -277.471696)
			(xy 385.322988 -277.423912) (xy 385.319028 -277.374858) (xy 384.98018 -277.374858) (xy 384.979685 -277.399465)
			(xy 384.97179 -277.448042) (xy 384.956206 -277.494723) (xy 384.933335 -277.5383) (xy 384.90377 -277.577644)
			(xy 384.868277 -277.611736) (xy 384.827774 -277.639692) (xy 384.783312 -277.66079) (xy 384.736041 -277.674482)
			(xy 384.687186 -277.680414) (xy 384.638011 -277.678433) (xy 384.589792 -277.668589) (xy 384.543776 -277.651137)
			(xy 384.501155 -277.62653) (xy 384.463034 -277.595405) (xy 384.430399 -277.558568) (xy 384.404096 -277.516972)
			(xy 384.384805 -277.471696) (xy 384.373028 -277.423912) (xy 384.369068 -277.374858) (xy 382.898142 -277.374858)
			(xy 382.898142 -278.324818) (xy 384.369068 -278.324818) (xy 384.373028 -278.275764) (xy 384.384805 -278.22798)
			(xy 384.404096 -278.182704) (xy 384.430399 -278.141108) (xy 384.463034 -278.104271) (xy 384.501155 -278.073146)
			(xy 384.543776 -278.048539) (xy 384.589792 -278.031087) (xy 384.638011 -278.021243) (xy 384.687186 -278.019262)
			(xy 384.736041 -278.025194) (xy 384.783312 -278.038886) (xy 384.827774 -278.059984) (xy 384.868277 -278.08794)
			(xy 384.90377 -278.122032) (xy 384.933335 -278.161376) (xy 384.956206 -278.204953) (xy 384.97179 -278.251634)
			(xy 384.979685 -278.300211) (xy 384.98018 -278.324818) (xy 385.319028 -278.324818) (xy 385.322988 -278.275764)
			(xy 385.334765 -278.22798) (xy 385.354056 -278.182704) (xy 385.380359 -278.141108) (xy 385.412994 -278.104271)
			(xy 385.451115 -278.073146) (xy 385.493736 -278.048539) (xy 385.539752 -278.031087) (xy 385.587971 -278.021243)
			(xy 385.637146 -278.019262) (xy 385.686001 -278.025194) (xy 385.733272 -278.038886) (xy 385.777734 -278.059984)
			(xy 385.818237 -278.08794) (xy 385.85373 -278.122032) (xy 385.883295 -278.161376) (xy 385.906166 -278.204953)
			(xy 385.92175 -278.251634) (xy 385.929645 -278.300211) (xy 385.93014 -278.324818) (xy 385.929645 -278.349425)
			(xy 385.92175 -278.398002) (xy 385.906166 -278.444683) (xy 385.883295 -278.48826) (xy 385.85373 -278.527604)
			(xy 385.818237 -278.561696) (xy 385.777734 -278.589652) (xy 385.733272 -278.61075) (xy 385.686001 -278.624442)
			(xy 385.637146 -278.630374) (xy 385.587971 -278.628393) (xy 385.539752 -278.618549) (xy 385.493736 -278.601097)
			(xy 385.451115 -278.57649) (xy 385.412994 -278.545365) (xy 385.380359 -278.508528) (xy 385.354056 -278.466932)
			(xy 385.334765 -278.421656) (xy 385.322988 -278.373872) (xy 385.319028 -278.324818) (xy 384.98018 -278.324818)
			(xy 384.979685 -278.349425) (xy 384.97179 -278.398002) (xy 384.956206 -278.444683) (xy 384.933335 -278.48826)
			(xy 384.90377 -278.527604) (xy 384.868277 -278.561696) (xy 384.827774 -278.589652) (xy 384.783312 -278.61075)
			(xy 384.736041 -278.624442) (xy 384.687186 -278.630374) (xy 384.638011 -278.628393) (xy 384.589792 -278.618549)
			(xy 384.543776 -278.601097) (xy 384.501155 -278.57649) (xy 384.463034 -278.545365) (xy 384.430399 -278.508528)
			(xy 384.404096 -278.466932) (xy 384.384805 -278.421656) (xy 384.373028 -278.373872) (xy 384.369068 -278.324818)
			(xy 382.898142 -278.324818) (xy 382.898142 -279.274778) (xy 384.369068 -279.274778) (xy 384.373028 -279.225724)
			(xy 384.384805 -279.17794) (xy 384.404096 -279.132664) (xy 384.430399 -279.091068) (xy 384.463034 -279.054231)
			(xy 384.501155 -279.023106) (xy 384.543776 -278.998499) (xy 384.589792 -278.981047) (xy 384.638011 -278.971203)
			(xy 384.687186 -278.969222) (xy 384.736041 -278.975154) (xy 384.783312 -278.988846) (xy 384.827774 -279.009944)
			(xy 384.868277 -279.0379) (xy 384.90377 -279.071992) (xy 384.933335 -279.111336) (xy 384.956206 -279.154913)
			(xy 384.97179 -279.201594) (xy 384.979685 -279.250171) (xy 384.98018 -279.274778) (xy 385.319028 -279.274778)
			(xy 385.322988 -279.225724) (xy 385.334765 -279.17794) (xy 385.354056 -279.132664) (xy 385.380359 -279.091068)
			(xy 385.412994 -279.054231) (xy 385.451115 -279.023106) (xy 385.493736 -278.998499) (xy 385.539752 -278.981047)
			(xy 385.587971 -278.971203) (xy 385.637146 -278.969222) (xy 385.686001 -278.975154) (xy 385.733272 -278.988846)
			(xy 385.777734 -279.009944) (xy 385.818237 -279.0379) (xy 385.85373 -279.071992) (xy 385.883295 -279.111336)
			(xy 385.906166 -279.154913) (xy 385.92175 -279.201594) (xy 385.929645 -279.250171) (xy 385.93014 -279.274778)
			(xy 385.929645 -279.299385) (xy 385.92175 -279.347962) (xy 385.906166 -279.394643) (xy 385.883295 -279.43822)
			(xy 385.85373 -279.477564) (xy 385.818237 -279.511656) (xy 385.777734 -279.539612) (xy 385.733272 -279.56071)
			(xy 385.686001 -279.574402) (xy 385.637146 -279.580334) (xy 385.587971 -279.578353) (xy 385.539752 -279.568509)
			(xy 385.493736 -279.551057) (xy 385.451115 -279.52645) (xy 385.412994 -279.495325) (xy 385.380359 -279.458488)
			(xy 385.354056 -279.416892) (xy 385.334765 -279.371616) (xy 385.322988 -279.323832) (xy 385.319028 -279.274778)
			(xy 384.98018 -279.274778) (xy 384.979685 -279.299385) (xy 384.97179 -279.347962) (xy 384.956206 -279.394643)
			(xy 384.933335 -279.43822) (xy 384.90377 -279.477564) (xy 384.868277 -279.511656) (xy 384.827774 -279.539612)
			(xy 384.783312 -279.56071) (xy 384.736041 -279.574402) (xy 384.687186 -279.580334) (xy 384.638011 -279.578353)
			(xy 384.589792 -279.568509) (xy 384.543776 -279.551057) (xy 384.501155 -279.52645) (xy 384.463034 -279.495325)
			(xy 384.430399 -279.458488) (xy 384.404096 -279.416892) (xy 384.384805 -279.371616) (xy 384.373028 -279.323832)
			(xy 384.369068 -279.274778) (xy 382.898142 -279.274778) (xy 382.898142 -279.917906) (xy 382.898396 -279.917906)
			(xy 382.898396 -280.224738) (xy 384.369068 -280.224738) (xy 384.373028 -280.175684) (xy 384.384805 -280.1279)
			(xy 384.404096 -280.082624) (xy 384.430399 -280.041028) (xy 384.463034 -280.004191) (xy 384.501155 -279.973066)
			(xy 384.543776 -279.948459) (xy 384.589792 -279.931007) (xy 384.638011 -279.921163) (xy 384.687186 -279.919182)
			(xy 384.736041 -279.925114) (xy 384.783312 -279.938806) (xy 384.827774 -279.959904) (xy 384.868277 -279.98786)
			(xy 384.90377 -280.021952) (xy 384.933335 -280.061296) (xy 384.956206 -280.104873) (xy 384.97179 -280.151554)
			(xy 384.979685 -280.200131) (xy 384.98018 -280.224738) (xy 385.319028 -280.224738) (xy 385.322988 -280.175684)
			(xy 385.334765 -280.1279) (xy 385.354056 -280.082624) (xy 385.380359 -280.041028) (xy 385.412994 -280.004191)
			(xy 385.451115 -279.973066) (xy 385.493736 -279.948459) (xy 385.539752 -279.931007) (xy 385.587971 -279.921163)
			(xy 385.637146 -279.919182) (xy 385.686001 -279.925114) (xy 385.733272 -279.938806) (xy 385.777734 -279.959904)
			(xy 385.818237 -279.98786) (xy 385.85373 -280.021952) (xy 385.883295 -280.061296) (xy 385.906166 -280.104873)
			(xy 385.92175 -280.151554) (xy 385.929645 -280.200131) (xy 385.93014 -280.224738) (xy 385.929645 -280.249345)
			(xy 385.92175 -280.297922) (xy 385.906166 -280.344603) (xy 385.883295 -280.38818) (xy 385.85373 -280.427524)
			(xy 385.818237 -280.461616) (xy 385.777734 -280.489572) (xy 385.733272 -280.51067) (xy 385.686001 -280.524362)
			(xy 385.637146 -280.530294) (xy 385.587971 -280.528313) (xy 385.539752 -280.518469) (xy 385.493736 -280.501017)
			(xy 385.451115 -280.47641) (xy 385.412994 -280.445285) (xy 385.380359 -280.408448) (xy 385.354056 -280.366852)
			(xy 385.334765 -280.321576) (xy 385.322988 -280.273792) (xy 385.319028 -280.224738) (xy 384.98018 -280.224738)
			(xy 384.979685 -280.249345) (xy 384.97179 -280.297922) (xy 384.956206 -280.344603) (xy 384.933335 -280.38818)
			(xy 384.90377 -280.427524) (xy 384.868277 -280.461616) (xy 384.827774 -280.489572) (xy 384.783312 -280.51067)
			(xy 384.736041 -280.524362) (xy 384.687186 -280.530294) (xy 384.638011 -280.528313) (xy 384.589792 -280.518469)
			(xy 384.543776 -280.501017) (xy 384.501155 -280.47641) (xy 384.463034 -280.445285) (xy 384.430399 -280.408448)
			(xy 384.404096 -280.366852) (xy 384.384805 -280.321576) (xy 384.373028 -280.273792) (xy 384.369068 -280.224738)
			(xy 382.898396 -280.224738) (xy 382.898396 -281.174952) (xy 384.369068 -281.174952) (xy 384.373028 -281.125898)
			(xy 384.384805 -281.078114) (xy 384.404096 -281.032838) (xy 384.430399 -280.991242) (xy 384.463034 -280.954405)
			(xy 384.501155 -280.92328) (xy 384.543776 -280.898673) (xy 384.589792 -280.881221) (xy 384.638011 -280.871377)
			(xy 384.687186 -280.869396) (xy 384.736041 -280.875328) (xy 384.783312 -280.88902) (xy 384.827774 -280.910118)
			(xy 384.868277 -280.938074) (xy 384.90377 -280.972166) (xy 384.933335 -281.01151) (xy 384.956206 -281.055087)
			(xy 384.97179 -281.101768) (xy 384.979685 -281.150345) (xy 384.98018 -281.174952) (xy 385.319028 -281.174952)
			(xy 385.322988 -281.125898) (xy 385.334765 -281.078114) (xy 385.354056 -281.032838) (xy 385.380359 -280.991242)
			(xy 385.412994 -280.954405) (xy 385.451115 -280.92328) (xy 385.493736 -280.898673) (xy 385.539752 -280.881221)
			(xy 385.587971 -280.871377) (xy 385.637146 -280.869396) (xy 385.686001 -280.875328) (xy 385.733272 -280.88902)
			(xy 385.777734 -280.910118) (xy 385.818237 -280.938074) (xy 385.85373 -280.972166) (xy 385.883295 -281.01151)
			(xy 385.906166 -281.055087) (xy 385.92175 -281.101768) (xy 385.929645 -281.150345) (xy 385.93014 -281.174952)
			(xy 385.929645 -281.199559) (xy 385.92175 -281.248136) (xy 385.906166 -281.294817) (xy 385.883295 -281.338394)
			(xy 385.85373 -281.377738) (xy 385.818237 -281.41183) (xy 385.777734 -281.439786) (xy 385.733272 -281.460884)
			(xy 385.686001 -281.474576) (xy 385.637146 -281.480508) (xy 385.587971 -281.478527) (xy 385.539752 -281.468683)
			(xy 385.493736 -281.451231) (xy 385.451115 -281.426624) (xy 385.412994 -281.395499) (xy 385.380359 -281.358662)
			(xy 385.354056 -281.317066) (xy 385.334765 -281.27179) (xy 385.322988 -281.224006) (xy 385.319028 -281.174952)
			(xy 384.98018 -281.174952) (xy 384.979685 -281.199559) (xy 384.97179 -281.248136) (xy 384.956206 -281.294817)
			(xy 384.933335 -281.338394) (xy 384.90377 -281.377738) (xy 384.868277 -281.41183) (xy 384.827774 -281.439786)
			(xy 384.783312 -281.460884) (xy 384.736041 -281.474576) (xy 384.687186 -281.480508) (xy 384.638011 -281.478527)
			(xy 384.589792 -281.468683) (xy 384.543776 -281.451231) (xy 384.501155 -281.426624) (xy 384.463034 -281.395499)
			(xy 384.430399 -281.358662) (xy 384.404096 -281.317066) (xy 384.384805 -281.27179) (xy 384.373028 -281.224006)
			(xy 384.369068 -281.174952) (xy 382.898396 -281.174952) (xy 382.898396 -282.124912) (xy 384.369068 -282.124912)
			(xy 384.373028 -282.075858) (xy 384.384805 -282.028074) (xy 384.404096 -281.982798) (xy 384.430399 -281.941202)
			(xy 384.463034 -281.904365) (xy 384.501155 -281.87324) (xy 384.543776 -281.848633) (xy 384.589792 -281.831181)
			(xy 384.638011 -281.821337) (xy 384.687186 -281.819356) (xy 384.736041 -281.825288) (xy 384.783312 -281.83898)
			(xy 384.827774 -281.860078) (xy 384.868277 -281.888034) (xy 384.90377 -281.922126) (xy 384.933335 -281.96147)
			(xy 384.956206 -282.005047) (xy 384.97179 -282.051728) (xy 384.979685 -282.100305) (xy 384.98018 -282.124912)
			(xy 385.319028 -282.124912) (xy 385.322988 -282.075858) (xy 385.334765 -282.028074) (xy 385.354056 -281.982798)
			(xy 385.380359 -281.941202) (xy 385.412994 -281.904365) (xy 385.451115 -281.87324) (xy 385.493736 -281.848633)
			(xy 385.539752 -281.831181) (xy 385.587971 -281.821337) (xy 385.637146 -281.819356) (xy 385.686001 -281.825288)
			(xy 385.733272 -281.83898) (xy 385.777734 -281.860078) (xy 385.818237 -281.888034) (xy 385.85373 -281.922126)
			(xy 385.883295 -281.96147) (xy 385.906166 -282.005047) (xy 385.92175 -282.051728) (xy 385.929645 -282.100305)
			(xy 385.93014 -282.124912) (xy 385.929645 -282.149519) (xy 385.92175 -282.198096) (xy 385.906166 -282.244777)
			(xy 385.883295 -282.288354) (xy 385.85373 -282.327698) (xy 385.818237 -282.36179) (xy 385.777734 -282.389746)
			(xy 385.733272 -282.410844) (xy 385.686001 -282.424536) (xy 385.637146 -282.430468) (xy 385.587971 -282.428487)
			(xy 385.539752 -282.418643) (xy 385.493736 -282.401191) (xy 385.451115 -282.376584) (xy 385.412994 -282.345459)
			(xy 385.380359 -282.308622) (xy 385.354056 -282.267026) (xy 385.334765 -282.22175) (xy 385.322988 -282.173966)
			(xy 385.319028 -282.124912) (xy 384.98018 -282.124912) (xy 384.979685 -282.149519) (xy 384.97179 -282.198096)
			(xy 384.956206 -282.244777) (xy 384.933335 -282.288354) (xy 384.90377 -282.327698) (xy 384.868277 -282.36179)
			(xy 384.827774 -282.389746) (xy 384.783312 -282.410844) (xy 384.736041 -282.424536) (xy 384.687186 -282.430468)
			(xy 384.638011 -282.428487) (xy 384.589792 -282.418643) (xy 384.543776 -282.401191) (xy 384.501155 -282.376584)
			(xy 384.463034 -282.345459) (xy 384.430399 -282.308622) (xy 384.404096 -282.267026) (xy 384.384805 -282.22175)
			(xy 384.373028 -282.173966) (xy 384.369068 -282.124912) (xy 382.898396 -282.124912) (xy 382.898396 -283.074872)
			(xy 384.369068 -283.074872) (xy 384.373028 -283.025818) (xy 384.384805 -282.978034) (xy 384.404096 -282.932758)
			(xy 384.430399 -282.891162) (xy 384.463034 -282.854325) (xy 384.501155 -282.8232) (xy 384.543776 -282.798593)
			(xy 384.589792 -282.781141) (xy 384.638011 -282.771297) (xy 384.687186 -282.769316) (xy 384.736041 -282.775248)
			(xy 384.783312 -282.78894) (xy 384.827774 -282.810038) (xy 384.868277 -282.837994) (xy 384.90377 -282.872086)
			(xy 384.933335 -282.91143) (xy 384.956206 -282.955007) (xy 384.97179 -283.001688) (xy 384.979685 -283.050265)
			(xy 384.98018 -283.074872) (xy 385.319028 -283.074872) (xy 385.322988 -283.025818) (xy 385.334765 -282.978034)
			(xy 385.354056 -282.932758) (xy 385.380359 -282.891162) (xy 385.412994 -282.854325) (xy 385.451115 -282.8232)
			(xy 385.493736 -282.798593) (xy 385.539752 -282.781141) (xy 385.587971 -282.771297) (xy 385.637146 -282.769316)
			(xy 385.686001 -282.775248) (xy 385.733272 -282.78894) (xy 385.777734 -282.810038) (xy 385.818237 -282.837994)
			(xy 385.85373 -282.872086) (xy 385.883295 -282.91143) (xy 385.906166 -282.955007) (xy 385.92175 -283.001688)
			(xy 385.929645 -283.050265) (xy 385.93014 -283.074872) (xy 385.929645 -283.099479) (xy 385.92175 -283.148056)
			(xy 385.906166 -283.194737) (xy 385.883295 -283.238314) (xy 385.85373 -283.277658) (xy 385.818237 -283.31175)
			(xy 385.777734 -283.339706) (xy 385.733272 -283.360804) (xy 385.686001 -283.374496) (xy 385.637146 -283.380428)
			(xy 385.587971 -283.378447) (xy 385.539752 -283.368603) (xy 385.493736 -283.351151) (xy 385.451115 -283.326544)
			(xy 385.412994 -283.295419) (xy 385.380359 -283.258582) (xy 385.354056 -283.216986) (xy 385.334765 -283.17171)
			(xy 385.322988 -283.123926) (xy 385.319028 -283.074872) (xy 384.98018 -283.074872) (xy 384.979685 -283.099479)
			(xy 384.97179 -283.148056) (xy 384.956206 -283.194737) (xy 384.933335 -283.238314) (xy 384.90377 -283.277658)
			(xy 384.868277 -283.31175) (xy 384.827774 -283.339706) (xy 384.783312 -283.360804) (xy 384.736041 -283.374496)
			(xy 384.687186 -283.380428) (xy 384.638011 -283.378447) (xy 384.589792 -283.368603) (xy 384.543776 -283.351151)
			(xy 384.501155 -283.326544) (xy 384.463034 -283.295419) (xy 384.430399 -283.258582) (xy 384.404096 -283.216986)
			(xy 384.384805 -283.17171) (xy 384.373028 -283.123926) (xy 384.369068 -283.074872) (xy 382.898396 -283.074872)
			(xy 382.898396 -284.024832) (xy 384.369068 -284.024832) (xy 384.373028 -283.975778) (xy 384.384805 -283.927994)
			(xy 384.404096 -283.882718) (xy 384.430399 -283.841122) (xy 384.463034 -283.804285) (xy 384.501155 -283.77316)
			(xy 384.543776 -283.748553) (xy 384.589792 -283.731101) (xy 384.638011 -283.721257) (xy 384.687186 -283.719276)
			(xy 384.736041 -283.725208) (xy 384.783312 -283.7389) (xy 384.827774 -283.759998) (xy 384.868277 -283.787954)
			(xy 384.90377 -283.822046) (xy 384.933335 -283.86139) (xy 384.956206 -283.904967) (xy 384.97179 -283.951648)
			(xy 384.979685 -284.000225) (xy 384.98018 -284.024832) (xy 385.319028 -284.024832) (xy 385.322988 -283.975778)
			(xy 385.334765 -283.927994) (xy 385.354056 -283.882718) (xy 385.380359 -283.841122) (xy 385.412994 -283.804285)
			(xy 385.451115 -283.77316) (xy 385.493736 -283.748553) (xy 385.539752 -283.731101) (xy 385.587971 -283.721257)
			(xy 385.637146 -283.719276) (xy 385.686001 -283.725208) (xy 385.733272 -283.7389) (xy 385.777734 -283.759998)
			(xy 385.818237 -283.787954) (xy 385.85373 -283.822046) (xy 385.883295 -283.86139) (xy 385.906166 -283.904967)
			(xy 385.92175 -283.951648) (xy 385.929645 -284.000225) (xy 385.93014 -284.024832) (xy 385.929645 -284.049439)
			(xy 385.92175 -284.098016) (xy 385.906166 -284.144697) (xy 385.883295 -284.188274) (xy 385.85373 -284.227618)
			(xy 385.818237 -284.26171) (xy 385.777734 -284.289666) (xy 385.733272 -284.310764) (xy 385.686001 -284.324456)
			(xy 385.637146 -284.330388) (xy 385.587971 -284.328407) (xy 385.539752 -284.318563) (xy 385.493736 -284.301111)
			(xy 385.451115 -284.276504) (xy 385.412994 -284.245379) (xy 385.380359 -284.208542) (xy 385.354056 -284.166946)
			(xy 385.334765 -284.12167) (xy 385.322988 -284.073886) (xy 385.319028 -284.024832) (xy 384.98018 -284.024832)
			(xy 384.979685 -284.049439) (xy 384.97179 -284.098016) (xy 384.956206 -284.144697) (xy 384.933335 -284.188274)
			(xy 384.90377 -284.227618) (xy 384.868277 -284.26171) (xy 384.827774 -284.289666) (xy 384.783312 -284.310764)
			(xy 384.736041 -284.324456) (xy 384.687186 -284.330388) (xy 384.638011 -284.328407) (xy 384.589792 -284.318563)
			(xy 384.543776 -284.301111) (xy 384.501155 -284.276504) (xy 384.463034 -284.245379) (xy 384.430399 -284.208542)
			(xy 384.404096 -284.166946) (xy 384.384805 -284.12167) (xy 384.373028 -284.073886) (xy 384.369068 -284.024832)
			(xy 382.898396 -284.024832) (xy 382.898396 -284.974792) (xy 384.369068 -284.974792) (xy 384.373028 -284.925738)
			(xy 384.384805 -284.877954) (xy 384.404096 -284.832678) (xy 384.430399 -284.791082) (xy 384.463034 -284.754245)
			(xy 384.501155 -284.72312) (xy 384.543776 -284.698513) (xy 384.589792 -284.681061) (xy 384.638011 -284.671217)
			(xy 384.687186 -284.669236) (xy 384.736041 -284.675168) (xy 384.783312 -284.68886) (xy 384.827774 -284.709958)
			(xy 384.868277 -284.737914) (xy 384.90377 -284.772006) (xy 384.933335 -284.81135) (xy 384.956206 -284.854927)
			(xy 384.97179 -284.901608) (xy 384.979685 -284.950185) (xy 384.98018 -284.974792) (xy 385.319028 -284.974792)
			(xy 385.322988 -284.925738) (xy 385.334765 -284.877954) (xy 385.354056 -284.832678) (xy 385.380359 -284.791082)
			(xy 385.412994 -284.754245) (xy 385.451115 -284.72312) (xy 385.493736 -284.698513) (xy 385.539752 -284.681061)
			(xy 385.587971 -284.671217) (xy 385.637146 -284.669236) (xy 385.686001 -284.675168) (xy 385.733272 -284.68886)
			(xy 385.777734 -284.709958) (xy 385.818237 -284.737914) (xy 385.85373 -284.772006) (xy 385.883295 -284.81135)
			(xy 385.906166 -284.854927) (xy 385.92175 -284.901608) (xy 385.929645 -284.950185) (xy 385.93014 -284.974792)
			(xy 385.929645 -284.999399) (xy 385.92175 -285.047976) (xy 385.906166 -285.094657) (xy 385.883295 -285.138234)
			(xy 385.85373 -285.177578) (xy 385.818237 -285.21167) (xy 385.777734 -285.239626) (xy 385.733272 -285.260724)
			(xy 385.686001 -285.274416) (xy 385.637146 -285.280348) (xy 385.587971 -285.278367) (xy 385.539752 -285.268523)
			(xy 385.493736 -285.251071) (xy 385.451115 -285.226464) (xy 385.412994 -285.195339) (xy 385.380359 -285.158502)
			(xy 385.354056 -285.116906) (xy 385.334765 -285.07163) (xy 385.322988 -285.023846) (xy 385.319028 -284.974792)
			(xy 384.98018 -284.974792) (xy 384.979685 -284.999399) (xy 384.97179 -285.047976) (xy 384.956206 -285.094657)
			(xy 384.933335 -285.138234) (xy 384.90377 -285.177578) (xy 384.868277 -285.21167) (xy 384.827774 -285.239626)
			(xy 384.783312 -285.260724) (xy 384.736041 -285.274416) (xy 384.687186 -285.280348) (xy 384.638011 -285.278367)
			(xy 384.589792 -285.268523) (xy 384.543776 -285.251071) (xy 384.501155 -285.226464) (xy 384.463034 -285.195339)
			(xy 384.430399 -285.158502) (xy 384.404096 -285.116906) (xy 384.384805 -285.07163) (xy 384.373028 -285.023846)
			(xy 384.369068 -284.974792) (xy 382.898396 -284.974792) (xy 382.898396 -285.924752) (xy 384.369068 -285.924752)
			(xy 384.373028 -285.875698) (xy 384.384805 -285.827914) (xy 384.404096 -285.782638) (xy 384.430399 -285.741042)
			(xy 384.463034 -285.704205) (xy 384.501155 -285.67308) (xy 384.543776 -285.648473) (xy 384.589792 -285.631021)
			(xy 384.638011 -285.621177) (xy 384.687186 -285.619196) (xy 384.736041 -285.625128) (xy 384.783312 -285.63882)
			(xy 384.827774 -285.659918) (xy 384.868277 -285.687874) (xy 384.90377 -285.721966) (xy 384.933335 -285.76131)
			(xy 384.956206 -285.804887) (xy 384.97179 -285.851568) (xy 384.979685 -285.900145) (xy 384.98018 -285.924752)
			(xy 385.319028 -285.924752) (xy 385.322988 -285.875698) (xy 385.334765 -285.827914) (xy 385.354056 -285.782638)
			(xy 385.380359 -285.741042) (xy 385.412994 -285.704205) (xy 385.451115 -285.67308) (xy 385.493736 -285.648473)
			(xy 385.539752 -285.631021) (xy 385.587971 -285.621177) (xy 385.637146 -285.619196) (xy 385.686001 -285.625128)
			(xy 385.733272 -285.63882) (xy 385.777734 -285.659918) (xy 385.818237 -285.687874) (xy 385.85373 -285.721966)
			(xy 385.883295 -285.76131) (xy 385.906166 -285.804887) (xy 385.92175 -285.851568) (xy 385.929645 -285.900145)
			(xy 385.93014 -285.924752) (xy 385.929645 -285.949359) (xy 385.92175 -285.997936) (xy 385.906166 -286.044617)
			(xy 385.883295 -286.088194) (xy 385.85373 -286.127538) (xy 385.818237 -286.16163) (xy 385.777734 -286.189586)
			(xy 385.733272 -286.210684) (xy 385.686001 -286.224376) (xy 385.637146 -286.230308) (xy 385.587971 -286.228327)
			(xy 385.539752 -286.218483) (xy 385.493736 -286.201031) (xy 385.451115 -286.176424) (xy 385.412994 -286.145299)
			(xy 385.380359 -286.108462) (xy 385.354056 -286.066866) (xy 385.334765 -286.02159) (xy 385.322988 -285.973806)
			(xy 385.319028 -285.924752) (xy 384.98018 -285.924752) (xy 384.979685 -285.949359) (xy 384.97179 -285.997936)
			(xy 384.956206 -286.044617) (xy 384.933335 -286.088194) (xy 384.90377 -286.127538) (xy 384.868277 -286.16163)
			(xy 384.827774 -286.189586) (xy 384.783312 -286.210684) (xy 384.736041 -286.224376) (xy 384.687186 -286.230308)
			(xy 384.638011 -286.228327) (xy 384.589792 -286.218483) (xy 384.543776 -286.201031) (xy 384.501155 -286.176424)
			(xy 384.463034 -286.145299) (xy 384.430399 -286.108462) (xy 384.404096 -286.066866) (xy 384.384805 -286.02159)
			(xy 384.373028 -285.973806) (xy 384.369068 -285.924752) (xy 382.898396 -285.924752) (xy 382.898396 -286.874966)
			(xy 384.369068 -286.874966) (xy 384.373028 -286.825912) (xy 384.384805 -286.778128) (xy 384.404096 -286.732852)
			(xy 384.430399 -286.691256) (xy 384.463034 -286.654419) (xy 384.501155 -286.623294) (xy 384.543776 -286.598687)
			(xy 384.589792 -286.581235) (xy 384.638011 -286.571391) (xy 384.687186 -286.56941) (xy 384.736041 -286.575342)
			(xy 384.783312 -286.589034) (xy 384.827774 -286.610132) (xy 384.868277 -286.638088) (xy 384.90377 -286.67218)
			(xy 384.933335 -286.711524) (xy 384.956206 -286.755101) (xy 384.97179 -286.801782) (xy 384.979685 -286.850359)
			(xy 384.98018 -286.874966) (xy 385.319028 -286.874966) (xy 385.322988 -286.825912) (xy 385.334765 -286.778128)
			(xy 385.354056 -286.732852) (xy 385.380359 -286.691256) (xy 385.412994 -286.654419) (xy 385.451115 -286.623294)
			(xy 385.493736 -286.598687) (xy 385.539752 -286.581235) (xy 385.587971 -286.571391) (xy 385.637146 -286.56941)
			(xy 385.686001 -286.575342) (xy 385.733272 -286.589034) (xy 385.777734 -286.610132) (xy 385.818237 -286.638088)
			(xy 385.85373 -286.67218) (xy 385.883295 -286.711524) (xy 385.906166 -286.755101) (xy 385.92175 -286.801782)
			(xy 385.929645 -286.850359) (xy 385.93014 -286.874966) (xy 385.929645 -286.899573) (xy 385.92175 -286.94815)
			(xy 385.906166 -286.994831) (xy 385.883295 -287.038408) (xy 385.85373 -287.077752) (xy 385.818237 -287.111844)
			(xy 385.777734 -287.1398) (xy 385.733272 -287.160898) (xy 385.686001 -287.17459) (xy 385.637146 -287.180522)
			(xy 385.587971 -287.178541) (xy 385.539752 -287.168697) (xy 385.493736 -287.151245) (xy 385.451115 -287.126638)
			(xy 385.412994 -287.095513) (xy 385.380359 -287.058676) (xy 385.354056 -287.01708) (xy 385.334765 -286.971804)
			(xy 385.322988 -286.92402) (xy 385.319028 -286.874966) (xy 384.98018 -286.874966) (xy 384.979685 -286.899573)
			(xy 384.97179 -286.94815) (xy 384.956206 -286.994831) (xy 384.933335 -287.038408) (xy 384.90377 -287.077752)
			(xy 384.868277 -287.111844) (xy 384.827774 -287.1398) (xy 384.783312 -287.160898) (xy 384.736041 -287.17459)
			(xy 384.687186 -287.180522) (xy 384.638011 -287.178541) (xy 384.589792 -287.168697) (xy 384.543776 -287.151245)
			(xy 384.501155 -287.126638) (xy 384.463034 -287.095513) (xy 384.430399 -287.058676) (xy 384.404096 -287.01708)
			(xy 384.384805 -286.971804) (xy 384.373028 -286.92402) (xy 384.369068 -286.874966) (xy 382.898396 -286.874966)
			(xy 382.898396 -287.824926) (xy 384.369068 -287.824926) (xy 384.373028 -287.775872) (xy 384.384805 -287.728088)
			(xy 384.404096 -287.682812) (xy 384.430399 -287.641216) (xy 384.463034 -287.604379) (xy 384.501155 -287.573254)
			(xy 384.543776 -287.548647) (xy 384.589792 -287.531195) (xy 384.638011 -287.521351) (xy 384.687186 -287.51937)
			(xy 384.736041 -287.525302) (xy 384.783312 -287.538994) (xy 384.827774 -287.560092) (xy 384.868277 -287.588048)
			(xy 384.90377 -287.62214) (xy 384.933335 -287.661484) (xy 384.956206 -287.705061) (xy 384.97179 -287.751742)
			(xy 384.979685 -287.800319) (xy 384.98018 -287.824926) (xy 385.319028 -287.824926) (xy 385.322988 -287.775872)
			(xy 385.334765 -287.728088) (xy 385.354056 -287.682812) (xy 385.380359 -287.641216) (xy 385.412994 -287.604379)
			(xy 385.451115 -287.573254) (xy 385.493736 -287.548647) (xy 385.539752 -287.531195) (xy 385.587971 -287.521351)
			(xy 385.637146 -287.51937) (xy 385.686001 -287.525302) (xy 385.733272 -287.538994) (xy 385.777734 -287.560092)
			(xy 385.818237 -287.588048) (xy 385.85373 -287.62214) (xy 385.883295 -287.661484) (xy 385.906166 -287.705061)
			(xy 385.92175 -287.751742) (xy 385.929645 -287.800319) (xy 385.93014 -287.824926) (xy 386.269242 -287.824926)
			(xy 386.273202 -287.775872) (xy 386.284979 -287.728088) (xy 386.30427 -287.682812) (xy 386.330573 -287.641216)
			(xy 386.363208 -287.604379) (xy 386.401329 -287.573254) (xy 386.44395 -287.548647) (xy 386.489966 -287.531195)
			(xy 386.538185 -287.521351) (xy 386.58736 -287.51937) (xy 386.636215 -287.525302) (xy 386.683486 -287.538994)
			(xy 386.727948 -287.560092) (xy 386.768451 -287.588048) (xy 386.803944 -287.62214) (xy 386.833509 -287.661484)
			(xy 386.85638 -287.705061) (xy 386.871964 -287.751742) (xy 386.879859 -287.800319) (xy 386.880354 -287.824926)
			(xy 386.879859 -287.849533) (xy 386.871964 -287.89811) (xy 386.85638 -287.944791) (xy 386.833509 -287.988368)
			(xy 386.803944 -288.027712) (xy 386.768451 -288.061804) (xy 386.727948 -288.08976) (xy 386.683486 -288.110858)
			(xy 386.636215 -288.12455) (xy 386.58736 -288.130482) (xy 386.538185 -288.128501) (xy 386.489966 -288.118657)
			(xy 386.44395 -288.101205) (xy 386.401329 -288.076598) (xy 386.363208 -288.045473) (xy 386.330573 -288.008636)
			(xy 386.30427 -287.96704) (xy 386.284979 -287.921764) (xy 386.273202 -287.87398) (xy 386.269242 -287.824926)
			(xy 385.93014 -287.824926) (xy 385.929645 -287.849533) (xy 385.92175 -287.89811) (xy 385.906166 -287.944791)
			(xy 385.883295 -287.988368) (xy 385.85373 -288.027712) (xy 385.818237 -288.061804) (xy 385.777734 -288.08976)
			(xy 385.733272 -288.110858) (xy 385.686001 -288.12455) (xy 385.637146 -288.130482) (xy 385.587971 -288.128501)
			(xy 385.539752 -288.118657) (xy 385.493736 -288.101205) (xy 385.451115 -288.076598) (xy 385.412994 -288.045473)
			(xy 385.380359 -288.008636) (xy 385.354056 -287.96704) (xy 385.334765 -287.921764) (xy 385.322988 -287.87398)
			(xy 385.319028 -287.824926) (xy 384.98018 -287.824926) (xy 384.979685 -287.849533) (xy 384.97179 -287.89811)
			(xy 384.956206 -287.944791) (xy 384.933335 -287.988368) (xy 384.90377 -288.027712) (xy 384.868277 -288.061804)
			(xy 384.827774 -288.08976) (xy 384.783312 -288.110858) (xy 384.736041 -288.12455) (xy 384.687186 -288.130482)
			(xy 384.638011 -288.128501) (xy 384.589792 -288.118657) (xy 384.543776 -288.101205) (xy 384.501155 -288.076598)
			(xy 384.463034 -288.045473) (xy 384.430399 -288.008636) (xy 384.404096 -287.96704) (xy 384.384805 -287.921764)
			(xy 384.373028 -287.87398) (xy 384.369068 -287.824926) (xy 382.898396 -287.824926) (xy 382.898396 -288.774886)
			(xy 384.369068 -288.774886) (xy 384.373028 -288.725832) (xy 384.384805 -288.678048) (xy 384.404096 -288.632772)
			(xy 384.430399 -288.591176) (xy 384.463034 -288.554339) (xy 384.501155 -288.523214) (xy 384.543776 -288.498607)
			(xy 384.589792 -288.481155) (xy 384.638011 -288.471311) (xy 384.687186 -288.46933) (xy 384.736041 -288.475262)
			(xy 384.783312 -288.488954) (xy 384.827774 -288.510052) (xy 384.868277 -288.538008) (xy 384.90377 -288.5721)
			(xy 384.933335 -288.611444) (xy 384.956206 -288.655021) (xy 384.97179 -288.701702) (xy 384.979685 -288.750279)
			(xy 384.98018 -288.774886) (xy 385.319028 -288.774886) (xy 385.322988 -288.725832) (xy 385.334765 -288.678048)
			(xy 385.354056 -288.632772) (xy 385.380359 -288.591176) (xy 385.412994 -288.554339) (xy 385.451115 -288.523214)
			(xy 385.493736 -288.498607) (xy 385.539752 -288.481155) (xy 385.587971 -288.471311) (xy 385.637146 -288.46933)
			(xy 385.686001 -288.475262) (xy 385.733272 -288.488954) (xy 385.777734 -288.510052) (xy 385.818237 -288.538008)
			(xy 385.85373 -288.5721) (xy 385.883295 -288.611444) (xy 385.906166 -288.655021) (xy 385.92175 -288.701702)
			(xy 385.929645 -288.750279) (xy 385.93014 -288.774886) (xy 386.269242 -288.774886) (xy 386.273202 -288.725832)
			(xy 386.284979 -288.678048) (xy 386.30427 -288.632772) (xy 386.330573 -288.591176) (xy 386.363208 -288.554339)
			(xy 386.401329 -288.523214) (xy 386.44395 -288.498607) (xy 386.489966 -288.481155) (xy 386.538185 -288.471311)
			(xy 386.58736 -288.46933) (xy 386.636215 -288.475262) (xy 386.683486 -288.488954) (xy 386.727948 -288.510052)
			(xy 386.768451 -288.538008) (xy 386.803944 -288.5721) (xy 386.833509 -288.611444) (xy 386.85638 -288.655021)
			(xy 386.871964 -288.701702) (xy 386.879859 -288.750279) (xy 386.880354 -288.774886) (xy 387.219202 -288.774886)
			(xy 387.223162 -288.725832) (xy 387.234939 -288.678048) (xy 387.25423 -288.632772) (xy 387.280533 -288.591176)
			(xy 387.313168 -288.554339) (xy 387.351289 -288.523214) (xy 387.39391 -288.498607) (xy 387.439926 -288.481155)
			(xy 387.488145 -288.471311) (xy 387.53732 -288.46933) (xy 387.586175 -288.475262) (xy 387.633446 -288.488954)
			(xy 387.677908 -288.510052) (xy 387.718411 -288.538008) (xy 387.753904 -288.5721) (xy 387.783469 -288.611444)
			(xy 387.80634 -288.655021) (xy 387.821924 -288.701702) (xy 387.829819 -288.750279) (xy 387.830314 -288.774886)
			(xy 387.829819 -288.799493) (xy 387.821924 -288.84807) (xy 387.80634 -288.894751) (xy 387.783469 -288.938328)
			(xy 387.753904 -288.977672) (xy 387.718411 -289.011764) (xy 387.677908 -289.03972) (xy 387.633446 -289.060818)
			(xy 387.586175 -289.07451) (xy 387.53732 -289.080442) (xy 387.488145 -289.078461) (xy 387.439926 -289.068617)
			(xy 387.39391 -289.051165) (xy 387.351289 -289.026558) (xy 387.313168 -288.995433) (xy 387.280533 -288.958596)
			(xy 387.25423 -288.917) (xy 387.234939 -288.871724) (xy 387.223162 -288.82394) (xy 387.219202 -288.774886)
			(xy 386.880354 -288.774886) (xy 386.879859 -288.799493) (xy 386.871964 -288.84807) (xy 386.85638 -288.894751)
			(xy 386.833509 -288.938328) (xy 386.803944 -288.977672) (xy 386.768451 -289.011764) (xy 386.727948 -289.03972)
			(xy 386.683486 -289.060818) (xy 386.636215 -289.07451) (xy 386.58736 -289.080442) (xy 386.538185 -289.078461)
			(xy 386.489966 -289.068617) (xy 386.44395 -289.051165) (xy 386.401329 -289.026558) (xy 386.363208 -288.995433)
			(xy 386.330573 -288.958596) (xy 386.30427 -288.917) (xy 386.284979 -288.871724) (xy 386.273202 -288.82394)
			(xy 386.269242 -288.774886) (xy 385.93014 -288.774886) (xy 385.929645 -288.799493) (xy 385.92175 -288.84807)
			(xy 385.906166 -288.894751) (xy 385.883295 -288.938328) (xy 385.85373 -288.977672) (xy 385.818237 -289.011764)
			(xy 385.777734 -289.03972) (xy 385.733272 -289.060818) (xy 385.686001 -289.07451) (xy 385.637146 -289.080442)
			(xy 385.587971 -289.078461) (xy 385.539752 -289.068617) (xy 385.493736 -289.051165) (xy 385.451115 -289.026558)
			(xy 385.412994 -288.995433) (xy 385.380359 -288.958596) (xy 385.354056 -288.917) (xy 385.334765 -288.871724)
			(xy 385.322988 -288.82394) (xy 385.319028 -288.774886) (xy 384.98018 -288.774886) (xy 384.979685 -288.799493)
			(xy 384.97179 -288.84807) (xy 384.956206 -288.894751) (xy 384.933335 -288.938328) (xy 384.90377 -288.977672)
			(xy 384.868277 -289.011764) (xy 384.827774 -289.03972) (xy 384.783312 -289.060818) (xy 384.736041 -289.07451)
			(xy 384.687186 -289.080442) (xy 384.638011 -289.078461) (xy 384.589792 -289.068617) (xy 384.543776 -289.051165)
			(xy 384.501155 -289.026558) (xy 384.463034 -288.995433) (xy 384.430399 -288.958596) (xy 384.404096 -288.917)
			(xy 384.384805 -288.871724) (xy 384.373028 -288.82394) (xy 384.369068 -288.774886) (xy 382.898396 -288.774886)
			(xy 382.898396 -289.1028) (xy 382.898819 -289.11287) (xy 382.906533 -289.131475) (xy 382.913382 -289.138868)
			(xy 383.49936 -289.724846) (xy 384.369068 -289.724846) (xy 384.373028 -289.675792) (xy 384.384805 -289.628008)
			(xy 384.404096 -289.582732) (xy 384.430399 -289.541136) (xy 384.463034 -289.504299) (xy 384.501155 -289.473174)
			(xy 384.543776 -289.448567) (xy 384.589792 -289.431115) (xy 384.638011 -289.421271) (xy 384.687186 -289.41929)
			(xy 384.736041 -289.425222) (xy 384.783312 -289.438914) (xy 384.827774 -289.460012) (xy 384.868277 -289.487968)
			(xy 384.90377 -289.52206) (xy 384.933335 -289.561404) (xy 384.956206 -289.604981) (xy 384.97179 -289.651662)
			(xy 384.979685 -289.700239) (xy 384.98018 -289.724846) (xy 385.319028 -289.724846) (xy 385.322988 -289.675792)
			(xy 385.334765 -289.628008) (xy 385.354056 -289.582732) (xy 385.380359 -289.541136) (xy 385.412994 -289.504299)
			(xy 385.451115 -289.473174) (xy 385.493736 -289.448567) (xy 385.539752 -289.431115) (xy 385.587971 -289.421271)
			(xy 385.637146 -289.41929) (xy 385.686001 -289.425222) (xy 385.733272 -289.438914) (xy 385.777734 -289.460012)
			(xy 385.818237 -289.487968) (xy 385.85373 -289.52206) (xy 385.883295 -289.561404) (xy 385.906166 -289.604981)
			(xy 385.92175 -289.651662) (xy 385.929645 -289.700239) (xy 385.93014 -289.724846) (xy 386.269242 -289.724846)
			(xy 386.273202 -289.675792) (xy 386.284979 -289.628008) (xy 386.30427 -289.582732) (xy 386.330573 -289.541136)
			(xy 386.363208 -289.504299) (xy 386.401329 -289.473174) (xy 386.44395 -289.448567) (xy 386.489966 -289.431115)
			(xy 386.538185 -289.421271) (xy 386.58736 -289.41929) (xy 386.636215 -289.425222) (xy 386.683486 -289.438914)
			(xy 386.727948 -289.460012) (xy 386.768451 -289.487968) (xy 386.803944 -289.52206) (xy 386.833509 -289.561404)
			(xy 386.85638 -289.604981) (xy 386.871964 -289.651662) (xy 386.879859 -289.700239) (xy 386.880354 -289.724846)
			(xy 387.219202 -289.724846) (xy 387.223162 -289.675792) (xy 387.234939 -289.628008) (xy 387.25423 -289.582732)
			(xy 387.280533 -289.541136) (xy 387.313168 -289.504299) (xy 387.351289 -289.473174) (xy 387.39391 -289.448567)
			(xy 387.439926 -289.431115) (xy 387.488145 -289.421271) (xy 387.53732 -289.41929) (xy 387.586175 -289.425222)
			(xy 387.633446 -289.438914) (xy 387.677908 -289.460012) (xy 387.718411 -289.487968) (xy 387.753904 -289.52206)
			(xy 387.783469 -289.561404) (xy 387.80634 -289.604981) (xy 387.821924 -289.651662) (xy 387.829819 -289.700239)
			(xy 387.830314 -289.724846) (xy 388.169162 -289.724846) (xy 388.173122 -289.675792) (xy 388.184899 -289.628008)
			(xy 388.20419 -289.582732) (xy 388.230493 -289.541136) (xy 388.263128 -289.504299) (xy 388.301249 -289.473174)
			(xy 388.34387 -289.448567) (xy 388.389886 -289.431115) (xy 388.438105 -289.421271) (xy 388.48728 -289.41929)
			(xy 388.536135 -289.425222) (xy 388.583406 -289.438914) (xy 388.627868 -289.460012) (xy 388.668371 -289.487968)
			(xy 388.703864 -289.52206) (xy 388.733429 -289.561404) (xy 388.7563 -289.604981) (xy 388.771884 -289.651662)
			(xy 388.779779 -289.700239) (xy 388.780274 -289.724846) (xy 388.779779 -289.749453) (xy 388.771884 -289.79803)
			(xy 388.7563 -289.844711) (xy 388.733429 -289.888288) (xy 388.703864 -289.927632) (xy 388.668371 -289.961724)
			(xy 388.627868 -289.98968) (xy 388.583406 -290.010778) (xy 388.536135 -290.02447) (xy 388.48728 -290.030402)
			(xy 388.438105 -290.028421) (xy 388.389886 -290.018577) (xy 388.34387 -290.001125) (xy 388.301249 -289.976518)
			(xy 388.263128 -289.945393) (xy 388.230493 -289.908556) (xy 388.20419 -289.86696) (xy 388.184899 -289.821684)
			(xy 388.173122 -289.7739) (xy 388.169162 -289.724846) (xy 387.830314 -289.724846) (xy 387.829819 -289.749453)
			(xy 387.821924 -289.79803) (xy 387.80634 -289.844711) (xy 387.783469 -289.888288) (xy 387.753904 -289.927632)
			(xy 387.718411 -289.961724) (xy 387.677908 -289.98968) (xy 387.633446 -290.010778) (xy 387.586175 -290.02447)
			(xy 387.53732 -290.030402) (xy 387.488145 -290.028421) (xy 387.439926 -290.018577) (xy 387.39391 -290.001125)
			(xy 387.351289 -289.976518) (xy 387.313168 -289.945393) (xy 387.280533 -289.908556) (xy 387.25423 -289.86696)
			(xy 387.234939 -289.821684) (xy 387.223162 -289.7739) (xy 387.219202 -289.724846) (xy 386.880354 -289.724846)
			(xy 386.879859 -289.749453) (xy 386.871964 -289.79803) (xy 386.85638 -289.844711) (xy 386.833509 -289.888288)
			(xy 386.803944 -289.927632) (xy 386.768451 -289.961724) (xy 386.727948 -289.98968) (xy 386.683486 -290.010778)
			(xy 386.636215 -290.02447) (xy 386.58736 -290.030402) (xy 386.538185 -290.028421) (xy 386.489966 -290.018577)
			(xy 386.44395 -290.001125) (xy 386.401329 -289.976518) (xy 386.363208 -289.945393) (xy 386.330573 -289.908556)
			(xy 386.30427 -289.86696) (xy 386.284979 -289.821684) (xy 386.273202 -289.7739) (xy 386.269242 -289.724846)
			(xy 385.93014 -289.724846) (xy 385.929645 -289.749453) (xy 385.92175 -289.79803) (xy 385.906166 -289.844711)
			(xy 385.883295 -289.888288) (xy 385.85373 -289.927632) (xy 385.818237 -289.961724) (xy 385.777734 -289.98968)
			(xy 385.733272 -290.010778) (xy 385.686001 -290.02447) (xy 385.637146 -290.030402) (xy 385.587971 -290.028421)
			(xy 385.539752 -290.018577) (xy 385.493736 -290.001125) (xy 385.451115 -289.976518) (xy 385.412994 -289.945393)
			(xy 385.380359 -289.908556) (xy 385.354056 -289.86696) (xy 385.334765 -289.821684) (xy 385.322988 -289.7739)
			(xy 385.319028 -289.724846) (xy 384.98018 -289.724846) (xy 384.979685 -289.749453) (xy 384.97179 -289.79803)
			(xy 384.956206 -289.844711) (xy 384.933335 -289.888288) (xy 384.90377 -289.927632) (xy 384.868277 -289.961724)
			(xy 384.827774 -289.98968) (xy 384.783312 -290.010778) (xy 384.736041 -290.02447) (xy 384.687186 -290.030402)
			(xy 384.638011 -290.028421) (xy 384.589792 -290.018577) (xy 384.543776 -290.001125) (xy 384.501155 -289.976518)
			(xy 384.463034 -289.945393) (xy 384.430399 -289.908556) (xy 384.404096 -289.86696) (xy 384.384805 -289.821684)
			(xy 384.373028 -289.7739) (xy 384.369068 -289.724846) (xy 383.49936 -289.724846) (xy 384.259074 -290.48456)
			(xy 384.267161 -290.491862) (xy 384.28755 -290.499494) (xy 384.298444 -290.499292) (xy 384.38582 -290.49345)
			(xy 384.405124 -290.483036) (xy 384.411728 -290.4744) (xy 384.427496 -290.454526) (xy 384.464054 -290.419354)
			(xy 384.505549 -290.39017) (xy 384.55101 -290.367658) (xy 384.599374 -290.352344) (xy 384.649507 -290.344586)
			(xy 384.674872 -290.344098) (xy 384.700863 -290.344579) (xy 384.752204 -290.352707) (xy 384.801642 -290.368767)
			(xy 384.847959 -290.392363) (xy 384.890013 -290.422915) (xy 384.926771 -290.45967) (xy 384.957325 -290.501723)
			(xy 384.980925 -290.548038) (xy 384.996988 -290.597474) (xy 385.005119 -290.648816) (xy 385.00558 -290.674806)
			(xy 385.319028 -290.674806) (xy 385.322988 -290.625752) (xy 385.334765 -290.577968) (xy 385.354056 -290.532692)
			(xy 385.380359 -290.491096) (xy 385.412994 -290.454259) (xy 385.451115 -290.423134) (xy 385.493736 -290.398527)
			(xy 385.539752 -290.381075) (xy 385.587971 -290.371231) (xy 385.637146 -290.36925) (xy 385.686001 -290.375182)
			(xy 385.733272 -290.388874) (xy 385.777734 -290.409972) (xy 385.818237 -290.437928) (xy 385.85373 -290.47202)
			(xy 385.883295 -290.511364) (xy 385.906166 -290.554941) (xy 385.92175 -290.601622) (xy 385.929645 -290.650199)
			(xy 385.93014 -290.674806) (xy 386.269242 -290.674806) (xy 386.273202 -290.625752) (xy 386.284979 -290.577968)
			(xy 386.30427 -290.532692) (xy 386.330573 -290.491096) (xy 386.363208 -290.454259) (xy 386.401329 -290.423134)
			(xy 386.44395 -290.398527) (xy 386.489966 -290.381075) (xy 386.538185 -290.371231) (xy 386.58736 -290.36925)
			(xy 386.636215 -290.375182) (xy 386.683486 -290.388874) (xy 386.727948 -290.409972) (xy 386.768451 -290.437928)
			(xy 386.803944 -290.47202) (xy 386.833509 -290.511364) (xy 386.85638 -290.554941) (xy 386.871964 -290.601622)
			(xy 386.879859 -290.650199) (xy 386.880354 -290.674806) (xy 389.119122 -290.674806) (xy 389.123082 -290.625752)
			(xy 389.134859 -290.577968) (xy 389.15415 -290.532692) (xy 389.180453 -290.491096) (xy 389.213088 -290.454259)
			(xy 389.251209 -290.423134) (xy 389.29383 -290.398527) (xy 389.339846 -290.381075) (xy 389.388065 -290.371231)
			(xy 389.43724 -290.36925) (xy 389.486095 -290.375182) (xy 389.533366 -290.388874) (xy 389.577828 -290.409972)
			(xy 389.618331 -290.437928) (xy 389.653824 -290.47202) (xy 389.683389 -290.511364) (xy 389.70626 -290.554941)
			(xy 389.721844 -290.601622) (xy 389.729739 -290.650199) (xy 389.730234 -290.674806) (xy 389.729739 -290.699413)
			(xy 389.721844 -290.74799) (xy 389.70626 -290.794671) (xy 389.683389 -290.838248) (xy 389.653824 -290.877592)
			(xy 389.618331 -290.911684) (xy 389.577828 -290.93964) (xy 389.533366 -290.960738) (xy 389.486095 -290.97443)
			(xy 389.43724 -290.980362) (xy 389.388065 -290.978381) (xy 389.339846 -290.968537) (xy 389.29383 -290.951085)
			(xy 389.251209 -290.926478) (xy 389.213088 -290.895353) (xy 389.180453 -290.858516) (xy 389.15415 -290.81692)
			(xy 389.134859 -290.771644) (xy 389.123082 -290.72386) (xy 389.119122 -290.674806) (xy 386.880354 -290.674806)
			(xy 386.879859 -290.699413) (xy 386.871964 -290.74799) (xy 386.85638 -290.794671) (xy 386.833509 -290.838248)
			(xy 386.803944 -290.877592) (xy 386.768451 -290.911684) (xy 386.727948 -290.93964) (xy 386.683486 -290.960738)
			(xy 386.636215 -290.97443) (xy 386.58736 -290.980362) (xy 386.538185 -290.978381) (xy 386.489966 -290.968537)
			(xy 386.44395 -290.951085) (xy 386.401329 -290.926478) (xy 386.363208 -290.895353) (xy 386.330573 -290.858516)
			(xy 386.30427 -290.81692) (xy 386.284979 -290.771644) (xy 386.273202 -290.72386) (xy 386.269242 -290.674806)
			(xy 385.93014 -290.674806) (xy 385.929645 -290.699413) (xy 385.92175 -290.74799) (xy 385.906166 -290.794671)
			(xy 385.883295 -290.838248) (xy 385.85373 -290.877592) (xy 385.818237 -290.911684) (xy 385.777734 -290.93964)
			(xy 385.733272 -290.960738) (xy 385.686001 -290.97443) (xy 385.637146 -290.980362) (xy 385.587971 -290.978381)
			(xy 385.539752 -290.968537) (xy 385.493736 -290.951085) (xy 385.451115 -290.926478) (xy 385.412994 -290.895353)
			(xy 385.380359 -290.858516) (xy 385.354056 -290.81692) (xy 385.334765 -290.771644) (xy 385.322988 -290.72386)
			(xy 385.319028 -290.674806) (xy 385.00558 -290.674806) (xy 385.005126 -290.700176) (xy 384.997391 -290.750324)
			(xy 384.98209 -290.798703) (xy 384.95958 -290.844177) (xy 384.930389 -290.88568) (xy 384.895203 -290.922239)
			(xy 384.875278 -290.93795) (xy 384.866642 -290.944554) (xy 384.856228 -290.963858) (xy 384.850386 -291.051234)
			(xy 384.85012 -291.062143) (xy 384.857742 -291.082565) (xy 384.865118 -291.090604) (xy 385.209034 -291.43452)
			(xy 385.217122 -291.441817) (xy 385.237511 -291.44943) (xy 385.248404 -291.449252) (xy 385.33578 -291.44341)
			(xy 385.355084 -291.432996) (xy 385.361688 -291.42436) (xy 385.377456 -291.404485) (xy 385.414015 -291.369313)
			(xy 385.45551 -291.340128) (xy 385.500971 -291.317613) (xy 385.549333 -291.302295) (xy 385.599467 -291.294532)
			(xy 385.624832 -291.294058) (xy 385.650819 -291.29457) (xy 385.702151 -291.302704) (xy 385.75158 -291.318768)
			(xy 385.797887 -291.342365) (xy 385.839934 -291.372914) (xy 385.876684 -291.409665) (xy 385.907234 -291.451711)
			(xy 385.930832 -291.498019) (xy 385.946895 -291.547447) (xy 385.95503 -291.598779) (xy 385.95554 -291.624766)
			(xy 386.269242 -291.624766) (xy 386.273202 -291.575712) (xy 386.284979 -291.527928) (xy 386.30427 -291.482652)
			(xy 386.330573 -291.441056) (xy 386.363208 -291.404219) (xy 386.401329 -291.373094) (xy 386.44395 -291.348487)
			(xy 386.489966 -291.331035) (xy 386.538185 -291.321191) (xy 386.58736 -291.31921) (xy 386.636215 -291.325142)
			(xy 386.683486 -291.338834) (xy 386.727948 -291.359932) (xy 386.768451 -291.387888) (xy 386.803944 -291.42198)
			(xy 386.833509 -291.461324) (xy 386.85638 -291.504901) (xy 386.871964 -291.551582) (xy 386.879859 -291.600159)
			(xy 386.880354 -291.624766) (xy 389.119122 -291.624766) (xy 389.123082 -291.575712) (xy 389.134859 -291.527928)
			(xy 389.15415 -291.482652) (xy 389.180453 -291.441056) (xy 389.213088 -291.404219) (xy 389.251209 -291.373094)
			(xy 389.29383 -291.348487) (xy 389.339846 -291.331035) (xy 389.388065 -291.321191) (xy 389.43724 -291.31921)
			(xy 389.486095 -291.325142) (xy 389.533366 -291.338834) (xy 389.577828 -291.359932) (xy 389.618331 -291.387888)
			(xy 389.653824 -291.42198) (xy 389.683389 -291.461324) (xy 389.70626 -291.504901) (xy 389.721844 -291.551582)
			(xy 389.729739 -291.600159) (xy 389.730234 -291.624766) (xy 390.069082 -291.624766) (xy 390.073042 -291.575712)
			(xy 390.084819 -291.527928) (xy 390.10411 -291.482652) (xy 390.130413 -291.441056) (xy 390.163048 -291.404219)
			(xy 390.201169 -291.373094) (xy 390.24379 -291.348487) (xy 390.289806 -291.331035) (xy 390.338025 -291.321191)
			(xy 390.3872 -291.31921) (xy 390.436055 -291.325142) (xy 390.483326 -291.338834) (xy 390.527788 -291.359932)
			(xy 390.568291 -291.387888) (xy 390.603784 -291.42198) (xy 390.633349 -291.461324) (xy 390.65622 -291.504901)
			(xy 390.671804 -291.551582) (xy 390.679699 -291.600159) (xy 390.680194 -291.624766) (xy 390.679699 -291.649373)
			(xy 390.671804 -291.69795) (xy 390.65622 -291.744631) (xy 390.633349 -291.788208) (xy 390.603784 -291.827552)
			(xy 390.568291 -291.861644) (xy 390.527788 -291.8896) (xy 390.483326 -291.910698) (xy 390.436055 -291.92439)
			(xy 390.3872 -291.930322) (xy 390.338025 -291.928341) (xy 390.289806 -291.918497) (xy 390.24379 -291.901045)
			(xy 390.201169 -291.876438) (xy 390.163048 -291.845313) (xy 390.130413 -291.808476) (xy 390.10411 -291.76688)
			(xy 390.084819 -291.721604) (xy 390.073042 -291.67382) (xy 390.069082 -291.624766) (xy 389.730234 -291.624766)
			(xy 389.729739 -291.649373) (xy 389.721844 -291.69795) (xy 389.70626 -291.744631) (xy 389.683389 -291.788208)
			(xy 389.653824 -291.827552) (xy 389.618331 -291.861644) (xy 389.577828 -291.8896) (xy 389.533366 -291.910698)
			(xy 389.486095 -291.92439) (xy 389.43724 -291.930322) (xy 389.388065 -291.928341) (xy 389.339846 -291.918497)
			(xy 389.29383 -291.901045) (xy 389.251209 -291.876438) (xy 389.213088 -291.845313) (xy 389.180453 -291.808476)
			(xy 389.15415 -291.76688) (xy 389.134859 -291.721604) (xy 389.123082 -291.67382) (xy 389.119122 -291.624766)
			(xy 386.880354 -291.624766) (xy 386.879859 -291.649373) (xy 386.871964 -291.69795) (xy 386.85638 -291.744631)
			(xy 386.833509 -291.788208) (xy 386.803944 -291.827552) (xy 386.768451 -291.861644) (xy 386.727948 -291.8896)
			(xy 386.683486 -291.910698) (xy 386.636215 -291.92439) (xy 386.58736 -291.930322) (xy 386.538185 -291.928341)
			(xy 386.489966 -291.918497) (xy 386.44395 -291.901045) (xy 386.401329 -291.876438) (xy 386.363208 -291.845313)
			(xy 386.330573 -291.808476) (xy 386.30427 -291.76688) (xy 386.284979 -291.721604) (xy 386.273202 -291.67382)
			(xy 386.269242 -291.624766) (xy 385.95554 -291.624766) (xy 385.955081 -291.650134) (xy 385.947338 -291.700276)
			(xy 385.932029 -291.748647) (xy 385.909512 -291.794112) (xy 385.880316 -291.835606) (xy 385.845126 -291.872154)
			(xy 385.825238 -291.88791) (xy 385.816602 -291.894514) (xy 385.806188 -291.913818) (xy 385.800346 -292.001194)
			(xy 385.800093 -292.012097) (xy 385.807739 -292.032496) (xy 385.815078 -292.040564) (xy 386.159248 -292.384734)
			(xy 386.167332 -292.392044) (xy 386.187722 -292.399689) (xy 386.198618 -292.399466) (xy 386.285994 -292.393624)
			(xy 386.305298 -292.38321) (xy 386.311902 -292.374574) (xy 386.32767 -292.354699) (xy 386.364228 -292.319527)
			(xy 386.405723 -292.290343) (xy 386.451184 -292.267829) (xy 386.499548 -292.252512) (xy 386.549681 -292.244751)
			(xy 386.575046 -292.244272) (xy 386.601031 -292.244785) (xy 386.652361 -292.252921) (xy 386.701787 -292.268986)
			(xy 386.748092 -292.292584) (xy 386.790135 -292.323134) (xy 386.826883 -292.359885) (xy 386.85743 -292.40193)
			(xy 386.881024 -292.448237) (xy 386.897085 -292.497664) (xy 386.905217 -292.548995) (xy 386.905749 -292.574726)
			(xy 387.219202 -292.574726) (xy 387.223162 -292.525672) (xy 387.234939 -292.477888) (xy 387.25423 -292.432612)
			(xy 387.280533 -292.391016) (xy 387.313168 -292.354179) (xy 387.351289 -292.323054) (xy 387.39391 -292.298447)
			(xy 387.439926 -292.280995) (xy 387.488145 -292.271151) (xy 387.53732 -292.26917) (xy 387.586175 -292.275102)
			(xy 387.633446 -292.288794) (xy 387.677908 -292.309892) (xy 387.718411 -292.337848) (xy 387.753904 -292.37194)
			(xy 387.783469 -292.411284) (xy 387.80634 -292.454861) (xy 387.821924 -292.501542) (xy 387.829819 -292.550119)
			(xy 387.830314 -292.574726) (xy 388.169162 -292.574726) (xy 388.173122 -292.525672) (xy 388.184899 -292.477888)
			(xy 388.20419 -292.432612) (xy 388.230493 -292.391016) (xy 388.263128 -292.354179) (xy 388.301249 -292.323054)
			(xy 388.34387 -292.298447) (xy 388.389886 -292.280995) (xy 388.438105 -292.271151) (xy 388.48728 -292.26917)
			(xy 388.536135 -292.275102) (xy 388.583406 -292.288794) (xy 388.627868 -292.309892) (xy 388.668371 -292.337848)
			(xy 388.703864 -292.37194) (xy 388.733429 -292.411284) (xy 388.7563 -292.454861) (xy 388.771884 -292.501542)
			(xy 388.779779 -292.550119) (xy 388.780274 -292.574726) (xy 388.780269 -292.57498) (xy 389.119122 -292.57498)
			(xy 389.123082 -292.525926) (xy 389.134859 -292.478142) (xy 389.15415 -292.432866) (xy 389.180453 -292.39127)
			(xy 389.213088 -292.354433) (xy 389.251209 -292.323308) (xy 389.29383 -292.298701) (xy 389.339846 -292.281249)
			(xy 389.388065 -292.271405) (xy 389.43724 -292.269424) (xy 389.486095 -292.275356) (xy 389.533366 -292.289048)
			(xy 389.577828 -292.310146) (xy 389.618331 -292.338102) (xy 389.653824 -292.372194) (xy 389.683389 -292.411538)
			(xy 389.70626 -292.455115) (xy 389.721844 -292.501796) (xy 389.729739 -292.550373) (xy 389.730234 -292.57498)
			(xy 389.729739 -292.599587) (xy 389.729407 -292.601629) (xy 390.019276 -292.601629) (xy 390.019276 -292.548331)
			(xy 390.027219 -292.495627) (xy 390.042929 -292.444697) (xy 390.066055 -292.396676) (xy 390.096079 -292.352639)
			(xy 390.132331 -292.313568) (xy 390.174002 -292.280337) (xy 390.22016 -292.253688) (xy 390.269774 -292.234216)
			(xy 390.321736 -292.222356) (xy 390.374886 -292.218373) (xy 390.428036 -292.222356) (xy 390.479998 -292.234216)
			(xy 390.529612 -292.253688) (xy 390.57577 -292.280337) (xy 390.617441 -292.313568) (xy 390.653693 -292.352639)
			(xy 390.683717 -292.396676) (xy 390.706843 -292.444697) (xy 390.722553 -292.495627) (xy 390.730496 -292.548331)
			(xy 390.730994 -292.57498) (xy 391.019042 -292.57498) (xy 391.023002 -292.525926) (xy 391.034779 -292.478142)
			(xy 391.05407 -292.432866) (xy 391.080373 -292.39127) (xy 391.113008 -292.354433) (xy 391.151129 -292.323308)
			(xy 391.19375 -292.298701) (xy 391.239766 -292.281249) (xy 391.287985 -292.271405) (xy 391.33716 -292.269424)
			(xy 391.386015 -292.275356) (xy 391.433286 -292.289048) (xy 391.477748 -292.310146) (xy 391.518251 -292.338102)
			(xy 391.553744 -292.372194) (xy 391.583309 -292.411538) (xy 391.60618 -292.455115) (xy 391.621764 -292.501796)
			(xy 391.629659 -292.550373) (xy 391.630154 -292.57498) (xy 391.629659 -292.599587) (xy 391.621764 -292.648164)
			(xy 391.60618 -292.694845) (xy 391.583309 -292.738422) (xy 391.553744 -292.777766) (xy 391.518251 -292.811858)
			(xy 391.477748 -292.839814) (xy 391.433286 -292.860912) (xy 391.386015 -292.874604) (xy 391.33716 -292.880536)
			(xy 391.287985 -292.878555) (xy 391.239766 -292.868711) (xy 391.19375 -292.851259) (xy 391.151129 -292.826652)
			(xy 391.113008 -292.795527) (xy 391.080373 -292.75869) (xy 391.05407 -292.717094) (xy 391.034779 -292.671818)
			(xy 391.023002 -292.624034) (xy 391.019042 -292.57498) (xy 390.730994 -292.57498) (xy 390.730496 -292.601629)
			(xy 390.722553 -292.654333) (xy 390.706843 -292.705263) (xy 390.683717 -292.753284) (xy 390.653693 -292.797321)
			(xy 390.617441 -292.836392) (xy 390.57577 -292.869623) (xy 390.529612 -292.896272) (xy 390.479998 -292.915744)
			(xy 390.428036 -292.927604) (xy 390.374886 -292.931588) (xy 390.321736 -292.927604) (xy 390.269774 -292.915744)
			(xy 390.22016 -292.896272) (xy 390.174002 -292.869623) (xy 390.132331 -292.836392) (xy 390.096079 -292.797321)
			(xy 390.066055 -292.753284) (xy 390.042929 -292.705263) (xy 390.027219 -292.654333) (xy 390.019276 -292.601629)
			(xy 389.729407 -292.601629) (xy 389.721844 -292.648164) (xy 389.70626 -292.694845) (xy 389.683389 -292.738422)
			(xy 389.653824 -292.777766) (xy 389.618331 -292.811858) (xy 389.577828 -292.839814) (xy 389.533366 -292.860912)
			(xy 389.486095 -292.874604) (xy 389.43724 -292.880536) (xy 389.388065 -292.878555) (xy 389.339846 -292.868711)
			(xy 389.29383 -292.851259) (xy 389.251209 -292.826652) (xy 389.213088 -292.795527) (xy 389.180453 -292.75869)
			(xy 389.15415 -292.717094) (xy 389.134859 -292.671818) (xy 389.123082 -292.624034) (xy 389.119122 -292.57498)
			(xy 388.780269 -292.57498) (xy 388.779779 -292.599333) (xy 388.771884 -292.64791) (xy 388.7563 -292.694591)
			(xy 388.733429 -292.738168) (xy 388.703864 -292.777512) (xy 388.668371 -292.811604) (xy 388.627868 -292.83956)
			(xy 388.583406 -292.860658) (xy 388.536135 -292.87435) (xy 388.48728 -292.880282) (xy 388.438105 -292.878301)
			(xy 388.389886 -292.868457) (xy 388.34387 -292.851005) (xy 388.301249 -292.826398) (xy 388.263128 -292.795273)
			(xy 388.230493 -292.758436) (xy 388.20419 -292.71684) (xy 388.184899 -292.671564) (xy 388.173122 -292.62378)
			(xy 388.169162 -292.574726) (xy 387.830314 -292.574726) (xy 387.829819 -292.599333) (xy 387.821924 -292.64791)
			(xy 387.80634 -292.694591) (xy 387.783469 -292.738168) (xy 387.753904 -292.777512) (xy 387.718411 -292.811604)
			(xy 387.677908 -292.83956) (xy 387.633446 -292.860658) (xy 387.586175 -292.87435) (xy 387.53732 -292.880282)
			(xy 387.488145 -292.878301) (xy 387.439926 -292.868457) (xy 387.39391 -292.851005) (xy 387.351289 -292.826398)
			(xy 387.313168 -292.795273) (xy 387.280533 -292.758436) (xy 387.25423 -292.71684) (xy 387.234939 -292.671564)
			(xy 387.223162 -292.62378) (xy 387.219202 -292.574726) (xy 386.905749 -292.574726) (xy 386.905754 -292.57498)
			(xy 386.905294 -292.600348) (xy 386.89755 -292.650488) (xy 386.882239 -292.698858) (xy 386.859722 -292.744323)
			(xy 386.830526 -292.785816) (xy 386.795336 -292.822364) (xy 386.775452 -292.838124) (xy 386.766816 -292.844728)
			(xy 386.756402 -292.864032) (xy 386.75056 -292.951408) (xy 386.750311 -292.962309) (xy 386.757962 -292.982703)
			(xy 386.765292 -292.990778) (xy 387.109208 -293.334694) (xy 387.117294 -293.341998) (xy 387.137684 -293.349626)
			(xy 387.148578 -293.349426) (xy 387.235954 -293.343584) (xy 387.255258 -293.33317) (xy 387.261862 -293.324534)
			(xy 387.277629 -293.30466) (xy 387.314187 -293.269488) (xy 387.355682 -293.240306) (xy 387.401144 -293.217796)
			(xy 387.449508 -293.202485) (xy 387.499641 -293.194731) (xy 387.525006 -293.194232) (xy 387.550994 -293.194716)
			(xy 387.602329 -293.202848) (xy 387.65176 -293.218911) (xy 387.69807 -293.24251) (xy 387.740117 -293.273063)
			(xy 387.776867 -293.309818) (xy 387.807414 -293.351869) (xy 387.831007 -293.398182) (xy 387.847063 -293.447615)
			(xy 387.855188 -293.498952) (xy 387.855714 -293.52494) (xy 388.169162 -293.52494) (xy 388.173122 -293.475886)
			(xy 388.184899 -293.428102) (xy 388.20419 -293.382826) (xy 388.230493 -293.34123) (xy 388.263128 -293.304393)
			(xy 388.301249 -293.273268) (xy 388.34387 -293.248661) (xy 388.389886 -293.231209) (xy 388.438105 -293.221365)
			(xy 388.48728 -293.219384) (xy 388.536135 -293.225316) (xy 388.583406 -293.239008) (xy 388.627868 -293.260106)
			(xy 388.668371 -293.288062) (xy 388.703864 -293.322154) (xy 388.733429 -293.361498) (xy 388.7563 -293.405075)
			(xy 388.771884 -293.451756) (xy 388.779779 -293.500333) (xy 388.780274 -293.52494) (xy 389.119122 -293.52494)
			(xy 389.123082 -293.475886) (xy 389.134859 -293.428102) (xy 389.15415 -293.382826) (xy 389.180453 -293.34123)
			(xy 389.213088 -293.304393) (xy 389.251209 -293.273268) (xy 389.29383 -293.248661) (xy 389.339846 -293.231209)
			(xy 389.388065 -293.221365) (xy 389.43724 -293.219384) (xy 389.486095 -293.225316) (xy 389.533366 -293.239008)
			(xy 389.577828 -293.260106) (xy 389.618331 -293.288062) (xy 389.653824 -293.322154) (xy 389.683389 -293.361498)
			(xy 389.70626 -293.405075) (xy 389.721844 -293.451756) (xy 389.729739 -293.500333) (xy 389.730234 -293.52494)
			(xy 390.069082 -293.52494) (xy 390.073042 -293.475886) (xy 390.084819 -293.428102) (xy 390.10411 -293.382826)
			(xy 390.130413 -293.34123) (xy 390.163048 -293.304393) (xy 390.201169 -293.273268) (xy 390.24379 -293.248661)
			(xy 390.289806 -293.231209) (xy 390.338025 -293.221365) (xy 390.3872 -293.219384) (xy 390.436055 -293.225316)
			(xy 390.483326 -293.239008) (xy 390.527788 -293.260106) (xy 390.568291 -293.288062) (xy 390.603784 -293.322154)
			(xy 390.633349 -293.361498) (xy 390.65622 -293.405075) (xy 390.671804 -293.451756) (xy 390.679699 -293.500333)
			(xy 390.680194 -293.52494) (xy 390.679699 -293.549547) (xy 390.679367 -293.551589) (xy 390.969236 -293.551589)
			(xy 390.969236 -293.498291) (xy 390.977179 -293.445587) (xy 390.992889 -293.394657) (xy 391.016015 -293.346636)
			(xy 391.046039 -293.302599) (xy 391.082291 -293.263528) (xy 391.123962 -293.230297) (xy 391.17012 -293.203648)
			(xy 391.219734 -293.184176) (xy 391.271696 -293.172316) (xy 391.324846 -293.168333) (xy 391.377996 -293.172316)
			(xy 391.429958 -293.184176) (xy 391.479572 -293.203648) (xy 391.52573 -293.230297) (xy 391.567401 -293.263528)
			(xy 391.603653 -293.302599) (xy 391.633677 -293.346636) (xy 391.656803 -293.394657) (xy 391.672513 -293.445587)
			(xy 391.680456 -293.498291) (xy 391.680954 -293.52494) (xy 391.969002 -293.52494) (xy 391.972962 -293.475886)
			(xy 391.984739 -293.428102) (xy 392.00403 -293.382826) (xy 392.030333 -293.34123) (xy 392.062968 -293.304393)
			(xy 392.101089 -293.273268) (xy 392.14371 -293.248661) (xy 392.189726 -293.231209) (xy 392.237945 -293.221365)
			(xy 392.28712 -293.219384) (xy 392.335975 -293.225316) (xy 392.383246 -293.239008) (xy 392.427708 -293.260106)
			(xy 392.468211 -293.288062) (xy 392.503704 -293.322154) (xy 392.533269 -293.361498) (xy 392.55614 -293.405075)
			(xy 392.571724 -293.451756) (xy 392.579619 -293.500333) (xy 392.580114 -293.52494) (xy 392.579619 -293.549547)
			(xy 392.571724 -293.598124) (xy 392.55614 -293.644805) (xy 392.533269 -293.688382) (xy 392.503704 -293.727726)
			(xy 392.468211 -293.761818) (xy 392.427708 -293.789774) (xy 392.383246 -293.810872) (xy 392.335975 -293.824564)
			(xy 392.28712 -293.830496) (xy 392.237945 -293.828515) (xy 392.189726 -293.818671) (xy 392.14371 -293.801219)
			(xy 392.101089 -293.776612) (xy 392.062968 -293.745487) (xy 392.030333 -293.70865) (xy 392.00403 -293.667054)
			(xy 391.984739 -293.621778) (xy 391.972962 -293.573994) (xy 391.969002 -293.52494) (xy 391.680954 -293.52494)
			(xy 391.680456 -293.551589) (xy 391.672513 -293.604293) (xy 391.656803 -293.655223) (xy 391.633677 -293.703244)
			(xy 391.603653 -293.747281) (xy 391.567401 -293.786352) (xy 391.52573 -293.819583) (xy 391.479572 -293.846232)
			(xy 391.429958 -293.865704) (xy 391.377996 -293.877564) (xy 391.324846 -293.881548) (xy 391.271696 -293.877564)
			(xy 391.219734 -293.865704) (xy 391.17012 -293.846232) (xy 391.123962 -293.819583) (xy 391.082291 -293.786352)
			(xy 391.046039 -293.747281) (xy 391.016015 -293.703244) (xy 390.992889 -293.655223) (xy 390.977179 -293.604293)
			(xy 390.969236 -293.551589) (xy 390.679367 -293.551589) (xy 390.671804 -293.598124) (xy 390.65622 -293.644805)
			(xy 390.633349 -293.688382) (xy 390.603784 -293.727726) (xy 390.568291 -293.761818) (xy 390.527788 -293.789774)
			(xy 390.483326 -293.810872) (xy 390.436055 -293.824564) (xy 390.3872 -293.830496) (xy 390.338025 -293.828515)
			(xy 390.289806 -293.818671) (xy 390.24379 -293.801219) (xy 390.201169 -293.776612) (xy 390.163048 -293.745487)
			(xy 390.130413 -293.70865) (xy 390.10411 -293.667054) (xy 390.084819 -293.621778) (xy 390.073042 -293.573994)
			(xy 390.069082 -293.52494) (xy 389.730234 -293.52494) (xy 389.729739 -293.549547) (xy 389.721844 -293.598124)
			(xy 389.70626 -293.644805) (xy 389.683389 -293.688382) (xy 389.653824 -293.727726) (xy 389.618331 -293.761818)
			(xy 389.577828 -293.789774) (xy 389.533366 -293.810872) (xy 389.486095 -293.824564) (xy 389.43724 -293.830496)
			(xy 389.388065 -293.828515) (xy 389.339846 -293.818671) (xy 389.29383 -293.801219) (xy 389.251209 -293.776612)
			(xy 389.213088 -293.745487) (xy 389.180453 -293.70865) (xy 389.15415 -293.667054) (xy 389.134859 -293.621778)
			(xy 389.123082 -293.573994) (xy 389.119122 -293.52494) (xy 388.780274 -293.52494) (xy 388.779779 -293.549547)
			(xy 388.771884 -293.598124) (xy 388.7563 -293.644805) (xy 388.733429 -293.688382) (xy 388.703864 -293.727726)
			(xy 388.668371 -293.761818) (xy 388.627868 -293.789774) (xy 388.583406 -293.810872) (xy 388.536135 -293.824564)
			(xy 388.48728 -293.830496) (xy 388.438105 -293.828515) (xy 388.389886 -293.818671) (xy 388.34387 -293.801219)
			(xy 388.301249 -293.776612) (xy 388.263128 -293.745487) (xy 388.230493 -293.70865) (xy 388.20419 -293.667054)
			(xy 388.184899 -293.621778) (xy 388.173122 -293.573994) (xy 388.169162 -293.52494) (xy 387.855714 -293.52494)
			(xy 387.855257 -293.55031) (xy 387.847519 -293.600455) (xy 387.832215 -293.648831) (xy 387.809703 -293.694303)
			(xy 387.780513 -293.735805) (xy 387.745328 -293.772363) (xy 387.725412 -293.788084) (xy 387.716776 -293.794688)
			(xy 387.706362 -293.813992) (xy 387.70052 -293.901368) (xy 387.700262 -293.912273) (xy 387.707897 -293.932683)
			(xy 387.715252 -293.940738) (xy 388.249414 -294.4749) (xy 389.119122 -294.4749) (xy 389.123082 -294.425846)
			(xy 389.134859 -294.378062) (xy 389.15415 -294.332786) (xy 389.180453 -294.29119) (xy 389.213088 -294.254353)
			(xy 389.251209 -294.223228) (xy 389.29383 -294.198621) (xy 389.339846 -294.181169) (xy 389.388065 -294.171325)
			(xy 389.43724 -294.169344) (xy 389.486095 -294.175276) (xy 389.533366 -294.188968) (xy 389.577828 -294.210066)
			(xy 389.618331 -294.238022) (xy 389.653824 -294.272114) (xy 389.683389 -294.311458) (xy 389.70626 -294.355035)
			(xy 389.721844 -294.401716) (xy 389.729739 -294.450293) (xy 389.730234 -294.4749) (xy 389.729739 -294.499507)
			(xy 389.729407 -294.501549) (xy 390.019276 -294.501549) (xy 390.019276 -294.448251) (xy 390.027219 -294.395547)
			(xy 390.042929 -294.344617) (xy 390.066055 -294.296596) (xy 390.096079 -294.252559) (xy 390.132331 -294.213488)
			(xy 390.174002 -294.180257) (xy 390.22016 -294.153608) (xy 390.269774 -294.134136) (xy 390.321736 -294.122276)
			(xy 390.374886 -294.118293) (xy 390.428036 -294.122276) (xy 390.479998 -294.134136) (xy 390.529612 -294.153608)
			(xy 390.57577 -294.180257) (xy 390.617441 -294.213488) (xy 390.653693 -294.252559) (xy 390.683717 -294.296596)
			(xy 390.706843 -294.344617) (xy 390.722553 -294.395547) (xy 390.730496 -294.448251) (xy 390.730994 -294.4749)
			(xy 391.019042 -294.4749) (xy 391.023002 -294.425846) (xy 391.034779 -294.378062) (xy 391.05407 -294.332786)
			(xy 391.080373 -294.29119) (xy 391.113008 -294.254353) (xy 391.151129 -294.223228) (xy 391.19375 -294.198621)
			(xy 391.239766 -294.181169) (xy 391.287985 -294.171325) (xy 391.33716 -294.169344) (xy 391.386015 -294.175276)
			(xy 391.433286 -294.188968) (xy 391.477748 -294.210066) (xy 391.518251 -294.238022) (xy 391.553744 -294.272114)
			(xy 391.583309 -294.311458) (xy 391.60618 -294.355035) (xy 391.621764 -294.401716) (xy 391.629659 -294.450293)
			(xy 391.630154 -294.4749) (xy 391.969002 -294.4749) (xy 391.972962 -294.425846) (xy 391.984739 -294.378062)
			(xy 392.00403 -294.332786) (xy 392.030333 -294.29119) (xy 392.062968 -294.254353) (xy 392.101089 -294.223228)
			(xy 392.14371 -294.198621) (xy 392.189726 -294.181169) (xy 392.237945 -294.171325) (xy 392.28712 -294.169344)
			(xy 392.335975 -294.175276) (xy 392.383246 -294.188968) (xy 392.427708 -294.210066) (xy 392.468211 -294.238022)
			(xy 392.503704 -294.272114) (xy 392.533269 -294.311458) (xy 392.55614 -294.355035) (xy 392.571724 -294.401716)
			(xy 392.579619 -294.450293) (xy 392.580114 -294.4749) (xy 392.919216 -294.4749) (xy 392.923176 -294.425846)
			(xy 392.934953 -294.378062) (xy 392.954244 -294.332786) (xy 392.980547 -294.29119) (xy 393.013182 -294.254353)
			(xy 393.051303 -294.223228) (xy 393.093924 -294.198621) (xy 393.13994 -294.181169) (xy 393.188159 -294.171325)
			(xy 393.237334 -294.169344) (xy 393.286189 -294.175276) (xy 393.33346 -294.188968) (xy 393.377922 -294.210066)
			(xy 393.418425 -294.238022) (xy 393.453918 -294.272114) (xy 393.483483 -294.311458) (xy 393.506354 -294.355035)
			(xy 393.521938 -294.401716) (xy 393.529833 -294.450293) (xy 393.530328 -294.4749) (xy 393.529833 -294.499507)
			(xy 393.521938 -294.548084) (xy 393.506354 -294.594765) (xy 393.483483 -294.638342) (xy 393.453918 -294.677686)
			(xy 393.418425 -294.711778) (xy 393.377922 -294.739734) (xy 393.33346 -294.760832) (xy 393.286189 -294.774524)
			(xy 393.237334 -294.780456) (xy 393.188159 -294.778475) (xy 393.13994 -294.768631) (xy 393.093924 -294.751179)
			(xy 393.051303 -294.726572) (xy 393.013182 -294.695447) (xy 392.980547 -294.65861) (xy 392.954244 -294.617014)
			(xy 392.934953 -294.571738) (xy 392.923176 -294.523954) (xy 392.919216 -294.4749) (xy 392.580114 -294.4749)
			(xy 392.579619 -294.499507) (xy 392.571724 -294.548084) (xy 392.55614 -294.594765) (xy 392.533269 -294.638342)
			(xy 392.503704 -294.677686) (xy 392.468211 -294.711778) (xy 392.427708 -294.739734) (xy 392.383246 -294.760832)
			(xy 392.335975 -294.774524) (xy 392.28712 -294.780456) (xy 392.237945 -294.778475) (xy 392.189726 -294.768631)
			(xy 392.14371 -294.751179) (xy 392.101089 -294.726572) (xy 392.062968 -294.695447) (xy 392.030333 -294.65861)
			(xy 392.00403 -294.617014) (xy 391.984739 -294.571738) (xy 391.972962 -294.523954) (xy 391.969002 -294.4749)
			(xy 391.630154 -294.4749) (xy 391.629659 -294.499507) (xy 391.621764 -294.548084) (xy 391.60618 -294.594765)
			(xy 391.583309 -294.638342) (xy 391.553744 -294.677686) (xy 391.518251 -294.711778) (xy 391.477748 -294.739734)
			(xy 391.433286 -294.760832) (xy 391.386015 -294.774524) (xy 391.33716 -294.780456) (xy 391.287985 -294.778475)
			(xy 391.239766 -294.768631) (xy 391.19375 -294.751179) (xy 391.151129 -294.726572) (xy 391.113008 -294.695447)
			(xy 391.080373 -294.65861) (xy 391.05407 -294.617014) (xy 391.034779 -294.571738) (xy 391.023002 -294.523954)
			(xy 391.019042 -294.4749) (xy 390.730994 -294.4749) (xy 390.730496 -294.501549) (xy 390.722553 -294.554253)
			(xy 390.706843 -294.605183) (xy 390.683717 -294.653204) (xy 390.653693 -294.697241) (xy 390.617441 -294.736312)
			(xy 390.57577 -294.769543) (xy 390.529612 -294.796192) (xy 390.479998 -294.815664) (xy 390.428036 -294.827524)
			(xy 390.374886 -294.831508) (xy 390.321736 -294.827524) (xy 390.269774 -294.815664) (xy 390.22016 -294.796192)
			(xy 390.174002 -294.769543) (xy 390.132331 -294.736312) (xy 390.096079 -294.697241) (xy 390.066055 -294.653204)
			(xy 390.042929 -294.605183) (xy 390.027219 -294.554253) (xy 390.019276 -294.501549) (xy 389.729407 -294.501549)
			(xy 389.721844 -294.548084) (xy 389.70626 -294.594765) (xy 389.683389 -294.638342) (xy 389.653824 -294.677686)
			(xy 389.618331 -294.711778) (xy 389.577828 -294.739734) (xy 389.533366 -294.760832) (xy 389.486095 -294.774524)
			(xy 389.43724 -294.780456) (xy 389.388065 -294.778475) (xy 389.339846 -294.768631) (xy 389.29383 -294.751179)
			(xy 389.251209 -294.726572) (xy 389.213088 -294.695447) (xy 389.180453 -294.65861) (xy 389.15415 -294.617014)
			(xy 389.134859 -294.571738) (xy 389.123082 -294.523954) (xy 389.119122 -294.4749) (xy 388.249414 -294.4749)
			(xy 389.959088 -296.184574) (xy 389.967176 -296.191872) (xy 389.987565 -296.199496) (xy 389.998458 -296.199306)
			(xy 390.085834 -296.193464) (xy 390.105138 -296.18305) (xy 390.111742 -296.174414) (xy 390.12751 -296.15454)
			(xy 390.164068 -296.119368) (xy 390.205563 -296.090185) (xy 390.251024 -296.067673) (xy 390.299388 -296.052361)
			(xy 390.349521 -296.044605) (xy 390.374886 -296.044112) (xy 390.400875 -296.044594) (xy 390.452215 -296.052724)
			(xy 390.50165 -296.068785) (xy 390.547963 -296.092382) (xy 390.590015 -296.122935) (xy 390.626769 -296.15969)
			(xy 390.657321 -296.201742) (xy 390.680917 -296.248056) (xy 390.696978 -296.297491) (xy 390.705106 -296.348831)
			(xy 390.705594 -296.37482) (xy 390.705357 -296.391577) (xy 390.701925 -296.424916) (xy 390.698736 -296.441368)
			(xy 390.698736 -296.441876) (xy 390.697117 -296.452981) (xy 390.702516 -296.474735) (xy 390.70915 -296.483786)
			(xy 390.758934 -296.545) (xy 390.766554 -296.553391) (xy 390.786987 -296.563136) (xy 390.798304 -296.563796)
			(xy 391.851388 -296.563796) (xy 391.862722 -296.563199) (xy 391.883184 -296.55345) (xy 391.890758 -296.545)
			(xy 391.940542 -296.483786) (xy 391.947164 -296.474726) (xy 391.952583 -296.452978) (xy 391.950956 -296.441876)
			(xy 391.950956 -296.441368) (xy 391.947759 -296.424917) (xy 391.944325 -296.391578) (xy 391.944098 -296.37482)
			(xy 391.944608 -296.348833) (xy 391.952738 -296.297498) (xy 391.968799 -296.248068) (xy 391.992395 -296.201758)
			(xy 392.022945 -296.15971) (xy 392.059696 -296.122959) (xy 392.101744 -296.092409) (xy 392.148054 -296.068813)
			(xy 392.197484 -296.052752) (xy 392.248819 -296.044622) (xy 392.300793 -296.044622) (xy 392.352128 -296.052752)
			(xy 392.401558 -296.068813) (xy 392.447868 -296.092409) (xy 392.489916 -296.122959) (xy 392.526667 -296.15971)
			(xy 392.557217 -296.201758) (xy 392.580813 -296.248068) (xy 392.596874 -296.297498) (xy 392.605004 -296.348833)
			(xy 392.605514 -296.37482) (xy 392.605277 -296.391577) (xy 392.601846 -296.424916) (xy 392.598656 -296.441368)
			(xy 392.598656 -296.441876) (xy 392.597036 -296.452981) (xy 392.602437 -296.474734) (xy 392.60907 -296.483786)
			(xy 392.658854 -296.545) (xy 392.666476 -296.553388) (xy 392.686909 -296.563124) (xy 392.698224 -296.563796)
			(xy 392.801602 -296.563796) (xy 392.812935 -296.563196) (xy 392.833392 -296.553444) (xy 392.840972 -296.545)
			(xy 392.890756 -296.483786) (xy 392.897377 -296.474726) (xy 392.902794 -296.452978) (xy 392.90117 -296.441876)
			(xy 392.90117 -296.441368) (xy 392.897973 -296.424917) (xy 392.894539 -296.391578) (xy 392.894312 -296.37482)
			(xy 392.894822 -296.348833) (xy 392.902952 -296.297498) (xy 392.919013 -296.248068) (xy 392.942609 -296.201758)
			(xy 392.973159 -296.15971) (xy 393.00991 -296.122959) (xy 393.051958 -296.092409) (xy 393.098268 -296.068813)
			(xy 393.147698 -296.052752) (xy 393.199033 -296.044622) (xy 393.251007 -296.044622) (xy 393.302342 -296.052752)
			(xy 393.351772 -296.068813) (xy 393.398082 -296.092409) (xy 393.44013 -296.122959) (xy 393.476881 -296.15971)
			(xy 393.507431 -296.201758) (xy 393.531027 -296.248068) (xy 393.547088 -296.297498) (xy 393.555218 -296.348833)
			(xy 393.555728 -296.37482) (xy 393.55553 -296.393067) (xy 393.551586 -296.429347) (xy 393.547854 -296.44721)
			(xy 393.545314 -296.45864) (xy 393.550394 -296.480992) (xy 393.60729 -296.551858) (xy 393.614922 -296.560371)
			(xy 393.635499 -296.570265) (xy 393.646914 -296.570908)
		)
		(stroke
			(width 0)
			(type solid)
		)
		(fill yes)
		(layer "In11.Cu")
		(net "PCEPLL3_VDDA18_PEX3")
	)
	(gr_poly
		(pts
			(xy 161.585402 -296.561002) (xy 161.592768 -296.551858) (xy 161.642298 -296.490136) (xy 161.648929 -296.480869)
			(xy 161.654077 -296.458704) (xy 161.652204 -296.447464) (xy 161.652204 -296.44721) (xy 161.648497 -296.429343)
			(xy 161.644546 -296.393066) (xy 161.64433 -296.37482) (xy 161.64484 -296.348833) (xy 161.65297 -296.297498)
			(xy 161.669031 -296.248068) (xy 161.692627 -296.201758) (xy 161.723177 -296.15971) (xy 161.759928 -296.122959)
			(xy 161.801976 -296.092409) (xy 161.848286 -296.068813) (xy 161.897716 -296.052752) (xy 161.949051 -296.044622)
			(xy 162.001025 -296.044622) (xy 162.05236 -296.052752) (xy 162.10179 -296.068813) (xy 162.1481 -296.092409)
			(xy 162.190148 -296.122959) (xy 162.226899 -296.15971) (xy 162.257449 -296.201758) (xy 162.281045 -296.248068)
			(xy 162.297106 -296.297498) (xy 162.305236 -296.348833) (xy 162.305746 -296.37482) (xy 162.305548 -296.393067)
			(xy 162.301604 -296.429347) (xy 162.297872 -296.44721) (xy 162.297872 -296.447464) (xy 162.296031 -296.458704)
			(xy 162.301168 -296.480862) (xy 162.307778 -296.490136) (xy 162.357308 -296.551858) (xy 162.364941 -296.560369)
			(xy 162.385518 -296.570255) (xy 162.396932 -296.570908) (xy 162.514788 -296.570908) (xy 162.535362 -296.561002)
			(xy 162.542728 -296.551858) (xy 162.592258 -296.490136) (xy 162.598894 -296.480871) (xy 162.604046 -296.458704)
			(xy 162.602164 -296.447464) (xy 162.602164 -296.44721) (xy 162.598457 -296.429343) (xy 162.594505 -296.393066)
			(xy 162.59429 -296.37482) (xy 162.5948 -296.348833) (xy 162.60293 -296.297498) (xy 162.618991 -296.248068)
			(xy 162.642587 -296.201758) (xy 162.673137 -296.15971) (xy 162.709888 -296.122959) (xy 162.751936 -296.092409)
			(xy 162.798246 -296.068813) (xy 162.847676 -296.052752) (xy 162.899011 -296.044622) (xy 162.950985 -296.044622)
			(xy 163.00232 -296.052752) (xy 163.05175 -296.068813) (xy 163.09806 -296.092409) (xy 163.140108 -296.122959)
			(xy 163.176859 -296.15971) (xy 163.207409 -296.201758) (xy 163.231005 -296.248068) (xy 163.247066 -296.297498)
			(xy 163.255196 -296.348833) (xy 163.255706 -296.37482) (xy 163.255508 -296.393067) (xy 163.251564 -296.429347)
			(xy 163.247832 -296.44721) (xy 163.247832 -296.447464) (xy 163.245991 -296.458704) (xy 163.251125 -296.480864)
			(xy 163.257738 -296.490136) (xy 163.307268 -296.551858) (xy 163.314898 -296.560375) (xy 163.335475 -296.570278)
			(xy 163.346892 -296.570908) (xy 163.918138 -296.570908) (xy 163.92652 -296.570146) (xy 163.934125 -296.568631)
			(xy 163.947959 -296.561644) (xy 163.953698 -296.55643) (xy 164.178742 -296.331386) (xy 164.185593 -296.32399)
			(xy 164.193331 -296.305391) (xy 164.193728 -296.295318) (xy 164.193728 -294.90035) (xy 164.186108 -294.881554)
			(xy 164.178742 -294.874442) (xy 164.085016 -294.780716) (xy 164.076054 -294.772737) (xy 164.053269 -294.765314)
			(xy 164.041328 -294.766492) (xy 164.026596 -294.768778) (xy 164.019738 -294.772334) (xy 163.997069 -294.782854)
			(xy 163.949353 -294.797702) (xy 163.899945 -294.805193) (xy 163.874958 -294.805608) (xy 163.847671 -294.805055)
			(xy 163.793836 -294.79611) (xy 163.742198 -294.778453) (xy 163.694158 -294.752563) (xy 163.672266 -294.736266)
			(xy 163.665916 -294.731186) (xy 163.64204 -294.722804) (xy 163.637921 -294.721418) (xy 163.629366 -294.719891)
			(xy 163.625022 -294.719756) (xy 163.174934 -294.719756) (xy 163.170587 -294.719864) (xy 163.162029 -294.721394)
			(xy 163.157916 -294.722804) (xy 163.13404 -294.731186) (xy 163.12769 -294.736266) (xy 163.105785 -294.752547)
			(xy 163.057753 -294.778458) (xy 163.00612 -294.796133) (xy 162.952285 -294.805092) (xy 162.897711 -294.805092)
			(xy 162.843876 -294.796133) (xy 162.792243 -294.778458) (xy 162.744211 -294.752547) (xy 162.722306 -294.736266)
			(xy 162.715956 -294.731186) (xy 162.69208 -294.722804) (xy 162.687961 -294.721415) (xy 162.679407 -294.719881)
			(xy 162.675062 -294.719756) (xy 162.224974 -294.719756) (xy 162.220628 -294.719869) (xy 162.212074 -294.721409)
			(xy 162.207956 -294.722804) (xy 162.18408 -294.731186) (xy 162.17773 -294.736266) (xy 162.15582 -294.752536)
			(xy 162.107784 -294.77843) (xy 162.056153 -294.796094) (xy 162.002323 -294.805051) (xy 161.975038 -294.805608)
			(xy 161.949929 -294.805144) (xy 161.900288 -294.797555) (xy 161.852366 -294.782546) (xy 161.807264 -294.760462)
			(xy 161.766022 -294.731811) (xy 161.729587 -294.697252) (xy 161.698797 -294.65758) (xy 161.674361 -294.613708)
			(xy 161.656842 -294.566646) (xy 161.646641 -294.517475) (xy 161.644838 -294.492426) (xy 161.643959 -294.483124)
			(xy 161.636403 -294.466054) (xy 161.630106 -294.459152) (xy 161.381948 -294.211248) (xy 161.3789 -294.211248)
			(xy 161.303716 -294.132762) (xy 161.303208 -294.132254) (xy 160.090866 -292.919912) (xy 160.083951 -292.913634)
			(xy 160.066888 -292.906079) (xy 160.057592 -292.90518) (xy 160.030708 -292.903238) (xy 159.978055 -292.891724)
			(xy 159.927966 -292.871823) (xy 159.881768 -292.84406) (xy 159.840686 -292.809173) (xy 159.805805 -292.768084)
			(xy 159.778051 -292.721881) (xy 159.758158 -292.671789) (xy 159.746654 -292.619134) (xy 159.744664 -292.592252)
			(xy 159.743791 -292.582947) (xy 159.736243 -292.565869) (xy 159.729932 -292.558978) (xy 159.140652 -291.969698)
			(xy 159.133736 -291.963424) (xy 159.116672 -291.955876) (xy 159.107378 -291.954966) (xy 159.080521 -291.95301)
			(xy 159.027923 -291.941481) (xy 158.977888 -291.921581) (xy 158.93174 -291.893837) (xy 158.890697 -291.858981)
			(xy 158.855845 -291.817934) (xy 158.828105 -291.771783) (xy 158.80821 -291.721747) (xy 158.796685 -291.669148)
			(xy 158.794704 -291.642292) (xy 158.793819 -291.632994) (xy 158.786251 -291.615935) (xy 158.779972 -291.609018)
			(xy 158.190692 -291.019738) (xy 158.18378 -291.013454) (xy 158.166717 -291.005887) (xy 158.157418 -291.005006)
			(xy 158.130557 -291.003053) (xy 158.077952 -290.99153) (xy 158.027909 -290.971634) (xy 157.981752 -290.943892)
			(xy 157.9407 -290.909037) (xy 157.905839 -290.867991) (xy 157.87809 -290.821838) (xy 157.858186 -290.771798)
			(xy 157.846654 -290.719195) (xy 157.844744 -290.692332) (xy 157.843867 -290.683029) (xy 157.836313 -290.665958)
			(xy 157.830012 -290.659058) (xy 157.240732 -290.069778) (xy 157.233814 -290.063509) (xy 157.21675 -290.05597)
			(xy 157.207458 -290.055046) (xy 157.180599 -290.053089) (xy 157.127999 -290.041559) (xy 157.077962 -290.021658)
			(xy 157.03181 -289.993915) (xy 156.990762 -289.95906) (xy 156.955904 -289.918016) (xy 156.928156 -289.871866)
			(xy 156.908251 -289.821831) (xy 156.896715 -289.769232) (xy 156.894784 -289.742372) (xy 156.893898 -289.733073)
			(xy 156.886334 -289.716012) (xy 156.880052 -289.709098) (xy 156.290772 -289.119818) (xy 156.283858 -289.113539)
			(xy 156.266795 -289.105981) (xy 156.257498 -289.105086) (xy 156.230639 -289.103132) (xy 156.178037 -289.091605)
			(xy 156.127999 -289.071708) (xy 156.081846 -289.043964) (xy 156.040799 -289.009109) (xy 156.005942 -288.968063)
			(xy 155.978197 -288.921911) (xy 155.958298 -288.871873) (xy 155.94677 -288.819271) (xy 155.944824 -288.792412)
			(xy 155.943943 -288.783112) (xy 155.936381 -288.766047) (xy 155.930092 -288.759138) (xy 154.390852 -287.219898)
			(xy 154.383936 -287.213624) (xy 154.366872 -287.206076) (xy 154.357578 -287.205166) (xy 154.332529 -287.20337)
			(xy 154.283362 -287.193159) (xy 154.236302 -287.175632) (xy 154.192434 -287.151193) (xy 154.152764 -287.120402)
			(xy 154.118205 -287.083968) (xy 154.089551 -287.042729) (xy 154.067461 -286.997631) (xy 154.052443 -286.949713)
			(xy 154.044841 -286.900074) (xy 154.044396 -286.874966) (xy 154.044918 -286.848522) (xy 154.053338 -286.796307)
			(xy 154.06996 -286.746098) (xy 154.094358 -286.699172) (xy 154.125912 -286.656727) (xy 154.163818 -286.619843)
			(xy 154.207109 -286.58946) (xy 154.254683 -286.566353) (xy 154.279854 -286.558228) (xy 154.295856 -286.553402)
			(xy 154.315922 -286.526478) (xy 154.315922 -286.27324) (xy 154.295856 -286.246316) (xy 154.279854 -286.24149)
			(xy 154.25468 -286.233377) (xy 154.207103 -286.210278) (xy 154.163809 -286.179901) (xy 154.125901 -286.143021)
			(xy 154.094346 -286.100578) (xy 154.069949 -286.053654) (xy 154.053331 -286.003444) (xy 154.044915 -285.95123)
			(xy 154.044918 -285.898342) (xy 154.053337 -285.846129) (xy 154.06996 -285.795921) (xy 154.094361 -285.748999)
			(xy 154.125919 -285.706558) (xy 154.16383 -285.669681) (xy 154.207127 -285.639308) (xy 154.254706 -285.616213)
			(xy 154.279854 -285.608014) (xy 154.295856 -285.603188) (xy 154.315922 -285.576264) (xy 154.315922 -285.32328)
			(xy 154.295856 -285.296356) (xy 154.279854 -285.29153) (xy 154.254677 -285.283416) (xy 154.207094 -285.260317)
			(xy 154.163793 -285.229938) (xy 154.12588 -285.193055) (xy 154.09432 -285.150608) (xy 154.069918 -285.103679)
			(xy 154.053296 -285.053465) (xy 154.044878 -285.001245) (xy 154.044878 -284.948351) (xy 154.053297 -284.896131)
			(xy 154.06992 -284.845917) (xy 154.094322 -284.798988) (xy 154.125883 -284.756542) (xy 154.163797 -284.719659)
			(xy 154.207098 -284.689281) (xy 154.254681 -284.666182) (xy 154.279854 -284.658054) (xy 154.295856 -284.653228)
			(xy 154.315922 -284.626304) (xy 154.315922 -284.37332) (xy 154.295856 -284.346396) (xy 154.279854 -284.34157)
			(xy 154.254674 -284.333456) (xy 154.207084 -284.310355) (xy 154.163778 -284.279975) (xy 154.125859 -284.243089)
			(xy 154.094294 -284.200638) (xy 154.069887 -284.153705) (xy 154.053262 -284.103485) (xy 154.044841 -284.051259)
			(xy 154.044839 -283.998359) (xy 154.053257 -283.946133) (xy 154.06988 -283.895912) (xy 154.094284 -283.848978)
			(xy 154.125847 -283.806525) (xy 154.163764 -283.769637) (xy 154.207068 -283.739254) (xy 154.254657 -283.71615)
			(xy 154.279854 -283.708094) (xy 154.295856 -283.703268) (xy 154.315922 -283.676344) (xy 154.315922 -283.42336)
			(xy 154.295856 -283.396436) (xy 154.279854 -283.39161) (xy 154.254679 -283.383497) (xy 154.207098 -283.360397)
			(xy 154.163801 -283.330019) (xy 154.125891 -283.293138) (xy 154.094333 -283.250693) (xy 154.069933 -283.203766)
			(xy 154.053313 -283.153554) (xy 154.044897 -283.101337) (xy 154.044898 -283.048446) (xy 154.053317 -282.99623)
			(xy 154.06994 -282.946019) (xy 154.094342 -282.899093) (xy 154.125901 -282.85665) (xy 154.163814 -282.81977)
			(xy 154.207112 -282.789395) (xy 154.254694 -282.766298) (xy 154.279854 -282.758134) (xy 154.295856 -282.753308)
			(xy 154.315922 -282.726384) (xy 154.315922 -282.4734) (xy 154.295856 -282.446476) (xy 154.279854 -282.44165)
			(xy 154.254675 -282.433536) (xy 154.207089 -282.410436) (xy 154.163786 -282.380056) (xy 154.125869 -282.343172)
			(xy 154.094307 -282.300723) (xy 154.069903 -282.253792) (xy 154.053279 -282.203575) (xy 154.044859 -282.151352)
			(xy 154.044859 -282.098455) (xy 154.053277 -282.046232) (xy 154.0699 -281.996015) (xy 154.094303 -281.949083)
			(xy 154.125865 -281.906633) (xy 154.16378 -281.869748) (xy 154.207083 -281.839368) (xy 154.254669 -281.816266)
			(xy 154.279854 -281.808174) (xy 154.295856 -281.803348) (xy 154.315922 -281.776424) (xy 154.315922 -281.52344)
			(xy 154.295856 -281.496516) (xy 154.279854 -281.49169) (xy 154.25468 -281.483577) (xy 154.207103 -281.460478)
			(xy 154.163809 -281.430101) (xy 154.125901 -281.393221) (xy 154.094346 -281.350778) (xy 154.069949 -281.303854)
			(xy 154.053331 -281.253644) (xy 154.044915 -281.20143) (xy 154.044918 -281.148542) (xy 154.053337 -281.096329)
			(xy 154.06996 -281.046121) (xy 154.094361 -280.999199) (xy 154.125919 -280.956758) (xy 154.16383 -280.919881)
			(xy 154.207127 -280.889508) (xy 154.254706 -280.866413) (xy 154.279854 -280.858214) (xy 154.295856 -280.853388)
			(xy 154.315922 -280.826464) (xy 154.315922 -280.573226) (xy 154.295856 -280.546302) (xy 154.279854 -280.541476)
			(xy 154.254673 -280.533362) (xy 154.207083 -280.510261) (xy 154.163775 -280.47988) (xy 154.125856 -280.442994)
			(xy 154.09429 -280.400543) (xy 154.069883 -280.353608) (xy 154.053256 -280.303388) (xy 154.044835 -280.251161)
			(xy 154.044833 -280.19826) (xy 154.053251 -280.146033) (xy 154.069874 -280.095812) (xy 154.094278 -280.048876)
			(xy 154.125841 -280.006423) (xy 154.163759 -279.969534) (xy 154.207064 -279.93915) (xy 154.254653 -279.916046)
			(xy 154.279854 -279.908) (xy 154.295856 -279.903174) (xy 154.315922 -279.87625) (xy 154.315922 -279.623266)
			(xy 154.295856 -279.596342) (xy 154.279854 -279.591516) (xy 154.254678 -279.583403) (xy 154.207097 -279.560303)
			(xy 154.163799 -279.529925) (xy 154.125887 -279.493043) (xy 154.094329 -279.450597) (xy 154.069929 -279.40367)
			(xy 154.053308 -279.353457) (xy 154.044891 -279.30124) (xy 154.044892 -279.248348) (xy 154.053311 -279.19613)
			(xy 154.069934 -279.145918) (xy 154.094336 -279.098992) (xy 154.125896 -279.056547) (xy 154.163809 -279.019667)
			(xy 154.207108 -278.989291) (xy 154.25469 -278.966193) (xy 154.279854 -278.95804) (xy 154.295856 -278.953214)
			(xy 154.315922 -278.92629) (xy 154.315922 -278.673306) (xy 154.295856 -278.646382) (xy 154.279854 -278.641556)
			(xy 154.254675 -278.633442) (xy 154.207087 -278.610342) (xy 154.163783 -278.579962) (xy 154.125866 -278.543077)
			(xy 154.094303 -278.500628) (xy 154.069898 -278.453696) (xy 154.053274 -278.403478) (xy 154.044854 -278.351254)
			(xy 154.044853 -278.298356) (xy 154.053271 -278.246132) (xy 154.069894 -278.195914) (xy 154.094297 -278.148981)
			(xy 154.125859 -278.106531) (xy 154.163775 -278.069645) (xy 154.207078 -278.039263) (xy 154.254665 -278.016161)
			(xy 154.279854 -278.00808) (xy 154.295856 -278.003254) (xy 154.315922 -277.97633) (xy 154.315922 -277.723346)
			(xy 154.295856 -277.696422) (xy 154.279854 -277.691596) (xy 154.25468 -277.683483) (xy 154.207102 -277.660384)
			(xy 154.163807 -277.630007) (xy 154.125898 -277.593126) (xy 154.094342 -277.550682) (xy 154.069944 -277.503757)
			(xy 154.053325 -277.453547) (xy 154.04491 -277.401332) (xy 154.044912 -277.348444) (xy 154.053331 -277.296229)
			(xy 154.069954 -277.24602) (xy 154.094355 -277.199097) (xy 154.125914 -277.156656) (xy 154.163825 -277.119778)
			(xy 154.207123 -277.089404) (xy 154.254702 -277.066309) (xy 154.279854 -277.05812) (xy 154.295856 -277.053294)
			(xy 154.315922 -277.02637) (xy 154.315922 -276.773386) (xy 154.295856 -276.746462) (xy 154.279854 -276.741636)
			(xy 154.254676 -276.733522) (xy 154.207092 -276.710422) (xy 154.163791 -276.680043) (xy 154.125877 -276.64316)
			(xy 154.094316 -276.600712) (xy 154.069913 -276.553783) (xy 154.053291 -276.503568) (xy 154.044872 -276.451347)
			(xy 154.044873 -276.398452) (xy 154.053291 -276.346231) (xy 154.069914 -276.296016) (xy 154.094317 -276.249087)
			(xy 154.125878 -276.206639) (xy 154.163792 -276.169756) (xy 154.207093 -276.139377) (xy 154.254678 -276.116277)
			(xy 154.279854 -276.10816) (xy 154.295856 -276.103334) (xy 154.315922 -276.07641) (xy 154.315922 -275.823426)
			(xy 154.295856 -275.796502) (xy 154.279854 -275.791676) (xy 154.254673 -275.783562) (xy 154.207083 -275.760461)
			(xy 154.163775 -275.73008) (xy 154.125856 -275.693194) (xy 154.09429 -275.650743) (xy 154.069883 -275.603808)
			(xy 154.053256 -275.553588) (xy 154.044835 -275.501361) (xy 154.044833 -275.44846) (xy 154.053251 -275.396233)
			(xy 154.069874 -275.346012) (xy 154.094278 -275.299076) (xy 154.125841 -275.256623) (xy 154.163759 -275.219734)
			(xy 154.207064 -275.18935) (xy 154.254653 -275.166246) (xy 154.279854 -275.1582) (xy 154.295856 -275.153374)
			(xy 154.315922 -275.12645) (xy 154.315922 -274.873466) (xy 154.295856 -274.846542) (xy 154.279854 -274.841716)
			(xy 154.254678 -274.833603) (xy 154.207097 -274.810503) (xy 154.163799 -274.780125) (xy 154.125887 -274.743243)
			(xy 154.094329 -274.700797) (xy 154.069929 -274.65387) (xy 154.053308 -274.603657) (xy 154.044891 -274.55144)
			(xy 154.044892 -274.498548) (xy 154.053311 -274.44633) (xy 154.069934 -274.396118) (xy 154.094336 -274.349192)
			(xy 154.125896 -274.306747) (xy 154.163809 -274.269867) (xy 154.207108 -274.239491) (xy 154.25469 -274.216393)
			(xy 154.279854 -274.20824) (xy 154.295856 -274.203414) (xy 154.315922 -274.17649) (xy 154.315922 -273.923252)
			(xy 154.295856 -273.896328) (xy 154.279854 -273.891502) (xy 154.254662 -273.883406) (xy 154.207046 -273.860334)
			(xy 154.163712 -273.829972) (xy 154.125766 -273.793096) (xy 154.094178 -273.750648) (xy 154.069754 -273.70371)
			(xy 154.053117 -273.653482) (xy 154.044692 -273.601246) (xy 154.044693 -273.548334) (xy 154.053122 -273.496098)
			(xy 154.069762 -273.44587) (xy 154.094189 -273.398935) (xy 154.12578 -273.356488) (xy 154.163728 -273.319615)
			(xy 154.207063 -273.289256) (xy 154.254681 -273.266186) (xy 154.279854 -273.258026) (xy 154.295856 -273.2532)
			(xy 154.315922 -273.226276) (xy 154.315922 -272.973292) (xy 154.295856 -272.946368) (xy 154.279854 -272.941542)
			(xy 154.254676 -272.933428) (xy 154.207091 -272.910328) (xy 154.163789 -272.879949) (xy 154.125874 -272.843065)
			(xy 154.094312 -272.800617) (xy 154.069909 -272.753687) (xy 154.053286 -272.703471) (xy 154.044867 -272.651249)
			(xy 154.044867 -272.598353) (xy 154.053285 -272.546132) (xy 154.069908 -272.495915) (xy 154.094311 -272.448985)
			(xy 154.125872 -272.406537) (xy 154.163787 -272.369653) (xy 154.207089 -272.339273) (xy 154.254674 -272.316172)
			(xy 154.279854 -272.308066) (xy 154.295856 -272.30324) (xy 154.315922 -272.276316) (xy 154.315922 -265.896344)
			(xy 154.29484 -265.868912) (xy 154.277568 -265.864594) (xy 154.250565 -265.857179) (xy 154.198926 -265.835522)
			(xy 154.151008 -265.806549) (xy 154.10784 -265.770883) (xy 154.07035 -265.729289) (xy 154.039342 -265.682661)
			(xy 154.015484 -265.632002) (xy 153.999288 -265.578399) (xy 153.991101 -265.523004) (xy 153.9911 -265.467008)
			(xy 153.999285 -265.411613) (xy 154.01548 -265.358009) (xy 154.039336 -265.307349) (xy 154.070342 -265.260721)
			(xy 154.107831 -265.219126) (xy 154.150998 -265.183458) (xy 154.198916 -265.154483) (xy 154.250554 -265.132825)
			(xy 154.277568 -265.125454) (xy 154.288352 -265.122131) (xy 154.305766 -265.107825) (xy 154.315391 -265.087447)
			(xy 154.315922 -265.076178) (xy 154.315922 -265.039094) (xy 154.315559 -265.030046) (xy 154.309281 -265.013073)
			(xy 154.297506 -264.999332) (xy 154.28976 -264.994644) (xy 154.25166 -264.973562) (xy 154.22626 -264.973562)
			(xy 154.21483 -264.979658) (xy 154.186892 -264.993944) (xy 154.127507 -265.014197) (xy 154.065608 -265.024464)
			(xy 154.034236 -265.025124) (xy 154.006981 -265.024664) (xy 153.953025 -265.016911) (xy 153.900722 -265.001558)
			(xy 153.851136 -264.978918) (xy 153.805278 -264.949451) (xy 153.764079 -264.913758) (xy 153.72838 -264.872564)
			(xy 153.698907 -264.826709) (xy 153.67626 -264.777127) (xy 153.6609 -264.724826) (xy 153.65314 -264.670871)
			(xy 153.652728 -264.643616) (xy 153.653185 -264.617153) (xy 153.660509 -264.564736) (xy 153.675006 -264.513834)
			(xy 153.696396 -264.465422) (xy 153.72427 -264.420431) (xy 153.758093 -264.379722) (xy 153.797217 -264.344078)
			(xy 153.84089 -264.31418) (xy 153.888275 -264.290604) (xy 153.938463 -264.273801) (xy 153.964386 -264.268458)
			(xy 153.972514 -264.266934) (xy 153.994612 -264.254742) (xy 153.998211 -264.252621) (xy 154.004726 -264.247392)
			(xy 154.007566 -264.244328) (xy 154.022044 -264.228326) (xy 154.026853 -264.222516) (xy 154.033168 -264.208828)
			(xy 154.03449 -264.201402) (xy 154.034998 -264.196576) (xy 154.036804 -264.168773) (xy 154.047468 -264.11409)
			(xy 154.065968 -264.061538) (xy 154.091912 -264.012234) (xy 154.124747 -263.967225) (xy 154.163776 -263.927467)
			(xy 154.20817 -263.893805) (xy 154.256987 -263.866955) (xy 154.282902 -263.856724) (xy 154.297888 -263.851136)
			(xy 154.315922 -263.825228) (xy 154.315922 -263.761728) (xy 154.298904 -263.736074) (xy 154.284426 -263.730232)
			(xy 154.258634 -263.719024) (xy 154.210383 -263.690139) (xy 154.166897 -263.654483) (xy 154.129116 -263.612829)
			(xy 154.097859 -263.56608) (xy 154.073805 -263.515249) (xy 154.057473 -263.461437) (xy 154.049218 -263.40581)
			(xy 154.049219 -263.349575) (xy 154.057476 -263.293948) (xy 154.07381 -263.240137) (xy 154.097867 -263.189307)
			(xy 154.129125 -263.142559) (xy 154.166908 -263.100907) (xy 154.210396 -263.065252) (xy 154.258647 -263.036369)
			(xy 154.284426 -263.025128) (xy 154.298904 -263.019286) (xy 154.315922 -262.993632) (xy 154.315922 -260.743446)
			(xy 154.315668 -260.743192) (xy 154.315668 -260.712458) (xy 154.31516 -260.70433) (xy 154.313533 -260.696477)
			(xy 154.306161 -260.682246) (xy 154.300682 -260.67639) (xy 153.482802 -259.85851) (xy 153.475404 -259.851662)
			(xy 153.456806 -259.843925) (xy 153.446734 -259.843524) (xy 151.081994 -259.843524) (xy 151.072474 -259.843924)
			(xy 151.054735 -259.850844) (xy 151.04745 -259.856986) (xy 151.026212 -259.87584) (xy 150.979198 -259.907696)
			(xy 150.927979 -259.932225) (xy 150.873688 -259.948887) (xy 150.817527 -259.95731) (xy 150.760737 -259.95731)
			(xy 150.704576 -259.948887) (xy 150.650285 -259.932225) (xy 150.599066 -259.907696) (xy 150.552052 -259.87584)
			(xy 150.530814 -259.856986) (xy 150.523557 -259.850795) (xy 150.505802 -259.843864) (xy 150.49627 -259.843524)
			(xy 150.313644 -259.843524) (xy 150.294848 -259.851144) (xy 150.287736 -259.85851) (xy 150.091648 -260.054598)
			(xy 150.084796 -260.061994) (xy 150.077053 -260.080593) (xy 150.076662 -260.090666) (xy 150.076662 -260.338316)
			(xy 152.679144 -260.338316) (xy 152.683215 -260.282694) (xy 152.695341 -260.228257) (xy 152.715264 -260.176166)
			(xy 152.74256 -260.127531) (xy 152.776646 -260.083388) (xy 152.816795 -260.044679) (xy 152.862153 -260.012228)
			(xy 152.911753 -259.986727) (xy 152.964537 -259.96872) (xy 153.01938 -259.95859) (xy 153.075114 -259.956553)
			(xy 153.130551 -259.962653) (xy 153.184508 -259.976759) (xy 153.235837 -259.998571) (xy 153.283443 -260.027625)
			(xy 153.326311 -260.0633) (xy 153.363528 -260.104837) (xy 153.394301 -260.15135) (xy 153.417973 -260.201847)
			(xy 153.434041 -260.255254) (xy 153.442161 -260.31043) (xy 153.44267 -260.338316) (xy 153.442161 -260.366202)
			(xy 153.434041 -260.421378) (xy 153.417973 -260.474785) (xy 153.394301 -260.525282) (xy 153.363528 -260.571795)
			(xy 153.326311 -260.613332) (xy 153.283443 -260.649007) (xy 153.235837 -260.678061) (xy 153.184508 -260.699873)
			(xy 153.130551 -260.713979) (xy 153.075114 -260.720079) (xy 153.01938 -260.718042) (xy 152.964537 -260.707912)
			(xy 152.911753 -260.689905) (xy 152.862153 -260.664404) (xy 152.816795 -260.631953) (xy 152.776646 -260.593244)
			(xy 152.74256 -260.549101) (xy 152.715264 -260.500466) (xy 152.695341 -260.448375) (xy 152.683215 -260.393938)
			(xy 152.679144 -260.338316) (xy 150.076662 -260.338316) (xy 150.076662 -262.438388) (xy 150.07744 -262.450566)
			(xy 150.088723 -262.472163) (xy 150.098252 -262.47979) (xy 150.176484 -262.534908) (xy 150.201122 -262.53821)
			(xy 150.212806 -262.533892) (xy 150.244088 -262.523373) (xy 150.309096 -262.512016) (xy 150.342092 -262.511286)
			(xy 150.369346 -262.511749) (xy 150.423298 -262.519505) (xy 150.475598 -262.534861) (xy 150.52518 -262.557503)
			(xy 150.571035 -262.586971) (xy 150.612229 -262.622665) (xy 150.647924 -262.663859) (xy 150.677393 -262.709713)
			(xy 150.700037 -262.759295) (xy 150.715393 -262.811594) (xy 150.721919 -262.85698) (xy 153.136852 -262.85698)
			(xy 153.140923 -262.801358) (xy 153.153049 -262.746921) (xy 153.172972 -262.69483) (xy 153.200268 -262.646195)
			(xy 153.234354 -262.602052) (xy 153.274503 -262.563343) (xy 153.319861 -262.530892) (xy 153.369461 -262.505391)
			(xy 153.422245 -262.487384) (xy 153.477088 -262.477254) (xy 153.532822 -262.475217) (xy 153.588259 -262.481317)
			(xy 153.642216 -262.495423) (xy 153.693545 -262.517235) (xy 153.741151 -262.546289) (xy 153.784019 -262.581964)
			(xy 153.821236 -262.623501) (xy 153.852009 -262.670014) (xy 153.875681 -262.720511) (xy 153.891749 -262.773918)
			(xy 153.899869 -262.829094) (xy 153.900378 -262.85698) (xy 153.899869 -262.884866) (xy 153.891749 -262.940042)
			(xy 153.875681 -262.993449) (xy 153.852009 -263.043946) (xy 153.821236 -263.090459) (xy 153.784019 -263.131996)
			(xy 153.741151 -263.167671) (xy 153.693545 -263.196725) (xy 153.642216 -263.218537) (xy 153.588259 -263.232643)
			(xy 153.532822 -263.238743) (xy 153.477088 -263.236706) (xy 153.422245 -263.226576) (xy 153.369461 -263.208569)
			(xy 153.319861 -263.183068) (xy 153.274503 -263.150617) (xy 153.234354 -263.111908) (xy 153.200268 -263.067765)
			(xy 153.172972 -263.01913) (xy 153.153049 -262.967039) (xy 153.140923 -262.912602) (xy 153.136852 -262.85698)
			(xy 150.721919 -262.85698) (xy 150.723151 -262.865546) (xy 150.723151 -262.920054) (xy 150.715393 -262.974006)
			(xy 150.700037 -263.026305) (xy 150.677393 -263.075887) (xy 150.647924 -263.121741) (xy 150.612229 -263.162935)
			(xy 150.571035 -263.198629) (xy 150.52518 -263.228097) (xy 150.475598 -263.250739) (xy 150.423298 -263.266095)
			(xy 150.369346 -263.273851) (xy 150.342092 -263.274302) (xy 150.309093 -263.273606) (xy 150.244083 -263.262239)
			(xy 150.212806 -263.251696) (xy 150.201122 -263.247378) (xy 150.176484 -263.25068) (xy 150.098252 -263.305798)
			(xy 150.088667 -263.313373) (xy 150.077397 -263.335004) (xy 150.076662 -263.3472) (xy 150.076662 -264.683748)
			(xy 150.077096 -264.693813) (xy 150.084829 -264.712399) (xy 150.091648 -264.719816) (xy 150.739856 -265.368024)
			(xy 150.746704 -265.375422) (xy 150.754436 -265.39402) (xy 150.754842 -265.404092) (xy 150.754842 -267.578078)
			(xy 152.95321 -267.578078) (xy 152.957281 -267.522456) (xy 152.969407 -267.468019) (xy 152.98933 -267.415928)
			(xy 153.016626 -267.367293) (xy 153.050712 -267.32315) (xy 153.090861 -267.284441) (xy 153.136219 -267.25199)
			(xy 153.185819 -267.226489) (xy 153.238603 -267.208482) (xy 153.293446 -267.198352) (xy 153.34918 -267.196315)
			(xy 153.404617 -267.202415) (xy 153.458574 -267.216521) (xy 153.509903 -267.238333) (xy 153.557509 -267.267387)
			(xy 153.600377 -267.303062) (xy 153.637594 -267.344599) (xy 153.668367 -267.391112) (xy 153.692039 -267.441609)
			(xy 153.708107 -267.495016) (xy 153.716227 -267.550192) (xy 153.716736 -267.578078) (xy 153.716227 -267.605964)
			(xy 153.708107 -267.66114) (xy 153.692039 -267.714547) (xy 153.668367 -267.765044) (xy 153.637594 -267.811557)
			(xy 153.600377 -267.853094) (xy 153.557509 -267.888769) (xy 153.509903 -267.917823) (xy 153.458574 -267.939635)
			(xy 153.404617 -267.953741) (xy 153.34918 -267.959841) (xy 153.293446 -267.957804) (xy 153.238603 -267.947674)
			(xy 153.185819 -267.929667) (xy 153.136219 -267.904166) (xy 153.090861 -267.871715) (xy 153.050712 -267.833006)
			(xy 153.016626 -267.788863) (xy 152.98933 -267.740228) (xy 152.969407 -267.688137) (xy 152.957281 -267.6337)
			(xy 152.95321 -267.578078) (xy 150.754842 -267.578078) (xy 150.754842 -273.388328) (xy 150.754412 -273.398395)
			(xy 150.746684 -273.416986) (xy 150.739856 -273.424396) (xy 150.713186 -273.451066) (xy 150.706341 -273.458464)
			(xy 150.698617 -273.477063) (xy 150.6982 -273.487134) (xy 150.6982 -273.574764) (xy 153.119086 -273.574764)
			(xy 153.123046 -273.52571) (xy 153.134823 -273.477926) (xy 153.154114 -273.43265) (xy 153.180417 -273.391054)
			(xy 153.213052 -273.354217) (xy 153.251173 -273.323092) (xy 153.293794 -273.298485) (xy 153.33981 -273.281033)
			(xy 153.388029 -273.271189) (xy 153.437204 -273.269208) (xy 153.486059 -273.27514) (xy 153.53333 -273.288832)
			(xy 153.577792 -273.30993) (xy 153.618295 -273.337886) (xy 153.653788 -273.371978) (xy 153.683353 -273.411322)
			(xy 153.706224 -273.454899) (xy 153.721808 -273.50158) (xy 153.729703 -273.550157) (xy 153.730198 -273.574764)
			(xy 153.729703 -273.599371) (xy 153.721808 -273.647948) (xy 153.706224 -273.694629) (xy 153.683353 -273.738206)
			(xy 153.653788 -273.77755) (xy 153.618295 -273.811642) (xy 153.577792 -273.839598) (xy 153.53333 -273.860696)
			(xy 153.486059 -273.874388) (xy 153.437204 -273.88032) (xy 153.388029 -273.878339) (xy 153.33981 -273.868495)
			(xy 153.293794 -273.851043) (xy 153.251173 -273.826436) (xy 153.213052 -273.795311) (xy 153.180417 -273.758474)
			(xy 153.154114 -273.716878) (xy 153.134823 -273.671602) (xy 153.123046 -273.623818) (xy 153.119086 -273.574764)
			(xy 150.6982 -273.574764) (xy 150.6982 -274.524724) (xy 153.119086 -274.524724) (xy 153.123046 -274.47567)
			(xy 153.134823 -274.427886) (xy 153.154114 -274.38261) (xy 153.180417 -274.341014) (xy 153.213052 -274.304177)
			(xy 153.251173 -274.273052) (xy 153.293794 -274.248445) (xy 153.33981 -274.230993) (xy 153.388029 -274.221149)
			(xy 153.437204 -274.219168) (xy 153.486059 -274.2251) (xy 153.53333 -274.238792) (xy 153.577792 -274.25989)
			(xy 153.618295 -274.287846) (xy 153.653788 -274.321938) (xy 153.683353 -274.361282) (xy 153.706224 -274.404859)
			(xy 153.721808 -274.45154) (xy 153.729703 -274.500117) (xy 153.730198 -274.524724) (xy 153.729703 -274.549331)
			(xy 153.721808 -274.597908) (xy 153.706224 -274.644589) (xy 153.683353 -274.688166) (xy 153.653788 -274.72751)
			(xy 153.618295 -274.761602) (xy 153.577792 -274.789558) (xy 153.53333 -274.810656) (xy 153.486059 -274.824348)
			(xy 153.437204 -274.83028) (xy 153.388029 -274.828299) (xy 153.33981 -274.818455) (xy 153.293794 -274.801003)
			(xy 153.251173 -274.776396) (xy 153.213052 -274.745271) (xy 153.180417 -274.708434) (xy 153.154114 -274.666838)
			(xy 153.134823 -274.621562) (xy 153.123046 -274.573778) (xy 153.119086 -274.524724) (xy 150.6982 -274.524724)
			(xy 150.6982 -275.474938) (xy 152.169126 -275.474938) (xy 152.173086 -275.425884) (xy 152.184863 -275.3781)
			(xy 152.204154 -275.332824) (xy 152.230457 -275.291228) (xy 152.263092 -275.254391) (xy 152.301213 -275.223266)
			(xy 152.343834 -275.198659) (xy 152.38985 -275.181207) (xy 152.438069 -275.171363) (xy 152.487244 -275.169382)
			(xy 152.536099 -275.175314) (xy 152.58337 -275.189006) (xy 152.627832 -275.210104) (xy 152.668335 -275.23806)
			(xy 152.703828 -275.272152) (xy 152.733393 -275.311496) (xy 152.756264 -275.355073) (xy 152.771848 -275.401754)
			(xy 152.779743 -275.450331) (xy 152.780238 -275.474938) (xy 153.119086 -275.474938) (xy 153.123046 -275.425884)
			(xy 153.134823 -275.3781) (xy 153.154114 -275.332824) (xy 153.180417 -275.291228) (xy 153.213052 -275.254391)
			(xy 153.251173 -275.223266) (xy 153.293794 -275.198659) (xy 153.33981 -275.181207) (xy 153.388029 -275.171363)
			(xy 153.437204 -275.169382) (xy 153.486059 -275.175314) (xy 153.53333 -275.189006) (xy 153.577792 -275.210104)
			(xy 153.618295 -275.23806) (xy 153.653788 -275.272152) (xy 153.683353 -275.311496) (xy 153.706224 -275.355073)
			(xy 153.721808 -275.401754) (xy 153.729703 -275.450331) (xy 153.730198 -275.474938) (xy 153.729703 -275.499545)
			(xy 153.721808 -275.548122) (xy 153.706224 -275.594803) (xy 153.683353 -275.63838) (xy 153.653788 -275.677724)
			(xy 153.618295 -275.711816) (xy 153.577792 -275.739772) (xy 153.53333 -275.76087) (xy 153.486059 -275.774562)
			(xy 153.437204 -275.780494) (xy 153.388029 -275.778513) (xy 153.33981 -275.768669) (xy 153.293794 -275.751217)
			(xy 153.251173 -275.72661) (xy 153.213052 -275.695485) (xy 153.180417 -275.658648) (xy 153.154114 -275.617052)
			(xy 153.134823 -275.571776) (xy 153.123046 -275.523992) (xy 153.119086 -275.474938) (xy 152.780238 -275.474938)
			(xy 152.779743 -275.499545) (xy 152.771848 -275.548122) (xy 152.756264 -275.594803) (xy 152.733393 -275.63838)
			(xy 152.703828 -275.677724) (xy 152.668335 -275.711816) (xy 152.627832 -275.739772) (xy 152.58337 -275.76087)
			(xy 152.536099 -275.774562) (xy 152.487244 -275.780494) (xy 152.438069 -275.778513) (xy 152.38985 -275.768669)
			(xy 152.343834 -275.751217) (xy 152.301213 -275.72661) (xy 152.263092 -275.695485) (xy 152.230457 -275.658648)
			(xy 152.204154 -275.617052) (xy 152.184863 -275.571776) (xy 152.173086 -275.523992) (xy 152.169126 -275.474938)
			(xy 150.6982 -275.474938) (xy 150.6982 -276.424898) (xy 152.169126 -276.424898) (xy 152.173086 -276.375844)
			(xy 152.184863 -276.32806) (xy 152.204154 -276.282784) (xy 152.230457 -276.241188) (xy 152.263092 -276.204351)
			(xy 152.301213 -276.173226) (xy 152.343834 -276.148619) (xy 152.38985 -276.131167) (xy 152.438069 -276.121323)
			(xy 152.487244 -276.119342) (xy 152.536099 -276.125274) (xy 152.58337 -276.138966) (xy 152.627832 -276.160064)
			(xy 152.668335 -276.18802) (xy 152.703828 -276.222112) (xy 152.733393 -276.261456) (xy 152.756264 -276.305033)
			(xy 152.771848 -276.351714) (xy 152.779743 -276.400291) (xy 152.780238 -276.424898) (xy 153.119086 -276.424898)
			(xy 153.123046 -276.375844) (xy 153.134823 -276.32806) (xy 153.154114 -276.282784) (xy 153.180417 -276.241188)
			(xy 153.213052 -276.204351) (xy 153.251173 -276.173226) (xy 153.293794 -276.148619) (xy 153.33981 -276.131167)
			(xy 153.388029 -276.121323) (xy 153.437204 -276.119342) (xy 153.486059 -276.125274) (xy 153.53333 -276.138966)
			(xy 153.577792 -276.160064) (xy 153.618295 -276.18802) (xy 153.653788 -276.222112) (xy 153.683353 -276.261456)
			(xy 153.706224 -276.305033) (xy 153.721808 -276.351714) (xy 153.729703 -276.400291) (xy 153.730198 -276.424898)
			(xy 153.729703 -276.449505) (xy 153.721808 -276.498082) (xy 153.706224 -276.544763) (xy 153.683353 -276.58834)
			(xy 153.653788 -276.627684) (xy 153.618295 -276.661776) (xy 153.577792 -276.689732) (xy 153.53333 -276.71083)
			(xy 153.486059 -276.724522) (xy 153.437204 -276.730454) (xy 153.388029 -276.728473) (xy 153.33981 -276.718629)
			(xy 153.293794 -276.701177) (xy 153.251173 -276.67657) (xy 153.213052 -276.645445) (xy 153.180417 -276.608608)
			(xy 153.154114 -276.567012) (xy 153.134823 -276.521736) (xy 153.123046 -276.473952) (xy 153.119086 -276.424898)
			(xy 152.780238 -276.424898) (xy 152.779743 -276.449505) (xy 152.771848 -276.498082) (xy 152.756264 -276.544763)
			(xy 152.733393 -276.58834) (xy 152.703828 -276.627684) (xy 152.668335 -276.661776) (xy 152.627832 -276.689732)
			(xy 152.58337 -276.71083) (xy 152.536099 -276.724522) (xy 152.487244 -276.730454) (xy 152.438069 -276.728473)
			(xy 152.38985 -276.718629) (xy 152.343834 -276.701177) (xy 152.301213 -276.67657) (xy 152.263092 -276.645445)
			(xy 152.230457 -276.608608) (xy 152.204154 -276.567012) (xy 152.184863 -276.521736) (xy 152.173086 -276.473952)
			(xy 152.169126 -276.424898) (xy 150.6982 -276.424898) (xy 150.6982 -277.374858) (xy 152.169126 -277.374858)
			(xy 152.173086 -277.325804) (xy 152.184863 -277.27802) (xy 152.204154 -277.232744) (xy 152.230457 -277.191148)
			(xy 152.263092 -277.154311) (xy 152.301213 -277.123186) (xy 152.343834 -277.098579) (xy 152.38985 -277.081127)
			(xy 152.438069 -277.071283) (xy 152.487244 -277.069302) (xy 152.536099 -277.075234) (xy 152.58337 -277.088926)
			(xy 152.627832 -277.110024) (xy 152.668335 -277.13798) (xy 152.703828 -277.172072) (xy 152.733393 -277.211416)
			(xy 152.756264 -277.254993) (xy 152.771848 -277.301674) (xy 152.779743 -277.350251) (xy 152.780238 -277.374858)
			(xy 153.119086 -277.374858) (xy 153.123046 -277.325804) (xy 153.134823 -277.27802) (xy 153.154114 -277.232744)
			(xy 153.180417 -277.191148) (xy 153.213052 -277.154311) (xy 153.251173 -277.123186) (xy 153.293794 -277.098579)
			(xy 153.33981 -277.081127) (xy 153.388029 -277.071283) (xy 153.437204 -277.069302) (xy 153.486059 -277.075234)
			(xy 153.53333 -277.088926) (xy 153.577792 -277.110024) (xy 153.618295 -277.13798) (xy 153.653788 -277.172072)
			(xy 153.683353 -277.211416) (xy 153.706224 -277.254993) (xy 153.721808 -277.301674) (xy 153.729703 -277.350251)
			(xy 153.730198 -277.374858) (xy 153.729703 -277.399465) (xy 153.721808 -277.448042) (xy 153.706224 -277.494723)
			(xy 153.683353 -277.5383) (xy 153.653788 -277.577644) (xy 153.618295 -277.611736) (xy 153.577792 -277.639692)
			(xy 153.53333 -277.66079) (xy 153.486059 -277.674482) (xy 153.437204 -277.680414) (xy 153.388029 -277.678433)
			(xy 153.33981 -277.668589) (xy 153.293794 -277.651137) (xy 153.251173 -277.62653) (xy 153.213052 -277.595405)
			(xy 153.180417 -277.558568) (xy 153.154114 -277.516972) (xy 153.134823 -277.471696) (xy 153.123046 -277.423912)
			(xy 153.119086 -277.374858) (xy 152.780238 -277.374858) (xy 152.779743 -277.399465) (xy 152.771848 -277.448042)
			(xy 152.756264 -277.494723) (xy 152.733393 -277.5383) (xy 152.703828 -277.577644) (xy 152.668335 -277.611736)
			(xy 152.627832 -277.639692) (xy 152.58337 -277.66079) (xy 152.536099 -277.674482) (xy 152.487244 -277.680414)
			(xy 152.438069 -277.678433) (xy 152.38985 -277.668589) (xy 152.343834 -277.651137) (xy 152.301213 -277.62653)
			(xy 152.263092 -277.595405) (xy 152.230457 -277.558568) (xy 152.204154 -277.516972) (xy 152.184863 -277.471696)
			(xy 152.173086 -277.423912) (xy 152.169126 -277.374858) (xy 150.6982 -277.374858) (xy 150.6982 -278.324818)
			(xy 152.169126 -278.324818) (xy 152.173086 -278.275764) (xy 152.184863 -278.22798) (xy 152.204154 -278.182704)
			(xy 152.230457 -278.141108) (xy 152.263092 -278.104271) (xy 152.301213 -278.073146) (xy 152.343834 -278.048539)
			(xy 152.38985 -278.031087) (xy 152.438069 -278.021243) (xy 152.487244 -278.019262) (xy 152.536099 -278.025194)
			(xy 152.58337 -278.038886) (xy 152.627832 -278.059984) (xy 152.668335 -278.08794) (xy 152.703828 -278.122032)
			(xy 152.733393 -278.161376) (xy 152.756264 -278.204953) (xy 152.771848 -278.251634) (xy 152.779743 -278.300211)
			(xy 152.780238 -278.324818) (xy 153.119086 -278.324818) (xy 153.123046 -278.275764) (xy 153.134823 -278.22798)
			(xy 153.154114 -278.182704) (xy 153.180417 -278.141108) (xy 153.213052 -278.104271) (xy 153.251173 -278.073146)
			(xy 153.293794 -278.048539) (xy 153.33981 -278.031087) (xy 153.388029 -278.021243) (xy 153.437204 -278.019262)
			(xy 153.486059 -278.025194) (xy 153.53333 -278.038886) (xy 153.577792 -278.059984) (xy 153.618295 -278.08794)
			(xy 153.653788 -278.122032) (xy 153.683353 -278.161376) (xy 153.706224 -278.204953) (xy 153.721808 -278.251634)
			(xy 153.729703 -278.300211) (xy 153.730198 -278.324818) (xy 153.729703 -278.349425) (xy 153.721808 -278.398002)
			(xy 153.706224 -278.444683) (xy 153.683353 -278.48826) (xy 153.653788 -278.527604) (xy 153.618295 -278.561696)
			(xy 153.577792 -278.589652) (xy 153.53333 -278.61075) (xy 153.486059 -278.624442) (xy 153.437204 -278.630374)
			(xy 153.388029 -278.628393) (xy 153.33981 -278.618549) (xy 153.293794 -278.601097) (xy 153.251173 -278.57649)
			(xy 153.213052 -278.545365) (xy 153.180417 -278.508528) (xy 153.154114 -278.466932) (xy 153.134823 -278.421656)
			(xy 153.123046 -278.373872) (xy 153.119086 -278.324818) (xy 152.780238 -278.324818) (xy 152.779743 -278.349425)
			(xy 152.771848 -278.398002) (xy 152.756264 -278.444683) (xy 152.733393 -278.48826) (xy 152.703828 -278.527604)
			(xy 152.668335 -278.561696) (xy 152.627832 -278.589652) (xy 152.58337 -278.61075) (xy 152.536099 -278.624442)
			(xy 152.487244 -278.630374) (xy 152.438069 -278.628393) (xy 152.38985 -278.618549) (xy 152.343834 -278.601097)
			(xy 152.301213 -278.57649) (xy 152.263092 -278.545365) (xy 152.230457 -278.508528) (xy 152.204154 -278.466932)
			(xy 152.184863 -278.421656) (xy 152.173086 -278.373872) (xy 152.169126 -278.324818) (xy 150.6982 -278.324818)
			(xy 150.6982 -279.274778) (xy 152.169126 -279.274778) (xy 152.173086 -279.225724) (xy 152.184863 -279.17794)
			(xy 152.204154 -279.132664) (xy 152.230457 -279.091068) (xy 152.263092 -279.054231) (xy 152.301213 -279.023106)
			(xy 152.343834 -278.998499) (xy 152.38985 -278.981047) (xy 152.438069 -278.971203) (xy 152.487244 -278.969222)
			(xy 152.536099 -278.975154) (xy 152.58337 -278.988846) (xy 152.627832 -279.009944) (xy 152.668335 -279.0379)
			(xy 152.703828 -279.071992) (xy 152.733393 -279.111336) (xy 152.756264 -279.154913) (xy 152.771848 -279.201594)
			(xy 152.779743 -279.250171) (xy 152.780238 -279.274778) (xy 153.119086 -279.274778) (xy 153.123046 -279.225724)
			(xy 153.134823 -279.17794) (xy 153.154114 -279.132664) (xy 153.180417 -279.091068) (xy 153.213052 -279.054231)
			(xy 153.251173 -279.023106) (xy 153.293794 -278.998499) (xy 153.33981 -278.981047) (xy 153.388029 -278.971203)
			(xy 153.437204 -278.969222) (xy 153.486059 -278.975154) (xy 153.53333 -278.988846) (xy 153.577792 -279.009944)
			(xy 153.618295 -279.0379) (xy 153.653788 -279.071992) (xy 153.683353 -279.111336) (xy 153.706224 -279.154913)
			(xy 153.721808 -279.201594) (xy 153.729703 -279.250171) (xy 153.730198 -279.274778) (xy 153.729703 -279.299385)
			(xy 153.721808 -279.347962) (xy 153.706224 -279.394643) (xy 153.683353 -279.43822) (xy 153.653788 -279.477564)
			(xy 153.618295 -279.511656) (xy 153.577792 -279.539612) (xy 153.53333 -279.56071) (xy 153.486059 -279.574402)
			(xy 153.437204 -279.580334) (xy 153.388029 -279.578353) (xy 153.33981 -279.568509) (xy 153.293794 -279.551057)
			(xy 153.251173 -279.52645) (xy 153.213052 -279.495325) (xy 153.180417 -279.458488) (xy 153.154114 -279.416892)
			(xy 153.134823 -279.371616) (xy 153.123046 -279.323832) (xy 153.119086 -279.274778) (xy 152.780238 -279.274778)
			(xy 152.779743 -279.299385) (xy 152.771848 -279.347962) (xy 152.756264 -279.394643) (xy 152.733393 -279.43822)
			(xy 152.703828 -279.477564) (xy 152.668335 -279.511656) (xy 152.627832 -279.539612) (xy 152.58337 -279.56071)
			(xy 152.536099 -279.574402) (xy 152.487244 -279.580334) (xy 152.438069 -279.578353) (xy 152.38985 -279.568509)
			(xy 152.343834 -279.551057) (xy 152.301213 -279.52645) (xy 152.263092 -279.495325) (xy 152.230457 -279.458488)
			(xy 152.204154 -279.416892) (xy 152.184863 -279.371616) (xy 152.173086 -279.323832) (xy 152.169126 -279.274778)
			(xy 150.6982 -279.274778) (xy 150.6982 -279.917906) (xy 150.698454 -279.917906) (xy 150.698454 -280.224738)
			(xy 152.169126 -280.224738) (xy 152.173086 -280.175684) (xy 152.184863 -280.1279) (xy 152.204154 -280.082624)
			(xy 152.230457 -280.041028) (xy 152.263092 -280.004191) (xy 152.301213 -279.973066) (xy 152.343834 -279.948459)
			(xy 152.38985 -279.931007) (xy 152.438069 -279.921163) (xy 152.487244 -279.919182) (xy 152.536099 -279.925114)
			(xy 152.58337 -279.938806) (xy 152.627832 -279.959904) (xy 152.668335 -279.98786) (xy 152.703828 -280.021952)
			(xy 152.733393 -280.061296) (xy 152.756264 -280.104873) (xy 152.771848 -280.151554) (xy 152.779743 -280.200131)
			(xy 152.780238 -280.224738) (xy 153.119086 -280.224738) (xy 153.123046 -280.175684) (xy 153.134823 -280.1279)
			(xy 153.154114 -280.082624) (xy 153.180417 -280.041028) (xy 153.213052 -280.004191) (xy 153.251173 -279.973066)
			(xy 153.293794 -279.948459) (xy 153.33981 -279.931007) (xy 153.388029 -279.921163) (xy 153.437204 -279.919182)
			(xy 153.486059 -279.925114) (xy 153.53333 -279.938806) (xy 153.577792 -279.959904) (xy 153.618295 -279.98786)
			(xy 153.653788 -280.021952) (xy 153.683353 -280.061296) (xy 153.706224 -280.104873) (xy 153.721808 -280.151554)
			(xy 153.729703 -280.200131) (xy 153.730198 -280.224738) (xy 153.729703 -280.249345) (xy 153.721808 -280.297922)
			(xy 153.706224 -280.344603) (xy 153.683353 -280.38818) (xy 153.653788 -280.427524) (xy 153.618295 -280.461616)
			(xy 153.577792 -280.489572) (xy 153.53333 -280.51067) (xy 153.486059 -280.524362) (xy 153.437204 -280.530294)
			(xy 153.388029 -280.528313) (xy 153.33981 -280.518469) (xy 153.293794 -280.501017) (xy 153.251173 -280.47641)
			(xy 153.213052 -280.445285) (xy 153.180417 -280.408448) (xy 153.154114 -280.366852) (xy 153.134823 -280.321576)
			(xy 153.123046 -280.273792) (xy 153.119086 -280.224738) (xy 152.780238 -280.224738) (xy 152.779743 -280.249345)
			(xy 152.771848 -280.297922) (xy 152.756264 -280.344603) (xy 152.733393 -280.38818) (xy 152.703828 -280.427524)
			(xy 152.668335 -280.461616) (xy 152.627832 -280.489572) (xy 152.58337 -280.51067) (xy 152.536099 -280.524362)
			(xy 152.487244 -280.530294) (xy 152.438069 -280.528313) (xy 152.38985 -280.518469) (xy 152.343834 -280.501017)
			(xy 152.301213 -280.47641) (xy 152.263092 -280.445285) (xy 152.230457 -280.408448) (xy 152.204154 -280.366852)
			(xy 152.184863 -280.321576) (xy 152.173086 -280.273792) (xy 152.169126 -280.224738) (xy 150.698454 -280.224738)
			(xy 150.698454 -281.174952) (xy 152.169126 -281.174952) (xy 152.173086 -281.125898) (xy 152.184863 -281.078114)
			(xy 152.204154 -281.032838) (xy 152.230457 -280.991242) (xy 152.263092 -280.954405) (xy 152.301213 -280.92328)
			(xy 152.343834 -280.898673) (xy 152.38985 -280.881221) (xy 152.438069 -280.871377) (xy 152.487244 -280.869396)
			(xy 152.536099 -280.875328) (xy 152.58337 -280.88902) (xy 152.627832 -280.910118) (xy 152.668335 -280.938074)
			(xy 152.703828 -280.972166) (xy 152.733393 -281.01151) (xy 152.756264 -281.055087) (xy 152.771848 -281.101768)
			(xy 152.779743 -281.150345) (xy 152.780238 -281.174952) (xy 153.119086 -281.174952) (xy 153.123046 -281.125898)
			(xy 153.134823 -281.078114) (xy 153.154114 -281.032838) (xy 153.180417 -280.991242) (xy 153.213052 -280.954405)
			(xy 153.251173 -280.92328) (xy 153.293794 -280.898673) (xy 153.33981 -280.881221) (xy 153.388029 -280.871377)
			(xy 153.437204 -280.869396) (xy 153.486059 -280.875328) (xy 153.53333 -280.88902) (xy 153.577792 -280.910118)
			(xy 153.618295 -280.938074) (xy 153.653788 -280.972166) (xy 153.683353 -281.01151) (xy 153.706224 -281.055087)
			(xy 153.721808 -281.101768) (xy 153.729703 -281.150345) (xy 153.730198 -281.174952) (xy 153.729703 -281.199559)
			(xy 153.721808 -281.248136) (xy 153.706224 -281.294817) (xy 153.683353 -281.338394) (xy 153.653788 -281.377738)
			(xy 153.618295 -281.41183) (xy 153.577792 -281.439786) (xy 153.53333 -281.460884) (xy 153.486059 -281.474576)
			(xy 153.437204 -281.480508) (xy 153.388029 -281.478527) (xy 153.33981 -281.468683) (xy 153.293794 -281.451231)
			(xy 153.251173 -281.426624) (xy 153.213052 -281.395499) (xy 153.180417 -281.358662) (xy 153.154114 -281.317066)
			(xy 153.134823 -281.27179) (xy 153.123046 -281.224006) (xy 153.119086 -281.174952) (xy 152.780238 -281.174952)
			(xy 152.779743 -281.199559) (xy 152.771848 -281.248136) (xy 152.756264 -281.294817) (xy 152.733393 -281.338394)
			(xy 152.703828 -281.377738) (xy 152.668335 -281.41183) (xy 152.627832 -281.439786) (xy 152.58337 -281.460884)
			(xy 152.536099 -281.474576) (xy 152.487244 -281.480508) (xy 152.438069 -281.478527) (xy 152.38985 -281.468683)
			(xy 152.343834 -281.451231) (xy 152.301213 -281.426624) (xy 152.263092 -281.395499) (xy 152.230457 -281.358662)
			(xy 152.204154 -281.317066) (xy 152.184863 -281.27179) (xy 152.173086 -281.224006) (xy 152.169126 -281.174952)
			(xy 150.698454 -281.174952) (xy 150.698454 -282.124912) (xy 152.169126 -282.124912) (xy 152.173086 -282.075858)
			(xy 152.184863 -282.028074) (xy 152.204154 -281.982798) (xy 152.230457 -281.941202) (xy 152.263092 -281.904365)
			(xy 152.301213 -281.87324) (xy 152.343834 -281.848633) (xy 152.38985 -281.831181) (xy 152.438069 -281.821337)
			(xy 152.487244 -281.819356) (xy 152.536099 -281.825288) (xy 152.58337 -281.83898) (xy 152.627832 -281.860078)
			(xy 152.668335 -281.888034) (xy 152.703828 -281.922126) (xy 152.733393 -281.96147) (xy 152.756264 -282.005047)
			(xy 152.771848 -282.051728) (xy 152.779743 -282.100305) (xy 152.780238 -282.124912) (xy 153.119086 -282.124912)
			(xy 153.123046 -282.075858) (xy 153.134823 -282.028074) (xy 153.154114 -281.982798) (xy 153.180417 -281.941202)
			(xy 153.213052 -281.904365) (xy 153.251173 -281.87324) (xy 153.293794 -281.848633) (xy 153.33981 -281.831181)
			(xy 153.388029 -281.821337) (xy 153.437204 -281.819356) (xy 153.486059 -281.825288) (xy 153.53333 -281.83898)
			(xy 153.577792 -281.860078) (xy 153.618295 -281.888034) (xy 153.653788 -281.922126) (xy 153.683353 -281.96147)
			(xy 153.706224 -282.005047) (xy 153.721808 -282.051728) (xy 153.729703 -282.100305) (xy 153.730198 -282.124912)
			(xy 153.729703 -282.149519) (xy 153.721808 -282.198096) (xy 153.706224 -282.244777) (xy 153.683353 -282.288354)
			(xy 153.653788 -282.327698) (xy 153.618295 -282.36179) (xy 153.577792 -282.389746) (xy 153.53333 -282.410844)
			(xy 153.486059 -282.424536) (xy 153.437204 -282.430468) (xy 153.388029 -282.428487) (xy 153.33981 -282.418643)
			(xy 153.293794 -282.401191) (xy 153.251173 -282.376584) (xy 153.213052 -282.345459) (xy 153.180417 -282.308622)
			(xy 153.154114 -282.267026) (xy 153.134823 -282.22175) (xy 153.123046 -282.173966) (xy 153.119086 -282.124912)
			(xy 152.780238 -282.124912) (xy 152.779743 -282.149519) (xy 152.771848 -282.198096) (xy 152.756264 -282.244777)
			(xy 152.733393 -282.288354) (xy 152.703828 -282.327698) (xy 152.668335 -282.36179) (xy 152.627832 -282.389746)
			(xy 152.58337 -282.410844) (xy 152.536099 -282.424536) (xy 152.487244 -282.430468) (xy 152.438069 -282.428487)
			(xy 152.38985 -282.418643) (xy 152.343834 -282.401191) (xy 152.301213 -282.376584) (xy 152.263092 -282.345459)
			(xy 152.230457 -282.308622) (xy 152.204154 -282.267026) (xy 152.184863 -282.22175) (xy 152.173086 -282.173966)
			(xy 152.169126 -282.124912) (xy 150.698454 -282.124912) (xy 150.698454 -283.074872) (xy 152.169126 -283.074872)
			(xy 152.173086 -283.025818) (xy 152.184863 -282.978034) (xy 152.204154 -282.932758) (xy 152.230457 -282.891162)
			(xy 152.263092 -282.854325) (xy 152.301213 -282.8232) (xy 152.343834 -282.798593) (xy 152.38985 -282.781141)
			(xy 152.438069 -282.771297) (xy 152.487244 -282.769316) (xy 152.536099 -282.775248) (xy 152.58337 -282.78894)
			(xy 152.627832 -282.810038) (xy 152.668335 -282.837994) (xy 152.703828 -282.872086) (xy 152.733393 -282.91143)
			(xy 152.756264 -282.955007) (xy 152.771848 -283.001688) (xy 152.779743 -283.050265) (xy 152.780238 -283.074872)
			(xy 153.119086 -283.074872) (xy 153.123046 -283.025818) (xy 153.134823 -282.978034) (xy 153.154114 -282.932758)
			(xy 153.180417 -282.891162) (xy 153.213052 -282.854325) (xy 153.251173 -282.8232) (xy 153.293794 -282.798593)
			(xy 153.33981 -282.781141) (xy 153.388029 -282.771297) (xy 153.437204 -282.769316) (xy 153.486059 -282.775248)
			(xy 153.53333 -282.78894) (xy 153.577792 -282.810038) (xy 153.618295 -282.837994) (xy 153.653788 -282.872086)
			(xy 153.683353 -282.91143) (xy 153.706224 -282.955007) (xy 153.721808 -283.001688) (xy 153.729703 -283.050265)
			(xy 153.730198 -283.074872) (xy 153.729703 -283.099479) (xy 153.721808 -283.148056) (xy 153.706224 -283.194737)
			(xy 153.683353 -283.238314) (xy 153.653788 -283.277658) (xy 153.618295 -283.31175) (xy 153.577792 -283.339706)
			(xy 153.53333 -283.360804) (xy 153.486059 -283.374496) (xy 153.437204 -283.380428) (xy 153.388029 -283.378447)
			(xy 153.33981 -283.368603) (xy 153.293794 -283.351151) (xy 153.251173 -283.326544) (xy 153.213052 -283.295419)
			(xy 153.180417 -283.258582) (xy 153.154114 -283.216986) (xy 153.134823 -283.17171) (xy 153.123046 -283.123926)
			(xy 153.119086 -283.074872) (xy 152.780238 -283.074872) (xy 152.779743 -283.099479) (xy 152.771848 -283.148056)
			(xy 152.756264 -283.194737) (xy 152.733393 -283.238314) (xy 152.703828 -283.277658) (xy 152.668335 -283.31175)
			(xy 152.627832 -283.339706) (xy 152.58337 -283.360804) (xy 152.536099 -283.374496) (xy 152.487244 -283.380428)
			(xy 152.438069 -283.378447) (xy 152.38985 -283.368603) (xy 152.343834 -283.351151) (xy 152.301213 -283.326544)
			(xy 152.263092 -283.295419) (xy 152.230457 -283.258582) (xy 152.204154 -283.216986) (xy 152.184863 -283.17171)
			(xy 152.173086 -283.123926) (xy 152.169126 -283.074872) (xy 150.698454 -283.074872) (xy 150.698454 -284.024832)
			(xy 152.169126 -284.024832) (xy 152.173086 -283.975778) (xy 152.184863 -283.927994) (xy 152.204154 -283.882718)
			(xy 152.230457 -283.841122) (xy 152.263092 -283.804285) (xy 152.301213 -283.77316) (xy 152.343834 -283.748553)
			(xy 152.38985 -283.731101) (xy 152.438069 -283.721257) (xy 152.487244 -283.719276) (xy 152.536099 -283.725208)
			(xy 152.58337 -283.7389) (xy 152.627832 -283.759998) (xy 152.668335 -283.787954) (xy 152.703828 -283.822046)
			(xy 152.733393 -283.86139) (xy 152.756264 -283.904967) (xy 152.771848 -283.951648) (xy 152.779743 -284.000225)
			(xy 152.780238 -284.024832) (xy 153.119086 -284.024832) (xy 153.123046 -283.975778) (xy 153.134823 -283.927994)
			(xy 153.154114 -283.882718) (xy 153.180417 -283.841122) (xy 153.213052 -283.804285) (xy 153.251173 -283.77316)
			(xy 153.293794 -283.748553) (xy 153.33981 -283.731101) (xy 153.388029 -283.721257) (xy 153.437204 -283.719276)
			(xy 153.486059 -283.725208) (xy 153.53333 -283.7389) (xy 153.577792 -283.759998) (xy 153.618295 -283.787954)
			(xy 153.653788 -283.822046) (xy 153.683353 -283.86139) (xy 153.706224 -283.904967) (xy 153.721808 -283.951648)
			(xy 153.729703 -284.000225) (xy 153.730198 -284.024832) (xy 153.729703 -284.049439) (xy 153.721808 -284.098016)
			(xy 153.706224 -284.144697) (xy 153.683353 -284.188274) (xy 153.653788 -284.227618) (xy 153.618295 -284.26171)
			(xy 153.577792 -284.289666) (xy 153.53333 -284.310764) (xy 153.486059 -284.324456) (xy 153.437204 -284.330388)
			(xy 153.388029 -284.328407) (xy 153.33981 -284.318563) (xy 153.293794 -284.301111) (xy 153.251173 -284.276504)
			(xy 153.213052 -284.245379) (xy 153.180417 -284.208542) (xy 153.154114 -284.166946) (xy 153.134823 -284.12167)
			(xy 153.123046 -284.073886) (xy 153.119086 -284.024832) (xy 152.780238 -284.024832) (xy 152.779743 -284.049439)
			(xy 152.771848 -284.098016) (xy 152.756264 -284.144697) (xy 152.733393 -284.188274) (xy 152.703828 -284.227618)
			(xy 152.668335 -284.26171) (xy 152.627832 -284.289666) (xy 152.58337 -284.310764) (xy 152.536099 -284.324456)
			(xy 152.487244 -284.330388) (xy 152.438069 -284.328407) (xy 152.38985 -284.318563) (xy 152.343834 -284.301111)
			(xy 152.301213 -284.276504) (xy 152.263092 -284.245379) (xy 152.230457 -284.208542) (xy 152.204154 -284.166946)
			(xy 152.184863 -284.12167) (xy 152.173086 -284.073886) (xy 152.169126 -284.024832) (xy 150.698454 -284.024832)
			(xy 150.698454 -284.974792) (xy 152.169126 -284.974792) (xy 152.173086 -284.925738) (xy 152.184863 -284.877954)
			(xy 152.204154 -284.832678) (xy 152.230457 -284.791082) (xy 152.263092 -284.754245) (xy 152.301213 -284.72312)
			(xy 152.343834 -284.698513) (xy 152.38985 -284.681061) (xy 152.438069 -284.671217) (xy 152.487244 -284.669236)
			(xy 152.536099 -284.675168) (xy 152.58337 -284.68886) (xy 152.627832 -284.709958) (xy 152.668335 -284.737914)
			(xy 152.703828 -284.772006) (xy 152.733393 -284.81135) (xy 152.756264 -284.854927) (xy 152.771848 -284.901608)
			(xy 152.779743 -284.950185) (xy 152.780238 -284.974792) (xy 153.119086 -284.974792) (xy 153.123046 -284.925738)
			(xy 153.134823 -284.877954) (xy 153.154114 -284.832678) (xy 153.180417 -284.791082) (xy 153.213052 -284.754245)
			(xy 153.251173 -284.72312) (xy 153.293794 -284.698513) (xy 153.33981 -284.681061) (xy 153.388029 -284.671217)
			(xy 153.437204 -284.669236) (xy 153.486059 -284.675168) (xy 153.53333 -284.68886) (xy 153.577792 -284.709958)
			(xy 153.618295 -284.737914) (xy 153.653788 -284.772006) (xy 153.683353 -284.81135) (xy 153.706224 -284.854927)
			(xy 153.721808 -284.901608) (xy 153.729703 -284.950185) (xy 153.730198 -284.974792) (xy 153.729703 -284.999399)
			(xy 153.721808 -285.047976) (xy 153.706224 -285.094657) (xy 153.683353 -285.138234) (xy 153.653788 -285.177578)
			(xy 153.618295 -285.21167) (xy 153.577792 -285.239626) (xy 153.53333 -285.260724) (xy 153.486059 -285.274416)
			(xy 153.437204 -285.280348) (xy 153.388029 -285.278367) (xy 153.33981 -285.268523) (xy 153.293794 -285.251071)
			(xy 153.251173 -285.226464) (xy 153.213052 -285.195339) (xy 153.180417 -285.158502) (xy 153.154114 -285.116906)
			(xy 153.134823 -285.07163) (xy 153.123046 -285.023846) (xy 153.119086 -284.974792) (xy 152.780238 -284.974792)
			(xy 152.779743 -284.999399) (xy 152.771848 -285.047976) (xy 152.756264 -285.094657) (xy 152.733393 -285.138234)
			(xy 152.703828 -285.177578) (xy 152.668335 -285.21167) (xy 152.627832 -285.239626) (xy 152.58337 -285.260724)
			(xy 152.536099 -285.274416) (xy 152.487244 -285.280348) (xy 152.438069 -285.278367) (xy 152.38985 -285.268523)
			(xy 152.343834 -285.251071) (xy 152.301213 -285.226464) (xy 152.263092 -285.195339) (xy 152.230457 -285.158502)
			(xy 152.204154 -285.116906) (xy 152.184863 -285.07163) (xy 152.173086 -285.023846) (xy 152.169126 -284.974792)
			(xy 150.698454 -284.974792) (xy 150.698454 -285.924752) (xy 152.169126 -285.924752) (xy 152.173086 -285.875698)
			(xy 152.184863 -285.827914) (xy 152.204154 -285.782638) (xy 152.230457 -285.741042) (xy 152.263092 -285.704205)
			(xy 152.301213 -285.67308) (xy 152.343834 -285.648473) (xy 152.38985 -285.631021) (xy 152.438069 -285.621177)
			(xy 152.487244 -285.619196) (xy 152.536099 -285.625128) (xy 152.58337 -285.63882) (xy 152.627832 -285.659918)
			(xy 152.668335 -285.687874) (xy 152.703828 -285.721966) (xy 152.733393 -285.76131) (xy 152.756264 -285.804887)
			(xy 152.771848 -285.851568) (xy 152.779743 -285.900145) (xy 152.780238 -285.924752) (xy 153.119086 -285.924752)
			(xy 153.123046 -285.875698) (xy 153.134823 -285.827914) (xy 153.154114 -285.782638) (xy 153.180417 -285.741042)
			(xy 153.213052 -285.704205) (xy 153.251173 -285.67308) (xy 153.293794 -285.648473) (xy 153.33981 -285.631021)
			(xy 153.388029 -285.621177) (xy 153.437204 -285.619196) (xy 153.486059 -285.625128) (xy 153.53333 -285.63882)
			(xy 153.577792 -285.659918) (xy 153.618295 -285.687874) (xy 153.653788 -285.721966) (xy 153.683353 -285.76131)
			(xy 153.706224 -285.804887) (xy 153.721808 -285.851568) (xy 153.729703 -285.900145) (xy 153.730198 -285.924752)
			(xy 153.729703 -285.949359) (xy 153.721808 -285.997936) (xy 153.706224 -286.044617) (xy 153.683353 -286.088194)
			(xy 153.653788 -286.127538) (xy 153.618295 -286.16163) (xy 153.577792 -286.189586) (xy 153.53333 -286.210684)
			(xy 153.486059 -286.224376) (xy 153.437204 -286.230308) (xy 153.388029 -286.228327) (xy 153.33981 -286.218483)
			(xy 153.293794 -286.201031) (xy 153.251173 -286.176424) (xy 153.213052 -286.145299) (xy 153.180417 -286.108462)
			(xy 153.154114 -286.066866) (xy 153.134823 -286.02159) (xy 153.123046 -285.973806) (xy 153.119086 -285.924752)
			(xy 152.780238 -285.924752) (xy 152.779743 -285.949359) (xy 152.771848 -285.997936) (xy 152.756264 -286.044617)
			(xy 152.733393 -286.088194) (xy 152.703828 -286.127538) (xy 152.668335 -286.16163) (xy 152.627832 -286.189586)
			(xy 152.58337 -286.210684) (xy 152.536099 -286.224376) (xy 152.487244 -286.230308) (xy 152.438069 -286.228327)
			(xy 152.38985 -286.218483) (xy 152.343834 -286.201031) (xy 152.301213 -286.176424) (xy 152.263092 -286.145299)
			(xy 152.230457 -286.108462) (xy 152.204154 -286.066866) (xy 152.184863 -286.02159) (xy 152.173086 -285.973806)
			(xy 152.169126 -285.924752) (xy 150.698454 -285.924752) (xy 150.698454 -286.874966) (xy 152.169126 -286.874966)
			(xy 152.173086 -286.825912) (xy 152.184863 -286.778128) (xy 152.204154 -286.732852) (xy 152.230457 -286.691256)
			(xy 152.263092 -286.654419) (xy 152.301213 -286.623294) (xy 152.343834 -286.598687) (xy 152.38985 -286.581235)
			(xy 152.438069 -286.571391) (xy 152.487244 -286.56941) (xy 152.536099 -286.575342) (xy 152.58337 -286.589034)
			(xy 152.627832 -286.610132) (xy 152.668335 -286.638088) (xy 152.703828 -286.67218) (xy 152.733393 -286.711524)
			(xy 152.756264 -286.755101) (xy 152.771848 -286.801782) (xy 152.779743 -286.850359) (xy 152.780238 -286.874966)
			(xy 153.119086 -286.874966) (xy 153.123046 -286.825912) (xy 153.134823 -286.778128) (xy 153.154114 -286.732852)
			(xy 153.180417 -286.691256) (xy 153.213052 -286.654419) (xy 153.251173 -286.623294) (xy 153.293794 -286.598687)
			(xy 153.33981 -286.581235) (xy 153.388029 -286.571391) (xy 153.437204 -286.56941) (xy 153.486059 -286.575342)
			(xy 153.53333 -286.589034) (xy 153.577792 -286.610132) (xy 153.618295 -286.638088) (xy 153.653788 -286.67218)
			(xy 153.683353 -286.711524) (xy 153.706224 -286.755101) (xy 153.721808 -286.801782) (xy 153.729703 -286.850359)
			(xy 153.730198 -286.874966) (xy 153.729703 -286.899573) (xy 153.721808 -286.94815) (xy 153.706224 -286.994831)
			(xy 153.683353 -287.038408) (xy 153.653788 -287.077752) (xy 153.618295 -287.111844) (xy 153.577792 -287.1398)
			(xy 153.53333 -287.160898) (xy 153.486059 -287.17459) (xy 153.437204 -287.180522) (xy 153.388029 -287.178541)
			(xy 153.33981 -287.168697) (xy 153.293794 -287.151245) (xy 153.251173 -287.126638) (xy 153.213052 -287.095513)
			(xy 153.180417 -287.058676) (xy 153.154114 -287.01708) (xy 153.134823 -286.971804) (xy 153.123046 -286.92402)
			(xy 153.119086 -286.874966) (xy 152.780238 -286.874966) (xy 152.779743 -286.899573) (xy 152.771848 -286.94815)
			(xy 152.756264 -286.994831) (xy 152.733393 -287.038408) (xy 152.703828 -287.077752) (xy 152.668335 -287.111844)
			(xy 152.627832 -287.1398) (xy 152.58337 -287.160898) (xy 152.536099 -287.17459) (xy 152.487244 -287.180522)
			(xy 152.438069 -287.178541) (xy 152.38985 -287.168697) (xy 152.343834 -287.151245) (xy 152.301213 -287.126638)
			(xy 152.263092 -287.095513) (xy 152.230457 -287.058676) (xy 152.204154 -287.01708) (xy 152.184863 -286.971804)
			(xy 152.173086 -286.92402) (xy 152.169126 -286.874966) (xy 150.698454 -286.874966) (xy 150.698454 -287.824926)
			(xy 152.169126 -287.824926) (xy 152.173086 -287.775872) (xy 152.184863 -287.728088) (xy 152.204154 -287.682812)
			(xy 152.230457 -287.641216) (xy 152.263092 -287.604379) (xy 152.301213 -287.573254) (xy 152.343834 -287.548647)
			(xy 152.38985 -287.531195) (xy 152.438069 -287.521351) (xy 152.487244 -287.51937) (xy 152.536099 -287.525302)
			(xy 152.58337 -287.538994) (xy 152.627832 -287.560092) (xy 152.668335 -287.588048) (xy 152.703828 -287.62214)
			(xy 152.733393 -287.661484) (xy 152.756264 -287.705061) (xy 152.771848 -287.751742) (xy 152.779743 -287.800319)
			(xy 152.780238 -287.824926) (xy 153.119086 -287.824926) (xy 153.123046 -287.775872) (xy 153.134823 -287.728088)
			(xy 153.154114 -287.682812) (xy 153.180417 -287.641216) (xy 153.213052 -287.604379) (xy 153.251173 -287.573254)
			(xy 153.293794 -287.548647) (xy 153.33981 -287.531195) (xy 153.388029 -287.521351) (xy 153.437204 -287.51937)
			(xy 153.486059 -287.525302) (xy 153.53333 -287.538994) (xy 153.577792 -287.560092) (xy 153.618295 -287.588048)
			(xy 153.653788 -287.62214) (xy 153.683353 -287.661484) (xy 153.706224 -287.705061) (xy 153.721808 -287.751742)
			(xy 153.729703 -287.800319) (xy 153.730198 -287.824926) (xy 154.0693 -287.824926) (xy 154.07326 -287.775872)
			(xy 154.085037 -287.728088) (xy 154.104328 -287.682812) (xy 154.130631 -287.641216) (xy 154.163266 -287.604379)
			(xy 154.201387 -287.573254) (xy 154.244008 -287.548647) (xy 154.290024 -287.531195) (xy 154.338243 -287.521351)
			(xy 154.387418 -287.51937) (xy 154.436273 -287.525302) (xy 154.483544 -287.538994) (xy 154.528006 -287.560092)
			(xy 154.568509 -287.588048) (xy 154.604002 -287.62214) (xy 154.633567 -287.661484) (xy 154.656438 -287.705061)
			(xy 154.672022 -287.751742) (xy 154.679917 -287.800319) (xy 154.680412 -287.824926) (xy 154.679917 -287.849533)
			(xy 154.672022 -287.89811) (xy 154.656438 -287.944791) (xy 154.633567 -287.988368) (xy 154.604002 -288.027712)
			(xy 154.568509 -288.061804) (xy 154.528006 -288.08976) (xy 154.483544 -288.110858) (xy 154.436273 -288.12455)
			(xy 154.387418 -288.130482) (xy 154.338243 -288.128501) (xy 154.290024 -288.118657) (xy 154.244008 -288.101205)
			(xy 154.201387 -288.076598) (xy 154.163266 -288.045473) (xy 154.130631 -288.008636) (xy 154.104328 -287.96704)
			(xy 154.085037 -287.921764) (xy 154.07326 -287.87398) (xy 154.0693 -287.824926) (xy 153.730198 -287.824926)
			(xy 153.729703 -287.849533) (xy 153.721808 -287.89811) (xy 153.706224 -287.944791) (xy 153.683353 -287.988368)
			(xy 153.653788 -288.027712) (xy 153.618295 -288.061804) (xy 153.577792 -288.08976) (xy 153.53333 -288.110858)
			(xy 153.486059 -288.12455) (xy 153.437204 -288.130482) (xy 153.388029 -288.128501) (xy 153.33981 -288.118657)
			(xy 153.293794 -288.101205) (xy 153.251173 -288.076598) (xy 153.213052 -288.045473) (xy 153.180417 -288.008636)
			(xy 153.154114 -287.96704) (xy 153.134823 -287.921764) (xy 153.123046 -287.87398) (xy 153.119086 -287.824926)
			(xy 152.780238 -287.824926) (xy 152.779743 -287.849533) (xy 152.771848 -287.89811) (xy 152.756264 -287.944791)
			(xy 152.733393 -287.988368) (xy 152.703828 -288.027712) (xy 152.668335 -288.061804) (xy 152.627832 -288.08976)
			(xy 152.58337 -288.110858) (xy 152.536099 -288.12455) (xy 152.487244 -288.130482) (xy 152.438069 -288.128501)
			(xy 152.38985 -288.118657) (xy 152.343834 -288.101205) (xy 152.301213 -288.076598) (xy 152.263092 -288.045473)
			(xy 152.230457 -288.008636) (xy 152.204154 -287.96704) (xy 152.184863 -287.921764) (xy 152.173086 -287.87398)
			(xy 152.169126 -287.824926) (xy 150.698454 -287.824926) (xy 150.698454 -288.774886) (xy 152.169126 -288.774886)
			(xy 152.173086 -288.725832) (xy 152.184863 -288.678048) (xy 152.204154 -288.632772) (xy 152.230457 -288.591176)
			(xy 152.263092 -288.554339) (xy 152.301213 -288.523214) (xy 152.343834 -288.498607) (xy 152.38985 -288.481155)
			(xy 152.438069 -288.471311) (xy 152.487244 -288.46933) (xy 152.536099 -288.475262) (xy 152.58337 -288.488954)
			(xy 152.627832 -288.510052) (xy 152.668335 -288.538008) (xy 152.703828 -288.5721) (xy 152.733393 -288.611444)
			(xy 152.756264 -288.655021) (xy 152.771848 -288.701702) (xy 152.779743 -288.750279) (xy 152.780238 -288.774886)
			(xy 153.119086 -288.774886) (xy 153.123046 -288.725832) (xy 153.134823 -288.678048) (xy 153.154114 -288.632772)
			(xy 153.180417 -288.591176) (xy 153.213052 -288.554339) (xy 153.251173 -288.523214) (xy 153.293794 -288.498607)
			(xy 153.33981 -288.481155) (xy 153.388029 -288.471311) (xy 153.437204 -288.46933) (xy 153.486059 -288.475262)
			(xy 153.53333 -288.488954) (xy 153.577792 -288.510052) (xy 153.618295 -288.538008) (xy 153.653788 -288.5721)
			(xy 153.683353 -288.611444) (xy 153.706224 -288.655021) (xy 153.721808 -288.701702) (xy 153.729703 -288.750279)
			(xy 153.730198 -288.774886) (xy 154.0693 -288.774886) (xy 154.07326 -288.725832) (xy 154.085037 -288.678048)
			(xy 154.104328 -288.632772) (xy 154.130631 -288.591176) (xy 154.163266 -288.554339) (xy 154.201387 -288.523214)
			(xy 154.244008 -288.498607) (xy 154.290024 -288.481155) (xy 154.338243 -288.471311) (xy 154.387418 -288.46933)
			(xy 154.436273 -288.475262) (xy 154.483544 -288.488954) (xy 154.528006 -288.510052) (xy 154.568509 -288.538008)
			(xy 154.604002 -288.5721) (xy 154.633567 -288.611444) (xy 154.656438 -288.655021) (xy 154.672022 -288.701702)
			(xy 154.679917 -288.750279) (xy 154.680412 -288.774886) (xy 155.01926 -288.774886) (xy 155.02322 -288.725832)
			(xy 155.034997 -288.678048) (xy 155.054288 -288.632772) (xy 155.080591 -288.591176) (xy 155.113226 -288.554339)
			(xy 155.151347 -288.523214) (xy 155.193968 -288.498607) (xy 155.239984 -288.481155) (xy 155.288203 -288.471311)
			(xy 155.337378 -288.46933) (xy 155.386233 -288.475262) (xy 155.433504 -288.488954) (xy 155.477966 -288.510052)
			(xy 155.518469 -288.538008) (xy 155.553962 -288.5721) (xy 155.583527 -288.611444) (xy 155.606398 -288.655021)
			(xy 155.621982 -288.701702) (xy 155.629877 -288.750279) (xy 155.630372 -288.774886) (xy 155.629877 -288.799493)
			(xy 155.621982 -288.84807) (xy 155.606398 -288.894751) (xy 155.583527 -288.938328) (xy 155.553962 -288.977672)
			(xy 155.518469 -289.011764) (xy 155.477966 -289.03972) (xy 155.433504 -289.060818) (xy 155.386233 -289.07451)
			(xy 155.337378 -289.080442) (xy 155.288203 -289.078461) (xy 155.239984 -289.068617) (xy 155.193968 -289.051165)
			(xy 155.151347 -289.026558) (xy 155.113226 -288.995433) (xy 155.080591 -288.958596) (xy 155.054288 -288.917)
			(xy 155.034997 -288.871724) (xy 155.02322 -288.82394) (xy 155.01926 -288.774886) (xy 154.680412 -288.774886)
			(xy 154.679917 -288.799493) (xy 154.672022 -288.84807) (xy 154.656438 -288.894751) (xy 154.633567 -288.938328)
			(xy 154.604002 -288.977672) (xy 154.568509 -289.011764) (xy 154.528006 -289.03972) (xy 154.483544 -289.060818)
			(xy 154.436273 -289.07451) (xy 154.387418 -289.080442) (xy 154.338243 -289.078461) (xy 154.290024 -289.068617)
			(xy 154.244008 -289.051165) (xy 154.201387 -289.026558) (xy 154.163266 -288.995433) (xy 154.130631 -288.958596)
			(xy 154.104328 -288.917) (xy 154.085037 -288.871724) (xy 154.07326 -288.82394) (xy 154.0693 -288.774886)
			(xy 153.730198 -288.774886) (xy 153.729703 -288.799493) (xy 153.721808 -288.84807) (xy 153.706224 -288.894751)
			(xy 153.683353 -288.938328) (xy 153.653788 -288.977672) (xy 153.618295 -289.011764) (xy 153.577792 -289.03972)
			(xy 153.53333 -289.060818) (xy 153.486059 -289.07451) (xy 153.437204 -289.080442) (xy 153.388029 -289.078461)
			(xy 153.33981 -289.068617) (xy 153.293794 -289.051165) (xy 153.251173 -289.026558) (xy 153.213052 -288.995433)
			(xy 153.180417 -288.958596) (xy 153.154114 -288.917) (xy 153.134823 -288.871724) (xy 153.123046 -288.82394)
			(xy 153.119086 -288.774886) (xy 152.780238 -288.774886) (xy 152.779743 -288.799493) (xy 152.771848 -288.84807)
			(xy 152.756264 -288.894751) (xy 152.733393 -288.938328) (xy 152.703828 -288.977672) (xy 152.668335 -289.011764)
			(xy 152.627832 -289.03972) (xy 152.58337 -289.060818) (xy 152.536099 -289.07451) (xy 152.487244 -289.080442)
			(xy 152.438069 -289.078461) (xy 152.38985 -289.068617) (xy 152.343834 -289.051165) (xy 152.301213 -289.026558)
			(xy 152.263092 -288.995433) (xy 152.230457 -288.958596) (xy 152.204154 -288.917) (xy 152.184863 -288.871724)
			(xy 152.173086 -288.82394) (xy 152.169126 -288.774886) (xy 150.698454 -288.774886) (xy 150.698454 -289.1028)
			(xy 150.698879 -289.112869) (xy 150.706599 -289.131468) (xy 150.71344 -289.138868) (xy 151.299418 -289.724846)
			(xy 152.169126 -289.724846) (xy 152.173086 -289.675792) (xy 152.184863 -289.628008) (xy 152.204154 -289.582732)
			(xy 152.230457 -289.541136) (xy 152.263092 -289.504299) (xy 152.301213 -289.473174) (xy 152.343834 -289.448567)
			(xy 152.38985 -289.431115) (xy 152.438069 -289.421271) (xy 152.487244 -289.41929) (xy 152.536099 -289.425222)
			(xy 152.58337 -289.438914) (xy 152.627832 -289.460012) (xy 152.668335 -289.487968) (xy 152.703828 -289.52206)
			(xy 152.733393 -289.561404) (xy 152.756264 -289.604981) (xy 152.771848 -289.651662) (xy 152.779743 -289.700239)
			(xy 152.780238 -289.724846) (xy 153.119086 -289.724846) (xy 153.123046 -289.675792) (xy 153.134823 -289.628008)
			(xy 153.154114 -289.582732) (xy 153.180417 -289.541136) (xy 153.213052 -289.504299) (xy 153.251173 -289.473174)
			(xy 153.293794 -289.448567) (xy 153.33981 -289.431115) (xy 153.388029 -289.421271) (xy 153.437204 -289.41929)
			(xy 153.486059 -289.425222) (xy 153.53333 -289.438914) (xy 153.577792 -289.460012) (xy 153.618295 -289.487968)
			(xy 153.653788 -289.52206) (xy 153.683353 -289.561404) (xy 153.706224 -289.604981) (xy 153.721808 -289.651662)
			(xy 153.729703 -289.700239) (xy 153.730198 -289.724846) (xy 154.0693 -289.724846) (xy 154.07326 -289.675792)
			(xy 154.085037 -289.628008) (xy 154.104328 -289.582732) (xy 154.130631 -289.541136) (xy 154.163266 -289.504299)
			(xy 154.201387 -289.473174) (xy 154.244008 -289.448567) (xy 154.290024 -289.431115) (xy 154.338243 -289.421271)
			(xy 154.387418 -289.41929) (xy 154.436273 -289.425222) (xy 154.483544 -289.438914) (xy 154.528006 -289.460012)
			(xy 154.568509 -289.487968) (xy 154.604002 -289.52206) (xy 154.633567 -289.561404) (xy 154.656438 -289.604981)
			(xy 154.672022 -289.651662) (xy 154.679917 -289.700239) (xy 154.680412 -289.724846) (xy 155.01926 -289.724846)
			(xy 155.02322 -289.675792) (xy 155.034997 -289.628008) (xy 155.054288 -289.582732) (xy 155.080591 -289.541136)
			(xy 155.113226 -289.504299) (xy 155.151347 -289.473174) (xy 155.193968 -289.448567) (xy 155.239984 -289.431115)
			(xy 155.288203 -289.421271) (xy 155.337378 -289.41929) (xy 155.386233 -289.425222) (xy 155.433504 -289.438914)
			(xy 155.477966 -289.460012) (xy 155.518469 -289.487968) (xy 155.553962 -289.52206) (xy 155.583527 -289.561404)
			(xy 155.606398 -289.604981) (xy 155.621982 -289.651662) (xy 155.629877 -289.700239) (xy 155.630372 -289.724846)
			(xy 155.96922 -289.724846) (xy 155.97318 -289.675792) (xy 155.984957 -289.628008) (xy 156.004248 -289.582732)
			(xy 156.030551 -289.541136) (xy 156.063186 -289.504299) (xy 156.101307 -289.473174) (xy 156.143928 -289.448567)
			(xy 156.189944 -289.431115) (xy 156.238163 -289.421271) (xy 156.287338 -289.41929) (xy 156.336193 -289.425222)
			(xy 156.383464 -289.438914) (xy 156.427926 -289.460012) (xy 156.468429 -289.487968) (xy 156.503922 -289.52206)
			(xy 156.533487 -289.561404) (xy 156.556358 -289.604981) (xy 156.571942 -289.651662) (xy 156.579837 -289.700239)
			(xy 156.580332 -289.724846) (xy 156.579837 -289.749453) (xy 156.571942 -289.79803) (xy 156.556358 -289.844711)
			(xy 156.533487 -289.888288) (xy 156.503922 -289.927632) (xy 156.468429 -289.961724) (xy 156.427926 -289.98968)
			(xy 156.383464 -290.010778) (xy 156.336193 -290.02447) (xy 156.287338 -290.030402) (xy 156.238163 -290.028421)
			(xy 156.189944 -290.018577) (xy 156.143928 -290.001125) (xy 156.101307 -289.976518) (xy 156.063186 -289.945393)
			(xy 156.030551 -289.908556) (xy 156.004248 -289.86696) (xy 155.984957 -289.821684) (xy 155.97318 -289.7739)
			(xy 155.96922 -289.724846) (xy 155.630372 -289.724846) (xy 155.629877 -289.749453) (xy 155.621982 -289.79803)
			(xy 155.606398 -289.844711) (xy 155.583527 -289.888288) (xy 155.553962 -289.927632) (xy 155.518469 -289.961724)
			(xy 155.477966 -289.98968) (xy 155.433504 -290.010778) (xy 155.386233 -290.02447) (xy 155.337378 -290.030402)
			(xy 155.288203 -290.028421) (xy 155.239984 -290.018577) (xy 155.193968 -290.001125) (xy 155.151347 -289.976518)
			(xy 155.113226 -289.945393) (xy 155.080591 -289.908556) (xy 155.054288 -289.86696) (xy 155.034997 -289.821684)
			(xy 155.02322 -289.7739) (xy 155.01926 -289.724846) (xy 154.680412 -289.724846) (xy 154.679917 -289.749453)
			(xy 154.672022 -289.79803) (xy 154.656438 -289.844711) (xy 154.633567 -289.888288) (xy 154.604002 -289.927632)
			(xy 154.568509 -289.961724) (xy 154.528006 -289.98968) (xy 154.483544 -290.010778) (xy 154.436273 -290.02447)
			(xy 154.387418 -290.030402) (xy 154.338243 -290.028421) (xy 154.290024 -290.018577) (xy 154.244008 -290.001125)
			(xy 154.201387 -289.976518) (xy 154.163266 -289.945393) (xy 154.130631 -289.908556) (xy 154.104328 -289.86696)
			(xy 154.085037 -289.821684) (xy 154.07326 -289.7739) (xy 154.0693 -289.724846) (xy 153.730198 -289.724846)
			(xy 153.729703 -289.749453) (xy 153.721808 -289.79803) (xy 153.706224 -289.844711) (xy 153.683353 -289.888288)
			(xy 153.653788 -289.927632) (xy 153.618295 -289.961724) (xy 153.577792 -289.98968) (xy 153.53333 -290.010778)
			(xy 153.486059 -290.02447) (xy 153.437204 -290.030402) (xy 153.388029 -290.028421) (xy 153.33981 -290.018577)
			(xy 153.293794 -290.001125) (xy 153.251173 -289.976518) (xy 153.213052 -289.945393) (xy 153.180417 -289.908556)
			(xy 153.154114 -289.86696) (xy 153.134823 -289.821684) (xy 153.123046 -289.7739) (xy 153.119086 -289.724846)
			(xy 152.780238 -289.724846) (xy 152.779743 -289.749453) (xy 152.771848 -289.79803) (xy 152.756264 -289.844711)
			(xy 152.733393 -289.888288) (xy 152.703828 -289.927632) (xy 152.668335 -289.961724) (xy 152.627832 -289.98968)
			(xy 152.58337 -290.010778) (xy 152.536099 -290.02447) (xy 152.487244 -290.030402) (xy 152.438069 -290.028421)
			(xy 152.38985 -290.018577) (xy 152.343834 -290.001125) (xy 152.301213 -289.976518) (xy 152.263092 -289.945393)
			(xy 152.230457 -289.908556) (xy 152.204154 -289.86696) (xy 152.184863 -289.821684) (xy 152.173086 -289.7739)
			(xy 152.169126 -289.724846) (xy 151.299418 -289.724846) (xy 152.067006 -290.492434) (xy 152.087326 -290.500054)
			(xy 152.098502 -290.499292) (xy 152.185878 -290.49345) (xy 152.205182 -290.483036) (xy 152.211786 -290.4744)
			(xy 152.227553 -290.454523) (xy 152.26411 -290.419347) (xy 152.305604 -290.390158) (xy 152.351065 -290.36764)
			(xy 152.399429 -290.35232) (xy 152.449564 -290.344556) (xy 152.47493 -290.344098) (xy 152.500915 -290.34461)
			(xy 152.552246 -290.352744) (xy 152.601672 -290.368808) (xy 152.647977 -290.392405) (xy 152.690021 -290.422956)
			(xy 152.726768 -290.459707) (xy 152.757313 -290.501754) (xy 152.780906 -290.548061) (xy 152.796964 -290.597489)
			(xy 152.805093 -290.64882) (xy 152.805638 -290.674806) (xy 153.119086 -290.674806) (xy 153.123046 -290.625752)
			(xy 153.134823 -290.577968) (xy 153.154114 -290.532692) (xy 153.180417 -290.491096) (xy 153.213052 -290.454259)
			(xy 153.251173 -290.423134) (xy 153.293794 -290.398527) (xy 153.33981 -290.381075) (xy 153.388029 -290.371231)
			(xy 153.437204 -290.36925) (xy 153.486059 -290.375182) (xy 153.53333 -290.388874) (xy 153.577792 -290.409972)
			(xy 153.618295 -290.437928) (xy 153.653788 -290.47202) (xy 153.683353 -290.511364) (xy 153.706224 -290.554941)
			(xy 153.721808 -290.601622) (xy 153.729703 -290.650199) (xy 153.730198 -290.674806) (xy 154.0693 -290.674806)
			(xy 154.07326 -290.625752) (xy 154.085037 -290.577968) (xy 154.104328 -290.532692) (xy 154.130631 -290.491096)
			(xy 154.163266 -290.454259) (xy 154.201387 -290.423134) (xy 154.244008 -290.398527) (xy 154.290024 -290.381075)
			(xy 154.338243 -290.371231) (xy 154.387418 -290.36925) (xy 154.436273 -290.375182) (xy 154.483544 -290.388874)
			(xy 154.528006 -290.409972) (xy 154.568509 -290.437928) (xy 154.604002 -290.47202) (xy 154.633567 -290.511364)
			(xy 154.656438 -290.554941) (xy 154.672022 -290.601622) (xy 154.679917 -290.650199) (xy 154.680412 -290.674806)
			(xy 156.91918 -290.674806) (xy 156.92314 -290.625752) (xy 156.934917 -290.577968) (xy 156.954208 -290.532692)
			(xy 156.980511 -290.491096) (xy 157.013146 -290.454259) (xy 157.051267 -290.423134) (xy 157.093888 -290.398527)
			(xy 157.139904 -290.381075) (xy 157.188123 -290.371231) (xy 157.237298 -290.36925) (xy 157.286153 -290.375182)
			(xy 157.333424 -290.388874) (xy 157.377886 -290.409972) (xy 157.418389 -290.437928) (xy 157.453882 -290.47202)
			(xy 157.483447 -290.511364) (xy 157.506318 -290.554941) (xy 157.521902 -290.601622) (xy 157.529797 -290.650199)
			(xy 157.530292 -290.674806) (xy 157.529797 -290.699413) (xy 157.521902 -290.74799) (xy 157.506318 -290.794671)
			(xy 157.483447 -290.838248) (xy 157.453882 -290.877592) (xy 157.418389 -290.911684) (xy 157.377886 -290.93964)
			(xy 157.333424 -290.960738) (xy 157.286153 -290.97443) (xy 157.237298 -290.980362) (xy 157.188123 -290.978381)
			(xy 157.139904 -290.968537) (xy 157.093888 -290.951085) (xy 157.051267 -290.926478) (xy 157.013146 -290.895353)
			(xy 156.980511 -290.858516) (xy 156.954208 -290.81692) (xy 156.934917 -290.771644) (xy 156.92314 -290.72386)
			(xy 156.91918 -290.674806) (xy 154.680412 -290.674806) (xy 154.679917 -290.699413) (xy 154.672022 -290.74799)
			(xy 154.656438 -290.794671) (xy 154.633567 -290.838248) (xy 154.604002 -290.877592) (xy 154.568509 -290.911684)
			(xy 154.528006 -290.93964) (xy 154.483544 -290.960738) (xy 154.436273 -290.97443) (xy 154.387418 -290.980362)
			(xy 154.338243 -290.978381) (xy 154.290024 -290.968537) (xy 154.244008 -290.951085) (xy 154.201387 -290.926478)
			(xy 154.163266 -290.895353) (xy 154.130631 -290.858516) (xy 154.104328 -290.81692) (xy 154.085037 -290.771644)
			(xy 154.07326 -290.72386) (xy 154.0693 -290.674806) (xy 153.730198 -290.674806) (xy 153.729703 -290.699413)
			(xy 153.721808 -290.74799) (xy 153.706224 -290.794671) (xy 153.683353 -290.838248) (xy 153.653788 -290.877592)
			(xy 153.618295 -290.911684) (xy 153.577792 -290.93964) (xy 153.53333 -290.960738) (xy 153.486059 -290.97443)
			(xy 153.437204 -290.980362) (xy 153.388029 -290.978381) (xy 153.33981 -290.968537) (xy 153.293794 -290.951085)
			(xy 153.251173 -290.926478) (xy 153.213052 -290.895353) (xy 153.180417 -290.858516) (xy 153.154114 -290.81692)
			(xy 153.134823 -290.771644) (xy 153.123046 -290.72386) (xy 153.119086 -290.674806) (xy 152.805638 -290.674806)
			(xy 152.805184 -290.700176) (xy 152.797449 -290.750323) (xy 152.782146 -290.7987) (xy 152.759633 -290.844172)
			(xy 152.730441 -290.885673) (xy 152.695252 -290.922228) (xy 152.675336 -290.93795) (xy 152.6667 -290.944554)
			(xy 152.656286 -290.963858) (xy 152.650444 -291.051234) (xy 152.649682 -291.06241) (xy 152.657302 -291.08273)
			(xy 153.016966 -291.442394) (xy 153.037286 -291.450014) (xy 153.048462 -291.449252) (xy 153.135838 -291.44341)
			(xy 153.155142 -291.432996) (xy 153.161746 -291.42436) (xy 153.177516 -291.404489) (xy 153.214076 -291.369323)
			(xy 153.255572 -291.340145) (xy 153.301033 -291.317638) (xy 153.349395 -291.302328) (xy 153.399526 -291.294575)
			(xy 153.42489 -291.294058) (xy 153.450879 -291.294567) (xy 153.502216 -291.302696) (xy 153.55165 -291.318756)
			(xy 153.597964 -291.34235) (xy 153.640016 -291.372899) (xy 153.676772 -291.40965) (xy 153.707327 -291.451699)
			(xy 153.730928 -291.498009) (xy 153.746994 -291.547441) (xy 153.75513 -291.598777) (xy 153.755598 -291.624766)
			(xy 154.0693 -291.624766) (xy 154.07326 -291.575712) (xy 154.085037 -291.527928) (xy 154.104328 -291.482652)
			(xy 154.130631 -291.441056) (xy 154.163266 -291.404219) (xy 154.201387 -291.373094) (xy 154.244008 -291.348487)
			(xy 154.290024 -291.331035) (xy 154.338243 -291.321191) (xy 154.387418 -291.31921) (xy 154.436273 -291.325142)
			(xy 154.483544 -291.338834) (xy 154.528006 -291.359932) (xy 154.568509 -291.387888) (xy 154.604002 -291.42198)
			(xy 154.633567 -291.461324) (xy 154.656438 -291.504901) (xy 154.672022 -291.551582) (xy 154.679917 -291.600159)
			(xy 154.680412 -291.624766) (xy 156.91918 -291.624766) (xy 156.92314 -291.575712) (xy 156.934917 -291.527928)
			(xy 156.954208 -291.482652) (xy 156.980511 -291.441056) (xy 157.013146 -291.404219) (xy 157.051267 -291.373094)
			(xy 157.093888 -291.348487) (xy 157.139904 -291.331035) (xy 157.188123 -291.321191) (xy 157.237298 -291.31921)
			(xy 157.286153 -291.325142) (xy 157.333424 -291.338834) (xy 157.377886 -291.359932) (xy 157.418389 -291.387888)
			(xy 157.453882 -291.42198) (xy 157.483447 -291.461324) (xy 157.506318 -291.504901) (xy 157.521902 -291.551582)
			(xy 157.529797 -291.600159) (xy 157.530292 -291.624766) (xy 157.86914 -291.624766) (xy 157.8731 -291.575712)
			(xy 157.884877 -291.527928) (xy 157.904168 -291.482652) (xy 157.930471 -291.441056) (xy 157.963106 -291.404219)
			(xy 158.001227 -291.373094) (xy 158.043848 -291.348487) (xy 158.089864 -291.331035) (xy 158.138083 -291.321191)
			(xy 158.187258 -291.31921) (xy 158.236113 -291.325142) (xy 158.283384 -291.338834) (xy 158.327846 -291.359932)
			(xy 158.368349 -291.387888) (xy 158.403842 -291.42198) (xy 158.433407 -291.461324) (xy 158.456278 -291.504901)
			(xy 158.471862 -291.551582) (xy 158.479757 -291.600159) (xy 158.480252 -291.624766) (xy 158.479757 -291.649373)
			(xy 158.471862 -291.69795) (xy 158.456278 -291.744631) (xy 158.433407 -291.788208) (xy 158.403842 -291.827552)
			(xy 158.368349 -291.861644) (xy 158.327846 -291.8896) (xy 158.283384 -291.910698) (xy 158.236113 -291.92439)
			(xy 158.187258 -291.930322) (xy 158.138083 -291.928341) (xy 158.089864 -291.918497) (xy 158.043848 -291.901045)
			(xy 158.001227 -291.876438) (xy 157.963106 -291.845313) (xy 157.930471 -291.808476) (xy 157.904168 -291.76688)
			(xy 157.884877 -291.721604) (xy 157.8731 -291.67382) (xy 157.86914 -291.624766) (xy 157.530292 -291.624766)
			(xy 157.529797 -291.649373) (xy 157.521902 -291.69795) (xy 157.506318 -291.744631) (xy 157.483447 -291.788208)
			(xy 157.453882 -291.827552) (xy 157.418389 -291.861644) (xy 157.377886 -291.8896) (xy 157.333424 -291.910698)
			(xy 157.286153 -291.92439) (xy 157.237298 -291.930322) (xy 157.188123 -291.928341) (xy 157.139904 -291.918497)
			(xy 157.093888 -291.901045) (xy 157.051267 -291.876438) (xy 157.013146 -291.845313) (xy 156.980511 -291.808476)
			(xy 156.954208 -291.76688) (xy 156.934917 -291.721604) (xy 156.92314 -291.67382) (xy 156.91918 -291.624766)
			(xy 154.680412 -291.624766) (xy 154.679917 -291.649373) (xy 154.672022 -291.69795) (xy 154.656438 -291.744631)
			(xy 154.633567 -291.788208) (xy 154.604002 -291.827552) (xy 154.568509 -291.861644) (xy 154.528006 -291.8896)
			(xy 154.483544 -291.910698) (xy 154.436273 -291.92439) (xy 154.387418 -291.930322) (xy 154.338243 -291.928341)
			(xy 154.290024 -291.918497) (xy 154.244008 -291.901045) (xy 154.201387 -291.876438) (xy 154.163266 -291.845313)
			(xy 154.130631 -291.808476) (xy 154.104328 -291.76688) (xy 154.085037 -291.721604) (xy 154.07326 -291.67382)
			(xy 154.0693 -291.624766) (xy 153.755598 -291.624766) (xy 153.755139 -291.650135) (xy 153.747397 -291.700278)
			(xy 153.73209 -291.74865) (xy 153.709576 -291.794119) (xy 153.680383 -291.835616) (xy 153.645196 -291.872169)
			(xy 153.625296 -291.88791) (xy 153.61666 -291.894514) (xy 153.606246 -291.913818) (xy 153.600404 -292.001194)
			(xy 153.599642 -292.01237) (xy 153.607262 -292.03269) (xy 153.96718 -292.392608) (xy 153.9875 -292.400228)
			(xy 153.998676 -292.399466) (xy 154.086052 -292.393624) (xy 154.105356 -292.38321) (xy 154.11196 -292.374574)
			(xy 154.127729 -292.354703) (xy 154.164289 -292.319537) (xy 154.205786 -292.29036) (xy 154.251247 -292.267854)
			(xy 154.299609 -292.252545) (xy 154.349741 -292.244793) (xy 154.375104 -292.244272) (xy 154.401092 -292.244782)
			(xy 154.452427 -292.252913) (xy 154.501858 -292.268974) (xy 154.548168 -292.29257) (xy 154.590218 -292.323119)
			(xy 154.626971 -292.35987) (xy 154.657522 -292.401918) (xy 154.68112 -292.448227) (xy 154.697183 -292.497658)
			(xy 154.705317 -292.548992) (xy 154.705807 -292.574726) (xy 155.01926 -292.574726) (xy 155.02322 -292.525672)
			(xy 155.034997 -292.477888) (xy 155.054288 -292.432612) (xy 155.080591 -292.391016) (xy 155.113226 -292.354179)
			(xy 155.151347 -292.323054) (xy 155.193968 -292.298447) (xy 155.239984 -292.280995) (xy 155.288203 -292.271151)
			(xy 155.337378 -292.26917) (xy 155.386233 -292.275102) (xy 155.433504 -292.288794) (xy 155.477966 -292.309892)
			(xy 155.518469 -292.337848) (xy 155.553962 -292.37194) (xy 155.583527 -292.411284) (xy 155.606398 -292.454861)
			(xy 155.621982 -292.501542) (xy 155.629877 -292.550119) (xy 155.630372 -292.574726) (xy 155.96922 -292.574726)
			(xy 155.97318 -292.525672) (xy 155.984957 -292.477888) (xy 156.004248 -292.432612) (xy 156.030551 -292.391016)
			(xy 156.063186 -292.354179) (xy 156.101307 -292.323054) (xy 156.143928 -292.298447) (xy 156.189944 -292.280995)
			(xy 156.238163 -292.271151) (xy 156.287338 -292.26917) (xy 156.336193 -292.275102) (xy 156.383464 -292.288794)
			(xy 156.427926 -292.309892) (xy 156.468429 -292.337848) (xy 156.503922 -292.37194) (xy 156.533487 -292.411284)
			(xy 156.556358 -292.454861) (xy 156.571942 -292.501542) (xy 156.579837 -292.550119) (xy 156.580332 -292.574726)
			(xy 156.580327 -292.57498) (xy 156.91918 -292.57498) (xy 156.92314 -292.525926) (xy 156.934917 -292.478142)
			(xy 156.954208 -292.432866) (xy 156.980511 -292.39127) (xy 157.013146 -292.354433) (xy 157.051267 -292.323308)
			(xy 157.093888 -292.298701) (xy 157.139904 -292.281249) (xy 157.188123 -292.271405) (xy 157.237298 -292.269424)
			(xy 157.286153 -292.275356) (xy 157.333424 -292.289048) (xy 157.377886 -292.310146) (xy 157.418389 -292.338102)
			(xy 157.453882 -292.372194) (xy 157.483447 -292.411538) (xy 157.506318 -292.455115) (xy 157.521902 -292.501796)
			(xy 157.529797 -292.550373) (xy 157.530292 -292.57498) (xy 157.529797 -292.599587) (xy 157.529465 -292.601629)
			(xy 157.819334 -292.601629) (xy 157.819334 -292.548331) (xy 157.827277 -292.495627) (xy 157.842987 -292.444697)
			(xy 157.866113 -292.396676) (xy 157.896137 -292.352639) (xy 157.932389 -292.313568) (xy 157.97406 -292.280337)
			(xy 158.020218 -292.253688) (xy 158.069832 -292.234216) (xy 158.121794 -292.222356) (xy 158.174944 -292.218373)
			(xy 158.228094 -292.222356) (xy 158.280056 -292.234216) (xy 158.32967 -292.253688) (xy 158.375828 -292.280337)
			(xy 158.417499 -292.313568) (xy 158.453751 -292.352639) (xy 158.483775 -292.396676) (xy 158.506901 -292.444697)
			(xy 158.522611 -292.495627) (xy 158.530554 -292.548331) (xy 158.531052 -292.57498) (xy 158.8191 -292.57498)
			(xy 158.82306 -292.525926) (xy 158.834837 -292.478142) (xy 158.854128 -292.432866) (xy 158.880431 -292.39127)
			(xy 158.913066 -292.354433) (xy 158.951187 -292.323308) (xy 158.993808 -292.298701) (xy 159.039824 -292.281249)
			(xy 159.088043 -292.271405) (xy 159.137218 -292.269424) (xy 159.186073 -292.275356) (xy 159.233344 -292.289048)
			(xy 159.277806 -292.310146) (xy 159.318309 -292.338102) (xy 159.353802 -292.372194) (xy 159.383367 -292.411538)
			(xy 159.406238 -292.455115) (xy 159.421822 -292.501796) (xy 159.429717 -292.550373) (xy 159.430212 -292.57498)
			(xy 159.429717 -292.599587) (xy 159.421822 -292.648164) (xy 159.406238 -292.694845) (xy 159.383367 -292.738422)
			(xy 159.353802 -292.777766) (xy 159.318309 -292.811858) (xy 159.277806 -292.839814) (xy 159.233344 -292.860912)
			(xy 159.186073 -292.874604) (xy 159.137218 -292.880536) (xy 159.088043 -292.878555) (xy 159.039824 -292.868711)
			(xy 158.993808 -292.851259) (xy 158.951187 -292.826652) (xy 158.913066 -292.795527) (xy 158.880431 -292.75869)
			(xy 158.854128 -292.717094) (xy 158.834837 -292.671818) (xy 158.82306 -292.624034) (xy 158.8191 -292.57498)
			(xy 158.531052 -292.57498) (xy 158.530554 -292.601629) (xy 158.522611 -292.654333) (xy 158.506901 -292.705263)
			(xy 158.483775 -292.753284) (xy 158.453751 -292.797321) (xy 158.417499 -292.836392) (xy 158.375828 -292.869623)
			(xy 158.32967 -292.896272) (xy 158.280056 -292.915744) (xy 158.228094 -292.927604) (xy 158.174944 -292.931588)
			(xy 158.121794 -292.927604) (xy 158.069832 -292.915744) (xy 158.020218 -292.896272) (xy 157.97406 -292.869623)
			(xy 157.932389 -292.836392) (xy 157.896137 -292.797321) (xy 157.866113 -292.753284) (xy 157.842987 -292.705263)
			(xy 157.827277 -292.654333) (xy 157.819334 -292.601629) (xy 157.529465 -292.601629) (xy 157.521902 -292.648164)
			(xy 157.506318 -292.694845) (xy 157.483447 -292.738422) (xy 157.453882 -292.777766) (xy 157.418389 -292.811858)
			(xy 157.377886 -292.839814) (xy 157.333424 -292.860912) (xy 157.286153 -292.874604) (xy 157.237298 -292.880536)
			(xy 157.188123 -292.878555) (xy 157.139904 -292.868711) (xy 157.093888 -292.851259) (xy 157.051267 -292.826652)
			(xy 157.013146 -292.795527) (xy 156.980511 -292.75869) (xy 156.954208 -292.717094) (xy 156.934917 -292.671818)
			(xy 156.92314 -292.624034) (xy 156.91918 -292.57498) (xy 156.580327 -292.57498) (xy 156.579837 -292.599333)
			(xy 156.571942 -292.64791) (xy 156.556358 -292.694591) (xy 156.533487 -292.738168) (xy 156.503922 -292.777512)
			(xy 156.468429 -292.811604) (xy 156.427926 -292.83956) (xy 156.383464 -292.860658) (xy 156.336193 -292.87435)
			(xy 156.287338 -292.880282) (xy 156.238163 -292.878301) (xy 156.189944 -292.868457) (xy 156.143928 -292.851005)
			(xy 156.101307 -292.826398) (xy 156.063186 -292.795273) (xy 156.030551 -292.758436) (xy 156.004248 -292.71684)
			(xy 155.984957 -292.671564) (xy 155.97318 -292.62378) (xy 155.96922 -292.574726) (xy 155.630372 -292.574726)
			(xy 155.629877 -292.599333) (xy 155.621982 -292.64791) (xy 155.606398 -292.694591) (xy 155.583527 -292.738168)
			(xy 155.553962 -292.777512) (xy 155.518469 -292.811604) (xy 155.477966 -292.83956) (xy 155.433504 -292.860658)
			(xy 155.386233 -292.87435) (xy 155.337378 -292.880282) (xy 155.288203 -292.878301) (xy 155.239984 -292.868457)
			(xy 155.193968 -292.851005) (xy 155.151347 -292.826398) (xy 155.113226 -292.795273) (xy 155.080591 -292.758436)
			(xy 155.054288 -292.71684) (xy 155.034997 -292.671564) (xy 155.02322 -292.62378) (xy 155.01926 -292.574726)
			(xy 154.705807 -292.574726) (xy 154.705812 -292.57498) (xy 154.705352 -292.600348) (xy 154.697609 -292.65049)
			(xy 154.6823 -292.698862) (xy 154.659785 -292.74433) (xy 154.630593 -292.785826) (xy 154.595406 -292.822379)
			(xy 154.57551 -292.838124) (xy 154.566874 -292.844728) (xy 154.55646 -292.864032) (xy 154.550618 -292.951408)
			(xy 154.549856 -292.962584) (xy 154.557476 -292.982904) (xy 154.91714 -293.342568) (xy 154.93746 -293.350188)
			(xy 154.948636 -293.349426) (xy 155.036012 -293.343584) (xy 155.055316 -293.33317) (xy 155.06192 -293.324534)
			(xy 155.077687 -293.304657) (xy 155.114243 -293.269481) (xy 155.155738 -293.240294) (xy 155.201199 -293.217778)
			(xy 155.249563 -293.202461) (xy 155.299698 -293.194701) (xy 155.325064 -293.194232) (xy 155.351054 -293.194712)
			(xy 155.402395 -293.202839) (xy 155.451831 -293.218899) (xy 155.498147 -293.242496) (xy 155.5402 -293.273048)
			(xy 155.576955 -293.309803) (xy 155.607507 -293.351857) (xy 155.631102 -293.398172) (xy 155.647161 -293.447609)
			(xy 155.655288 -293.49895) (xy 155.655772 -293.52494) (xy 155.96922 -293.52494) (xy 155.97318 -293.475886)
			(xy 155.984957 -293.428102) (xy 156.004248 -293.382826) (xy 156.030551 -293.34123) (xy 156.063186 -293.304393)
			(xy 156.101307 -293.273268) (xy 156.143928 -293.248661) (xy 156.189944 -293.231209) (xy 156.238163 -293.221365)
			(xy 156.287338 -293.219384) (xy 156.336193 -293.225316) (xy 156.383464 -293.239008) (xy 156.427926 -293.260106)
			(xy 156.468429 -293.288062) (xy 156.503922 -293.322154) (xy 156.533487 -293.361498) (xy 156.556358 -293.405075)
			(xy 156.571942 -293.451756) (xy 156.579837 -293.500333) (xy 156.580332 -293.52494) (xy 156.91918 -293.52494)
			(xy 156.92314 -293.475886) (xy 156.934917 -293.428102) (xy 156.954208 -293.382826) (xy 156.980511 -293.34123)
			(xy 157.013146 -293.304393) (xy 157.051267 -293.273268) (xy 157.093888 -293.248661) (xy 157.139904 -293.231209)
			(xy 157.188123 -293.221365) (xy 157.237298 -293.219384) (xy 157.286153 -293.225316) (xy 157.333424 -293.239008)
			(xy 157.377886 -293.260106) (xy 157.418389 -293.288062) (xy 157.453882 -293.322154) (xy 157.483447 -293.361498)
			(xy 157.506318 -293.405075) (xy 157.521902 -293.451756) (xy 157.529797 -293.500333) (xy 157.530292 -293.52494)
			(xy 157.86914 -293.52494) (xy 157.8731 -293.475886) (xy 157.884877 -293.428102) (xy 157.904168 -293.382826)
			(xy 157.930471 -293.34123) (xy 157.963106 -293.304393) (xy 158.001227 -293.273268) (xy 158.043848 -293.248661)
			(xy 158.089864 -293.231209) (xy 158.138083 -293.221365) (xy 158.187258 -293.219384) (xy 158.236113 -293.225316)
			(xy 158.283384 -293.239008) (xy 158.327846 -293.260106) (xy 158.368349 -293.288062) (xy 158.403842 -293.322154)
			(xy 158.433407 -293.361498) (xy 158.456278 -293.405075) (xy 158.471862 -293.451756) (xy 158.479757 -293.500333)
			(xy 158.480252 -293.52494) (xy 158.479757 -293.549547) (xy 158.479425 -293.551589) (xy 158.769294 -293.551589)
			(xy 158.769294 -293.498291) (xy 158.777237 -293.445587) (xy 158.792947 -293.394657) (xy 158.816073 -293.346636)
			(xy 158.846097 -293.302599) (xy 158.882349 -293.263528) (xy 158.92402 -293.230297) (xy 158.970178 -293.203648)
			(xy 159.019792 -293.184176) (xy 159.071754 -293.172316) (xy 159.124904 -293.168333) (xy 159.178054 -293.172316)
			(xy 159.230016 -293.184176) (xy 159.27963 -293.203648) (xy 159.325788 -293.230297) (xy 159.367459 -293.263528)
			(xy 159.403711 -293.302599) (xy 159.433735 -293.346636) (xy 159.456861 -293.394657) (xy 159.472571 -293.445587)
			(xy 159.480514 -293.498291) (xy 159.481012 -293.52494) (xy 159.76906 -293.52494) (xy 159.77302 -293.475886)
			(xy 159.784797 -293.428102) (xy 159.804088 -293.382826) (xy 159.830391 -293.34123) (xy 159.863026 -293.304393)
			(xy 159.901147 -293.273268) (xy 159.943768 -293.248661) (xy 159.989784 -293.231209) (xy 160.038003 -293.221365)
			(xy 160.087178 -293.219384) (xy 160.136033 -293.225316) (xy 160.183304 -293.239008) (xy 160.227766 -293.260106)
			(xy 160.268269 -293.288062) (xy 160.303762 -293.322154) (xy 160.333327 -293.361498) (xy 160.356198 -293.405075)
			(xy 160.371782 -293.451756) (xy 160.379677 -293.500333) (xy 160.380172 -293.52494) (xy 160.379677 -293.549547)
			(xy 160.371782 -293.598124) (xy 160.356198 -293.644805) (xy 160.333327 -293.688382) (xy 160.303762 -293.727726)
			(xy 160.268269 -293.761818) (xy 160.227766 -293.789774) (xy 160.183304 -293.810872) (xy 160.136033 -293.824564)
			(xy 160.087178 -293.830496) (xy 160.038003 -293.828515) (xy 159.989784 -293.818671) (xy 159.943768 -293.801219)
			(xy 159.901147 -293.776612) (xy 159.863026 -293.745487) (xy 159.830391 -293.70865) (xy 159.804088 -293.667054)
			(xy 159.784797 -293.621778) (xy 159.77302 -293.573994) (xy 159.76906 -293.52494) (xy 159.481012 -293.52494)
			(xy 159.480514 -293.551589) (xy 159.472571 -293.604293) (xy 159.456861 -293.655223) (xy 159.433735 -293.703244)
			(xy 159.403711 -293.747281) (xy 159.367459 -293.786352) (xy 159.325788 -293.819583) (xy 159.27963 -293.846232)
			(xy 159.230016 -293.865704) (xy 159.178054 -293.877564) (xy 159.124904 -293.881548) (xy 159.071754 -293.877564)
			(xy 159.019792 -293.865704) (xy 158.970178 -293.846232) (xy 158.92402 -293.819583) (xy 158.882349 -293.786352)
			(xy 158.846097 -293.747281) (xy 158.816073 -293.703244) (xy 158.792947 -293.655223) (xy 158.777237 -293.604293)
			(xy 158.769294 -293.551589) (xy 158.479425 -293.551589) (xy 158.471862 -293.598124) (xy 158.456278 -293.644805)
			(xy 158.433407 -293.688382) (xy 158.403842 -293.727726) (xy 158.368349 -293.761818) (xy 158.327846 -293.789774)
			(xy 158.283384 -293.810872) (xy 158.236113 -293.824564) (xy 158.187258 -293.830496) (xy 158.138083 -293.828515)
			(xy 158.089864 -293.818671) (xy 158.043848 -293.801219) (xy 158.001227 -293.776612) (xy 157.963106 -293.745487)
			(xy 157.930471 -293.70865) (xy 157.904168 -293.667054) (xy 157.884877 -293.621778) (xy 157.8731 -293.573994)
			(xy 157.86914 -293.52494) (xy 157.530292 -293.52494) (xy 157.529797 -293.549547) (xy 157.521902 -293.598124)
			(xy 157.506318 -293.644805) (xy 157.483447 -293.688382) (xy 157.453882 -293.727726) (xy 157.418389 -293.761818)
			(xy 157.377886 -293.789774) (xy 157.333424 -293.810872) (xy 157.286153 -293.824564) (xy 157.237298 -293.830496)
			(xy 157.188123 -293.828515) (xy 157.139904 -293.818671) (xy 157.093888 -293.801219) (xy 157.051267 -293.776612)
			(xy 157.013146 -293.745487) (xy 156.980511 -293.70865) (xy 156.954208 -293.667054) (xy 156.934917 -293.621778)
			(xy 156.92314 -293.573994) (xy 156.91918 -293.52494) (xy 156.580332 -293.52494) (xy 156.579837 -293.549547)
			(xy 156.571942 -293.598124) (xy 156.556358 -293.644805) (xy 156.533487 -293.688382) (xy 156.503922 -293.727726)
			(xy 156.468429 -293.761818) (xy 156.427926 -293.789774) (xy 156.383464 -293.810872) (xy 156.336193 -293.824564)
			(xy 156.287338 -293.830496) (xy 156.238163 -293.828515) (xy 156.189944 -293.818671) (xy 156.143928 -293.801219)
			(xy 156.101307 -293.776612) (xy 156.063186 -293.745487) (xy 156.030551 -293.70865) (xy 156.004248 -293.667054)
			(xy 155.984957 -293.621778) (xy 155.97318 -293.573994) (xy 155.96922 -293.52494) (xy 155.655772 -293.52494)
			(xy 155.655315 -293.550309) (xy 155.647576 -293.600454) (xy 155.632271 -293.648829) (xy 155.609757 -293.694299)
			(xy 155.580565 -293.735797) (xy 155.545377 -293.772352) (xy 155.52547 -293.788084) (xy 155.516834 -293.794688)
			(xy 155.50642 -293.813992) (xy 155.500578 -293.901368) (xy 155.499816 -293.912544) (xy 155.507436 -293.932864)
			(xy 156.049472 -294.4749) (xy 156.91918 -294.4749) (xy 156.92314 -294.425846) (xy 156.934917 -294.378062)
			(xy 156.954208 -294.332786) (xy 156.980511 -294.29119) (xy 157.013146 -294.254353) (xy 157.051267 -294.223228)
			(xy 157.093888 -294.198621) (xy 157.139904 -294.181169) (xy 157.188123 -294.171325) (xy 157.237298 -294.169344)
			(xy 157.286153 -294.175276) (xy 157.333424 -294.188968) (xy 157.377886 -294.210066) (xy 157.418389 -294.238022)
			(xy 157.453882 -294.272114) (xy 157.483447 -294.311458) (xy 157.506318 -294.355035) (xy 157.521902 -294.401716)
			(xy 157.529797 -294.450293) (xy 157.530292 -294.4749) (xy 157.529797 -294.499507) (xy 157.529465 -294.501549)
			(xy 157.819334 -294.501549) (xy 157.819334 -294.448251) (xy 157.827277 -294.395547) (xy 157.842987 -294.344617)
			(xy 157.866113 -294.296596) (xy 157.896137 -294.252559) (xy 157.932389 -294.213488) (xy 157.97406 -294.180257)
			(xy 158.020218 -294.153608) (xy 158.069832 -294.134136) (xy 158.121794 -294.122276) (xy 158.174944 -294.118293)
			(xy 158.228094 -294.122276) (xy 158.280056 -294.134136) (xy 158.32967 -294.153608) (xy 158.375828 -294.180257)
			(xy 158.417499 -294.213488) (xy 158.453751 -294.252559) (xy 158.483775 -294.296596) (xy 158.506901 -294.344617)
			(xy 158.522611 -294.395547) (xy 158.530554 -294.448251) (xy 158.531052 -294.4749) (xy 158.8191 -294.4749)
			(xy 158.82306 -294.425846) (xy 158.834837 -294.378062) (xy 158.854128 -294.332786) (xy 158.880431 -294.29119)
			(xy 158.913066 -294.254353) (xy 158.951187 -294.223228) (xy 158.993808 -294.198621) (xy 159.039824 -294.181169)
			(xy 159.088043 -294.171325) (xy 159.137218 -294.169344) (xy 159.186073 -294.175276) (xy 159.233344 -294.188968)
			(xy 159.277806 -294.210066) (xy 159.318309 -294.238022) (xy 159.353802 -294.272114) (xy 159.383367 -294.311458)
			(xy 159.406238 -294.355035) (xy 159.421822 -294.401716) (xy 159.429717 -294.450293) (xy 159.430212 -294.4749)
			(xy 159.76906 -294.4749) (xy 159.77302 -294.425846) (xy 159.784797 -294.378062) (xy 159.804088 -294.332786)
			(xy 159.830391 -294.29119) (xy 159.863026 -294.254353) (xy 159.901147 -294.223228) (xy 159.943768 -294.198621)
			(xy 159.989784 -294.181169) (xy 160.038003 -294.171325) (xy 160.087178 -294.169344) (xy 160.136033 -294.175276)
			(xy 160.183304 -294.188968) (xy 160.227766 -294.210066) (xy 160.268269 -294.238022) (xy 160.303762 -294.272114)
			(xy 160.333327 -294.311458) (xy 160.356198 -294.355035) (xy 160.371782 -294.401716) (xy 160.379677 -294.450293)
			(xy 160.380172 -294.4749) (xy 160.719274 -294.4749) (xy 160.723234 -294.425846) (xy 160.735011 -294.378062)
			(xy 160.754302 -294.332786) (xy 160.780605 -294.29119) (xy 160.81324 -294.254353) (xy 160.851361 -294.223228)
			(xy 160.893982 -294.198621) (xy 160.939998 -294.181169) (xy 160.988217 -294.171325) (xy 161.037392 -294.169344)
			(xy 161.086247 -294.175276) (xy 161.133518 -294.188968) (xy 161.17798 -294.210066) (xy 161.218483 -294.238022)
			(xy 161.253976 -294.272114) (xy 161.283541 -294.311458) (xy 161.306412 -294.355035) (xy 161.321996 -294.401716)
			(xy 161.329891 -294.450293) (xy 161.330386 -294.4749) (xy 161.329891 -294.499507) (xy 161.321996 -294.548084)
			(xy 161.306412 -294.594765) (xy 161.283541 -294.638342) (xy 161.253976 -294.677686) (xy 161.218483 -294.711778)
			(xy 161.17798 -294.739734) (xy 161.133518 -294.760832) (xy 161.086247 -294.774524) (xy 161.037392 -294.780456)
			(xy 160.988217 -294.778475) (xy 160.939998 -294.768631) (xy 160.893982 -294.751179) (xy 160.851361 -294.726572)
			(xy 160.81324 -294.695447) (xy 160.780605 -294.65861) (xy 160.754302 -294.617014) (xy 160.735011 -294.571738)
			(xy 160.723234 -294.523954) (xy 160.719274 -294.4749) (xy 160.380172 -294.4749) (xy 160.379677 -294.499507)
			(xy 160.371782 -294.548084) (xy 160.356198 -294.594765) (xy 160.333327 -294.638342) (xy 160.303762 -294.677686)
			(xy 160.268269 -294.711778) (xy 160.227766 -294.739734) (xy 160.183304 -294.760832) (xy 160.136033 -294.774524)
			(xy 160.087178 -294.780456) (xy 160.038003 -294.778475) (xy 159.989784 -294.768631) (xy 159.943768 -294.751179)
			(xy 159.901147 -294.726572) (xy 159.863026 -294.695447) (xy 159.830391 -294.65861) (xy 159.804088 -294.617014)
			(xy 159.784797 -294.571738) (xy 159.77302 -294.523954) (xy 159.76906 -294.4749) (xy 159.430212 -294.4749)
			(xy 159.429717 -294.499507) (xy 159.421822 -294.548084) (xy 159.406238 -294.594765) (xy 159.383367 -294.638342)
			(xy 159.353802 -294.677686) (xy 159.318309 -294.711778) (xy 159.277806 -294.739734) (xy 159.233344 -294.760832)
			(xy 159.186073 -294.774524) (xy 159.137218 -294.780456) (xy 159.088043 -294.778475) (xy 159.039824 -294.768631)
			(xy 158.993808 -294.751179) (xy 158.951187 -294.726572) (xy 158.913066 -294.695447) (xy 158.880431 -294.65861)
			(xy 158.854128 -294.617014) (xy 158.834837 -294.571738) (xy 158.82306 -294.523954) (xy 158.8191 -294.4749)
			(xy 158.531052 -294.4749) (xy 158.530554 -294.501549) (xy 158.522611 -294.554253) (xy 158.506901 -294.605183)
			(xy 158.483775 -294.653204) (xy 158.453751 -294.697241) (xy 158.417499 -294.736312) (xy 158.375828 -294.769543)
			(xy 158.32967 -294.796192) (xy 158.280056 -294.815664) (xy 158.228094 -294.827524) (xy 158.174944 -294.831508)
			(xy 158.121794 -294.827524) (xy 158.069832 -294.815664) (xy 158.020218 -294.796192) (xy 157.97406 -294.769543)
			(xy 157.932389 -294.736312) (xy 157.896137 -294.697241) (xy 157.866113 -294.653204) (xy 157.842987 -294.605183)
			(xy 157.827277 -294.554253) (xy 157.819334 -294.501549) (xy 157.529465 -294.501549) (xy 157.521902 -294.548084)
			(xy 157.506318 -294.594765) (xy 157.483447 -294.638342) (xy 157.453882 -294.677686) (xy 157.418389 -294.711778)
			(xy 157.377886 -294.739734) (xy 157.333424 -294.760832) (xy 157.286153 -294.774524) (xy 157.237298 -294.780456)
			(xy 157.188123 -294.778475) (xy 157.139904 -294.768631) (xy 157.093888 -294.751179) (xy 157.051267 -294.726572)
			(xy 157.013146 -294.695447) (xy 156.980511 -294.65861) (xy 156.954208 -294.617014) (xy 156.934917 -294.571738)
			(xy 156.92314 -294.523954) (xy 156.91918 -294.4749) (xy 156.049472 -294.4749) (xy 157.76702 -296.192448)
			(xy 157.78734 -296.200068) (xy 157.798516 -296.199306) (xy 157.885892 -296.193464) (xy 157.905196 -296.18305)
			(xy 157.9118 -296.174414) (xy 157.927567 -296.154537) (xy 157.964123 -296.119361) (xy 158.005618 -296.090173)
			(xy 158.051079 -296.067656) (xy 158.099443 -296.052337) (xy 158.149578 -296.044574) (xy 158.174944 -296.044112)
			(xy 158.200928 -296.044625) (xy 158.252256 -296.052761) (xy 158.30168 -296.068826) (xy 158.347982 -296.092425)
			(xy 158.390022 -296.122976) (xy 158.426766 -296.159727) (xy 158.457309 -296.201773) (xy 158.480898 -296.248079)
			(xy 158.496954 -296.297506) (xy 158.50508 -296.348836) (xy 158.505652 -296.37482) (xy 158.505416 -296.391577)
			(xy 158.501984 -296.424916) (xy 158.498794 -296.441368) (xy 158.496508 -296.452798) (xy 158.501842 -296.474642)
			(xy 158.558992 -296.545) (xy 158.56661 -296.553398) (xy 158.587043 -296.563159) (xy 158.598362 -296.563796)
			(xy 159.662876 -296.563796) (xy 159.68345 -296.55389) (xy 159.690816 -296.545) (xy 159.739584 -296.485056)
			(xy 159.744781 -296.478091) (xy 159.750613 -296.461733) (xy 159.751014 -296.453052) (xy 159.751014 -296.441622)
			(xy 159.749998 -296.436796) (xy 159.747253 -296.42145) (xy 159.744328 -296.390409) (xy 159.744156 -296.37482)
			(xy 159.744666 -296.348833) (xy 159.752796 -296.297498) (xy 159.768857 -296.248068) (xy 159.792453 -296.201758)
			(xy 159.823003 -296.15971) (xy 159.859754 -296.122959) (xy 159.901802 -296.092409) (xy 159.948112 -296.068813)
			(xy 159.997542 -296.052752) (xy 160.048877 -296.044622) (xy 160.100851 -296.044622) (xy 160.152186 -296.052752)
			(xy 160.201616 -296.068813) (xy 160.247926 -296.092409) (xy 160.289974 -296.122959) (xy 160.326725 -296.15971)
			(xy 160.357275 -296.201758) (xy 160.380871 -296.248068) (xy 160.396932 -296.297498) (xy 160.405062 -296.348833)
			(xy 160.405572 -296.37482) (xy 160.405335 -296.391577) (xy 160.401903 -296.424916) (xy 160.398714 -296.441368)
			(xy 160.396428 -296.452798) (xy 160.401762 -296.474642) (xy 160.458912 -296.545) (xy 160.466531 -296.553395)
			(xy 160.486964 -296.563148) (xy 160.498282 -296.563796) (xy 160.61309 -296.563796) (xy 160.633664 -296.55389)
			(xy 160.64103 -296.545) (xy 160.689798 -296.485056) (xy 160.694993 -296.478091) (xy 160.700824 -296.461733)
			(xy 160.701228 -296.453052) (xy 160.701228 -296.441622) (xy 160.700212 -296.436796) (xy 160.697467 -296.42145)
			(xy 160.694542 -296.390409) (xy 160.69437 -296.37482) (xy 160.69488 -296.348833) (xy 160.70301 -296.297498)
			(xy 160.719071 -296.248068) (xy 160.742667 -296.201758) (xy 160.773217 -296.15971) (xy 160.809968 -296.122959)
			(xy 160.852016 -296.092409) (xy 160.898326 -296.068813) (xy 160.947756 -296.052752) (xy 160.999091 -296.044622)
			(xy 161.051065 -296.044622) (xy 161.1024 -296.052752) (xy 161.15183 -296.068813) (xy 161.19814 -296.092409)
			(xy 161.240188 -296.122959) (xy 161.276939 -296.15971) (xy 161.307489 -296.201758) (xy 161.331085 -296.248068)
			(xy 161.347146 -296.297498) (xy 161.355276 -296.348833) (xy 161.355786 -296.37482) (xy 161.355588 -296.393067)
			(xy 161.351643 -296.429347) (xy 161.347912 -296.44721) (xy 161.347912 -296.447464) (xy 161.34607 -296.458703)
			(xy 161.351211 -296.48086) (xy 161.357818 -296.490136) (xy 161.407348 -296.551858) (xy 161.414977 -296.560378)
			(xy 161.435554 -296.570289) (xy 161.446972 -296.570908) (xy 161.564828 -296.570908)
		)
		(stroke
			(width 0)
			(type solid)
		)
		(fill yes)
		(layer "In11.Cu")
		(net "PCEPLL3_VDDA18_PEX1")
	)
	(gr_poly
		(pts
			(xy 342.921336 -230.67518) (xy 342.93082 -230.674776) (xy 342.948489 -230.667871) (xy 342.962467 -230.655045)
			(xy 342.967056 -230.646732) (xy 342.967564 -230.645716) (xy 343.01176 -230.546402) (xy 343.007188 -230.516938)
			(xy 342.997028 -230.505762) (xy 342.978751 -230.484662) (xy 342.947927 -230.438122) (xy 342.924214 -230.387588)
			(xy 342.908119 -230.334137) (xy 342.899984 -230.278911) (xy 342.899492 -230.251) (xy 342.899978 -230.223749)
			(xy 342.907734 -230.169801) (xy 342.923089 -230.117506) (xy 342.945731 -230.067929) (xy 342.975197 -230.022079)
			(xy 343.010888 -229.980888) (xy 343.052079 -229.945197) (xy 343.097929 -229.915731) (xy 343.147506 -229.893089)
			(xy 343.199801 -229.877734) (xy 343.253749 -229.869978) (xy 343.281 -229.869492) (xy 343.31087 -229.870072)
			(xy 343.369879 -229.879389) (xy 343.426713 -229.897794) (xy 343.479981 -229.924836) (xy 343.52838 -229.959856)
			(xy 343.549986 -229.98049) (xy 343.559725 -229.989502) (xy 343.582763 -230.002648) (xy 343.608407 -230.009426)
			(xy 343.634932 -230.009382) (xy 343.660553 -230.002518) (xy 343.683547 -229.989295) (xy 343.693242 -229.980236)
			(xy 343.714872 -229.959488) (xy 343.763396 -229.924311) (xy 343.816817 -229.897143) (xy 343.873826 -229.878652)
			(xy 343.933024 -229.869291) (xy 343.96299 -229.86873) (xy 343.990262 -229.869193) (xy 344.04425 -229.876954)
			(xy 344.096584 -229.892319) (xy 344.146199 -229.914976) (xy 344.192085 -229.944463) (xy 344.233307 -229.98018)
			(xy 344.269026 -230.021401) (xy 344.298515 -230.067285) (xy 344.321175 -230.116899) (xy 344.336542 -230.169232)
			(xy 344.344306 -230.22322) (xy 344.344752 -230.250492) (xy 344.344265 -230.278462) (xy 344.336111 -230.333806)
			(xy 344.319975 -230.387369) (xy 344.296203 -230.438007) (xy 344.265303 -230.484639) (xy 344.246962 -230.505762)
			(xy 344.237546 -230.516979) (xy 344.224982 -230.543419) (xy 344.220431 -230.572337) (xy 344.224266 -230.601358)
			(xy 344.236173 -230.628101) (xy 344.255173 -230.65037) (xy 344.279708 -230.666338) (xy 344.307764 -230.674694)
			(xy 344.3224 -230.67518) (xy 351.14611 -230.67518) (xy 351.156128 -230.674758) (xy 351.174638 -230.667086)
			(xy 351.188803 -230.652913) (xy 351.196464 -230.634399) (xy 351.19691 -230.62438) (xy 351.19691 -229.363524)
			(xy 351.197347 -229.35346) (xy 351.205082 -229.334877) (xy 351.211896 -229.327456) (xy 352.05289 -228.486462)
			(xy 352.05924 -228.475794) (xy 352.061272 -228.469952) (xy 352.069675 -228.444315) (xy 352.092689 -228.39552)
			(xy 352.122343 -228.350451) (xy 352.158046 -228.310004) (xy 352.199086 -228.274986) (xy 352.244647 -228.246094)
			(xy 352.293822 -228.223902) (xy 352.34563 -228.208854) (xy 352.399041 -228.201248) (xy 352.426016 -228.200712)
			(xy 352.452657 -228.201157) (xy 352.505421 -228.208575) (xy 352.556638 -228.223266) (xy 352.605312 -228.244942)
			(xy 352.650496 -228.273182) (xy 352.691308 -228.307436) (xy 352.726956 -228.347038) (xy 352.742246 -228.36886)
			(xy 352.750121 -228.379808) (xy 352.770513 -228.39744) (xy 352.794815 -228.40911) (xy 352.821326 -228.414001)
			(xy 352.848192 -228.411771) (xy 352.873534 -228.402575) (xy 352.895578 -228.387057) (xy 352.904552 -228.376988)
			(xy 352.922792 -228.355964) (xy 352.964319 -228.318905) (xy 353.010786 -228.288267) (xy 353.061208 -228.264698)
			(xy 353.114518 -228.248699) (xy 353.169585 -228.240607) (xy 353.197414 -228.240082) (xy 353.224683 -228.240546)
			(xy 353.278666 -228.24831) (xy 353.330995 -228.263678) (xy 353.380603 -228.286337) (xy 353.426482 -228.315826)
			(xy 353.467697 -228.351544) (xy 353.503409 -228.392764) (xy 353.53289 -228.438648) (xy 353.555542 -228.48826)
			(xy 353.570902 -228.540591) (xy 353.578658 -228.594575) (xy 353.579176 -228.621844) (xy 353.579176 -228.622098)
			(xy 353.578556 -228.652994) (xy 353.568556 -228.713973) (xy 353.548867 -228.772545) (xy 353.53498 -228.800152)
			(xy 353.532186 -228.80574) (xy 353.529138 -228.817678) (xy 353.529138 -230.21798) (xy 353.528699 -230.228042)
			(xy 353.520957 -230.24662) (xy 353.514152 -230.254048) (xy 353.237546 -230.530654) (xy 353.231997 -230.536662)
			(xy 353.224727 -230.5513) (xy 353.223322 -230.559356) (xy 353.221796 -230.573798) (xy 353.225978 -230.602523)
			(xy 353.238074 -230.62891) (xy 353.257107 -230.650826) (xy 353.281538 -230.666501) (xy 353.309392 -230.674668)
			(xy 353.323906 -230.67518) (xy 354.206302 -230.67518) (xy 354.216372 -230.674756) (xy 354.234974 -230.667039)
			(xy 354.24237 -230.660194) (xy 354.73259 -230.169974) (xy 354.739433 -230.162574) (xy 354.74716 -230.143976)
			(xy 354.747576 -230.133906) (xy 354.747576 -225.331782) (xy 354.747149 -225.321714) (xy 354.739427 -225.303116)
			(xy 354.73259 -225.295714) (xy 354.389182 -224.952306) (xy 354.38207 -224.94494) (xy 354.363274 -224.93732)
			(xy 351.700084 -224.93732) (xy 351.687836 -224.938047) (xy 351.666087 -224.949324) (xy 351.658428 -224.95891)
			(xy 351.613724 -225.022664) (xy 351.609565 -225.029176) (xy 351.604906 -225.0439) (xy 351.60458 -225.05162)
			(xy 351.60458 -225.073972) (xy 351.60712 -225.081846) (xy 351.61501 -225.106902) (xy 351.623682 -225.15871)
			(xy 351.624392 -225.18497) (xy 351.624392 -225.190812) (xy 351.623581 -225.21659) (xy 351.614951 -225.267435)
			(xy 351.598533 -225.316325) (xy 351.574725 -225.362073) (xy 351.544105 -225.403571) (xy 351.507414 -225.439814)
			(xy 351.465542 -225.469922) (xy 351.419505 -225.493166) (xy 351.370418 -225.508982) (xy 351.31947 -225.516987)
			(xy 351.267898 -225.516987) (xy 351.21695 -225.508982) (xy 351.167863 -225.493166) (xy 351.121826 -225.469922)
			(xy 351.079954 -225.439814) (xy 351.043263 -225.403571) (xy 351.012643 -225.362073) (xy 350.988835 -225.316325)
			(xy 350.972417 -225.267435) (xy 350.963787 -225.21659) (xy 350.962976 -225.190812) (xy 350.962976 -225.186494)
			(xy 350.963596 -225.157705) (xy 350.973556 -225.100994) (xy 350.982788 -225.073718) (xy 350.982788 -225.073464)
			(xy 350.986284 -225.061709) (xy 350.983118 -225.037426) (xy 350.976692 -225.026982) (xy 350.92894 -224.95891)
			(xy 350.921316 -224.949282) (xy 350.899546 -224.938003) (xy 350.887284 -224.93732) (xy 350.84893 -224.93732)
			(xy 350.83995 -224.937676) (xy 350.823105 -224.943901) (xy 350.809469 -224.955587) (xy 350.804734 -224.963228)
			(xy 350.789748 -224.989644) (xy 350.784154 -225.00088) (xy 350.783606 -225.025941) (xy 350.788732 -225.037396)
			(xy 350.788732 -225.03765) (xy 350.799928 -225.060894) (xy 350.815769 -225.109991) (xy 350.82379 -225.160953)
			(xy 350.824292 -225.186748) (xy 350.823779 -225.212732) (xy 350.815642 -225.26406) (xy 350.799577 -225.313483)
			(xy 350.775978 -225.359785) (xy 350.745427 -225.401825) (xy 350.708676 -225.438569) (xy 350.66663 -225.469112)
			(xy 350.620324 -225.492701) (xy 350.570898 -225.508757) (xy 350.519568 -225.516884) (xy 350.493584 -225.517456)
			(xy 350.467799 -225.516961) (xy 350.416855 -225.508955) (xy 350.36777 -225.493139) (xy 350.321735 -225.469897)
			(xy 350.279865 -225.439792) (xy 350.243175 -225.403553) (xy 350.212553 -225.362059) (xy 350.188743 -225.316315)
			(xy 350.17232 -225.26743) (xy 350.163684 -225.216589) (xy 350.162876 -225.190812) (xy 350.162876 -225.186494)
			(xy 350.163496 -225.157705) (xy 350.173456 -225.100994) (xy 350.182688 -225.073718) (xy 350.182688 -225.073464)
			(xy 350.186184 -225.061709) (xy 350.183018 -225.037426) (xy 350.176592 -225.026982) (xy 350.12884 -224.95891)
			(xy 350.121216 -224.949282) (xy 350.099446 -224.938003) (xy 350.087184 -224.93732) (xy 350.049084 -224.93732)
			(xy 350.040099 -224.937667) (xy 350.02324 -224.94388) (xy 350.009588 -224.955562) (xy 350.004888 -224.963228)
			(xy 349.989902 -224.989644) (xy 349.984304 -225.000879) (xy 349.983755 -225.025942) (xy 349.988886 -225.037396)
			(xy 349.988886 -225.03765) (xy 350.00008 -225.060894) (xy 350.015918 -225.109992) (xy 350.023939 -225.160954)
			(xy 350.024446 -225.186748) (xy 350.023933 -225.212734) (xy 350.015797 -225.264065) (xy 349.999732 -225.313491)
			(xy 349.976134 -225.359797) (xy 349.945584 -225.401842) (xy 349.908834 -225.438591) (xy 349.866788 -225.469139)
			(xy 349.820482 -225.492736) (xy 349.771055 -225.508799) (xy 349.719724 -225.516934) (xy 349.693738 -225.517456)
			(xy 349.667956 -225.516958) (xy 349.617017 -225.508946) (xy 349.567938 -225.493126) (xy 349.521909 -225.469881)
			(xy 349.480045 -225.439775) (xy 349.443361 -225.403537) (xy 349.412744 -225.362045) (xy 349.388938 -225.316304)
			(xy 349.372518 -225.267423) (xy 349.363883 -225.216586) (xy 349.36303 -225.190812) (xy 349.36303 -225.186494)
			(xy 349.36365 -225.157705) (xy 349.373608 -225.100993) (xy 349.382842 -225.073718) (xy 349.382842 -225.073464)
			(xy 349.386336 -225.061708) (xy 349.383172 -225.037425) (xy 349.376746 -225.026982) (xy 349.328994 -224.95891)
			(xy 349.321367 -224.949291) (xy 349.299597 -224.938031) (xy 349.287338 -224.93732) (xy 349.248984 -224.93732)
			(xy 349.239999 -224.937667) (xy 349.22314 -224.94388) (xy 349.209488 -224.955562) (xy 349.204788 -224.963228)
			(xy 349.189802 -224.989644) (xy 349.184204 -225.000879) (xy 349.183655 -225.025942) (xy 349.188786 -225.037396)
			(xy 349.188786 -225.03765) (xy 349.19998 -225.060894) (xy 349.215818 -225.109992) (xy 349.223839 -225.160954)
			(xy 349.224346 -225.186748) (xy 349.223833 -225.212734) (xy 349.215697 -225.264065) (xy 349.199632 -225.313491)
			(xy 349.176034 -225.359797) (xy 349.145484 -225.401842) (xy 349.108734 -225.438591) (xy 349.066688 -225.469139)
			(xy 349.020382 -225.492736) (xy 348.970955 -225.508799) (xy 348.919624 -225.516934) (xy 348.893638 -225.517456)
			(xy 348.867856 -225.516958) (xy 348.816917 -225.508946) (xy 348.767838 -225.493126) (xy 348.721809 -225.469881)
			(xy 348.679945 -225.439775) (xy 348.643261 -225.403537) (xy 348.612644 -225.362045) (xy 348.588838 -225.316304)
			(xy 348.572418 -225.267423) (xy 348.563783 -225.216586) (xy 348.56293 -225.190812) (xy 348.56293 -225.186494)
			(xy 348.56355 -225.157705) (xy 348.573508 -225.100993) (xy 348.582742 -225.073718) (xy 348.582742 -225.073464)
			(xy 348.586236 -225.061708) (xy 348.583072 -225.037425) (xy 348.576646 -225.026982) (xy 348.528894 -224.95891)
			(xy 348.521267 -224.949291) (xy 348.499497 -224.938031) (xy 348.487238 -224.93732) (xy 348.448884 -224.93732)
			(xy 348.439899 -224.937667) (xy 348.42304 -224.94388) (xy 348.409388 -224.955562) (xy 348.404688 -224.963228)
			(xy 348.389702 -224.989644) (xy 348.384104 -225.000879) (xy 348.383555 -225.025942) (xy 348.388686 -225.037396)
			(xy 348.388686 -225.03765) (xy 348.39988 -225.060894) (xy 348.415718 -225.109992) (xy 348.423739 -225.160954)
			(xy 348.424246 -225.186748) (xy 348.423733 -225.212734) (xy 348.415597 -225.264065) (xy 348.399532 -225.313491)
			(xy 348.375934 -225.359797) (xy 348.345384 -225.401842) (xy 348.308634 -225.438591) (xy 348.266588 -225.469139)
			(xy 348.220282 -225.492736) (xy 348.170855 -225.508799) (xy 348.119524 -225.516934) (xy 348.093538 -225.517456)
			(xy 348.067756 -225.516958) (xy 348.016817 -225.508946) (xy 347.967738 -225.493126) (xy 347.921709 -225.469881)
			(xy 347.879845 -225.439775) (xy 347.843161 -225.403537) (xy 347.812544 -225.362045) (xy 347.788738 -225.316304)
			(xy 347.772318 -225.267423) (xy 347.763683 -225.216586) (xy 347.76283 -225.190812) (xy 347.76283 -225.186494)
			(xy 347.76345 -225.157705) (xy 347.773408 -225.100993) (xy 347.782642 -225.073718) (xy 347.782642 -225.073464)
			(xy 347.786136 -225.061708) (xy 347.782972 -225.037425) (xy 347.776546 -225.026982) (xy 347.728794 -224.95891)
			(xy 347.721167 -224.949291) (xy 347.699397 -224.938031) (xy 347.687138 -224.93732) (xy 347.6625 -224.93732)
			(xy 347.657266 -224.937166) (xy 347.647022 -224.934995) (xy 347.64218 -224.933002) (xy 347.632583 -224.929326)
			(xy 347.612052 -224.929116) (xy 347.593063 -224.936927) (xy 347.585538 -224.943924) (xy 347.568266 -224.96145)
			(xy 347.564456 -224.996248) (xy 347.573854 -225.011234) (xy 347.585829 -225.031042) (xy 347.604725 -225.073296)
			(xy 347.617539 -225.117774) (xy 347.62402 -225.163605) (xy 347.6244 -225.186748) (xy 347.623887 -225.212732)
			(xy 347.61575 -225.264061) (xy 347.599685 -225.313484) (xy 347.576086 -225.359787) (xy 347.545536 -225.401828)
			(xy 347.508785 -225.438572) (xy 347.466739 -225.469116) (xy 347.420433 -225.492706) (xy 347.371006 -225.508763)
			(xy 347.319677 -225.516891) (xy 347.293692 -225.517456) (xy 347.267704 -225.516946) (xy 347.216368 -225.508815)
			(xy 347.166935 -225.492754) (xy 347.120623 -225.469158) (xy 347.078572 -225.438609) (xy 347.041817 -225.401858)
			(xy 347.011263 -225.359811) (xy 346.987662 -225.313502) (xy 346.971595 -225.264071) (xy 346.963457 -225.212736)
			(xy 346.962984 -225.186748) (xy 346.963464 -225.160756) (xy 346.971589 -225.109411) (xy 346.987647 -225.05997)
			(xy 347.011242 -225.013649) (xy 347.041793 -224.971591) (xy 347.078548 -224.934829) (xy 347.120601 -224.904271)
			(xy 347.166918 -224.880668) (xy 347.216357 -224.864602) (xy 347.2677 -224.856468) (xy 347.293692 -224.85604)
			(xy 347.317692 -224.856447) (xy 347.365191 -224.863349) (xy 347.411192 -224.877052) (xy 347.433138 -224.886774)
			(xy 347.434408 -224.887536) (xy 347.43771 -224.888806) (xy 347.448083 -224.892309) (xy 347.469921 -224.891085)
			(xy 347.48926 -224.880868) (xy 347.496384 -224.87255) (xy 347.504258 -224.86239) (xy 347.509566 -224.85486)
			(xy 347.51494 -224.837253) (xy 347.513763 -224.818882) (xy 347.506186 -224.802104) (xy 347.49994 -224.795334)
			(xy 347.415104 -224.710498) (xy 347.389196 -224.70364) (xy 347.375988 -224.707196) (xy 347.355764 -224.712069)
			(xy 347.314492 -224.717287) (xy 347.293692 -224.71761) (xy 347.290898 -224.71761) (xy 347.265194 -224.716904)
			(xy 347.214465 -224.708517) (xy 347.165646 -224.692379) (xy 347.119912 -224.668881) (xy 347.078366 -224.638588)
			(xy 347.042008 -224.60223) (xy 347.011716 -224.560683) (xy 346.988218 -224.514949) (xy 346.972082 -224.466129)
			(xy 346.963695 -224.4154) (xy 346.962984 -224.389696) (xy 346.962984 -224.386648) (xy 346.963325 -224.365912)
			(xy 346.968553 -224.324771) (xy 346.973398 -224.304606) (xy 346.976954 -224.291398) (xy 346.970096 -224.26549)
			(xy 346.884498 -224.179892) (xy 346.877634 -224.173638) (xy 346.860686 -224.166085) (xy 346.842161 -224.165048)
			(xy 346.824476 -224.170661) (xy 346.816934 -224.176082) (xy 346.8116 -224.1804) (xy 346.803094 -224.188035)
			(xy 346.793212 -224.208612) (xy 346.79255 -224.220024) (xy 346.79255 -224.24517) (xy 346.796868 -224.255076)
			(xy 346.805527 -224.275964) (xy 346.817742 -224.3195) (xy 346.82392 -224.364294) (xy 346.8243 -224.386902)
			(xy 346.823817 -224.412891) (xy 346.815685 -224.464229) (xy 346.799623 -224.513663) (xy 346.776025 -224.559975)
			(xy 346.745472 -224.602025) (xy 346.708718 -224.638779) (xy 346.666666 -224.66933) (xy 346.620353 -224.692926)
			(xy 346.570919 -224.708988) (xy 346.519581 -224.717118) (xy 346.493592 -224.71761) (xy 346.467605 -224.7171)
			(xy 346.416272 -224.708968) (xy 346.366842 -224.692907) (xy 346.320533 -224.66931) (xy 346.278486 -224.638761)
			(xy 346.241736 -224.602009) (xy 346.211186 -224.559961) (xy 346.187591 -224.513653) (xy 346.17153 -224.464223)
			(xy 346.1634 -224.412889) (xy 346.162884 -224.386902) (xy 346.163393 -224.360914) (xy 346.171524 -224.309579)
			(xy 346.187584 -224.260148) (xy 346.21118 -224.213838) (xy 346.24173 -224.171789) (xy 346.278481 -224.135036)
			(xy 346.320529 -224.104485) (xy 346.366839 -224.080888) (xy 346.41627 -224.064826) (xy 346.467605 -224.056694)
			(xy 346.493592 -224.056194) (xy 346.517925 -224.056644) (xy 346.566063 -224.063804) (xy 346.612636 -224.077927)
			(xy 346.634816 -224.087944) (xy 346.650564 -224.095564) (xy 346.684854 -224.08769) (xy 346.717366 -224.047558)
			(xy 346.713048 -224.005648) (xy 346.700856 -223.995742) (xy 346.696792 -223.992186) (xy 346.615004 -223.910398)
			(xy 346.589096 -223.90354) (xy 346.575888 -223.907096) (xy 346.555664 -223.911969) (xy 346.514392 -223.917187)
			(xy 346.493592 -223.91751) (xy 346.490798 -223.91751) (xy 346.465094 -223.916804) (xy 346.414365 -223.908417)
			(xy 346.365546 -223.892279) (xy 346.319812 -223.868781) (xy 346.278266 -223.838488) (xy 346.241908 -223.80213)
			(xy 346.211616 -223.760583) (xy 346.188118 -223.714849) (xy 346.171982 -223.666029) (xy 346.163595 -223.6153)
			(xy 346.162884 -223.589596) (xy 346.162884 -223.586548) (xy 346.163225 -223.565812) (xy 346.168453 -223.524671)
			(xy 346.173298 -223.504506) (xy 346.176854 -223.491298) (xy 346.169996 -223.46539) (xy 346.08516 -223.380554)
			(xy 346.078299 -223.374282) (xy 346.061344 -223.366699) (xy 346.0428 -223.365643) (xy 346.025094 -223.371252)
			(xy 346.017596 -223.376744) (xy 346.008706 -223.383856) (xy 346.005684 -223.386288) (xy 346.000326 -223.391899)
			(xy 345.998038 -223.395032) (xy 345.992514 -223.404034) (xy 345.988581 -223.424763) (xy 345.990418 -223.435164)
			(xy 345.992958 -223.445832) (xy 345.99499 -223.450658) (xy 345.995244 -223.451166) (xy 346.004459 -223.472579)
			(xy 346.01746 -223.517345) (xy 346.024047 -223.563494) (xy 346.024454 -223.586802) (xy 346.023944 -223.61279)
			(xy 346.015814 -223.664127) (xy 345.999753 -223.713561) (xy 345.976158 -223.759873) (xy 345.945609 -223.801925)
			(xy 345.908858 -223.83868) (xy 345.866811 -223.869235) (xy 345.820501 -223.892836) (xy 345.77107 -223.908904)
			(xy 345.719734 -223.917041) (xy 345.693746 -223.91751) (xy 345.667754 -223.91703) (xy 345.61641 -223.908905)
			(xy 345.566969 -223.892847) (xy 345.52065 -223.869251) (xy 345.478592 -223.8387) (xy 345.441831 -223.801945)
			(xy 345.411274 -223.759891) (xy 345.387672 -223.713575) (xy 345.371606 -223.664137) (xy 345.363473 -223.612794)
			(xy 345.363038 -223.586802) (xy 345.363521 -223.560814) (xy 345.371652 -223.509478) (xy 345.387715 -223.460046)
			(xy 345.411313 -223.413736) (xy 345.441866 -223.371688) (xy 345.478621 -223.334938) (xy 345.520673 -223.30439)
			(xy 345.566987 -223.280798) (xy 345.616421 -223.264742) (xy 345.667758 -223.256618) (xy 345.693746 -223.256094)
			(xy 345.717745 -223.256505) (xy 345.765242 -223.263413) (xy 345.81124 -223.277121) (xy 345.833192 -223.286828)
			(xy 345.834462 -223.28759) (xy 345.837764 -223.28886) (xy 345.848142 -223.292371) (xy 345.869993 -223.291163)
			(xy 345.889355 -223.280961) (xy 345.896438 -223.272604) (xy 345.904312 -223.262444) (xy 345.909607 -223.254913)
			(xy 345.91496 -223.237314) (xy 345.913772 -223.218956) (xy 345.906196 -223.202193) (xy 345.899994 -223.195388)
			(xy 345.815158 -223.110552) (xy 345.78925 -223.103694) (xy 345.776042 -223.10725) (xy 345.755819 -223.112126)
			(xy 345.714547 -223.11735) (xy 345.693746 -223.117664) (xy 345.690952 -223.117664) (xy 345.665247 -223.116962)
			(xy 345.614514 -223.108581) (xy 345.56569 -223.092448) (xy 345.519952 -223.068951) (xy 345.478403 -223.038658)
			(xy 345.442043 -223.002299) (xy 345.41175 -222.960749) (xy 345.388253 -222.915011) (xy 345.372119 -222.866188)
			(xy 345.363738 -222.815455) (xy 345.363038 -222.78975) (xy 345.363038 -222.786702) (xy 345.363384 -222.767531)
			(xy 345.367963 -222.72946) (xy 345.372182 -222.710756) (xy 345.373452 -222.704914) (xy 345.373452 -222.684848)
			(xy 345.371674 -222.671386) (xy 345.369388 -222.663004) (xy 345.369134 -222.662242) (xy 345.368396 -222.658544)
			(xy 345.367892 -222.65102) (xy 345.368118 -222.647256) (xy 345.36888 -222.638366) (xy 345.364562 -222.621856)
			(xy 345.30919 -222.541084) (xy 345.301662 -222.531194) (xy 345.279694 -222.519625) (xy 345.26728 -222.518986)
			(xy 344.520012 -222.518986) (xy 344.507592 -222.5196) (xy 344.485616 -222.531177) (xy 344.478102 -222.541084)
			(xy 344.423492 -222.62084) (xy 344.420698 -222.645732) (xy 344.42527 -222.657416) (xy 344.436644 -222.688585)
			(xy 344.448915 -222.753784) (xy 344.449654 -222.786956) (xy 344.449156 -222.813605) (xy 344.441213 -222.866309)
			(xy 344.425503 -222.917239) (xy 344.402377 -222.96526) (xy 344.372353 -223.009297) (xy 344.336101 -223.048368)
			(xy 344.29443 -223.081599) (xy 344.248272 -223.108248) (xy 344.198658 -223.12772) (xy 344.146696 -223.13958)
			(xy 344.093546 -223.143564) (xy 344.040396 -223.13958) (xy 343.988434 -223.12772) (xy 343.93882 -223.108248)
			(xy 343.892662 -223.081599) (xy 343.850991 -223.048368) (xy 343.814739 -223.009297) (xy 343.784715 -222.96526)
			(xy 343.761589 -222.917239) (xy 343.745879 -222.866309) (xy 343.737936 -222.813605) (xy 343.737438 -222.786956)
			(xy 343.738167 -222.753783) (xy 343.75043 -222.68858) (xy 343.761822 -222.657416) (xy 343.766394 -222.645732)
			(xy 343.7636 -222.62084) (xy 343.70899 -222.541084) (xy 343.701462 -222.531194) (xy 343.679494 -222.519625)
			(xy 343.66708 -222.518986) (xy 341.320628 -222.518986) (xy 341.308206 -222.519597) (xy 341.286224 -222.53117)
			(xy 341.278718 -222.541084) (xy 341.224108 -222.62084) (xy 341.221314 -222.645732) (xy 341.225886 -222.657416)
			(xy 341.237262 -222.688585) (xy 341.249536 -222.753784) (xy 341.25027 -222.786956) (xy 341.249772 -222.813605)
			(xy 341.241829 -222.866309) (xy 341.226119 -222.917239) (xy 341.202993 -222.96526) (xy 341.172969 -223.009297)
			(xy 341.136717 -223.048368) (xy 341.095046 -223.081599) (xy 341.048888 -223.108248) (xy 340.999274 -223.12772)
			(xy 340.947312 -223.13958) (xy 340.894162 -223.143564) (xy 340.841012 -223.13958) (xy 340.78905 -223.12772)
			(xy 340.739436 -223.108248) (xy 340.693278 -223.081599) (xy 340.651607 -223.048368) (xy 340.615355 -223.009297)
			(xy 340.585331 -222.96526) (xy 340.562205 -222.917239) (xy 340.546495 -222.866309) (xy 340.538552 -222.813605)
			(xy 340.538054 -222.786956) (xy 340.538783 -222.753783) (xy 340.551048 -222.68858) (xy 340.562438 -222.657416)
			(xy 340.56701 -222.645732) (xy 340.564216 -222.62084) (xy 340.509606 -222.541084) (xy 340.502079 -222.531191)
			(xy 340.480112 -222.519615) (xy 340.467696 -222.518986) (xy 339.74151 -222.518986) (xy 339.731439 -222.518564)
			(xy 339.712834 -222.510851) (xy 339.705442 -222.504) (xy 339.682836 -222.481394) (xy 339.675724 -222.474028)
			(xy 339.656928 -222.466408) (xy 339.597746 -222.466408) (xy 339.587746 -222.466897) (xy 339.569255 -222.474523)
			(xy 339.555055 -222.488609) (xy 339.550756 -222.49765) (xy 339.540088 -222.52305) (xy 339.537673 -222.529558)
			(xy 339.536116 -222.543348) (xy 339.53704 -222.550228) (xy 339.53704 -222.550482) (xy 339.538301 -222.557288)
			(xy 339.543962 -222.569914) (xy 339.548216 -222.575374) (xy 339.5661 -222.597844) (xy 339.594641 -222.647673)
			(xy 339.614154 -222.70168) (xy 339.624055 -222.758244) (xy 339.62467 -222.786956) (xy 339.62416 -222.812943)
			(xy 339.61603 -222.864278) (xy 339.599969 -222.913708) (xy 339.576373 -222.960018) (xy 339.545823 -223.002066)
			(xy 339.509072 -223.038817) (xy 339.467024 -223.069367) (xy 339.420714 -223.092963) (xy 339.371284 -223.109024)
			(xy 339.319949 -223.117154) (xy 339.267975 -223.117154) (xy 339.21664 -223.109024) (xy 339.16721 -223.092963)
			(xy 339.1209 -223.069367) (xy 339.078852 -223.038817) (xy 339.042101 -223.002066) (xy 339.011551 -222.960018)
			(xy 338.987955 -222.913708) (xy 338.971894 -222.864278) (xy 338.963764 -222.812943) (xy 338.963254 -222.786956)
			(xy 338.963917 -222.758266) (xy 338.973899 -222.701759) (xy 338.993455 -222.647812) (xy 339.007196 -222.622618)
			(xy 339.007958 -222.621348) (xy 339.010244 -222.616522) (xy 339.012629 -222.611371) (xy 339.015322 -222.600348)
			(xy 339.015578 -222.594678) (xy 339.015832 -222.580454) (xy 338.965286 -222.492062) (xy 338.965286 -222.491808)
			(xy 338.961779 -222.486164) (xy 338.952393 -222.476764) (xy 338.946744 -222.473266) (xy 338.940808 -222.4701)
			(xy 338.927815 -222.466628) (xy 338.92109 -222.466408) (xy 338.866988 -222.466408) (xy 338.860258 -222.466584)
			(xy 338.847259 -222.470069) (xy 338.841334 -222.473266) (xy 338.83569 -222.476773) (xy 338.826295 -222.486162)
			(xy 338.822792 -222.491808) (xy 338.822792 -222.492062) (xy 338.779104 -222.568262) (xy 338.775985 -222.574138)
			(xy 338.772646 -222.587011) (xy 338.7725 -222.593662) (xy 338.7725 -222.607632) (xy 338.78139 -222.622872)
			(xy 338.785454 -222.630492) (xy 338.797825 -222.654699) (xy 338.815361 -222.706151) (xy 338.824253 -222.759777)
			(xy 338.824824 -222.786956) (xy 338.824314 -222.812943) (xy 338.816184 -222.864278) (xy 338.800123 -222.913708)
			(xy 338.776527 -222.960018) (xy 338.745977 -223.002066) (xy 338.709226 -223.038817) (xy 338.667178 -223.069367)
			(xy 338.620868 -223.092963) (xy 338.571438 -223.109024) (xy 338.520103 -223.117154) (xy 338.468129 -223.117154)
			(xy 338.416794 -223.109024) (xy 338.367364 -223.092963) (xy 338.321054 -223.069367) (xy 338.279006 -223.038817)
			(xy 338.242255 -223.002066) (xy 338.211705 -222.960018) (xy 338.188109 -222.913708) (xy 338.172048 -222.864278)
			(xy 338.163918 -222.812943) (xy 338.163408 -222.786956) (xy 338.164071 -222.758266) (xy 338.174055 -222.70176)
			(xy 338.193613 -222.647814) (xy 338.20735 -222.622618) (xy 338.208112 -222.621348) (xy 338.210398 -222.616522)
			(xy 338.212785 -222.611372) (xy 338.21548 -222.600348) (xy 338.215732 -222.594678) (xy 338.215986 -222.580454)
			(xy 338.16544 -222.492062) (xy 338.16544 -222.491808) (xy 338.161931 -222.486166) (xy 338.15254 -222.476774)
			(xy 338.146898 -222.473266) (xy 338.140963 -222.470093) (xy 338.12797 -222.466607) (xy 338.121244 -222.466408)
			(xy 338.066888 -222.466408) (xy 338.060158 -222.466584) (xy 338.047159 -222.470069) (xy 338.041234 -222.473266)
			(xy 338.03559 -222.476773) (xy 338.026195 -222.486162) (xy 338.022692 -222.491808) (xy 338.022692 -222.492062)
			(xy 337.979004 -222.568262) (xy 337.975885 -222.574138) (xy 337.972546 -222.587011) (xy 337.9724 -222.593662)
			(xy 337.9724 -222.607632) (xy 337.98129 -222.622872) (xy 337.985354 -222.630492) (xy 337.997725 -222.654699)
			(xy 338.015261 -222.706151) (xy 338.024153 -222.759777) (xy 338.024724 -222.786956) (xy 338.024244 -222.812948)
			(xy 338.016119 -222.864293) (xy 338.00006 -222.913734) (xy 337.976465 -222.960055) (xy 337.945914 -223.002114)
			(xy 337.909159 -223.038875) (xy 337.867106 -223.069434) (xy 337.82079 -223.093037) (xy 337.771351 -223.109104)
			(xy 337.720008 -223.117239) (xy 337.694016 -223.117664) (xy 337.681266 -223.117574) (xy 337.655837 -223.11567)
			(xy 337.643216 -223.113854) (xy 337.617821 -223.109411) (xy 337.568723 -223.093694) (xy 337.522657 -223.070551)
			(xy 337.480737 -223.040545) (xy 337.443979 -223.004399) (xy 337.413271 -222.96299) (xy 337.4009 -222.940372)
			(xy 337.400646 -222.939864) (xy 337.397852 -222.934784) (xy 337.394042 -222.930466) (xy 337.385914 -222.922846)
			(xy 337.368134 -222.909384) (xy 337.363224 -222.905918) (xy 337.352181 -222.90118) (xy 337.34629 -222.899986)
			(xy 337.277202 -222.888048) (xy 337.265009 -222.886679) (xy 337.241666 -222.894116) (xy 337.232498 -222.902272)
			(xy 337.177888 -222.956882) (xy 337.17484 -222.961708) (xy 337.16223 -222.981255) (xy 337.132401 -223.016948)
			(xy 337.115404 -223.032828) (xy 337.10753 -223.03994) (xy 337.094068 -223.068896) (xy 337.09191 -223.073962)
			(xy 337.089607 -223.084727) (xy 337.089496 -223.090232) (xy 337.089496 -223.278446) (xy 337.090766 -223.289114)
			(xy 337.093052 -223.299528) (xy 337.096354 -223.309688) (xy 337.107022 -223.333564) (xy 337.114896 -223.340676)
			(xy 337.133377 -223.35789) (xy 337.165412 -223.396932) (xy 337.191136 -223.440393) (xy 337.209949 -223.487261)
			(xy 337.221416 -223.536445) (xy 337.225267 -223.586801) (xy 337.223279 -223.612789) (xy 337.363818 -223.612789)
			(xy 337.363818 -223.560815) (xy 337.371948 -223.50948) (xy 337.388009 -223.46005) (xy 337.411605 -223.41374)
			(xy 337.442155 -223.371692) (xy 337.478906 -223.334941) (xy 337.520954 -223.304391) (xy 337.567264 -223.280795)
			(xy 337.616694 -223.264734) (xy 337.668029 -223.256604) (xy 337.720003 -223.256604) (xy 337.771338 -223.264734)
			(xy 337.820768 -223.280795) (xy 337.867078 -223.304391) (xy 337.909126 -223.334941) (xy 337.945877 -223.371692)
			(xy 337.976427 -223.41374) (xy 338.000023 -223.46005) (xy 338.016084 -223.50948) (xy 338.024214 -223.560815)
			(xy 338.024724 -223.586802) (xy 338.024214 -223.612789) (xy 338.163918 -223.612789) (xy 338.163918 -223.560815)
			(xy 338.172048 -223.50948) (xy 338.188109 -223.46005) (xy 338.211705 -223.41374) (xy 338.242255 -223.371692)
			(xy 338.279006 -223.334941) (xy 338.321054 -223.304391) (xy 338.367364 -223.280795) (xy 338.416794 -223.264734)
			(xy 338.468129 -223.256604) (xy 338.520103 -223.256604) (xy 338.571438 -223.264734) (xy 338.620868 -223.280795)
			(xy 338.667178 -223.304391) (xy 338.709226 -223.334941) (xy 338.745977 -223.371692) (xy 338.776527 -223.41374)
			(xy 338.800123 -223.46005) (xy 338.816184 -223.50948) (xy 338.824314 -223.560815) (xy 338.824824 -223.586802)
			(xy 338.824314 -223.612789) (xy 338.963764 -223.612789) (xy 338.963764 -223.560815) (xy 338.971894 -223.50948)
			(xy 338.987955 -223.46005) (xy 339.011551 -223.41374) (xy 339.042101 -223.371692) (xy 339.078852 -223.334941)
			(xy 339.1209 -223.304391) (xy 339.16721 -223.280795) (xy 339.21664 -223.264734) (xy 339.267975 -223.256604)
			(xy 339.319949 -223.256604) (xy 339.371284 -223.264734) (xy 339.420714 -223.280795) (xy 339.467024 -223.304391)
			(xy 339.509072 -223.334941) (xy 339.545823 -223.371692) (xy 339.576373 -223.41374) (xy 339.599969 -223.46005)
			(xy 339.61603 -223.50948) (xy 339.62416 -223.560815) (xy 339.62467 -223.586802) (xy 339.62416 -223.612789)
			(xy 339.763864 -223.612789) (xy 339.763864 -223.560815) (xy 339.771994 -223.50948) (xy 339.788055 -223.46005)
			(xy 339.811651 -223.41374) (xy 339.842201 -223.371692) (xy 339.878952 -223.334941) (xy 339.921 -223.304391)
			(xy 339.96731 -223.280795) (xy 340.01674 -223.264734) (xy 340.068075 -223.256604) (xy 340.120049 -223.256604)
			(xy 340.171384 -223.264734) (xy 340.220814 -223.280795) (xy 340.267124 -223.304391) (xy 340.309172 -223.334941)
			(xy 340.345923 -223.371692) (xy 340.376473 -223.41374) (xy 340.400069 -223.46005) (xy 340.41613 -223.50948)
			(xy 340.42426 -223.560815) (xy 340.42477 -223.586802) (xy 340.42426 -223.612789) (xy 341.36381 -223.612789)
			(xy 341.36381 -223.560815) (xy 341.37194 -223.50948) (xy 341.388001 -223.46005) (xy 341.411597 -223.41374)
			(xy 341.442147 -223.371692) (xy 341.478898 -223.334941) (xy 341.520946 -223.304391) (xy 341.567256 -223.280795)
			(xy 341.616686 -223.264734) (xy 341.668021 -223.256604) (xy 341.719995 -223.256604) (xy 341.77133 -223.264734)
			(xy 341.82076 -223.280795) (xy 341.86707 -223.304391) (xy 341.909118 -223.334941) (xy 341.945869 -223.371692)
			(xy 341.976419 -223.41374) (xy 342.000015 -223.46005) (xy 342.016076 -223.50948) (xy 342.024206 -223.560815)
			(xy 342.024716 -223.586802) (xy 342.024206 -223.612789) (xy 342.963502 -223.612789) (xy 342.963502 -223.560815)
			(xy 342.971632 -223.50948) (xy 342.987693 -223.46005) (xy 343.011289 -223.41374) (xy 343.041839 -223.371692)
			(xy 343.07859 -223.334941) (xy 343.120638 -223.304391) (xy 343.166948 -223.280795) (xy 343.216378 -223.264734)
			(xy 343.267713 -223.256604) (xy 343.319687 -223.256604) (xy 343.371022 -223.264734) (xy 343.420452 -223.280795)
			(xy 343.466762 -223.304391) (xy 343.50881 -223.334941) (xy 343.545561 -223.371692) (xy 343.576111 -223.41374)
			(xy 343.599707 -223.46005) (xy 343.615768 -223.50948) (xy 343.623898 -223.560815) (xy 343.624408 -223.586802)
			(xy 343.623898 -223.612789) (xy 344.563448 -223.612789) (xy 344.563448 -223.560815) (xy 344.571578 -223.50948)
			(xy 344.587639 -223.46005) (xy 344.611235 -223.41374) (xy 344.641785 -223.371692) (xy 344.678536 -223.334941)
			(xy 344.720584 -223.304391) (xy 344.766894 -223.280795) (xy 344.816324 -223.264734) (xy 344.867659 -223.256604)
			(xy 344.919633 -223.256604) (xy 344.970968 -223.264734) (xy 345.020398 -223.280795) (xy 345.066708 -223.304391)
			(xy 345.108756 -223.334941) (xy 345.145507 -223.371692) (xy 345.176057 -223.41374) (xy 345.199653 -223.46005)
			(xy 345.215714 -223.50948) (xy 345.223844 -223.560815) (xy 345.224354 -223.586802) (xy 345.223844 -223.612789)
			(xy 345.215714 -223.664124) (xy 345.199653 -223.713554) (xy 345.176057 -223.759864) (xy 345.145507 -223.801912)
			(xy 345.108756 -223.838663) (xy 345.066708 -223.869213) (xy 345.020398 -223.892809) (xy 344.970968 -223.90887)
			(xy 344.919633 -223.917) (xy 344.867659 -223.917) (xy 344.816324 -223.90887) (xy 344.766894 -223.892809)
			(xy 344.720584 -223.869213) (xy 344.678536 -223.838663) (xy 344.641785 -223.801912) (xy 344.611235 -223.759864)
			(xy 344.587639 -223.713554) (xy 344.571578 -223.664124) (xy 344.563448 -223.612789) (xy 343.623898 -223.612789)
			(xy 343.615768 -223.664124) (xy 343.599707 -223.713554) (xy 343.576111 -223.759864) (xy 343.545561 -223.801912)
			(xy 343.50881 -223.838663) (xy 343.466762 -223.869213) (xy 343.420452 -223.892809) (xy 343.371022 -223.90887)
			(xy 343.319687 -223.917) (xy 343.267713 -223.917) (xy 343.216378 -223.90887) (xy 343.166948 -223.892809)
			(xy 343.120638 -223.869213) (xy 343.07859 -223.838663) (xy 343.041839 -223.801912) (xy 343.011289 -223.759864)
			(xy 342.987693 -223.713554) (xy 342.971632 -223.664124) (xy 342.963502 -223.612789) (xy 342.024206 -223.612789)
			(xy 342.016076 -223.664124) (xy 342.000015 -223.713554) (xy 341.976419 -223.759864) (xy 341.945869 -223.801912)
			(xy 341.909118 -223.838663) (xy 341.86707 -223.869213) (xy 341.82076 -223.892809) (xy 341.77133 -223.90887)
			(xy 341.719995 -223.917) (xy 341.668021 -223.917) (xy 341.616686 -223.90887) (xy 341.567256 -223.892809)
			(xy 341.520946 -223.869213) (xy 341.478898 -223.838663) (xy 341.442147 -223.801912) (xy 341.411597 -223.759864)
			(xy 341.388001 -223.713554) (xy 341.37194 -223.664124) (xy 341.36381 -223.612789) (xy 340.42426 -223.612789)
			(xy 340.41613 -223.664124) (xy 340.400069 -223.713554) (xy 340.376473 -223.759864) (xy 340.345923 -223.801912)
			(xy 340.309172 -223.838663) (xy 340.267124 -223.869213) (xy 340.220814 -223.892809) (xy 340.171384 -223.90887)
			(xy 340.120049 -223.917) (xy 340.068075 -223.917) (xy 340.01674 -223.90887) (xy 339.96731 -223.892809)
			(xy 339.921 -223.869213) (xy 339.878952 -223.838663) (xy 339.842201 -223.801912) (xy 339.811651 -223.759864)
			(xy 339.788055 -223.713554) (xy 339.771994 -223.664124) (xy 339.763864 -223.612789) (xy 339.62416 -223.612789)
			(xy 339.61603 -223.664124) (xy 339.599969 -223.713554) (xy 339.576373 -223.759864) (xy 339.545823 -223.801912)
			(xy 339.509072 -223.838663) (xy 339.467024 -223.869213) (xy 339.420714 -223.892809) (xy 339.371284 -223.90887)
			(xy 339.319949 -223.917) (xy 339.267975 -223.917) (xy 339.21664 -223.90887) (xy 339.16721 -223.892809)
			(xy 339.1209 -223.869213) (xy 339.078852 -223.838663) (xy 339.042101 -223.801912) (xy 339.011551 -223.759864)
			(xy 338.987955 -223.713554) (xy 338.971894 -223.664124) (xy 338.963764 -223.612789) (xy 338.824314 -223.612789)
			(xy 338.816184 -223.664124) (xy 338.800123 -223.713554) (xy 338.776527 -223.759864) (xy 338.745977 -223.801912)
			(xy 338.709226 -223.838663) (xy 338.667178 -223.869213) (xy 338.620868 -223.892809) (xy 338.571438 -223.90887)
			(xy 338.520103 -223.917) (xy 338.468129 -223.917) (xy 338.416794 -223.90887) (xy 338.367364 -223.892809)
			(xy 338.321054 -223.869213) (xy 338.279006 -223.838663) (xy 338.242255 -223.801912) (xy 338.211705 -223.759864)
			(xy 338.188109 -223.713554) (xy 338.172048 -223.664124) (xy 338.163918 -223.612789) (xy 338.024214 -223.612789)
			(xy 338.016084 -223.664124) (xy 338.000023 -223.713554) (xy 337.976427 -223.759864) (xy 337.945877 -223.801912)
			(xy 337.909126 -223.838663) (xy 337.867078 -223.869213) (xy 337.820768 -223.892809) (xy 337.771338 -223.90887)
			(xy 337.720003 -223.917) (xy 337.668029 -223.917) (xy 337.616694 -223.90887) (xy 337.567264 -223.892809)
			(xy 337.520954 -223.869213) (xy 337.478906 -223.838663) (xy 337.442155 -223.801912) (xy 337.411605 -223.759864)
			(xy 337.388009 -223.713554) (xy 337.371948 -223.664124) (xy 337.363818 -223.612789) (xy 337.223279 -223.612789)
			(xy 337.221415 -223.637157) (xy 337.209949 -223.686341) (xy 337.191134 -223.733209) (xy 337.16541 -223.77667)
			(xy 337.133375 -223.815712) (xy 337.114896 -223.832928) (xy 337.107022 -223.84004) (xy 337.094068 -223.868742)
			(xy 337.089496 -223.878902) (xy 337.089496 -224.078546) (xy 337.090766 -224.089214) (xy 337.093052 -224.099628)
			(xy 337.096354 -224.109788) (xy 337.107022 -224.133664) (xy 337.114896 -224.140776) (xy 337.133377 -224.15799)
			(xy 337.165412 -224.197032) (xy 337.191136 -224.240493) (xy 337.209949 -224.287361) (xy 337.221416 -224.336545)
			(xy 337.225267 -224.386901) (xy 337.223279 -224.412889) (xy 337.363818 -224.412889) (xy 337.363818 -224.360915)
			(xy 337.371948 -224.30958) (xy 337.388009 -224.26015) (xy 337.411605 -224.21384) (xy 337.442155 -224.171792)
			(xy 337.478906 -224.135041) (xy 337.520954 -224.104491) (xy 337.567264 -224.080895) (xy 337.616694 -224.064834)
			(xy 337.668029 -224.056704) (xy 337.720003 -224.056704) (xy 337.771338 -224.064834) (xy 337.820768 -224.080895)
			(xy 337.867078 -224.104491) (xy 337.909126 -224.135041) (xy 337.945877 -224.171792) (xy 337.976427 -224.21384)
			(xy 338.000023 -224.26015) (xy 338.016084 -224.30958) (xy 338.024214 -224.360915) (xy 338.024724 -224.386902)
			(xy 338.024214 -224.412889) (xy 338.163918 -224.412889) (xy 338.163918 -224.360915) (xy 338.172048 -224.30958)
			(xy 338.188109 -224.26015) (xy 338.211705 -224.21384) (xy 338.242255 -224.171792) (xy 338.279006 -224.135041)
			(xy 338.321054 -224.104491) (xy 338.367364 -224.080895) (xy 338.416794 -224.064834) (xy 338.468129 -224.056704)
			(xy 338.520103 -224.056704) (xy 338.571438 -224.064834) (xy 338.620868 -224.080895) (xy 338.667178 -224.104491)
			(xy 338.709226 -224.135041) (xy 338.745977 -224.171792) (xy 338.776527 -224.21384) (xy 338.800123 -224.26015)
			(xy 338.816184 -224.30958) (xy 338.824314 -224.360915) (xy 338.824824 -224.386902) (xy 338.824314 -224.412889)
			(xy 338.963764 -224.412889) (xy 338.963764 -224.360915) (xy 338.971894 -224.30958) (xy 338.987955 -224.26015)
			(xy 339.011551 -224.21384) (xy 339.042101 -224.171792) (xy 339.078852 -224.135041) (xy 339.1209 -224.104491)
			(xy 339.16721 -224.080895) (xy 339.21664 -224.064834) (xy 339.267975 -224.056704) (xy 339.319949 -224.056704)
			(xy 339.371284 -224.064834) (xy 339.420714 -224.080895) (xy 339.467024 -224.104491) (xy 339.509072 -224.135041)
			(xy 339.545823 -224.171792) (xy 339.576373 -224.21384) (xy 339.599969 -224.26015) (xy 339.61603 -224.30958)
			(xy 339.62416 -224.360915) (xy 339.62467 -224.386902) (xy 339.62416 -224.412889) (xy 339.763864 -224.412889)
			(xy 339.763864 -224.360915) (xy 339.771994 -224.30958) (xy 339.788055 -224.26015) (xy 339.811651 -224.21384)
			(xy 339.842201 -224.171792) (xy 339.878952 -224.135041) (xy 339.921 -224.104491) (xy 339.96731 -224.080895)
			(xy 340.01674 -224.064834) (xy 340.068075 -224.056704) (xy 340.120049 -224.056704) (xy 340.171384 -224.064834)
			(xy 340.220814 -224.080895) (xy 340.267124 -224.104491) (xy 340.309172 -224.135041) (xy 340.345923 -224.171792)
			(xy 340.376473 -224.21384) (xy 340.400069 -224.26015) (xy 340.41613 -224.30958) (xy 340.42426 -224.360915)
			(xy 340.42477 -224.386902) (xy 340.42426 -224.412889) (xy 340.563964 -224.412889) (xy 340.563964 -224.360915)
			(xy 340.572094 -224.30958) (xy 340.588155 -224.26015) (xy 340.611751 -224.21384) (xy 340.642301 -224.171792)
			(xy 340.679052 -224.135041) (xy 340.7211 -224.104491) (xy 340.76741 -224.080895) (xy 340.81684 -224.064834)
			(xy 340.868175 -224.056704) (xy 340.920149 -224.056704) (xy 340.971484 -224.064834) (xy 341.020914 -224.080895)
			(xy 341.067224 -224.104491) (xy 341.109272 -224.135041) (xy 341.146023 -224.171792) (xy 341.176573 -224.21384)
			(xy 341.200169 -224.26015) (xy 341.21623 -224.30958) (xy 341.22436 -224.360915) (xy 341.22487 -224.386902)
			(xy 341.22436 -224.412889) (xy 341.36381 -224.412889) (xy 341.36381 -224.360915) (xy 341.37194 -224.30958)
			(xy 341.388001 -224.26015) (xy 341.411597 -224.21384) (xy 341.442147 -224.171792) (xy 341.478898 -224.135041)
			(xy 341.520946 -224.104491) (xy 341.567256 -224.080895) (xy 341.616686 -224.064834) (xy 341.668021 -224.056704)
			(xy 341.719995 -224.056704) (xy 341.77133 -224.064834) (xy 341.82076 -224.080895) (xy 341.86707 -224.104491)
			(xy 341.909118 -224.135041) (xy 341.945869 -224.171792) (xy 341.976419 -224.21384) (xy 342.000015 -224.26015)
			(xy 342.016076 -224.30958) (xy 342.024206 -224.360915) (xy 342.024716 -224.386902) (xy 342.024206 -224.412889)
			(xy 342.963502 -224.412889) (xy 342.963502 -224.360915) (xy 342.971632 -224.30958) (xy 342.987693 -224.26015)
			(xy 343.011289 -224.21384) (xy 343.041839 -224.171792) (xy 343.07859 -224.135041) (xy 343.120638 -224.104491)
			(xy 343.166948 -224.080895) (xy 343.216378 -224.064834) (xy 343.267713 -224.056704) (xy 343.319687 -224.056704)
			(xy 343.371022 -224.064834) (xy 343.420452 -224.080895) (xy 343.466762 -224.104491) (xy 343.50881 -224.135041)
			(xy 343.545561 -224.171792) (xy 343.576111 -224.21384) (xy 343.599707 -224.26015) (xy 343.615768 -224.30958)
			(xy 343.623898 -224.360915) (xy 343.624408 -224.386902) (xy 343.623898 -224.412889) (xy 343.763348 -224.412889)
			(xy 343.763348 -224.360915) (xy 343.771478 -224.30958) (xy 343.787539 -224.26015) (xy 343.811135 -224.21384)
			(xy 343.841685 -224.171792) (xy 343.878436 -224.135041) (xy 343.920484 -224.104491) (xy 343.966794 -224.080895)
			(xy 344.016224 -224.064834) (xy 344.067559 -224.056704) (xy 344.119533 -224.056704) (xy 344.170868 -224.064834)
			(xy 344.220298 -224.080895) (xy 344.266608 -224.104491) (xy 344.308656 -224.135041) (xy 344.345407 -224.171792)
			(xy 344.375957 -224.21384) (xy 344.399553 -224.26015) (xy 344.415614 -224.30958) (xy 344.423744 -224.360915)
			(xy 344.424254 -224.386902) (xy 344.423744 -224.412889) (xy 344.563448 -224.412889) (xy 344.563448 -224.360915)
			(xy 344.571578 -224.30958) (xy 344.587639 -224.26015) (xy 344.611235 -224.21384) (xy 344.641785 -224.171792)
			(xy 344.678536 -224.135041) (xy 344.720584 -224.104491) (xy 344.766894 -224.080895) (xy 344.816324 -224.064834)
			(xy 344.867659 -224.056704) (xy 344.919633 -224.056704) (xy 344.970968 -224.064834) (xy 345.020398 -224.080895)
			(xy 345.066708 -224.104491) (xy 345.108756 -224.135041) (xy 345.145507 -224.171792) (xy 345.176057 -224.21384)
			(xy 345.199653 -224.26015) (xy 345.215714 -224.30958) (xy 345.223844 -224.360915) (xy 345.224354 -224.386902)
			(xy 345.223844 -224.412889) (xy 345.363548 -224.412889) (xy 345.363548 -224.360915) (xy 345.371678 -224.30958)
			(xy 345.387739 -224.26015) (xy 345.411335 -224.21384) (xy 345.441885 -224.171792) (xy 345.478636 -224.135041)
			(xy 345.520684 -224.104491) (xy 345.566994 -224.080895) (xy 345.616424 -224.064834) (xy 345.667759 -224.056704)
			(xy 345.719733 -224.056704) (xy 345.771068 -224.064834) (xy 345.820498 -224.080895) (xy 345.866808 -224.104491)
			(xy 345.908856 -224.135041) (xy 345.945607 -224.171792) (xy 345.976157 -224.21384) (xy 345.999753 -224.26015)
			(xy 346.015814 -224.30958) (xy 346.023944 -224.360915) (xy 346.024454 -224.386902) (xy 346.023944 -224.412889)
			(xy 346.015814 -224.464224) (xy 345.999753 -224.513654) (xy 345.976157 -224.559964) (xy 345.945607 -224.602012)
			(xy 345.908856 -224.638763) (xy 345.866808 -224.669313) (xy 345.820498 -224.692909) (xy 345.771068 -224.70897)
			(xy 345.719733 -224.7171) (xy 345.667759 -224.7171) (xy 345.616424 -224.70897) (xy 345.566994 -224.692909)
			(xy 345.520684 -224.669313) (xy 345.478636 -224.638763) (xy 345.441885 -224.602012) (xy 345.411335 -224.559964)
			(xy 345.387739 -224.513654) (xy 345.371678 -224.464224) (xy 345.363548 -224.412889) (xy 345.223844 -224.412889)
			(xy 345.215714 -224.464224) (xy 345.199653 -224.513654) (xy 345.176057 -224.559964) (xy 345.145507 -224.602012)
			(xy 345.108756 -224.638763) (xy 345.066708 -224.669313) (xy 345.020398 -224.692909) (xy 344.970968 -224.70897)
			(xy 344.919633 -224.7171) (xy 344.867659 -224.7171) (xy 344.816324 -224.70897) (xy 344.766894 -224.692909)
			(xy 344.720584 -224.669313) (xy 344.678536 -224.638763) (xy 344.641785 -224.602012) (xy 344.611235 -224.559964)
			(xy 344.587639 -224.513654) (xy 344.571578 -224.464224) (xy 344.563448 -224.412889) (xy 344.423744 -224.412889)
			(xy 344.415614 -224.464224) (xy 344.399553 -224.513654) (xy 344.375957 -224.559964) (xy 344.345407 -224.602012)
			(xy 344.308656 -224.638763) (xy 344.266608 -224.669313) (xy 344.220298 -224.692909) (xy 344.170868 -224.70897)
			(xy 344.119533 -224.7171) (xy 344.067559 -224.7171) (xy 344.016224 -224.70897) (xy 343.966794 -224.692909)
			(xy 343.920484 -224.669313) (xy 343.878436 -224.638763) (xy 343.841685 -224.602012) (xy 343.811135 -224.559964)
			(xy 343.787539 -224.513654) (xy 343.771478 -224.464224) (xy 343.763348 -224.412889) (xy 343.623898 -224.412889)
			(xy 343.615768 -224.464224) (xy 343.599707 -224.513654) (xy 343.576111 -224.559964) (xy 343.545561 -224.602012)
			(xy 343.50881 -224.638763) (xy 343.466762 -224.669313) (xy 343.420452 -224.692909) (xy 343.371022 -224.70897)
			(xy 343.319687 -224.7171) (xy 343.267713 -224.7171) (xy 343.216378 -224.70897) (xy 343.166948 -224.692909)
			(xy 343.120638 -224.669313) (xy 343.07859 -224.638763) (xy 343.041839 -224.602012) (xy 343.011289 -224.559964)
			(xy 342.987693 -224.513654) (xy 342.971632 -224.464224) (xy 342.963502 -224.412889) (xy 342.024206 -224.412889)
			(xy 342.016076 -224.464224) (xy 342.000015 -224.513654) (xy 341.976419 -224.559964) (xy 341.945869 -224.602012)
			(xy 341.909118 -224.638763) (xy 341.86707 -224.669313) (xy 341.82076 -224.692909) (xy 341.77133 -224.70897)
			(xy 341.719995 -224.7171) (xy 341.668021 -224.7171) (xy 341.616686 -224.70897) (xy 341.567256 -224.692909)
			(xy 341.520946 -224.669313) (xy 341.478898 -224.638763) (xy 341.442147 -224.602012) (xy 341.411597 -224.559964)
			(xy 341.388001 -224.513654) (xy 341.37194 -224.464224) (xy 341.36381 -224.412889) (xy 341.22436 -224.412889)
			(xy 341.21623 -224.464224) (xy 341.200169 -224.513654) (xy 341.176573 -224.559964) (xy 341.146023 -224.602012)
			(xy 341.109272 -224.638763) (xy 341.067224 -224.669313) (xy 341.020914 -224.692909) (xy 340.971484 -224.70897)
			(xy 340.920149 -224.7171) (xy 340.868175 -224.7171) (xy 340.81684 -224.70897) (xy 340.76741 -224.692909)
			(xy 340.7211 -224.669313) (xy 340.679052 -224.638763) (xy 340.642301 -224.602012) (xy 340.611751 -224.559964)
			(xy 340.588155 -224.513654) (xy 340.572094 -224.464224) (xy 340.563964 -224.412889) (xy 340.42426 -224.412889)
			(xy 340.41613 -224.464224) (xy 340.400069 -224.513654) (xy 340.376473 -224.559964) (xy 340.345923 -224.602012)
			(xy 340.309172 -224.638763) (xy 340.267124 -224.669313) (xy 340.220814 -224.692909) (xy 340.171384 -224.70897)
			(xy 340.120049 -224.7171) (xy 340.068075 -224.7171) (xy 340.01674 -224.70897) (xy 339.96731 -224.692909)
			(xy 339.921 -224.669313) (xy 339.878952 -224.638763) (xy 339.842201 -224.602012) (xy 339.811651 -224.559964)
			(xy 339.788055 -224.513654) (xy 339.771994 -224.464224) (xy 339.763864 -224.412889) (xy 339.62416 -224.412889)
			(xy 339.61603 -224.464224) (xy 339.599969 -224.513654) (xy 339.576373 -224.559964) (xy 339.545823 -224.602012)
			(xy 339.509072 -224.638763) (xy 339.467024 -224.669313) (xy 339.420714 -224.692909) (xy 339.371284 -224.70897)
			(xy 339.319949 -224.7171) (xy 339.267975 -224.7171) (xy 339.21664 -224.70897) (xy 339.16721 -224.692909)
			(xy 339.1209 -224.669313) (xy 339.078852 -224.638763) (xy 339.042101 -224.602012) (xy 339.011551 -224.559964)
			(xy 338.987955 -224.513654) (xy 338.971894 -224.464224) (xy 338.963764 -224.412889) (xy 338.824314 -224.412889)
			(xy 338.816184 -224.464224) (xy 338.800123 -224.513654) (xy 338.776527 -224.559964) (xy 338.745977 -224.602012)
			(xy 338.709226 -224.638763) (xy 338.667178 -224.669313) (xy 338.620868 -224.692909) (xy 338.571438 -224.70897)
			(xy 338.520103 -224.7171) (xy 338.468129 -224.7171) (xy 338.416794 -224.70897) (xy 338.367364 -224.692909)
			(xy 338.321054 -224.669313) (xy 338.279006 -224.638763) (xy 338.242255 -224.602012) (xy 338.211705 -224.559964)
			(xy 338.188109 -224.513654) (xy 338.172048 -224.464224) (xy 338.163918 -224.412889) (xy 338.024214 -224.412889)
			(xy 338.016084 -224.464224) (xy 338.000023 -224.513654) (xy 337.976427 -224.559964) (xy 337.945877 -224.602012)
			(xy 337.909126 -224.638763) (xy 337.867078 -224.669313) (xy 337.820768 -224.692909) (xy 337.771338 -224.70897)
			(xy 337.720003 -224.7171) (xy 337.668029 -224.7171) (xy 337.616694 -224.70897) (xy 337.567264 -224.692909)
			(xy 337.520954 -224.669313) (xy 337.478906 -224.638763) (xy 337.442155 -224.602012) (xy 337.411605 -224.559964)
			(xy 337.388009 -224.513654) (xy 337.371948 -224.464224) (xy 337.363818 -224.412889) (xy 337.223279 -224.412889)
			(xy 337.221415 -224.437257) (xy 337.209949 -224.486441) (xy 337.191134 -224.533309) (xy 337.16541 -224.57677)
			(xy 337.133375 -224.615812) (xy 337.114896 -224.633028) (xy 337.107022 -224.64014) (xy 337.094068 -224.668842)
			(xy 337.089496 -224.679002) (xy 337.089496 -224.878392) (xy 337.090766 -224.88906) (xy 337.093052 -224.899474)
			(xy 337.096354 -224.909634) (xy 337.107022 -224.93351) (xy 337.114896 -224.940622) (xy 337.133374 -224.957836)
			(xy 337.165402 -224.996877) (xy 337.191118 -225.040336) (xy 337.209926 -225.087201) (xy 337.221386 -225.136381)
			(xy 337.225233 -225.186732) (xy 337.223242 -225.212735) (xy 337.363818 -225.212735) (xy 337.363818 -225.160761)
			(xy 337.371948 -225.109426) (xy 337.388009 -225.059996) (xy 337.411605 -225.013686) (xy 337.442155 -224.971638)
			(xy 337.478906 -224.934887) (xy 337.520954 -224.904337) (xy 337.567264 -224.880741) (xy 337.616694 -224.86468)
			(xy 337.668029 -224.85655) (xy 337.720003 -224.85655) (xy 337.771338 -224.86468) (xy 337.820768 -224.880741)
			(xy 337.867078 -224.904337) (xy 337.909126 -224.934887) (xy 337.945877 -224.971638) (xy 337.976427 -225.013686)
			(xy 338.000023 -225.059996) (xy 338.016084 -225.109426) (xy 338.024214 -225.160761) (xy 338.024724 -225.186748)
			(xy 338.024214 -225.212735) (xy 338.163918 -225.212735) (xy 338.163918 -225.160761) (xy 338.172048 -225.109426)
			(xy 338.188109 -225.059996) (xy 338.211705 -225.013686) (xy 338.242255 -224.971638) (xy 338.279006 -224.934887)
			(xy 338.321054 -224.904337) (xy 338.367364 -224.880741) (xy 338.416794 -224.86468) (xy 338.468129 -224.85655)
			(xy 338.520103 -224.85655) (xy 338.571438 -224.86468) (xy 338.620868 -224.880741) (xy 338.667178 -224.904337)
			(xy 338.709226 -224.934887) (xy 338.745977 -224.971638) (xy 338.776527 -225.013686) (xy 338.800123 -225.059996)
			(xy 338.816184 -225.109426) (xy 338.824314 -225.160761) (xy 338.824824 -225.186748) (xy 338.824314 -225.212735)
			(xy 338.963764 -225.212735) (xy 338.963764 -225.160761) (xy 338.971894 -225.109426) (xy 338.987955 -225.059996)
			(xy 339.011551 -225.013686) (xy 339.042101 -224.971638) (xy 339.078852 -224.934887) (xy 339.1209 -224.904337)
			(xy 339.16721 -224.880741) (xy 339.21664 -224.86468) (xy 339.267975 -224.85655) (xy 339.319949 -224.85655)
			(xy 339.371284 -224.86468) (xy 339.420714 -224.880741) (xy 339.467024 -224.904337) (xy 339.509072 -224.934887)
			(xy 339.545823 -224.971638) (xy 339.576373 -225.013686) (xy 339.599969 -225.059996) (xy 339.61603 -225.109426)
			(xy 339.62416 -225.160761) (xy 339.62467 -225.186748) (xy 339.62416 -225.212735) (xy 339.763864 -225.212735)
			(xy 339.763864 -225.160761) (xy 339.771994 -225.109426) (xy 339.788055 -225.059996) (xy 339.811651 -225.013686)
			(xy 339.842201 -224.971638) (xy 339.878952 -224.934887) (xy 339.921 -224.904337) (xy 339.96731 -224.880741)
			(xy 340.01674 -224.86468) (xy 340.068075 -224.85655) (xy 340.120049 -224.85655) (xy 340.171384 -224.86468)
			(xy 340.220814 -224.880741) (xy 340.267124 -224.904337) (xy 340.309172 -224.934887) (xy 340.345923 -224.971638)
			(xy 340.376473 -225.013686) (xy 340.400069 -225.059996) (xy 340.41613 -225.109426) (xy 340.42426 -225.160761)
			(xy 340.42477 -225.186748) (xy 340.42426 -225.212735) (xy 340.563964 -225.212735) (xy 340.563964 -225.160761)
			(xy 340.572094 -225.109426) (xy 340.588155 -225.059996) (xy 340.611751 -225.013686) (xy 340.642301 -224.971638)
			(xy 340.679052 -224.934887) (xy 340.7211 -224.904337) (xy 340.76741 -224.880741) (xy 340.81684 -224.86468)
			(xy 340.868175 -224.85655) (xy 340.920149 -224.85655) (xy 340.971484 -224.86468) (xy 341.020914 -224.880741)
			(xy 341.067224 -224.904337) (xy 341.109272 -224.934887) (xy 341.146023 -224.971638) (xy 341.176573 -225.013686)
			(xy 341.200169 -225.059996) (xy 341.21623 -225.109426) (xy 341.22436 -225.160761) (xy 341.22487 -225.186748)
			(xy 341.22436 -225.212735) (xy 341.36381 -225.212735) (xy 341.36381 -225.160761) (xy 341.37194 -225.109426)
			(xy 341.388001 -225.059996) (xy 341.411597 -225.013686) (xy 341.442147 -224.971638) (xy 341.478898 -224.934887)
			(xy 341.520946 -224.904337) (xy 341.567256 -224.880741) (xy 341.616686 -224.86468) (xy 341.668021 -224.85655)
			(xy 341.719995 -224.85655) (xy 341.77133 -224.86468) (xy 341.82076 -224.880741) (xy 341.86707 -224.904337)
			(xy 341.909118 -224.934887) (xy 341.945869 -224.971638) (xy 341.976419 -225.013686) (xy 342.000015 -225.059996)
			(xy 342.016076 -225.109426) (xy 342.024206 -225.160761) (xy 342.024716 -225.186748) (xy 342.024206 -225.212735)
			(xy 342.963502 -225.212735) (xy 342.963502 -225.160761) (xy 342.971632 -225.109426) (xy 342.987693 -225.059996)
			(xy 343.011289 -225.013686) (xy 343.041839 -224.971638) (xy 343.07859 -224.934887) (xy 343.120638 -224.904337)
			(xy 343.166948 -224.880741) (xy 343.216378 -224.86468) (xy 343.267713 -224.85655) (xy 343.319687 -224.85655)
			(xy 343.371022 -224.86468) (xy 343.420452 -224.880741) (xy 343.466762 -224.904337) (xy 343.50881 -224.934887)
			(xy 343.545561 -224.971638) (xy 343.576111 -225.013686) (xy 343.599707 -225.059996) (xy 343.615768 -225.109426)
			(xy 343.623898 -225.160761) (xy 343.624408 -225.186748) (xy 343.623898 -225.212735) (xy 343.763348 -225.212735)
			(xy 343.763348 -225.160761) (xy 343.771478 -225.109426) (xy 343.787539 -225.059996) (xy 343.811135 -225.013686)
			(xy 343.841685 -224.971638) (xy 343.878436 -224.934887) (xy 343.920484 -224.904337) (xy 343.966794 -224.880741)
			(xy 344.016224 -224.86468) (xy 344.067559 -224.85655) (xy 344.119533 -224.85655) (xy 344.170868 -224.86468)
			(xy 344.220298 -224.880741) (xy 344.266608 -224.904337) (xy 344.308656 -224.934887) (xy 344.345407 -224.971638)
			(xy 344.375957 -225.013686) (xy 344.399553 -225.059996) (xy 344.415614 -225.109426) (xy 344.423744 -225.160761)
			(xy 344.424254 -225.186748) (xy 344.423744 -225.212735) (xy 344.563448 -225.212735) (xy 344.563448 -225.160761)
			(xy 344.571578 -225.109426) (xy 344.587639 -225.059996) (xy 344.611235 -225.013686) (xy 344.641785 -224.971638)
			(xy 344.678536 -224.934887) (xy 344.720584 -224.904337) (xy 344.766894 -224.880741) (xy 344.816324 -224.86468)
			(xy 344.867659 -224.85655) (xy 344.919633 -224.85655) (xy 344.970968 -224.86468) (xy 345.020398 -224.880741)
			(xy 345.066708 -224.904337) (xy 345.108756 -224.934887) (xy 345.145507 -224.971638) (xy 345.176057 -225.013686)
			(xy 345.199653 -225.059996) (xy 345.215714 -225.109426) (xy 345.223844 -225.160761) (xy 345.224354 -225.186748)
			(xy 345.223844 -225.212735) (xy 345.363548 -225.212735) (xy 345.363548 -225.160761) (xy 345.371678 -225.109426)
			(xy 345.387739 -225.059996) (xy 345.411335 -225.013686) (xy 345.441885 -224.971638) (xy 345.478636 -224.934887)
			(xy 345.520684 -224.904337) (xy 345.566994 -224.880741) (xy 345.616424 -224.86468) (xy 345.667759 -224.85655)
			(xy 345.719733 -224.85655) (xy 345.771068 -224.86468) (xy 345.820498 -224.880741) (xy 345.866808 -224.904337)
			(xy 345.908856 -224.934887) (xy 345.945607 -224.971638) (xy 345.976157 -225.013686) (xy 345.999753 -225.059996)
			(xy 346.015814 -225.109426) (xy 346.023944 -225.160761) (xy 346.024454 -225.186748) (xy 346.023944 -225.212735)
			(xy 346.163394 -225.212735) (xy 346.163394 -225.160761) (xy 346.171524 -225.109426) (xy 346.187585 -225.059996)
			(xy 346.211181 -225.013686) (xy 346.241731 -224.971638) (xy 346.278482 -224.934887) (xy 346.32053 -224.904337)
			(xy 346.36684 -224.880741) (xy 346.41627 -224.86468) (xy 346.467605 -224.85655) (xy 346.519579 -224.85655)
			(xy 346.570914 -224.86468) (xy 346.620344 -224.880741) (xy 346.666654 -224.904337) (xy 346.708702 -224.934887)
			(xy 346.745453 -224.971638) (xy 346.776003 -225.013686) (xy 346.799599 -225.059996) (xy 346.81566 -225.109426)
			(xy 346.82379 -225.160761) (xy 346.8243 -225.186748) (xy 346.82379 -225.212735) (xy 346.81566 -225.26407)
			(xy 346.799599 -225.3135) (xy 346.776003 -225.35981) (xy 346.745453 -225.401858) (xy 346.708702 -225.438609)
			(xy 346.666654 -225.469159) (xy 346.620344 -225.492755) (xy 346.570914 -225.508816) (xy 346.519579 -225.516946)
			(xy 346.467605 -225.516946) (xy 346.41627 -225.508816) (xy 346.36684 -225.492755) (xy 346.32053 -225.469159)
			(xy 346.278482 -225.438609) (xy 346.241731 -225.401858) (xy 346.211181 -225.35981) (xy 346.187585 -225.3135)
			(xy 346.171524 -225.26407) (xy 346.163394 -225.212735) (xy 346.023944 -225.212735) (xy 346.015814 -225.26407)
			(xy 345.999753 -225.3135) (xy 345.976157 -225.35981) (xy 345.945607 -225.401858) (xy 345.908856 -225.438609)
			(xy 345.866808 -225.469159) (xy 345.820498 -225.492755) (xy 345.771068 -225.508816) (xy 345.719733 -225.516946)
			(xy 345.667759 -225.516946) (xy 345.616424 -225.508816) (xy 345.566994 -225.492755) (xy 345.520684 -225.469159)
			(xy 345.478636 -225.438609) (xy 345.441885 -225.401858) (xy 345.411335 -225.35981) (xy 345.387739 -225.3135)
			(xy 345.371678 -225.26407) (xy 345.363548 -225.212735) (xy 345.223844 -225.212735) (xy 345.215714 -225.26407)
			(xy 345.199653 -225.3135) (xy 345.176057 -225.35981) (xy 345.145507 -225.401858) (xy 345.108756 -225.438609)
			(xy 345.066708 -225.469159) (xy 345.020398 -225.492755) (xy 344.970968 -225.508816) (xy 344.919633 -225.516946)
			(xy 344.867659 -225.516946) (xy 344.816324 -225.508816) (xy 344.766894 -225.492755) (xy 344.720584 -225.469159)
			(xy 344.678536 -225.438609) (xy 344.641785 -225.401858) (xy 344.611235 -225.35981) (xy 344.587639 -225.3135)
			(xy 344.571578 -225.26407) (xy 344.563448 -225.212735) (xy 344.423744 -225.212735) (xy 344.415614 -225.26407)
			(xy 344.399553 -225.3135) (xy 344.375957 -225.35981) (xy 344.345407 -225.401858) (xy 344.308656 -225.438609)
			(xy 344.266608 -225.469159) (xy 344.220298 -225.492755) (xy 344.170868 -225.508816) (xy 344.119533 -225.516946)
			(xy 344.067559 -225.516946) (xy 344.016224 -225.508816) (xy 343.966794 -225.492755) (xy 343.920484 -225.469159)
			(xy 343.878436 -225.438609) (xy 343.841685 -225.401858) (xy 343.811135 -225.35981) (xy 343.787539 -225.3135)
			(xy 343.771478 -225.26407) (xy 343.763348 -225.212735) (xy 343.623898 -225.212735) (xy 343.615768 -225.26407)
			(xy 343.599707 -225.3135) (xy 343.576111 -225.35981) (xy 343.545561 -225.401858) (xy 343.50881 -225.438609)
			(xy 343.466762 -225.469159) (xy 343.420452 -225.492755) (xy 343.371022 -225.508816) (xy 343.319687 -225.516946)
			(xy 343.267713 -225.516946) (xy 343.216378 -225.508816) (xy 343.166948 -225.492755) (xy 343.120638 -225.469159)
			(xy 343.07859 -225.438609) (xy 343.041839 -225.401858) (xy 343.011289 -225.35981) (xy 342.987693 -225.3135)
			(xy 342.971632 -225.26407) (xy 342.963502 -225.212735) (xy 342.024206 -225.212735) (xy 342.016076 -225.26407)
			(xy 342.000015 -225.3135) (xy 341.976419 -225.35981) (xy 341.945869 -225.401858) (xy 341.909118 -225.438609)
			(xy 341.86707 -225.469159) (xy 341.82076 -225.492755) (xy 341.77133 -225.508816) (xy 341.719995 -225.516946)
			(xy 341.668021 -225.516946) (xy 341.616686 -225.508816) (xy 341.567256 -225.492755) (xy 341.520946 -225.469159)
			(xy 341.478898 -225.438609) (xy 341.442147 -225.401858) (xy 341.411597 -225.35981) (xy 341.388001 -225.3135)
			(xy 341.37194 -225.26407) (xy 341.36381 -225.212735) (xy 341.22436 -225.212735) (xy 341.21623 -225.26407)
			(xy 341.200169 -225.3135) (xy 341.176573 -225.35981) (xy 341.146023 -225.401858) (xy 341.109272 -225.438609)
			(xy 341.067224 -225.469159) (xy 341.020914 -225.492755) (xy 340.971484 -225.508816) (xy 340.920149 -225.516946)
			(xy 340.868175 -225.516946) (xy 340.81684 -225.508816) (xy 340.76741 -225.492755) (xy 340.7211 -225.469159)
			(xy 340.679052 -225.438609) (xy 340.642301 -225.401858) (xy 340.611751 -225.35981) (xy 340.588155 -225.3135)
			(xy 340.572094 -225.26407) (xy 340.563964 -225.212735) (xy 340.42426 -225.212735) (xy 340.41613 -225.26407)
			(xy 340.400069 -225.3135) (xy 340.376473 -225.35981) (xy 340.345923 -225.401858) (xy 340.309172 -225.438609)
			(xy 340.267124 -225.469159) (xy 340.220814 -225.492755) (xy 340.171384 -225.508816) (xy 340.120049 -225.516946)
			(xy 340.068075 -225.516946) (xy 340.01674 -225.508816) (xy 339.96731 -225.492755) (xy 339.921 -225.469159)
			(xy 339.878952 -225.438609) (xy 339.842201 -225.401858) (xy 339.811651 -225.35981) (xy 339.788055 -225.3135)
			(xy 339.771994 -225.26407) (xy 339.763864 -225.212735) (xy 339.62416 -225.212735) (xy 339.61603 -225.26407)
			(xy 339.599969 -225.3135) (xy 339.576373 -225.35981) (xy 339.545823 -225.401858) (xy 339.509072 -225.438609)
			(xy 339.467024 -225.469159) (xy 339.420714 -225.492755) (xy 339.371284 -225.508816) (xy 339.319949 -225.516946)
			(xy 339.267975 -225.516946) (xy 339.21664 -225.508816) (xy 339.16721 -225.492755) (xy 339.1209 -225.469159)
			(xy 339.078852 -225.438609) (xy 339.042101 -225.401858) (xy 339.011551 -225.35981) (xy 338.987955 -225.3135)
			(xy 338.971894 -225.26407) (xy 338.963764 -225.212735) (xy 338.824314 -225.212735) (xy 338.816184 -225.26407)
			(xy 338.800123 -225.3135) (xy 338.776527 -225.35981) (xy 338.745977 -225.401858) (xy 338.709226 -225.438609)
			(xy 338.667178 -225.469159) (xy 338.620868 -225.492755) (xy 338.571438 -225.508816) (xy 338.520103 -225.516946)
			(xy 338.468129 -225.516946) (xy 338.416794 -225.508816) (xy 338.367364 -225.492755) (xy 338.321054 -225.469159)
			(xy 338.279006 -225.438609) (xy 338.242255 -225.401858) (xy 338.211705 -225.35981) (xy 338.188109 -225.3135)
			(xy 338.172048 -225.26407) (xy 338.163918 -225.212735) (xy 338.024214 -225.212735) (xy 338.016084 -225.26407)
			(xy 338.000023 -225.3135) (xy 337.976427 -225.35981) (xy 337.945877 -225.401858) (xy 337.909126 -225.438609)
			(xy 337.867078 -225.469159) (xy 337.820768 -225.492755) (xy 337.771338 -225.508816) (xy 337.720003 -225.516946)
			(xy 337.668029 -225.516946) (xy 337.616694 -225.508816) (xy 337.567264 -225.492755) (xy 337.520954 -225.469159)
			(xy 337.478906 -225.438609) (xy 337.442155 -225.401858) (xy 337.411605 -225.35981) (xy 337.388009 -225.3135)
			(xy 337.371948 -225.26407) (xy 337.363818 -225.212735) (xy 337.223242 -225.212735) (xy 337.221377 -225.237082)
			(xy 337.209907 -225.28626) (xy 337.19109 -225.333121) (xy 337.165365 -225.376575) (xy 337.133329 -225.415611)
			(xy 337.114896 -225.432874) (xy 337.107022 -225.439986) (xy 337.094068 -225.468688) (xy 337.089496 -225.478848)
			(xy 337.089496 -225.678492) (xy 337.090766 -225.68916) (xy 337.093052 -225.699574) (xy 337.096354 -225.709734)
			(xy 337.107022 -225.73361) (xy 337.114896 -225.740722) (xy 337.133374 -225.757936) (xy 337.165402 -225.796977)
			(xy 337.191118 -225.840436) (xy 337.209926 -225.887301) (xy 337.221386 -225.936481) (xy 337.225233 -225.986832)
			(xy 337.223242 -226.012835) (xy 337.363818 -226.012835) (xy 337.363818 -225.960861) (xy 337.371948 -225.909526)
			(xy 337.388009 -225.860096) (xy 337.411605 -225.813786) (xy 337.442155 -225.771738) (xy 337.478906 -225.734987)
			(xy 337.520954 -225.704437) (xy 337.567264 -225.680841) (xy 337.616694 -225.66478) (xy 337.668029 -225.65665)
			(xy 337.720003 -225.65665) (xy 337.771338 -225.66478) (xy 337.820768 -225.680841) (xy 337.867078 -225.704437)
			(xy 337.909126 -225.734987) (xy 337.945877 -225.771738) (xy 337.976427 -225.813786) (xy 338.000023 -225.860096)
			(xy 338.016084 -225.909526) (xy 338.024214 -225.960861) (xy 338.024724 -225.986848) (xy 338.024214 -226.012835)
			(xy 338.163918 -226.012835) (xy 338.163918 -225.960861) (xy 338.172048 -225.909526) (xy 338.188109 -225.860096)
			(xy 338.211705 -225.813786) (xy 338.242255 -225.771738) (xy 338.279006 -225.734987) (xy 338.321054 -225.704437)
			(xy 338.367364 -225.680841) (xy 338.416794 -225.66478) (xy 338.468129 -225.65665) (xy 338.520103 -225.65665)
			(xy 338.571438 -225.66478) (xy 338.620868 -225.680841) (xy 338.667178 -225.704437) (xy 338.709226 -225.734987)
			(xy 338.745977 -225.771738) (xy 338.776527 -225.813786) (xy 338.800123 -225.860096) (xy 338.816184 -225.909526)
			(xy 338.824314 -225.960861) (xy 338.824824 -225.986848) (xy 338.824314 -226.012835) (xy 338.963764 -226.012835)
			(xy 338.963764 -225.960861) (xy 338.971894 -225.909526) (xy 338.987955 -225.860096) (xy 339.011551 -225.813786)
			(xy 339.042101 -225.771738) (xy 339.078852 -225.734987) (xy 339.1209 -225.704437) (xy 339.16721 -225.680841)
			(xy 339.21664 -225.66478) (xy 339.267975 -225.65665) (xy 339.319949 -225.65665) (xy 339.371284 -225.66478)
			(xy 339.420714 -225.680841) (xy 339.467024 -225.704437) (xy 339.509072 -225.734987) (xy 339.545823 -225.771738)
			(xy 339.576373 -225.813786) (xy 339.599969 -225.860096) (xy 339.61603 -225.909526) (xy 339.62416 -225.960861)
			(xy 339.62467 -225.986848) (xy 339.62416 -226.012835) (xy 339.62412 -226.013089) (xy 339.76361 -226.013089)
			(xy 339.76361 -225.961115) (xy 339.77174 -225.90978) (xy 339.787801 -225.86035) (xy 339.811397 -225.81404)
			(xy 339.841947 -225.771992) (xy 339.878698 -225.735241) (xy 339.920746 -225.704691) (xy 339.967056 -225.681095)
			(xy 340.016486 -225.665034) (xy 340.067821 -225.656904) (xy 340.119795 -225.656904) (xy 340.17113 -225.665034)
			(xy 340.22056 -225.681095) (xy 340.26687 -225.704691) (xy 340.308918 -225.735241) (xy 340.345669 -225.771992)
			(xy 340.376219 -225.81404) (xy 340.399815 -225.86035) (xy 340.415876 -225.90978) (xy 340.424006 -225.961115)
			(xy 340.424516 -225.987102) (xy 340.424011 -226.012835) (xy 340.563964 -226.012835) (xy 340.563964 -225.960861)
			(xy 340.572094 -225.909526) (xy 340.588155 -225.860096) (xy 340.611751 -225.813786) (xy 340.642301 -225.771738)
			(xy 340.679052 -225.734987) (xy 340.7211 -225.704437) (xy 340.76741 -225.680841) (xy 340.81684 -225.66478)
			(xy 340.868175 -225.65665) (xy 340.920149 -225.65665) (xy 340.971484 -225.66478) (xy 341.020914 -225.680841)
			(xy 341.067224 -225.704437) (xy 341.109272 -225.734987) (xy 341.146023 -225.771738) (xy 341.176573 -225.813786)
			(xy 341.200169 -225.860096) (xy 341.21623 -225.909526) (xy 341.22436 -225.960861) (xy 341.22487 -225.986848)
			(xy 341.22436 -226.012835) (xy 341.36381 -226.012835) (xy 341.36381 -225.960861) (xy 341.37194 -225.909526)
			(xy 341.388001 -225.860096) (xy 341.411597 -225.813786) (xy 341.442147 -225.771738) (xy 341.478898 -225.734987)
			(xy 341.520946 -225.704437) (xy 341.567256 -225.680841) (xy 341.616686 -225.66478) (xy 341.668021 -225.65665)
			(xy 341.719995 -225.65665) (xy 341.77133 -225.66478) (xy 341.82076 -225.680841) (xy 341.86707 -225.704437)
			(xy 341.909118 -225.734987) (xy 341.945869 -225.771738) (xy 341.976419 -225.813786) (xy 342.000015 -225.860096)
			(xy 342.016076 -225.909526) (xy 342.024206 -225.960861) (xy 342.024716 -225.986848) (xy 342.024206 -226.012835)
			(xy 342.963502 -226.012835) (xy 342.963502 -225.960861) (xy 342.971632 -225.909526) (xy 342.987693 -225.860096)
			(xy 343.011289 -225.813786) (xy 343.041839 -225.771738) (xy 343.07859 -225.734987) (xy 343.120638 -225.704437)
			(xy 343.166948 -225.680841) (xy 343.216378 -225.66478) (xy 343.267713 -225.65665) (xy 343.319687 -225.65665)
			(xy 343.371022 -225.66478) (xy 343.420452 -225.680841) (xy 343.466762 -225.704437) (xy 343.50881 -225.734987)
			(xy 343.545561 -225.771738) (xy 343.576111 -225.813786) (xy 343.599707 -225.860096) (xy 343.615768 -225.909526)
			(xy 343.623898 -225.960861) (xy 343.624408 -225.986848) (xy 343.623898 -226.012835) (xy 343.763348 -226.012835)
			(xy 343.763348 -225.960861) (xy 343.771478 -225.909526) (xy 343.787539 -225.860096) (xy 343.811135 -225.813786)
			(xy 343.841685 -225.771738) (xy 343.878436 -225.734987) (xy 343.920484 -225.704437) (xy 343.966794 -225.680841)
			(xy 344.016224 -225.66478) (xy 344.067559 -225.65665) (xy 344.119533 -225.65665) (xy 344.170868 -225.66478)
			(xy 344.220298 -225.680841) (xy 344.266608 -225.704437) (xy 344.308656 -225.734987) (xy 344.345407 -225.771738)
			(xy 344.375957 -225.813786) (xy 344.399553 -225.860096) (xy 344.415614 -225.909526) (xy 344.423744 -225.960861)
			(xy 344.424254 -225.986848) (xy 344.423744 -226.012835) (xy 344.423704 -226.013089) (xy 344.563702 -226.013089)
			(xy 344.563702 -225.961115) (xy 344.571832 -225.90978) (xy 344.587893 -225.86035) (xy 344.611489 -225.81404)
			(xy 344.642039 -225.771992) (xy 344.67879 -225.735241) (xy 344.720838 -225.704691) (xy 344.767148 -225.681095)
			(xy 344.816578 -225.665034) (xy 344.867913 -225.656904) (xy 344.919887 -225.656904) (xy 344.971222 -225.665034)
			(xy 345.020652 -225.681095) (xy 345.066962 -225.704691) (xy 345.10901 -225.735241) (xy 345.145761 -225.771992)
			(xy 345.176311 -225.81404) (xy 345.199907 -225.86035) (xy 345.215968 -225.90978) (xy 345.224098 -225.961115)
			(xy 345.224608 -225.987102) (xy 345.224103 -226.012835) (xy 345.363548 -226.012835) (xy 345.363548 -225.960861)
			(xy 345.371678 -225.909526) (xy 345.387739 -225.860096) (xy 345.411335 -225.813786) (xy 345.441885 -225.771738)
			(xy 345.478636 -225.734987) (xy 345.520684 -225.704437) (xy 345.566994 -225.680841) (xy 345.616424 -225.66478)
			(xy 345.667759 -225.65665) (xy 345.719733 -225.65665) (xy 345.771068 -225.66478) (xy 345.820498 -225.680841)
			(xy 345.866808 -225.704437) (xy 345.908856 -225.734987) (xy 345.945607 -225.771738) (xy 345.976157 -225.813786)
			(xy 345.999753 -225.860096) (xy 346.015814 -225.909526) (xy 346.023944 -225.960861) (xy 346.024454 -225.986848)
			(xy 346.023944 -226.012835) (xy 346.163394 -226.012835) (xy 346.163394 -225.960861) (xy 346.171524 -225.909526)
			(xy 346.187585 -225.860096) (xy 346.211181 -225.813786) (xy 346.241731 -225.771738) (xy 346.278482 -225.734987)
			(xy 346.32053 -225.704437) (xy 346.36684 -225.680841) (xy 346.41627 -225.66478) (xy 346.467605 -225.65665)
			(xy 346.519579 -225.65665) (xy 346.570914 -225.66478) (xy 346.620344 -225.680841) (xy 346.666654 -225.704437)
			(xy 346.708702 -225.734987) (xy 346.745453 -225.771738) (xy 346.776003 -225.813786) (xy 346.799599 -225.860096)
			(xy 346.81566 -225.909526) (xy 346.82379 -225.960861) (xy 346.8243 -225.986848) (xy 346.82379 -226.012835)
			(xy 346.963494 -226.012835) (xy 346.963494 -225.960861) (xy 346.971624 -225.909526) (xy 346.987685 -225.860096)
			(xy 347.011281 -225.813786) (xy 347.041831 -225.771738) (xy 347.078582 -225.734987) (xy 347.12063 -225.704437)
			(xy 347.16694 -225.680841) (xy 347.21637 -225.66478) (xy 347.267705 -225.65665) (xy 347.319679 -225.65665)
			(xy 347.371014 -225.66478) (xy 347.420444 -225.680841) (xy 347.466754 -225.704437) (xy 347.508802 -225.734987)
			(xy 347.545553 -225.771738) (xy 347.576103 -225.813786) (xy 347.599699 -225.860096) (xy 347.61576 -225.909526)
			(xy 347.62389 -225.960861) (xy 347.6244 -225.986848) (xy 347.62389 -226.012835) (xy 347.76334 -226.012835)
			(xy 347.76334 -225.960861) (xy 347.77147 -225.909526) (xy 347.787531 -225.860096) (xy 347.811127 -225.813786)
			(xy 347.841677 -225.771738) (xy 347.878428 -225.734987) (xy 347.920476 -225.704437) (xy 347.966786 -225.680841)
			(xy 348.016216 -225.66478) (xy 348.067551 -225.65665) (xy 348.119525 -225.65665) (xy 348.17086 -225.66478)
			(xy 348.22029 -225.680841) (xy 348.2666 -225.704437) (xy 348.308648 -225.734987) (xy 348.345399 -225.771738)
			(xy 348.375949 -225.813786) (xy 348.399545 -225.860096) (xy 348.415606 -225.909526) (xy 348.423736 -225.960861)
			(xy 348.424246 -225.986848) (xy 348.423736 -226.012835) (xy 348.423696 -226.013089) (xy 348.563694 -226.013089)
			(xy 348.563694 -225.961115) (xy 348.571824 -225.90978) (xy 348.587885 -225.86035) (xy 348.611481 -225.81404)
			(xy 348.642031 -225.771992) (xy 348.678782 -225.735241) (xy 348.72083 -225.704691) (xy 348.76714 -225.681095)
			(xy 348.81657 -225.665034) (xy 348.867905 -225.656904) (xy 348.919879 -225.656904) (xy 348.971214 -225.665034)
			(xy 349.020644 -225.681095) (xy 349.066954 -225.704691) (xy 349.109002 -225.735241) (xy 349.145753 -225.771992)
			(xy 349.176303 -225.81404) (xy 349.199899 -225.86035) (xy 349.21596 -225.90978) (xy 349.22409 -225.961115)
			(xy 349.2246 -225.987102) (xy 349.224095 -226.012835) (xy 349.36354 -226.012835) (xy 349.36354 -225.960861)
			(xy 349.37167 -225.909526) (xy 349.387731 -225.860096) (xy 349.411327 -225.813786) (xy 349.441877 -225.771738)
			(xy 349.478628 -225.734987) (xy 349.520676 -225.704437) (xy 349.566986 -225.680841) (xy 349.616416 -225.66478)
			(xy 349.667751 -225.65665) (xy 349.719725 -225.65665) (xy 349.77106 -225.66478) (xy 349.82049 -225.680841)
			(xy 349.8668 -225.704437) (xy 349.908848 -225.734987) (xy 349.945599 -225.771738) (xy 349.976149 -225.813786)
			(xy 349.999745 -225.860096) (xy 350.015806 -225.909526) (xy 350.023936 -225.960861) (xy 350.024446 -225.986848)
			(xy 350.023936 -226.012835) (xy 350.163386 -226.012835) (xy 350.163386 -225.960861) (xy 350.171516 -225.909526)
			(xy 350.187577 -225.860096) (xy 350.211173 -225.813786) (xy 350.241723 -225.771738) (xy 350.278474 -225.734987)
			(xy 350.320522 -225.704437) (xy 350.366832 -225.680841) (xy 350.416262 -225.66478) (xy 350.467597 -225.65665)
			(xy 350.519571 -225.65665) (xy 350.570906 -225.66478) (xy 350.620336 -225.680841) (xy 350.666646 -225.704437)
			(xy 350.708694 -225.734987) (xy 350.745445 -225.771738) (xy 350.775995 -225.813786) (xy 350.799591 -225.860096)
			(xy 350.815652 -225.909526) (xy 350.823782 -225.960861) (xy 350.824292 -225.986848) (xy 350.823782 -226.012835)
			(xy 350.963486 -226.012835) (xy 350.963486 -225.960861) (xy 350.971616 -225.909526) (xy 350.987677 -225.860096)
			(xy 351.011273 -225.813786) (xy 351.041823 -225.771738) (xy 351.078574 -225.734987) (xy 351.120622 -225.704437)
			(xy 351.166932 -225.680841) (xy 351.216362 -225.66478) (xy 351.267697 -225.65665) (xy 351.319671 -225.65665)
			(xy 351.371006 -225.66478) (xy 351.420436 -225.680841) (xy 351.466746 -225.704437) (xy 351.508794 -225.734987)
			(xy 351.545545 -225.771738) (xy 351.576095 -225.813786) (xy 351.599691 -225.860096) (xy 351.615752 -225.909526)
			(xy 351.623882 -225.960861) (xy 351.624392 -225.986848) (xy 351.623882 -226.012835) (xy 351.615752 -226.06417)
			(xy 351.599691 -226.1136) (xy 351.576095 -226.15991) (xy 351.545545 -226.201958) (xy 351.508794 -226.238709)
			(xy 351.466746 -226.269259) (xy 351.420436 -226.292855) (xy 351.371006 -226.308916) (xy 351.319671 -226.317046)
			(xy 351.267697 -226.317046) (xy 351.216362 -226.308916) (xy 351.166932 -226.292855) (xy 351.120622 -226.269259)
			(xy 351.078574 -226.238709) (xy 351.041823 -226.201958) (xy 351.011273 -226.15991) (xy 350.987677 -226.1136)
			(xy 350.971616 -226.06417) (xy 350.963486 -226.012835) (xy 350.823782 -226.012835) (xy 350.815652 -226.06417)
			(xy 350.799591 -226.1136) (xy 350.775995 -226.15991) (xy 350.745445 -226.201958) (xy 350.708694 -226.238709)
			(xy 350.666646 -226.269259) (xy 350.620336 -226.292855) (xy 350.570906 -226.308916) (xy 350.519571 -226.317046)
			(xy 350.467597 -226.317046) (xy 350.416262 -226.308916) (xy 350.366832 -226.292855) (xy 350.320522 -226.269259)
			(xy 350.278474 -226.238709) (xy 350.241723 -226.201958) (xy 350.211173 -226.15991) (xy 350.187577 -226.1136)
			(xy 350.171516 -226.06417) (xy 350.163386 -226.012835) (xy 350.023936 -226.012835) (xy 350.015806 -226.06417)
			(xy 349.999745 -226.1136) (xy 349.976149 -226.15991) (xy 349.945599 -226.201958) (xy 349.908848 -226.238709)
			(xy 349.8668 -226.269259) (xy 349.82049 -226.292855) (xy 349.77106 -226.308916) (xy 349.719725 -226.317046)
			(xy 349.667751 -226.317046) (xy 349.616416 -226.308916) (xy 349.566986 -226.292855) (xy 349.520676 -226.269259)
			(xy 349.478628 -226.238709) (xy 349.441877 -226.201958) (xy 349.411327 -226.15991) (xy 349.387731 -226.1136)
			(xy 349.37167 -226.06417) (xy 349.36354 -226.012835) (xy 349.224095 -226.012835) (xy 349.22409 -226.013089)
			(xy 349.21596 -226.064424) (xy 349.199899 -226.113854) (xy 349.176303 -226.160164) (xy 349.145753 -226.202212)
			(xy 349.109002 -226.238963) (xy 349.066954 -226.269513) (xy 349.020644 -226.293109) (xy 348.971214 -226.30917)
			(xy 348.919879 -226.3173) (xy 348.867905 -226.3173) (xy 348.81657 -226.30917) (xy 348.76714 -226.293109)
			(xy 348.72083 -226.269513) (xy 348.678782 -226.238963) (xy 348.642031 -226.202212) (xy 348.611481 -226.160164)
			(xy 348.587885 -226.113854) (xy 348.571824 -226.064424) (xy 348.563694 -226.013089) (xy 348.423696 -226.013089)
			(xy 348.415606 -226.06417) (xy 348.399545 -226.1136) (xy 348.375949 -226.15991) (xy 348.345399 -226.201958)
			(xy 348.308648 -226.238709) (xy 348.2666 -226.269259) (xy 348.22029 -226.292855) (xy 348.17086 -226.308916)
			(xy 348.119525 -226.317046) (xy 348.067551 -226.317046) (xy 348.016216 -226.308916) (xy 347.966786 -226.292855)
			(xy 347.920476 -226.269259) (xy 347.878428 -226.238709) (xy 347.841677 -226.201958) (xy 347.811127 -226.15991)
			(xy 347.787531 -226.1136) (xy 347.77147 -226.06417) (xy 347.76334 -226.012835) (xy 347.62389 -226.012835)
			(xy 347.61576 -226.06417) (xy 347.599699 -226.1136) (xy 347.576103 -226.15991) (xy 347.545553 -226.201958)
			(xy 347.508802 -226.238709) (xy 347.466754 -226.269259) (xy 347.420444 -226.292855) (xy 347.371014 -226.308916)
			(xy 347.319679 -226.317046) (xy 347.267705 -226.317046) (xy 347.21637 -226.308916) (xy 347.16694 -226.292855)
			(xy 347.12063 -226.269259) (xy 347.078582 -226.238709) (xy 347.041831 -226.201958) (xy 347.011281 -226.15991)
			(xy 346.987685 -226.1136) (xy 346.971624 -226.06417) (xy 346.963494 -226.012835) (xy 346.82379 -226.012835)
			(xy 346.81566 -226.06417) (xy 346.799599 -226.1136) (xy 346.776003 -226.15991) (xy 346.745453 -226.201958)
			(xy 346.708702 -226.238709) (xy 346.666654 -226.269259) (xy 346.620344 -226.292855) (xy 346.570914 -226.308916)
			(xy 346.519579 -226.317046) (xy 346.467605 -226.317046) (xy 346.41627 -226.308916) (xy 346.36684 -226.292855)
			(xy 346.32053 -226.269259) (xy 346.278482 -226.238709) (xy 346.241731 -226.201958) (xy 346.211181 -226.15991)
			(xy 346.187585 -226.1136) (xy 346.171524 -226.06417) (xy 346.163394 -226.012835) (xy 346.023944 -226.012835)
			(xy 346.015814 -226.06417) (xy 345.999753 -226.1136) (xy 345.976157 -226.15991) (xy 345.945607 -226.201958)
			(xy 345.908856 -226.238709) (xy 345.866808 -226.269259) (xy 345.820498 -226.292855) (xy 345.771068 -226.308916)
			(xy 345.719733 -226.317046) (xy 345.667759 -226.317046) (xy 345.616424 -226.308916) (xy 345.566994 -226.292855)
			(xy 345.520684 -226.269259) (xy 345.478636 -226.238709) (xy 345.441885 -226.201958) (xy 345.411335 -226.15991)
			(xy 345.387739 -226.1136) (xy 345.371678 -226.06417) (xy 345.363548 -226.012835) (xy 345.224103 -226.012835)
			(xy 345.224098 -226.013089) (xy 345.215968 -226.064424) (xy 345.199907 -226.113854) (xy 345.176311 -226.160164)
			(xy 345.145761 -226.202212) (xy 345.10901 -226.238963) (xy 345.066962 -226.269513) (xy 345.020652 -226.293109)
			(xy 344.971222 -226.30917) (xy 344.919887 -226.3173) (xy 344.867913 -226.3173) (xy 344.816578 -226.30917)
			(xy 344.767148 -226.293109) (xy 344.720838 -226.269513) (xy 344.67879 -226.238963) (xy 344.642039 -226.202212)
			(xy 344.611489 -226.160164) (xy 344.587893 -226.113854) (xy 344.571832 -226.064424) (xy 344.563702 -226.013089)
			(xy 344.423704 -226.013089) (xy 344.415614 -226.06417) (xy 344.399553 -226.1136) (xy 344.375957 -226.15991)
			(xy 344.345407 -226.201958) (xy 344.308656 -226.238709) (xy 344.266608 -226.269259) (xy 344.220298 -226.292855)
			(xy 344.170868 -226.308916) (xy 344.119533 -226.317046) (xy 344.067559 -226.317046) (xy 344.016224 -226.308916)
			(xy 343.966794 -226.292855) (xy 343.920484 -226.269259) (xy 343.878436 -226.238709) (xy 343.841685 -226.201958)
			(xy 343.811135 -226.15991) (xy 343.787539 -226.1136) (xy 343.771478 -226.06417) (xy 343.763348 -226.012835)
			(xy 343.623898 -226.012835) (xy 343.615768 -226.06417) (xy 343.599707 -226.1136) (xy 343.576111 -226.15991)
			(xy 343.545561 -226.201958) (xy 343.50881 -226.238709) (xy 343.466762 -226.269259) (xy 343.420452 -226.292855)
			(xy 343.371022 -226.308916) (xy 343.319687 -226.317046) (xy 343.267713 -226.317046) (xy 343.216378 -226.308916)
			(xy 343.166948 -226.292855) (xy 343.120638 -226.269259) (xy 343.07859 -226.238709) (xy 343.041839 -226.201958)
			(xy 343.011289 -226.15991) (xy 342.987693 -226.1136) (xy 342.971632 -226.06417) (xy 342.963502 -226.012835)
			(xy 342.024206 -226.012835) (xy 342.016076 -226.06417) (xy 342.000015 -226.1136) (xy 341.976419 -226.15991)
			(xy 341.945869 -226.201958) (xy 341.909118 -226.238709) (xy 341.86707 -226.269259) (xy 341.82076 -226.292855)
			(xy 341.77133 -226.308916) (xy 341.719995 -226.317046) (xy 341.668021 -226.317046) (xy 341.616686 -226.308916)
			(xy 341.567256 -226.292855) (xy 341.520946 -226.269259) (xy 341.478898 -226.238709) (xy 341.442147 -226.201958)
			(xy 341.411597 -226.15991) (xy 341.388001 -226.1136) (xy 341.37194 -226.06417) (xy 341.36381 -226.012835)
			(xy 341.22436 -226.012835) (xy 341.21623 -226.06417) (xy 341.200169 -226.1136) (xy 341.176573 -226.15991)
			(xy 341.146023 -226.201958) (xy 341.109272 -226.238709) (xy 341.067224 -226.269259) (xy 341.020914 -226.292855)
			(xy 340.971484 -226.308916) (xy 340.920149 -226.317046) (xy 340.868175 -226.317046) (xy 340.81684 -226.308916)
			(xy 340.76741 -226.292855) (xy 340.7211 -226.269259) (xy 340.679052 -226.238709) (xy 340.642301 -226.201958)
			(xy 340.611751 -226.15991) (xy 340.588155 -226.1136) (xy 340.572094 -226.06417) (xy 340.563964 -226.012835)
			(xy 340.424011 -226.012835) (xy 340.424006 -226.013089) (xy 340.415876 -226.064424) (xy 340.399815 -226.113854)
			(xy 340.376219 -226.160164) (xy 340.345669 -226.202212) (xy 340.308918 -226.238963) (xy 340.26687 -226.269513)
			(xy 340.22056 -226.293109) (xy 340.17113 -226.30917) (xy 340.119795 -226.3173) (xy 340.067821 -226.3173)
			(xy 340.016486 -226.30917) (xy 339.967056 -226.293109) (xy 339.920746 -226.269513) (xy 339.878698 -226.238963)
			(xy 339.841947 -226.202212) (xy 339.811397 -226.160164) (xy 339.787801 -226.113854) (xy 339.77174 -226.064424)
			(xy 339.76361 -226.013089) (xy 339.62412 -226.013089) (xy 339.61603 -226.06417) (xy 339.599969 -226.1136)
			(xy 339.576373 -226.15991) (xy 339.545823 -226.201958) (xy 339.509072 -226.238709) (xy 339.467024 -226.269259)
			(xy 339.420714 -226.292855) (xy 339.371284 -226.308916) (xy 339.319949 -226.317046) (xy 339.267975 -226.317046)
			(xy 339.21664 -226.308916) (xy 339.16721 -226.292855) (xy 339.1209 -226.269259) (xy 339.078852 -226.238709)
			(xy 339.042101 -226.201958) (xy 339.011551 -226.15991) (xy 338.987955 -226.1136) (xy 338.971894 -226.06417)
			(xy 338.963764 -226.012835) (xy 338.824314 -226.012835) (xy 338.816184 -226.06417) (xy 338.800123 -226.1136)
			(xy 338.776527 -226.15991) (xy 338.745977 -226.201958) (xy 338.709226 -226.238709) (xy 338.667178 -226.269259)
			(xy 338.620868 -226.292855) (xy 338.571438 -226.308916) (xy 338.520103 -226.317046) (xy 338.468129 -226.317046)
			(xy 338.416794 -226.308916) (xy 338.367364 -226.292855) (xy 338.321054 -226.269259) (xy 338.279006 -226.238709)
			(xy 338.242255 -226.201958) (xy 338.211705 -226.15991) (xy 338.188109 -226.1136) (xy 338.172048 -226.06417)
			(xy 338.163918 -226.012835) (xy 338.024214 -226.012835) (xy 338.016084 -226.06417) (xy 338.000023 -226.1136)
			(xy 337.976427 -226.15991) (xy 337.945877 -226.201958) (xy 337.909126 -226.238709) (xy 337.867078 -226.269259)
			(xy 337.820768 -226.292855) (xy 337.771338 -226.308916) (xy 337.720003 -226.317046) (xy 337.668029 -226.317046)
			(xy 337.616694 -226.308916) (xy 337.567264 -226.292855) (xy 337.520954 -226.269259) (xy 337.478906 -226.238709)
			(xy 337.442155 -226.201958) (xy 337.411605 -226.15991) (xy 337.388009 -226.1136) (xy 337.371948 -226.06417)
			(xy 337.363818 -226.012835) (xy 337.223242 -226.012835) (xy 337.221377 -226.037182) (xy 337.209907 -226.08636)
			(xy 337.19109 -226.133221) (xy 337.165365 -226.176675) (xy 337.133329 -226.215711) (xy 337.114896 -226.232974)
			(xy 337.107022 -226.240086) (xy 337.094068 -226.268788) (xy 337.089496 -226.278948) (xy 337.089496 -226.478592)
			(xy 337.090766 -226.48926) (xy 337.093052 -226.499674) (xy 337.096354 -226.509834) (xy 337.107022 -226.53371)
			(xy 337.114896 -226.540822) (xy 337.133638 -226.558308) (xy 337.166028 -226.598031) (xy 337.19191 -226.642272)
			(xy 337.210665 -226.689973) (xy 337.221845 -226.739994) (xy 337.225184 -226.79114) (xy 337.223227 -226.812935)
			(xy 337.363818 -226.812935) (xy 337.363818 -226.760961) (xy 337.371948 -226.709626) (xy 337.388009 -226.660196)
			(xy 337.411605 -226.613886) (xy 337.442155 -226.571838) (xy 337.478906 -226.535087) (xy 337.520954 -226.504537)
			(xy 337.567264 -226.480941) (xy 337.616694 -226.46488) (xy 337.668029 -226.45675) (xy 337.720003 -226.45675)
			(xy 337.771338 -226.46488) (xy 337.820768 -226.480941) (xy 337.867078 -226.504537) (xy 337.909126 -226.535087)
			(xy 337.945877 -226.571838) (xy 337.976427 -226.613886) (xy 338.000023 -226.660196) (xy 338.016084 -226.709626)
			(xy 338.024214 -226.760961) (xy 338.024724 -226.786948) (xy 338.024214 -226.812935) (xy 338.963764 -226.812935)
			(xy 338.963764 -226.760961) (xy 338.971894 -226.709626) (xy 338.987955 -226.660196) (xy 339.011551 -226.613886)
			(xy 339.042101 -226.571838) (xy 339.078852 -226.535087) (xy 339.1209 -226.504537) (xy 339.16721 -226.480941)
			(xy 339.21664 -226.46488) (xy 339.267975 -226.45675) (xy 339.319949 -226.45675) (xy 339.371284 -226.46488)
			(xy 339.420714 -226.480941) (xy 339.467024 -226.504537) (xy 339.509072 -226.535087) (xy 339.545823 -226.571838)
			(xy 339.576373 -226.613886) (xy 339.599969 -226.660196) (xy 339.61603 -226.709626) (xy 339.62416 -226.760961)
			(xy 339.62467 -226.786948) (xy 339.62416 -226.812935) (xy 339.763864 -226.812935) (xy 339.763864 -226.760961)
			(xy 339.771994 -226.709626) (xy 339.788055 -226.660196) (xy 339.811651 -226.613886) (xy 339.842201 -226.571838)
			(xy 339.878952 -226.535087) (xy 339.921 -226.504537) (xy 339.96731 -226.480941) (xy 340.01674 -226.46488)
			(xy 340.068075 -226.45675) (xy 340.120049 -226.45675) (xy 340.171384 -226.46488) (xy 340.220814 -226.480941)
			(xy 340.267124 -226.504537) (xy 340.309172 -226.535087) (xy 340.345923 -226.571838) (xy 340.376473 -226.613886)
			(xy 340.400069 -226.660196) (xy 340.41613 -226.709626) (xy 340.42426 -226.760961) (xy 340.42477 -226.786948)
			(xy 340.42426 -226.812935) (xy 340.563964 -226.812935) (xy 340.563964 -226.760961) (xy 340.572094 -226.709626)
			(xy 340.588155 -226.660196) (xy 340.611751 -226.613886) (xy 340.642301 -226.571838) (xy 340.679052 -226.535087)
			(xy 340.7211 -226.504537) (xy 340.76741 -226.480941) (xy 340.81684 -226.46488) (xy 340.868175 -226.45675)
			(xy 340.920149 -226.45675) (xy 340.971484 -226.46488) (xy 341.020914 -226.480941) (xy 341.067224 -226.504537)
			(xy 341.109272 -226.535087) (xy 341.146023 -226.571838) (xy 341.176573 -226.613886) (xy 341.200169 -226.660196)
			(xy 341.21623 -226.709626) (xy 341.22436 -226.760961) (xy 341.22487 -226.786948) (xy 341.22436 -226.812935)
			(xy 341.36381 -226.812935) (xy 341.36381 -226.760961) (xy 341.37194 -226.709626) (xy 341.388001 -226.660196)
			(xy 341.411597 -226.613886) (xy 341.442147 -226.571838) (xy 341.478898 -226.535087) (xy 341.520946 -226.504537)
			(xy 341.567256 -226.480941) (xy 341.616686 -226.46488) (xy 341.668021 -226.45675) (xy 341.719995 -226.45675)
			(xy 341.77133 -226.46488) (xy 341.82076 -226.480941) (xy 341.86707 -226.504537) (xy 341.909118 -226.535087)
			(xy 341.945869 -226.571838) (xy 341.976419 -226.613886) (xy 342.000015 -226.660196) (xy 342.016076 -226.709626)
			(xy 342.024206 -226.760961) (xy 342.024716 -226.786948) (xy 342.024206 -226.812935) (xy 343.763348 -226.812935)
			(xy 343.763348 -226.760961) (xy 343.771478 -226.709626) (xy 343.787539 -226.660196) (xy 343.811135 -226.613886)
			(xy 343.841685 -226.571838) (xy 343.878436 -226.535087) (xy 343.920484 -226.504537) (xy 343.966794 -226.480941)
			(xy 344.016224 -226.46488) (xy 344.067559 -226.45675) (xy 344.119533 -226.45675) (xy 344.170868 -226.46488)
			(xy 344.220298 -226.480941) (xy 344.266608 -226.504537) (xy 344.308656 -226.535087) (xy 344.345407 -226.571838)
			(xy 344.375957 -226.613886) (xy 344.399553 -226.660196) (xy 344.415614 -226.709626) (xy 344.423744 -226.760961)
			(xy 344.424254 -226.786948) (xy 344.423744 -226.812935) (xy 344.563448 -226.812935) (xy 344.563448 -226.760961)
			(xy 344.571578 -226.709626) (xy 344.587639 -226.660196) (xy 344.611235 -226.613886) (xy 344.641785 -226.571838)
			(xy 344.678536 -226.535087) (xy 344.720584 -226.504537) (xy 344.766894 -226.480941) (xy 344.816324 -226.46488)
			(xy 344.867659 -226.45675) (xy 344.919633 -226.45675) (xy 344.970968 -226.46488) (xy 345.020398 -226.480941)
			(xy 345.066708 -226.504537) (xy 345.108756 -226.535087) (xy 345.145507 -226.571838) (xy 345.176057 -226.613886)
			(xy 345.199653 -226.660196) (xy 345.215714 -226.709626) (xy 345.223844 -226.760961) (xy 345.224354 -226.786948)
			(xy 345.223844 -226.812935) (xy 345.363548 -226.812935) (xy 345.363548 -226.760961) (xy 345.371678 -226.709626)
			(xy 345.387739 -226.660196) (xy 345.411335 -226.613886) (xy 345.441885 -226.571838) (xy 345.478636 -226.535087)
			(xy 345.520684 -226.504537) (xy 345.566994 -226.480941) (xy 345.616424 -226.46488) (xy 345.667759 -226.45675)
			(xy 345.719733 -226.45675) (xy 345.771068 -226.46488) (xy 345.820498 -226.480941) (xy 345.866808 -226.504537)
			(xy 345.908856 -226.535087) (xy 345.945607 -226.571838) (xy 345.976157 -226.613886) (xy 345.999753 -226.660196)
			(xy 346.015814 -226.709626) (xy 346.023944 -226.760961) (xy 346.024454 -226.786948) (xy 346.023944 -226.812935)
			(xy 346.963494 -226.812935) (xy 346.963494 -226.760961) (xy 346.971624 -226.709626) (xy 346.987685 -226.660196)
			(xy 347.011281 -226.613886) (xy 347.041831 -226.571838) (xy 347.078582 -226.535087) (xy 347.12063 -226.504537)
			(xy 347.16694 -226.480941) (xy 347.21637 -226.46488) (xy 347.267705 -226.45675) (xy 347.319679 -226.45675)
			(xy 347.371014 -226.46488) (xy 347.420444 -226.480941) (xy 347.466754 -226.504537) (xy 347.508802 -226.535087)
			(xy 347.545553 -226.571838) (xy 347.576103 -226.613886) (xy 347.599699 -226.660196) (xy 347.61576 -226.709626)
			(xy 347.62389 -226.760961) (xy 347.6244 -226.786948) (xy 347.62389 -226.812935) (xy 347.76334 -226.812935)
			(xy 347.76334 -226.760961) (xy 347.77147 -226.709626) (xy 347.787531 -226.660196) (xy 347.811127 -226.613886)
			(xy 347.841677 -226.571838) (xy 347.878428 -226.535087) (xy 347.920476 -226.504537) (xy 347.966786 -226.480941)
			(xy 348.016216 -226.46488) (xy 348.067551 -226.45675) (xy 348.119525 -226.45675) (xy 348.17086 -226.46488)
			(xy 348.22029 -226.480941) (xy 348.2666 -226.504537) (xy 348.308648 -226.535087) (xy 348.345399 -226.571838)
			(xy 348.375949 -226.613886) (xy 348.399545 -226.660196) (xy 348.415606 -226.709626) (xy 348.423736 -226.760961)
			(xy 348.424246 -226.786948) (xy 348.423736 -226.812935) (xy 348.56344 -226.812935) (xy 348.56344 -226.760961)
			(xy 348.57157 -226.709626) (xy 348.587631 -226.660196) (xy 348.611227 -226.613886) (xy 348.641777 -226.571838)
			(xy 348.678528 -226.535087) (xy 348.720576 -226.504537) (xy 348.766886 -226.480941) (xy 348.816316 -226.46488)
			(xy 348.867651 -226.45675) (xy 348.919625 -226.45675) (xy 348.97096 -226.46488) (xy 349.02039 -226.480941)
			(xy 349.0667 -226.504537) (xy 349.108748 -226.535087) (xy 349.145499 -226.571838) (xy 349.176049 -226.613886)
			(xy 349.199645 -226.660196) (xy 349.215706 -226.709626) (xy 349.223836 -226.760961) (xy 349.224346 -226.786948)
			(xy 349.223836 -226.812935) (xy 349.36354 -226.812935) (xy 349.36354 -226.760961) (xy 349.37167 -226.709626)
			(xy 349.387731 -226.660196) (xy 349.411327 -226.613886) (xy 349.441877 -226.571838) (xy 349.478628 -226.535087)
			(xy 349.520676 -226.504537) (xy 349.566986 -226.480941) (xy 349.616416 -226.46488) (xy 349.667751 -226.45675)
			(xy 349.719725 -226.45675) (xy 349.77106 -226.46488) (xy 349.82049 -226.480941) (xy 349.8668 -226.504537)
			(xy 349.908848 -226.535087) (xy 349.945599 -226.571838) (xy 349.976149 -226.613886) (xy 349.999745 -226.660196)
			(xy 350.015806 -226.709626) (xy 350.023936 -226.760961) (xy 350.024446 -226.786948) (xy 350.023936 -226.812935)
			(xy 350.163386 -226.812935) (xy 350.163386 -226.760961) (xy 350.171516 -226.709626) (xy 350.187577 -226.660196)
			(xy 350.211173 -226.613886) (xy 350.241723 -226.571838) (xy 350.278474 -226.535087) (xy 350.320522 -226.504537)
			(xy 350.366832 -226.480941) (xy 350.416262 -226.46488) (xy 350.467597 -226.45675) (xy 350.519571 -226.45675)
			(xy 350.570906 -226.46488) (xy 350.620336 -226.480941) (xy 350.666646 -226.504537) (xy 350.708694 -226.535087)
			(xy 350.745445 -226.571838) (xy 350.775995 -226.613886) (xy 350.799591 -226.660196) (xy 350.815652 -226.709626)
			(xy 350.823782 -226.760961) (xy 350.824292 -226.786948) (xy 350.823782 -226.812935) (xy 350.963486 -226.812935)
			(xy 350.963486 -226.760961) (xy 350.971616 -226.709626) (xy 350.987677 -226.660196) (xy 351.011273 -226.613886)
			(xy 351.041823 -226.571838) (xy 351.078574 -226.535087) (xy 351.120622 -226.504537) (xy 351.166932 -226.480941)
			(xy 351.216362 -226.46488) (xy 351.267697 -226.45675) (xy 351.319671 -226.45675) (xy 351.371006 -226.46488)
			(xy 351.420436 -226.480941) (xy 351.466746 -226.504537) (xy 351.508794 -226.535087) (xy 351.545545 -226.571838)
			(xy 351.576095 -226.613886) (xy 351.599691 -226.660196) (xy 351.615752 -226.709626) (xy 351.623882 -226.760961)
			(xy 351.624392 -226.786948) (xy 351.623882 -226.812935) (xy 351.615752 -226.86427) (xy 351.599691 -226.9137)
			(xy 351.576095 -226.96001) (xy 351.545545 -227.002058) (xy 351.508794 -227.038809) (xy 351.466746 -227.069359)
			(xy 351.420436 -227.092955) (xy 351.371006 -227.109016) (xy 351.319671 -227.117146) (xy 351.267697 -227.117146)
			(xy 351.216362 -227.109016) (xy 351.166932 -227.092955) (xy 351.120622 -227.069359) (xy 351.078574 -227.038809)
			(xy 351.041823 -227.002058) (xy 351.011273 -226.96001) (xy 350.987677 -226.9137) (xy 350.971616 -226.86427)
			(xy 350.963486 -226.812935) (xy 350.823782 -226.812935) (xy 350.815652 -226.86427) (xy 350.799591 -226.9137)
			(xy 350.775995 -226.96001) (xy 350.745445 -227.002058) (xy 350.708694 -227.038809) (xy 350.666646 -227.069359)
			(xy 350.620336 -227.092955) (xy 350.570906 -227.109016) (xy 350.519571 -227.117146) (xy 350.467597 -227.117146)
			(xy 350.416262 -227.109016) (xy 350.366832 -227.092955) (xy 350.320522 -227.069359) (xy 350.278474 -227.038809)
			(xy 350.241723 -227.002058) (xy 350.211173 -226.96001) (xy 350.187577 -226.9137) (xy 350.171516 -226.86427)
			(xy 350.163386 -226.812935) (xy 350.023936 -226.812935) (xy 350.015806 -226.86427) (xy 349.999745 -226.9137)
			(xy 349.976149 -226.96001) (xy 349.945599 -227.002058) (xy 349.908848 -227.038809) (xy 349.8668 -227.069359)
			(xy 349.82049 -227.092955) (xy 349.77106 -227.109016) (xy 349.719725 -227.117146) (xy 349.667751 -227.117146)
			(xy 349.616416 -227.109016) (xy 349.566986 -227.092955) (xy 349.520676 -227.069359) (xy 349.478628 -227.038809)
			(xy 349.441877 -227.002058) (xy 349.411327 -226.96001) (xy 349.387731 -226.9137) (xy 349.37167 -226.86427)
			(xy 349.36354 -226.812935) (xy 349.223836 -226.812935) (xy 349.215706 -226.86427) (xy 349.199645 -226.9137)
			(xy 349.176049 -226.96001) (xy 349.145499 -227.002058) (xy 349.108748 -227.038809) (xy 349.0667 -227.069359)
			(xy 349.02039 -227.092955) (xy 348.97096 -227.109016) (xy 348.919625 -227.117146) (xy 348.867651 -227.117146)
			(xy 348.816316 -227.109016) (xy 348.766886 -227.092955) (xy 348.720576 -227.069359) (xy 348.678528 -227.038809)
			(xy 348.641777 -227.002058) (xy 348.611227 -226.96001) (xy 348.587631 -226.9137) (xy 348.57157 -226.86427)
			(xy 348.56344 -226.812935) (xy 348.423736 -226.812935) (xy 348.415606 -226.86427) (xy 348.399545 -226.9137)
			(xy 348.375949 -226.96001) (xy 348.345399 -227.002058) (xy 348.308648 -227.038809) (xy 348.2666 -227.069359)
			(xy 348.22029 -227.092955) (xy 348.17086 -227.109016) (xy 348.119525 -227.117146) (xy 348.067551 -227.117146)
			(xy 348.016216 -227.109016) (xy 347.966786 -227.092955) (xy 347.920476 -227.069359) (xy 347.878428 -227.038809)
			(xy 347.841677 -227.002058) (xy 347.811127 -226.96001) (xy 347.787531 -226.9137) (xy 347.77147 -226.86427)
			(xy 347.76334 -226.812935) (xy 347.62389 -226.812935) (xy 347.61576 -226.86427) (xy 347.599699 -226.9137)
			(xy 347.576103 -226.96001) (xy 347.545553 -227.002058) (xy 347.508802 -227.038809) (xy 347.466754 -227.069359)
			(xy 347.420444 -227.092955) (xy 347.371014 -227.109016) (xy 347.319679 -227.117146) (xy 347.267705 -227.117146)
			(xy 347.21637 -227.109016) (xy 347.16694 -227.092955) (xy 347.12063 -227.069359) (xy 347.078582 -227.038809)
			(xy 347.041831 -227.002058) (xy 347.011281 -226.96001) (xy 346.987685 -226.9137) (xy 346.971624 -226.86427)
			(xy 346.963494 -226.812935) (xy 346.023944 -226.812935) (xy 346.015814 -226.86427) (xy 345.999753 -226.9137)
			(xy 345.976157 -226.96001) (xy 345.945607 -227.002058) (xy 345.908856 -227.038809) (xy 345.866808 -227.069359)
			(xy 345.820498 -227.092955) (xy 345.771068 -227.109016) (xy 345.719733 -227.117146) (xy 345.667759 -227.117146)
			(xy 345.616424 -227.109016) (xy 345.566994 -227.092955) (xy 345.520684 -227.069359) (xy 345.478636 -227.038809)
			(xy 345.441885 -227.002058) (xy 345.411335 -226.96001) (xy 345.387739 -226.9137) (xy 345.371678 -226.86427)
			(xy 345.363548 -226.812935) (xy 345.223844 -226.812935) (xy 345.215714 -226.86427) (xy 345.199653 -226.9137)
			(xy 345.176057 -226.96001) (xy 345.145507 -227.002058) (xy 345.108756 -227.038809) (xy 345.066708 -227.069359)
			(xy 345.020398 -227.092955) (xy 344.970968 -227.109016) (xy 344.919633 -227.117146) (xy 344.867659 -227.117146)
			(xy 344.816324 -227.109016) (xy 344.766894 -227.092955) (xy 344.720584 -227.069359) (xy 344.678536 -227.038809)
			(xy 344.641785 -227.002058) (xy 344.611235 -226.96001) (xy 344.587639 -226.9137) (xy 344.571578 -226.86427)
			(xy 344.563448 -226.812935) (xy 344.423744 -226.812935) (xy 344.415614 -226.86427) (xy 344.399553 -226.9137)
			(xy 344.375957 -226.96001) (xy 344.345407 -227.002058) (xy 344.308656 -227.038809) (xy 344.266608 -227.069359)
			(xy 344.220298 -227.092955) (xy 344.170868 -227.109016) (xy 344.119533 -227.117146) (xy 344.067559 -227.117146)
			(xy 344.016224 -227.109016) (xy 343.966794 -227.092955) (xy 343.920484 -227.069359) (xy 343.878436 -227.038809)
			(xy 343.841685 -227.002058) (xy 343.811135 -226.96001) (xy 343.787539 -226.9137) (xy 343.771478 -226.86427)
			(xy 343.763348 -226.812935) (xy 342.024206 -226.812935) (xy 342.016076 -226.86427) (xy 342.000015 -226.9137)
			(xy 341.976419 -226.96001) (xy 341.945869 -227.002058) (xy 341.909118 -227.038809) (xy 341.86707 -227.069359)
			(xy 341.82076 -227.092955) (xy 341.77133 -227.109016) (xy 341.719995 -227.117146) (xy 341.668021 -227.117146)
			(xy 341.616686 -227.109016) (xy 341.567256 -227.092955) (xy 341.520946 -227.069359) (xy 341.478898 -227.038809)
			(xy 341.442147 -227.002058) (xy 341.411597 -226.96001) (xy 341.388001 -226.9137) (xy 341.37194 -226.86427)
			(xy 341.36381 -226.812935) (xy 341.22436 -226.812935) (xy 341.21623 -226.86427) (xy 341.200169 -226.9137)
			(xy 341.176573 -226.96001) (xy 341.146023 -227.002058) (xy 341.109272 -227.038809) (xy 341.067224 -227.069359)
			(xy 341.020914 -227.092955) (xy 340.971484 -227.109016) (xy 340.920149 -227.117146) (xy 340.868175 -227.117146)
			(xy 340.81684 -227.109016) (xy 340.76741 -227.092955) (xy 340.7211 -227.069359) (xy 340.679052 -227.038809)
			(xy 340.642301 -227.002058) (xy 340.611751 -226.96001) (xy 340.588155 -226.9137) (xy 340.572094 -226.86427)
			(xy 340.563964 -226.812935) (xy 340.42426 -226.812935) (xy 340.41613 -226.86427) (xy 340.400069 -226.9137)
			(xy 340.376473 -226.96001) (xy 340.345923 -227.002058) (xy 340.309172 -227.038809) (xy 340.267124 -227.069359)
			(xy 340.220814 -227.092955) (xy 340.171384 -227.109016) (xy 340.120049 -227.117146) (xy 340.068075 -227.117146)
			(xy 340.01674 -227.109016) (xy 339.96731 -227.092955) (xy 339.921 -227.069359) (xy 339.878952 -227.038809)
			(xy 339.842201 -227.002058) (xy 339.811651 -226.96001) (xy 339.788055 -226.9137) (xy 339.771994 -226.86427)
			(xy 339.763864 -226.812935) (xy 339.62416 -226.812935) (xy 339.61603 -226.86427) (xy 339.599969 -226.9137)
			(xy 339.576373 -226.96001) (xy 339.545823 -227.002058) (xy 339.509072 -227.038809) (xy 339.467024 -227.069359)
			(xy 339.420714 -227.092955) (xy 339.371284 -227.109016) (xy 339.319949 -227.117146) (xy 339.267975 -227.117146)
			(xy 339.21664 -227.109016) (xy 339.16721 -227.092955) (xy 339.1209 -227.069359) (xy 339.078852 -227.038809)
			(xy 339.042101 -227.002058) (xy 339.011551 -226.96001) (xy 338.987955 -226.9137) (xy 338.971894 -226.86427)
			(xy 338.963764 -226.812935) (xy 338.024214 -226.812935) (xy 338.016084 -226.86427) (xy 338.000023 -226.9137)
			(xy 337.976427 -226.96001) (xy 337.945877 -227.002058) (xy 337.909126 -227.038809) (xy 337.867078 -227.069359)
			(xy 337.820768 -227.092955) (xy 337.771338 -227.109016) (xy 337.720003 -227.117146) (xy 337.668029 -227.117146)
			(xy 337.616694 -227.109016) (xy 337.567264 -227.092955) (xy 337.520954 -227.069359) (xy 337.478906 -227.038809)
			(xy 337.442155 -227.002058) (xy 337.411605 -226.96001) (xy 337.388009 -226.9137) (xy 337.371948 -226.86427)
			(xy 337.363818 -226.812935) (xy 337.223227 -226.812935) (xy 337.2206 -226.84219) (xy 337.208205 -226.891924)
			(xy 337.188293 -226.939153) (xy 337.161341 -226.98275) (xy 337.127992 -227.021673) (xy 337.1088 -227.038662)
			(xy 337.107276 -227.039932) (xy 337.103974 -227.043234) (xy 337.100883 -227.046434) (xy 337.095779 -227.05372)
			(xy 337.093814 -227.057712) (xy 337.079082 -227.089208) (xy 337.077812 -227.091748) (xy 337.072478 -227.101908)
			(xy 337.069786 -227.10744) (xy 337.066839 -227.119381) (xy 337.066636 -227.12553) (xy 337.066636 -227.612781)
			(xy 338.96351 -227.612781) (xy 338.96351 -227.560807) (xy 338.97164 -227.509472) (xy 338.987701 -227.460042)
			(xy 339.011297 -227.413732) (xy 339.041847 -227.371684) (xy 339.078598 -227.334933) (xy 339.120646 -227.304383)
			(xy 339.166956 -227.280787) (xy 339.216386 -227.264726) (xy 339.267721 -227.256596) (xy 339.319695 -227.256596)
			(xy 339.37103 -227.264726) (xy 339.42046 -227.280787) (xy 339.46677 -227.304383) (xy 339.508818 -227.334933)
			(xy 339.545569 -227.371684) (xy 339.576119 -227.413732) (xy 339.599715 -227.460042) (xy 339.615776 -227.509472)
			(xy 339.623906 -227.560807) (xy 339.624416 -227.586794) (xy 339.623906 -227.612781) (xy 346.163394 -227.612781)
			(xy 346.163394 -227.560807) (xy 346.171524 -227.509472) (xy 346.187585 -227.460042) (xy 346.211181 -227.413732)
			(xy 346.241731 -227.371684) (xy 346.278482 -227.334933) (xy 346.32053 -227.304383) (xy 346.36684 -227.280787)
			(xy 346.41627 -227.264726) (xy 346.467605 -227.256596) (xy 346.519579 -227.256596) (xy 346.570914 -227.264726)
			(xy 346.620344 -227.280787) (xy 346.666654 -227.304383) (xy 346.708702 -227.334933) (xy 346.745453 -227.371684)
			(xy 346.776003 -227.413732) (xy 346.799599 -227.460042) (xy 346.81566 -227.509472) (xy 346.82379 -227.560807)
			(xy 346.8243 -227.586794) (xy 346.82379 -227.612781) (xy 346.81566 -227.664116) (xy 346.799599 -227.713546)
			(xy 346.776003 -227.759856) (xy 346.745453 -227.801904) (xy 346.708702 -227.838655) (xy 346.666654 -227.869205)
			(xy 346.620344 -227.892801) (xy 346.570914 -227.908862) (xy 346.519579 -227.916992) (xy 346.467605 -227.916992)
			(xy 346.41627 -227.908862) (xy 346.36684 -227.892801) (xy 346.32053 -227.869205) (xy 346.278482 -227.838655)
			(xy 346.241731 -227.801904) (xy 346.211181 -227.759856) (xy 346.187585 -227.713546) (xy 346.171524 -227.664116)
			(xy 346.163394 -227.612781) (xy 339.623906 -227.612781) (xy 339.615776 -227.664116) (xy 339.599715 -227.713546)
			(xy 339.576119 -227.759856) (xy 339.545569 -227.801904) (xy 339.508818 -227.838655) (xy 339.46677 -227.869205)
			(xy 339.42046 -227.892801) (xy 339.37103 -227.908862) (xy 339.319695 -227.916992) (xy 339.267721 -227.916992)
			(xy 339.216386 -227.908862) (xy 339.166956 -227.892801) (xy 339.120646 -227.869205) (xy 339.078598 -227.838655)
			(xy 339.041847 -227.801904) (xy 339.011297 -227.759856) (xy 338.987701 -227.713546) (xy 338.97164 -227.664116)
			(xy 338.96351 -227.612781) (xy 337.066636 -227.612781) (xy 337.066636 -228.05009) (xy 337.067058 -228.06016)
			(xy 337.074774 -228.078764) (xy 337.081622 -228.086158) (xy 337.110832 -228.115368) (xy 337.117675 -228.122767)
			(xy 337.125396 -228.141366) (xy 337.125818 -228.151436) (xy 337.125818 -228.753649) (xy 337.738202 -228.753649)
			(xy 337.738202 -228.700351) (xy 337.746145 -228.647647) (xy 337.761855 -228.596717) (xy 337.784981 -228.548696)
			(xy 337.815005 -228.504659) (xy 337.851257 -228.465588) (xy 337.892928 -228.432357) (xy 337.939086 -228.405708)
			(xy 337.9887 -228.386236) (xy 338.040662 -228.374376) (xy 338.093812 -228.370393) (xy 338.146962 -228.374376)
			(xy 338.198924 -228.386236) (xy 338.248538 -228.405708) (xy 338.294696 -228.432357) (xy 338.336367 -228.465588)
			(xy 338.372619 -228.504659) (xy 338.402643 -228.548696) (xy 338.425769 -228.596717) (xy 338.441479 -228.647647)
			(xy 338.449422 -228.700351) (xy 338.44992 -228.727) (xy 338.449422 -228.753649) (xy 338.98839 -228.753649)
			(xy 338.98839 -228.700351) (xy 338.996333 -228.647647) (xy 339.012043 -228.596717) (xy 339.035169 -228.548696)
			(xy 339.065193 -228.504659) (xy 339.101445 -228.465588) (xy 339.143116 -228.432357) (xy 339.189274 -228.405708)
			(xy 339.238888 -228.386236) (xy 339.29085 -228.374376) (xy 339.344 -228.370393) (xy 339.39715 -228.374376)
			(xy 339.449112 -228.386236) (xy 339.498726 -228.405708) (xy 339.544884 -228.432357) (xy 339.586555 -228.465588)
			(xy 339.622807 -228.504659) (xy 339.652831 -228.548696) (xy 339.675957 -228.596717) (xy 339.691667 -228.647647)
			(xy 339.69961 -228.700351) (xy 339.700108 -228.727) (xy 339.69961 -228.753649) (xy 339.691667 -228.806353)
			(xy 339.675957 -228.857283) (xy 339.652831 -228.905304) (xy 339.622807 -228.949341) (xy 339.586555 -228.988412)
			(xy 339.544884 -229.021643) (xy 339.498726 -229.048292) (xy 339.449112 -229.067764) (xy 339.39715 -229.079624)
			(xy 339.344 -229.083608) (xy 339.29085 -229.079624) (xy 339.238888 -229.067764) (xy 339.189274 -229.048292)
			(xy 339.143116 -229.021643) (xy 339.101445 -228.988412) (xy 339.065193 -228.949341) (xy 339.035169 -228.905304)
			(xy 339.012043 -228.857283) (xy 338.996333 -228.806353) (xy 338.98839 -228.753649) (xy 338.449422 -228.753649)
			(xy 338.441479 -228.806353) (xy 338.425769 -228.857283) (xy 338.402643 -228.905304) (xy 338.372619 -228.949341)
			(xy 338.336367 -228.988412) (xy 338.294696 -229.021643) (xy 338.248538 -229.048292) (xy 338.198924 -229.067764)
			(xy 338.146962 -229.079624) (xy 338.093812 -229.083608) (xy 338.040662 -229.079624) (xy 337.9887 -229.067764)
			(xy 337.939086 -229.048292) (xy 337.892928 -229.021643) (xy 337.851257 -228.988412) (xy 337.815005 -228.949341)
			(xy 337.784981 -228.905304) (xy 337.761855 -228.857283) (xy 337.746145 -228.806353) (xy 337.738202 -228.753649)
			(xy 337.125818 -228.753649) (xy 337.125818 -229.19563) (xy 337.126247 -229.205697) (xy 337.133971 -229.224292)
			(xy 337.140804 -229.231698) (xy 337.590384 -229.681278) (xy 337.596394 -229.686821) (xy 337.611035 -229.694079)
			(xy 337.619086 -229.695502) (xy 337.632929 -229.696963) (xy 337.660506 -229.693254) (xy 337.686065 -229.682256)
			(xy 337.707718 -229.664781) (xy 337.723864 -229.642121) (xy 337.729068 -229.629208) (xy 337.739407 -229.601801)
			(xy 337.767284 -229.550287) (xy 337.802714 -229.503644) (xy 337.844863 -229.46297) (xy 337.892738 -229.429222)
			(xy 337.945212 -229.403196) (xy 338.00105 -229.385504) (xy 338.058937 -229.376562) (xy 338.088224 -229.37597)
			(xy 338.115475 -229.376457) (xy 338.169421 -229.384217) (xy 338.221714 -229.399574) (xy 338.27129 -229.422216)
			(xy 338.317139 -229.451682) (xy 338.358328 -229.487374) (xy 338.394019 -229.528563) (xy 338.423485 -229.574412)
			(xy 338.446127 -229.623988) (xy 338.461484 -229.676281) (xy 338.469243 -229.730227) (xy 338.469732 -229.757478)
			(xy 338.469191 -229.786763) (xy 338.460223 -229.844644) (xy 338.448794 -229.880668) (xy 338.986366 -229.880668)
			(xy 338.990437 -229.825046) (xy 339.002563 -229.770609) (xy 339.022486 -229.718518) (xy 339.049782 -229.669883)
			(xy 339.083868 -229.62574) (xy 339.124017 -229.587031) (xy 339.169375 -229.55458) (xy 339.218975 -229.529079)
			(xy 339.271759 -229.511072) (xy 339.326602 -229.500942) (xy 339.382336 -229.498905) (xy 339.437773 -229.505005)
			(xy 339.49173 -229.519111) (xy 339.543059 -229.540923) (xy 339.590665 -229.569977) (xy 339.633533 -229.605652)
			(xy 339.67075 -229.647189) (xy 339.701523 -229.693702) (xy 339.725195 -229.744199) (xy 339.741263 -229.797606)
			(xy 339.749383 -229.852782) (xy 339.749892 -229.880668) (xy 339.749383 -229.908554) (xy 339.741263 -229.96373)
			(xy 339.725195 -230.017137) (xy 339.701523 -230.067634) (xy 339.67075 -230.114147) (xy 339.661922 -230.124)
			(xy 339.978492 -230.124) (xy 339.978975 -230.095081) (xy 339.987707 -230.037907) (xy 340.004969 -229.982706)
			(xy 340.030367 -229.930744) (xy 340.063319 -229.883211) (xy 340.103068 -229.841197) (xy 340.125558 -229.82301)
			(xy 340.13436 -229.815399) (xy 340.144544 -229.794501) (xy 340.145116 -229.782878) (xy 340.145116 -229.703122)
			(xy 340.144544 -229.691494) (xy 340.134378 -229.670585) (xy 340.125558 -229.66299) (xy 340.103061 -229.644815)
			(xy 340.063329 -229.602791) (xy 340.030392 -229.555252) (xy 340.005007 -229.503288) (xy 339.987753 -229.448088)
			(xy 339.979026 -229.390917) (xy 339.978492 -229.362) (xy 339.978909 -229.335737) (xy 339.98612 -229.283709)
			(xy 340.000406 -229.233163) (xy 340.021495 -229.185057) (xy 340.048989 -229.140301) (xy 340.082367 -229.099745)
			(xy 340.120997 -229.064154) (xy 340.142322 -229.048818) (xy 340.151878 -229.041355) (xy 340.163297 -229.020015)
			(xy 340.164166 -229.007924) (xy 340.165944 -228.913436) (xy 340.15553 -228.891846) (xy 340.145624 -228.884226)
			(xy 340.124036 -228.867271) (xy 340.085813 -228.827877) (xy 340.054078 -228.783091) (xy 340.029581 -228.73397)
			(xy 340.012899 -228.681677) (xy 340.004427 -228.627444) (xy 340.003892 -228.6) (xy 340.00439 -228.573351)
			(xy 340.012333 -228.520647) (xy 340.028043 -228.469717) (xy 340.051169 -228.421696) (xy 340.081193 -228.377659)
			(xy 340.117445 -228.338588) (xy 340.159116 -228.305357) (xy 340.205274 -228.278708) (xy 340.254888 -228.259236)
			(xy 340.30685 -228.247376) (xy 340.36 -228.243393) (xy 340.41315 -228.247376) (xy 340.465112 -228.259236)
			(xy 340.514726 -228.278708) (xy 340.560884 -228.305357) (xy 340.602555 -228.338588) (xy 340.638807 -228.377659)
			(xy 340.668831 -228.421696) (xy 340.691957 -228.469717) (xy 340.707667 -228.520647) (xy 340.71561 -228.573351)
			(xy 340.716108 -228.6) (xy 340.715586 -228.62745) (xy 340.707165 -228.681702) (xy 340.690509 -228.734015)
			(xy 340.666012 -228.783147) (xy 340.634257 -228.827932) (xy 340.595997 -228.867306) (xy 340.574376 -228.884226)
			(xy 340.56447 -228.891846) (xy 340.554056 -228.913436) (xy 340.556088 -229.02037) (xy 340.567518 -229.041706)
			(xy 340.577678 -229.048818) (xy 340.599011 -229.064141) (xy 340.637634 -229.099738) (xy 340.671005 -229.140299)
			(xy 340.698493 -229.185057) (xy 340.719578 -229.233164) (xy 340.73386 -229.28371) (xy 340.741069 -229.335738)
			(xy 340.741508 -229.362) (xy 342.899492 -229.362) (xy 342.899975 -229.335646) (xy 342.907212 -229.283438)
			(xy 342.921574 -229.232726) (xy 342.942789 -229.184477) (xy 342.970452 -229.139612) (xy 343.004033 -229.098988)
			(xy 343.042893 -229.06338) (xy 343.064338 -229.048056) (xy 343.075421 -229.039924) (xy 343.0931 -229.018885)
			(xy 343.104519 -228.993889) (xy 343.108848 -228.966752) (xy 343.105775 -228.939444) (xy 343.095521 -228.913948)
			(xy 343.078831 -228.892116) (xy 343.068148 -228.883464) (xy 343.046712 -228.866501) (xy 343.008783 -228.827138)
			(xy 342.977313 -228.782442) (xy 342.95304 -228.733464) (xy 342.936535 -228.681353) (xy 342.928184 -228.627331)
			(xy 342.927686 -228.6) (xy 342.928184 -228.573351) (xy 342.936127 -228.520647) (xy 342.951837 -228.469717)
			(xy 342.974963 -228.421696) (xy 343.004987 -228.377659) (xy 343.041239 -228.338588) (xy 343.08291 -228.305357)
			(xy 343.129068 -228.278708) (xy 343.178682 -228.259236) (xy 343.230644 -228.247376) (xy 343.283794 -228.243393)
			(xy 343.336944 -228.247376) (xy 343.388906 -228.259236) (xy 343.43852 -228.278708) (xy 343.484678 -228.305357)
			(xy 343.526349 -228.338588) (xy 343.562601 -228.377659) (xy 343.592625 -228.421696) (xy 343.615751 -228.469717)
			(xy 343.631461 -228.520647) (xy 343.639404 -228.573351) (xy 343.639902 -228.6) (xy 343.639375 -228.627544)
			(xy 343.630917 -228.681979) (xy 343.614171 -228.734461) (xy 343.604579 -228.753649) (xy 345.84639 -228.753649)
			(xy 345.84639 -228.700351) (xy 345.854333 -228.647647) (xy 345.870043 -228.596717) (xy 345.893169 -228.548696)
			(xy 345.923193 -228.504659) (xy 345.959445 -228.465588) (xy 346.001116 -228.432357) (xy 346.047274 -228.405708)
			(xy 346.096888 -228.386236) (xy 346.14885 -228.374376) (xy 346.202 -228.370393) (xy 346.25515 -228.374376)
			(xy 346.307112 -228.386236) (xy 346.356726 -228.405708) (xy 346.402884 -228.432357) (xy 346.444555 -228.465588)
			(xy 346.480807 -228.504659) (xy 346.510831 -228.548696) (xy 346.533957 -228.596717) (xy 346.549667 -228.647647)
			(xy 346.55761 -228.700351) (xy 346.558108 -228.727) (xy 346.55761 -228.753649) (xy 346.86239 -228.753649)
			(xy 346.86239 -228.700351) (xy 346.870333 -228.647647) (xy 346.886043 -228.596717) (xy 346.909169 -228.548696)
			(xy 346.939193 -228.504659) (xy 346.975445 -228.465588) (xy 347.017116 -228.432357) (xy 347.063274 -228.405708)
			(xy 347.112888 -228.386236) (xy 347.16485 -228.374376) (xy 347.218 -228.370393) (xy 347.27115 -228.374376)
			(xy 347.323112 -228.386236) (xy 347.372726 -228.405708) (xy 347.38515 -228.412881) (xy 350.963486 -228.412881)
			(xy 350.963486 -228.360907) (xy 350.971616 -228.309572) (xy 350.987677 -228.260142) (xy 351.011273 -228.213832)
			(xy 351.041823 -228.171784) (xy 351.078574 -228.135033) (xy 351.120622 -228.104483) (xy 351.166932 -228.080887)
			(xy 351.216362 -228.064826) (xy 351.267697 -228.056696) (xy 351.319671 -228.056696) (xy 351.371006 -228.064826)
			(xy 351.420436 -228.080887) (xy 351.466746 -228.104483) (xy 351.508794 -228.135033) (xy 351.545545 -228.171784)
			(xy 351.576095 -228.213832) (xy 351.599691 -228.260142) (xy 351.615752 -228.309572) (xy 351.623882 -228.360907)
			(xy 351.624392 -228.386894) (xy 351.623882 -228.412881) (xy 351.615752 -228.464216) (xy 351.599691 -228.513646)
			(xy 351.576095 -228.559956) (xy 351.545545 -228.602004) (xy 351.508794 -228.638755) (xy 351.466746 -228.669305)
			(xy 351.420436 -228.692901) (xy 351.371006 -228.708962) (xy 351.319671 -228.717092) (xy 351.267697 -228.717092)
			(xy 351.216362 -228.708962) (xy 351.166932 -228.692901) (xy 351.120622 -228.669305) (xy 351.078574 -228.638755)
			(xy 351.041823 -228.602004) (xy 351.011273 -228.559956) (xy 350.987677 -228.513646) (xy 350.971616 -228.464216)
			(xy 350.963486 -228.412881) (xy 347.38515 -228.412881) (xy 347.418884 -228.432357) (xy 347.460555 -228.465588)
			(xy 347.496807 -228.504659) (xy 347.526831 -228.548696) (xy 347.549957 -228.596717) (xy 347.565667 -228.647647)
			(xy 347.57361 -228.700351) (xy 347.574108 -228.727) (xy 347.57361 -228.753649) (xy 347.565667 -228.806353)
			(xy 347.549957 -228.857283) (xy 347.538704 -228.880649) (xy 349.328222 -228.880649) (xy 349.328222 -228.827351)
			(xy 349.336165 -228.774647) (xy 349.351875 -228.723717) (xy 349.375001 -228.675696) (xy 349.405025 -228.631659)
			(xy 349.441277 -228.592588) (xy 349.482948 -228.559357) (xy 349.529106 -228.532708) (xy 349.57872 -228.513236)
			(xy 349.630682 -228.501376) (xy 349.683832 -228.497393) (xy 349.736982 -228.501376) (xy 349.788944 -228.513236)
			(xy 349.838558 -228.532708) (xy 349.884716 -228.559357) (xy 349.926387 -228.592588) (xy 349.962639 -228.631659)
			(xy 349.992663 -228.675696) (xy 350.015789 -228.723717) (xy 350.031499 -228.774647) (xy 350.039442 -228.827351)
			(xy 350.03994 -228.854) (xy 350.039442 -228.880649) (xy 350.031499 -228.933353) (xy 350.015789 -228.984283)
			(xy 349.992663 -229.032304) (xy 349.962639 -229.076341) (xy 349.926387 -229.115412) (xy 349.884716 -229.148643)
			(xy 349.838558 -229.175292) (xy 349.788944 -229.194764) (xy 349.736982 -229.206624) (xy 349.683832 -229.210608)
			(xy 349.630682 -229.206624) (xy 349.57872 -229.194764) (xy 349.529106 -229.175292) (xy 349.482948 -229.148643)
			(xy 349.441277 -229.115412) (xy 349.405025 -229.076341) (xy 349.375001 -229.032304) (xy 349.351875 -228.984283)
			(xy 349.336165 -228.933353) (xy 349.328222 -228.880649) (xy 347.538704 -228.880649) (xy 347.526831 -228.905304)
			(xy 347.496807 -228.949341) (xy 347.460555 -228.988412) (xy 347.418884 -229.021643) (xy 347.372726 -229.048292)
			(xy 347.323112 -229.067764) (xy 347.27115 -229.079624) (xy 347.218 -229.083608) (xy 347.16485 -229.079624)
			(xy 347.112888 -229.067764) (xy 347.063274 -229.048292) (xy 347.017116 -229.021643) (xy 346.975445 -228.988412)
			(xy 346.939193 -228.949341) (xy 346.909169 -228.905304) (xy 346.886043 -228.857283) (xy 346.870333 -228.806353)
			(xy 346.86239 -228.753649) (xy 346.55761 -228.753649) (xy 346.549667 -228.806353) (xy 346.533957 -228.857283)
			(xy 346.510831 -228.905304) (xy 346.480807 -228.949341) (xy 346.444555 -228.988412) (xy 346.402884 -229.021643)
			(xy 346.356726 -229.048292) (xy 346.307112 -229.067764) (xy 346.25515 -229.079624) (xy 346.202 -229.083608)
			(xy 346.14885 -229.079624) (xy 346.096888 -229.067764) (xy 346.047274 -229.048292) (xy 346.001116 -229.021643)
			(xy 345.959445 -228.988412) (xy 345.923193 -228.949341) (xy 345.893169 -228.905304) (xy 345.870043 -228.857283)
			(xy 345.854333 -228.806353) (xy 345.84639 -228.753649) (xy 343.604579 -228.753649) (xy 343.589539 -228.783735)
			(xy 343.557608 -228.828625) (xy 343.519141 -228.868058) (xy 343.497408 -228.884988) (xy 343.486681 -228.893585)
			(xy 343.469809 -228.91527) (xy 343.459348 -228.940676) (xy 343.456058 -228.967954) (xy 343.460179 -228.995119)
			(xy 343.471411 -229.020194) (xy 343.488936 -229.041354) (xy 343.499948 -229.04958) (xy 343.521126 -229.064942)
			(xy 343.559465 -229.10054) (xy 343.592581 -229.141044) (xy 343.619851 -229.185693) (xy 343.640764 -229.233649)
			(xy 343.654928 -229.284014) (xy 343.662077 -229.335841) (xy 343.662508 -229.362) (xy 343.662022 -229.389251)
			(xy 343.654266 -229.443199) (xy 343.638911 -229.495494) (xy 343.616269 -229.545071) (xy 343.586803 -229.590921)
			(xy 343.551112 -229.632112) (xy 343.509921 -229.667803) (xy 343.464071 -229.697269) (xy 343.414494 -229.719911)
			(xy 343.362199 -229.735266) (xy 343.308404 -229.743) (xy 346.835982 -229.743) (xy 346.840053 -229.687378)
			(xy 346.852179 -229.632941) (xy 346.872102 -229.58085) (xy 346.899398 -229.532215) (xy 346.933484 -229.488072)
			(xy 346.973633 -229.449363) (xy 347.018991 -229.416912) (xy 347.068591 -229.391411) (xy 347.121375 -229.373404)
			(xy 347.176218 -229.363274) (xy 347.231952 -229.361237) (xy 347.287389 -229.367337) (xy 347.341346 -229.381443)
			(xy 347.392675 -229.403255) (xy 347.440281 -229.432309) (xy 347.483149 -229.467984) (xy 347.520366 -229.509521)
			(xy 347.551139 -229.556034) (xy 347.574811 -229.606531) (xy 347.590879 -229.659938) (xy 347.598999 -229.715114)
			(xy 347.599508 -229.743) (xy 347.598999 -229.770886) (xy 347.590879 -229.826062) (xy 347.574811 -229.879469)
			(xy 347.551139 -229.929966) (xy 347.520366 -229.976479) (xy 347.483149 -230.018016) (xy 347.440281 -230.053691)
			(xy 347.392675 -230.082745) (xy 347.341346 -230.104557) (xy 347.287389 -230.118663) (xy 347.231952 -230.124763)
			(xy 347.176218 -230.122726) (xy 347.121375 -230.112596) (xy 347.068591 -230.094589) (xy 347.018991 -230.069088)
			(xy 346.973633 -230.036637) (xy 346.933484 -229.997928) (xy 346.899398 -229.953785) (xy 346.872102 -229.90515)
			(xy 346.852179 -229.853059) (xy 346.840053 -229.798622) (xy 346.835982 -229.743) (xy 343.308404 -229.743)
			(xy 343.308251 -229.743022) (xy 343.253749 -229.743022) (xy 343.199801 -229.735266) (xy 343.147506 -229.719911)
			(xy 343.097929 -229.697269) (xy 343.052079 -229.667803) (xy 343.010888 -229.632112) (xy 342.975197 -229.590921)
			(xy 342.945731 -229.545071) (xy 342.923089 -229.495494) (xy 342.907734 -229.443199) (xy 342.899978 -229.389251)
			(xy 342.899492 -229.362) (xy 340.741508 -229.362) (xy 340.741025 -229.390919) (xy 340.732293 -229.448093)
			(xy 340.715031 -229.503294) (xy 340.689633 -229.555256) (xy 340.656681 -229.602789) (xy 340.616932 -229.644803)
			(xy 340.594442 -229.66299) (xy 340.58564 -229.670601) (xy 340.575456 -229.691499) (xy 340.574884 -229.703122)
			(xy 340.574884 -229.782878) (xy 340.575456 -229.794506) (xy 340.585622 -229.815415) (xy 340.594442 -229.82301)
			(xy 340.616939 -229.841185) (xy 340.656671 -229.883209) (xy 340.689608 -229.930748) (xy 340.714993 -229.982712)
			(xy 340.732247 -230.037912) (xy 340.740974 -230.095083) (xy 340.741508 -230.124) (xy 340.741022 -230.151251)
			(xy 340.733266 -230.205199) (xy 340.717911 -230.257494) (xy 340.695269 -230.307071) (xy 340.665803 -230.352921)
			(xy 340.630112 -230.394112) (xy 340.588921 -230.429803) (xy 340.543071 -230.459269) (xy 340.493494 -230.481911)
			(xy 340.441199 -230.497266) (xy 340.387251 -230.505022) (xy 340.332749 -230.505022) (xy 340.278801 -230.497266)
			(xy 340.226506 -230.481911) (xy 340.176929 -230.459269) (xy 340.131079 -230.429803) (xy 340.089888 -230.394112)
			(xy 340.054197 -230.352921) (xy 340.024731 -230.307071) (xy 340.002089 -230.257494) (xy 339.986734 -230.205199)
			(xy 339.978978 -230.151251) (xy 339.978492 -230.124) (xy 339.661922 -230.124) (xy 339.633533 -230.155684)
			(xy 339.590665 -230.191359) (xy 339.543059 -230.220413) (xy 339.49173 -230.242225) (xy 339.437773 -230.256331)
			(xy 339.382336 -230.262431) (xy 339.326602 -230.260394) (xy 339.271759 -230.250264) (xy 339.218975 -230.232257)
			(xy 339.169375 -230.206756) (xy 339.124017 -230.174305) (xy 339.083868 -230.135596) (xy 339.049782 -230.091453)
			(xy 339.022486 -230.042818) (xy 339.002563 -229.990727) (xy 338.990437 -229.93629) (xy 338.986366 -229.880668)
			(xy 338.448794 -229.880668) (xy 338.442511 -229.900472) (xy 338.41647 -229.952935) (xy 338.382714 -230.0008)
			(xy 338.342035 -230.04294) (xy 338.295391 -230.078365) (xy 338.24388 -230.106241) (xy 338.216494 -230.116634)
			(xy 338.203516 -230.121728) (xy 338.180783 -230.137851) (xy 338.163263 -230.159527) (xy 338.152265 -230.185136)
			(xy 338.14861 -230.212766) (xy 338.1502 -230.226616) (xy 338.151649 -230.234659) (xy 338.158905 -230.249291)
			(xy 338.164424 -230.255318) (xy 338.5693 -230.660194) (xy 338.576698 -230.667041) (xy 338.595296 -230.674777)
			(xy 338.605368 -230.67518)
		)
		(stroke
			(width 0)
			(type solid)
		)
		(fill yes)
		(layer "In11.Cu")
		(net "P3V3_FPGA_VCCIO0")
	)
	(gr_poly
		(pts
			(xy 393.895834 -293.95674) (xy 393.906202 -293.956248) (xy 393.925252 -293.948058) (xy 393.939529 -293.93302)
			(xy 393.943586 -293.923466) (xy 393.972288 -293.844726) (xy 393.976352 -293.833804) (xy 393.979414 -293.823903)
			(xy 393.978212 -293.803234) (xy 393.968974 -293.784704) (xy 393.961366 -293.77767) (xy 393.943371 -293.761865)
			(xy 393.911674 -293.725962) (xy 393.885477 -293.685869) (xy 393.865324 -293.642423) (xy 393.851637 -293.596528)
			(xy 393.8447 -293.54914) (xy 393.844272 -293.525194) (xy 393.844272 -293.52494) (xy 393.844782 -293.498953)
			(xy 393.852912 -293.447618) (xy 393.868973 -293.398188) (xy 393.892569 -293.351878) (xy 393.923119 -293.30983)
			(xy 393.95987 -293.273079) (xy 394.001918 -293.242529) (xy 394.048228 -293.218933) (xy 394.097658 -293.202872)
			(xy 394.148993 -293.194742) (xy 394.200967 -293.194742) (xy 394.252302 -293.202872) (xy 394.301732 -293.218933)
			(xy 394.348042 -293.242529) (xy 394.39009 -293.273079) (xy 394.426841 -293.30983) (xy 394.457391 -293.351878)
			(xy 394.480987 -293.398188) (xy 394.497048 -293.447618) (xy 394.505178 -293.498953) (xy 394.505688 -293.52494)
			(xy 394.505688 -293.525194) (xy 394.505098 -293.553233) (xy 394.49564 -293.608509) (xy 394.476995 -293.661397)
			(xy 394.449696 -293.710383) (xy 394.414525 -293.754062) (xy 394.393928 -293.773098) (xy 394.38834 -293.777924)
			(xy 394.37945 -293.791894) (xy 394.373601 -293.802148) (xy 394.371085 -293.82559) (xy 394.374624 -293.836852)
			(xy 394.377672 -293.844726) (xy 394.406374 -293.923466) (xy 394.410396 -293.93305) (xy 394.424663 -293.948135)
			(xy 394.443743 -293.956323) (xy 394.454126 -293.95674) (xy 394.845794 -293.95674) (xy 394.856155 -293.956237)
			(xy 394.875186 -293.948035) (xy 394.889444 -293.932997) (xy 394.893546 -293.923466) (xy 394.922248 -293.844726)
			(xy 394.926312 -293.833804) (xy 394.929375 -293.823904) (xy 394.928173 -293.803235) (xy 394.918929 -293.784709)
			(xy 394.911326 -293.77767) (xy 394.893328 -293.761867) (xy 394.861626 -293.725966) (xy 394.835424 -293.685874)
			(xy 394.815267 -293.642427) (xy 394.801577 -293.596531) (xy 394.794639 -293.549141) (xy 394.794232 -293.525194)
			(xy 394.794232 -293.52494) (xy 394.794742 -293.498953) (xy 394.802872 -293.447618) (xy 394.818933 -293.398188)
			(xy 394.842529 -293.351878) (xy 394.873079 -293.30983) (xy 394.90983 -293.273079) (xy 394.951878 -293.242529)
			(xy 394.998188 -293.218933) (xy 395.047618 -293.202872) (xy 395.098953 -293.194742) (xy 395.150927 -293.194742)
			(xy 395.202262 -293.202872) (xy 395.251692 -293.218933) (xy 395.298002 -293.242529) (xy 395.34005 -293.273079)
			(xy 395.376801 -293.30983) (xy 395.407351 -293.351878) (xy 395.430947 -293.398188) (xy 395.447008 -293.447618)
			(xy 395.455138 -293.498953) (xy 395.455648 -293.52494) (xy 395.455648 -293.525194) (xy 395.455058 -293.553234)
			(xy 395.445602 -293.608511) (xy 395.426959 -293.661401) (xy 395.399663 -293.71039) (xy 395.364497 -293.754075)
			(xy 395.343888 -293.773098) (xy 395.3383 -293.777924) (xy 395.32941 -293.791894) (xy 395.323565 -293.802149)
			(xy 395.32105 -293.82559) (xy 395.324584 -293.836852) (xy 395.327632 -293.844726) (xy 395.356334 -293.923466)
			(xy 395.360359 -293.933043) (xy 395.374629 -293.948111) (xy 395.393708 -293.956278) (xy 395.404086 -293.95674)
			(xy 396.02918 -293.95674) (xy 396.047976 -293.94912) (xy 396.055088 -293.941754) (xy 396.307818 -293.689024)
			(xy 396.314661 -293.681625) (xy 396.322381 -293.663026) (xy 396.322804 -293.652956) (xy 396.322804 -292.981888)
			(xy 396.322075 -292.969643) (xy 396.310788 -292.947905) (xy 396.301214 -292.940232) (xy 396.267178 -292.916356)
			(xy 396.233142 -292.89248) (xy 396.222894 -292.886098) (xy 396.199018 -292.882775) (xy 396.187422 -292.88613)
			(xy 396.186914 -292.886384) (xy 396.159985 -292.895383) (xy 396.104048 -292.905093) (xy 396.075662 -292.905688)
			(xy 396.0749 -292.905688) (xy 396.048911 -292.905205) (xy 395.997574 -292.897073) (xy 395.948141 -292.881011)
			(xy 395.901829 -292.857413) (xy 395.859779 -292.82686) (xy 395.823027 -292.790106) (xy 395.792477 -292.748054)
			(xy 395.768881 -292.701741) (xy 395.752822 -292.652307) (xy 395.744694 -292.600969) (xy 395.744192 -292.57498)
			(xy 395.744703 -292.548994) (xy 395.752836 -292.497662) (xy 395.768899 -292.448234) (xy 395.792496 -292.401927)
			(xy 395.823046 -292.359882) (xy 395.859797 -292.323133) (xy 395.901844 -292.292585) (xy 395.948152 -292.268991)
			(xy 395.997581 -292.252931) (xy 396.048914 -292.244801) (xy 396.0749 -292.244272) (xy 396.10315 -292.244828)
			(xy 396.158829 -292.254414) (xy 396.185644 -292.263322) (xy 396.186152 -292.263576) (xy 396.18793 -292.264084)
			(xy 396.199435 -292.267221) (xy 396.223 -292.263758) (xy 396.233142 -292.25748) (xy 396.301214 -292.209728)
			(xy 396.310851 -292.202109) (xy 396.322143 -292.180338) (xy 396.322804 -292.168072) (xy 396.322804 -292.031674)
			(xy 396.322072 -292.01943) (xy 396.310782 -291.997697) (xy 396.301214 -291.990018) (xy 396.267178 -291.966142)
			(xy 396.233142 -291.942266) (xy 396.222896 -291.935875) (xy 396.199016 -291.932547) (xy 396.187422 -291.935916)
			(xy 396.186914 -291.93617) (xy 396.159985 -291.945169) (xy 396.104048 -291.95488) (xy 396.075662 -291.955474)
			(xy 396.0749 -291.955474) (xy 396.048912 -291.954991) (xy 395.997575 -291.946859) (xy 395.948143 -291.930797)
			(xy 395.901832 -291.907198) (xy 395.859783 -291.876646) (xy 395.823032 -291.839891) (xy 395.792484 -291.797839)
			(xy 395.76889 -291.751526) (xy 395.752833 -291.702092) (xy 395.744706 -291.650754) (xy 395.744192 -291.624766)
			(xy 395.744704 -291.598781) (xy 395.752839 -291.54745) (xy 395.768903 -291.498024) (xy 395.792501 -291.451719)
			(xy 395.823051 -291.409676) (xy 395.859802 -291.372929) (xy 395.901848 -291.342383) (xy 395.948156 -291.31879)
			(xy 395.997583 -291.302731) (xy 396.048915 -291.294601) (xy 396.0749 -291.294058) (xy 396.10315 -291.294614)
			(xy 396.15883 -291.304199) (xy 396.185644 -291.313108) (xy 396.186152 -291.313362) (xy 396.18793 -291.31387)
			(xy 396.199436 -291.317004) (xy 396.223002 -291.313546) (xy 396.233142 -291.307266) (xy 396.301214 -291.259514)
			(xy 396.310849 -291.251895) (xy 396.322135 -291.230123) (xy 396.322804 -291.217858) (xy 396.322804 -291.081714)
			(xy 396.322081 -291.069466) (xy 396.3108 -291.047718) (xy 396.301214 -291.040058) (xy 396.267178 -291.016182)
			(xy 396.233142 -290.992306) (xy 396.222895 -290.985922) (xy 396.199018 -290.982597) (xy 396.187422 -290.985956)
			(xy 396.186914 -290.98621) (xy 396.159985 -290.995208) (xy 396.104048 -291.004918) (xy 396.075662 -291.005514)
			(xy 396.0749 -291.005514) (xy 396.048913 -291.005004) (xy 395.997578 -290.996874) (xy 395.948147 -290.980813)
			(xy 395.901837 -290.957217) (xy 395.859788 -290.926668) (xy 395.823036 -290.889916) (xy 395.792486 -290.847868)
			(xy 395.768889 -290.801559) (xy 395.752827 -290.752128) (xy 395.744696 -290.700793) (xy 395.744192 -290.674806)
			(xy 395.744675 -290.648816) (xy 395.752805 -290.597477) (xy 395.768867 -290.548042) (xy 395.792464 -290.501728)
			(xy 395.823016 -290.459675) (xy 395.859771 -290.42292) (xy 395.901823 -290.392367) (xy 395.948136 -290.368769)
			(xy 395.997571 -290.352707) (xy 396.04891 -290.344575) (xy 396.0749 -290.344098) (xy 396.10315 -290.344654)
			(xy 396.15883 -290.354237) (xy 396.185644 -290.363148) (xy 396.186152 -290.363402) (xy 396.18793 -290.36391)
			(xy 396.199436 -290.367046) (xy 396.223001 -290.363584) (xy 396.233142 -290.357306) (xy 396.301214 -290.309554)
			(xy 396.310856 -290.301937) (xy 396.322159 -290.280166) (xy 396.322804 -290.267898) (xy 396.322804 -290.166298)
			(xy 396.315184 -290.147502) (xy 396.307818 -290.14039) (xy 396.221458 -290.05403) (xy 396.213899 -290.04708)
			(xy 396.194893 -290.039354) (xy 396.184628 -290.039044) (xy 396.177516 -290.039298) (xy 396.170658 -290.04133)
			(xy 396.147341 -290.047964) (xy 396.099392 -290.055111) (xy 396.075154 -290.055554) (xy 396.0749 -290.055554)
			(xy 396.048912 -290.055044) (xy 395.997574 -290.046914) (xy 395.948141 -290.030854) (xy 395.901828 -290.007259)
			(xy 395.859776 -289.97671) (xy 395.82302 -289.939959) (xy 395.792465 -289.897911) (xy 395.768864 -289.851602)
			(xy 395.752797 -289.80217) (xy 395.744659 -289.750834) (xy 395.744192 -289.724846) (xy 395.744192 -289.724592)
			(xy 395.744655 -289.702137) (xy 395.7509 -289.65766) (xy 395.756638 -289.635946) (xy 395.758416 -289.629088)
			(xy 395.76014 -289.62228) (xy 395.760267 -289.608242) (xy 395.75867 -289.601402) (xy 395.75867 -289.600894)
			(xy 395.75672 -289.594495) (xy 395.750041 -289.582909) (xy 395.745462 -289.578034) (xy 395.271498 -289.10407)
			(xy 395.263938 -289.09712) (xy 395.244933 -289.089389) (xy 395.234668 -289.089084) (xy 395.227556 -289.089338)
			(xy 395.220698 -289.09137) (xy 395.19738 -289.098001) (xy 395.149432 -289.10514) (xy 395.125194 -289.105594)
			(xy 395.12494 -289.105594) (xy 395.098949 -289.105114) (xy 395.047606 -289.096987) (xy 394.998168 -289.080929)
			(xy 394.95185 -289.057333) (xy 394.909794 -289.026781) (xy 394.873036 -288.990026) (xy 394.842481 -288.947972)
			(xy 394.818881 -288.901657) (xy 394.802819 -288.852219) (xy 394.794688 -288.800877) (xy 394.794232 -288.774886)
			(xy 394.794232 -288.774632) (xy 394.794692 -288.752177) (xy 394.800933 -288.707699) (xy 394.806678 -288.685986)
			(xy 394.808456 -288.679128) (xy 394.810209 -288.672323) (xy 394.810347 -288.658276) (xy 394.80871 -288.651442)
			(xy 394.80871 -288.650934) (xy 394.806751 -288.64454) (xy 394.800058 -288.63297) (xy 394.795502 -288.628074)
			(xy 394.321538 -288.15411) (xy 394.313977 -288.147165) (xy 394.294971 -288.13945) (xy 394.284708 -288.139124)
			(xy 394.277596 -288.139378) (xy 394.270738 -288.14141) (xy 394.247421 -288.148043) (xy 394.199472 -288.155187)
			(xy 394.175234 -288.155634) (xy 394.17498 -288.155634) (xy 394.148993 -288.155123) (xy 394.09766 -288.14699)
			(xy 394.04823 -288.130928) (xy 394.001921 -288.107331) (xy 393.959874 -288.076782) (xy 393.923122 -288.040031)
			(xy 393.892572 -287.997984) (xy 393.868975 -287.951676) (xy 393.852911 -287.902246) (xy 393.844777 -287.850913)
			(xy 393.844272 -287.824926) (xy 393.844272 -287.824672) (xy 393.844737 -287.802217) (xy 393.850986 -287.757742)
			(xy 393.856718 -287.736026) (xy 393.858496 -287.729168) (xy 393.860218 -287.72236) (xy 393.860339 -287.708323)
			(xy 393.85875 -287.701482) (xy 393.85875 -287.700974) (xy 393.856797 -287.694577) (xy 393.850114 -287.682996)
			(xy 393.845542 -287.678114) (xy 393.371578 -287.20415) (xy 393.364021 -287.197194) (xy 393.345015 -287.189458)
			(xy 393.334748 -287.189164) (xy 393.327636 -287.189418) (xy 393.320778 -287.19145) (xy 393.29746 -287.19808)
			(xy 393.249512 -287.205217) (xy 393.225274 -287.205674) (xy 393.22502 -287.205674) (xy 393.199031 -287.205192)
			(xy 393.147692 -287.197063) (xy 393.098257 -287.181002) (xy 393.051943 -287.157405) (xy 393.009892 -287.126853)
			(xy 392.973138 -287.090098) (xy 392.942587 -287.048045) (xy 392.918992 -287.00173) (xy 392.902933 -286.952295)
			(xy 392.894807 -286.900955) (xy 392.894312 -286.874966) (xy 392.894312 -286.874712) (xy 392.894774 -286.852257)
			(xy 392.901016 -286.807779) (xy 392.906758 -286.786066) (xy 392.908536 -286.779208) (xy 392.910287 -286.772403)
			(xy 392.910419 -286.758357) (xy 392.90879 -286.751522) (xy 392.90879 -286.751014) (xy 392.906828 -286.744622)
			(xy 392.90013 -286.733057) (xy 392.895582 -286.728154) (xy 391.471404 -285.303976) (xy 391.463844 -285.297024)
			(xy 391.444839 -285.28929) (xy 391.434574 -285.28899) (xy 391.427462 -285.289244) (xy 391.420604 -285.291276)
			(xy 391.397286 -285.297907) (xy 391.349338 -285.305048) (xy 391.3251 -285.3055) (xy 391.324846 -285.3055)
			(xy 391.298855 -285.30502) (xy 391.247511 -285.296895) (xy 391.198071 -285.280836) (xy 391.151752 -285.257241)
			(xy 391.109695 -285.226689) (xy 391.072935 -285.189934) (xy 391.042379 -285.147881) (xy 391.018778 -285.101564)
			(xy 391.002714 -285.052126) (xy 390.994583 -285.000783) (xy 390.994138 -284.974792) (xy 390.994138 -284.974538)
			(xy 390.994598 -284.952083) (xy 391.000838 -284.907604) (xy 391.006584 -284.885892) (xy 391.008362 -284.879034)
			(xy 391.010116 -284.872229) (xy 391.010255 -284.858181) (xy 391.008616 -284.851348) (xy 391.008616 -284.85084)
			(xy 391.006658 -284.844446) (xy 390.999966 -284.832874) (xy 390.995408 -284.82798) (xy 390.521444 -284.354016)
			(xy 390.513883 -284.347069) (xy 390.494878 -284.339351) (xy 390.484614 -284.33903) (xy 390.477502 -284.339284)
			(xy 390.470644 -284.341316) (xy 390.447327 -284.34795) (xy 390.399378 -284.355095) (xy 390.37514 -284.35554)
			(xy 390.374886 -284.35554) (xy 390.348899 -284.355029) (xy 390.297564 -284.346897) (xy 390.248133 -284.330836)
			(xy 390.201823 -284.307239) (xy 390.159774 -284.27669) (xy 390.123022 -284.239939) (xy 390.09247 -284.197892)
			(xy 390.068871 -284.151583) (xy 390.052807 -284.102154) (xy 390.044672 -284.050819) (xy 390.044178 -284.024832)
			(xy 390.044629 -284.000314) (xy 390.051881 -283.951817) (xy 390.066218 -283.904923) (xy 390.087323 -283.860661)
			(xy 390.114734 -283.820001) (xy 390.147851 -283.783837) (xy 390.166606 -283.768038) (xy 390.168638 -283.76626)
			(xy 390.172448 -283.76245) (xy 390.178544 -283.756354) (xy 390.191498 -283.729938) (xy 390.193935 -283.724672)
			(xy 390.196622 -283.713385) (xy 390.196832 -283.707586) (xy 390.196832 -283.39796) (xy 390.195308 -283.385768)
			(xy 390.192768 -283.3751) (xy 390.191498 -283.369004) (xy 390.1821 -283.350462) (xy 390.180219 -283.346908)
			(xy 390.175497 -283.340399) (xy 390.172702 -283.337508) (xy 390.168638 -283.333444) (xy 390.166606 -283.331666)
			(xy 390.14617 -283.314409) (xy 390.110615 -283.274453) (xy 390.081952 -283.229296) (xy 390.060929 -283.180116)
			(xy 390.048093 -283.128193) (xy 390.043779 -283.074882) (xy 390.048098 -283.021572) (xy 390.06094 -282.969651)
			(xy 390.081968 -282.920473) (xy 390.110636 -282.875319) (xy 390.146195 -282.835366) (xy 390.166606 -282.818078)
			(xy 390.168638 -282.8163) (xy 390.172448 -282.81249) (xy 390.178544 -282.806394) (xy 390.191498 -282.779978)
			(xy 390.193939 -282.774713) (xy 390.196635 -282.763426) (xy 390.196832 -282.757626) (xy 390.196832 -282.448)
			(xy 390.195308 -282.435808) (xy 390.192768 -282.42514) (xy 390.191498 -282.419044) (xy 390.1821 -282.400502)
			(xy 390.180215 -282.396951) (xy 390.175488 -282.390447) (xy 390.172702 -282.387548) (xy 390.168638 -282.383484)
			(xy 390.166606 -282.381706) (xy 390.146166 -282.364449) (xy 390.110605 -282.324492) (xy 390.081936 -282.279333)
			(xy 390.060907 -282.23015) (xy 390.048066 -282.178223) (xy 390.043747 -282.124908) (xy 390.048064 -282.071592)
			(xy 390.060903 -282.019665) (xy 390.081929 -281.970481) (xy 390.110596 -281.92532) (xy 390.146155 -281.885361)
			(xy 390.166606 -281.868118) (xy 390.168638 -281.86634) (xy 390.172448 -281.86253) (xy 390.178544 -281.856434)
			(xy 390.191498 -281.830018) (xy 390.193943 -281.824753) (xy 390.196648 -281.813467) (xy 390.196832 -281.807666)
			(xy 390.196832 -281.49804) (xy 390.195308 -281.485848) (xy 390.192768 -281.47518) (xy 390.191498 -281.469084)
			(xy 390.1821 -281.450542) (xy 390.180217 -281.446989) (xy 390.175494 -281.440482) (xy 390.172702 -281.437588)
			(xy 390.168638 -281.433524) (xy 390.166606 -281.431746) (xy 390.146171 -281.41449) (xy 390.110619 -281.374533)
			(xy 390.08196 -281.329378) (xy 390.060939 -281.280199) (xy 390.048106 -281.228278) (xy 390.043794 -281.17497)
			(xy 390.048116 -281.121662) (xy 390.060959 -281.069744) (xy 390.081988 -281.020569) (xy 390.110656 -280.975418)
			(xy 390.146215 -280.935469) (xy 390.166606 -280.918158) (xy 390.168638 -280.91638) (xy 390.172448 -280.91257)
			(xy 390.178544 -280.906474) (xy 390.191498 -280.880058) (xy 390.193937 -280.874792) (xy 390.196629 -280.863506)
			(xy 390.196832 -280.857706) (xy 390.196832 -280.547826) (xy 390.195308 -280.535634) (xy 390.192768 -280.524966)
			(xy 390.191498 -280.51887) (xy 390.1821 -280.500328) (xy 390.180217 -280.496775) (xy 390.175492 -280.49027)
			(xy 390.172702 -280.487374) (xy 390.168638 -280.48331) (xy 390.166606 -280.481532) (xy 390.146164 -280.464275)
			(xy 390.110599 -280.424317) (xy 390.081926 -280.379157) (xy 390.060893 -280.329971) (xy 390.048049 -280.278043)
			(xy 390.043727 -280.224724) (xy 390.048041 -280.171405) (xy 390.060878 -280.119474) (xy 390.081904 -280.070286)
			(xy 390.11057 -280.025121) (xy 390.14613 -279.985158) (xy 390.166606 -279.967944) (xy 390.168638 -279.966166)
			(xy 390.172448 -279.962356) (xy 390.178544 -279.95626) (xy 390.191498 -279.929844) (xy 390.193936 -279.924578)
			(xy 390.196624 -279.913292) (xy 390.196832 -279.907492) (xy 390.196832 -279.597866) (xy 390.195308 -279.585674)
			(xy 390.192768 -279.575006) (xy 390.191498 -279.56891) (xy 390.1821 -279.550368) (xy 390.180219 -279.546814)
			(xy 390.175498 -279.540304) (xy 390.172702 -279.537414) (xy 390.168638 -279.53335) (xy 390.166606 -279.531572)
			(xy 390.146169 -279.514315) (xy 390.110613 -279.474359) (xy 390.08195 -279.429202) (xy 390.060926 -279.380021)
			(xy 390.048089 -279.328098) (xy 390.043774 -279.274786) (xy 390.048093 -279.221475) (xy 390.060934 -279.169553)
			(xy 390.081963 -279.120374) (xy 390.11063 -279.075219) (xy 390.146189 -279.035265) (xy 390.166606 -279.017984)
			(xy 390.168638 -279.016206) (xy 390.172448 -279.012396) (xy 390.178544 -279.0063) (xy 390.191498 -278.979884)
			(xy 390.19394 -278.974619) (xy 390.196637 -278.963333) (xy 390.196832 -278.957532) (xy 390.196832 -278.647906)
			(xy 390.195308 -278.635714) (xy 390.192768 -278.625046) (xy 390.191498 -278.61895) (xy 390.1821 -278.600408)
			(xy 390.180215 -278.596856) (xy 390.175489 -278.590352) (xy 390.172702 -278.587454) (xy 390.168638 -278.58339)
			(xy 390.166606 -278.581612) (xy 390.146166 -278.564355) (xy 390.110604 -278.524398) (xy 390.081934 -278.479238)
			(xy 390.060904 -278.430055) (xy 390.048062 -278.378128) (xy 390.043743 -278.324811) (xy 390.048059 -278.271495)
			(xy 390.060897 -278.219567) (xy 390.081923 -278.170382) (xy 390.11059 -278.125221) (xy 390.146149 -278.08526)
			(xy 390.166606 -278.068024) (xy 390.168638 -278.066246) (xy 390.172448 -278.062436) (xy 390.178544 -278.05634)
			(xy 390.191498 -278.029924) (xy 390.193944 -278.02466) (xy 390.19665 -278.013374) (xy 390.196832 -278.007572)
			(xy 390.196832 -277.697946) (xy 390.195308 -277.685754) (xy 390.192768 -277.675086) (xy 390.191498 -277.66899)
			(xy 390.1821 -277.650448) (xy 390.180218 -277.646895) (xy 390.175495 -277.640387) (xy 390.172702 -277.637494)
			(xy 390.168638 -277.63343) (xy 390.166606 -277.631652) (xy 390.146171 -277.614395) (xy 390.110618 -277.574439)
			(xy 390.081957 -277.529283) (xy 390.060936 -277.480104) (xy 390.048102 -277.428183) (xy 390.043789 -277.374873)
			(xy 390.048111 -277.321565) (xy 390.060953 -277.269646) (xy 390.081982 -277.22047) (xy 390.11065 -277.175318)
			(xy 390.146209 -277.135368) (xy 390.166606 -277.118064) (xy 390.168638 -277.116286) (xy 390.172448 -277.112476)
			(xy 390.178544 -277.10638) (xy 390.191498 -277.079964) (xy 390.193938 -277.074698) (xy 390.196631 -277.063412)
			(xy 390.196832 -277.057612) (xy 390.196832 -276.747986) (xy 390.195308 -276.735794) (xy 390.192768 -276.725126)
			(xy 390.191498 -276.71903) (xy 390.1821 -276.700488) (xy 390.180214 -276.696937) (xy 390.175486 -276.690435)
			(xy 390.172702 -276.687534) (xy 390.168638 -276.68347) (xy 390.166606 -276.681692) (xy 390.146167 -276.664435)
			(xy 390.110608 -276.624478) (xy 390.081942 -276.57932) (xy 390.060915 -276.530138) (xy 390.048075 -276.478213)
			(xy 390.043758 -276.424899) (xy 390.048076 -276.371585) (xy 390.060916 -276.31966) (xy 390.081943 -276.270478)
			(xy 390.11061 -276.22532) (xy 390.146169 -276.185363) (xy 390.166606 -276.168104) (xy 390.168638 -276.166326)
			(xy 390.172448 -276.162516) (xy 390.178544 -276.15642) (xy 390.191498 -276.130004) (xy 390.193942 -276.124739)
			(xy 390.196644 -276.113453) (xy 390.196832 -276.107652) (xy 390.196832 -275.798026) (xy 390.195308 -275.785834)
			(xy 390.192768 -275.775166) (xy 390.191498 -275.76907) (xy 390.1821 -275.750528) (xy 390.180217 -275.746975)
			(xy 390.175492 -275.74047) (xy 390.172702 -275.737574) (xy 390.168638 -275.73351) (xy 390.166606 -275.731732)
			(xy 390.146164 -275.714475) (xy 390.110599 -275.674517) (xy 390.081926 -275.629357) (xy 390.060893 -275.580171)
			(xy 390.048049 -275.528243) (xy 390.043727 -275.474924) (xy 390.048041 -275.421605) (xy 390.060878 -275.369674)
			(xy 390.081904 -275.320486) (xy 390.11057 -275.275321) (xy 390.14613 -275.235358) (xy 390.166606 -275.218144)
			(xy 390.168638 -275.216366) (xy 390.172448 -275.212556) (xy 390.178544 -275.20646) (xy 390.191498 -275.180044)
			(xy 390.193936 -275.174778) (xy 390.196624 -275.163492) (xy 390.196832 -275.157692) (xy 390.196832 -274.848066)
			(xy 390.195308 -274.835874) (xy 390.192768 -274.825206) (xy 390.191498 -274.81911) (xy 390.1821 -274.800568)
			(xy 390.180219 -274.797014) (xy 390.175498 -274.790504) (xy 390.172702 -274.787614) (xy 390.168638 -274.78355)
			(xy 390.166606 -274.781772) (xy 390.146169 -274.764515) (xy 390.110613 -274.724559) (xy 390.08195 -274.679402)
			(xy 390.060926 -274.630221) (xy 390.048089 -274.578298) (xy 390.043774 -274.524986) (xy 390.048093 -274.471675)
			(xy 390.060934 -274.419753) (xy 390.081963 -274.370574) (xy 390.11063 -274.325419) (xy 390.146189 -274.285465)
			(xy 390.166606 -274.268184) (xy 390.168638 -274.266406) (xy 390.172448 -274.262596) (xy 390.178544 -274.2565)
			(xy 390.191498 -274.230084) (xy 390.19394 -274.224819) (xy 390.196637 -274.213533) (xy 390.196832 -274.207732)
			(xy 390.196832 -273.897852) (xy 390.195308 -273.88566) (xy 390.192768 -273.874992) (xy 390.191498 -273.868896)
			(xy 390.1821 -273.850354) (xy 390.180218 -273.8468) (xy 390.175496 -273.840292) (xy 390.172702 -273.8374)
			(xy 390.168638 -273.833336) (xy 390.166606 -273.831558) (xy 390.14617 -273.814301) (xy 390.110616 -273.774345)
			(xy 390.081955 -273.729189) (xy 390.060933 -273.680009) (xy 390.048098 -273.628087) (xy 390.043785 -273.574777)
			(xy 390.048105 -273.521468) (xy 390.060947 -273.469548) (xy 390.081976 -273.420371) (xy 390.110644 -273.375219)
			(xy 390.146203 -273.335267) (xy 390.166606 -273.31797) (xy 390.168638 -273.316192) (xy 390.172448 -273.312382)
			(xy 390.178544 -273.306286) (xy 390.191498 -273.27987) (xy 390.193938 -273.274604) (xy 390.196633 -273.263318)
			(xy 390.196832 -273.257518) (xy 390.196832 -272.947892) (xy 390.195308 -272.9357) (xy 390.192768 -272.925032)
			(xy 390.191498 -272.918936) (xy 390.1821 -272.900394) (xy 390.180215 -272.896843) (xy 390.175487 -272.89034)
			(xy 390.172702 -272.88744) (xy 390.168638 -272.883376) (xy 390.166606 -272.881598) (xy 390.146167 -272.864341)
			(xy 390.110607 -272.824384) (xy 390.081939 -272.779226) (xy 390.060912 -272.730043) (xy 390.048071 -272.678117)
			(xy 390.043754 -272.624803) (xy 390.048071 -272.571488) (xy 390.06091 -272.519562) (xy 390.081937 -272.470379)
			(xy 390.110604 -272.42522) (xy 390.146163 -272.385262) (xy 390.166606 -272.36801) (xy 390.168638 -272.366232)
			(xy 390.172448 -272.362422) (xy 390.178544 -272.356326) (xy 390.191498 -272.32991) (xy 390.193943 -272.324645)
			(xy 390.196646 -272.313359) (xy 390.196832 -272.307558) (xy 390.196832 -265.340592) (xy 390.196578 -265.336274)
			(xy 390.166098 -264.988548) (xy 390.16559 -264.984738) (xy 390.11352 -264.671048) (xy 390.113012 -264.667238)
			(xy 389.577072 -258.625594) (xy 389.57591 -258.616859) (xy 389.568514 -258.600878) (xy 389.562594 -258.594352)
			(xy 387.52018 -256.551938) (xy 387.512782 -256.54509) (xy 387.494184 -256.537357) (xy 387.484112 -256.536952)
			(xy 383.365756 -256.536952) (xy 383.356772 -256.537302) (xy 383.339913 -256.543516) (xy 383.326256 -256.555193)
			(xy 383.32156 -256.56286) (xy 383.306969 -256.587768) (xy 383.271446 -256.633269) (xy 383.229467 -256.672893)
			(xy 383.181994 -256.705733) (xy 383.130111 -256.731039) (xy 383.075005 -256.748232) (xy 383.017937 -256.756918)
			(xy 382.989074 -256.757424) (xy 382.976336 -256.757345) (xy 382.950915 -256.75569) (xy 382.938274 -256.754122)
			(xy 382.90736 -256.74931) (xy 382.847558 -256.730939) (xy 382.791547 -256.703074) (xy 382.765808 -256.685288)
			(xy 382.759458 -256.68097) (xy 382.737868 -256.673604) (xy 382.733364 -256.672225) (xy 382.724034 -256.670943)
			(xy 382.719326 -256.671064) (xy 382.703324 -256.671826) (xy 382.698186 -256.672218) (xy 382.688208 -256.674783)
			(xy 382.683512 -256.676906) (xy 382.663954 -256.686558) (xy 382.657858 -256.692654) (xy 382.29159 -257.058922)
			(xy 382.284737 -257.066317) (xy 382.276997 -257.084916) (xy 382.276604 -257.09499) (xy 382.276604 -257.137916)
			(xy 384.879086 -257.137916) (xy 384.883157 -257.082294) (xy 384.895283 -257.027857) (xy 384.915206 -256.975766)
			(xy 384.942502 -256.927131) (xy 384.976588 -256.882988) (xy 385.016737 -256.844279) (xy 385.062095 -256.811828)
			(xy 385.111695 -256.786327) (xy 385.164479 -256.76832) (xy 385.219322 -256.75819) (xy 385.275056 -256.756153)
			(xy 385.330493 -256.762253) (xy 385.38445 -256.776359) (xy 385.435779 -256.798171) (xy 385.483385 -256.827225)
			(xy 385.526253 -256.8629) (xy 385.56347 -256.904437) (xy 385.594243 -256.95095) (xy 385.617915 -257.001447)
			(xy 385.633983 -257.054854) (xy 385.642103 -257.11003) (xy 385.642612 -257.137916) (xy 385.642103 -257.165802)
			(xy 385.633983 -257.220978) (xy 385.617915 -257.274385) (xy 385.594243 -257.324882) (xy 385.56347 -257.371395)
			(xy 385.526253 -257.412932) (xy 385.483385 -257.448607) (xy 385.435779 -257.477661) (xy 385.38445 -257.499473)
			(xy 385.330493 -257.513579) (xy 385.275056 -257.519679) (xy 385.219322 -257.517642) (xy 385.164479 -257.507512)
			(xy 385.111695 -257.489505) (xy 385.062095 -257.464004) (xy 385.016737 -257.431553) (xy 384.976588 -257.392844)
			(xy 384.942502 -257.348701) (xy 384.915206 -257.300066) (xy 384.895283 -257.247975) (xy 384.883157 -257.193538)
			(xy 384.879086 -257.137916) (xy 382.276604 -257.137916) (xy 382.276604 -258.702048) (xy 382.284224 -258.720844)
			(xy 382.29159 -258.727956) (xy 382.685798 -259.122164) (xy 382.693195 -259.129015) (xy 382.711793 -259.136755)
			(xy 382.721866 -259.13715) (xy 385.392422 -259.13715) (xy 385.402489 -259.137579) (xy 385.421083 -259.145304)
			(xy 385.42849 -259.152136) (xy 385.675378 -259.399024) (xy 386.435344 -259.399024) (xy 386.439417 -259.343365)
			(xy 386.451552 -259.288892) (xy 386.471488 -259.236766) (xy 386.498802 -259.188098) (xy 386.53291 -259.143926)
			(xy 386.573087 -259.105191) (xy 386.618475 -259.072719) (xy 386.668107 -259.047201) (xy 386.720927 -259.029182)
			(xy 386.775806 -259.019045) (xy 386.831577 -259.017007) (xy 386.887051 -259.02311) (xy 386.941044 -259.037226)
			(xy 386.992407 -259.059053) (xy 387.040045 -259.088126) (xy 387.082941 -259.123825) (xy 387.120183 -259.165389)
			(xy 387.150977 -259.211933) (xy 387.174665 -259.262464) (xy 387.190743 -259.315906) (xy 387.198869 -259.37112)
			(xy 387.199378 -259.399024) (xy 387.198869 -259.426928) (xy 387.190743 -259.482142) (xy 387.174665 -259.535584)
			(xy 387.150977 -259.586115) (xy 387.120183 -259.632659) (xy 387.082941 -259.674223) (xy 387.040045 -259.709922)
			(xy 386.992407 -259.738995) (xy 386.941044 -259.760822) (xy 386.887051 -259.774938) (xy 386.831577 -259.781041)
			(xy 386.775806 -259.779003) (xy 386.720927 -259.768866) (xy 386.668107 -259.750847) (xy 386.618475 -259.725329)
			(xy 386.573087 -259.692857) (xy 386.53291 -259.654122) (xy 386.498802 -259.60995) (xy 386.471488 -259.561282)
			(xy 386.451552 -259.509156) (xy 386.439417 -259.454683) (xy 386.435344 -259.399024) (xy 385.675378 -259.399024)
			(xy 386.649214 -260.37286) (xy 387.427468 -260.37286) (xy 387.431541 -260.317201) (xy 387.443676 -260.262728)
			(xy 387.463612 -260.210602) (xy 387.490926 -260.161934) (xy 387.525034 -260.117762) (xy 387.565211 -260.079027)
			(xy 387.610599 -260.046555) (xy 387.660231 -260.021037) (xy 387.713051 -260.003018) (xy 387.76793 -259.992881)
			(xy 387.823701 -259.990843) (xy 387.879175 -259.996946) (xy 387.933168 -260.011062) (xy 387.984531 -260.032889)
			(xy 388.032169 -260.061962) (xy 388.075065 -260.097661) (xy 388.112307 -260.139225) (xy 388.143101 -260.185769)
			(xy 388.166789 -260.2363) (xy 388.182867 -260.289742) (xy 388.190993 -260.344956) (xy 388.191502 -260.37286)
			(xy 388.190993 -260.400764) (xy 388.182867 -260.455978) (xy 388.166789 -260.50942) (xy 388.143101 -260.559951)
			(xy 388.112307 -260.606495) (xy 388.075065 -260.648059) (xy 388.032169 -260.683758) (xy 387.984531 -260.712831)
			(xy 387.933168 -260.734658) (xy 387.879175 -260.748774) (xy 387.823701 -260.754877) (xy 387.76793 -260.752839)
			(xy 387.713051 -260.742702) (xy 387.660231 -260.724683) (xy 387.610599 -260.699165) (xy 387.565211 -260.666693)
			(xy 387.525034 -260.627958) (xy 387.490926 -260.583786) (xy 387.463612 -260.535118) (xy 387.443676 -260.482992)
			(xy 387.431541 -260.428519) (xy 387.427468 -260.37286) (xy 386.649214 -260.37286) (xy 386.754878 -260.478524)
			(xy 386.761723 -260.485923) (xy 386.769452 -260.504521) (xy 386.769864 -260.514592) (xy 386.769864 -260.585712)
			(xy 386.770372 -260.585966) (xy 386.770372 -262.629396) (xy 386.77059 -262.636205) (xy 386.774195 -262.649338)
			(xy 386.777484 -262.655304) (xy 386.786374 -262.67029) (xy 386.794248 -262.68045) (xy 386.807456 -262.693658)
			(xy 386.81279 -262.69696) (xy 386.836248 -262.71195) (xy 386.87896 -262.747653) (xy 386.916032 -262.789181)
			(xy 386.94668 -262.835654) (xy 386.970252 -262.886085) (xy 386.98625 -262.939405) (xy 386.994333 -262.994484)
			(xy 386.99433 -263.050152) (xy 386.986242 -263.10523) (xy 386.97024 -263.158548) (xy 386.946662 -263.208977)
			(xy 386.91601 -263.255447) (xy 386.878934 -263.296972) (xy 386.836219 -263.332671) (xy 386.81279 -263.347708)
			(xy 386.807456 -263.35101) (xy 386.794248 -263.364218) (xy 386.786374 -263.374378) (xy 386.777484 -263.389364)
			(xy 386.774202 -263.395332) (xy 386.770603 -263.408464) (xy 386.770372 -263.415272) (xy 386.770372 -263.820148)
			(xy 386.770608 -263.8271) (xy 386.774336 -263.840497) (xy 386.777738 -263.846564) (xy 386.790184 -263.866884)
			(xy 386.793573 -263.872106) (xy 386.802444 -263.880834) (xy 386.80771 -263.884156) (xy 386.807964 -263.88441)
			(xy 386.830721 -263.8982) (xy 386.872535 -263.931108) (xy 386.909374 -263.969504) (xy 386.940524 -264.012644)
			(xy 386.965381 -264.059692) (xy 386.974842 -264.084562) (xy 386.983074 -264.108559) (xy 386.993851 -264.158134)
			(xy 386.99797 -264.2087) (xy 386.99536 -264.259366) (xy 386.986066 -264.30924) (xy 386.970251 -264.357445)
			(xy 386.959602 -264.380472) (xy 386.95757 -264.384536) (xy 386.95376 -264.397744) (xy 386.951982 -264.406888)
			(xy 386.949017 -264.43167) (xy 386.937464 -264.480224) (xy 386.919672 -264.526856) (xy 386.895946 -264.570766)
			(xy 386.866693 -264.611205) (xy 386.853812 -264.625328) (xy 388.763 -264.625328) (xy 388.767071 -264.569706)
			(xy 388.779197 -264.515269) (xy 388.79912 -264.463178) (xy 388.826416 -264.414543) (xy 388.860502 -264.3704)
			(xy 388.900651 -264.331691) (xy 388.946009 -264.29924) (xy 388.995609 -264.273739) (xy 389.048393 -264.255732)
			(xy 389.103236 -264.245602) (xy 389.15897 -264.243565) (xy 389.214407 -264.249665) (xy 389.268364 -264.263771)
			(xy 389.319693 -264.285583) (xy 389.367299 -264.314637) (xy 389.410167 -264.350312) (xy 389.447384 -264.391849)
			(xy 389.478157 -264.438362) (xy 389.501829 -264.488859) (xy 389.517897 -264.542266) (xy 389.526017 -264.597442)
			(xy 389.526526 -264.625328) (xy 389.526017 -264.653214) (xy 389.517897 -264.70839) (xy 389.501829 -264.761797)
			(xy 389.478157 -264.812294) (xy 389.447384 -264.858807) (xy 389.410167 -264.900344) (xy 389.367299 -264.936019)
			(xy 389.319693 -264.965073) (xy 389.268364 -264.986885) (xy 389.214407 -265.000991) (xy 389.15897 -265.007091)
			(xy 389.103236 -265.005054) (xy 389.048393 -264.994924) (xy 388.995609 -264.976917) (xy 388.946009 -264.951416)
			(xy 388.900651 -264.918965) (xy 388.860502 -264.880256) (xy 388.826416 -264.836113) (xy 388.79912 -264.787478)
			(xy 388.779197 -264.735387) (xy 388.767071 -264.68095) (xy 388.763 -264.625328) (xy 386.853812 -264.625328)
			(xy 386.849874 -264.629646) (xy 386.838586 -264.641409) (xy 386.814297 -264.663159) (xy 386.80136 -264.67308)
			(xy 386.800344 -264.673842) (xy 386.79882 -264.675112) (xy 386.790692 -264.683494) (xy 386.78612 -264.691114)
			(xy 386.77596 -264.710672) (xy 386.773378 -264.716099) (xy 386.770557 -264.727779) (xy 386.770372 -264.733786)
			(xy 386.770372 -265.155934) (xy 386.768848 -265.157204) (xy 386.768848 -265.737848) (xy 388.73252 -265.737848)
			(xy 388.736591 -265.682226) (xy 388.748717 -265.627789) (xy 388.76864 -265.575698) (xy 388.795936 -265.527063)
			(xy 388.830022 -265.48292) (xy 388.870171 -265.444211) (xy 388.915529 -265.41176) (xy 388.965129 -265.386259)
			(xy 389.017913 -265.368252) (xy 389.072756 -265.358122) (xy 389.12849 -265.356085) (xy 389.183927 -265.362185)
			(xy 389.237884 -265.376291) (xy 389.289213 -265.398103) (xy 389.336819 -265.427157) (xy 389.379687 -265.462832)
			(xy 389.416904 -265.504369) (xy 389.447677 -265.550882) (xy 389.471349 -265.601379) (xy 389.487417 -265.654786)
			(xy 389.495537 -265.709962) (xy 389.496046 -265.737848) (xy 389.495537 -265.765734) (xy 389.487417 -265.82091)
			(xy 389.471349 -265.874317) (xy 389.447677 -265.924814) (xy 389.416904 -265.971327) (xy 389.379687 -266.012864)
			(xy 389.336819 -266.048539) (xy 389.289213 -266.077593) (xy 389.237884 -266.099405) (xy 389.183927 -266.113511)
			(xy 389.12849 -266.119611) (xy 389.072756 -266.117574) (xy 389.017913 -266.107444) (xy 388.965129 -266.089437)
			(xy 388.915529 -266.063936) (xy 388.870171 -266.031485) (xy 388.830022 -265.992776) (xy 388.795936 -265.948633)
			(xy 388.76864 -265.899998) (xy 388.748717 -265.847907) (xy 388.736591 -265.79347) (xy 388.73252 -265.737848)
			(xy 386.768848 -265.737848) (xy 386.768848 -265.890502) (xy 386.770372 -265.89228) (xy 386.770372 -266.963398)
			(xy 386.956044 -266.963398) (xy 386.960115 -266.907776) (xy 386.972241 -266.853339) (xy 386.992164 -266.801248)
			(xy 387.01946 -266.752613) (xy 387.053546 -266.70847) (xy 387.093695 -266.669761) (xy 387.139053 -266.63731)
			(xy 387.188653 -266.611809) (xy 387.241437 -266.593802) (xy 387.29628 -266.583672) (xy 387.352014 -266.581635)
			(xy 387.407451 -266.587735) (xy 387.461408 -266.601841) (xy 387.512737 -266.623653) (xy 387.560343 -266.652707)
			(xy 387.603211 -266.688382) (xy 387.640428 -266.729919) (xy 387.671201 -266.776432) (xy 387.694873 -266.826929)
			(xy 387.710941 -266.880336) (xy 387.716137 -266.915646) (xy 388.736076 -266.915646) (xy 388.740147 -266.860024)
			(xy 388.752273 -266.805587) (xy 388.772196 -266.753496) (xy 388.799492 -266.704861) (xy 388.833578 -266.660718)
			(xy 388.873727 -266.622009) (xy 388.919085 -266.589558) (xy 388.968685 -266.564057) (xy 389.021469 -266.54605)
			(xy 389.076312 -266.53592) (xy 389.132046 -266.533883) (xy 389.187483 -266.539983) (xy 389.24144 -266.554089)
			(xy 389.292769 -266.575901) (xy 389.340375 -266.604955) (xy 389.383243 -266.64063) (xy 389.42046 -266.682167)
			(xy 389.451233 -266.72868) (xy 389.474905 -266.779177) (xy 389.490973 -266.832584) (xy 389.499093 -266.88776)
			(xy 389.499602 -266.915646) (xy 389.499093 -266.943532) (xy 389.490973 -266.998708) (xy 389.474905 -267.052115)
			(xy 389.451233 -267.102612) (xy 389.42046 -267.149125) (xy 389.383243 -267.190662) (xy 389.340375 -267.226337)
			(xy 389.292769 -267.255391) (xy 389.24144 -267.277203) (xy 389.187483 -267.291309) (xy 389.132046 -267.297409)
			(xy 389.076312 -267.295372) (xy 389.021469 -267.285242) (xy 388.968685 -267.267235) (xy 388.919085 -267.241734)
			(xy 388.873727 -267.209283) (xy 388.833578 -267.170574) (xy 388.799492 -267.126431) (xy 388.772196 -267.077796)
			(xy 388.752273 -267.025705) (xy 388.740147 -266.971268) (xy 388.736076 -266.915646) (xy 387.716137 -266.915646)
			(xy 387.719061 -266.935512) (xy 387.71957 -266.963398) (xy 387.719061 -266.991284) (xy 387.710941 -267.04646)
			(xy 387.694873 -267.099867) (xy 387.671201 -267.150364) (xy 387.640428 -267.196877) (xy 387.603211 -267.238414)
			(xy 387.560343 -267.274089) (xy 387.512737 -267.303143) (xy 387.461408 -267.324955) (xy 387.407451 -267.339061)
			(xy 387.352014 -267.345161) (xy 387.29628 -267.343124) (xy 387.241437 -267.332994) (xy 387.188653 -267.314987)
			(xy 387.139053 -267.289486) (xy 387.093695 -267.257035) (xy 387.053546 -267.218326) (xy 387.01946 -267.174183)
			(xy 386.992164 -267.125548) (xy 386.972241 -267.073457) (xy 386.960115 -267.01902) (xy 386.956044 -266.963398)
			(xy 386.770372 -266.963398) (xy 386.770372 -268.339062) (xy 388.744204 -268.339062) (xy 388.748275 -268.28344)
			(xy 388.760401 -268.229003) (xy 388.780324 -268.176912) (xy 388.80762 -268.128277) (xy 388.841706 -268.084134)
			(xy 388.881855 -268.045425) (xy 388.927213 -268.012974) (xy 388.976813 -267.987473) (xy 389.029597 -267.969466)
			(xy 389.08444 -267.959336) (xy 389.140174 -267.957299) (xy 389.195611 -267.963399) (xy 389.249568 -267.977505)
			(xy 389.300897 -267.999317) (xy 389.348503 -268.028371) (xy 389.391371 -268.064046) (xy 389.428588 -268.105583)
			(xy 389.459361 -268.152096) (xy 389.483033 -268.202593) (xy 389.499101 -268.256) (xy 389.507221 -268.311176)
			(xy 389.50773 -268.339062) (xy 389.507221 -268.366948) (xy 389.499101 -268.422124) (xy 389.483033 -268.475531)
			(xy 389.459361 -268.526028) (xy 389.428588 -268.572541) (xy 389.391371 -268.614078) (xy 389.348503 -268.649753)
			(xy 389.300897 -268.678807) (xy 389.249568 -268.700619) (xy 389.195611 -268.714725) (xy 389.140174 -268.720825)
			(xy 389.08444 -268.718788) (xy 389.029597 -268.708658) (xy 388.976813 -268.690651) (xy 388.927213 -268.66515)
			(xy 388.881855 -268.632699) (xy 388.841706 -268.59399) (xy 388.80762 -268.549847) (xy 388.780324 -268.501212)
			(xy 388.760401 -268.449121) (xy 388.748275 -268.394684) (xy 388.744204 -268.339062) (xy 386.770372 -268.339062)
			(xy 386.770372 -268.873478) (xy 386.771076 -268.886209) (xy 386.783216 -268.908592) (xy 386.793486 -268.91615)
			(xy 386.829554 -268.939518) (xy 386.875782 -268.969744) (xy 386.901182 -268.971776) (xy 386.91312 -268.966442)
			(xy 386.937582 -268.956094) (xy 386.988651 -268.941503) (xy 387.04125 -268.934137) (xy 387.067806 -268.933676)
			(xy 387.095058 -268.934162) (xy 387.149007 -268.94192) (xy 387.201304 -268.957276) (xy 387.250882 -268.979918)
			(xy 387.296734 -269.009386) (xy 387.337925 -269.045079) (xy 387.373617 -269.086271) (xy 387.403084 -269.132123)
			(xy 387.425726 -269.181702) (xy 387.441082 -269.233998) (xy 387.448838 -269.287948) (xy 387.448838 -269.342452)
			(xy 387.441082 -269.396402) (xy 387.425726 -269.448698) (xy 387.403084 -269.498277) (xy 387.373617 -269.544129)
			(xy 387.337925 -269.585321) (xy 387.296734 -269.621014) (xy 387.250882 -269.650482) (xy 387.201304 -269.673124)
			(xy 387.149007 -269.68848) (xy 387.095058 -269.696238) (xy 387.067806 -269.696692) (xy 387.041249 -269.696234)
			(xy 386.988649 -269.688869) (xy 386.937579 -269.674281) (xy 386.91312 -269.663926) (xy 386.901182 -269.658592)
			(xy 386.875782 -269.660624) (xy 386.829554 -269.69085) (xy 386.793486 -269.714218) (xy 386.786557 -269.719082)
			(xy 386.776146 -269.73242) (xy 386.770671 -269.748429) (xy 386.770372 -269.75689) (xy 386.770372 -269.943326)
			(xy 388.630666 -269.943326) (xy 388.634737 -269.887704) (xy 388.646863 -269.833267) (xy 388.666786 -269.781176)
			(xy 388.694082 -269.732541) (xy 388.728168 -269.688398) (xy 388.768317 -269.649689) (xy 388.813675 -269.617238)
			(xy 388.863275 -269.591737) (xy 388.916059 -269.57373) (xy 388.970902 -269.5636) (xy 389.026636 -269.561563)
			(xy 389.082073 -269.567663) (xy 389.13603 -269.581769) (xy 389.187359 -269.603581) (xy 389.234965 -269.632635)
			(xy 389.277833 -269.66831) (xy 389.31505 -269.709847) (xy 389.345823 -269.75636) (xy 389.369495 -269.806857)
			(xy 389.385563 -269.860264) (xy 389.393683 -269.91544) (xy 389.394192 -269.943326) (xy 389.393683 -269.971212)
			(xy 389.385563 -270.026388) (xy 389.369495 -270.079795) (xy 389.345823 -270.130292) (xy 389.31505 -270.176805)
			(xy 389.277833 -270.218342) (xy 389.234965 -270.254017) (xy 389.187359 -270.283071) (xy 389.13603 -270.304883)
			(xy 389.082073 -270.318989) (xy 389.026636 -270.325089) (xy 388.970902 -270.323052) (xy 388.916059 -270.312922)
			(xy 388.863275 -270.294915) (xy 388.813675 -270.269414) (xy 388.768317 -270.236963) (xy 388.728168 -270.198254)
			(xy 388.694082 -270.154111) (xy 388.666786 -270.105476) (xy 388.646863 -270.053385) (xy 388.634737 -269.998948)
			(xy 388.630666 -269.943326) (xy 386.770372 -269.943326) (xy 386.770372 -272.322036) (xy 386.771134 -272.33118)
			(xy 386.775198 -272.343626) (xy 386.787898 -272.371312) (xy 386.795772 -272.378424) (xy 386.81428 -272.395651)
			(xy 386.846361 -272.434729) (xy 386.872123 -272.478234) (xy 386.890965 -272.525151) (xy 386.902449 -272.57439)
			(xy 386.906306 -272.624803) (xy 386.906306 -272.624804) (xy 387.219202 -272.624804) (xy 387.223162 -272.57575)
			(xy 387.234939 -272.527966) (xy 387.25423 -272.48269) (xy 387.280533 -272.441094) (xy 387.313168 -272.404257)
			(xy 387.351289 -272.373132) (xy 387.39391 -272.348525) (xy 387.439926 -272.331073) (xy 387.488145 -272.321229)
			(xy 387.53732 -272.319248) (xy 387.586175 -272.32518) (xy 387.633446 -272.338872) (xy 387.677908 -272.35997)
			(xy 387.718411 -272.387926) (xy 387.753904 -272.422018) (xy 387.783469 -272.461362) (xy 387.80634 -272.504939)
			(xy 387.821924 -272.55162) (xy 387.829819 -272.600197) (xy 387.830314 -272.624804) (xy 388.169162 -272.624804)
			(xy 388.173122 -272.57575) (xy 388.184899 -272.527966) (xy 388.20419 -272.48269) (xy 388.230493 -272.441094)
			(xy 388.263128 -272.404257) (xy 388.301249 -272.373132) (xy 388.34387 -272.348525) (xy 388.389886 -272.331073)
			(xy 388.438105 -272.321229) (xy 388.48728 -272.319248) (xy 388.536135 -272.32518) (xy 388.583406 -272.338872)
			(xy 388.627868 -272.35997) (xy 388.668371 -272.387926) (xy 388.703864 -272.422018) (xy 388.733429 -272.461362)
			(xy 388.7563 -272.504939) (xy 388.771884 -272.55162) (xy 388.779779 -272.600197) (xy 388.780274 -272.624804)
			(xy 389.119122 -272.624804) (xy 389.123082 -272.57575) (xy 389.134859 -272.527966) (xy 389.15415 -272.48269)
			(xy 389.180453 -272.441094) (xy 389.213088 -272.404257) (xy 389.251209 -272.373132) (xy 389.29383 -272.348525)
			(xy 389.339846 -272.331073) (xy 389.388065 -272.321229) (xy 389.43724 -272.319248) (xy 389.486095 -272.32518)
			(xy 389.533366 -272.338872) (xy 389.577828 -272.35997) (xy 389.618331 -272.387926) (xy 389.653824 -272.422018)
			(xy 389.683389 -272.461362) (xy 389.70626 -272.504939) (xy 389.721844 -272.55162) (xy 389.729739 -272.600197)
			(xy 389.730234 -272.624804) (xy 389.729739 -272.649411) (xy 389.721844 -272.697988) (xy 389.70626 -272.744669)
			(xy 389.683389 -272.788246) (xy 389.653824 -272.82759) (xy 389.618331 -272.861682) (xy 389.577828 -272.889638)
			(xy 389.533366 -272.910736) (xy 389.486095 -272.924428) (xy 389.43724 -272.93036) (xy 389.388065 -272.928379)
			(xy 389.339846 -272.918535) (xy 389.29383 -272.901083) (xy 389.251209 -272.876476) (xy 389.213088 -272.845351)
			(xy 389.180453 -272.808514) (xy 389.15415 -272.766918) (xy 389.134859 -272.721642) (xy 389.123082 -272.673858)
			(xy 389.119122 -272.624804) (xy 388.780274 -272.624804) (xy 388.779779 -272.649411) (xy 388.771884 -272.697988)
			(xy 388.7563 -272.744669) (xy 388.733429 -272.788246) (xy 388.703864 -272.82759) (xy 388.668371 -272.861682)
			(xy 388.627868 -272.889638) (xy 388.583406 -272.910736) (xy 388.536135 -272.924428) (xy 388.48728 -272.93036)
			(xy 388.438105 -272.928379) (xy 388.389886 -272.918535) (xy 388.34387 -272.901083) (xy 388.301249 -272.876476)
			(xy 388.263128 -272.845351) (xy 388.230493 -272.808514) (xy 388.20419 -272.766918) (xy 388.184899 -272.721642)
			(xy 388.173122 -272.673858) (xy 388.169162 -272.624804) (xy 387.830314 -272.624804) (xy 387.829819 -272.649411)
			(xy 387.821924 -272.697988) (xy 387.80634 -272.744669) (xy 387.783469 -272.788246) (xy 387.753904 -272.82759)
			(xy 387.718411 -272.861682) (xy 387.677908 -272.889638) (xy 387.633446 -272.910736) (xy 387.586175 -272.924428)
			(xy 387.53732 -272.93036) (xy 387.488145 -272.928379) (xy 387.439926 -272.918535) (xy 387.39391 -272.901083)
			(xy 387.351289 -272.876476) (xy 387.313168 -272.845351) (xy 387.280533 -272.808514) (xy 387.25423 -272.766918)
			(xy 387.234939 -272.721642) (xy 387.223162 -272.673858) (xy 387.219202 -272.624804) (xy 386.906306 -272.624804)
			(xy 386.902448 -272.675215) (xy 386.890964 -272.724454) (xy 386.872121 -272.771371) (xy 386.846358 -272.814875)
			(xy 386.814276 -272.853953) (xy 386.795772 -272.871184) (xy 386.787898 -272.878296) (xy 386.775198 -272.905982)
			(xy 386.771134 -272.918428) (xy 386.770372 -272.927572) (xy 386.770372 -273.272504) (xy 386.770489 -273.277866)
			(xy 386.772662 -273.288367) (xy 386.77469 -273.293332) (xy 386.785104 -273.316192) (xy 386.7912 -273.324828)
			(xy 386.795264 -273.328384) (xy 386.815611 -273.347365) (xy 386.850281 -273.390883) (xy 386.87719 -273.439583)
			(xy 386.89558 -273.492096) (xy 386.904935 -273.546944) (xy 386.9055 -273.574764) (xy 387.219202 -273.574764)
			(xy 387.223162 -273.52571) (xy 387.234939 -273.477926) (xy 387.25423 -273.43265) (xy 387.280533 -273.391054)
			(xy 387.313168 -273.354217) (xy 387.351289 -273.323092) (xy 387.39391 -273.298485) (xy 387.439926 -273.281033)
			(xy 387.488145 -273.271189) (xy 387.53732 -273.269208) (xy 387.586175 -273.27514) (xy 387.633446 -273.288832)
			(xy 387.677908 -273.30993) (xy 387.718411 -273.337886) (xy 387.753904 -273.371978) (xy 387.783469 -273.411322)
			(xy 387.80634 -273.454899) (xy 387.821924 -273.50158) (xy 387.829819 -273.550157) (xy 387.830314 -273.574764)
			(xy 388.169162 -273.574764) (xy 388.173122 -273.52571) (xy 388.184899 -273.477926) (xy 388.20419 -273.43265)
			(xy 388.230493 -273.391054) (xy 388.263128 -273.354217) (xy 388.301249 -273.323092) (xy 388.34387 -273.298485)
			(xy 388.389886 -273.281033) (xy 388.438105 -273.271189) (xy 388.48728 -273.269208) (xy 388.536135 -273.27514)
			(xy 388.583406 -273.288832) (xy 388.627868 -273.30993) (xy 388.668371 -273.337886) (xy 388.703864 -273.371978)
			(xy 388.733429 -273.411322) (xy 388.7563 -273.454899) (xy 388.771884 -273.50158) (xy 388.779779 -273.550157)
			(xy 388.780274 -273.574764) (xy 389.119122 -273.574764) (xy 389.123082 -273.52571) (xy 389.134859 -273.477926)
			(xy 389.15415 -273.43265) (xy 389.180453 -273.391054) (xy 389.213088 -273.354217) (xy 389.251209 -273.323092)
			(xy 389.29383 -273.298485) (xy 389.339846 -273.281033) (xy 389.388065 -273.271189) (xy 389.43724 -273.269208)
			(xy 389.486095 -273.27514) (xy 389.533366 -273.288832) (xy 389.577828 -273.30993) (xy 389.618331 -273.337886)
			(xy 389.653824 -273.371978) (xy 389.683389 -273.411322) (xy 389.70626 -273.454899) (xy 389.721844 -273.50158)
			(xy 389.729739 -273.550157) (xy 389.730234 -273.574764) (xy 389.729739 -273.599371) (xy 389.721844 -273.647948)
			(xy 389.70626 -273.694629) (xy 389.683389 -273.738206) (xy 389.653824 -273.77755) (xy 389.618331 -273.811642)
			(xy 389.577828 -273.839598) (xy 389.533366 -273.860696) (xy 389.486095 -273.874388) (xy 389.43724 -273.88032)
			(xy 389.388065 -273.878339) (xy 389.339846 -273.868495) (xy 389.29383 -273.851043) (xy 389.251209 -273.826436)
			(xy 389.213088 -273.795311) (xy 389.180453 -273.758474) (xy 389.15415 -273.716878) (xy 389.134859 -273.671602)
			(xy 389.123082 -273.623818) (xy 389.119122 -273.574764) (xy 388.780274 -273.574764) (xy 388.779779 -273.599371)
			(xy 388.771884 -273.647948) (xy 388.7563 -273.694629) (xy 388.733429 -273.738206) (xy 388.703864 -273.77755)
			(xy 388.668371 -273.811642) (xy 388.627868 -273.839598) (xy 388.583406 -273.860696) (xy 388.536135 -273.874388)
			(xy 388.48728 -273.88032) (xy 388.438105 -273.878339) (xy 388.389886 -273.868495) (xy 388.34387 -273.851043)
			(xy 388.301249 -273.826436) (xy 388.263128 -273.795311) (xy 388.230493 -273.758474) (xy 388.20419 -273.716878)
			(xy 388.184899 -273.671602) (xy 388.173122 -273.623818) (xy 388.169162 -273.574764) (xy 387.830314 -273.574764)
			(xy 387.829819 -273.599371) (xy 387.821924 -273.647948) (xy 387.80634 -273.694629) (xy 387.783469 -273.738206)
			(xy 387.753904 -273.77755) (xy 387.718411 -273.811642) (xy 387.677908 -273.839598) (xy 387.633446 -273.860696)
			(xy 387.586175 -273.874388) (xy 387.53732 -273.88032) (xy 387.488145 -273.878339) (xy 387.439926 -273.868495)
			(xy 387.39391 -273.851043) (xy 387.351289 -273.826436) (xy 387.313168 -273.795311) (xy 387.280533 -273.758474)
			(xy 387.25423 -273.716878) (xy 387.234939 -273.671602) (xy 387.223162 -273.623818) (xy 387.219202 -273.574764)
			(xy 386.9055 -273.574764) (xy 386.905085 -273.598374) (xy 386.898333 -273.64511) (xy 386.884991 -273.690407)
			(xy 386.86533 -273.73334) (xy 386.839752 -273.773034) (xy 386.808778 -273.808677) (xy 386.7912 -273.824446)
			(xy 386.78993 -273.825716) (xy 386.789676 -273.82597) (xy 386.784088 -273.830796) (xy 386.780786 -273.835114)
			(xy 386.776031 -273.841896) (xy 386.770711 -273.857572) (xy 386.770372 -273.865848) (xy 386.770372 -274.22221)
			(xy 386.771134 -274.231354) (xy 386.775198 -274.2438) (xy 386.787898 -274.271486) (xy 386.795772 -274.278598)
			(xy 386.814282 -274.295825) (xy 386.846367 -274.334904) (xy 386.872133 -274.378409) (xy 386.890978 -274.425329)
			(xy 386.902465 -274.47457) (xy 386.906325 -274.524978) (xy 387.219202 -274.524978) (xy 387.223162 -274.475924)
			(xy 387.234939 -274.42814) (xy 387.25423 -274.382864) (xy 387.280533 -274.341268) (xy 387.313168 -274.304431)
			(xy 387.351289 -274.273306) (xy 387.39391 -274.248699) (xy 387.439926 -274.231247) (xy 387.488145 -274.221403)
			(xy 387.53732 -274.219422) (xy 387.586175 -274.225354) (xy 387.633446 -274.239046) (xy 387.677908 -274.260144)
			(xy 387.718411 -274.2881) (xy 387.753904 -274.322192) (xy 387.783469 -274.361536) (xy 387.80634 -274.405113)
			(xy 387.821924 -274.451794) (xy 387.829819 -274.500371) (xy 387.830314 -274.524978) (xy 388.169162 -274.524978)
			(xy 388.173122 -274.475924) (xy 388.184899 -274.42814) (xy 388.20419 -274.382864) (xy 388.230493 -274.341268)
			(xy 388.263128 -274.304431) (xy 388.301249 -274.273306) (xy 388.34387 -274.248699) (xy 388.389886 -274.231247)
			(xy 388.438105 -274.221403) (xy 388.48728 -274.219422) (xy 388.536135 -274.225354) (xy 388.583406 -274.239046)
			(xy 388.627868 -274.260144) (xy 388.668371 -274.2881) (xy 388.703864 -274.322192) (xy 388.733429 -274.361536)
			(xy 388.7563 -274.405113) (xy 388.771884 -274.451794) (xy 388.779779 -274.500371) (xy 388.780274 -274.524978)
			(xy 389.119122 -274.524978) (xy 389.123082 -274.475924) (xy 389.134859 -274.42814) (xy 389.15415 -274.382864)
			(xy 389.180453 -274.341268) (xy 389.213088 -274.304431) (xy 389.251209 -274.273306) (xy 389.29383 -274.248699)
			(xy 389.339846 -274.231247) (xy 389.388065 -274.221403) (xy 389.43724 -274.219422) (xy 389.486095 -274.225354)
			(xy 389.533366 -274.239046) (xy 389.577828 -274.260144) (xy 389.618331 -274.2881) (xy 389.653824 -274.322192)
			(xy 389.683389 -274.361536) (xy 389.70626 -274.405113) (xy 389.721844 -274.451794) (xy 389.729739 -274.500371)
			(xy 389.730234 -274.524978) (xy 389.729739 -274.549585) (xy 389.721844 -274.598162) (xy 389.70626 -274.644843)
			(xy 389.683389 -274.68842) (xy 389.653824 -274.727764) (xy 389.618331 -274.761856) (xy 389.577828 -274.789812)
			(xy 389.533366 -274.81091) (xy 389.486095 -274.824602) (xy 389.43724 -274.830534) (xy 389.388065 -274.828553)
			(xy 389.339846 -274.818709) (xy 389.29383 -274.801257) (xy 389.251209 -274.77665) (xy 389.213088 -274.745525)
			(xy 389.180453 -274.708688) (xy 389.15415 -274.667092) (xy 389.134859 -274.621816) (xy 389.123082 -274.574032)
			(xy 389.119122 -274.524978) (xy 388.780274 -274.524978) (xy 388.779779 -274.549585) (xy 388.771884 -274.598162)
			(xy 388.7563 -274.644843) (xy 388.733429 -274.68842) (xy 388.703864 -274.727764) (xy 388.668371 -274.761856)
			(xy 388.627868 -274.789812) (xy 388.583406 -274.81091) (xy 388.536135 -274.824602) (xy 388.48728 -274.830534)
			(xy 388.438105 -274.828553) (xy 388.389886 -274.818709) (xy 388.34387 -274.801257) (xy 388.301249 -274.77665)
			(xy 388.263128 -274.745525) (xy 388.230493 -274.708688) (xy 388.20419 -274.667092) (xy 388.184899 -274.621816)
			(xy 388.173122 -274.574032) (xy 388.169162 -274.524978) (xy 387.830314 -274.524978) (xy 387.829819 -274.549585)
			(xy 387.821924 -274.598162) (xy 387.80634 -274.644843) (xy 387.783469 -274.68842) (xy 387.753904 -274.727764)
			(xy 387.718411 -274.761856) (xy 387.677908 -274.789812) (xy 387.633446 -274.81091) (xy 387.586175 -274.824602)
			(xy 387.53732 -274.830534) (xy 387.488145 -274.828553) (xy 387.439926 -274.818709) (xy 387.39391 -274.801257)
			(xy 387.351289 -274.77665) (xy 387.313168 -274.745525) (xy 387.280533 -274.708688) (xy 387.25423 -274.667092)
			(xy 387.234939 -274.621816) (xy 387.223162 -274.574032) (xy 387.219202 -274.524978) (xy 386.906325 -274.524978)
			(xy 386.906326 -274.524985) (xy 386.90247 -274.575401) (xy 386.890987 -274.624643) (xy 386.872146 -274.671564)
			(xy 386.846384 -274.715072) (xy 386.814302 -274.754153) (xy 386.795772 -274.771358) (xy 386.787898 -274.77847)
			(xy 386.775198 -274.806156) (xy 386.771134 -274.818602) (xy 386.770372 -274.827746) (xy 386.770372 -275.17217)
			(xy 386.771134 -275.181314) (xy 386.775198 -275.19376) (xy 386.787898 -275.221446) (xy 386.795772 -275.228558)
			(xy 386.814277 -275.245786) (xy 386.846353 -275.284863) (xy 386.87211 -275.328365) (xy 386.890947 -275.375281)
			(xy 386.902427 -275.424516) (xy 386.90628 -275.474925) (xy 386.906279 -275.474938) (xy 387.219202 -275.474938)
			(xy 387.223162 -275.425884) (xy 387.234939 -275.3781) (xy 387.25423 -275.332824) (xy 387.280533 -275.291228)
			(xy 387.313168 -275.254391) (xy 387.351289 -275.223266) (xy 387.39391 -275.198659) (xy 387.439926 -275.181207)
			(xy 387.488145 -275.171363) (xy 387.53732 -275.169382) (xy 387.586175 -275.175314) (xy 387.633446 -275.189006)
			(xy 387.677908 -275.210104) (xy 387.718411 -275.23806) (xy 387.753904 -275.272152) (xy 387.783469 -275.311496)
			(xy 387.80634 -275.355073) (xy 387.821924 -275.401754) (xy 387.829819 -275.450331) (xy 387.830314 -275.474938)
			(xy 388.169162 -275.474938) (xy 388.173122 -275.425884) (xy 388.184899 -275.3781) (xy 388.20419 -275.332824)
			(xy 388.230493 -275.291228) (xy 388.263128 -275.254391) (xy 388.301249 -275.223266) (xy 388.34387 -275.198659)
			(xy 388.389886 -275.181207) (xy 388.438105 -275.171363) (xy 388.48728 -275.169382) (xy 388.536135 -275.175314)
			(xy 388.583406 -275.189006) (xy 388.627868 -275.210104) (xy 388.668371 -275.23806) (xy 388.703864 -275.272152)
			(xy 388.733429 -275.311496) (xy 388.7563 -275.355073) (xy 388.771884 -275.401754) (xy 388.779779 -275.450331)
			(xy 388.780274 -275.474938) (xy 389.119122 -275.474938) (xy 389.123082 -275.425884) (xy 389.134859 -275.3781)
			(xy 389.15415 -275.332824) (xy 389.180453 -275.291228) (xy 389.213088 -275.254391) (xy 389.251209 -275.223266)
			(xy 389.29383 -275.198659) (xy 389.339846 -275.181207) (xy 389.388065 -275.171363) (xy 389.43724 -275.169382)
			(xy 389.486095 -275.175314) (xy 389.533366 -275.189006) (xy 389.577828 -275.210104) (xy 389.618331 -275.23806)
			(xy 389.653824 -275.272152) (xy 389.683389 -275.311496) (xy 389.70626 -275.355073) (xy 389.721844 -275.401754)
			(xy 389.729739 -275.450331) (xy 389.730234 -275.474938) (xy 389.729739 -275.499545) (xy 389.721844 -275.548122)
			(xy 389.70626 -275.594803) (xy 389.683389 -275.63838) (xy 389.653824 -275.677724) (xy 389.618331 -275.711816)
			(xy 389.577828 -275.739772) (xy 389.533366 -275.76087) (xy 389.486095 -275.774562) (xy 389.43724 -275.780494)
			(xy 389.388065 -275.778513) (xy 389.339846 -275.768669) (xy 389.29383 -275.751217) (xy 389.251209 -275.72661)
			(xy 389.213088 -275.695485) (xy 389.180453 -275.658648) (xy 389.15415 -275.617052) (xy 389.134859 -275.571776)
			(xy 389.123082 -275.523992) (xy 389.119122 -275.474938) (xy 388.780274 -275.474938) (xy 388.779779 -275.499545)
			(xy 388.771884 -275.548122) (xy 388.7563 -275.594803) (xy 388.733429 -275.63838) (xy 388.703864 -275.677724)
			(xy 388.668371 -275.711816) (xy 388.627868 -275.739772) (xy 388.583406 -275.76087) (xy 388.536135 -275.774562)
			(xy 388.48728 -275.780494) (xy 388.438105 -275.778513) (xy 388.389886 -275.768669) (xy 388.34387 -275.751217)
			(xy 388.301249 -275.72661) (xy 388.263128 -275.695485) (xy 388.230493 -275.658648) (xy 388.20419 -275.617052)
			(xy 388.184899 -275.571776) (xy 388.173122 -275.523992) (xy 388.169162 -275.474938) (xy 387.830314 -275.474938)
			(xy 387.829819 -275.499545) (xy 387.821924 -275.548122) (xy 387.80634 -275.594803) (xy 387.783469 -275.63838)
			(xy 387.753904 -275.677724) (xy 387.718411 -275.711816) (xy 387.677908 -275.739772) (xy 387.633446 -275.76087)
			(xy 387.586175 -275.774562) (xy 387.53732 -275.780494) (xy 387.488145 -275.778513) (xy 387.439926 -275.768669)
			(xy 387.39391 -275.751217) (xy 387.351289 -275.72661) (xy 387.313168 -275.695485) (xy 387.280533 -275.658648)
			(xy 387.25423 -275.617052) (xy 387.234939 -275.571776) (xy 387.223162 -275.523992) (xy 387.219202 -275.474938)
			(xy 386.906279 -275.474938) (xy 386.902419 -275.525334) (xy 386.890932 -275.574568) (xy 386.872088 -275.62148)
			(xy 386.846324 -275.664979) (xy 386.814242 -275.704051) (xy 386.795772 -275.721318) (xy 386.787898 -275.72843)
			(xy 386.775198 -275.756116) (xy 386.771134 -275.768562) (xy 386.770372 -275.777706) (xy 386.770372 -276.12213)
			(xy 386.771134 -276.131274) (xy 386.775198 -276.14372) (xy 386.787898 -276.171406) (xy 386.795772 -276.178518)
			(xy 386.81428 -276.195745) (xy 386.846363 -276.234823) (xy 386.872125 -276.278328) (xy 386.890968 -276.325246)
			(xy 386.902453 -276.374485) (xy 386.906311 -276.424898) (xy 387.219202 -276.424898) (xy 387.223162 -276.375844)
			(xy 387.234939 -276.32806) (xy 387.25423 -276.282784) (xy 387.280533 -276.241188) (xy 387.313168 -276.204351)
			(xy 387.351289 -276.173226) (xy 387.39391 -276.148619) (xy 387.439926 -276.131167) (xy 387.488145 -276.121323)
			(xy 387.53732 -276.119342) (xy 387.586175 -276.125274) (xy 387.633446 -276.138966) (xy 387.677908 -276.160064)
			(xy 387.718411 -276.18802) (xy 387.753904 -276.222112) (xy 387.783469 -276.261456) (xy 387.80634 -276.305033)
			(xy 387.821924 -276.351714) (xy 387.829819 -276.400291) (xy 387.830314 -276.424898) (xy 388.169162 -276.424898)
			(xy 388.173122 -276.375844) (xy 388.184899 -276.32806) (xy 388.20419 -276.282784) (xy 388.230493 -276.241188)
			(xy 388.263128 -276.204351) (xy 388.301249 -276.173226) (xy 388.34387 -276.148619) (xy 388.389886 -276.131167)
			(xy 388.438105 -276.121323) (xy 388.48728 -276.119342) (xy 388.536135 -276.125274) (xy 388.583406 -276.138966)
			(xy 388.627868 -276.160064) (xy 388.668371 -276.18802) (xy 388.703864 -276.222112) (xy 388.733429 -276.261456)
			(xy 388.7563 -276.305033) (xy 388.771884 -276.351714) (xy 388.779779 -276.400291) (xy 388.780274 -276.424898)
			(xy 389.119122 -276.424898) (xy 389.123082 -276.375844) (xy 389.134859 -276.32806) (xy 389.15415 -276.282784)
			(xy 389.180453 -276.241188) (xy 389.213088 -276.204351) (xy 389.251209 -276.173226) (xy 389.29383 -276.148619)
			(xy 389.339846 -276.131167) (xy 389.388065 -276.121323) (xy 389.43724 -276.119342) (xy 389.486095 -276.125274)
			(xy 389.533366 -276.138966) (xy 389.577828 -276.160064) (xy 389.618331 -276.18802) (xy 389.653824 -276.222112)
			(xy 389.683389 -276.261456) (xy 389.70626 -276.305033) (xy 389.721844 -276.351714) (xy 389.729739 -276.400291)
			(xy 389.730234 -276.424898) (xy 389.729739 -276.449505) (xy 389.721844 -276.498082) (xy 389.70626 -276.544763)
			(xy 389.683389 -276.58834) (xy 389.653824 -276.627684) (xy 389.618331 -276.661776) (xy 389.577828 -276.689732)
			(xy 389.533366 -276.71083) (xy 389.486095 -276.724522) (xy 389.43724 -276.730454) (xy 389.388065 -276.728473)
			(xy 389.339846 -276.718629) (xy 389.29383 -276.701177) (xy 389.251209 -276.67657) (xy 389.213088 -276.645445)
			(xy 389.180453 -276.608608) (xy 389.15415 -276.567012) (xy 389.134859 -276.521736) (xy 389.123082 -276.473952)
			(xy 389.119122 -276.424898) (xy 388.780274 -276.424898) (xy 388.779779 -276.449505) (xy 388.771884 -276.498082)
			(xy 388.7563 -276.544763) (xy 388.733429 -276.58834) (xy 388.703864 -276.627684) (xy 388.668371 -276.661776)
			(xy 388.627868 -276.689732) (xy 388.583406 -276.71083) (xy 388.536135 -276.724522) (xy 388.48728 -276.730454)
			(xy 388.438105 -276.728473) (xy 388.389886 -276.718629) (xy 388.34387 -276.701177) (xy 388.301249 -276.67657)
			(xy 388.263128 -276.645445) (xy 388.230493 -276.608608) (xy 388.20419 -276.567012) (xy 388.184899 -276.521736)
			(xy 388.173122 -276.473952) (xy 388.169162 -276.424898) (xy 387.830314 -276.424898) (xy 387.829819 -276.449505)
			(xy 387.821924 -276.498082) (xy 387.80634 -276.544763) (xy 387.783469 -276.58834) (xy 387.753904 -276.627684)
			(xy 387.718411 -276.661776) (xy 387.677908 -276.689732) (xy 387.633446 -276.71083) (xy 387.586175 -276.724522)
			(xy 387.53732 -276.730454) (xy 387.488145 -276.728473) (xy 387.439926 -276.718629) (xy 387.39391 -276.701177)
			(xy 387.351289 -276.67657) (xy 387.313168 -276.645445) (xy 387.280533 -276.608608) (xy 387.25423 -276.567012)
			(xy 387.234939 -276.521736) (xy 387.223162 -276.473952) (xy 387.219202 -276.424898) (xy 386.906311 -276.424898)
			(xy 386.906311 -276.424899) (xy 386.902453 -276.475312) (xy 386.890969 -276.524551) (xy 386.872127 -276.57147)
			(xy 386.846364 -276.614975) (xy 386.814282 -276.654053) (xy 386.795772 -276.671278) (xy 386.787898 -276.67839)
			(xy 386.775198 -276.706076) (xy 386.771134 -276.718522) (xy 386.770372 -276.727666) (xy 386.770372 -277.07209)
			(xy 386.771134 -277.081234) (xy 386.775198 -277.09368) (xy 386.787898 -277.121366) (xy 386.795772 -277.128478)
			(xy 386.814283 -277.145705) (xy 386.846372 -277.184784) (xy 386.87214 -277.228291) (xy 386.890989 -277.275212)
			(xy 386.902478 -277.324454) (xy 386.90634 -277.374858) (xy 387.219202 -277.374858) (xy 387.223162 -277.325804)
			(xy 387.234939 -277.27802) (xy 387.25423 -277.232744) (xy 387.280533 -277.191148) (xy 387.313168 -277.154311)
			(xy 387.351289 -277.123186) (xy 387.39391 -277.098579) (xy 387.439926 -277.081127) (xy 387.488145 -277.071283)
			(xy 387.53732 -277.069302) (xy 387.586175 -277.075234) (xy 387.633446 -277.088926) (xy 387.677908 -277.110024)
			(xy 387.718411 -277.13798) (xy 387.753904 -277.172072) (xy 387.783469 -277.211416) (xy 387.80634 -277.254993)
			(xy 387.821924 -277.301674) (xy 387.829819 -277.350251) (xy 387.830314 -277.374858) (xy 388.169162 -277.374858)
			(xy 388.173122 -277.325804) (xy 388.184899 -277.27802) (xy 388.20419 -277.232744) (xy 388.230493 -277.191148)
			(xy 388.263128 -277.154311) (xy 388.301249 -277.123186) (xy 388.34387 -277.098579) (xy 388.389886 -277.081127)
			(xy 388.438105 -277.071283) (xy 388.48728 -277.069302) (xy 388.536135 -277.075234) (xy 388.583406 -277.088926)
			(xy 388.627868 -277.110024) (xy 388.668371 -277.13798) (xy 388.703864 -277.172072) (xy 388.733429 -277.211416)
			(xy 388.7563 -277.254993) (xy 388.771884 -277.301674) (xy 388.779779 -277.350251) (xy 388.780274 -277.374858)
			(xy 389.119122 -277.374858) (xy 389.123082 -277.325804) (xy 389.134859 -277.27802) (xy 389.15415 -277.232744)
			(xy 389.180453 -277.191148) (xy 389.213088 -277.154311) (xy 389.251209 -277.123186) (xy 389.29383 -277.098579)
			(xy 389.339846 -277.081127) (xy 389.388065 -277.071283) (xy 389.43724 -277.069302) (xy 389.486095 -277.075234)
			(xy 389.533366 -277.088926) (xy 389.577828 -277.110024) (xy 389.618331 -277.13798) (xy 389.653824 -277.172072)
			(xy 389.683389 -277.211416) (xy 389.70626 -277.254993) (xy 389.721844 -277.301674) (xy 389.729739 -277.350251)
			(xy 389.730234 -277.374858) (xy 389.729739 -277.399465) (xy 389.721844 -277.448042) (xy 389.70626 -277.494723)
			(xy 389.683389 -277.5383) (xy 389.653824 -277.577644) (xy 389.618331 -277.611736) (xy 389.577828 -277.639692)
			(xy 389.533366 -277.66079) (xy 389.486095 -277.674482) (xy 389.43724 -277.680414) (xy 389.388065 -277.678433)
			(xy 389.339846 -277.668589) (xy 389.29383 -277.651137) (xy 389.251209 -277.62653) (xy 389.213088 -277.595405)
			(xy 389.180453 -277.558568) (xy 389.15415 -277.516972) (xy 389.134859 -277.471696) (xy 389.123082 -277.423912)
			(xy 389.119122 -277.374858) (xy 388.780274 -277.374858) (xy 388.779779 -277.399465) (xy 388.771884 -277.448042)
			(xy 388.7563 -277.494723) (xy 388.733429 -277.5383) (xy 388.703864 -277.577644) (xy 388.668371 -277.611736)
			(xy 388.627868 -277.639692) (xy 388.583406 -277.66079) (xy 388.536135 -277.674482) (xy 388.48728 -277.680414)
			(xy 388.438105 -277.678433) (xy 388.389886 -277.668589) (xy 388.34387 -277.651137) (xy 388.301249 -277.62653)
			(xy 388.263128 -277.595405) (xy 388.230493 -277.558568) (xy 388.20419 -277.516972) (xy 388.184899 -277.471696)
			(xy 388.173122 -277.423912) (xy 388.169162 -277.374858) (xy 387.830314 -277.374858) (xy 387.829819 -277.399465)
			(xy 387.821924 -277.448042) (xy 387.80634 -277.494723) (xy 387.783469 -277.5383) (xy 387.753904 -277.577644)
			(xy 387.718411 -277.611736) (xy 387.677908 -277.639692) (xy 387.633446 -277.66079) (xy 387.586175 -277.674482)
			(xy 387.53732 -277.680414) (xy 387.488145 -277.678433) (xy 387.439926 -277.668589) (xy 387.39391 -277.651137)
			(xy 387.351289 -277.62653) (xy 387.313168 -277.595405) (xy 387.280533 -277.558568) (xy 387.25423 -277.516972)
			(xy 387.234939 -277.471696) (xy 387.223162 -277.423912) (xy 387.219202 -277.374858) (xy 386.90634 -277.374858)
			(xy 386.906341 -277.374872) (xy 386.902487 -277.42529) (xy 386.891006 -277.474535) (xy 386.872165 -277.521459)
			(xy 386.846404 -277.56497) (xy 386.814322 -277.604054) (xy 386.795772 -277.621238) (xy 386.787898 -277.62835)
			(xy 386.775198 -277.656036) (xy 386.771134 -277.668482) (xy 386.770372 -277.677626) (xy 386.770372 -278.02205)
			(xy 386.771134 -278.031194) (xy 386.775198 -278.04364) (xy 386.787898 -278.071326) (xy 386.795772 -278.078438)
			(xy 386.814279 -278.095665) (xy 386.846358 -278.134743) (xy 386.872118 -278.178247) (xy 386.890958 -278.225163)
			(xy 386.90244 -278.274401) (xy 386.906296 -278.324812) (xy 386.906296 -278.324818) (xy 387.219202 -278.324818)
			(xy 387.223162 -278.275764) (xy 387.234939 -278.22798) (xy 387.25423 -278.182704) (xy 387.280533 -278.141108)
			(xy 387.313168 -278.104271) (xy 387.351289 -278.073146) (xy 387.39391 -278.048539) (xy 387.439926 -278.031087)
			(xy 387.488145 -278.021243) (xy 387.53732 -278.019262) (xy 387.586175 -278.025194) (xy 387.633446 -278.038886)
			(xy 387.677908 -278.059984) (xy 387.718411 -278.08794) (xy 387.753904 -278.122032) (xy 387.783469 -278.161376)
			(xy 387.80634 -278.204953) (xy 387.821924 -278.251634) (xy 387.829819 -278.300211) (xy 387.830314 -278.324818)
			(xy 388.169162 -278.324818) (xy 388.173122 -278.275764) (xy 388.184899 -278.22798) (xy 388.20419 -278.182704)
			(xy 388.230493 -278.141108) (xy 388.263128 -278.104271) (xy 388.301249 -278.073146) (xy 388.34387 -278.048539)
			(xy 388.389886 -278.031087) (xy 388.438105 -278.021243) (xy 388.48728 -278.019262) (xy 388.536135 -278.025194)
			(xy 388.583406 -278.038886) (xy 388.627868 -278.059984) (xy 388.668371 -278.08794) (xy 388.703864 -278.122032)
			(xy 388.733429 -278.161376) (xy 388.7563 -278.204953) (xy 388.771884 -278.251634) (xy 388.779779 -278.300211)
			(xy 388.780274 -278.324818) (xy 389.119122 -278.324818) (xy 389.123082 -278.275764) (xy 389.134859 -278.22798)
			(xy 389.15415 -278.182704) (xy 389.180453 -278.141108) (xy 389.213088 -278.104271) (xy 389.251209 -278.073146)
			(xy 389.29383 -278.048539) (xy 389.339846 -278.031087) (xy 389.388065 -278.021243) (xy 389.43724 -278.019262)
			(xy 389.486095 -278.025194) (xy 389.533366 -278.038886) (xy 389.577828 -278.059984) (xy 389.618331 -278.08794)
			(xy 389.653824 -278.122032) (xy 389.683389 -278.161376) (xy 389.70626 -278.204953) (xy 389.721844 -278.251634)
			(xy 389.729739 -278.300211) (xy 389.730234 -278.324818) (xy 389.729739 -278.349425) (xy 389.721844 -278.398002)
			(xy 389.70626 -278.444683) (xy 389.683389 -278.48826) (xy 389.653824 -278.527604) (xy 389.618331 -278.561696)
			(xy 389.577828 -278.589652) (xy 389.533366 -278.61075) (xy 389.486095 -278.624442) (xy 389.43724 -278.630374)
			(xy 389.388065 -278.628393) (xy 389.339846 -278.618549) (xy 389.29383 -278.601097) (xy 389.251209 -278.57649)
			(xy 389.213088 -278.545365) (xy 389.180453 -278.508528) (xy 389.15415 -278.466932) (xy 389.134859 -278.421656)
			(xy 389.123082 -278.373872) (xy 389.119122 -278.324818) (xy 388.780274 -278.324818) (xy 388.779779 -278.349425)
			(xy 388.771884 -278.398002) (xy 388.7563 -278.444683) (xy 388.733429 -278.48826) (xy 388.703864 -278.527604)
			(xy 388.668371 -278.561696) (xy 388.627868 -278.589652) (xy 388.583406 -278.61075) (xy 388.536135 -278.624442)
			(xy 388.48728 -278.630374) (xy 388.438105 -278.628393) (xy 388.389886 -278.618549) (xy 388.34387 -278.601097)
			(xy 388.301249 -278.57649) (xy 388.263128 -278.545365) (xy 388.230493 -278.508528) (xy 388.20419 -278.466932)
			(xy 388.184899 -278.421656) (xy 388.173122 -278.373872) (xy 388.169162 -278.324818) (xy 387.830314 -278.324818)
			(xy 387.829819 -278.349425) (xy 387.821924 -278.398002) (xy 387.80634 -278.444683) (xy 387.783469 -278.48826)
			(xy 387.753904 -278.527604) (xy 387.718411 -278.561696) (xy 387.677908 -278.589652) (xy 387.633446 -278.61075)
			(xy 387.586175 -278.624442) (xy 387.53732 -278.630374) (xy 387.488145 -278.628393) (xy 387.439926 -278.618549)
			(xy 387.39391 -278.601097) (xy 387.351289 -278.57649) (xy 387.313168 -278.545365) (xy 387.280533 -278.508528)
			(xy 387.25423 -278.466932) (xy 387.234939 -278.421656) (xy 387.223162 -278.373872) (xy 387.219202 -278.324818)
			(xy 386.906296 -278.324818) (xy 386.902436 -278.375223) (xy 386.890951 -278.424459) (xy 386.872107 -278.471375)
			(xy 386.846344 -278.514877) (xy 386.814262 -278.553952) (xy 386.795772 -278.571198) (xy 386.787898 -278.57831)
			(xy 386.775198 -278.605996) (xy 386.771134 -278.618442) (xy 386.770372 -278.627586) (xy 386.770372 -278.97201)
			(xy 386.771134 -278.981154) (xy 386.775198 -278.9936) (xy 386.787898 -279.021286) (xy 386.795772 -279.028398)
			(xy 386.814282 -279.045625) (xy 386.846367 -279.084704) (xy 386.872133 -279.128209) (xy 386.890978 -279.175129)
			(xy 386.902465 -279.22437) (xy 386.906325 -279.274778) (xy 387.219202 -279.274778) (xy 387.223162 -279.225724)
			(xy 387.234939 -279.17794) (xy 387.25423 -279.132664) (xy 387.280533 -279.091068) (xy 387.313168 -279.054231)
			(xy 387.351289 -279.023106) (xy 387.39391 -278.998499) (xy 387.439926 -278.981047) (xy 387.488145 -278.971203)
			(xy 387.53732 -278.969222) (xy 387.586175 -278.975154) (xy 387.633446 -278.988846) (xy 387.677908 -279.009944)
			(xy 387.718411 -279.0379) (xy 387.753904 -279.071992) (xy 387.783469 -279.111336) (xy 387.80634 -279.154913)
			(xy 387.821924 -279.201594) (xy 387.829819 -279.250171) (xy 387.830314 -279.274778) (xy 388.169162 -279.274778)
			(xy 388.173122 -279.225724) (xy 388.184899 -279.17794) (xy 388.20419 -279.132664) (xy 388.230493 -279.091068)
			(xy 388.263128 -279.054231) (xy 388.301249 -279.023106) (xy 388.34387 -278.998499) (xy 388.389886 -278.981047)
			(xy 388.438105 -278.971203) (xy 388.48728 -278.969222) (xy 388.536135 -278.975154) (xy 388.583406 -278.988846)
			(xy 388.627868 -279.009944) (xy 388.668371 -279.0379) (xy 388.703864 -279.071992) (xy 388.733429 -279.111336)
			(xy 388.7563 -279.154913) (xy 388.771884 -279.201594) (xy 388.779779 -279.250171) (xy 388.780274 -279.274778)
			(xy 389.119122 -279.274778) (xy 389.123082 -279.225724) (xy 389.134859 -279.17794) (xy 389.15415 -279.132664)
			(xy 389.180453 -279.091068) (xy 389.213088 -279.054231) (xy 389.251209 -279.023106) (xy 389.29383 -278.998499)
			(xy 389.339846 -278.981047) (xy 389.388065 -278.971203) (xy 389.43724 -278.969222) (xy 389.486095 -278.975154)
			(xy 389.533366 -278.988846) (xy 389.577828 -279.009944) (xy 389.618331 -279.0379) (xy 389.653824 -279.071992)
			(xy 389.683389 -279.111336) (xy 389.70626 -279.154913) (xy 389.721844 -279.201594) (xy 389.729739 -279.250171)
			(xy 389.730234 -279.274778) (xy 389.729739 -279.299385) (xy 389.721844 -279.347962) (xy 389.70626 -279.394643)
			(xy 389.683389 -279.43822) (xy 389.653824 -279.477564) (xy 389.618331 -279.511656) (xy 389.577828 -279.539612)
			(xy 389.533366 -279.56071) (xy 389.486095 -279.574402) (xy 389.43724 -279.580334) (xy 389.388065 -279.578353)
			(xy 389.339846 -279.568509) (xy 389.29383 -279.551057) (xy 389.251209 -279.52645) (xy 389.213088 -279.495325)
			(xy 389.180453 -279.458488) (xy 389.15415 -279.416892) (xy 389.134859 -279.371616) (xy 389.123082 -279.323832)
			(xy 389.119122 -279.274778) (xy 388.780274 -279.274778) (xy 388.779779 -279.299385) (xy 388.771884 -279.347962)
			(xy 388.7563 -279.394643) (xy 388.733429 -279.43822) (xy 388.703864 -279.477564) (xy 388.668371 -279.511656)
			(xy 388.627868 -279.539612) (xy 388.583406 -279.56071) (xy 388.536135 -279.574402) (xy 388.48728 -279.580334)
			(xy 388.438105 -279.578353) (xy 388.389886 -279.568509) (xy 388.34387 -279.551057) (xy 388.301249 -279.52645)
			(xy 388.263128 -279.495325) (xy 388.230493 -279.458488) (xy 388.20419 -279.416892) (xy 388.184899 -279.371616)
			(xy 388.173122 -279.323832) (xy 388.169162 -279.274778) (xy 387.830314 -279.274778) (xy 387.829819 -279.299385)
			(xy 387.821924 -279.347962) (xy 387.80634 -279.394643) (xy 387.783469 -279.43822) (xy 387.753904 -279.477564)
			(xy 387.718411 -279.511656) (xy 387.677908 -279.539612) (xy 387.633446 -279.56071) (xy 387.586175 -279.574402)
			(xy 387.53732 -279.580334) (xy 387.488145 -279.578353) (xy 387.439926 -279.568509) (xy 387.39391 -279.551057)
			(xy 387.351289 -279.52645) (xy 387.313168 -279.495325) (xy 387.280533 -279.458488) (xy 387.25423 -279.416892)
			(xy 387.234939 -279.371616) (xy 387.223162 -279.323832) (xy 387.219202 -279.274778) (xy 386.906325 -279.274778)
			(xy 386.906326 -279.274785) (xy 386.90247 -279.325201) (xy 386.890987 -279.374443) (xy 386.872146 -279.421364)
			(xy 386.846384 -279.464872) (xy 386.814302 -279.503953) (xy 386.795772 -279.521158) (xy 386.787898 -279.52827)
			(xy 386.775198 -279.555956) (xy 386.771134 -279.568402) (xy 386.770372 -279.577546) (xy 386.770372 -279.92197)
			(xy 386.771134 -279.931114) (xy 386.775198 -279.94356) (xy 386.787898 -279.971246) (xy 386.795772 -279.978358)
			(xy 386.814277 -279.995586) (xy 386.846353 -280.034663) (xy 386.87211 -280.078165) (xy 386.890947 -280.125081)
			(xy 386.902427 -280.174316) (xy 386.90628 -280.224725) (xy 386.906279 -280.224738) (xy 387.219202 -280.224738)
			(xy 387.223162 -280.175684) (xy 387.234939 -280.1279) (xy 387.25423 -280.082624) (xy 387.280533 -280.041028)
			(xy 387.313168 -280.004191) (xy 387.351289 -279.973066) (xy 387.39391 -279.948459) (xy 387.439926 -279.931007)
			(xy 387.488145 -279.921163) (xy 387.53732 -279.919182) (xy 387.586175 -279.925114) (xy 387.633446 -279.938806)
			(xy 387.677908 -279.959904) (xy 387.718411 -279.98786) (xy 387.753904 -280.021952) (xy 387.783469 -280.061296)
			(xy 387.80634 -280.104873) (xy 387.821924 -280.151554) (xy 387.829819 -280.200131) (xy 387.830314 -280.224738)
			(xy 388.169162 -280.224738) (xy 388.173122 -280.175684) (xy 388.184899 -280.1279) (xy 388.20419 -280.082624)
			(xy 388.230493 -280.041028) (xy 388.263128 -280.004191) (xy 388.301249 -279.973066) (xy 388.34387 -279.948459)
			(xy 388.389886 -279.931007) (xy 388.438105 -279.921163) (xy 388.48728 -279.919182) (xy 388.536135 -279.925114)
			(xy 388.583406 -279.938806) (xy 388.627868 -279.959904) (xy 388.668371 -279.98786) (xy 388.703864 -280.021952)
			(xy 388.733429 -280.061296) (xy 388.7563 -280.104873) (xy 388.771884 -280.151554) (xy 388.779779 -280.200131)
			(xy 388.780274 -280.224738) (xy 389.119122 -280.224738) (xy 389.123082 -280.175684) (xy 389.134859 -280.1279)
			(xy 389.15415 -280.082624) (xy 389.180453 -280.041028) (xy 389.213088 -280.004191) (xy 389.251209 -279.973066)
			(xy 389.29383 -279.948459) (xy 389.339846 -279.931007) (xy 389.388065 -279.921163) (xy 389.43724 -279.919182)
			(xy 389.486095 -279.925114) (xy 389.533366 -279.938806) (xy 389.577828 -279.959904) (xy 389.618331 -279.98786)
			(xy 389.653824 -280.021952) (xy 389.683389 -280.061296) (xy 389.70626 -280.104873) (xy 389.721844 -280.151554)
			(xy 389.729739 -280.200131) (xy 389.730234 -280.224738) (xy 389.729739 -280.249345) (xy 389.721844 -280.297922)
			(xy 389.70626 -280.344603) (xy 389.683389 -280.38818) (xy 389.653824 -280.427524) (xy 389.618331 -280.461616)
			(xy 389.577828 -280.489572) (xy 389.533366 -280.51067) (xy 389.486095 -280.524362) (xy 389.43724 -280.530294)
			(xy 389.388065 -280.528313) (xy 389.339846 -280.518469) (xy 389.29383 -280.501017) (xy 389.251209 -280.47641)
			(xy 389.213088 -280.445285) (xy 389.180453 -280.408448) (xy 389.15415 -280.366852) (xy 389.134859 -280.321576)
			(xy 389.123082 -280.273792) (xy 389.119122 -280.224738) (xy 388.780274 -280.224738) (xy 388.779779 -280.249345)
			(xy 388.771884 -280.297922) (xy 388.7563 -280.344603) (xy 388.733429 -280.38818) (xy 388.703864 -280.427524)
			(xy 388.668371 -280.461616) (xy 388.627868 -280.489572) (xy 388.583406 -280.51067) (xy 388.536135 -280.524362)
			(xy 388.48728 -280.530294) (xy 388.438105 -280.528313) (xy 388.389886 -280.518469) (xy 388.34387 -280.501017)
			(xy 388.301249 -280.47641) (xy 388.263128 -280.445285) (xy 388.230493 -280.408448) (xy 388.20419 -280.366852)
			(xy 388.184899 -280.321576) (xy 388.173122 -280.273792) (xy 388.169162 -280.224738) (xy 387.830314 -280.224738)
			(xy 387.829819 -280.249345) (xy 387.821924 -280.297922) (xy 387.80634 -280.344603) (xy 387.783469 -280.38818)
			(xy 387.753904 -280.427524) (xy 387.718411 -280.461616) (xy 387.677908 -280.489572) (xy 387.633446 -280.51067)
			(xy 387.586175 -280.524362) (xy 387.53732 -280.530294) (xy 387.488145 -280.528313) (xy 387.439926 -280.518469)
			(xy 387.39391 -280.501017) (xy 387.351289 -280.47641) (xy 387.313168 -280.445285) (xy 387.280533 -280.408448)
			(xy 387.25423 -280.366852) (xy 387.234939 -280.321576) (xy 387.223162 -280.273792) (xy 387.219202 -280.224738)
			(xy 386.906279 -280.224738) (xy 386.902419 -280.275134) (xy 386.890932 -280.324368) (xy 386.872088 -280.37128)
			(xy 386.846324 -280.414779) (xy 386.814242 -280.453851) (xy 386.795772 -280.471118) (xy 386.787898 -280.47823)
			(xy 386.775198 -280.505916) (xy 386.771134 -280.518362) (xy 386.770372 -280.527506) (xy 386.770372 -280.872184)
			(xy 386.771134 -280.881328) (xy 386.775198 -280.893774) (xy 386.787898 -280.92146) (xy 386.795772 -280.928572)
			(xy 386.814283 -280.945799) (xy 386.846373 -280.984878) (xy 386.872142 -281.028385) (xy 386.890992 -281.075307)
			(xy 386.902482 -281.12455) (xy 386.906344 -281.174952) (xy 387.219202 -281.174952) (xy 387.223162 -281.125898)
			(xy 387.234939 -281.078114) (xy 387.25423 -281.032838) (xy 387.280533 -280.991242) (xy 387.313168 -280.954405)
			(xy 387.351289 -280.92328) (xy 387.39391 -280.898673) (xy 387.439926 -280.881221) (xy 387.488145 -280.871377)
			(xy 387.53732 -280.869396) (xy 387.586175 -280.875328) (xy 387.633446 -280.88902) (xy 387.677908 -280.910118)
			(xy 387.718411 -280.938074) (xy 387.753904 -280.972166) (xy 387.783469 -281.01151) (xy 387.80634 -281.055087)
			(xy 387.821924 -281.101768) (xy 387.829819 -281.150345) (xy 387.830314 -281.174952) (xy 388.169162 -281.174952)
			(xy 388.173122 -281.125898) (xy 388.184899 -281.078114) (xy 388.20419 -281.032838) (xy 388.230493 -280.991242)
			(xy 388.263128 -280.954405) (xy 388.301249 -280.92328) (xy 388.34387 -280.898673) (xy 388.389886 -280.881221)
			(xy 388.438105 -280.871377) (xy 388.48728 -280.869396) (xy 388.536135 -280.875328) (xy 388.583406 -280.88902)
			(xy 388.627868 -280.910118) (xy 388.668371 -280.938074) (xy 388.703864 -280.972166) (xy 388.733429 -281.01151)
			(xy 388.7563 -281.055087) (xy 388.771884 -281.101768) (xy 388.779779 -281.150345) (xy 388.780274 -281.174952)
			(xy 389.119122 -281.174952) (xy 389.123082 -281.125898) (xy 389.134859 -281.078114) (xy 389.15415 -281.032838)
			(xy 389.180453 -280.991242) (xy 389.213088 -280.954405) (xy 389.251209 -280.92328) (xy 389.29383 -280.898673)
			(xy 389.339846 -280.881221) (xy 389.388065 -280.871377) (xy 389.43724 -280.869396) (xy 389.486095 -280.875328)
			(xy 389.533366 -280.88902) (xy 389.577828 -280.910118) (xy 389.618331 -280.938074) (xy 389.653824 -280.972166)
			(xy 389.683389 -281.01151) (xy 389.70626 -281.055087) (xy 389.721844 -281.101768) (xy 389.729739 -281.150345)
			(xy 389.730234 -281.174952) (xy 389.729739 -281.199559) (xy 389.721844 -281.248136) (xy 389.70626 -281.294817)
			(xy 389.683389 -281.338394) (xy 389.653824 -281.377738) (xy 389.618331 -281.41183) (xy 389.577828 -281.439786)
			(xy 389.533366 -281.460884) (xy 389.486095 -281.474576) (xy 389.43724 -281.480508) (xy 389.388065 -281.478527)
			(xy 389.339846 -281.468683) (xy 389.29383 -281.451231) (xy 389.251209 -281.426624) (xy 389.213088 -281.395499)
			(xy 389.180453 -281.358662) (xy 389.15415 -281.317066) (xy 389.134859 -281.27179) (xy 389.123082 -281.224006)
			(xy 389.119122 -281.174952) (xy 388.780274 -281.174952) (xy 388.779779 -281.199559) (xy 388.771884 -281.248136)
			(xy 388.7563 -281.294817) (xy 388.733429 -281.338394) (xy 388.703864 -281.377738) (xy 388.668371 -281.41183)
			(xy 388.627868 -281.439786) (xy 388.583406 -281.460884) (xy 388.536135 -281.474576) (xy 388.48728 -281.480508)
			(xy 388.438105 -281.478527) (xy 388.389886 -281.468683) (xy 388.34387 -281.451231) (xy 388.301249 -281.426624)
			(xy 388.263128 -281.395499) (xy 388.230493 -281.358662) (xy 388.20419 -281.317066) (xy 388.184899 -281.27179)
			(xy 388.173122 -281.224006) (xy 388.169162 -281.174952) (xy 387.830314 -281.174952) (xy 387.829819 -281.199559)
			(xy 387.821924 -281.248136) (xy 387.80634 -281.294817) (xy 387.783469 -281.338394) (xy 387.753904 -281.377738)
			(xy 387.718411 -281.41183) (xy 387.677908 -281.439786) (xy 387.633446 -281.460884) (xy 387.586175 -281.474576)
			(xy 387.53732 -281.480508) (xy 387.488145 -281.478527) (xy 387.439926 -281.468683) (xy 387.39391 -281.451231)
			(xy 387.351289 -281.426624) (xy 387.313168 -281.395499) (xy 387.280533 -281.358662) (xy 387.25423 -281.317066)
			(xy 387.234939 -281.27179) (xy 387.223162 -281.224006) (xy 387.219202 -281.174952) (xy 386.906344 -281.174952)
			(xy 386.906345 -281.174968) (xy 386.902492 -281.225387) (xy 386.891011 -281.274632) (xy 386.872171 -281.321557)
			(xy 386.84641 -281.365069) (xy 386.814328 -281.404154) (xy 386.795772 -281.421332) (xy 386.787898 -281.428444)
			(xy 386.775198 -281.45613) (xy 386.771134 -281.468576) (xy 386.770372 -281.47772) (xy 386.770372 -281.822144)
			(xy 386.771134 -281.831288) (xy 386.775198 -281.843734) (xy 386.787898 -281.87142) (xy 386.795772 -281.878532)
			(xy 386.814279 -281.895759) (xy 386.846359 -281.934837) (xy 386.87212 -281.978341) (xy 386.890961 -282.025258)
			(xy 386.902444 -282.074496) (xy 386.9063 -282.124908) (xy 386.9063 -282.124912) (xy 387.219202 -282.124912)
			(xy 387.223162 -282.075858) (xy 387.234939 -282.028074) (xy 387.25423 -281.982798) (xy 387.280533 -281.941202)
			(xy 387.313168 -281.904365) (xy 387.351289 -281.87324) (xy 387.39391 -281.848633) (xy 387.439926 -281.831181)
			(xy 387.488145 -281.821337) (xy 387.53732 -281.819356) (xy 387.586175 -281.825288) (xy 387.633446 -281.83898)
			(xy 387.677908 -281.860078) (xy 387.718411 -281.888034) (xy 387.753904 -281.922126) (xy 387.783469 -281.96147)
			(xy 387.80634 -282.005047) (xy 387.821924 -282.051728) (xy 387.829819 -282.100305) (xy 387.830314 -282.124912)
			(xy 388.169162 -282.124912) (xy 388.173122 -282.075858) (xy 388.184899 -282.028074) (xy 388.20419 -281.982798)
			(xy 388.230493 -281.941202) (xy 388.263128 -281.904365) (xy 388.301249 -281.87324) (xy 388.34387 -281.848633)
			(xy 388.389886 -281.831181) (xy 388.438105 -281.821337) (xy 388.48728 -281.819356) (xy 388.536135 -281.825288)
			(xy 388.583406 -281.83898) (xy 388.627868 -281.860078) (xy 388.668371 -281.888034) (xy 388.703864 -281.922126)
			(xy 388.733429 -281.96147) (xy 388.7563 -282.005047) (xy 388.771884 -282.051728) (xy 388.779779 -282.100305)
			(xy 388.780274 -282.124912) (xy 389.119122 -282.124912) (xy 389.123082 -282.075858) (xy 389.134859 -282.028074)
			(xy 389.15415 -281.982798) (xy 389.180453 -281.941202) (xy 389.213088 -281.904365) (xy 389.251209 -281.87324)
			(xy 389.29383 -281.848633) (xy 389.339846 -281.831181) (xy 389.388065 -281.821337) (xy 389.43724 -281.819356)
			(xy 389.486095 -281.825288) (xy 389.533366 -281.83898) (xy 389.577828 -281.860078) (xy 389.618331 -281.888034)
			(xy 389.653824 -281.922126) (xy 389.683389 -281.96147) (xy 389.70626 -282.005047) (xy 389.721844 -282.051728)
			(xy 389.729739 -282.100305) (xy 389.730234 -282.124912) (xy 389.729739 -282.149519) (xy 389.721844 -282.198096)
			(xy 389.70626 -282.244777) (xy 389.683389 -282.288354) (xy 389.653824 -282.327698) (xy 389.618331 -282.36179)
			(xy 389.577828 -282.389746) (xy 389.533366 -282.410844) (xy 389.486095 -282.424536) (xy 389.43724 -282.430468)
			(xy 389.388065 -282.428487) (xy 389.339846 -282.418643) (xy 389.29383 -282.401191) (xy 389.251209 -282.376584)
			(xy 389.213088 -282.345459) (xy 389.180453 -282.308622) (xy 389.15415 -282.267026) (xy 389.134859 -282.22175)
			(xy 389.123082 -282.173966) (xy 389.119122 -282.124912) (xy 388.780274 -282.124912) (xy 388.779779 -282.149519)
			(xy 388.771884 -282.198096) (xy 388.7563 -282.244777) (xy 388.733429 -282.288354) (xy 388.703864 -282.327698)
			(xy 388.668371 -282.36179) (xy 388.627868 -282.389746) (xy 388.583406 -282.410844) (xy 388.536135 -282.424536)
			(xy 388.48728 -282.430468) (xy 388.438105 -282.428487) (xy 388.389886 -282.418643) (xy 388.34387 -282.401191)
			(xy 388.301249 -282.376584) (xy 388.263128 -282.345459) (xy 388.230493 -282.308622) (xy 388.20419 -282.267026)
			(xy 388.184899 -282.22175) (xy 388.173122 -282.173966) (xy 388.169162 -282.124912) (xy 387.830314 -282.124912)
			(xy 387.829819 -282.149519) (xy 387.821924 -282.198096) (xy 387.80634 -282.244777) (xy 387.783469 -282.288354)
			(xy 387.753904 -282.327698) (xy 387.718411 -282.36179) (xy 387.677908 -282.389746) (xy 387.633446 -282.410844)
			(xy 387.586175 -282.424536) (xy 387.53732 -282.430468) (xy 387.488145 -282.428487) (xy 387.439926 -282.418643)
			(xy 387.39391 -282.401191) (xy 387.351289 -282.376584) (xy 387.313168 -282.345459) (xy 387.280533 -282.308622)
			(xy 387.25423 -282.267026) (xy 387.234939 -282.22175) (xy 387.223162 -282.173966) (xy 387.219202 -282.124912)
			(xy 386.9063 -282.124912) (xy 386.902441 -282.17532) (xy 386.890956 -282.224557) (xy 386.872113 -282.271473)
			(xy 386.84635 -282.314976) (xy 386.814268 -282.354052) (xy 386.795772 -282.371292) (xy 386.787898 -282.378404)
			(xy 386.775198 -282.40609) (xy 386.771134 -282.418536) (xy 386.770372 -282.42768) (xy 386.770372 -282.772104)
			(xy 386.771134 -282.781248) (xy 386.775198 -282.793694) (xy 386.787898 -282.82138) (xy 386.795772 -282.828492)
			(xy 386.814282 -282.845719) (xy 386.846368 -282.884798) (xy 386.872135 -282.928304) (xy 386.890982 -282.975224)
			(xy 386.902469 -283.024465) (xy 386.906329 -283.074872) (xy 387.219202 -283.074872) (xy 387.223162 -283.025818)
			(xy 387.234939 -282.978034) (xy 387.25423 -282.932758) (xy 387.280533 -282.891162) (xy 387.313168 -282.854325)
			(xy 387.351289 -282.8232) (xy 387.39391 -282.798593) (xy 387.439926 -282.781141) (xy 387.488145 -282.771297)
			(xy 387.53732 -282.769316) (xy 387.586175 -282.775248) (xy 387.633446 -282.78894) (xy 387.677908 -282.810038)
			(xy 387.718411 -282.837994) (xy 387.753904 -282.872086) (xy 387.783469 -282.91143) (xy 387.80634 -282.955007)
			(xy 387.821924 -283.001688) (xy 387.829819 -283.050265) (xy 387.830314 -283.074872) (xy 388.169162 -283.074872)
			(xy 388.173122 -283.025818) (xy 388.184899 -282.978034) (xy 388.20419 -282.932758) (xy 388.230493 -282.891162)
			(xy 388.263128 -282.854325) (xy 388.301249 -282.8232) (xy 388.34387 -282.798593) (xy 388.389886 -282.781141)
			(xy 388.438105 -282.771297) (xy 388.48728 -282.769316) (xy 388.536135 -282.775248) (xy 388.583406 -282.78894)
			(xy 388.627868 -282.810038) (xy 388.668371 -282.837994) (xy 388.703864 -282.872086) (xy 388.733429 -282.91143)
			(xy 388.7563 -282.955007) (xy 388.771884 -283.001688) (xy 388.779779 -283.050265) (xy 388.780274 -283.074872)
			(xy 389.119122 -283.074872) (xy 389.123082 -283.025818) (xy 389.134859 -282.978034) (xy 389.15415 -282.932758)
			(xy 389.180453 -282.891162) (xy 389.213088 -282.854325) (xy 389.251209 -282.8232) (xy 389.29383 -282.798593)
			(xy 389.339846 -282.781141) (xy 389.388065 -282.771297) (xy 389.43724 -282.769316) (xy 389.486095 -282.775248)
			(xy 389.533366 -282.78894) (xy 389.577828 -282.810038) (xy 389.618331 -282.837994) (xy 389.653824 -282.872086)
			(xy 389.683389 -282.91143) (xy 389.70626 -282.955007) (xy 389.721844 -283.001688) (xy 389.729739 -283.050265)
			(xy 389.730234 -283.074872) (xy 389.729739 -283.099479) (xy 389.721844 -283.148056) (xy 389.70626 -283.194737)
			(xy 389.683389 -283.238314) (xy 389.653824 -283.277658) (xy 389.618331 -283.31175) (xy 389.577828 -283.339706)
			(xy 389.533366 -283.360804) (xy 389.486095 -283.374496) (xy 389.43724 -283.380428) (xy 389.388065 -283.378447)
			(xy 389.339846 -283.368603) (xy 389.29383 -283.351151) (xy 389.251209 -283.326544) (xy 389.213088 -283.295419)
			(xy 389.180453 -283.258582) (xy 389.15415 -283.216986) (xy 389.134859 -283.17171) (xy 389.123082 -283.123926)
			(xy 389.119122 -283.074872) (xy 388.780274 -283.074872) (xy 388.779779 -283.099479) (xy 388.771884 -283.148056)
			(xy 388.7563 -283.194737) (xy 388.733429 -283.238314) (xy 388.703864 -283.277658) (xy 388.668371 -283.31175)
			(xy 388.627868 -283.339706) (xy 388.583406 -283.360804) (xy 388.536135 -283.374496) (xy 388.48728 -283.380428)
			(xy 388.438105 -283.378447) (xy 388.389886 -283.368603) (xy 388.34387 -283.351151) (xy 388.301249 -283.326544)
			(xy 388.263128 -283.295419) (xy 388.230493 -283.258582) (xy 388.20419 -283.216986) (xy 388.184899 -283.17171)
			(xy 388.173122 -283.123926) (xy 388.169162 -283.074872) (xy 387.830314 -283.074872) (xy 387.829819 -283.099479)
			(xy 387.821924 -283.148056) (xy 387.80634 -283.194737) (xy 387.783469 -283.238314) (xy 387.753904 -283.277658)
			(xy 387.718411 -283.31175) (xy 387.677908 -283.339706) (xy 387.633446 -283.360804) (xy 387.586175 -283.374496)
			(xy 387.53732 -283.380428) (xy 387.488145 -283.378447) (xy 387.439926 -283.368603) (xy 387.39391 -283.351151)
			(xy 387.351289 -283.326544) (xy 387.313168 -283.295419) (xy 387.280533 -283.258582) (xy 387.25423 -283.216986)
			(xy 387.234939 -283.17171) (xy 387.223162 -283.123926) (xy 387.219202 -283.074872) (xy 386.906329 -283.074872)
			(xy 386.90633 -283.074881) (xy 386.902475 -283.125298) (xy 386.890993 -283.17454) (xy 386.872152 -283.221463)
			(xy 386.84639 -283.264971) (xy 386.814308 -283.304054) (xy 386.795772 -283.321252) (xy 386.787898 -283.328364)
			(xy 386.775198 -283.35605) (xy 386.771134 -283.368496) (xy 386.770372 -283.37764) (xy 386.770372 -283.722064)
			(xy 386.771134 -283.731208) (xy 386.775198 -283.743654) (xy 386.787898 -283.77134) (xy 386.795772 -283.778452)
			(xy 386.814277 -283.79568) (xy 386.846354 -283.834757) (xy 386.872112 -283.87826) (xy 386.89095 -283.925176)
			(xy 386.902431 -283.974412) (xy 386.906285 -284.024821) (xy 386.906284 -284.024832) (xy 387.219202 -284.024832)
			(xy 387.223162 -283.975778) (xy 387.234939 -283.927994) (xy 387.25423 -283.882718) (xy 387.280533 -283.841122)
			(xy 387.313168 -283.804285) (xy 387.351289 -283.77316) (xy 387.39391 -283.748553) (xy 387.439926 -283.731101)
			(xy 387.488145 -283.721257) (xy 387.53732 -283.719276) (xy 387.586175 -283.725208) (xy 387.633446 -283.7389)
			(xy 387.677908 -283.759998) (xy 387.718411 -283.787954) (xy 387.753904 -283.822046) (xy 387.783469 -283.86139)
			(xy 387.80634 -283.904967) (xy 387.821924 -283.951648) (xy 387.829819 -284.000225) (xy 387.830314 -284.024832)
			(xy 388.169162 -284.024832) (xy 388.173122 -283.975778) (xy 388.184899 -283.927994) (xy 388.20419 -283.882718)
			(xy 388.230493 -283.841122) (xy 388.263128 -283.804285) (xy 388.301249 -283.77316) (xy 388.34387 -283.748553)
			(xy 388.389886 -283.731101) (xy 388.438105 -283.721257) (xy 388.48728 -283.719276) (xy 388.536135 -283.725208)
			(xy 388.583406 -283.7389) (xy 388.627868 -283.759998) (xy 388.668371 -283.787954) (xy 388.703864 -283.822046)
			(xy 388.733429 -283.86139) (xy 388.7563 -283.904967) (xy 388.771884 -283.951648) (xy 388.779779 -284.000225)
			(xy 388.780274 -284.024832) (xy 389.119122 -284.024832) (xy 389.123082 -283.975778) (xy 389.134859 -283.927994)
			(xy 389.15415 -283.882718) (xy 389.180453 -283.841122) (xy 389.213088 -283.804285) (xy 389.251209 -283.77316)
			(xy 389.29383 -283.748553) (xy 389.339846 -283.731101) (xy 389.388065 -283.721257) (xy 389.43724 -283.719276)
			(xy 389.486095 -283.725208) (xy 389.533366 -283.7389) (xy 389.577828 -283.759998) (xy 389.618331 -283.787954)
			(xy 389.653824 -283.822046) (xy 389.683389 -283.86139) (xy 389.70626 -283.904967) (xy 389.721844 -283.951648)
			(xy 389.729739 -284.000225) (xy 389.730234 -284.024832) (xy 389.729739 -284.049439) (xy 389.721844 -284.098016)
			(xy 389.70626 -284.144697) (xy 389.683389 -284.188274) (xy 389.653824 -284.227618) (xy 389.618331 -284.26171)
			(xy 389.577828 -284.289666) (xy 389.533366 -284.310764) (xy 389.486095 -284.324456) (xy 389.43724 -284.330388)
			(xy 389.388065 -284.328407) (xy 389.339846 -284.318563) (xy 389.29383 -284.301111) (xy 389.251209 -284.276504)
			(xy 389.213088 -284.245379) (xy 389.180453 -284.208542) (xy 389.15415 -284.166946) (xy 389.134859 -284.12167)
			(xy 389.123082 -284.073886) (xy 389.119122 -284.024832) (xy 388.780274 -284.024832) (xy 388.779779 -284.049439)
			(xy 388.771884 -284.098016) (xy 388.7563 -284.144697) (xy 388.733429 -284.188274) (xy 388.703864 -284.227618)
			(xy 388.668371 -284.26171) (xy 388.627868 -284.289666) (xy 388.583406 -284.310764) (xy 388.536135 -284.324456)
			(xy 388.48728 -284.330388) (xy 388.438105 -284.328407) (xy 388.389886 -284.318563) (xy 388.34387 -284.301111)
			(xy 388.301249 -284.276504) (xy 388.263128 -284.245379) (xy 388.230493 -284.208542) (xy 388.20419 -284.166946)
			(xy 388.184899 -284.12167) (xy 388.173122 -284.073886) (xy 388.169162 -284.024832) (xy 387.830314 -284.024832)
			(xy 387.829819 -284.049439) (xy 387.821924 -284.098016) (xy 387.80634 -284.144697) (xy 387.783469 -284.188274)
			(xy 387.753904 -284.227618) (xy 387.718411 -284.26171) (xy 387.677908 -284.289666) (xy 387.633446 -284.310764)
			(xy 387.586175 -284.324456) (xy 387.53732 -284.330388) (xy 387.488145 -284.328407) (xy 387.439926 -284.318563)
			(xy 387.39391 -284.301111) (xy 387.351289 -284.276504) (xy 387.313168 -284.245379) (xy 387.280533 -284.208542)
			(xy 387.25423 -284.166946) (xy 387.234939 -284.12167) (xy 387.223162 -284.073886) (xy 387.219202 -284.024832)
			(xy 386.906284 -284.024832) (xy 386.902424 -284.07523) (xy 386.890938 -284.124465) (xy 386.872093 -284.171379)
			(xy 386.84633 -284.214878) (xy 386.814248 -284.253951) (xy 386.795772 -284.271212) (xy 386.787898 -284.278324)
			(xy 386.775198 -284.30601) (xy 386.771134 -284.318456) (xy 386.770372 -284.3276) (xy 386.770372 -284.672024)
			(xy 386.771134 -284.681168) (xy 386.775198 -284.693614) (xy 386.787898 -284.7213) (xy 386.795772 -284.728412)
			(xy 386.81428 -284.745639) (xy 386.846364 -284.784717) (xy 386.872128 -284.828222) (xy 386.890971 -284.875141)
			(xy 386.902456 -284.924381) (xy 386.906315 -284.974792) (xy 387.219202 -284.974792) (xy 387.223162 -284.925738)
			(xy 387.234939 -284.877954) (xy 387.25423 -284.832678) (xy 387.280533 -284.791082) (xy 387.313168 -284.754245)
			(xy 387.351289 -284.72312) (xy 387.39391 -284.698513) (xy 387.439926 -284.681061) (xy 387.488145 -284.671217)
			(xy 387.53732 -284.669236) (xy 387.586175 -284.675168) (xy 387.633446 -284.68886) (xy 387.677908 -284.709958)
			(xy 387.718411 -284.737914) (xy 387.753904 -284.772006) (xy 387.783469 -284.81135) (xy 387.80634 -284.854927)
			(xy 387.821924 -284.901608) (xy 387.829819 -284.950185) (xy 387.830314 -284.974792) (xy 388.169162 -284.974792)
			(xy 388.173122 -284.925738) (xy 388.184899 -284.877954) (xy 388.20419 -284.832678) (xy 388.230493 -284.791082)
			(xy 388.263128 -284.754245) (xy 388.301249 -284.72312) (xy 388.34387 -284.698513) (xy 388.389886 -284.681061)
			(xy 388.438105 -284.671217) (xy 388.48728 -284.669236) (xy 388.536135 -284.675168) (xy 388.583406 -284.68886)
			(xy 388.627868 -284.709958) (xy 388.668371 -284.737914) (xy 388.703864 -284.772006) (xy 388.733429 -284.81135)
			(xy 388.7563 -284.854927) (xy 388.771884 -284.901608) (xy 388.779779 -284.950185) (xy 388.780274 -284.974792)
			(xy 389.119122 -284.974792) (xy 389.123082 -284.925738) (xy 389.134859 -284.877954) (xy 389.15415 -284.832678)
			(xy 389.180453 -284.791082) (xy 389.213088 -284.754245) (xy 389.251209 -284.72312) (xy 389.29383 -284.698513)
			(xy 389.339846 -284.681061) (xy 389.388065 -284.671217) (xy 389.43724 -284.669236) (xy 389.486095 -284.675168)
			(xy 389.533366 -284.68886) (xy 389.577828 -284.709958) (xy 389.618331 -284.737914) (xy 389.653824 -284.772006)
			(xy 389.683389 -284.81135) (xy 389.70626 -284.854927) (xy 389.721844 -284.901608) (xy 389.729739 -284.950185)
			(xy 389.730234 -284.974792) (xy 389.729739 -284.999399) (xy 389.721844 -285.047976) (xy 389.70626 -285.094657)
			(xy 389.683389 -285.138234) (xy 389.653824 -285.177578) (xy 389.618331 -285.21167) (xy 389.577828 -285.239626)
			(xy 389.533366 -285.260724) (xy 389.486095 -285.274416) (xy 389.43724 -285.280348) (xy 389.388065 -285.278367)
			(xy 389.339846 -285.268523) (xy 389.29383 -285.251071) (xy 389.251209 -285.226464) (xy 389.213088 -285.195339)
			(xy 389.180453 -285.158502) (xy 389.15415 -285.116906) (xy 389.134859 -285.07163) (xy 389.123082 -285.023846)
			(xy 389.119122 -284.974792) (xy 388.780274 -284.974792) (xy 388.779779 -284.999399) (xy 388.771884 -285.047976)
			(xy 388.7563 -285.094657) (xy 388.733429 -285.138234) (xy 388.703864 -285.177578) (xy 388.668371 -285.21167)
			(xy 388.627868 -285.239626) (xy 388.583406 -285.260724) (xy 388.536135 -285.274416) (xy 388.48728 -285.280348)
			(xy 388.438105 -285.278367) (xy 388.389886 -285.268523) (xy 388.34387 -285.251071) (xy 388.301249 -285.226464)
			(xy 388.263128 -285.195339) (xy 388.230493 -285.158502) (xy 388.20419 -285.116906) (xy 388.184899 -285.07163)
			(xy 388.173122 -285.023846) (xy 388.169162 -284.974792) (xy 387.830314 -284.974792) (xy 387.829819 -284.999399)
			(xy 387.821924 -285.047976) (xy 387.80634 -285.094657) (xy 387.783469 -285.138234) (xy 387.753904 -285.177578)
			(xy 387.718411 -285.21167) (xy 387.677908 -285.239626) (xy 387.633446 -285.260724) (xy 387.586175 -285.274416)
			(xy 387.53732 -285.280348) (xy 387.488145 -285.278367) (xy 387.439926 -285.268523) (xy 387.39391 -285.251071)
			(xy 387.351289 -285.226464) (xy 387.313168 -285.195339) (xy 387.280533 -285.158502) (xy 387.25423 -285.116906)
			(xy 387.234939 -285.07163) (xy 387.223162 -285.023846) (xy 387.219202 -284.974792) (xy 386.906315 -284.974792)
			(xy 386.906315 -284.974795) (xy 386.902458 -285.025209) (xy 386.890975 -285.074449) (xy 386.872132 -285.121368)
			(xy 386.84637 -285.164874) (xy 386.814288 -285.203953) (xy 386.795772 -285.221172) (xy 386.787898 -285.228284)
			(xy 386.775198 -285.25597) (xy 386.771134 -285.268416) (xy 386.770372 -285.27756) (xy 386.770372 -285.621984)
			(xy 386.771134 -285.631128) (xy 386.775198 -285.643574) (xy 386.787898 -285.67126) (xy 386.795772 -285.678372)
			(xy 386.814283 -285.695599) (xy 386.846373 -285.734678) (xy 386.872142 -285.778185) (xy 386.890992 -285.825107)
			(xy 386.902482 -285.87435) (xy 386.906344 -285.924752) (xy 387.219202 -285.924752) (xy 387.223162 -285.875698)
			(xy 387.234939 -285.827914) (xy 387.25423 -285.782638) (xy 387.280533 -285.741042) (xy 387.313168 -285.704205)
			(xy 387.351289 -285.67308) (xy 387.39391 -285.648473) (xy 387.439926 -285.631021) (xy 387.488145 -285.621177)
			(xy 387.53732 -285.619196) (xy 387.586175 -285.625128) (xy 387.633446 -285.63882) (xy 387.677908 -285.659918)
			(xy 387.718411 -285.687874) (xy 387.753904 -285.721966) (xy 387.783469 -285.76131) (xy 387.80634 -285.804887)
			(xy 387.821924 -285.851568) (xy 387.829819 -285.900145) (xy 387.830314 -285.924752) (xy 388.169162 -285.924752)
			(xy 388.173122 -285.875698) (xy 388.184899 -285.827914) (xy 388.20419 -285.782638) (xy 388.230493 -285.741042)
			(xy 388.263128 -285.704205) (xy 388.301249 -285.67308) (xy 388.34387 -285.648473) (xy 388.389886 -285.631021)
			(xy 388.438105 -285.621177) (xy 388.48728 -285.619196) (xy 388.536135 -285.625128) (xy 388.583406 -285.63882)
			(xy 388.627868 -285.659918) (xy 388.668371 -285.687874) (xy 388.703864 -285.721966) (xy 388.733429 -285.76131)
			(xy 388.7563 -285.804887) (xy 388.771884 -285.851568) (xy 388.779779 -285.900145) (xy 388.780274 -285.924752)
			(xy 389.119122 -285.924752) (xy 389.123082 -285.875698) (xy 389.134859 -285.827914) (xy 389.15415 -285.782638)
			(xy 389.180453 -285.741042) (xy 389.213088 -285.704205) (xy 389.251209 -285.67308) (xy 389.29383 -285.648473)
			(xy 389.339846 -285.631021) (xy 389.388065 -285.621177) (xy 389.43724 -285.619196) (xy 389.486095 -285.625128)
			(xy 389.533366 -285.63882) (xy 389.577828 -285.659918) (xy 389.618331 -285.687874) (xy 389.653824 -285.721966)
			(xy 389.683389 -285.76131) (xy 389.70626 -285.804887) (xy 389.721844 -285.851568) (xy 389.729739 -285.900145)
			(xy 389.730234 -285.924752) (xy 389.729739 -285.949359) (xy 389.721844 -285.997936) (xy 389.70626 -286.044617)
			(xy 389.683389 -286.088194) (xy 389.653824 -286.127538) (xy 389.618331 -286.16163) (xy 389.577828 -286.189586)
			(xy 389.533366 -286.210684) (xy 389.486095 -286.224376) (xy 389.43724 -286.230308) (xy 389.388065 -286.228327)
			(xy 389.339846 -286.218483) (xy 389.29383 -286.201031) (xy 389.251209 -286.176424) (xy 389.213088 -286.145299)
			(xy 389.180453 -286.108462) (xy 389.15415 -286.066866) (xy 389.134859 -286.02159) (xy 389.123082 -285.973806)
			(xy 389.119122 -285.924752) (xy 388.780274 -285.924752) (xy 388.779779 -285.949359) (xy 388.771884 -285.997936)
			(xy 388.7563 -286.044617) (xy 388.733429 -286.088194) (xy 388.703864 -286.127538) (xy 388.668371 -286.16163)
			(xy 388.627868 -286.189586) (xy 388.583406 -286.210684) (xy 388.536135 -286.224376) (xy 388.48728 -286.230308)
			(xy 388.438105 -286.228327) (xy 388.389886 -286.218483) (xy 388.34387 -286.201031) (xy 388.301249 -286.176424)
			(xy 388.263128 -286.145299) (xy 388.230493 -286.108462) (xy 388.20419 -286.066866) (xy 388.184899 -286.02159)
			(xy 388.173122 -285.973806) (xy 388.169162 -285.924752) (xy 387.830314 -285.924752) (xy 387.829819 -285.949359)
			(xy 387.821924 -285.997936) (xy 387.80634 -286.044617) (xy 387.783469 -286.088194) (xy 387.753904 -286.127538)
			(xy 387.718411 -286.16163) (xy 387.677908 -286.189586) (xy 387.633446 -286.210684) (xy 387.586175 -286.224376)
			(xy 387.53732 -286.230308) (xy 387.488145 -286.228327) (xy 387.439926 -286.218483) (xy 387.39391 -286.201031)
			(xy 387.351289 -286.176424) (xy 387.313168 -286.145299) (xy 387.280533 -286.108462) (xy 387.25423 -286.066866)
			(xy 387.234939 -286.02159) (xy 387.223162 -285.973806) (xy 387.219202 -285.924752) (xy 386.906344 -285.924752)
			(xy 386.906345 -285.924768) (xy 386.902492 -285.975187) (xy 386.891011 -286.024432) (xy 386.872171 -286.071357)
			(xy 386.84641 -286.114869) (xy 386.814328 -286.153954) (xy 386.795772 -286.171132) (xy 386.787898 -286.178244)
			(xy 386.775198 -286.20593) (xy 386.771134 -286.218376) (xy 386.770372 -286.22752) (xy 386.770372 -286.572198)
			(xy 386.771134 -286.581342) (xy 386.775198 -286.593788) (xy 386.787898 -286.621474) (xy 386.795772 -286.628586)
			(xy 386.816096 -286.647576) (xy 386.850714 -286.691108) (xy 386.87757 -286.739813) (xy 386.895906 -286.792322)
			(xy 386.905209 -286.847157) (xy 386.905754 -286.874966) (xy 387.219202 -286.874966) (xy 387.223162 -286.825912)
			(xy 387.234939 -286.778128) (xy 387.25423 -286.732852) (xy 387.280533 -286.691256) (xy 387.313168 -286.654419)
			(xy 387.351289 -286.623294) (xy 387.39391 -286.598687) (xy 387.439926 -286.581235) (xy 387.488145 -286.571391)
			(xy 387.53732 -286.56941) (xy 387.586175 -286.575342) (xy 387.633446 -286.589034) (xy 387.677908 -286.610132)
			(xy 387.718411 -286.638088) (xy 387.753904 -286.67218) (xy 387.783469 -286.711524) (xy 387.80634 -286.755101)
			(xy 387.821924 -286.801782) (xy 387.829819 -286.850359) (xy 387.830314 -286.874966) (xy 388.169162 -286.874966)
			(xy 388.173122 -286.825912) (xy 388.184899 -286.778128) (xy 388.20419 -286.732852) (xy 388.230493 -286.691256)
			(xy 388.263128 -286.654419) (xy 388.301249 -286.623294) (xy 388.34387 -286.598687) (xy 388.389886 -286.581235)
			(xy 388.438105 -286.571391) (xy 388.48728 -286.56941) (xy 388.536135 -286.575342) (xy 388.583406 -286.589034)
			(xy 388.627868 -286.610132) (xy 388.668371 -286.638088) (xy 388.703864 -286.67218) (xy 388.733429 -286.711524)
			(xy 388.7563 -286.755101) (xy 388.771884 -286.801782) (xy 388.779779 -286.850359) (xy 388.780274 -286.874966)
			(xy 389.119122 -286.874966) (xy 389.123082 -286.825912) (xy 389.134859 -286.778128) (xy 389.15415 -286.732852)
			(xy 389.180453 -286.691256) (xy 389.213088 -286.654419) (xy 389.251209 -286.623294) (xy 389.29383 -286.598687)
			(xy 389.339846 -286.581235) (xy 389.388065 -286.571391) (xy 389.43724 -286.56941) (xy 389.486095 -286.575342)
			(xy 389.533366 -286.589034) (xy 389.577828 -286.610132) (xy 389.618331 -286.638088) (xy 389.653824 -286.67218)
			(xy 389.683389 -286.711524) (xy 389.70626 -286.755101) (xy 389.721844 -286.801782) (xy 389.729739 -286.850359)
			(xy 389.730234 -286.874966) (xy 390.069082 -286.874966) (xy 390.073042 -286.825912) (xy 390.084819 -286.778128)
			(xy 390.10411 -286.732852) (xy 390.130413 -286.691256) (xy 390.163048 -286.654419) (xy 390.201169 -286.623294)
			(xy 390.24379 -286.598687) (xy 390.289806 -286.581235) (xy 390.338025 -286.571391) (xy 390.3872 -286.56941)
			(xy 390.436055 -286.575342) (xy 390.483326 -286.589034) (xy 390.527788 -286.610132) (xy 390.568291 -286.638088)
			(xy 390.603784 -286.67218) (xy 390.633349 -286.711524) (xy 390.65622 -286.755101) (xy 390.671804 -286.801782)
			(xy 390.679699 -286.850359) (xy 390.680189 -286.874712) (xy 391.019042 -286.874712) (xy 391.023002 -286.825658)
			(xy 391.034779 -286.777874) (xy 391.05407 -286.732598) (xy 391.080373 -286.691002) (xy 391.113008 -286.654165)
			(xy 391.151129 -286.62304) (xy 391.19375 -286.598433) (xy 391.239766 -286.580981) (xy 391.287985 -286.571137)
			(xy 391.33716 -286.569156) (xy 391.386015 -286.575088) (xy 391.433286 -286.58878) (xy 391.477748 -286.609878)
			(xy 391.518251 -286.637834) (xy 391.553744 -286.671926) (xy 391.583309 -286.71127) (xy 391.60618 -286.754847)
			(xy 391.621764 -286.801528) (xy 391.629659 -286.850105) (xy 391.630154 -286.874712) (xy 391.969002 -286.874712)
			(xy 391.972962 -286.825658) (xy 391.984739 -286.777874) (xy 392.00403 -286.732598) (xy 392.030333 -286.691002)
			(xy 392.062968 -286.654165) (xy 392.101089 -286.62304) (xy 392.14371 -286.598433) (xy 392.189726 -286.580981)
			(xy 392.237945 -286.571137) (xy 392.28712 -286.569156) (xy 392.335975 -286.575088) (xy 392.383246 -286.58878)
			(xy 392.427708 -286.609878) (xy 392.468211 -286.637834) (xy 392.503704 -286.671926) (xy 392.533269 -286.71127)
			(xy 392.55614 -286.754847) (xy 392.571724 -286.801528) (xy 392.579619 -286.850105) (xy 392.580114 -286.874712)
			(xy 392.579619 -286.899319) (xy 392.571724 -286.947896) (xy 392.55614 -286.994577) (xy 392.533269 -287.038154)
			(xy 392.503704 -287.077498) (xy 392.468211 -287.11159) (xy 392.427708 -287.139546) (xy 392.383246 -287.160644)
			(xy 392.335975 -287.174336) (xy 392.28712 -287.180268) (xy 392.237945 -287.178287) (xy 392.189726 -287.168443)
			(xy 392.14371 -287.150991) (xy 392.101089 -287.126384) (xy 392.062968 -287.095259) (xy 392.030333 -287.058422)
			(xy 392.00403 -287.016826) (xy 391.984739 -286.97155) (xy 391.972962 -286.923766) (xy 391.969002 -286.874712)
			(xy 391.630154 -286.874712) (xy 391.629659 -286.899319) (xy 391.621764 -286.947896) (xy 391.60618 -286.994577)
			(xy 391.583309 -287.038154) (xy 391.553744 -287.077498) (xy 391.518251 -287.11159) (xy 391.477748 -287.139546)
			(xy 391.433286 -287.160644) (xy 391.386015 -287.174336) (xy 391.33716 -287.180268) (xy 391.287985 -287.178287)
			(xy 391.239766 -287.168443) (xy 391.19375 -287.150991) (xy 391.151129 -287.126384) (xy 391.113008 -287.095259)
			(xy 391.080373 -287.058422) (xy 391.05407 -287.016826) (xy 391.034779 -286.97155) (xy 391.023002 -286.923766)
			(xy 391.019042 -286.874712) (xy 390.680189 -286.874712) (xy 390.680194 -286.874966) (xy 390.679699 -286.899573)
			(xy 390.671804 -286.94815) (xy 390.65622 -286.994831) (xy 390.633349 -287.038408) (xy 390.603784 -287.077752)
			(xy 390.568291 -287.111844) (xy 390.527788 -287.1398) (xy 390.483326 -287.160898) (xy 390.436055 -287.17459)
			(xy 390.3872 -287.180522) (xy 390.338025 -287.178541) (xy 390.289806 -287.168697) (xy 390.24379 -287.151245)
			(xy 390.201169 -287.126638) (xy 390.163048 -287.095513) (xy 390.130413 -287.058676) (xy 390.10411 -287.01708)
			(xy 390.084819 -286.971804) (xy 390.073042 -286.92402) (xy 390.069082 -286.874966) (xy 389.730234 -286.874966)
			(xy 389.729739 -286.899573) (xy 389.721844 -286.94815) (xy 389.70626 -286.994831) (xy 389.683389 -287.038408)
			(xy 389.653824 -287.077752) (xy 389.618331 -287.111844) (xy 389.577828 -287.1398) (xy 389.533366 -287.160898)
			(xy 389.486095 -287.17459) (xy 389.43724 -287.180522) (xy 389.388065 -287.178541) (xy 389.339846 -287.168697)
			(xy 389.29383 -287.151245) (xy 389.251209 -287.126638) (xy 389.213088 -287.095513) (xy 389.180453 -287.058676)
			(xy 389.15415 -287.01708) (xy 389.134859 -286.971804) (xy 389.123082 -286.92402) (xy 389.119122 -286.874966)
			(xy 388.780274 -286.874966) (xy 388.779779 -286.899573) (xy 388.771884 -286.94815) (xy 388.7563 -286.994831)
			(xy 388.733429 -287.038408) (xy 388.703864 -287.077752) (xy 388.668371 -287.111844) (xy 388.627868 -287.1398)
			(xy 388.583406 -287.160898) (xy 388.536135 -287.17459) (xy 388.48728 -287.180522) (xy 388.438105 -287.178541)
			(xy 388.389886 -287.168697) (xy 388.34387 -287.151245) (xy 388.301249 -287.126638) (xy 388.263128 -287.095513)
			(xy 388.230493 -287.058676) (xy 388.20419 -287.01708) (xy 388.184899 -286.971804) (xy 388.173122 -286.92402)
			(xy 388.169162 -286.874966) (xy 387.830314 -286.874966) (xy 387.829819 -286.899573) (xy 387.821924 -286.94815)
			(xy 387.80634 -286.994831) (xy 387.783469 -287.038408) (xy 387.753904 -287.077752) (xy 387.718411 -287.111844)
			(xy 387.677908 -287.1398) (xy 387.633446 -287.160898) (xy 387.586175 -287.17459) (xy 387.53732 -287.180522)
			(xy 387.488145 -287.178541) (xy 387.439926 -287.168697) (xy 387.39391 -287.151245) (xy 387.351289 -287.126638)
			(xy 387.313168 -287.095513) (xy 387.280533 -287.058676) (xy 387.25423 -287.01708) (xy 387.234939 -286.971804)
			(xy 387.223162 -286.92402) (xy 387.219202 -286.874966) (xy 386.905754 -286.874966) (xy 386.905364 -286.897899)
			(xy 386.899028 -286.943324) (xy 386.886473 -286.987437) (xy 386.87756 -287.00857) (xy 386.873242 -287.018222)
			(xy 386.872988 -287.038542) (xy 386.877052 -287.048448) (xy 386.87906 -287.053011) (xy 386.884559 -287.061326)
			(xy 386.887974 -287.064958) (xy 387.647942 -287.824926) (xy 389.119122 -287.824926) (xy 389.123082 -287.775872)
			(xy 389.134859 -287.728088) (xy 389.15415 -287.682812) (xy 389.180453 -287.641216) (xy 389.213088 -287.604379)
			(xy 389.251209 -287.573254) (xy 389.29383 -287.548647) (xy 389.339846 -287.531195) (xy 389.388065 -287.521351)
			(xy 389.43724 -287.51937) (xy 389.486095 -287.525302) (xy 389.533366 -287.538994) (xy 389.577828 -287.560092)
			(xy 389.618331 -287.588048) (xy 389.653824 -287.62214) (xy 389.683389 -287.661484) (xy 389.70626 -287.705061)
			(xy 389.721844 -287.751742) (xy 389.729739 -287.800319) (xy 389.730234 -287.824926) (xy 392.919216 -287.824926)
			(xy 392.923176 -287.775872) (xy 392.934953 -287.728088) (xy 392.954244 -287.682812) (xy 392.980547 -287.641216)
			(xy 393.013182 -287.604379) (xy 393.051303 -287.573254) (xy 393.093924 -287.548647) (xy 393.13994 -287.531195)
			(xy 393.188159 -287.521351) (xy 393.237334 -287.51937) (xy 393.286189 -287.525302) (xy 393.33346 -287.538994)
			(xy 393.377922 -287.560092) (xy 393.418425 -287.588048) (xy 393.453918 -287.62214) (xy 393.483483 -287.661484)
			(xy 393.506354 -287.705061) (xy 393.521938 -287.751742) (xy 393.529833 -287.800319) (xy 393.530328 -287.824926)
			(xy 393.529833 -287.849533) (xy 393.521938 -287.89811) (xy 393.506354 -287.944791) (xy 393.483483 -287.988368)
			(xy 393.453918 -288.027712) (xy 393.418425 -288.061804) (xy 393.377922 -288.08976) (xy 393.33346 -288.110858)
			(xy 393.286189 -288.12455) (xy 393.237334 -288.130482) (xy 393.188159 -288.128501) (xy 393.13994 -288.118657)
			(xy 393.093924 -288.101205) (xy 393.051303 -288.076598) (xy 393.013182 -288.045473) (xy 392.980547 -288.008636)
			(xy 392.954244 -287.96704) (xy 392.934953 -287.921764) (xy 392.923176 -287.87398) (xy 392.919216 -287.824926)
			(xy 389.730234 -287.824926) (xy 389.729739 -287.849533) (xy 389.721844 -287.89811) (xy 389.70626 -287.944791)
			(xy 389.683389 -287.988368) (xy 389.653824 -288.027712) (xy 389.618331 -288.061804) (xy 389.577828 -288.08976)
			(xy 389.533366 -288.110858) (xy 389.486095 -288.12455) (xy 389.43724 -288.130482) (xy 389.388065 -288.128501)
			(xy 389.339846 -288.118657) (xy 389.29383 -288.101205) (xy 389.251209 -288.076598) (xy 389.213088 -288.045473)
			(xy 389.180453 -288.008636) (xy 389.15415 -287.96704) (xy 389.134859 -287.921764) (xy 389.123082 -287.87398)
			(xy 389.119122 -287.824926) (xy 387.647942 -287.824926) (xy 388.295896 -288.47288) (xy 388.326884 -288.478722)
			(xy 388.341108 -288.472372) (xy 388.362204 -288.463483) (xy 388.406233 -288.450947) (xy 388.451569 -288.444602)
			(xy 388.474458 -288.444178) (xy 388.474966 -288.444178) (xy 388.500957 -288.444659) (xy 388.552301 -288.452785)
			(xy 388.601741 -288.468845) (xy 388.64806 -288.49244) (xy 388.690117 -288.522992) (xy 388.726877 -288.559746)
			(xy 388.757435 -288.601799) (xy 388.781037 -288.648115) (xy 388.797103 -288.697552) (xy 388.805238 -288.748895)
			(xy 388.805674 -288.774886) (xy 389.119122 -288.774886) (xy 389.123082 -288.725832) (xy 389.134859 -288.678048)
			(xy 389.15415 -288.632772) (xy 389.180453 -288.591176) (xy 389.213088 -288.554339) (xy 389.251209 -288.523214)
			(xy 389.29383 -288.498607) (xy 389.339846 -288.481155) (xy 389.388065 -288.471311) (xy 389.43724 -288.46933)
			(xy 389.486095 -288.475262) (xy 389.533366 -288.488954) (xy 389.577828 -288.510052) (xy 389.618331 -288.538008)
			(xy 389.653824 -288.5721) (xy 389.683389 -288.611444) (xy 389.70626 -288.655021) (xy 389.721844 -288.701702)
			(xy 389.729739 -288.750279) (xy 389.730234 -288.774886) (xy 390.069082 -288.774886) (xy 390.073042 -288.725832)
			(xy 390.084819 -288.678048) (xy 390.10411 -288.632772) (xy 390.130413 -288.591176) (xy 390.163048 -288.554339)
			(xy 390.201169 -288.523214) (xy 390.24379 -288.498607) (xy 390.289806 -288.481155) (xy 390.338025 -288.471311)
			(xy 390.3872 -288.46933) (xy 390.436055 -288.475262) (xy 390.483326 -288.488954) (xy 390.527788 -288.510052)
			(xy 390.568291 -288.538008) (xy 390.603784 -288.5721) (xy 390.633349 -288.611444) (xy 390.65622 -288.655021)
			(xy 390.671804 -288.701702) (xy 390.679699 -288.750279) (xy 390.680194 -288.774886) (xy 391.019042 -288.774886)
			(xy 391.023002 -288.725832) (xy 391.034779 -288.678048) (xy 391.05407 -288.632772) (xy 391.080373 -288.591176)
			(xy 391.113008 -288.554339) (xy 391.151129 -288.523214) (xy 391.19375 -288.498607) (xy 391.239766 -288.481155)
			(xy 391.287985 -288.471311) (xy 391.33716 -288.46933) (xy 391.386015 -288.475262) (xy 391.433286 -288.488954)
			(xy 391.477748 -288.510052) (xy 391.518251 -288.538008) (xy 391.553744 -288.5721) (xy 391.583309 -288.611444)
			(xy 391.60618 -288.655021) (xy 391.621764 -288.701702) (xy 391.629659 -288.750279) (xy 391.630154 -288.774886)
			(xy 391.969002 -288.774886) (xy 391.972962 -288.725832) (xy 391.984739 -288.678048) (xy 392.00403 -288.632772)
			(xy 392.030333 -288.591176) (xy 392.062968 -288.554339) (xy 392.101089 -288.523214) (xy 392.14371 -288.498607)
			(xy 392.189726 -288.481155) (xy 392.237945 -288.471311) (xy 392.28712 -288.46933) (xy 392.335975 -288.475262)
			(xy 392.383246 -288.488954) (xy 392.427708 -288.510052) (xy 392.468211 -288.538008) (xy 392.503704 -288.5721)
			(xy 392.533269 -288.611444) (xy 392.55614 -288.655021) (xy 392.571724 -288.701702) (xy 392.579619 -288.750279)
			(xy 392.580114 -288.774886) (xy 392.919216 -288.774886) (xy 392.923176 -288.725832) (xy 392.934953 -288.678048)
			(xy 392.954244 -288.632772) (xy 392.980547 -288.591176) (xy 393.013182 -288.554339) (xy 393.051303 -288.523214)
			(xy 393.093924 -288.498607) (xy 393.13994 -288.481155) (xy 393.188159 -288.471311) (xy 393.237334 -288.46933)
			(xy 393.286189 -288.475262) (xy 393.33346 -288.488954) (xy 393.377922 -288.510052) (xy 393.418425 -288.538008)
			(xy 393.453918 -288.5721) (xy 393.483483 -288.611444) (xy 393.506354 -288.655021) (xy 393.521938 -288.701702)
			(xy 393.529833 -288.750279) (xy 393.530328 -288.774886) (xy 393.869176 -288.774886) (xy 393.873136 -288.725832)
			(xy 393.884913 -288.678048) (xy 393.904204 -288.632772) (xy 393.930507 -288.591176) (xy 393.963142 -288.554339)
			(xy 394.001263 -288.523214) (xy 394.043884 -288.498607) (xy 394.0899 -288.481155) (xy 394.138119 -288.471311)
			(xy 394.187294 -288.46933) (xy 394.236149 -288.475262) (xy 394.28342 -288.488954) (xy 394.327882 -288.510052)
			(xy 394.368385 -288.538008) (xy 394.403878 -288.5721) (xy 394.433443 -288.611444) (xy 394.456314 -288.655021)
			(xy 394.471898 -288.701702) (xy 394.479793 -288.750279) (xy 394.480288 -288.774886) (xy 394.479793 -288.799493)
			(xy 394.471898 -288.84807) (xy 394.456314 -288.894751) (xy 394.433443 -288.938328) (xy 394.403878 -288.977672)
			(xy 394.368385 -289.011764) (xy 394.327882 -289.03972) (xy 394.28342 -289.060818) (xy 394.236149 -289.07451)
			(xy 394.187294 -289.080442) (xy 394.138119 -289.078461) (xy 394.0899 -289.068617) (xy 394.043884 -289.051165)
			(xy 394.001263 -289.026558) (xy 393.963142 -288.995433) (xy 393.930507 -288.958596) (xy 393.904204 -288.917)
			(xy 393.884913 -288.871724) (xy 393.873136 -288.82394) (xy 393.869176 -288.774886) (xy 393.530328 -288.774886)
			(xy 393.529833 -288.799493) (xy 393.521938 -288.84807) (xy 393.506354 -288.894751) (xy 393.483483 -288.938328)
			(xy 393.453918 -288.977672) (xy 393.418425 -289.011764) (xy 393.377922 -289.03972) (xy 393.33346 -289.060818)
			(xy 393.286189 -289.07451) (xy 393.237334 -289.080442) (xy 393.188159 -289.078461) (xy 393.13994 -289.068617)
			(xy 393.093924 -289.051165) (xy 393.051303 -289.026558) (xy 393.013182 -288.995433) (xy 392.980547 -288.958596)
			(xy 392.954244 -288.917) (xy 392.934953 -288.871724) (xy 392.923176 -288.82394) (xy 392.919216 -288.774886)
			(xy 392.580114 -288.774886) (xy 392.579619 -288.799493) (xy 392.571724 -288.84807) (xy 392.55614 -288.894751)
			(xy 392.533269 -288.938328) (xy 392.503704 -288.977672) (xy 392.468211 -289.011764) (xy 392.427708 -289.03972)
			(xy 392.383246 -289.060818) (xy 392.335975 -289.07451) (xy 392.28712 -289.080442) (xy 392.237945 -289.078461)
			(xy 392.189726 -289.068617) (xy 392.14371 -289.051165) (xy 392.101089 -289.026558) (xy 392.062968 -288.995433)
			(xy 392.030333 -288.958596) (xy 392.00403 -288.917) (xy 391.984739 -288.871724) (xy 391.972962 -288.82394)
			(xy 391.969002 -288.774886) (xy 391.630154 -288.774886) (xy 391.629659 -288.799493) (xy 391.621764 -288.84807)
			(xy 391.60618 -288.894751) (xy 391.583309 -288.938328) (xy 391.553744 -288.977672) (xy 391.518251 -289.011764)
			(xy 391.477748 -289.03972) (xy 391.433286 -289.060818) (xy 391.386015 -289.07451) (xy 391.33716 -289.080442)
			(xy 391.287985 -289.078461) (xy 391.239766 -289.068617) (xy 391.19375 -289.051165) (xy 391.151129 -289.026558)
			(xy 391.113008 -288.995433) (xy 391.080373 -288.958596) (xy 391.05407 -288.917) (xy 391.034779 -288.871724)
			(xy 391.023002 -288.82394) (xy 391.019042 -288.774886) (xy 390.680194 -288.774886) (xy 390.679699 -288.799493)
			(xy 390.671804 -288.84807) (xy 390.65622 -288.894751) (xy 390.633349 -288.938328) (xy 390.603784 -288.977672)
			(xy 390.568291 -289.011764) (xy 390.527788 -289.03972) (xy 390.483326 -289.060818) (xy 390.436055 -289.07451)
			(xy 390.3872 -289.080442) (xy 390.338025 -289.078461) (xy 390.289806 -289.068617) (xy 390.24379 -289.051165)
			(xy 390.201169 -289.026558) (xy 390.163048 -288.995433) (xy 390.130413 -288.958596) (xy 390.10411 -288.917)
			(xy 390.084819 -288.871724) (xy 390.073042 -288.82394) (xy 390.069082 -288.774886) (xy 389.730234 -288.774886)
			(xy 389.729739 -288.799493) (xy 389.721844 -288.84807) (xy 389.70626 -288.894751) (xy 389.683389 -288.938328)
			(xy 389.653824 -288.977672) (xy 389.618331 -289.011764) (xy 389.577828 -289.03972) (xy 389.533366 -289.060818)
			(xy 389.486095 -289.07451) (xy 389.43724 -289.080442) (xy 389.388065 -289.078461) (xy 389.339846 -289.068617)
			(xy 389.29383 -289.051165) (xy 389.251209 -289.026558) (xy 389.213088 -288.995433) (xy 389.180453 -288.958596)
			(xy 389.15415 -288.917) (xy 389.134859 -288.871724) (xy 389.123082 -288.82394) (xy 389.119122 -288.774886)
			(xy 388.805674 -288.774886) (xy 388.805283 -288.797818) (xy 388.798945 -288.843243) (xy 388.786388 -288.887355)
			(xy 388.77748 -288.90849) (xy 388.773162 -288.918142) (xy 388.772908 -288.938462) (xy 388.776972 -288.948368)
			(xy 388.778982 -288.95293) (xy 388.784485 -288.961241) (xy 388.787894 -288.964878) (xy 389.245856 -289.42284)
			(xy 389.276844 -289.428682) (xy 389.291068 -289.422332) (xy 389.312164 -289.413442) (xy 389.356192 -289.400902)
			(xy 389.401529 -289.394552) (xy 389.424418 -289.394138) (xy 389.424926 -289.394138) (xy 389.450913 -289.394623)
			(xy 389.502245 -289.402758) (xy 389.551673 -289.418823) (xy 389.59798 -289.442423) (xy 389.640024 -289.472976)
			(xy 389.676771 -289.509731) (xy 389.707315 -289.551782) (xy 389.730905 -289.598093) (xy 389.746959 -289.647525)
			(xy 389.755083 -289.698859) (xy 389.755634 -289.724846) (xy 390.069082 -289.724846) (xy 390.073042 -289.675792)
			(xy 390.084819 -289.628008) (xy 390.10411 -289.582732) (xy 390.130413 -289.541136) (xy 390.163048 -289.504299)
			(xy 390.201169 -289.473174) (xy 390.24379 -289.448567) (xy 390.289806 -289.431115) (xy 390.338025 -289.421271)
			(xy 390.3872 -289.41929) (xy 390.436055 -289.425222) (xy 390.483326 -289.438914) (xy 390.527788 -289.460012)
			(xy 390.568291 -289.487968) (xy 390.603784 -289.52206) (xy 390.633349 -289.561404) (xy 390.65622 -289.604981)
			(xy 390.671804 -289.651662) (xy 390.679699 -289.700239) (xy 390.680194 -289.724846) (xy 391.019042 -289.724846)
			(xy 391.023002 -289.675792) (xy 391.034779 -289.628008) (xy 391.05407 -289.582732) (xy 391.080373 -289.541136)
			(xy 391.113008 -289.504299) (xy 391.151129 -289.473174) (xy 391.19375 -289.448567) (xy 391.239766 -289.431115)
			(xy 391.287985 -289.421271) (xy 391.33716 -289.41929) (xy 391.386015 -289.425222) (xy 391.433286 -289.438914)
			(xy 391.477748 -289.460012) (xy 391.518251 -289.487968) (xy 391.553744 -289.52206) (xy 391.583309 -289.561404)
			(xy 391.60618 -289.604981) (xy 391.621764 -289.651662) (xy 391.629659 -289.700239) (xy 391.630154 -289.724846)
			(xy 391.969002 -289.724846) (xy 391.972962 -289.675792) (xy 391.984739 -289.628008) (xy 392.00403 -289.582732)
			(xy 392.030333 -289.541136) (xy 392.062968 -289.504299) (xy 392.101089 -289.473174) (xy 392.14371 -289.448567)
			(xy 392.189726 -289.431115) (xy 392.237945 -289.421271) (xy 392.28712 -289.41929) (xy 392.335975 -289.425222)
			(xy 392.383246 -289.438914) (xy 392.427708 -289.460012) (xy 392.468211 -289.487968) (xy 392.503704 -289.52206)
			(xy 392.533269 -289.561404) (xy 392.55614 -289.604981) (xy 392.571724 -289.651662) (xy 392.579619 -289.700239)
			(xy 392.580114 -289.724846) (xy 392.919216 -289.724846) (xy 392.923176 -289.675792) (xy 392.934953 -289.628008)
			(xy 392.954244 -289.582732) (xy 392.980547 -289.541136) (xy 393.013182 -289.504299) (xy 393.051303 -289.473174)
			(xy 393.093924 -289.448567) (xy 393.13994 -289.431115) (xy 393.188159 -289.421271) (xy 393.237334 -289.41929)
			(xy 393.286189 -289.425222) (xy 393.33346 -289.438914) (xy 393.377922 -289.460012) (xy 393.418425 -289.487968)
			(xy 393.453918 -289.52206) (xy 393.483483 -289.561404) (xy 393.506354 -289.604981) (xy 393.521938 -289.651662)
			(xy 393.529833 -289.700239) (xy 393.530328 -289.724846) (xy 393.869176 -289.724846) (xy 393.873136 -289.675792)
			(xy 393.884913 -289.628008) (xy 393.904204 -289.582732) (xy 393.930507 -289.541136) (xy 393.963142 -289.504299)
			(xy 394.001263 -289.473174) (xy 394.043884 -289.448567) (xy 394.0899 -289.431115) (xy 394.138119 -289.421271)
			(xy 394.187294 -289.41929) (xy 394.236149 -289.425222) (xy 394.28342 -289.438914) (xy 394.327882 -289.460012)
			(xy 394.368385 -289.487968) (xy 394.403878 -289.52206) (xy 394.433443 -289.561404) (xy 394.456314 -289.604981)
			(xy 394.471898 -289.651662) (xy 394.479793 -289.700239) (xy 394.480288 -289.724846) (xy 394.819136 -289.724846)
			(xy 394.823096 -289.675792) (xy 394.834873 -289.628008) (xy 394.854164 -289.582732) (xy 394.880467 -289.541136)
			(xy 394.913102 -289.504299) (xy 394.951223 -289.473174) (xy 394.993844 -289.448567) (xy 395.03986 -289.431115)
			(xy 395.088079 -289.421271) (xy 395.137254 -289.41929) (xy 395.186109 -289.425222) (xy 395.23338 -289.438914)
			(xy 395.277842 -289.460012) (xy 395.318345 -289.487968) (xy 395.353838 -289.52206) (xy 395.383403 -289.561404)
			(xy 395.406274 -289.604981) (xy 395.421858 -289.651662) (xy 395.429753 -289.700239) (xy 395.430248 -289.724846)
			(xy 395.429753 -289.749453) (xy 395.421858 -289.79803) (xy 395.406274 -289.844711) (xy 395.383403 -289.888288)
			(xy 395.353838 -289.927632) (xy 395.318345 -289.961724) (xy 395.277842 -289.98968) (xy 395.23338 -290.010778)
			(xy 395.186109 -290.02447) (xy 395.137254 -290.030402) (xy 395.088079 -290.028421) (xy 395.03986 -290.018577)
			(xy 394.993844 -290.001125) (xy 394.951223 -289.976518) (xy 394.913102 -289.945393) (xy 394.880467 -289.908556)
			(xy 394.854164 -289.86696) (xy 394.834873 -289.821684) (xy 394.823096 -289.7739) (xy 394.819136 -289.724846)
			(xy 394.480288 -289.724846) (xy 394.479793 -289.749453) (xy 394.471898 -289.79803) (xy 394.456314 -289.844711)
			(xy 394.433443 -289.888288) (xy 394.403878 -289.927632) (xy 394.368385 -289.961724) (xy 394.327882 -289.98968)
			(xy 394.28342 -290.010778) (xy 394.236149 -290.02447) (xy 394.187294 -290.030402) (xy 394.138119 -290.028421)
			(xy 394.0899 -290.018577) (xy 394.043884 -290.001125) (xy 394.001263 -289.976518) (xy 393.963142 -289.945393)
			(xy 393.930507 -289.908556) (xy 393.904204 -289.86696) (xy 393.884913 -289.821684) (xy 393.873136 -289.7739)
			(xy 393.869176 -289.724846) (xy 393.530328 -289.724846) (xy 393.529833 -289.749453) (xy 393.521938 -289.79803)
			(xy 393.506354 -289.844711) (xy 393.483483 -289.888288) (xy 393.453918 -289.927632) (xy 393.418425 -289.961724)
			(xy 393.377922 -289.98968) (xy 393.33346 -290.010778) (xy 393.286189 -290.02447) (xy 393.237334 -290.030402)
			(xy 393.188159 -290.028421) (xy 393.13994 -290.018577) (xy 393.093924 -290.001125) (xy 393.051303 -289.976518)
			(xy 393.013182 -289.945393) (xy 392.980547 -289.908556) (xy 392.954244 -289.86696) (xy 392.934953 -289.821684)
			(xy 392.923176 -289.7739) (xy 392.919216 -289.724846) (xy 392.580114 -289.724846) (xy 392.579619 -289.749453)
			(xy 392.571724 -289.79803) (xy 392.55614 -289.844711) (xy 392.533269 -289.888288) (xy 392.503704 -289.927632)
			(xy 392.468211 -289.961724) (xy 392.427708 -289.98968) (xy 392.383246 -290.010778) (xy 392.335975 -290.02447)
			(xy 392.28712 -290.030402) (xy 392.237945 -290.028421) (xy 392.189726 -290.018577) (xy 392.14371 -290.001125)
			(xy 392.101089 -289.976518) (xy 392.062968 -289.945393) (xy 392.030333 -289.908556) (xy 392.00403 -289.86696)
			(xy 391.984739 -289.821684) (xy 391.972962 -289.7739) (xy 391.969002 -289.724846) (xy 391.630154 -289.724846)
			(xy 391.629659 -289.749453) (xy 391.621764 -289.79803) (xy 391.60618 -289.844711) (xy 391.583309 -289.888288)
			(xy 391.553744 -289.927632) (xy 391.518251 -289.961724) (xy 391.477748 -289.98968) (xy 391.433286 -290.010778)
			(xy 391.386015 -290.02447) (xy 391.33716 -290.030402) (xy 391.287985 -290.028421) (xy 391.239766 -290.018577)
			(xy 391.19375 -290.001125) (xy 391.151129 -289.976518) (xy 391.113008 -289.945393) (xy 391.080373 -289.908556)
			(xy 391.05407 -289.86696) (xy 391.034779 -289.821684) (xy 391.023002 -289.7739) (xy 391.019042 -289.724846)
			(xy 390.680194 -289.724846) (xy 390.679699 -289.749453) (xy 390.671804 -289.79803) (xy 390.65622 -289.844711)
			(xy 390.633349 -289.888288) (xy 390.603784 -289.927632) (xy 390.568291 -289.961724) (xy 390.527788 -289.98968)
			(xy 390.483326 -290.010778) (xy 390.436055 -290.02447) (xy 390.3872 -290.030402) (xy 390.338025 -290.028421)
			(xy 390.289806 -290.018577) (xy 390.24379 -290.001125) (xy 390.201169 -289.976518) (xy 390.163048 -289.945393)
			(xy 390.130413 -289.908556) (xy 390.10411 -289.86696) (xy 390.084819 -289.821684) (xy 390.073042 -289.7739)
			(xy 390.069082 -289.724846) (xy 389.755634 -289.724846) (xy 389.755246 -289.747779) (xy 389.748914 -289.793206)
			(xy 389.736364 -289.837321) (xy 389.72744 -289.85845) (xy 389.723122 -289.868102) (xy 389.722868 -289.888422)
			(xy 389.726932 -289.898328) (xy 389.728938 -289.902893) (xy 389.734433 -289.911211) (xy 389.737854 -289.914838)
			(xy 390.195816 -290.3728) (xy 390.226804 -290.378642) (xy 390.241028 -290.372292) (xy 390.262123 -290.363398)
			(xy 390.306151 -290.35085) (xy 390.351488 -290.344493) (xy 390.374378 -290.344098) (xy 390.374886 -290.344098)
			(xy 390.400876 -290.34458) (xy 390.452216 -290.35271) (xy 390.501652 -290.368771) (xy 390.547966 -290.392368)
			(xy 390.590019 -290.42292) (xy 390.626775 -290.459675) (xy 390.657328 -290.501727) (xy 390.680926 -290.548041)
			(xy 390.696989 -290.597476) (xy 390.705119 -290.648816) (xy 390.705594 -290.674806) (xy 391.019042 -290.674806)
			(xy 391.023002 -290.625752) (xy 391.034779 -290.577968) (xy 391.05407 -290.532692) (xy 391.080373 -290.491096)
			(xy 391.113008 -290.454259) (xy 391.151129 -290.423134) (xy 391.19375 -290.398527) (xy 391.239766 -290.381075)
			(xy 391.287985 -290.371231) (xy 391.33716 -290.36925) (xy 391.386015 -290.375182) (xy 391.433286 -290.388874)
			(xy 391.477748 -290.409972) (xy 391.518251 -290.437928) (xy 391.553744 -290.47202) (xy 391.583309 -290.511364)
			(xy 391.60618 -290.554941) (xy 391.621764 -290.601622) (xy 391.629659 -290.650199) (xy 391.630154 -290.674806)
			(xy 391.969002 -290.674806) (xy 391.972962 -290.625752) (xy 391.984739 -290.577968) (xy 392.00403 -290.532692)
			(xy 392.030333 -290.491096) (xy 392.062968 -290.454259) (xy 392.101089 -290.423134) (xy 392.14371 -290.398527)
			(xy 392.189726 -290.381075) (xy 392.237945 -290.371231) (xy 392.28712 -290.36925) (xy 392.335975 -290.375182)
			(xy 392.383246 -290.388874) (xy 392.427708 -290.409972) (xy 392.468211 -290.437928) (xy 392.503704 -290.47202)
			(xy 392.533269 -290.511364) (xy 392.55614 -290.554941) (xy 392.571724 -290.601622) (xy 392.579619 -290.650199)
			(xy 392.580114 -290.674806) (xy 392.919216 -290.674806) (xy 392.923176 -290.625752) (xy 392.934953 -290.577968)
			(xy 392.954244 -290.532692) (xy 392.980547 -290.491096) (xy 393.013182 -290.454259) (xy 393.051303 -290.423134)
			(xy 393.093924 -290.398527) (xy 393.13994 -290.381075) (xy 393.188159 -290.371231) (xy 393.237334 -290.36925)
			(xy 393.286189 -290.375182) (xy 393.33346 -290.388874) (xy 393.377922 -290.409972) (xy 393.418425 -290.437928)
			(xy 393.453918 -290.47202) (xy 393.483483 -290.511364) (xy 393.506354 -290.554941) (xy 393.521938 -290.601622)
			(xy 393.529833 -290.650199) (xy 393.530328 -290.674806) (xy 393.869176 -290.674806) (xy 393.873136 -290.625752)
			(xy 393.884913 -290.577968) (xy 393.904204 -290.532692) (xy 393.930507 -290.491096) (xy 393.963142 -290.454259)
			(xy 394.001263 -290.423134) (xy 394.043884 -290.398527) (xy 394.0899 -290.381075) (xy 394.138119 -290.371231)
			(xy 394.187294 -290.36925) (xy 394.236149 -290.375182) (xy 394.28342 -290.388874) (xy 394.327882 -290.409972)
			(xy 394.368385 -290.437928) (xy 394.403878 -290.47202) (xy 394.433443 -290.511364) (xy 394.456314 -290.554941)
			(xy 394.471898 -290.601622) (xy 394.479793 -290.650199) (xy 394.480288 -290.674806) (xy 394.819136 -290.674806)
			(xy 394.823096 -290.625752) (xy 394.834873 -290.577968) (xy 394.854164 -290.532692) (xy 394.880467 -290.491096)
			(xy 394.913102 -290.454259) (xy 394.951223 -290.423134) (xy 394.993844 -290.398527) (xy 395.03986 -290.381075)
			(xy 395.088079 -290.371231) (xy 395.137254 -290.36925) (xy 395.186109 -290.375182) (xy 395.23338 -290.388874)
			(xy 395.277842 -290.409972) (xy 395.318345 -290.437928) (xy 395.353838 -290.47202) (xy 395.383403 -290.511364)
			(xy 395.406274 -290.554941) (xy 395.421858 -290.601622) (xy 395.429753 -290.650199) (xy 395.430248 -290.674806)
			(xy 395.429753 -290.699413) (xy 395.421858 -290.74799) (xy 395.406274 -290.794671) (xy 395.383403 -290.838248)
			(xy 395.353838 -290.877592) (xy 395.318345 -290.911684) (xy 395.277842 -290.93964) (xy 395.23338 -290.960738)
			(xy 395.186109 -290.97443) (xy 395.137254 -290.980362) (xy 395.088079 -290.978381) (xy 395.03986 -290.968537)
			(xy 394.993844 -290.951085) (xy 394.951223 -290.926478) (xy 394.913102 -290.895353) (xy 394.880467 -290.858516)
			(xy 394.854164 -290.81692) (xy 394.834873 -290.771644) (xy 394.823096 -290.72386) (xy 394.819136 -290.674806)
			(xy 394.480288 -290.674806) (xy 394.479793 -290.699413) (xy 394.471898 -290.74799) (xy 394.456314 -290.794671)
			(xy 394.433443 -290.838248) (xy 394.403878 -290.877592) (xy 394.368385 -290.911684) (xy 394.327882 -290.93964)
			(xy 394.28342 -290.960738) (xy 394.236149 -290.97443) (xy 394.187294 -290.980362) (xy 394.138119 -290.978381)
			(xy 394.0899 -290.968537) (xy 394.043884 -290.951085) (xy 394.001263 -290.926478) (xy 393.963142 -290.895353)
			(xy 393.930507 -290.858516) (xy 393.904204 -290.81692) (xy 393.884913 -290.771644) (xy 393.873136 -290.72386)
			(xy 393.869176 -290.674806) (xy 393.530328 -290.674806) (xy 393.529833 -290.699413) (xy 393.521938 -290.74799)
			(xy 393.506354 -290.794671) (xy 393.483483 -290.838248) (xy 393.453918 -290.877592) (xy 393.418425 -290.911684)
			(xy 393.377922 -290.93964) (xy 393.33346 -290.960738) (xy 393.286189 -290.97443) (xy 393.237334 -290.980362)
			(xy 393.188159 -290.978381) (xy 393.13994 -290.968537) (xy 393.093924 -290.951085) (xy 393.051303 -290.926478)
			(xy 393.013182 -290.895353) (xy 392.980547 -290.858516) (xy 392.954244 -290.81692) (xy 392.934953 -290.771644)
			(xy 392.923176 -290.72386) (xy 392.919216 -290.674806) (xy 392.580114 -290.674806) (xy 392.579619 -290.699413)
			(xy 392.571724 -290.74799) (xy 392.55614 -290.794671) (xy 392.533269 -290.838248) (xy 392.503704 -290.877592)
			(xy 392.468211 -290.911684) (xy 392.427708 -290.93964) (xy 392.383246 -290.960738) (xy 392.335975 -290.97443)
			(xy 392.28712 -290.980362) (xy 392.237945 -290.978381) (xy 392.189726 -290.968537) (xy 392.14371 -290.951085)
			(xy 392.101089 -290.926478) (xy 392.062968 -290.895353) (xy 392.030333 -290.858516) (xy 392.00403 -290.81692)
			(xy 391.984739 -290.771644) (xy 391.972962 -290.72386) (xy 391.969002 -290.674806) (xy 391.630154 -290.674806)
			(xy 391.629659 -290.699413) (xy 391.621764 -290.74799) (xy 391.60618 -290.794671) (xy 391.583309 -290.838248)
			(xy 391.553744 -290.877592) (xy 391.518251 -290.911684) (xy 391.477748 -290.93964) (xy 391.433286 -290.960738)
			(xy 391.386015 -290.97443) (xy 391.33716 -290.980362) (xy 391.287985 -290.978381) (xy 391.239766 -290.968537)
			(xy 391.19375 -290.951085) (xy 391.151129 -290.926478) (xy 391.113008 -290.895353) (xy 391.080373 -290.858516)
			(xy 391.05407 -290.81692) (xy 391.034779 -290.771644) (xy 391.023002 -290.72386) (xy 391.019042 -290.674806)
			(xy 390.705594 -290.674806) (xy 390.705202 -290.697738) (xy 390.698861 -290.743162) (xy 390.686302 -290.787273)
			(xy 390.6774 -290.80841) (xy 390.673082 -290.818062) (xy 390.672828 -290.838382) (xy 390.676892 -290.848288)
			(xy 390.678904 -290.852848) (xy 390.684411 -290.861155) (xy 390.687814 -290.864798) (xy 391.145776 -291.32276)
			(xy 391.176764 -291.328602) (xy 391.190988 -291.322252) (xy 391.212084 -291.313362) (xy 391.256112 -291.300825)
			(xy 391.301449 -291.294477) (xy 391.324338 -291.294058) (xy 391.324846 -291.294058) (xy 391.350832 -291.294571)
			(xy 391.402163 -291.302707) (xy 391.451589 -291.318772) (xy 391.497895 -291.342369) (xy 391.53994 -291.372919)
			(xy 391.576688 -291.40967) (xy 391.607237 -291.451715) (xy 391.630833 -291.498022) (xy 391.646896 -291.547449)
			(xy 391.65503 -291.59878) (xy 391.655554 -291.624766) (xy 391.969002 -291.624766) (xy 391.972962 -291.575712)
			(xy 391.984739 -291.527928) (xy 392.00403 -291.482652) (xy 392.030333 -291.441056) (xy 392.062968 -291.404219)
			(xy 392.101089 -291.373094) (xy 392.14371 -291.348487) (xy 392.189726 -291.331035) (xy 392.237945 -291.321191)
			(xy 392.28712 -291.31921) (xy 392.335975 -291.325142) (xy 392.383246 -291.338834) (xy 392.427708 -291.359932)
			(xy 392.468211 -291.387888) (xy 392.503704 -291.42198) (xy 392.533269 -291.461324) (xy 392.55614 -291.504901)
			(xy 392.571724 -291.551582) (xy 392.579619 -291.600159) (xy 392.580114 -291.624766) (xy 392.919216 -291.624766)
			(xy 392.923176 -291.575712) (xy 392.934953 -291.527928) (xy 392.954244 -291.482652) (xy 392.980547 -291.441056)
			(xy 393.013182 -291.404219) (xy 393.051303 -291.373094) (xy 393.093924 -291.348487) (xy 393.13994 -291.331035)
			(xy 393.188159 -291.321191) (xy 393.237334 -291.31921) (xy 393.286189 -291.325142) (xy 393.33346 -291.338834)
			(xy 393.377922 -291.359932) (xy 393.418425 -291.387888) (xy 393.453918 -291.42198) (xy 393.483483 -291.461324)
			(xy 393.506354 -291.504901) (xy 393.521938 -291.551582) (xy 393.529833 -291.600159) (xy 393.530328 -291.624766)
			(xy 393.869176 -291.624766) (xy 393.873136 -291.575712) (xy 393.884913 -291.527928) (xy 393.904204 -291.482652)
			(xy 393.930507 -291.441056) (xy 393.963142 -291.404219) (xy 394.001263 -291.373094) (xy 394.043884 -291.348487)
			(xy 394.0899 -291.331035) (xy 394.138119 -291.321191) (xy 394.187294 -291.31921) (xy 394.236149 -291.325142)
			(xy 394.28342 -291.338834) (xy 394.327882 -291.359932) (xy 394.368385 -291.387888) (xy 394.403878 -291.42198)
			(xy 394.433443 -291.461324) (xy 394.456314 -291.504901) (xy 394.471898 -291.551582) (xy 394.479793 -291.600159)
			(xy 394.480288 -291.624766) (xy 394.819136 -291.624766) (xy 394.823096 -291.575712) (xy 394.834873 -291.527928)
			(xy 394.854164 -291.482652) (xy 394.880467 -291.441056) (xy 394.913102 -291.404219) (xy 394.951223 -291.373094)
			(xy 394.993844 -291.348487) (xy 395.03986 -291.331035) (xy 395.088079 -291.321191) (xy 395.137254 -291.31921)
			(xy 395.186109 -291.325142) (xy 395.23338 -291.338834) (xy 395.277842 -291.359932) (xy 395.318345 -291.387888)
			(xy 395.353838 -291.42198) (xy 395.383403 -291.461324) (xy 395.406274 -291.504901) (xy 395.421858 -291.551582)
			(xy 395.429753 -291.600159) (xy 395.430248 -291.624766) (xy 395.429753 -291.649373) (xy 395.421858 -291.69795)
			(xy 395.406274 -291.744631) (xy 395.383403 -291.788208) (xy 395.353838 -291.827552) (xy 395.318345 -291.861644)
			(xy 395.277842 -291.8896) (xy 395.23338 -291.910698) (xy 395.186109 -291.92439) (xy 395.137254 -291.930322)
			(xy 395.088079 -291.928341) (xy 395.03986 -291.918497) (xy 394.993844 -291.901045) (xy 394.951223 -291.876438)
			(xy 394.913102 -291.845313) (xy 394.880467 -291.808476) (xy 394.854164 -291.76688) (xy 394.834873 -291.721604)
			(xy 394.823096 -291.67382) (xy 394.819136 -291.624766) (xy 394.480288 -291.624766) (xy 394.479793 -291.649373)
			(xy 394.471898 -291.69795) (xy 394.456314 -291.744631) (xy 394.433443 -291.788208) (xy 394.403878 -291.827552)
			(xy 394.368385 -291.861644) (xy 394.327882 -291.8896) (xy 394.28342 -291.910698) (xy 394.236149 -291.92439)
			(xy 394.187294 -291.930322) (xy 394.138119 -291.928341) (xy 394.0899 -291.918497) (xy 394.043884 -291.901045)
			(xy 394.001263 -291.876438) (xy 393.963142 -291.845313) (xy 393.930507 -291.808476) (xy 393.904204 -291.76688)
			(xy 393.884913 -291.721604) (xy 393.873136 -291.67382) (xy 393.869176 -291.624766) (xy 393.530328 -291.624766)
			(xy 393.529833 -291.649373) (xy 393.521938 -291.69795) (xy 393.506354 -291.744631) (xy 393.483483 -291.788208)
			(xy 393.453918 -291.827552) (xy 393.418425 -291.861644) (xy 393.377922 -291.8896) (xy 393.33346 -291.910698)
			(xy 393.286189 -291.92439) (xy 393.237334 -291.930322) (xy 393.188159 -291.928341) (xy 393.13994 -291.918497)
			(xy 393.093924 -291.901045) (xy 393.051303 -291.876438) (xy 393.013182 -291.845313) (xy 392.980547 -291.808476)
			(xy 392.954244 -291.76688) (xy 392.934953 -291.721604) (xy 392.923176 -291.67382) (xy 392.919216 -291.624766)
			(xy 392.580114 -291.624766) (xy 392.579619 -291.649373) (xy 392.571724 -291.69795) (xy 392.55614 -291.744631)
			(xy 392.533269 -291.788208) (xy 392.503704 -291.827552) (xy 392.468211 -291.861644) (xy 392.427708 -291.8896)
			(xy 392.383246 -291.910698) (xy 392.335975 -291.92439) (xy 392.28712 -291.930322) (xy 392.237945 -291.928341)
			(xy 392.189726 -291.918497) (xy 392.14371 -291.901045) (xy 392.101089 -291.876438) (xy 392.062968 -291.845313)
			(xy 392.030333 -291.808476) (xy 392.00403 -291.76688) (xy 391.984739 -291.721604) (xy 391.972962 -291.67382)
			(xy 391.969002 -291.624766) (xy 391.655554 -291.624766) (xy 391.655164 -291.647699) (xy 391.648828 -291.693124)
			(xy 391.636273 -291.737237) (xy 391.62736 -291.75837) (xy 391.623042 -291.768022) (xy 391.622788 -291.788342)
			(xy 391.626852 -291.798248) (xy 391.62886 -291.802811) (xy 391.634359 -291.811126) (xy 391.637774 -291.814758)
			(xy 392.09599 -292.272974) (xy 392.126978 -292.278816) (xy 392.141202 -292.272466) (xy 392.162338 -292.263563)
			(xy 392.206451 -292.251014) (xy 392.251874 -292.24468) (xy 392.274806 -292.244272) (xy 392.300793 -292.244782)
			(xy 392.352128 -292.252913) (xy 392.401559 -292.268974) (xy 392.44787 -292.29257) (xy 392.489919 -292.32312)
			(xy 392.526671 -292.359871) (xy 392.557222 -292.401919) (xy 392.58082 -292.448228) (xy 392.596884 -292.497658)
			(xy 392.605017 -292.548993) (xy 392.605514 -292.57498) (xy 392.919216 -292.57498) (xy 392.923176 -292.525926)
			(xy 392.934953 -292.478142) (xy 392.954244 -292.432866) (xy 392.980547 -292.39127) (xy 393.013182 -292.354433)
			(xy 393.051303 -292.323308) (xy 393.093924 -292.298701) (xy 393.13994 -292.281249) (xy 393.188159 -292.271405)
			(xy 393.237334 -292.269424) (xy 393.286189 -292.275356) (xy 393.33346 -292.289048) (xy 393.377922 -292.310146)
			(xy 393.418425 -292.338102) (xy 393.453918 -292.372194) (xy 393.483483 -292.411538) (xy 393.506354 -292.455115)
			(xy 393.521938 -292.501796) (xy 393.529833 -292.550373) (xy 393.530328 -292.57498) (xy 393.869176 -292.57498)
			(xy 393.873136 -292.525926) (xy 393.884913 -292.478142) (xy 393.904204 -292.432866) (xy 393.930507 -292.39127)
			(xy 393.963142 -292.354433) (xy 394.001263 -292.323308) (xy 394.043884 -292.298701) (xy 394.0899 -292.281249)
			(xy 394.138119 -292.271405) (xy 394.187294 -292.269424) (xy 394.236149 -292.275356) (xy 394.28342 -292.289048)
			(xy 394.327882 -292.310146) (xy 394.368385 -292.338102) (xy 394.403878 -292.372194) (xy 394.433443 -292.411538)
			(xy 394.456314 -292.455115) (xy 394.471898 -292.501796) (xy 394.479793 -292.550373) (xy 394.480288 -292.57498)
			(xy 394.819136 -292.57498) (xy 394.823096 -292.525926) (xy 394.834873 -292.478142) (xy 394.854164 -292.432866)
			(xy 394.880467 -292.39127) (xy 394.913102 -292.354433) (xy 394.951223 -292.323308) (xy 394.993844 -292.298701)
			(xy 395.03986 -292.281249) (xy 395.088079 -292.271405) (xy 395.137254 -292.269424) (xy 395.186109 -292.275356)
			(xy 395.23338 -292.289048) (xy 395.277842 -292.310146) (xy 395.318345 -292.338102) (xy 395.353838 -292.372194)
			(xy 395.383403 -292.411538) (xy 395.406274 -292.455115) (xy 395.421858 -292.501796) (xy 395.429753 -292.550373)
			(xy 395.430248 -292.57498) (xy 395.429753 -292.599587) (xy 395.421858 -292.648164) (xy 395.406274 -292.694845)
			(xy 395.383403 -292.738422) (xy 395.353838 -292.777766) (xy 395.318345 -292.811858) (xy 395.277842 -292.839814)
			(xy 395.23338 -292.860912) (xy 395.186109 -292.874604) (xy 395.137254 -292.880536) (xy 395.088079 -292.878555)
			(xy 395.03986 -292.868711) (xy 394.993844 -292.851259) (xy 394.951223 -292.826652) (xy 394.913102 -292.795527)
			(xy 394.880467 -292.75869) (xy 394.854164 -292.717094) (xy 394.834873 -292.671818) (xy 394.823096 -292.624034)
			(xy 394.819136 -292.57498) (xy 394.480288 -292.57498) (xy 394.479793 -292.599587) (xy 394.471898 -292.648164)
			(xy 394.456314 -292.694845) (xy 394.433443 -292.738422) (xy 394.403878 -292.777766) (xy 394.368385 -292.811858)
			(xy 394.327882 -292.839814) (xy 394.28342 -292.860912) (xy 394.236149 -292.874604) (xy 394.187294 -292.880536)
			(xy 394.138119 -292.878555) (xy 394.0899 -292.868711) (xy 394.043884 -292.851259) (xy 394.001263 -292.826652)
			(xy 393.963142 -292.795527) (xy 393.930507 -292.75869) (xy 393.904204 -292.717094) (xy 393.884913 -292.671818)
			(xy 393.873136 -292.624034) (xy 393.869176 -292.57498) (xy 393.530328 -292.57498) (xy 393.529833 -292.599587)
			(xy 393.521938 -292.648164) (xy 393.506354 -292.694845) (xy 393.483483 -292.738422) (xy 393.453918 -292.777766)
			(xy 393.418425 -292.811858) (xy 393.377922 -292.839814) (xy 393.33346 -292.860912) (xy 393.286189 -292.874604)
			(xy 393.237334 -292.880536) (xy 393.188159 -292.878555) (xy 393.13994 -292.868711) (xy 393.093924 -292.851259)
			(xy 393.051303 -292.826652) (xy 393.013182 -292.795527) (xy 392.980547 -292.75869) (xy 392.954244 -292.717094)
			(xy 392.934953 -292.671818) (xy 392.923176 -292.624034) (xy 392.919216 -292.57498) (xy 392.605514 -292.57498)
			(xy 392.605124 -292.597912) (xy 392.598787 -292.643337) (xy 392.586232 -292.68745) (xy 392.57732 -292.708584)
			(xy 392.57097 -292.722808) (xy 392.576812 -292.753796) (xy 393.651232 -293.828216) (xy 393.658083 -293.835612)
			(xy 393.665823 -293.854211) (xy 393.666218 -293.864284) (xy 393.666218 -293.90594) (xy 393.666713 -293.915941)
			(xy 393.67438 -293.934416) (xy 393.688533 -293.948552) (xy 393.707016 -293.956198) (xy 393.717018 -293.95674)
		)
		(stroke
			(width 0)
			(type solid)
		)
		(fill yes)
		(layer "In11.Cu")
		(net "PCEPLL5_VDDA18_PEX3")
	)
	(gr_poly
		(pts
			(xy 161.702242 -293.956232) (xy 161.70275 -293.956232) (xy 161.711625 -293.954658) (xy 161.727522 -293.946186)
			(xy 161.739494 -293.932728) (xy 161.743136 -293.924482) (xy 161.760154 -293.878762) (xy 161.760154 -293.878254)
			(xy 161.77641 -293.833804) (xy 161.778875 -293.82643) (xy 161.779649 -293.810909) (xy 161.777934 -293.803324)
			(xy 161.775902 -293.795958) (xy 161.76752 -293.78275) (xy 161.761424 -293.77767) (xy 161.743426 -293.761867)
			(xy 161.711724 -293.725966) (xy 161.685522 -293.685874) (xy 161.665366 -293.642427) (xy 161.651676 -293.59653)
			(xy 161.644737 -293.549141) (xy 161.64433 -293.525194) (xy 161.64433 -293.52494) (xy 161.64484 -293.498953)
			(xy 161.65297 -293.447618) (xy 161.669031 -293.398188) (xy 161.692627 -293.351878) (xy 161.723177 -293.30983)
			(xy 161.759928 -293.273079) (xy 161.801976 -293.242529) (xy 161.848286 -293.218933) (xy 161.897716 -293.202872)
			(xy 161.949051 -293.194742) (xy 162.001025 -293.194742) (xy 162.05236 -293.202872) (xy 162.10179 -293.218933)
			(xy 162.1481 -293.242529) (xy 162.190148 -293.273079) (xy 162.226899 -293.30983) (xy 162.257449 -293.351878)
			(xy 162.281045 -293.398188) (xy 162.297106 -293.447618) (xy 162.305236 -293.498953) (xy 162.305746 -293.52494)
			(xy 162.305746 -293.525194) (xy 162.305156 -293.553234) (xy 162.295699 -293.608511) (xy 162.277056 -293.661401)
			(xy 162.249761 -293.71039) (xy 162.214594 -293.754074) (xy 162.193986 -293.773098) (xy 162.188398 -293.777924)
			(xy 162.172142 -293.803578) (xy 162.17011 -293.810944) (xy 162.170618 -293.818818) (xy 162.170829 -293.822639)
			(xy 162.17224 -293.830161) (xy 162.173412 -293.833804) (xy 162.206432 -293.92372) (xy 162.21002 -293.932169)
			(xy 162.222111 -293.945961) (xy 162.23829 -293.954601) (xy 162.247326 -293.956232) (xy 162.247834 -293.956232)
			(xy 162.25393 -293.95674) (xy 162.646106 -293.95674) (xy 162.652202 -293.956232) (xy 162.65271 -293.956232)
			(xy 162.661589 -293.954664) (xy 162.677497 -293.946199) (xy 162.68948 -293.932742) (xy 162.693096 -293.924482)
			(xy 162.710114 -293.878762) (xy 162.710114 -293.878254) (xy 162.72637 -293.833804) (xy 162.728837 -293.82643)
			(xy 162.729611 -293.810908) (xy 162.727894 -293.803324) (xy 162.725862 -293.795958) (xy 162.71748 -293.78275)
			(xy 162.711384 -293.77767) (xy 162.693388 -293.761866) (xy 162.66169 -293.725963) (xy 162.635491 -293.685871)
			(xy 162.615337 -293.642424) (xy 162.601649 -293.596529) (xy 162.594711 -293.54914) (xy 162.59429 -293.525194)
			(xy 162.59429 -293.52494) (xy 162.5948 -293.498953) (xy 162.60293 -293.447618) (xy 162.618991 -293.398188)
			(xy 162.642587 -293.351878) (xy 162.673137 -293.30983) (xy 162.709888 -293.273079) (xy 162.751936 -293.242529)
			(xy 162.798246 -293.218933) (xy 162.847676 -293.202872) (xy 162.899011 -293.194742) (xy 162.950985 -293.194742)
			(xy 163.00232 -293.202872) (xy 163.05175 -293.218933) (xy 163.09806 -293.242529) (xy 163.140108 -293.273079)
			(xy 163.176859 -293.30983) (xy 163.207409 -293.351878) (xy 163.231005 -293.398188) (xy 163.247066 -293.447618)
			(xy 163.255196 -293.498953) (xy 163.255706 -293.52494) (xy 163.255706 -293.525194) (xy 163.255116 -293.553234)
			(xy 163.245658 -293.60851) (xy 163.227014 -293.661399) (xy 163.199716 -293.710385) (xy 163.164547 -293.754066)
			(xy 163.143946 -293.773098) (xy 163.138358 -293.777924) (xy 163.122102 -293.803578) (xy 163.12007 -293.810944)
			(xy 163.120578 -293.818818) (xy 163.120789 -293.822639) (xy 163.122199 -293.830161) (xy 163.123372 -293.833804)
			(xy 163.156392 -293.92372) (xy 163.159978 -293.932172) (xy 163.172066 -293.945974) (xy 163.188245 -293.954626)
			(xy 163.197286 -293.956232) (xy 163.197794 -293.956232) (xy 163.20389 -293.95674) (xy 163.819078 -293.95674)
			(xy 163.827714 -293.955978) (xy 163.835233 -293.954379) (xy 163.848923 -293.947404) (xy 163.854638 -293.942262)
			(xy 164.108384 -293.688516) (xy 164.113574 -293.682836) (xy 164.120551 -293.669129) (xy 164.1221 -293.661592)
			(xy 164.1221 -293.661084) (xy 164.122862 -293.652956) (xy 164.122862 -292.981634) (xy 164.1221 -292.972744)
			(xy 164.119991 -292.963592) (xy 164.110218 -292.947572) (xy 164.10305 -292.941502) (xy 164.071808 -292.919658)
			(xy 164.0332 -292.89248) (xy 164.025306 -292.887507) (xy 164.007195 -292.883091) (xy 163.997894 -292.883844)
			(xy 163.990528 -292.88486) (xy 163.988242 -292.885622) (xy 163.98621 -292.886384) (xy 163.959282 -292.895382)
			(xy 163.903344 -292.905079) (xy 163.874958 -292.905688) (xy 163.848975 -292.905175) (xy 163.797648 -292.89704)
			(xy 163.748226 -292.880976) (xy 163.701925 -292.85738) (xy 163.659886 -292.826831) (xy 163.623142 -292.790082)
			(xy 163.592598 -292.748039) (xy 163.569008 -292.701735) (xy 163.55295 -292.652311) (xy 163.544821 -292.600984)
			(xy 163.544821 -292.549016) (xy 163.55295 -292.497689) (xy 163.569008 -292.448265) (xy 163.592598 -292.401961)
			(xy 163.623142 -292.359918) (xy 163.659886 -292.323169) (xy 163.701925 -292.29262) (xy 163.748226 -292.269024)
			(xy 163.797648 -292.25296) (xy 163.848975 -292.244825) (xy 163.874958 -292.244272) (xy 163.901466 -292.244836)
			(xy 163.95379 -292.253385) (xy 163.979098 -292.26129) (xy 163.986972 -292.26383) (xy 163.987226 -292.26383)
			(xy 163.988496 -292.264338) (xy 163.99383 -292.265862) (xy 164.004498 -292.267132) (xy 164.010848 -292.266116)
			(xy 164.01161 -292.266116) (xy 164.01288 -292.265862) (xy 164.018322 -292.264779) (xy 164.028574 -292.260543)
			(xy 164.0332 -292.25748) (xy 164.03447 -292.256718) (xy 164.103304 -292.208204) (xy 164.11209 -292.200663)
			(xy 164.122262 -292.17989) (xy 164.122862 -292.168326) (xy 164.122862 -292.03142) (xy 164.1221 -292.02253)
			(xy 164.119989 -292.013379) (xy 164.110213 -291.997362) (xy 164.10305 -291.991288) (xy 164.071808 -291.969444)
			(xy 164.0332 -291.942266) (xy 164.025308 -291.937286) (xy 164.007195 -291.932862) (xy 163.997894 -291.93363)
			(xy 163.990528 -291.934646) (xy 163.988242 -291.935408) (xy 163.98621 -291.93617) (xy 163.959282 -291.945168)
			(xy 163.903344 -291.954866) (xy 163.874958 -291.955474) (xy 163.848976 -291.954961) (xy 163.797652 -291.946826)
			(xy 163.748232 -291.930763) (xy 163.701933 -291.907168) (xy 163.659895 -291.87662) (xy 163.623152 -291.839873)
			(xy 163.59261 -291.797831) (xy 163.56902 -291.751529) (xy 163.552964 -291.702108) (xy 163.544835 -291.650782)
			(xy 163.544835 -291.598818) (xy 163.552964 -291.547492) (xy 163.56902 -291.498071) (xy 163.59261 -291.451769)
			(xy 163.623152 -291.409727) (xy 163.659895 -291.37298) (xy 163.701933 -291.342432) (xy 163.748232 -291.318837)
			(xy 163.797652 -291.302774) (xy 163.848976 -291.294639) (xy 163.874958 -291.294058) (xy 163.901466 -291.294622)
			(xy 163.95379 -291.30317) (xy 163.979098 -291.311076) (xy 163.986972 -291.313616) (xy 163.987226 -291.313616)
			(xy 163.988496 -291.314124) (xy 163.99383 -291.315648) (xy 164.004498 -291.316918) (xy 164.010848 -291.315902)
			(xy 164.01161 -291.315902) (xy 164.01288 -291.315648) (xy 164.018323 -291.314567) (xy 164.028579 -291.310337)
			(xy 164.0332 -291.307266) (xy 164.03447 -291.306504) (xy 164.103304 -291.25799) (xy 164.112104 -291.250454)
			(xy 164.122311 -291.229683) (xy 164.122862 -291.218112) (xy 164.122862 -291.08146) (xy 164.1221 -291.07257)
			(xy 164.119995 -291.063415) (xy 164.110227 -291.047388) (xy 164.10305 -291.041328) (xy 164.071808 -291.019484)
			(xy 164.0332 -290.992306) (xy 164.025306 -290.987331) (xy 164.007195 -290.982913) (xy 163.997894 -290.98367)
			(xy 163.990528 -290.984686) (xy 163.988242 -290.985448) (xy 163.98621 -290.98621) (xy 163.959282 -290.99521)
			(xy 163.903344 -291.004909) (xy 163.874958 -291.005514) (xy 163.848973 -291.005001) (xy 163.797642 -290.996865)
			(xy 163.748216 -290.9808) (xy 163.701912 -290.957202) (xy 163.659869 -290.926651) (xy 163.623122 -290.889899)
			(xy 163.592576 -290.847852) (xy 163.568984 -290.801545) (xy 163.552925 -290.752117) (xy 163.544795 -290.700786)
			(xy 163.544795 -290.648814) (xy 163.552925 -290.597483) (xy 163.568984 -290.548055) (xy 163.592576 -290.501748)
			(xy 163.623122 -290.459701) (xy 163.659869 -290.422949) (xy 163.701912 -290.392398) (xy 163.748216 -290.3688)
			(xy 163.797642 -290.352735) (xy 163.848973 -290.344599) (xy 163.874958 -290.344098) (xy 163.901466 -290.344662)
			(xy 163.95379 -290.353212) (xy 163.979098 -290.361116) (xy 163.986972 -290.363656) (xy 163.987226 -290.363656)
			(xy 163.988496 -290.364164) (xy 163.99383 -290.365688) (xy 164.004498 -290.366958) (xy 164.010848 -290.365942)
			(xy 164.01161 -290.365942) (xy 164.01288 -290.365688) (xy 164.018322 -290.364605) (xy 164.028575 -290.360372)
			(xy 164.0332 -290.357306) (xy 164.03447 -290.356544) (xy 164.103304 -290.30803) (xy 164.112094 -290.30049)
			(xy 164.122277 -290.279718) (xy 164.122862 -290.268152) (xy 164.122862 -290.181284) (xy 164.121846 -290.171632)
			(xy 164.119306 -290.157916) (xy 164.117528 -290.153344) (xy 164.115496 -290.14801) (xy 164.021516 -290.05403)
			(xy 164.016702 -290.049507) (xy 164.005248 -290.042935) (xy 163.99891 -290.041076) (xy 163.99129 -290.039044)
			(xy 163.977574 -290.039298) (xy 163.97097 -290.04133) (xy 163.947591 -290.047979) (xy 163.899514 -290.055128)
			(xy 163.875212 -290.055554) (xy 163.874958 -290.055554) (xy 163.848972 -290.055041) (xy 163.79764 -290.046906)
			(xy 163.748212 -290.030842) (xy 163.701905 -290.007244) (xy 163.659858 -289.976695) (xy 163.623108 -289.939945)
			(xy 163.592558 -289.897899) (xy 163.56896 -289.851592) (xy 163.552895 -289.802164) (xy 163.544759 -289.750832)
			(xy 163.54425 -289.724846) (xy 163.54425 -289.724592) (xy 163.544698 -289.700291) (xy 163.551836 -289.652215)
			(xy 163.558474 -289.628834) (xy 163.560506 -289.62223) (xy 163.56076 -289.608514) (xy 163.558728 -289.600894)
			(xy 163.55681 -289.59458) (xy 163.550257 -289.58313) (xy 163.545774 -289.578288) (xy 163.071556 -289.10407)
			(xy 163.066736 -289.099557) (xy 163.055277 -289.093006) (xy 163.04895 -289.091116) (xy 163.04133 -289.089084)
			(xy 163.027614 -289.089338) (xy 163.02101 -289.09137) (xy 162.99763 -289.098014) (xy 162.949554 -289.105153)
			(xy 162.925252 -289.105594) (xy 162.924998 -289.105594) (xy 162.899009 -289.105111) (xy 162.847672 -289.096979)
			(xy 162.798238 -289.080917) (xy 162.751926 -289.057318) (xy 162.709876 -289.026766) (xy 162.673124 -288.990011)
			(xy 162.642573 -288.94796) (xy 162.618977 -288.901647) (xy 162.602917 -288.852213) (xy 162.594788 -288.800875)
			(xy 162.59429 -288.774886) (xy 162.59429 -288.774632) (xy 162.594742 -288.750332) (xy 162.60189 -288.702259)
			(xy 162.608514 -288.678874) (xy 162.610546 -288.67227) (xy 162.6108 -288.658554) (xy 162.608768 -288.650934)
			(xy 162.606846 -288.644622) (xy 162.600287 -288.633178) (xy 162.595814 -288.628328) (xy 162.121596 -288.15411)
			(xy 162.11678 -288.14959) (xy 162.105324 -288.143026) (xy 162.09899 -288.141156) (xy 162.09137 -288.139124)
			(xy 162.077654 -288.139378) (xy 162.07105 -288.14141) (xy 162.047671 -288.148058) (xy 161.999594 -288.155204)
			(xy 161.975292 -288.155634) (xy 161.975038 -288.155634) (xy 161.949046 -288.155154) (xy 161.897701 -288.147027)
			(xy 161.84826 -288.130969) (xy 161.80194 -288.107374) (xy 161.759881 -288.076822) (xy 161.723119 -288.040068)
			(xy 161.69256 -287.998015) (xy 161.668956 -287.951699) (xy 161.652888 -287.902261) (xy 161.644751 -287.850918)
			(xy 161.64433 -287.824926) (xy 161.64433 -287.824672) (xy 161.644779 -287.800371) (xy 161.65192 -287.752296)
			(xy 161.658554 -287.728914) (xy 161.660586 -287.72231) (xy 161.66084 -287.708594) (xy 161.658808 -287.700974)
			(xy 161.656888 -287.694661) (xy 161.65033 -287.683216) (xy 161.645854 -287.678368) (xy 161.171636 -287.20415)
			(xy 161.166824 -287.199624) (xy 161.155372 -287.193045) (xy 161.14903 -287.191196) (xy 161.14141 -287.189164)
			(xy 161.127694 -287.189418) (xy 161.12109 -287.19145) (xy 161.09771 -287.198093) (xy 161.049634 -287.20523)
			(xy 161.025332 -287.205674) (xy 161.025078 -287.205674) (xy 160.999091 -287.205189) (xy 160.947757 -287.197055)
			(xy 160.898328 -287.18099) (xy 160.85202 -287.157391) (xy 160.809974 -287.126838) (xy 160.773226 -287.090083)
			(xy 160.74268 -287.048032) (xy 160.719088 -287.001721) (xy 160.703032 -286.952289) (xy 160.694906 -286.900953)
			(xy 160.69437 -286.874966) (xy 160.69437 -286.874712) (xy 160.694816 -286.850411) (xy 160.701952 -286.802334)
			(xy 160.708594 -286.778954) (xy 160.710626 -286.77235) (xy 160.71088 -286.758634) (xy 160.708848 -286.751014)
			(xy 160.706923 -286.744704) (xy 160.700359 -286.733265) (xy 160.695894 -286.728408) (xy 159.271462 -285.303976)
			(xy 159.266643 -285.299462) (xy 159.255184 -285.292909) (xy 159.248856 -285.291022) (xy 159.241236 -285.28899)
			(xy 159.22752 -285.289244) (xy 159.220916 -285.291276) (xy 159.197536 -285.29792) (xy 159.14946 -285.30506)
			(xy 159.125158 -285.3055) (xy 159.124904 -285.3055) (xy 159.098915 -285.305017) (xy 159.047576 -285.296886)
			(xy 158.998142 -285.280824) (xy 158.951828 -285.257227) (xy 158.909777 -285.226674) (xy 158.873023 -285.18992)
			(xy 158.842471 -285.147868) (xy 158.818874 -285.101555) (xy 158.802813 -285.05212) (xy 158.794683 -285.000781)
			(xy 158.794196 -284.974792) (xy 158.794196 -284.974538) (xy 158.794648 -284.950238) (xy 158.801795 -284.902164)
			(xy 158.80842 -284.87878) (xy 158.810452 -284.872176) (xy 158.810706 -284.85846) (xy 158.808674 -284.85084)
			(xy 158.806753 -284.844528) (xy 158.800196 -284.833082) (xy 158.79572 -284.828234) (xy 158.321502 -284.354016)
			(xy 158.316686 -284.349495) (xy 158.305232 -284.342928) (xy 158.298896 -284.341062) (xy 158.291276 -284.33903)
			(xy 158.27756 -284.339284) (xy 158.270956 -284.341316) (xy 158.247577 -284.347964) (xy 158.1995 -284.355111)
			(xy 158.175198 -284.35554) (xy 158.174944 -284.35554) (xy 158.148952 -284.35506) (xy 158.097606 -284.346935)
			(xy 158.048163 -284.330877) (xy 158.001842 -284.307282) (xy 157.959782 -284.276731) (xy 157.923019 -284.239976)
			(xy 157.892458 -284.197923) (xy 157.868852 -284.151607) (xy 157.852783 -284.102168) (xy 157.844646 -284.050824)
			(xy 157.844236 -284.024832) (xy 157.844697 -284.000179) (xy 157.852031 -283.951422) (xy 157.866525 -283.904294)
			(xy 157.887859 -283.859842) (xy 157.915559 -283.819053) (xy 157.94901 -283.78283) (xy 157.967934 -283.767022)
			(xy 157.968188 -283.766768) (xy 157.972506 -283.763212) (xy 157.975808 -283.759402) (xy 157.980888 -283.752036)
			(xy 157.991556 -283.730192) (xy 157.99181 -283.72943) (xy 157.994132 -283.724267) (xy 157.996694 -283.713243)
			(xy 157.99689 -283.707586) (xy 157.99689 -283.397706) (xy 157.995874 -283.388054) (xy 157.99181 -283.371798)
			(xy 157.990032 -283.366972) (xy 157.98038 -283.34716) (xy 157.975808 -283.340302) (xy 157.972506 -283.336492)
			(xy 157.968188 -283.332936) (xy 157.967934 -283.332682) (xy 157.947308 -283.315423) (xy 157.911401 -283.27539)
			(xy 157.882442 -283.230075) (xy 157.861196 -283.180672) (xy 157.848221 -283.128483) (xy 157.84386 -283.074882)
			(xy 157.848227 -283.021282) (xy 157.861207 -282.969095) (xy 157.882459 -282.919694) (xy 157.911422 -282.874382)
			(xy 157.947334 -282.834352) (xy 157.967934 -282.817062) (xy 157.968188 -282.816808) (xy 157.972506 -282.813252)
			(xy 157.975808 -282.809442) (xy 157.980888 -282.802076) (xy 157.991556 -282.780232) (xy 157.99181 -282.77947)
			(xy 157.994136 -282.774308) (xy 157.996707 -282.763284) (xy 157.99689 -282.757626) (xy 157.99689 -282.447746)
			(xy 157.995874 -282.438094) (xy 157.99181 -282.421838) (xy 157.990032 -282.417012) (xy 157.98038 -282.3972)
			(xy 157.975808 -282.390342) (xy 157.972506 -282.386532) (xy 157.968188 -282.382976) (xy 157.967934 -282.382722)
			(xy 157.947305 -282.365463) (xy 157.911391 -282.325429) (xy 157.882427 -282.280111) (xy 157.861175 -282.230706)
			(xy 157.848195 -282.178513) (xy 157.843829 -282.124908) (xy 157.848192 -282.071302) (xy 157.86117 -282.019109)
			(xy 157.88242 -281.969702) (xy 157.911382 -281.924383) (xy 157.947294 -281.884347) (xy 157.967934 -281.867102)
			(xy 157.968188 -281.866848) (xy 157.972506 -281.863292) (xy 157.975808 -281.859482) (xy 157.980888 -281.852116)
			(xy 157.991556 -281.830272) (xy 157.99181 -281.82951) (xy 157.99413 -281.824347) (xy 157.996688 -281.813323)
			(xy 157.99689 -281.807666) (xy 157.99689 -281.497786) (xy 157.995874 -281.488134) (xy 157.99181 -281.471878)
			(xy 157.990032 -281.467052) (xy 157.98038 -281.44724) (xy 157.975808 -281.440382) (xy 157.972506 -281.436572)
			(xy 157.968188 -281.433016) (xy 157.967934 -281.432762) (xy 157.94731 -281.415503) (xy 157.911406 -281.37547)
			(xy 157.88245 -281.330156) (xy 157.861207 -281.280755) (xy 157.848235 -281.228568) (xy 157.843876 -281.17497)
			(xy 157.848244 -281.121373) (xy 157.861226 -281.069188) (xy 157.882479 -281.01979) (xy 157.911442 -280.974482)
			(xy 157.947354 -280.934455) (xy 157.967934 -280.917142) (xy 157.968188 -280.916888) (xy 157.972506 -280.913332)
			(xy 157.975808 -280.909522) (xy 157.980888 -280.902156) (xy 157.991556 -280.880312) (xy 157.99181 -280.87955)
			(xy 157.994134 -280.874388) (xy 157.9967 -280.863364) (xy 157.99689 -280.857706) (xy 157.99689 -280.547572)
			(xy 157.995874 -280.53792) (xy 157.99181 -280.521664) (xy 157.990032 -280.516838) (xy 157.98038 -280.497026)
			(xy 157.975808 -280.490168) (xy 157.972506 -280.486358) (xy 157.968188 -280.482802) (xy 157.967934 -280.482548)
			(xy 157.947303 -280.465289) (xy 157.911385 -280.425254) (xy 157.882416 -280.379935) (xy 157.861161 -280.330528)
			(xy 157.848177 -280.278332) (xy 157.843809 -280.224724) (xy 157.84817 -280.171115) (xy 157.861145 -280.118918)
			(xy 157.882394 -280.069507) (xy 157.911356 -280.024184) (xy 157.947268 -279.984144) (xy 157.967934 -279.966928)
			(xy 157.968188 -279.966674) (xy 157.972506 -279.963118) (xy 157.975808 -279.959308) (xy 157.980888 -279.951942)
			(xy 157.991556 -279.930098) (xy 157.99181 -279.929336) (xy 157.994132 -279.924173) (xy 157.996696 -279.91315)
			(xy 157.99689 -279.907492) (xy 157.99689 -279.597612) (xy 157.995874 -279.58796) (xy 157.99181 -279.571704)
			(xy 157.990032 -279.566878) (xy 157.98038 -279.547066) (xy 157.975808 -279.540208) (xy 157.972506 -279.536398)
			(xy 157.968188 -279.532842) (xy 157.967934 -279.532588) (xy 157.947308 -279.515329) (xy 157.911399 -279.475296)
			(xy 157.88244 -279.42998) (xy 157.861193 -279.380577) (xy 157.848217 -279.328387) (xy 157.843855 -279.274786)
			(xy 157.848222 -279.221185) (xy 157.861202 -279.168997) (xy 157.882453 -279.119595) (xy 157.911416 -279.074282)
			(xy 157.947328 -279.034252) (xy 157.967934 -279.016968) (xy 157.968188 -279.016714) (xy 157.972506 -279.013158)
			(xy 157.975808 -279.009348) (xy 157.980888 -279.001982) (xy 157.991556 -278.980138) (xy 157.99181 -278.979376)
			(xy 157.994136 -278.974214) (xy 157.996709 -278.963191) (xy 157.99689 -278.957532) (xy 157.99689 -278.647652)
			(xy 157.995874 -278.638) (xy 157.99181 -278.621744) (xy 157.990032 -278.616918) (xy 157.98038 -278.597106)
			(xy 157.975808 -278.590248) (xy 157.972506 -278.586438) (xy 157.968188 -278.582882) (xy 157.967934 -278.582628)
			(xy 157.947304 -278.565369) (xy 157.91139 -278.525334) (xy 157.882424 -278.480017) (xy 157.861171 -278.430611)
			(xy 157.848191 -278.378417) (xy 157.843824 -278.324811) (xy 157.848187 -278.271205) (xy 157.861164 -278.219011)
			(xy 157.882414 -278.169603) (xy 157.911376 -278.124284) (xy 157.947288 -278.084246) (xy 157.967934 -278.067008)
			(xy 157.968188 -278.066754) (xy 157.972506 -278.063198) (xy 157.975808 -278.059388) (xy 157.980888 -278.052022)
			(xy 157.991556 -278.030178) (xy 157.99181 -278.029416) (xy 157.99413 -278.024253) (xy 157.99669 -278.013229)
			(xy 157.99689 -278.007572) (xy 157.99689 -277.697692) (xy 157.995874 -277.68804) (xy 157.99181 -277.671784)
			(xy 157.990032 -277.666958) (xy 157.98038 -277.647146) (xy 157.975808 -277.640288) (xy 157.972506 -277.636478)
			(xy 157.968188 -277.632922) (xy 157.967934 -277.632668) (xy 157.947309 -277.615409) (xy 157.911404 -277.575376)
			(xy 157.882448 -277.530062) (xy 157.861204 -277.48066) (xy 157.848231 -277.428473) (xy 157.843871 -277.374874)
			(xy 157.848239 -277.321275) (xy 157.86122 -277.26909) (xy 157.882473 -277.219692) (xy 157.911436 -277.174382)
			(xy 157.947348 -277.134354) (xy 157.967934 -277.117048) (xy 157.968188 -277.116794) (xy 157.972506 -277.113238)
			(xy 157.975808 -277.109428) (xy 157.980888 -277.102062) (xy 157.991556 -277.080218) (xy 157.99181 -277.079456)
			(xy 157.994134 -277.074294) (xy 157.996702 -277.06327) (xy 157.99689 -277.057612) (xy 157.99689 -276.747732)
			(xy 157.995874 -276.73808) (xy 157.99181 -276.721824) (xy 157.990032 -276.716998) (xy 157.98038 -276.697186)
			(xy 157.975808 -276.690328) (xy 157.972506 -276.686518) (xy 157.968188 -276.682962) (xy 157.967934 -276.682708)
			(xy 157.947306 -276.665449) (xy 157.911394 -276.625415) (xy 157.882432 -276.580099) (xy 157.861182 -276.530694)
			(xy 157.848204 -276.478502) (xy 157.84384 -276.424899) (xy 157.848204 -276.371295) (xy 157.861183 -276.319104)
			(xy 157.882433 -276.269699) (xy 157.911396 -276.224383) (xy 157.947308 -276.184349) (xy 157.967934 -276.167088)
			(xy 157.968188 -276.166834) (xy 157.972506 -276.163278) (xy 157.975808 -276.159468) (xy 157.980888 -276.152102)
			(xy 157.991556 -276.130258) (xy 157.99181 -276.129496) (xy 157.994128 -276.124333) (xy 157.996683 -276.113309)
			(xy 157.99689 -276.107652) (xy 157.99689 -275.797772) (xy 157.995874 -275.78812) (xy 157.99181 -275.771864)
			(xy 157.990032 -275.767038) (xy 157.98038 -275.747226) (xy 157.975808 -275.740368) (xy 157.972506 -275.736558)
			(xy 157.968188 -275.733002) (xy 157.967934 -275.732748) (xy 157.947303 -275.715489) (xy 157.911385 -275.675454)
			(xy 157.882416 -275.630135) (xy 157.861161 -275.580728) (xy 157.848177 -275.528532) (xy 157.843809 -275.474924)
			(xy 157.84817 -275.421315) (xy 157.861145 -275.369118) (xy 157.882394 -275.319707) (xy 157.911356 -275.274384)
			(xy 157.947268 -275.234344) (xy 157.967934 -275.217128) (xy 157.968188 -275.216874) (xy 157.972506 -275.213318)
			(xy 157.975808 -275.209508) (xy 157.980888 -275.202142) (xy 157.991556 -275.180298) (xy 157.99181 -275.179536)
			(xy 157.994132 -275.174373) (xy 157.996696 -275.16335) (xy 157.99689 -275.157692) (xy 157.99689 -274.847812)
			(xy 157.995874 -274.83816) (xy 157.99181 -274.821904) (xy 157.990032 -274.817078) (xy 157.98038 -274.797266)
			(xy 157.975808 -274.790408) (xy 157.972506 -274.786598) (xy 157.968188 -274.783042) (xy 157.967934 -274.782788)
			(xy 157.947308 -274.765529) (xy 157.911399 -274.725496) (xy 157.88244 -274.68018) (xy 157.861193 -274.630777)
			(xy 157.848217 -274.578587) (xy 157.843855 -274.524986) (xy 157.848222 -274.471385) (xy 157.861202 -274.419197)
			(xy 157.882453 -274.369795) (xy 157.911416 -274.324482) (xy 157.947328 -274.284452) (xy 157.967934 -274.267168)
			(xy 157.968188 -274.266914) (xy 157.972506 -274.263358) (xy 157.975808 -274.259548) (xy 157.980888 -274.252182)
			(xy 157.991556 -274.230338) (xy 157.99181 -274.229576) (xy 157.994136 -274.224414) (xy 157.996709 -274.213391)
			(xy 157.99689 -274.207732) (xy 157.99689 -273.897598) (xy 157.995874 -273.887946) (xy 157.99181 -273.87169)
			(xy 157.990032 -273.866864) (xy 157.98038 -273.847052) (xy 157.975808 -273.840194) (xy 157.972506 -273.836384)
			(xy 157.968188 -273.832828) (xy 157.967934 -273.832574) (xy 157.947309 -273.815315) (xy 157.911403 -273.775282)
			(xy 157.882446 -273.729967) (xy 157.8612 -273.680565) (xy 157.848227 -273.628377) (xy 157.843866 -273.574777)
			(xy 157.848234 -273.521178) (xy 157.861215 -273.468992) (xy 157.882467 -273.419593) (xy 157.91143 -273.374282)
			(xy 157.947342 -273.334254) (xy 157.967934 -273.316954) (xy 157.968188 -273.3167) (xy 157.972506 -273.313144)
			(xy 157.975808 -273.309334) (xy 157.980888 -273.301968) (xy 157.991556 -273.280124) (xy 157.99181 -273.279362)
			(xy 157.994135 -273.2742) (xy 157.996704 -273.263176) (xy 157.99689 -273.257518) (xy 157.99689 -272.947638)
			(xy 157.995874 -272.937986) (xy 157.99181 -272.92173) (xy 157.990032 -272.916904) (xy 157.98038 -272.897092)
			(xy 157.975808 -272.890234) (xy 157.972506 -272.886424) (xy 157.968188 -272.882868) (xy 157.967934 -272.882614)
			(xy 157.947306 -272.865355) (xy 157.911393 -272.825321) (xy 157.88243 -272.780004) (xy 157.861179 -272.730599)
			(xy 157.8482 -272.678407) (xy 157.843835 -272.624803) (xy 157.848199 -272.571198) (xy 157.861177 -272.519006)
			(xy 157.882427 -272.4696) (xy 157.91139 -272.424283) (xy 157.947302 -272.384248) (xy 157.967934 -272.366994)
			(xy 157.968188 -272.36674) (xy 157.972506 -272.363184) (xy 157.975808 -272.359374) (xy 157.980888 -272.352008)
			(xy 157.991556 -272.330164) (xy 157.99181 -272.329402) (xy 157.994129 -272.324239) (xy 157.996685 -272.313215)
			(xy 157.99689 -272.307558) (xy 157.99689 -267.286486) (xy 157.996776 -267.281389) (xy 157.994727 -267.271404)
			(xy 157.992826 -267.266674) (xy 157.981396 -267.240004) (xy 157.976062 -267.234416) (xy 157.957334 -267.214839)
			(xy 157.925033 -267.171345) (xy 157.899209 -267.123719) (xy 157.880383 -267.072919) (xy 157.868931 -267.019967)
			(xy 157.865086 -266.965927) (xy 157.868924 -266.911887) (xy 157.880368 -266.858933) (xy 157.899187 -266.80813)
			(xy 157.925004 -266.760501) (xy 157.957299 -266.717002) (xy 157.976062 -266.69746) (xy 157.981396 -266.691872)
			(xy 157.992826 -266.665202) (xy 157.994695 -266.660462) (xy 157.99674 -266.650483) (xy 157.99689 -266.64539)
			(xy 157.99689 -266.552934) (xy 157.99689 -266.550902) (xy 157.996217 -266.542324) (xy 157.989853 -266.526351)
			(xy 157.984444 -266.51966) (xy 157.966249 -266.499751) (xy 157.935074 -266.455741) (xy 157.910414 -266.407776)
			(xy 157.892762 -266.356813) (xy 157.887162 -266.33043) (xy 157.88513 -266.320016) (xy 157.879034 -266.31138)
			(xy 157.876425 -266.307748) (xy 157.870168 -266.30136) (xy 157.866588 -266.29868) (xy 157.797754 -266.255754)
			(xy 157.793903 -266.253841) (xy 157.785734 -266.251158) (xy 157.781498 -266.25042) (xy 157.771592 -266.248896)
			(xy 157.760924 -266.25169) (xy 157.736561 -266.257864) (xy 157.68674 -266.264491) (xy 157.66161 -266.264898)
			(xy 157.634357 -266.264435) (xy 157.580405 -266.256679) (xy 157.528107 -266.241324) (xy 157.478526 -266.218682)
			(xy 157.432673 -266.189214) (xy 157.39148 -266.15352) (xy 157.355786 -266.112327) (xy 157.326318 -266.066474)
			(xy 157.303676 -266.016893) (xy 157.288321 -265.964595) (xy 157.280565 -265.910643) (xy 157.280102 -265.88339)
			(xy 157.280564 -265.856483) (xy 157.288126 -265.803202) (xy 157.303098 -265.751513) (xy 157.325184 -265.70244)
			(xy 157.353946 -265.656956) (xy 157.388813 -265.615964) (xy 157.429092 -265.580278) (xy 157.473986 -265.550604)
			(xy 157.522604 -265.527533) (xy 157.573981 -265.51152) (xy 157.627098 -265.502885) (xy 157.65399 -265.501882)
			(xy 157.66161 -265.501882) (xy 157.693748 -265.502528) (xy 157.757122 -265.513256) (xy 157.817806 -265.534441)
			(xy 157.846268 -265.54938) (xy 157.852364 -265.552936) (xy 157.86481 -265.555984) (xy 157.87116 -265.555984)
			(xy 157.877631 -265.555695) (xy 157.890105 -265.552218) (xy 157.895798 -265.549126) (xy 157.96133 -265.510518)
			(xy 157.971744 -265.504422) (xy 157.976824 -265.50112) (xy 157.981056 -265.497753) (xy 157.988104 -265.489555)
			(xy 157.990794 -265.484864) (xy 157.992572 -265.481308) (xy 157.994386 -265.47694) (xy 157.996566 -265.467738)
			(xy 157.99689 -265.46302) (xy 157.99689 -265.339068) (xy 157.996636 -265.33475) (xy 157.991048 -265.272774)
			(xy 157.96641 -264.991088) (xy 157.965902 -264.987024) (xy 157.91942 -264.706608) (xy 157.916378 -264.687898)
			(xy 157.911551 -264.650296) (xy 157.909768 -264.631424) (xy 157.90418 -264.569448) (xy 157.90164 -264.568432)
			(xy 157.878526 -264.559034) (xy 157.815788 -264.53338) (xy 157.809707 -264.531411) (xy 157.79698 -264.53026)
			(xy 157.790642 -264.531094) (xy 157.784038 -264.53211) (xy 157.771592 -264.537698) (xy 157.76575 -264.542524)
			(xy 157.744956 -264.55965) (xy 157.699458 -264.588491) (xy 157.650353 -264.610642) (xy 157.59862 -264.625661)
			(xy 157.545289 -264.63325) (xy 157.518354 -264.63371) (xy 157.491105 -264.633221) (xy 157.437162 -264.625459)
			(xy 157.384872 -264.6101) (xy 157.335301 -264.587456) (xy 157.289456 -264.557988) (xy 157.248271 -264.522297)
			(xy 157.212584 -264.481107) (xy 157.183122 -264.435259) (xy 157.160484 -264.385685) (xy 157.145131 -264.333393)
			(xy 157.137376 -264.279449) (xy 157.137376 -264.224951) (xy 157.145131 -264.171007) (xy 157.160484 -264.118715)
			(xy 157.183122 -264.069141) (xy 157.212584 -264.023293) (xy 157.248271 -263.982103) (xy 157.289456 -263.946412)
			(xy 157.335301 -263.916944) (xy 157.384872 -263.8943) (xy 157.437162 -263.878941) (xy 157.491105 -263.871179)
			(xy 157.518354 -263.870694) (xy 157.518608 -263.870694) (xy 157.543115 -263.871068) (xy 157.591724 -263.877343)
			(xy 157.639128 -263.889802) (xy 157.684541 -263.908238) (xy 157.70606 -263.91997) (xy 157.717744 -263.924796)
			(xy 157.738064 -263.93013) (xy 157.738318 -263.93013) (xy 157.75178 -263.929876) (xy 157.830012 -263.8806)
			(xy 157.840426 -263.873996) (xy 157.842458 -263.872726) (xy 157.763464 -262.979916) (xy 157.746954 -262.95731)
			(xy 157.734 -262.951722) (xy 157.708983 -262.940485) (xy 157.662187 -262.911889) (xy 157.619968 -262.876888)
			(xy 157.583193 -262.836203) (xy 157.552623 -262.790673) (xy 157.528885 -262.741235) (xy 157.512469 -262.688909)
			(xy 157.503714 -262.634771) (xy 157.5028 -262.579937) (xy 157.509745 -262.525537) (xy 157.524407 -262.472692)
			(xy 157.546483 -262.42249) (xy 157.575519 -262.375966) (xy 157.610916 -262.334078) (xy 157.651946 -262.297689)
			(xy 157.674564 -262.282178) (xy 157.686248 -262.274558) (xy 157.69844 -262.249412) (xy 157.684978 -262.097774)
			(xy 157.672024 -262.0772) (xy 157.661356 -262.07085) (xy 157.6373 -262.056005) (xy 157.593447 -262.020341)
			(xy 157.55533 -261.978601) (xy 157.523782 -261.931699) (xy 157.499493 -261.880659) (xy 157.482992 -261.826595)
			(xy 157.474641 -261.77069) (xy 157.474158 -261.742428) (xy 157.474672 -261.714556) (xy 157.482796 -261.659406)
			(xy 157.498862 -261.606026) (xy 157.522526 -261.555553) (xy 157.553285 -261.509063) (xy 157.590483 -261.467544)
			(xy 157.611572 -261.449312) (xy 157.612588 -261.448296) (xy 157.616144 -261.445248) (xy 157.625034 -261.422896)
			(xy 157.376876 -258.62534) (xy 157.375705 -258.616609) (xy 157.368299 -258.60064) (xy 157.362398 -258.594098)
			(xy 155.320238 -256.551938) (xy 155.31465 -256.547112) (xy 155.307907 -256.542451) (xy 155.292361 -256.537283)
			(xy 155.28417 -256.536952) (xy 151.165814 -256.536952) (xy 151.158702 -256.53746) (xy 151.148051 -256.539464)
			(xy 151.12975 -256.551034) (xy 151.123396 -256.559812) (xy 151.108881 -256.585056) (xy 151.073388 -256.631217)
			(xy 151.031292 -256.671449) (xy 150.983573 -256.704817) (xy 150.931337 -256.730547) (xy 150.875798 -256.748042)
			(xy 150.818246 -256.756894) (xy 150.789132 -256.757424) (xy 150.780242 -256.757424) (xy 150.751512 -256.756232)
			(xy 150.694877 -256.746288) (xy 150.64037 -256.727974) (xy 150.589222 -256.701702) (xy 150.565612 -256.685288)
			(xy 150.559262 -256.680716) (xy 150.537926 -256.673604) (xy 150.536656 -256.67335) (xy 150.535132 -256.672842)
			(xy 150.521924 -256.671064) (xy 150.519638 -256.671064) (xy 150.494746 -256.672334) (xy 150.486079 -256.673529)
			(xy 150.47024 -256.680935) (xy 150.463758 -256.686812) (xy 150.091648 -257.058922) (xy 150.086822 -257.06451)
			(xy 150.082155 -257.071251) (xy 150.076974 -257.086797) (xy 150.076662 -257.09499) (xy 150.076662 -257.137916)
			(xy 152.679144 -257.137916) (xy 152.683215 -257.082294) (xy 152.695341 -257.027857) (xy 152.715264 -256.975766)
			(xy 152.74256 -256.927131) (xy 152.776646 -256.882988) (xy 152.816795 -256.844279) (xy 152.862153 -256.811828)
			(xy 152.911753 -256.786327) (xy 152.964537 -256.76832) (xy 153.01938 -256.75819) (xy 153.075114 -256.756153)
			(xy 153.130551 -256.762253) (xy 153.184508 -256.776359) (xy 153.235837 -256.798171) (xy 153.283443 -256.827225)
			(xy 153.326311 -256.8629) (xy 153.363528 -256.904437) (xy 153.394301 -256.95095) (xy 153.417973 -257.001447)
			(xy 153.434041 -257.054854) (xy 153.442161 -257.11003) (xy 153.44267 -257.137916) (xy 153.442161 -257.165802)
			(xy 153.434041 -257.220978) (xy 153.417973 -257.274385) (xy 153.394301 -257.324882) (xy 153.363528 -257.371395)
			(xy 153.326311 -257.412932) (xy 153.283443 -257.448607) (xy 153.235837 -257.477661) (xy 153.184508 -257.499473)
			(xy 153.130551 -257.513579) (xy 153.075114 -257.519679) (xy 153.01938 -257.517642) (xy 152.964537 -257.507512)
			(xy 152.911753 -257.489505) (xy 152.862153 -257.464004) (xy 152.816795 -257.431553) (xy 152.776646 -257.392844)
			(xy 152.74256 -257.348701) (xy 152.715264 -257.300066) (xy 152.695341 -257.247975) (xy 152.683215 -257.193538)
			(xy 152.679144 -257.137916) (xy 150.076662 -257.137916) (xy 150.076662 -258.691888) (xy 150.077424 -258.700524)
			(xy 150.079025 -258.708042) (xy 150.086002 -258.72173) (xy 150.09114 -258.727448) (xy 150.486364 -259.122672)
			(xy 150.492043 -259.127866) (xy 150.505748 -259.134849) (xy 150.513288 -259.136388) (xy 150.513796 -259.136388)
			(xy 150.521924 -259.13715) (xy 153.19248 -259.13715) (xy 153.202543 -259.137589) (xy 153.221121 -259.14533)
			(xy 153.228548 -259.152136) (xy 154.554936 -260.478524) (xy 154.561785 -260.485921) (xy 154.569521 -260.50452)
			(xy 154.569922 -260.514592) (xy 154.569922 -260.585966) (xy 154.57043 -260.58622) (xy 154.57043 -260.637782)
			(xy 154.570684 -260.638036) (xy 154.570684 -262.99541) (xy 154.571414 -263.001126) (xy 154.57514 -263.012026)
			(xy 154.57805 -263.017) (xy 154.58186 -263.022842) (xy 154.591766 -263.031986) (xy 154.598878 -263.035542)
			(xy 154.624045 -263.048524) (xy 154.670575 -263.080795) (xy 154.711824 -263.11959) (xy 154.746885 -263.164056)
			(xy 154.774987 -263.213217) (xy 154.795514 -263.265992) (xy 154.808013 -263.321221) (xy 154.812212 -263.377691)
			(xy 154.808016 -263.434162) (xy 154.795519 -263.489391) (xy 154.774995 -263.542167) (xy 154.746895 -263.591329)
			(xy 154.711836 -263.635797) (xy 154.670589 -263.674594) (xy 154.62406 -263.706867) (xy 154.598878 -263.719818)
			(xy 154.59837 -263.720072) (xy 154.592233 -263.723399) (xy 154.581923 -263.732806) (xy 154.57805 -263.738614)
			(xy 154.57424 -263.744456) (xy 154.572462 -263.750552) (xy 154.570684 -263.764014) (xy 154.570684 -263.823958)
			(xy 154.571166 -263.829332) (xy 154.574107 -263.83971) (xy 154.576526 -263.844532) (xy 154.588972 -263.865106)
			(xy 154.590242 -263.867138) (xy 154.5971 -263.876028) (xy 154.602434 -263.881362) (xy 154.608276 -263.884664)
			(xy 154.632589 -263.899447) (xy 154.676943 -263.935085) (xy 154.715514 -263.976915) (xy 154.747445 -264.024009)
			(xy 154.772029 -264.075323) (xy 154.78872 -264.129718) (xy 154.797149 -264.185989) (xy 154.797129 -264.242887)
			(xy 154.788659 -264.299152) (xy 154.771928 -264.353535) (xy 154.747307 -264.40483) (xy 154.715342 -264.451901)
			(xy 154.676741 -264.493703) (xy 154.632361 -264.52931) (xy 154.608022 -264.544048) (xy 154.602434 -264.54735)
			(xy 154.59837 -264.551414) (xy 154.590242 -264.561574) (xy 154.577796 -264.582402) (xy 154.574776 -264.587737)
			(xy 154.571064 -264.599418) (xy 154.57043 -264.605516) (xy 154.57043 -265.030204) (xy 154.570684 -265.039094)
			(xy 154.570684 -265.076178) (xy 154.57043 -265.085068) (xy 154.57043 -265.133328) (xy 154.570891 -265.138149)
			(xy 154.573439 -265.147492) (xy 154.57551 -265.15187) (xy 154.582378 -265.16457) (xy 156.563058 -265.16457)
			(xy 156.567129 -265.108948) (xy 156.579255 -265.054511) (xy 156.599178 -265.00242) (xy 156.626474 -264.953785)
			(xy 156.66056 -264.909642) (xy 156.700709 -264.870933) (xy 156.746067 -264.838482) (xy 156.795667 -264.812981)
			(xy 156.848451 -264.794974) (xy 156.903294 -264.784844) (xy 156.959028 -264.782807) (xy 157.014465 -264.788907)
			(xy 157.068422 -264.803013) (xy 157.119751 -264.824825) (xy 157.167357 -264.853879) (xy 157.210225 -264.889554)
			(xy 157.247442 -264.931091) (xy 157.278215 -264.977604) (xy 157.301887 -265.028101) (xy 157.317955 -265.081508)
			(xy 157.326075 -265.136684) (xy 157.326584 -265.16457) (xy 157.326075 -265.192456) (xy 157.317955 -265.247632)
			(xy 157.301887 -265.301039) (xy 157.278215 -265.351536) (xy 157.247442 -265.398049) (xy 157.210225 -265.439586)
			(xy 157.167357 -265.475261) (xy 157.119751 -265.504315) (xy 157.068422 -265.526127) (xy 157.014465 -265.540233)
			(xy 156.959028 -265.546333) (xy 156.903294 -265.544296) (xy 156.848451 -265.534166) (xy 156.795667 -265.516159)
			(xy 156.746067 -265.490658) (xy 156.700709 -265.458207) (xy 156.66056 -265.419498) (xy 156.626474 -265.375355)
			(xy 156.599178 -265.32672) (xy 156.579255 -265.274629) (xy 156.567129 -265.220192) (xy 156.563058 -265.16457)
			(xy 154.582378 -265.16457) (xy 154.588972 -265.176762) (xy 154.592528 -265.181842) (xy 154.596084 -265.185906)
			(xy 154.60091 -265.189716) (xy 154.622413 -265.206438) (xy 154.660911 -265.244974) (xy 154.693536 -265.288595)
			(xy 154.719626 -265.336412) (xy 154.738649 -265.387453) (xy 154.750219 -265.440682) (xy 154.754101 -265.495014)
			(xy 154.750215 -265.549347) (xy 154.738641 -265.602575) (xy 154.719614 -265.653615) (xy 154.693521 -265.70143)
			(xy 154.660892 -265.745047) (xy 154.622391 -265.783581) (xy 154.60091 -265.800332) (xy 154.596084 -265.804142)
			(xy 154.592528 -265.808206) (xy 154.589226 -265.812778) (xy 154.574494 -265.840464) (xy 154.57304 -265.843999)
			(xy 154.571117 -265.851398) (xy 154.570684 -265.855196) (xy 154.570684 -266.517882) (xy 156.497018 -266.517882)
			(xy 156.501089 -266.46226) (xy 156.513215 -266.407823) (xy 156.533138 -266.355732) (xy 156.560434 -266.307097)
			(xy 156.59452 -266.262954) (xy 156.634669 -266.224245) (xy 156.680027 -266.191794) (xy 156.729627 -266.166293)
			(xy 156.782411 -266.148286) (xy 156.837254 -266.138156) (xy 156.892988 -266.136119) (xy 156.948425 -266.142219)
			(xy 157.002382 -266.156325) (xy 157.053711 -266.178137) (xy 157.101317 -266.207191) (xy 157.144185 -266.242866)
			(xy 157.181402 -266.284403) (xy 157.212175 -266.330916) (xy 157.235847 -266.381413) (xy 157.251915 -266.43482)
			(xy 157.260035 -266.489996) (xy 157.260544 -266.517882) (xy 157.260035 -266.545768) (xy 157.251915 -266.600944)
			(xy 157.235847 -266.654351) (xy 157.212175 -266.704848) (xy 157.181402 -266.751361) (xy 157.144185 -266.792898)
			(xy 157.101317 -266.828573) (xy 157.053711 -266.857627) (xy 157.002382 -266.879439) (xy 156.948425 -266.893545)
			(xy 156.892988 -266.899645) (xy 156.837254 -266.897608) (xy 156.782411 -266.887478) (xy 156.729627 -266.869471)
			(xy 156.680027 -266.84397) (xy 156.634669 -266.811519) (xy 156.59452 -266.77281) (xy 156.560434 -266.728667)
			(xy 156.533138 -266.680032) (xy 156.513215 -266.627941) (xy 156.501089 -266.573504) (xy 156.497018 -266.517882)
			(xy 154.570684 -266.517882) (xy 154.570684 -266.963398) (xy 154.756102 -266.963398) (xy 154.760173 -266.907776)
			(xy 154.772299 -266.853339) (xy 154.792222 -266.801248) (xy 154.819518 -266.752613) (xy 154.853604 -266.70847)
			(xy 154.893753 -266.669761) (xy 154.939111 -266.63731) (xy 154.988711 -266.611809) (xy 155.041495 -266.593802)
			(xy 155.096338 -266.583672) (xy 155.152072 -266.581635) (xy 155.207509 -266.587735) (xy 155.261466 -266.601841)
			(xy 155.312795 -266.623653) (xy 155.360401 -266.652707) (xy 155.403269 -266.688382) (xy 155.440486 -266.729919)
			(xy 155.471259 -266.776432) (xy 155.494931 -266.826929) (xy 155.510999 -266.880336) (xy 155.519119 -266.935512)
			(xy 155.519628 -266.963398) (xy 155.519119 -266.991284) (xy 155.510999 -267.04646) (xy 155.494931 -267.099867)
			(xy 155.471259 -267.150364) (xy 155.440486 -267.196877) (xy 155.403269 -267.238414) (xy 155.360401 -267.274089)
			(xy 155.312795 -267.303143) (xy 155.261466 -267.324955) (xy 155.207509 -267.339061) (xy 155.152072 -267.345161)
			(xy 155.096338 -267.343124) (xy 155.041495 -267.332994) (xy 154.988711 -267.314987) (xy 154.939111 -267.289486)
			(xy 154.893753 -267.257035) (xy 154.853604 -267.218326) (xy 154.819518 -267.174183) (xy 154.792222 -267.125548)
			(xy 154.772299 -267.073457) (xy 154.760173 -267.01902) (xy 154.756102 -266.963398) (xy 154.570684 -266.963398)
			(xy 154.570684 -268.339062) (xy 156.865826 -268.339062) (xy 156.869897 -268.28344) (xy 156.882023 -268.229003)
			(xy 156.901946 -268.176912) (xy 156.929242 -268.128277) (xy 156.963328 -268.084134) (xy 157.003477 -268.045425)
			(xy 157.048835 -268.012974) (xy 157.098435 -267.987473) (xy 157.151219 -267.969466) (xy 157.206062 -267.959336)
			(xy 157.261796 -267.957299) (xy 157.317233 -267.963399) (xy 157.37119 -267.977505) (xy 157.422519 -267.999317)
			(xy 157.470125 -268.028371) (xy 157.512993 -268.064046) (xy 157.55021 -268.105583) (xy 157.580983 -268.152096)
			(xy 157.604655 -268.202593) (xy 157.620723 -268.256) (xy 157.628843 -268.311176) (xy 157.629352 -268.339062)
			(xy 157.628843 -268.366948) (xy 157.620723 -268.422124) (xy 157.604655 -268.475531) (xy 157.580983 -268.526028)
			(xy 157.55021 -268.572541) (xy 157.512993 -268.614078) (xy 157.470125 -268.649753) (xy 157.422519 -268.678807)
			(xy 157.37119 -268.700619) (xy 157.317233 -268.714725) (xy 157.261796 -268.720825) (xy 157.206062 -268.718788)
			(xy 157.151219 -268.708658) (xy 157.098435 -268.690651) (xy 157.048835 -268.66515) (xy 157.003477 -268.632699)
			(xy 156.963328 -268.59399) (xy 156.929242 -268.549847) (xy 156.901946 -268.501212) (xy 156.882023 -268.449121)
			(xy 156.869897 -268.394684) (xy 156.865826 -268.339062) (xy 154.570684 -268.339062) (xy 154.570684 -268.878558)
			(xy 154.572028 -268.88802) (xy 154.58077 -268.905) (xy 154.587702 -268.911578) (xy 154.59202 -268.915134)
			(xy 154.66695 -268.963902) (xy 154.672014 -268.966693) (xy 154.683043 -268.970157) (xy 154.688794 -268.97076)
			(xy 154.70124 -268.971776) (xy 154.713178 -268.966442) (xy 154.737639 -268.956091) (xy 154.788708 -268.941495)
			(xy 154.841307 -268.934123) (xy 154.867864 -268.933676) (xy 154.89512 -268.934136) (xy 154.949077 -268.94189)
			(xy 155.001381 -268.957243) (xy 155.050968 -268.979885) (xy 155.096828 -269.009353) (xy 155.138026 -269.045048)
			(xy 155.173726 -269.086243) (xy 155.203198 -269.1321) (xy 155.225844 -269.181685) (xy 155.241203 -269.233988)
			(xy 155.248961 -269.287944) (xy 155.248961 -269.342456) (xy 155.241203 -269.396412) (xy 155.225844 -269.448715)
			(xy 155.203198 -269.4983) (xy 155.173726 -269.544157) (xy 155.138026 -269.585352) (xy 155.096828 -269.621047)
			(xy 155.050968 -269.650515) (xy 155.001381 -269.673157) (xy 154.949077 -269.68851) (xy 154.89512 -269.696264)
			(xy 154.867864 -269.696692) (xy 154.841308 -269.696231) (xy 154.78871 -269.688861) (xy 154.737642 -269.674267)
			(xy 154.713178 -269.663926) (xy 154.71267 -269.663672) (xy 154.706869 -269.661328) (xy 154.694533 -269.65926)
			(xy 154.688286 -269.659608) (xy 154.67584 -269.660624) (xy 154.591766 -269.715234) (xy 154.587118 -269.718735)
			(xy 154.579419 -269.727457) (xy 154.576526 -269.732506) (xy 154.573478 -269.738094) (xy 154.570684 -269.749016)
			(xy 154.570684 -269.987014) (xy 155.308552 -269.987014) (xy 155.312623 -269.931392) (xy 155.324749 -269.876955)
			(xy 155.344672 -269.824864) (xy 155.371968 -269.776229) (xy 155.406054 -269.732086) (xy 155.446203 -269.693377)
			(xy 155.491561 -269.660926) (xy 155.541161 -269.635425) (xy 155.593945 -269.617418) (xy 155.648788 -269.607288)
			(xy 155.704522 -269.605251) (xy 155.759959 -269.611351) (xy 155.813916 -269.625457) (xy 155.865245 -269.647269)
			(xy 155.912851 -269.676323) (xy 155.955719 -269.711998) (xy 155.992936 -269.753535) (xy 156.023709 -269.800048)
			(xy 156.047381 -269.850545) (xy 156.063449 -269.903952) (xy 156.071569 -269.959128) (xy 156.072078 -269.987014)
			(xy 156.071569 -270.0149) (xy 156.063449 -270.070076) (xy 156.047381 -270.123483) (xy 156.023709 -270.17398)
			(xy 155.992936 -270.220493) (xy 155.955719 -270.26203) (xy 155.912851 -270.297705) (xy 155.865245 -270.326759)
			(xy 155.813916 -270.348571) (xy 155.759959 -270.362677) (xy 155.704522 -270.368777) (xy 155.648788 -270.36674)
			(xy 155.593945 -270.35661) (xy 155.541161 -270.338603) (xy 155.491561 -270.313102) (xy 155.446203 -270.280651)
			(xy 155.406054 -270.241942) (xy 155.371968 -270.197799) (xy 155.344672 -270.149164) (xy 155.324749 -270.097073)
			(xy 155.312623 -270.042636) (xy 155.308552 -269.987014) (xy 154.570684 -269.987014) (xy 154.570684 -272.32737)
			(xy 154.573732 -272.339816) (xy 154.58059 -272.355056) (xy 154.58059 -272.355564) (xy 154.587956 -272.371566)
			(xy 154.59583 -272.378424) (xy 154.614339 -272.39565) (xy 154.646425 -272.434727) (xy 154.67219 -272.478231)
			(xy 154.691035 -272.525149) (xy 154.70252 -272.574389) (xy 154.706378 -272.624803) (xy 154.706378 -272.624804)
			(xy 155.01926 -272.624804) (xy 155.02322 -272.57575) (xy 155.034997 -272.527966) (xy 155.054288 -272.48269)
			(xy 155.080591 -272.441094) (xy 155.113226 -272.404257) (xy 155.151347 -272.373132) (xy 155.193968 -272.348525)
			(xy 155.239984 -272.331073) (xy 155.288203 -272.321229) (xy 155.337378 -272.319248) (xy 155.386233 -272.32518)
			(xy 155.433504 -272.338872) (xy 155.477966 -272.35997) (xy 155.518469 -272.387926) (xy 155.553962 -272.422018)
			(xy 155.583527 -272.461362) (xy 155.606398 -272.504939) (xy 155.621982 -272.55162) (xy 155.629877 -272.600197)
			(xy 155.630372 -272.624804) (xy 155.96922 -272.624804) (xy 155.97318 -272.57575) (xy 155.984957 -272.527966)
			(xy 156.004248 -272.48269) (xy 156.030551 -272.441094) (xy 156.063186 -272.404257) (xy 156.101307 -272.373132)
			(xy 156.143928 -272.348525) (xy 156.189944 -272.331073) (xy 156.238163 -272.321229) (xy 156.287338 -272.319248)
			(xy 156.336193 -272.32518) (xy 156.383464 -272.338872) (xy 156.427926 -272.35997) (xy 156.468429 -272.387926)
			(xy 156.503922 -272.422018) (xy 156.533487 -272.461362) (xy 156.556358 -272.504939) (xy 156.571942 -272.55162)
			(xy 156.579837 -272.600197) (xy 156.580332 -272.624804) (xy 156.91918 -272.624804) (xy 156.92314 -272.57575)
			(xy 156.934917 -272.527966) (xy 156.954208 -272.48269) (xy 156.980511 -272.441094) (xy 157.013146 -272.404257)
			(xy 157.051267 -272.373132) (xy 157.093888 -272.348525) (xy 157.139904 -272.331073) (xy 157.188123 -272.321229)
			(xy 157.237298 -272.319248) (xy 157.286153 -272.32518) (xy 157.333424 -272.338872) (xy 157.377886 -272.35997)
			(xy 157.418389 -272.387926) (xy 157.453882 -272.422018) (xy 157.483447 -272.461362) (xy 157.506318 -272.504939)
			(xy 157.521902 -272.55162) (xy 157.529797 -272.600197) (xy 157.530292 -272.624804) (xy 157.529797 -272.649411)
			(xy 157.521902 -272.697988) (xy 157.506318 -272.744669) (xy 157.483447 -272.788246) (xy 157.453882 -272.82759)
			(xy 157.418389 -272.861682) (xy 157.377886 -272.889638) (xy 157.333424 -272.910736) (xy 157.286153 -272.924428)
			(xy 157.237298 -272.93036) (xy 157.188123 -272.928379) (xy 157.139904 -272.918535) (xy 157.093888 -272.901083)
			(xy 157.051267 -272.876476) (xy 157.013146 -272.845351) (xy 156.980511 -272.808514) (xy 156.954208 -272.766918)
			(xy 156.934917 -272.721642) (xy 156.92314 -272.673858) (xy 156.91918 -272.624804) (xy 156.580332 -272.624804)
			(xy 156.579837 -272.649411) (xy 156.571942 -272.697988) (xy 156.556358 -272.744669) (xy 156.533487 -272.788246)
			(xy 156.503922 -272.82759) (xy 156.468429 -272.861682) (xy 156.427926 -272.889638) (xy 156.383464 -272.910736)
			(xy 156.336193 -272.924428) (xy 156.287338 -272.93036) (xy 156.238163 -272.928379) (xy 156.189944 -272.918535)
			(xy 156.143928 -272.901083) (xy 156.101307 -272.876476) (xy 156.063186 -272.845351) (xy 156.030551 -272.808514)
			(xy 156.004248 -272.766918) (xy 155.984957 -272.721642) (xy 155.97318 -272.673858) (xy 155.96922 -272.624804)
			(xy 155.630372 -272.624804) (xy 155.629877 -272.649411) (xy 155.621982 -272.697988) (xy 155.606398 -272.744669)
			(xy 155.583527 -272.788246) (xy 155.553962 -272.82759) (xy 155.518469 -272.861682) (xy 155.477966 -272.889638)
			(xy 155.433504 -272.910736) (xy 155.386233 -272.924428) (xy 155.337378 -272.93036) (xy 155.288203 -272.928379)
			(xy 155.239984 -272.918535) (xy 155.193968 -272.901083) (xy 155.151347 -272.876476) (xy 155.113226 -272.845351)
			(xy 155.080591 -272.808514) (xy 155.054288 -272.766918) (xy 155.034997 -272.721642) (xy 155.02322 -272.673858)
			(xy 155.01926 -272.624804) (xy 154.706378 -272.624804) (xy 154.702519 -272.675217) (xy 154.691033 -272.724456)
			(xy 154.672188 -272.771374) (xy 154.646422 -272.814878) (xy 154.614336 -272.853953) (xy 154.59583 -272.871184)
			(xy 154.587956 -272.878042) (xy 154.58059 -272.894044) (xy 154.58059 -272.894552) (xy 154.573732 -272.909792)
			(xy 154.570684 -272.922238) (xy 154.570684 -273.28876) (xy 154.571952 -273.297539) (xy 154.579617 -273.313519)
			(xy 154.58567 -273.320002) (xy 154.60408 -273.33579) (xy 154.636527 -273.371836) (xy 154.663365 -273.412232)
			(xy 154.684019 -273.456113) (xy 154.698046 -273.502539) (xy 154.705145 -273.550515) (xy 154.705558 -273.574764)
			(xy 155.01926 -273.574764) (xy 155.02322 -273.52571) (xy 155.034997 -273.477926) (xy 155.054288 -273.43265)
			(xy 155.080591 -273.391054) (xy 155.113226 -273.354217) (xy 155.151347 -273.323092) (xy 155.193968 -273.298485)
			(xy 155.239984 -273.281033) (xy 155.288203 -273.271189) (xy 155.337378 -273.269208) (xy 155.386233 -273.27514)
			(xy 155.433504 -273.288832) (xy 155.477966 -273.30993) (xy 155.518469 -273.337886) (xy 155.553962 -273.371978)
			(xy 155.583527 -273.411322) (xy 155.606398 -273.454899) (xy 155.621982 -273.50158) (xy 155.629877 -273.550157)
			(xy 155.630372 -273.574764) (xy 155.96922 -273.574764) (xy 155.97318 -273.52571) (xy 155.984957 -273.477926)
			(xy 156.004248 -273.43265) (xy 156.030551 -273.391054) (xy 156.063186 -273.354217) (xy 156.101307 -273.323092)
			(xy 156.143928 -273.298485) (xy 156.189944 -273.281033) (xy 156.238163 -273.271189) (xy 156.287338 -273.269208)
			(xy 156.336193 -273.27514) (xy 156.383464 -273.288832) (xy 156.427926 -273.30993) (xy 156.468429 -273.337886)
			(xy 156.503922 -273.371978) (xy 156.533487 -273.411322) (xy 156.556358 -273.454899) (xy 156.571942 -273.50158)
			(xy 156.579837 -273.550157) (xy 156.580332 -273.574764) (xy 156.91918 -273.574764) (xy 156.92314 -273.52571)
			(xy 156.934917 -273.477926) (xy 156.954208 -273.43265) (xy 156.980511 -273.391054) (xy 157.013146 -273.354217)
			(xy 157.051267 -273.323092) (xy 157.093888 -273.298485) (xy 157.139904 -273.281033) (xy 157.188123 -273.271189)
			(xy 157.237298 -273.269208) (xy 157.286153 -273.27514) (xy 157.333424 -273.288832) (xy 157.377886 -273.30993)
			(xy 157.418389 -273.337886) (xy 157.453882 -273.371978) (xy 157.483447 -273.411322) (xy 157.506318 -273.454899)
			(xy 157.521902 -273.50158) (xy 157.529797 -273.550157) (xy 157.530292 -273.574764) (xy 157.529797 -273.599371)
			(xy 157.521902 -273.647948) (xy 157.506318 -273.694629) (xy 157.483447 -273.738206) (xy 157.453882 -273.77755)
			(xy 157.418389 -273.811642) (xy 157.377886 -273.839598) (xy 157.333424 -273.860696) (xy 157.286153 -273.874388)
			(xy 157.237298 -273.88032) (xy 157.188123 -273.878339) (xy 157.139904 -273.868495) (xy 157.093888 -273.851043)
			(xy 157.051267 -273.826436) (xy 157.013146 -273.795311) (xy 156.980511 -273.758474) (xy 156.954208 -273.716878)
			(xy 156.934917 -273.671602) (xy 156.92314 -273.623818) (xy 156.91918 -273.574764) (xy 156.580332 -273.574764)
			(xy 156.579837 -273.599371) (xy 156.571942 -273.647948) (xy 156.556358 -273.694629) (xy 156.533487 -273.738206)
			(xy 156.503922 -273.77755) (xy 156.468429 -273.811642) (xy 156.427926 -273.839598) (xy 156.383464 -273.860696)
			(xy 156.336193 -273.874388) (xy 156.287338 -273.88032) (xy 156.238163 -273.878339) (xy 156.189944 -273.868495)
			(xy 156.143928 -273.851043) (xy 156.101307 -273.826436) (xy 156.063186 -273.795311) (xy 156.030551 -273.758474)
			(xy 156.004248 -273.716878) (xy 155.984957 -273.671602) (xy 155.97318 -273.623818) (xy 155.96922 -273.574764)
			(xy 155.630372 -273.574764) (xy 155.629877 -273.599371) (xy 155.621982 -273.647948) (xy 155.606398 -273.694629)
			(xy 155.583527 -273.738206) (xy 155.553962 -273.77755) (xy 155.518469 -273.811642) (xy 155.477966 -273.839598)
			(xy 155.433504 -273.860696) (xy 155.386233 -273.874388) (xy 155.337378 -273.88032) (xy 155.288203 -273.878339)
			(xy 155.239984 -273.868495) (xy 155.193968 -273.851043) (xy 155.151347 -273.826436) (xy 155.113226 -273.795311)
			(xy 155.080591 -273.758474) (xy 155.054288 -273.716878) (xy 155.034997 -273.671602) (xy 155.02322 -273.623818)
			(xy 155.01926 -273.574764) (xy 154.705558 -273.574764) (xy 154.705116 -273.598691) (xy 154.698182 -273.646041)
			(xy 154.684496 -273.691897) (xy 154.664345 -273.735303) (xy 154.638149 -273.775351) (xy 154.606455 -273.811206)
			(xy 154.588464 -273.826986) (xy 154.583892 -273.83105) (xy 154.577542 -273.839432) (xy 154.575002 -273.844766)
			(xy 154.571954 -273.85391) (xy 154.570684 -273.861022) (xy 154.570684 -274.227544) (xy 154.573732 -274.23999)
			(xy 154.58059 -274.25523) (xy 154.58059 -274.255738) (xy 154.587956 -274.27174) (xy 154.59583 -274.278598)
			(xy 154.614342 -274.295824) (xy 154.646431 -274.334901) (xy 154.6722 -274.378406) (xy 154.691048 -274.425327)
			(xy 154.702537 -274.474569) (xy 154.706397 -274.524978) (xy 155.01926 -274.524978) (xy 155.02322 -274.475924)
			(xy 155.034997 -274.42814) (xy 155.054288 -274.382864) (xy 155.080591 -274.341268) (xy 155.113226 -274.304431)
			(xy 155.151347 -274.273306) (xy 155.193968 -274.248699) (xy 155.239984 -274.231247) (xy 155.288203 -274.221403)
			(xy 155.337378 -274.219422) (xy 155.386233 -274.225354) (xy 155.433504 -274.239046) (xy 155.477966 -274.260144)
			(xy 155.518469 -274.2881) (xy 155.553962 -274.322192) (xy 155.583527 -274.361536) (xy 155.606398 -274.405113)
			(xy 155.621982 -274.451794) (xy 155.629877 -274.500371) (xy 155.630372 -274.524978) (xy 155.96922 -274.524978)
			(xy 155.97318 -274.475924) (xy 155.984957 -274.42814) (xy 156.004248 -274.382864) (xy 156.030551 -274.341268)
			(xy 156.063186 -274.304431) (xy 156.101307 -274.273306) (xy 156.143928 -274.248699) (xy 156.189944 -274.231247)
			(xy 156.238163 -274.221403) (xy 156.287338 -274.219422) (xy 156.336193 -274.225354) (xy 156.383464 -274.239046)
			(xy 156.427926 -274.260144) (xy 156.468429 -274.2881) (xy 156.503922 -274.322192) (xy 156.533487 -274.361536)
			(xy 156.556358 -274.405113) (xy 156.571942 -274.451794) (xy 156.579837 -274.500371) (xy 156.580332 -274.524978)
			(xy 156.91918 -274.524978) (xy 156.92314 -274.475924) (xy 156.934917 -274.42814) (xy 156.954208 -274.382864)
			(xy 156.980511 -274.341268) (xy 157.013146 -274.304431) (xy 157.051267 -274.273306) (xy 157.093888 -274.248699)
			(xy 157.139904 -274.231247) (xy 157.188123 -274.221403) (xy 157.237298 -274.219422) (xy 157.286153 -274.225354)
			(xy 157.333424 -274.239046) (xy 157.377886 -274.260144) (xy 157.418389 -274.2881) (xy 157.453882 -274.322192)
			(xy 157.483447 -274.361536) (xy 157.506318 -274.405113) (xy 157.521902 -274.451794) (xy 157.529797 -274.500371)
			(xy 157.530292 -274.524978) (xy 157.529797 -274.549585) (xy 157.521902 -274.598162) (xy 157.506318 -274.644843)
			(xy 157.483447 -274.68842) (xy 157.453882 -274.727764) (xy 157.418389 -274.761856) (xy 157.377886 -274.789812)
			(xy 157.333424 -274.81091) (xy 157.286153 -274.824602) (xy 157.237298 -274.830534) (xy 157.188123 -274.828553)
			(xy 157.139904 -274.818709) (xy 157.093888 -274.801257) (xy 157.051267 -274.77665) (xy 157.013146 -274.745525)
			(xy 156.980511 -274.708688) (xy 156.954208 -274.667092) (xy 156.934917 -274.621816) (xy 156.92314 -274.574032)
			(xy 156.91918 -274.524978) (xy 156.580332 -274.524978) (xy 156.579837 -274.549585) (xy 156.571942 -274.598162)
			(xy 156.556358 -274.644843) (xy 156.533487 -274.68842) (xy 156.503922 -274.727764) (xy 156.468429 -274.761856)
			(xy 156.427926 -274.789812) (xy 156.383464 -274.81091) (xy 156.336193 -274.824602) (xy 156.287338 -274.830534)
			(xy 156.238163 -274.828553) (xy 156.189944 -274.818709) (xy 156.143928 -274.801257) (xy 156.101307 -274.77665)
			(xy 156.063186 -274.745525) (xy 156.030551 -274.708688) (xy 156.004248 -274.667092) (xy 155.984957 -274.621816)
			(xy 155.97318 -274.574032) (xy 155.96922 -274.524978) (xy 155.630372 -274.524978) (xy 155.629877 -274.549585)
			(xy 155.621982 -274.598162) (xy 155.606398 -274.644843) (xy 155.583527 -274.68842) (xy 155.553962 -274.727764)
			(xy 155.518469 -274.761856) (xy 155.477966 -274.789812) (xy 155.433504 -274.81091) (xy 155.386233 -274.824602)
			(xy 155.337378 -274.830534) (xy 155.288203 -274.828553) (xy 155.239984 -274.818709) (xy 155.193968 -274.801257)
			(xy 155.151347 -274.77665) (xy 155.113226 -274.745525) (xy 155.080591 -274.708688) (xy 155.054288 -274.667092)
			(xy 155.034997 -274.621816) (xy 155.02322 -274.574032) (xy 155.01926 -274.524978) (xy 154.706397 -274.524978)
			(xy 154.706398 -274.524985) (xy 154.702541 -274.575402) (xy 154.691057 -274.624645) (xy 154.672213 -274.671567)
			(xy 154.646448 -274.715075) (xy 154.614362 -274.754155) (xy 154.59583 -274.771358) (xy 154.587956 -274.778216)
			(xy 154.58059 -274.794218) (xy 154.58059 -274.794726) (xy 154.573732 -274.809966) (xy 154.570684 -274.822412)
			(xy 154.570684 -275.177504) (xy 154.573732 -275.18995) (xy 154.58059 -275.20519) (xy 154.58059 -275.205698)
			(xy 154.587956 -275.2217) (xy 154.59583 -275.228558) (xy 154.614337 -275.245784) (xy 154.646417 -275.28486)
			(xy 154.672177 -275.328362) (xy 154.691017 -275.375278) (xy 154.702498 -275.424515) (xy 154.706352 -275.474925)
			(xy 154.706351 -275.474938) (xy 155.01926 -275.474938) (xy 155.02322 -275.425884) (xy 155.034997 -275.3781)
			(xy 155.054288 -275.332824) (xy 155.080591 -275.291228) (xy 155.113226 -275.254391) (xy 155.151347 -275.223266)
			(xy 155.193968 -275.198659) (xy 155.239984 -275.181207) (xy 155.288203 -275.171363) (xy 155.337378 -275.169382)
			(xy 155.386233 -275.175314) (xy 155.433504 -275.189006) (xy 155.477966 -275.210104) (xy 155.518469 -275.23806)
			(xy 155.553962 -275.272152) (xy 155.583527 -275.311496) (xy 155.606398 -275.355073) (xy 155.621982 -275.401754)
			(xy 155.629877 -275.450331) (xy 155.630372 -275.474938) (xy 155.96922 -275.474938) (xy 155.97318 -275.425884)
			(xy 155.984957 -275.3781) (xy 156.004248 -275.332824) (xy 156.030551 -275.291228) (xy 156.063186 -275.254391)
			(xy 156.101307 -275.223266) (xy 156.143928 -275.198659) (xy 156.189944 -275.181207) (xy 156.238163 -275.171363)
			(xy 156.287338 -275.169382) (xy 156.336193 -275.175314) (xy 156.383464 -275.189006) (xy 156.427926 -275.210104)
			(xy 156.468429 -275.23806) (xy 156.503922 -275.272152) (xy 156.533487 -275.311496) (xy 156.556358 -275.355073)
			(xy 156.571942 -275.401754) (xy 156.579837 -275.450331) (xy 156.580332 -275.474938) (xy 156.91918 -275.474938)
			(xy 156.92314 -275.425884) (xy 156.934917 -275.3781) (xy 156.954208 -275.332824) (xy 156.980511 -275.291228)
			(xy 157.013146 -275.254391) (xy 157.051267 -275.223266) (xy 157.093888 -275.198659) (xy 157.139904 -275.181207)
			(xy 157.188123 -275.171363) (xy 157.237298 -275.169382) (xy 157.286153 -275.175314) (xy 157.333424 -275.189006)
			(xy 157.377886 -275.210104) (xy 157.418389 -275.23806) (xy 157.453882 -275.272152) (xy 157.483447 -275.311496)
			(xy 157.506318 -275.355073) (xy 157.521902 -275.401754) (xy 157.529797 -275.450331) (xy 157.530292 -275.474938)
			(xy 157.529797 -275.499545) (xy 157.521902 -275.548122) (xy 157.506318 -275.594803) (xy 157.483447 -275.63838)
			(xy 157.453882 -275.677724) (xy 157.418389 -275.711816) (xy 157.377886 -275.739772) (xy 157.333424 -275.76087)
			(xy 157.286153 -275.774562) (xy 157.237298 -275.780494) (xy 157.188123 -275.778513) (xy 157.139904 -275.768669)
			(xy 157.093888 -275.751217) (xy 157.051267 -275.72661) (xy 157.013146 -275.695485) (xy 156.980511 -275.658648)
			(xy 156.954208 -275.617052) (xy 156.934917 -275.571776) (xy 156.92314 -275.523992) (xy 156.91918 -275.474938)
			(xy 156.580332 -275.474938) (xy 156.579837 -275.499545) (xy 156.571942 -275.548122) (xy 156.556358 -275.594803)
			(xy 156.533487 -275.63838) (xy 156.503922 -275.677724) (xy 156.468429 -275.711816) (xy 156.427926 -275.739772)
			(xy 156.383464 -275.76087) (xy 156.336193 -275.774562) (xy 156.287338 -275.780494) (xy 156.238163 -275.778513)
			(xy 156.189944 -275.768669) (xy 156.143928 -275.751217) (xy 156.101307 -275.72661) (xy 156.063186 -275.695485)
			(xy 156.030551 -275.658648) (xy 156.004248 -275.617052) (xy 155.984957 -275.571776) (xy 155.97318 -275.523992)
			(xy 155.96922 -275.474938) (xy 155.630372 -275.474938) (xy 155.629877 -275.499545) (xy 155.621982 -275.548122)
			(xy 155.606398 -275.594803) (xy 155.583527 -275.63838) (xy 155.553962 -275.677724) (xy 155.518469 -275.711816)
			(xy 155.477966 -275.739772) (xy 155.433504 -275.76087) (xy 155.386233 -275.774562) (xy 155.337378 -275.780494)
			(xy 155.288203 -275.778513) (xy 155.239984 -275.768669) (xy 155.193968 -275.751217) (xy 155.151347 -275.72661)
			(xy 155.113226 -275.695485) (xy 155.080591 -275.658648) (xy 155.054288 -275.617052) (xy 155.034997 -275.571776)
			(xy 155.02322 -275.523992) (xy 155.01926 -275.474938) (xy 154.706351 -275.474938) (xy 154.70249 -275.525335)
			(xy 154.691002 -275.57457) (xy 154.672155 -275.621483) (xy 154.646388 -275.664982) (xy 154.614302 -275.704052)
			(xy 154.59583 -275.721318) (xy 154.587956 -275.728176) (xy 154.58059 -275.744178) (xy 154.58059 -275.744686)
			(xy 154.573732 -275.759926) (xy 154.570684 -275.772372) (xy 154.570684 -276.127464) (xy 154.573732 -276.13991)
			(xy 154.58059 -276.15515) (xy 154.58059 -276.155658) (xy 154.587956 -276.17166) (xy 154.59583 -276.178518)
			(xy 154.61434 -276.195744) (xy 154.646426 -276.234821) (xy 154.672192 -276.278325) (xy 154.691038 -276.325244)
			(xy 154.702524 -276.374484) (xy 154.706382 -276.424898) (xy 155.01926 -276.424898) (xy 155.02322 -276.375844)
			(xy 155.034997 -276.32806) (xy 155.054288 -276.282784) (xy 155.080591 -276.241188) (xy 155.113226 -276.204351)
			(xy 155.151347 -276.173226) (xy 155.193968 -276.148619) (xy 155.239984 -276.131167) (xy 155.288203 -276.121323)
			(xy 155.337378 -276.119342) (xy 155.386233 -276.125274) (xy 155.433504 -276.138966) (xy 155.477966 -276.160064)
			(xy 155.518469 -276.18802) (xy 155.553962 -276.222112) (xy 155.583527 -276.261456) (xy 155.606398 -276.305033)
			(xy 155.621982 -276.351714) (xy 155.629877 -276.400291) (xy 155.630372 -276.424898) (xy 155.96922 -276.424898)
			(xy 155.97318 -276.375844) (xy 155.984957 -276.32806) (xy 156.004248 -276.282784) (xy 156.030551 -276.241188)
			(xy 156.063186 -276.204351) (xy 156.101307 -276.173226) (xy 156.143928 -276.148619) (xy 156.189944 -276.131167)
			(xy 156.238163 -276.121323) (xy 156.287338 -276.119342) (xy 156.336193 -276.125274) (xy 156.383464 -276.138966)
			(xy 156.427926 -276.160064) (xy 156.468429 -276.18802) (xy 156.503922 -276.222112) (xy 156.533487 -276.261456)
			(xy 156.556358 -276.305033) (xy 156.571942 -276.351714) (xy 156.579837 -276.400291) (xy 156.580332 -276.424898)
			(xy 156.91918 -276.424898) (xy 156.92314 -276.375844) (xy 156.934917 -276.32806) (xy 156.954208 -276.282784)
			(xy 156.980511 -276.241188) (xy 157.013146 -276.204351) (xy 157.051267 -276.173226) (xy 157.093888 -276.148619)
			(xy 157.139904 -276.131167) (xy 157.188123 -276.121323) (xy 157.237298 -276.119342) (xy 157.286153 -276.125274)
			(xy 157.333424 -276.138966) (xy 157.377886 -276.160064) (xy 157.418389 -276.18802) (xy 157.453882 -276.222112)
			(xy 157.483447 -276.261456) (xy 157.506318 -276.305033) (xy 157.521902 -276.351714) (xy 157.529797 -276.400291)
			(xy 157.530292 -276.424898) (xy 157.529797 -276.449505) (xy 157.521902 -276.498082) (xy 157.506318 -276.544763)
			(xy 157.483447 -276.58834) (xy 157.453882 -276.627684) (xy 157.418389 -276.661776) (xy 157.377886 -276.689732)
			(xy 157.333424 -276.71083) (xy 157.286153 -276.724522) (xy 157.237298 -276.730454) (xy 157.188123 -276.728473)
			(xy 157.139904 -276.718629) (xy 157.093888 -276.701177) (xy 157.051267 -276.67657) (xy 157.013146 -276.645445)
			(xy 156.980511 -276.608608) (xy 156.954208 -276.567012) (xy 156.934917 -276.521736) (xy 156.92314 -276.473952)
			(xy 156.91918 -276.424898) (xy 156.580332 -276.424898) (xy 156.579837 -276.449505) (xy 156.571942 -276.498082)
			(xy 156.556358 -276.544763) (xy 156.533487 -276.58834) (xy 156.503922 -276.627684) (xy 156.468429 -276.661776)
			(xy 156.427926 -276.689732) (xy 156.383464 -276.71083) (xy 156.336193 -276.724522) (xy 156.287338 -276.730454)
			(xy 156.238163 -276.728473) (xy 156.189944 -276.718629) (xy 156.143928 -276.701177) (xy 156.101307 -276.67657)
			(xy 156.063186 -276.645445) (xy 156.030551 -276.608608) (xy 156.004248 -276.567012) (xy 155.984957 -276.521736)
			(xy 155.97318 -276.473952) (xy 155.96922 -276.424898) (xy 155.630372 -276.424898) (xy 155.629877 -276.449505)
			(xy 155.621982 -276.498082) (xy 155.606398 -276.544763) (xy 155.583527 -276.58834) (xy 155.553962 -276.627684)
			(xy 155.518469 -276.661776) (xy 155.477966 -276.689732) (xy 155.433504 -276.71083) (xy 155.386233 -276.724522)
			(xy 155.337378 -276.730454) (xy 155.288203 -276.728473) (xy 155.239984 -276.718629) (xy 155.193968 -276.701177)
			(xy 155.151347 -276.67657) (xy 155.113226 -276.645445) (xy 155.080591 -276.608608) (xy 155.054288 -276.567012)
			(xy 155.034997 -276.521736) (xy 155.02322 -276.473952) (xy 155.01926 -276.424898) (xy 154.706382 -276.424898)
			(xy 154.706382 -276.424899) (xy 154.702524 -276.475313) (xy 154.691038 -276.524553) (xy 154.672193 -276.571472)
			(xy 154.646428 -276.614977) (xy 154.614342 -276.654054) (xy 154.59583 -276.671278) (xy 154.587956 -276.678136)
			(xy 154.58059 -276.694138) (xy 154.58059 -276.694646) (xy 154.573732 -276.709886) (xy 154.570684 -276.722332)
			(xy 154.570684 -277.077424) (xy 154.573732 -277.08987) (xy 154.58059 -277.10511) (xy 154.58059 -277.105618)
			(xy 154.587956 -277.12162) (xy 154.59583 -277.128478) (xy 154.614343 -277.145704) (xy 154.646436 -277.184782)
			(xy 154.672208 -277.228288) (xy 154.691059 -277.275209) (xy 154.702549 -277.324453) (xy 154.706412 -277.374858)
			(xy 155.01926 -277.374858) (xy 155.02322 -277.325804) (xy 155.034997 -277.27802) (xy 155.054288 -277.232744)
			(xy 155.080591 -277.191148) (xy 155.113226 -277.154311) (xy 155.151347 -277.123186) (xy 155.193968 -277.098579)
			(xy 155.239984 -277.081127) (xy 155.288203 -277.071283) (xy 155.337378 -277.069302) (xy 155.386233 -277.075234)
			(xy 155.433504 -277.088926) (xy 155.477966 -277.110024) (xy 155.518469 -277.13798) (xy 155.553962 -277.172072)
			(xy 155.583527 -277.211416) (xy 155.606398 -277.254993) (xy 155.621982 -277.301674) (xy 155.629877 -277.350251)
			(xy 155.630372 -277.374858) (xy 155.96922 -277.374858) (xy 155.97318 -277.325804) (xy 155.984957 -277.27802)
			(xy 156.004248 -277.232744) (xy 156.030551 -277.191148) (xy 156.063186 -277.154311) (xy 156.101307 -277.123186)
			(xy 156.143928 -277.098579) (xy 156.189944 -277.081127) (xy 156.238163 -277.071283) (xy 156.287338 -277.069302)
			(xy 156.336193 -277.075234) (xy 156.383464 -277.088926) (xy 156.427926 -277.110024) (xy 156.468429 -277.13798)
			(xy 156.503922 -277.172072) (xy 156.533487 -277.211416) (xy 156.556358 -277.254993) (xy 156.571942 -277.301674)
			(xy 156.579837 -277.350251) (xy 156.580332 -277.374858) (xy 156.91918 -277.374858) (xy 156.92314 -277.325804)
			(xy 156.934917 -277.27802) (xy 156.954208 -277.232744) (xy 156.980511 -277.191148) (xy 157.013146 -277.154311)
			(xy 157.051267 -277.123186) (xy 157.093888 -277.098579) (xy 157.139904 -277.081127) (xy 157.188123 -277.071283)
			(xy 157.237298 -277.069302) (xy 157.286153 -277.075234) (xy 157.333424 -277.088926) (xy 157.377886 -277.110024)
			(xy 157.418389 -277.13798) (xy 157.453882 -277.172072) (xy 157.483447 -277.211416) (xy 157.506318 -277.254993)
			(xy 157.521902 -277.301674) (xy 157.529797 -277.350251) (xy 157.530292 -277.374858) (xy 157.529797 -277.399465)
			(xy 157.521902 -277.448042) (xy 157.506318 -277.494723) (xy 157.483447 -277.5383) (xy 157.453882 -277.577644)
			(xy 157.418389 -277.611736) (xy 157.377886 -277.639692) (xy 157.333424 -277.66079) (xy 157.286153 -277.674482)
			(xy 157.237298 -277.680414) (xy 157.188123 -277.678433) (xy 157.139904 -277.668589) (xy 157.093888 -277.651137)
			(xy 157.051267 -277.62653) (xy 157.013146 -277.595405) (xy 156.980511 -277.558568) (xy 156.954208 -277.516972)
			(xy 156.934917 -277.471696) (xy 156.92314 -277.423912) (xy 156.91918 -277.374858) (xy 156.580332 -277.374858)
			(xy 156.579837 -277.399465) (xy 156.571942 -277.448042) (xy 156.556358 -277.494723) (xy 156.533487 -277.5383)
			(xy 156.503922 -277.577644) (xy 156.468429 -277.611736) (xy 156.427926 -277.639692) (xy 156.383464 -277.66079)
			(xy 156.336193 -277.674482) (xy 156.287338 -277.680414) (xy 156.238163 -277.678433) (xy 156.189944 -277.668589)
			(xy 156.143928 -277.651137) (xy 156.101307 -277.62653) (xy 156.063186 -277.595405) (xy 156.030551 -277.558568)
			(xy 156.004248 -277.516972) (xy 155.984957 -277.471696) (xy 155.97318 -277.423912) (xy 155.96922 -277.374858)
			(xy 155.630372 -277.374858) (xy 155.629877 -277.399465) (xy 155.621982 -277.448042) (xy 155.606398 -277.494723)
			(xy 155.583527 -277.5383) (xy 155.553962 -277.577644) (xy 155.518469 -277.611736) (xy 155.477966 -277.639692)
			(xy 155.433504 -277.66079) (xy 155.386233 -277.674482) (xy 155.337378 -277.680414) (xy 155.288203 -277.678433)
			(xy 155.239984 -277.668589) (xy 155.193968 -277.651137) (xy 155.151347 -277.62653) (xy 155.113226 -277.595405)
			(xy 155.080591 -277.558568) (xy 155.054288 -277.516972) (xy 155.034997 -277.471696) (xy 155.02322 -277.423912)
			(xy 155.01926 -277.374858) (xy 154.706412 -277.374858) (xy 154.706413 -277.374872) (xy 154.702558 -277.425291)
			(xy 154.691075 -277.474537) (xy 154.672232 -277.521462) (xy 154.646468 -277.564972) (xy 154.614382 -277.604055)
			(xy 154.59583 -277.621238) (xy 154.587956 -277.628096) (xy 154.58059 -277.644098) (xy 154.58059 -277.644606)
			(xy 154.573732 -277.659846) (xy 154.570684 -277.672292) (xy 154.570684 -278.027384) (xy 154.573732 -278.03983)
			(xy 154.58059 -278.05507) (xy 154.58059 -278.055578) (xy 154.587956 -278.07158) (xy 154.59583 -278.078438)
			(xy 154.614338 -278.095664) (xy 154.646422 -278.13474) (xy 154.672185 -278.178244) (xy 154.691027 -278.225161)
			(xy 154.702511 -278.2744) (xy 154.706367 -278.324812) (xy 154.706367 -278.324818) (xy 155.01926 -278.324818)
			(xy 155.02322 -278.275764) (xy 155.034997 -278.22798) (xy 155.054288 -278.182704) (xy 155.080591 -278.141108)
			(xy 155.113226 -278.104271) (xy 155.151347 -278.073146) (xy 155.193968 -278.048539) (xy 155.239984 -278.031087)
			(xy 155.288203 -278.021243) (xy 155.337378 -278.019262) (xy 155.386233 -278.025194) (xy 155.433504 -278.038886)
			(xy 155.477966 -278.059984) (xy 155.518469 -278.08794) (xy 155.553962 -278.122032) (xy 155.583527 -278.161376)
			(xy 155.606398 -278.204953) (xy 155.621982 -278.251634) (xy 155.629877 -278.300211) (xy 155.630372 -278.324818)
			(xy 155.96922 -278.324818) (xy 155.97318 -278.275764) (xy 155.984957 -278.22798) (xy 156.004248 -278.182704)
			(xy 156.030551 -278.141108) (xy 156.063186 -278.104271) (xy 156.101307 -278.073146) (xy 156.143928 -278.048539)
			(xy 156.189944 -278.031087) (xy 156.238163 -278.021243) (xy 156.287338 -278.019262) (xy 156.336193 -278.025194)
			(xy 156.383464 -278.038886) (xy 156.427926 -278.059984) (xy 156.468429 -278.08794) (xy 156.503922 -278.122032)
			(xy 156.533487 -278.161376) (xy 156.556358 -278.204953) (xy 156.571942 -278.251634) (xy 156.579837 -278.300211)
			(xy 156.580332 -278.324818) (xy 156.91918 -278.324818) (xy 156.92314 -278.275764) (xy 156.934917 -278.22798)
			(xy 156.954208 -278.182704) (xy 156.980511 -278.141108) (xy 157.013146 -278.104271) (xy 157.051267 -278.073146)
			(xy 157.093888 -278.048539) (xy 157.139904 -278.031087) (xy 157.188123 -278.021243) (xy 157.237298 -278.019262)
			(xy 157.286153 -278.025194) (xy 157.333424 -278.038886) (xy 157.377886 -278.059984) (xy 157.418389 -278.08794)
			(xy 157.453882 -278.122032) (xy 157.483447 -278.161376) (xy 157.506318 -278.204953) (xy 157.521902 -278.251634)
			(xy 157.529797 -278.300211) (xy 157.530292 -278.324818) (xy 157.529797 -278.349425) (xy 157.521902 -278.398002)
			(xy 157.506318 -278.444683) (xy 157.483447 -278.48826) (xy 157.453882 -278.527604) (xy 157.418389 -278.561696)
			(xy 157.377886 -278.589652) (xy 157.333424 -278.61075) (xy 157.286153 -278.624442) (xy 157.237298 -278.630374)
			(xy 157.188123 -278.628393) (xy 157.139904 -278.618549) (xy 157.093888 -278.601097) (xy 157.051267 -278.57649)
			(xy 157.013146 -278.545365) (xy 156.980511 -278.508528) (xy 156.954208 -278.466932) (xy 156.934917 -278.421656)
			(xy 156.92314 -278.373872) (xy 156.91918 -278.324818) (xy 156.580332 -278.324818) (xy 156.579837 -278.349425)
			(xy 156.571942 -278.398002) (xy 156.556358 -278.444683) (xy 156.533487 -278.48826) (xy 156.503922 -278.527604)
			(xy 156.468429 -278.561696) (xy 156.427926 -278.589652) (xy 156.383464 -278.61075) (xy 156.336193 -278.624442)
			(xy 156.287338 -278.630374) (xy 156.238163 -278.628393) (xy 156.189944 -278.618549) (xy 156.143928 -278.601097)
			(xy 156.101307 -278.57649) (xy 156.063186 -278.545365) (xy 156.030551 -278.508528) (xy 156.004248 -278.466932)
			(xy 155.984957 -278.421656) (xy 155.97318 -278.373872) (xy 155.96922 -278.324818) (xy 155.630372 -278.324818)
			(xy 155.629877 -278.349425) (xy 155.621982 -278.398002) (xy 155.606398 -278.444683) (xy 155.583527 -278.48826)
			(xy 155.553962 -278.527604) (xy 155.518469 -278.561696) (xy 155.477966 -278.589652) (xy 155.433504 -278.61075)
			(xy 155.386233 -278.624442) (xy 155.337378 -278.630374) (xy 155.288203 -278.628393) (xy 155.239984 -278.618549)
			(xy 155.193968 -278.601097) (xy 155.151347 -278.57649) (xy 155.113226 -278.545365) (xy 155.080591 -278.508528)
			(xy 155.054288 -278.466932) (xy 155.034997 -278.421656) (xy 155.02322 -278.373872) (xy 155.01926 -278.324818)
			(xy 154.706367 -278.324818) (xy 154.702507 -278.375224) (xy 154.69102 -278.424462) (xy 154.672174 -278.471378)
			(xy 154.646408 -278.514879) (xy 154.614322 -278.553953) (xy 154.59583 -278.571198) (xy 154.587956 -278.578056)
			(xy 154.58059 -278.594058) (xy 154.58059 -278.594566) (xy 154.573732 -278.609806) (xy 154.570684 -278.622252)
			(xy 154.570684 -278.977344) (xy 154.573732 -278.98979) (xy 154.58059 -279.00503) (xy 154.58059 -279.005538)
			(xy 154.587956 -279.02154) (xy 154.59583 -279.028398) (xy 154.614342 -279.045624) (xy 154.646431 -279.084701)
			(xy 154.6722 -279.128206) (xy 154.691048 -279.175127) (xy 154.702537 -279.224369) (xy 154.706397 -279.274778)
			(xy 155.01926 -279.274778) (xy 155.02322 -279.225724) (xy 155.034997 -279.17794) (xy 155.054288 -279.132664)
			(xy 155.080591 -279.091068) (xy 155.113226 -279.054231) (xy 155.151347 -279.023106) (xy 155.193968 -278.998499)
			(xy 155.239984 -278.981047) (xy 155.288203 -278.971203) (xy 155.337378 -278.969222) (xy 155.386233 -278.975154)
			(xy 155.433504 -278.988846) (xy 155.477966 -279.009944) (xy 155.518469 -279.0379) (xy 155.553962 -279.071992)
			(xy 155.583527 -279.111336) (xy 155.606398 -279.154913) (xy 155.621982 -279.201594) (xy 155.629877 -279.250171)
			(xy 155.630372 -279.274778) (xy 155.96922 -279.274778) (xy 155.97318 -279.225724) (xy 155.984957 -279.17794)
			(xy 156.004248 -279.132664) (xy 156.030551 -279.091068) (xy 156.063186 -279.054231) (xy 156.101307 -279.023106)
			(xy 156.143928 -278.998499) (xy 156.189944 -278.981047) (xy 156.238163 -278.971203) (xy 156.287338 -278.969222)
			(xy 156.336193 -278.975154) (xy 156.383464 -278.988846) (xy 156.427926 -279.009944) (xy 156.468429 -279.0379)
			(xy 156.503922 -279.071992) (xy 156.533487 -279.111336) (xy 156.556358 -279.154913) (xy 156.571942 -279.201594)
			(xy 156.579837 -279.250171) (xy 156.580332 -279.274778) (xy 156.91918 -279.274778) (xy 156.92314 -279.225724)
			(xy 156.934917 -279.17794) (xy 156.954208 -279.132664) (xy 156.980511 -279.091068) (xy 157.013146 -279.054231)
			(xy 157.051267 -279.023106) (xy 157.093888 -278.998499) (xy 157.139904 -278.981047) (xy 157.188123 -278.971203)
			(xy 157.237298 -278.969222) (xy 157.286153 -278.975154) (xy 157.333424 -278.988846) (xy 157.377886 -279.009944)
			(xy 157.418389 -279.0379) (xy 157.453882 -279.071992) (xy 157.483447 -279.111336) (xy 157.506318 -279.154913)
			(xy 157.521902 -279.201594) (xy 157.529797 -279.250171) (xy 157.530292 -279.274778) (xy 157.529797 -279.299385)
			(xy 157.521902 -279.347962) (xy 157.506318 -279.394643) (xy 157.483447 -279.43822) (xy 157.453882 -279.477564)
			(xy 157.418389 -279.511656) (xy 157.377886 -279.539612) (xy 157.333424 -279.56071) (xy 157.286153 -279.574402)
			(xy 157.237298 -279.580334) (xy 157.188123 -279.578353) (xy 157.139904 -279.568509) (xy 157.093888 -279.551057)
			(xy 157.051267 -279.52645) (xy 157.013146 -279.495325) (xy 156.980511 -279.458488) (xy 156.954208 -279.416892)
			(xy 156.934917 -279.371616) (xy 156.92314 -279.323832) (xy 156.91918 -279.274778) (xy 156.580332 -279.274778)
			(xy 156.579837 -279.299385) (xy 156.571942 -279.347962) (xy 156.556358 -279.394643) (xy 156.533487 -279.43822)
			(xy 156.503922 -279.477564) (xy 156.468429 -279.511656) (xy 156.427926 -279.539612) (xy 156.383464 -279.56071)
			(xy 156.336193 -279.574402) (xy 156.287338 -279.580334) (xy 156.238163 -279.578353) (xy 156.189944 -279.568509)
			(xy 156.143928 -279.551057) (xy 156.101307 -279.52645) (xy 156.063186 -279.495325) (xy 156.030551 -279.458488)
			(xy 156.004248 -279.416892) (xy 155.984957 -279.371616) (xy 155.97318 -279.323832) (xy 155.96922 -279.274778)
			(xy 155.630372 -279.274778) (xy 155.629877 -279.299385) (xy 155.621982 -279.347962) (xy 155.606398 -279.394643)
			(xy 155.583527 -279.43822) (xy 155.553962 -279.477564) (xy 155.518469 -279.511656) (xy 155.477966 -279.539612)
			(xy 155.433504 -279.56071) (xy 155.386233 -279.574402) (xy 155.337378 -279.580334) (xy 155.288203 -279.578353)
			(xy 155.239984 -279.568509) (xy 155.193968 -279.551057) (xy 155.151347 -279.52645) (xy 155.113226 -279.495325)
			(xy 155.080591 -279.458488) (xy 155.054288 -279.416892) (xy 155.034997 -279.371616) (xy 155.02322 -279.323832)
			(xy 155.01926 -279.274778) (xy 154.706397 -279.274778) (xy 154.706398 -279.274785) (xy 154.702541 -279.325202)
			(xy 154.691057 -279.374445) (xy 154.672213 -279.421367) (xy 154.646448 -279.464875) (xy 154.614362 -279.503955)
			(xy 154.59583 -279.521158) (xy 154.587956 -279.528016) (xy 154.58059 -279.544018) (xy 154.58059 -279.544526)
			(xy 154.573732 -279.559766) (xy 154.570684 -279.572212) (xy 154.570684 -279.927304) (xy 154.573732 -279.93975)
			(xy 154.58059 -279.95499) (xy 154.58059 -279.955498) (xy 154.587956 -279.9715) (xy 154.59583 -279.978358)
			(xy 154.614337 -279.995584) (xy 154.646417 -280.03466) (xy 154.672177 -280.078162) (xy 154.691017 -280.125078)
			(xy 154.702498 -280.174315) (xy 154.706352 -280.224725) (xy 154.706351 -280.224738) (xy 155.01926 -280.224738)
			(xy 155.02322 -280.175684) (xy 155.034997 -280.1279) (xy 155.054288 -280.082624) (xy 155.080591 -280.041028)
			(xy 155.113226 -280.004191) (xy 155.151347 -279.973066) (xy 155.193968 -279.948459) (xy 155.239984 -279.931007)
			(xy 155.288203 -279.921163) (xy 155.337378 -279.919182) (xy 155.386233 -279.925114) (xy 155.433504 -279.938806)
			(xy 155.477966 -279.959904) (xy 155.518469 -279.98786) (xy 155.553962 -280.021952) (xy 155.583527 -280.061296)
			(xy 155.606398 -280.104873) (xy 155.621982 -280.151554) (xy 155.629877 -280.200131) (xy 155.630372 -280.224738)
			(xy 155.96922 -280.224738) (xy 155.97318 -280.175684) (xy 155.984957 -280.1279) (xy 156.004248 -280.082624)
			(xy 156.030551 -280.041028) (xy 156.063186 -280.004191) (xy 156.101307 -279.973066) (xy 156.143928 -279.948459)
			(xy 156.189944 -279.931007) (xy 156.238163 -279.921163) (xy 156.287338 -279.919182) (xy 156.336193 -279.925114)
			(xy 156.383464 -279.938806) (xy 156.427926 -279.959904) (xy 156.468429 -279.98786) (xy 156.503922 -280.021952)
			(xy 156.533487 -280.061296) (xy 156.556358 -280.104873) (xy 156.571942 -280.151554) (xy 156.579837 -280.200131)
			(xy 156.580332 -280.224738) (xy 156.91918 -280.224738) (xy 156.92314 -280.175684) (xy 156.934917 -280.1279)
			(xy 156.954208 -280.082624) (xy 156.980511 -280.041028) (xy 157.013146 -280.004191) (xy 157.051267 -279.973066)
			(xy 157.093888 -279.948459) (xy 157.139904 -279.931007) (xy 157.188123 -279.921163) (xy 157.237298 -279.919182)
			(xy 157.286153 -279.925114) (xy 157.333424 -279.938806) (xy 157.377886 -279.959904) (xy 157.418389 -279.98786)
			(xy 157.453882 -280.021952) (xy 157.483447 -280.061296) (xy 157.506318 -280.104873) (xy 157.521902 -280.151554)
			(xy 157.529797 -280.200131) (xy 157.530292 -280.224738) (xy 157.529797 -280.249345) (xy 157.521902 -280.297922)
			(xy 157.506318 -280.344603) (xy 157.483447 -280.38818) (xy 157.453882 -280.427524) (xy 157.418389 -280.461616)
			(xy 157.377886 -280.489572) (xy 157.333424 -280.51067) (xy 157.286153 -280.524362) (xy 157.237298 -280.530294)
			(xy 157.188123 -280.528313) (xy 157.139904 -280.518469) (xy 157.093888 -280.501017) (xy 157.051267 -280.47641)
			(xy 157.013146 -280.445285) (xy 156.980511 -280.408448) (xy 156.954208 -280.366852) (xy 156.934917 -280.321576)
			(xy 156.92314 -280.273792) (xy 156.91918 -280.224738) (xy 156.580332 -280.224738) (xy 156.579837 -280.249345)
			(xy 156.571942 -280.297922) (xy 156.556358 -280.344603) (xy 156.533487 -280.38818) (xy 156.503922 -280.427524)
			(xy 156.468429 -280.461616) (xy 156.427926 -280.489572) (xy 156.383464 -280.51067) (xy 156.336193 -280.524362)
			(xy 156.287338 -280.530294) (xy 156.238163 -280.528313) (xy 156.189944 -280.518469) (xy 156.143928 -280.501017)
			(xy 156.101307 -280.47641) (xy 156.063186 -280.445285) (xy 156.030551 -280.408448) (xy 156.004248 -280.366852)
			(xy 155.984957 -280.321576) (xy 155.97318 -280.273792) (xy 155.96922 -280.224738) (xy 155.630372 -280.224738)
			(xy 155.629877 -280.249345) (xy 155.621982 -280.297922) (xy 155.606398 -280.344603) (xy 155.583527 -280.38818)
			(xy 155.553962 -280.427524) (xy 155.518469 -280.461616) (xy 155.477966 -280.489572) (xy 155.433504 -280.51067)
			(xy 155.386233 -280.524362) (xy 155.337378 -280.530294) (xy 155.288203 -280.528313) (xy 155.239984 -280.518469)
			(xy 155.193968 -280.501017) (xy 155.151347 -280.47641) (xy 155.113226 -280.445285) (xy 155.080591 -280.408448)
			(xy 155.054288 -280.366852) (xy 155.034997 -280.321576) (xy 155.02322 -280.273792) (xy 155.01926 -280.224738)
			(xy 154.706351 -280.224738) (xy 154.70249 -280.275135) (xy 154.691002 -280.32437) (xy 154.672155 -280.371283)
			(xy 154.646388 -280.414782) (xy 154.614302 -280.453852) (xy 154.59583 -280.471118) (xy 154.587956 -280.477976)
			(xy 154.58059 -280.493978) (xy 154.58059 -280.494486) (xy 154.573732 -280.509726) (xy 154.570684 -280.522172)
			(xy 154.570684 -280.877518) (xy 154.573732 -280.889964) (xy 154.58059 -280.905204) (xy 154.58059 -280.905712)
			(xy 154.587956 -280.921714) (xy 154.59583 -280.928572) (xy 154.614344 -280.945798) (xy 154.646437 -280.984876)
			(xy 154.67221 -281.028382) (xy 154.691062 -281.075304) (xy 154.702553 -281.124548) (xy 154.706416 -281.174952)
			(xy 155.01926 -281.174952) (xy 155.02322 -281.125898) (xy 155.034997 -281.078114) (xy 155.054288 -281.032838)
			(xy 155.080591 -280.991242) (xy 155.113226 -280.954405) (xy 155.151347 -280.92328) (xy 155.193968 -280.898673)
			(xy 155.239984 -280.881221) (xy 155.288203 -280.871377) (xy 155.337378 -280.869396) (xy 155.386233 -280.875328)
			(xy 155.433504 -280.88902) (xy 155.477966 -280.910118) (xy 155.518469 -280.938074) (xy 155.553962 -280.972166)
			(xy 155.583527 -281.01151) (xy 155.606398 -281.055087) (xy 155.621982 -281.101768) (xy 155.629877 -281.150345)
			(xy 155.630372 -281.174952) (xy 155.96922 -281.174952) (xy 155.97318 -281.125898) (xy 155.984957 -281.078114)
			(xy 156.004248 -281.032838) (xy 156.030551 -280.991242) (xy 156.063186 -280.954405) (xy 156.101307 -280.92328)
			(xy 156.143928 -280.898673) (xy 156.189944 -280.881221) (xy 156.238163 -280.871377) (xy 156.287338 -280.869396)
			(xy 156.336193 -280.875328) (xy 156.383464 -280.88902) (xy 156.427926 -280.910118) (xy 156.468429 -280.938074)
			(xy 156.503922 -280.972166) (xy 156.533487 -281.01151) (xy 156.556358 -281.055087) (xy 156.571942 -281.101768)
			(xy 156.579837 -281.150345) (xy 156.580332 -281.174952) (xy 156.91918 -281.174952) (xy 156.92314 -281.125898)
			(xy 156.934917 -281.078114) (xy 156.954208 -281.032838) (xy 156.980511 -280.991242) (xy 157.013146 -280.954405)
			(xy 157.051267 -280.92328) (xy 157.093888 -280.898673) (xy 157.139904 -280.881221) (xy 157.188123 -280.871377)
			(xy 157.237298 -280.869396) (xy 157.286153 -280.875328) (xy 157.333424 -280.88902) (xy 157.377886 -280.910118)
			(xy 157.418389 -280.938074) (xy 157.453882 -280.972166) (xy 157.483447 -281.01151) (xy 157.506318 -281.055087)
			(xy 157.521902 -281.101768) (xy 157.529797 -281.150345) (xy 157.530292 -281.174952) (xy 157.529797 -281.199559)
			(xy 157.521902 -281.248136) (xy 157.506318 -281.294817) (xy 157.483447 -281.338394) (xy 157.453882 -281.377738)
			(xy 157.418389 -281.41183) (xy 157.377886 -281.439786) (xy 157.333424 -281.460884) (xy 157.286153 -281.474576)
			(xy 157.237298 -281.480508) (xy 157.188123 -281.478527) (xy 157.139904 -281.468683) (xy 157.093888 -281.451231)
			(xy 157.051267 -281.426624) (xy 157.013146 -281.395499) (xy 156.980511 -281.358662) (xy 156.954208 -281.317066)
			(xy 156.934917 -281.27179) (xy 156.92314 -281.224006) (xy 156.91918 -281.174952) (xy 156.580332 -281.174952)
			(xy 156.579837 -281.199559) (xy 156.571942 -281.248136) (xy 156.556358 -281.294817) (xy 156.533487 -281.338394)
			(xy 156.503922 -281.377738) (xy 156.468429 -281.41183) (xy 156.427926 -281.439786) (xy 156.383464 -281.460884)
			(xy 156.336193 -281.474576) (xy 156.287338 -281.480508) (xy 156.238163 -281.478527) (xy 156.189944 -281.468683)
			(xy 156.143928 -281.451231) (xy 156.101307 -281.426624) (xy 156.063186 -281.395499) (xy 156.030551 -281.358662)
			(xy 156.004248 -281.317066) (xy 155.984957 -281.27179) (xy 155.97318 -281.224006) (xy 155.96922 -281.174952)
			(xy 155.630372 -281.174952) (xy 155.629877 -281.199559) (xy 155.621982 -281.248136) (xy 155.606398 -281.294817)
			(xy 155.583527 -281.338394) (xy 155.553962 -281.377738) (xy 155.518469 -281.41183) (xy 155.477966 -281.439786)
			(xy 155.433504 -281.460884) (xy 155.386233 -281.474576) (xy 155.337378 -281.480508) (xy 155.288203 -281.478527)
			(xy 155.239984 -281.468683) (xy 155.193968 -281.451231) (xy 155.151347 -281.426624) (xy 155.113226 -281.395499)
			(xy 155.080591 -281.358662) (xy 155.054288 -281.317066) (xy 155.034997 -281.27179) (xy 155.02322 -281.224006)
			(xy 155.01926 -281.174952) (xy 154.706416 -281.174952) (xy 154.706417 -281.174968) (xy 154.702563 -281.225388)
			(xy 154.691081 -281.274635) (xy 154.672238 -281.32156) (xy 154.646474 -281.365072) (xy 154.614388 -281.404155)
			(xy 154.59583 -281.421332) (xy 154.587956 -281.42819) (xy 154.58059 -281.444192) (xy 154.58059 -281.4447)
			(xy 154.573732 -281.45994) (xy 154.570684 -281.472386) (xy 154.570684 -281.827478) (xy 154.573732 -281.839924)
			(xy 154.58059 -281.855164) (xy 154.58059 -281.855672) (xy 154.587956 -281.871674) (xy 154.59583 -281.878532)
			(xy 154.614339 -281.895758) (xy 154.646423 -281.934835) (xy 154.672187 -281.978338) (xy 154.691031 -282.025256)
			(xy 154.702515 -282.074495) (xy 154.706372 -282.124908) (xy 154.706372 -282.124912) (xy 155.01926 -282.124912)
			(xy 155.02322 -282.075858) (xy 155.034997 -282.028074) (xy 155.054288 -281.982798) (xy 155.080591 -281.941202)
			(xy 155.113226 -281.904365) (xy 155.151347 -281.87324) (xy 155.193968 -281.848633) (xy 155.239984 -281.831181)
			(xy 155.288203 -281.821337) (xy 155.337378 -281.819356) (xy 155.386233 -281.825288) (xy 155.433504 -281.83898)
			(xy 155.477966 -281.860078) (xy 155.518469 -281.888034) (xy 155.553962 -281.922126) (xy 155.583527 -281.96147)
			(xy 155.606398 -282.005047) (xy 155.621982 -282.051728) (xy 155.629877 -282.100305) (xy 155.630372 -282.124912)
			(xy 155.96922 -282.124912) (xy 155.97318 -282.075858) (xy 155.984957 -282.028074) (xy 156.004248 -281.982798)
			(xy 156.030551 -281.941202) (xy 156.063186 -281.904365) (xy 156.101307 -281.87324) (xy 156.143928 -281.848633)
			(xy 156.189944 -281.831181) (xy 156.238163 -281.821337) (xy 156.287338 -281.819356) (xy 156.336193 -281.825288)
			(xy 156.383464 -281.83898) (xy 156.427926 -281.860078) (xy 156.468429 -281.888034) (xy 156.503922 -281.922126)
			(xy 156.533487 -281.96147) (xy 156.556358 -282.005047) (xy 156.571942 -282.051728) (xy 156.579837 -282.100305)
			(xy 156.580332 -282.124912) (xy 156.91918 -282.124912) (xy 156.92314 -282.075858) (xy 156.934917 -282.028074)
			(xy 156.954208 -281.982798) (xy 156.980511 -281.941202) (xy 157.013146 -281.904365) (xy 157.051267 -281.87324)
			(xy 157.093888 -281.848633) (xy 157.139904 -281.831181) (xy 157.188123 -281.821337) (xy 157.237298 -281.819356)
			(xy 157.286153 -281.825288) (xy 157.333424 -281.83898) (xy 157.377886 -281.860078) (xy 157.418389 -281.888034)
			(xy 157.453882 -281.922126) (xy 157.483447 -281.96147) (xy 157.506318 -282.005047) (xy 157.521902 -282.051728)
			(xy 157.529797 -282.100305) (xy 157.530292 -282.124912) (xy 157.529797 -282.149519) (xy 157.521902 -282.198096)
			(xy 157.506318 -282.244777) (xy 157.483447 -282.288354) (xy 157.453882 -282.327698) (xy 157.418389 -282.36179)
			(xy 157.377886 -282.389746) (xy 157.333424 -282.410844) (xy 157.286153 -282.424536) (xy 157.237298 -282.430468)
			(xy 157.188123 -282.428487) (xy 157.139904 -282.418643) (xy 157.093888 -282.401191) (xy 157.051267 -282.376584)
			(xy 157.013146 -282.345459) (xy 156.980511 -282.308622) (xy 156.954208 -282.267026) (xy 156.934917 -282.22175)
			(xy 156.92314 -282.173966) (xy 156.91918 -282.124912) (xy 156.580332 -282.124912) (xy 156.579837 -282.149519)
			(xy 156.571942 -282.198096) (xy 156.556358 -282.244777) (xy 156.533487 -282.288354) (xy 156.503922 -282.327698)
			(xy 156.468429 -282.36179) (xy 156.427926 -282.389746) (xy 156.383464 -282.410844) (xy 156.336193 -282.424536)
			(xy 156.287338 -282.430468) (xy 156.238163 -282.428487) (xy 156.189944 -282.418643) (xy 156.143928 -282.401191)
			(xy 156.101307 -282.376584) (xy 156.063186 -282.345459) (xy 156.030551 -282.308622) (xy 156.004248 -282.267026)
			(xy 155.984957 -282.22175) (xy 155.97318 -282.173966) (xy 155.96922 -282.124912) (xy 155.630372 -282.124912)
			(xy 155.629877 -282.149519) (xy 155.621982 -282.198096) (xy 155.606398 -282.244777) (xy 155.583527 -282.288354)
			(xy 155.553962 -282.327698) (xy 155.518469 -282.36179) (xy 155.477966 -282.389746) (xy 155.433504 -282.410844)
			(xy 155.386233 -282.424536) (xy 155.337378 -282.430468) (xy 155.288203 -282.428487) (xy 155.239984 -282.418643)
			(xy 155.193968 -282.401191) (xy 155.151347 -282.376584) (xy 155.113226 -282.345459) (xy 155.080591 -282.308622)
			(xy 155.054288 -282.267026) (xy 155.034997 -282.22175) (xy 155.02322 -282.173966) (xy 155.01926 -282.124912)
			(xy 154.706372 -282.124912) (xy 154.702512 -282.175321) (xy 154.691026 -282.224559) (xy 154.67218 -282.271476)
			(xy 154.646414 -282.314979) (xy 154.614328 -282.354053) (xy 154.59583 -282.371292) (xy 154.587956 -282.37815)
			(xy 154.58059 -282.394152) (xy 154.58059 -282.39466) (xy 154.573732 -282.4099) (xy 154.570684 -282.422346)
			(xy 154.570684 -282.777438) (xy 154.573732 -282.789884) (xy 154.58059 -282.805124) (xy 154.58059 -282.805632)
			(xy 154.587956 -282.821634) (xy 154.59583 -282.828492) (xy 154.614342 -282.845718) (xy 154.646432 -282.884795)
			(xy 154.672202 -282.928301) (xy 154.691051 -282.975221) (xy 154.702541 -283.024464) (xy 154.706401 -283.074872)
			(xy 155.01926 -283.074872) (xy 155.02322 -283.025818) (xy 155.034997 -282.978034) (xy 155.054288 -282.932758)
			(xy 155.080591 -282.891162) (xy 155.113226 -282.854325) (xy 155.151347 -282.8232) (xy 155.193968 -282.798593)
			(xy 155.239984 -282.781141) (xy 155.288203 -282.771297) (xy 155.337378 -282.769316) (xy 155.386233 -282.775248)
			(xy 155.433504 -282.78894) (xy 155.477966 -282.810038) (xy 155.518469 -282.837994) (xy 155.553962 -282.872086)
			(xy 155.583527 -282.91143) (xy 155.606398 -282.955007) (xy 155.621982 -283.001688) (xy 155.629877 -283.050265)
			(xy 155.630372 -283.074872) (xy 155.96922 -283.074872) (xy 155.97318 -283.025818) (xy 155.984957 -282.978034)
			(xy 156.004248 -282.932758) (xy 156.030551 -282.891162) (xy 156.063186 -282.854325) (xy 156.101307 -282.8232)
			(xy 156.143928 -282.798593) (xy 156.189944 -282.781141) (xy 156.238163 -282.771297) (xy 156.287338 -282.769316)
			(xy 156.336193 -282.775248) (xy 156.383464 -282.78894) (xy 156.427926 -282.810038) (xy 156.468429 -282.837994)
			(xy 156.503922 -282.872086) (xy 156.533487 -282.91143) (xy 156.556358 -282.955007) (xy 156.571942 -283.001688)
			(xy 156.579837 -283.050265) (xy 156.580332 -283.074872) (xy 156.91918 -283.074872) (xy 156.92314 -283.025818)
			(xy 156.934917 -282.978034) (xy 156.954208 -282.932758) (xy 156.980511 -282.891162) (xy 157.013146 -282.854325)
			(xy 157.051267 -282.8232) (xy 157.093888 -282.798593) (xy 157.139904 -282.781141) (xy 157.188123 -282.771297)
			(xy 157.237298 -282.769316) (xy 157.286153 -282.775248) (xy 157.333424 -282.78894) (xy 157.377886 -282.810038)
			(xy 157.418389 -282.837994) (xy 157.453882 -282.872086) (xy 157.483447 -282.91143) (xy 157.506318 -282.955007)
			(xy 157.521902 -283.001688) (xy 157.529797 -283.050265) (xy 157.530292 -283.074872) (xy 157.529797 -283.099479)
			(xy 157.521902 -283.148056) (xy 157.506318 -283.194737) (xy 157.483447 -283.238314) (xy 157.453882 -283.277658)
			(xy 157.418389 -283.31175) (xy 157.377886 -283.339706) (xy 157.333424 -283.360804) (xy 157.286153 -283.374496)
			(xy 157.237298 -283.380428) (xy 157.188123 -283.378447) (xy 157.139904 -283.368603) (xy 157.093888 -283.351151)
			(xy 157.051267 -283.326544) (xy 157.013146 -283.295419) (xy 156.980511 -283.258582) (xy 156.954208 -283.216986)
			(xy 156.934917 -283.17171) (xy 156.92314 -283.123926) (xy 156.91918 -283.074872) (xy 156.580332 -283.074872)
			(xy 156.579837 -283.099479) (xy 156.571942 -283.148056) (xy 156.556358 -283.194737) (xy 156.533487 -283.238314)
			(xy 156.503922 -283.277658) (xy 156.468429 -283.31175) (xy 156.427926 -283.339706) (xy 156.383464 -283.360804)
			(xy 156.336193 -283.374496) (xy 156.287338 -283.380428) (xy 156.238163 -283.378447) (xy 156.189944 -283.368603)
			(xy 156.143928 -283.351151) (xy 156.101307 -283.326544) (xy 156.063186 -283.295419) (xy 156.030551 -283.258582)
			(xy 156.004248 -283.216986) (xy 155.984957 -283.17171) (xy 155.97318 -283.123926) (xy 155.96922 -283.074872)
			(xy 155.630372 -283.074872) (xy 155.629877 -283.099479) (xy 155.621982 -283.148056) (xy 155.606398 -283.194737)
			(xy 155.583527 -283.238314) (xy 155.553962 -283.277658) (xy 155.518469 -283.31175) (xy 155.477966 -283.339706)
			(xy 155.433504 -283.360804) (xy 155.386233 -283.374496) (xy 155.337378 -283.380428) (xy 155.288203 -283.378447)
			(xy 155.239984 -283.368603) (xy 155.193968 -283.351151) (xy 155.151347 -283.326544) (xy 155.113226 -283.295419)
			(xy 155.080591 -283.258582) (xy 155.054288 -283.216986) (xy 155.034997 -283.17171) (xy 155.02322 -283.123926)
			(xy 155.01926 -283.074872) (xy 154.706401 -283.074872) (xy 154.706402 -283.074881) (xy 154.702546 -283.125299)
			(xy 154.691063 -283.174543) (xy 154.672219 -283.221466) (xy 154.646454 -283.264974) (xy 154.614368 -283.304055)
			(xy 154.59583 -283.321252) (xy 154.587956 -283.32811) (xy 154.58059 -283.344112) (xy 154.58059 -283.34462)
			(xy 154.573732 -283.35986) (xy 154.570684 -283.372306) (xy 154.570684 -283.727398) (xy 154.573732 -283.739844)
			(xy 154.58059 -283.755084) (xy 154.58059 -283.755592) (xy 154.587956 -283.771594) (xy 154.59583 -283.778452)
			(xy 154.614337 -283.795678) (xy 154.646418 -283.834754) (xy 154.67218 -283.878257) (xy 154.69102 -283.925173)
			(xy 154.702502 -283.97441) (xy 154.706357 -284.024821) (xy 154.706356 -284.024832) (xy 155.01926 -284.024832)
			(xy 155.02322 -283.975778) (xy 155.034997 -283.927994) (xy 155.054288 -283.882718) (xy 155.080591 -283.841122)
			(xy 155.113226 -283.804285) (xy 155.151347 -283.77316) (xy 155.193968 -283.748553) (xy 155.239984 -283.731101)
			(xy 155.288203 -283.721257) (xy 155.337378 -283.719276) (xy 155.386233 -283.725208) (xy 155.433504 -283.7389)
			(xy 155.477966 -283.759998) (xy 155.518469 -283.787954) (xy 155.553962 -283.822046) (xy 155.583527 -283.86139)
			(xy 155.606398 -283.904967) (xy 155.621982 -283.951648) (xy 155.629877 -284.000225) (xy 155.630372 -284.024832)
			(xy 155.96922 -284.024832) (xy 155.97318 -283.975778) (xy 155.984957 -283.927994) (xy 156.004248 -283.882718)
			(xy 156.030551 -283.841122) (xy 156.063186 -283.804285) (xy 156.101307 -283.77316) (xy 156.143928 -283.748553)
			(xy 156.189944 -283.731101) (xy 156.238163 -283.721257) (xy 156.287338 -283.719276) (xy 156.336193 -283.725208)
			(xy 156.383464 -283.7389) (xy 156.427926 -283.759998) (xy 156.468429 -283.787954) (xy 156.503922 -283.822046)
			(xy 156.533487 -283.86139) (xy 156.556358 -283.904967) (xy 156.571942 -283.951648) (xy 156.579837 -284.000225)
			(xy 156.580332 -284.024832) (xy 156.91918 -284.024832) (xy 156.92314 -283.975778) (xy 156.934917 -283.927994)
			(xy 156.954208 -283.882718) (xy 156.980511 -283.841122) (xy 157.013146 -283.804285) (xy 157.051267 -283.77316)
			(xy 157.093888 -283.748553) (xy 157.139904 -283.731101) (xy 157.188123 -283.721257) (xy 157.237298 -283.719276)
			(xy 157.286153 -283.725208) (xy 157.333424 -283.7389) (xy 157.377886 -283.759998) (xy 157.418389 -283.787954)
			(xy 157.453882 -283.822046) (xy 157.483447 -283.86139) (xy 157.506318 -283.904967) (xy 157.521902 -283.951648)
			(xy 157.529797 -284.000225) (xy 157.530292 -284.024832) (xy 157.529797 -284.049439) (xy 157.521902 -284.098016)
			(xy 157.506318 -284.144697) (xy 157.483447 -284.188274) (xy 157.453882 -284.227618) (xy 157.418389 -284.26171)
			(xy 157.377886 -284.289666) (xy 157.333424 -284.310764) (xy 157.286153 -284.324456) (xy 157.237298 -284.330388)
			(xy 157.188123 -284.328407) (xy 157.139904 -284.318563) (xy 157.093888 -284.301111) (xy 157.051267 -284.276504)
			(xy 157.013146 -284.245379) (xy 156.980511 -284.208542) (xy 156.954208 -284.166946) (xy 156.934917 -284.12167)
			(xy 156.92314 -284.073886) (xy 156.91918 -284.024832) (xy 156.580332 -284.024832) (xy 156.579837 -284.049439)
			(xy 156.571942 -284.098016) (xy 156.556358 -284.144697) (xy 156.533487 -284.188274) (xy 156.503922 -284.227618)
			(xy 156.468429 -284.26171) (xy 156.427926 -284.289666) (xy 156.383464 -284.310764) (xy 156.336193 -284.324456)
			(xy 156.287338 -284.330388) (xy 156.238163 -284.328407) (xy 156.189944 -284.318563) (xy 156.143928 -284.301111)
			(xy 156.101307 -284.276504) (xy 156.063186 -284.245379) (xy 156.030551 -284.208542) (xy 156.004248 -284.166946)
			(xy 155.984957 -284.12167) (xy 155.97318 -284.073886) (xy 155.96922 -284.024832) (xy 155.630372 -284.024832)
			(xy 155.629877 -284.049439) (xy 155.621982 -284.098016) (xy 155.606398 -284.144697) (xy 155.583527 -284.188274)
			(xy 155.553962 -284.227618) (xy 155.518469 -284.26171) (xy 155.477966 -284.289666) (xy 155.433504 -284.310764)
			(xy 155.386233 -284.324456) (xy 155.337378 -284.330388) (xy 155.288203 -284.328407) (xy 155.239984 -284.318563)
			(xy 155.193968 -284.301111) (xy 155.151347 -284.276504) (xy 155.113226 -284.245379) (xy 155.080591 -284.208542)
			(xy 155.054288 -284.166946) (xy 155.034997 -284.12167) (xy 155.02322 -284.073886) (xy 155.01926 -284.024832)
			(xy 154.706356 -284.024832) (xy 154.702495 -284.075232) (xy 154.691007 -284.124468) (xy 154.672161 -284.171381)
			(xy 154.646394 -284.214881) (xy 154.614308 -284.253953) (xy 154.59583 -284.271212) (xy 154.587956 -284.27807)
			(xy 154.58059 -284.294072) (xy 154.58059 -284.29458) (xy 154.573732 -284.30982) (xy 154.570684 -284.322266)
			(xy 154.570684 -284.677358) (xy 154.573732 -284.689804) (xy 154.58059 -284.705044) (xy 154.58059 -284.705552)
			(xy 154.587956 -284.721554) (xy 154.59583 -284.728412) (xy 154.61434 -284.745638) (xy 154.646428 -284.784715)
			(xy 154.672194 -284.82822) (xy 154.691041 -284.875139) (xy 154.702527 -284.924379) (xy 154.706387 -284.974792)
			(xy 155.01926 -284.974792) (xy 155.02322 -284.925738) (xy 155.034997 -284.877954) (xy 155.054288 -284.832678)
			(xy 155.080591 -284.791082) (xy 155.113226 -284.754245) (xy 155.151347 -284.72312) (xy 155.193968 -284.698513)
			(xy 155.239984 -284.681061) (xy 155.288203 -284.671217) (xy 155.337378 -284.669236) (xy 155.386233 -284.675168)
			(xy 155.433504 -284.68886) (xy 155.477966 -284.709958) (xy 155.518469 -284.737914) (xy 155.553962 -284.772006)
			(xy 155.583527 -284.81135) (xy 155.606398 -284.854927) (xy 155.621982 -284.901608) (xy 155.629877 -284.950185)
			(xy 155.630372 -284.974792) (xy 155.96922 -284.974792) (xy 155.97318 -284.925738) (xy 155.984957 -284.877954)
			(xy 156.004248 -284.832678) (xy 156.030551 -284.791082) (xy 156.063186 -284.754245) (xy 156.101307 -284.72312)
			(xy 156.143928 -284.698513) (xy 156.189944 -284.681061) (xy 156.238163 -284.671217) (xy 156.287338 -284.669236)
			(xy 156.336193 -284.675168) (xy 156.383464 -284.68886) (xy 156.427926 -284.709958) (xy 156.468429 -284.737914)
			(xy 156.503922 -284.772006) (xy 156.533487 -284.81135) (xy 156.556358 -284.854927) (xy 156.571942 -284.901608)
			(xy 156.579837 -284.950185) (xy 156.580332 -284.974792) (xy 156.91918 -284.974792) (xy 156.92314 -284.925738)
			(xy 156.934917 -284.877954) (xy 156.954208 -284.832678) (xy 156.980511 -284.791082) (xy 157.013146 -284.754245)
			(xy 157.051267 -284.72312) (xy 157.093888 -284.698513) (xy 157.139904 -284.681061) (xy 157.188123 -284.671217)
			(xy 157.237298 -284.669236) (xy 157.286153 -284.675168) (xy 157.333424 -284.68886) (xy 157.377886 -284.709958)
			(xy 157.418389 -284.737914) (xy 157.453882 -284.772006) (xy 157.483447 -284.81135) (xy 157.506318 -284.854927)
			(xy 157.521902 -284.901608) (xy 157.529797 -284.950185) (xy 157.530292 -284.974792) (xy 157.529797 -284.999399)
			(xy 157.521902 -285.047976) (xy 157.506318 -285.094657) (xy 157.483447 -285.138234) (xy 157.453882 -285.177578)
			(xy 157.418389 -285.21167) (xy 157.377886 -285.239626) (xy 157.333424 -285.260724) (xy 157.286153 -285.274416)
			(xy 157.237298 -285.280348) (xy 157.188123 -285.278367) (xy 157.139904 -285.268523) (xy 157.093888 -285.251071)
			(xy 157.051267 -285.226464) (xy 157.013146 -285.195339) (xy 156.980511 -285.158502) (xy 156.954208 -285.116906)
			(xy 156.934917 -285.07163) (xy 156.92314 -285.023846) (xy 156.91918 -284.974792) (xy 156.580332 -284.974792)
			(xy 156.579837 -284.999399) (xy 156.571942 -285.047976) (xy 156.556358 -285.094657) (xy 156.533487 -285.138234)
			(xy 156.503922 -285.177578) (xy 156.468429 -285.21167) (xy 156.427926 -285.239626) (xy 156.383464 -285.260724)
			(xy 156.336193 -285.274416) (xy 156.287338 -285.280348) (xy 156.238163 -285.278367) (xy 156.189944 -285.268523)
			(xy 156.143928 -285.251071) (xy 156.101307 -285.226464) (xy 156.063186 -285.195339) (xy 156.030551 -285.158502)
			(xy 156.004248 -285.116906) (xy 155.984957 -285.07163) (xy 155.97318 -285.023846) (xy 155.96922 -284.974792)
			(xy 155.630372 -284.974792) (xy 155.629877 -284.999399) (xy 155.621982 -285.047976) (xy 155.606398 -285.094657)
			(xy 155.583527 -285.138234) (xy 155.553962 -285.177578) (xy 155.518469 -285.21167) (xy 155.477966 -285.239626)
			(xy 155.433504 -285.260724) (xy 155.386233 -285.274416) (xy 155.337378 -285.280348) (xy 155.288203 -285.278367)
			(xy 155.239984 -285.268523) (xy 155.193968 -285.251071) (xy 155.151347 -285.226464) (xy 155.113226 -285.195339)
			(xy 155.080591 -285.158502) (xy 155.054288 -285.116906) (xy 155.034997 -285.07163) (xy 155.02322 -285.023846)
			(xy 155.01926 -284.974792) (xy 154.706387 -284.974792) (xy 154.706387 -284.974795) (xy 154.702529 -285.02521)
			(xy 154.691044 -285.074451) (xy 154.672199 -285.121371) (xy 154.646434 -285.164876) (xy 154.614348 -285.203954)
			(xy 154.59583 -285.221172) (xy 154.587956 -285.22803) (xy 154.58059 -285.244032) (xy 154.58059 -285.24454)
			(xy 154.573732 -285.25978) (xy 154.570684 -285.272226) (xy 154.570684 -285.627318) (xy 154.573732 -285.639764)
			(xy 154.58059 -285.655004) (xy 154.58059 -285.655512) (xy 154.587956 -285.671514) (xy 154.59583 -285.678372)
			(xy 154.614344 -285.695598) (xy 154.646437 -285.734676) (xy 154.67221 -285.778182) (xy 154.691062 -285.825104)
			(xy 154.702553 -285.874348) (xy 154.706416 -285.924752) (xy 155.01926 -285.924752) (xy 155.02322 -285.875698)
			(xy 155.034997 -285.827914) (xy 155.054288 -285.782638) (xy 155.080591 -285.741042) (xy 155.113226 -285.704205)
			(xy 155.151347 -285.67308) (xy 155.193968 -285.648473) (xy 155.239984 -285.631021) (xy 155.288203 -285.621177)
			(xy 155.337378 -285.619196) (xy 155.386233 -285.625128) (xy 155.433504 -285.63882) (xy 155.477966 -285.659918)
			(xy 155.518469 -285.687874) (xy 155.553962 -285.721966) (xy 155.583527 -285.76131) (xy 155.606398 -285.804887)
			(xy 155.621982 -285.851568) (xy 155.629877 -285.900145) (xy 155.630372 -285.924752) (xy 155.96922 -285.924752)
			(xy 155.97318 -285.875698) (xy 155.984957 -285.827914) (xy 156.004248 -285.782638) (xy 156.030551 -285.741042)
			(xy 156.063186 -285.704205) (xy 156.101307 -285.67308) (xy 156.143928 -285.648473) (xy 156.189944 -285.631021)
			(xy 156.238163 -285.621177) (xy 156.287338 -285.619196) (xy 156.336193 -285.625128) (xy 156.383464 -285.63882)
			(xy 156.427926 -285.659918) (xy 156.468429 -285.687874) (xy 156.503922 -285.721966) (xy 156.533487 -285.76131)
			(xy 156.556358 -285.804887) (xy 156.571942 -285.851568) (xy 156.579837 -285.900145) (xy 156.580332 -285.924752)
			(xy 156.91918 -285.924752) (xy 156.92314 -285.875698) (xy 156.934917 -285.827914) (xy 156.954208 -285.782638)
			(xy 156.980511 -285.741042) (xy 157.013146 -285.704205) (xy 157.051267 -285.67308) (xy 157.093888 -285.648473)
			(xy 157.139904 -285.631021) (xy 157.188123 -285.621177) (xy 157.237298 -285.619196) (xy 157.286153 -285.625128)
			(xy 157.333424 -285.63882) (xy 157.377886 -285.659918) (xy 157.418389 -285.687874) (xy 157.453882 -285.721966)
			(xy 157.483447 -285.76131) (xy 157.506318 -285.804887) (xy 157.521902 -285.851568) (xy 157.529797 -285.900145)
			(xy 157.530292 -285.924752) (xy 157.529797 -285.949359) (xy 157.521902 -285.997936) (xy 157.506318 -286.044617)
			(xy 157.483447 -286.088194) (xy 157.453882 -286.127538) (xy 157.418389 -286.16163) (xy 157.377886 -286.189586)
			(xy 157.333424 -286.210684) (xy 157.286153 -286.224376) (xy 157.237298 -286.230308) (xy 157.188123 -286.228327)
			(xy 157.139904 -286.218483) (xy 157.093888 -286.201031) (xy 157.051267 -286.176424) (xy 157.013146 -286.145299)
			(xy 156.980511 -286.108462) (xy 156.954208 -286.066866) (xy 156.934917 -286.02159) (xy 156.92314 -285.973806)
			(xy 156.91918 -285.924752) (xy 156.580332 -285.924752) (xy 156.579837 -285.949359) (xy 156.571942 -285.997936)
			(xy 156.556358 -286.044617) (xy 156.533487 -286.088194) (xy 156.503922 -286.127538) (xy 156.468429 -286.16163)
			(xy 156.427926 -286.189586) (xy 156.383464 -286.210684) (xy 156.336193 -286.224376) (xy 156.287338 -286.230308)
			(xy 156.238163 -286.228327) (xy 156.189944 -286.218483) (xy 156.143928 -286.201031) (xy 156.101307 -286.176424)
			(xy 156.063186 -286.145299) (xy 156.030551 -286.108462) (xy 156.004248 -286.066866) (xy 155.984957 -286.02159)
			(xy 155.97318 -285.973806) (xy 155.96922 -285.924752) (xy 155.630372 -285.924752) (xy 155.629877 -285.949359)
			(xy 155.621982 -285.997936) (xy 155.606398 -286.044617) (xy 155.583527 -286.088194) (xy 155.553962 -286.127538)
			(xy 155.518469 -286.16163) (xy 155.477966 -286.189586) (xy 155.433504 -286.210684) (xy 155.386233 -286.224376)
			(xy 155.337378 -286.230308) (xy 155.288203 -286.228327) (xy 155.239984 -286.218483) (xy 155.193968 -286.201031)
			(xy 155.151347 -286.176424) (xy 155.113226 -286.145299) (xy 155.080591 -286.108462) (xy 155.054288 -286.066866)
			(xy 155.034997 -286.02159) (xy 155.02322 -285.973806) (xy 155.01926 -285.924752) (xy 154.706416 -285.924752)
			(xy 154.706417 -285.924768) (xy 154.702563 -285.975188) (xy 154.691081 -286.024435) (xy 154.672238 -286.07136)
			(xy 154.646474 -286.114872) (xy 154.614388 -286.153955) (xy 154.59583 -286.171132) (xy 154.587956 -286.17799)
			(xy 154.58059 -286.193992) (xy 154.58059 -286.1945) (xy 154.573732 -286.20974) (xy 154.570684 -286.222186)
			(xy 154.570684 -286.577532) (xy 154.573732 -286.589978) (xy 154.58059 -286.605218) (xy 154.58059 -286.605726)
			(xy 154.587956 -286.621728) (xy 154.59583 -286.628586) (xy 154.61615 -286.647578) (xy 154.650763 -286.691111)
			(xy 154.677614 -286.739817) (xy 154.695947 -286.792325) (xy 154.705247 -286.847158) (xy 154.705812 -286.874966)
			(xy 155.01926 -286.874966) (xy 155.02322 -286.825912) (xy 155.034997 -286.778128) (xy 155.054288 -286.732852)
			(xy 155.080591 -286.691256) (xy 155.113226 -286.654419) (xy 155.151347 -286.623294) (xy 155.193968 -286.598687)
			(xy 155.239984 -286.581235) (xy 155.288203 -286.571391) (xy 155.337378 -286.56941) (xy 155.386233 -286.575342)
			(xy 155.433504 -286.589034) (xy 155.477966 -286.610132) (xy 155.518469 -286.638088) (xy 155.553962 -286.67218)
			(xy 155.583527 -286.711524) (xy 155.606398 -286.755101) (xy 155.621982 -286.801782) (xy 155.629877 -286.850359)
			(xy 155.630372 -286.874966) (xy 155.96922 -286.874966) (xy 155.97318 -286.825912) (xy 155.984957 -286.778128)
			(xy 156.004248 -286.732852) (xy 156.030551 -286.691256) (xy 156.063186 -286.654419) (xy 156.101307 -286.623294)
			(xy 156.143928 -286.598687) (xy 156.189944 -286.581235) (xy 156.238163 -286.571391) (xy 156.287338 -286.56941)
			(xy 156.336193 -286.575342) (xy 156.383464 -286.589034) (xy 156.427926 -286.610132) (xy 156.468429 -286.638088)
			(xy 156.503922 -286.67218) (xy 156.533487 -286.711524) (xy 156.556358 -286.755101) (xy 156.571942 -286.801782)
			(xy 156.579837 -286.850359) (xy 156.580332 -286.874966) (xy 156.91918 -286.874966) (xy 156.92314 -286.825912)
			(xy 156.934917 -286.778128) (xy 156.954208 -286.732852) (xy 156.980511 -286.691256) (xy 157.013146 -286.654419)
			(xy 157.051267 -286.623294) (xy 157.093888 -286.598687) (xy 157.139904 -286.581235) (xy 157.188123 -286.571391)
			(xy 157.237298 -286.56941) (xy 157.286153 -286.575342) (xy 157.333424 -286.589034) (xy 157.377886 -286.610132)
			(xy 157.418389 -286.638088) (xy 157.453882 -286.67218) (xy 157.483447 -286.711524) (xy 157.506318 -286.755101)
			(xy 157.521902 -286.801782) (xy 157.529797 -286.850359) (xy 157.530292 -286.874966) (xy 157.86914 -286.874966)
			(xy 157.8731 -286.825912) (xy 157.884877 -286.778128) (xy 157.904168 -286.732852) (xy 157.930471 -286.691256)
			(xy 157.963106 -286.654419) (xy 158.001227 -286.623294) (xy 158.043848 -286.598687) (xy 158.089864 -286.581235)
			(xy 158.138083 -286.571391) (xy 158.187258 -286.56941) (xy 158.236113 -286.575342) (xy 158.283384 -286.589034)
			(xy 158.327846 -286.610132) (xy 158.368349 -286.638088) (xy 158.403842 -286.67218) (xy 158.433407 -286.711524)
			(xy 158.456278 -286.755101) (xy 158.471862 -286.801782) (xy 158.479757 -286.850359) (xy 158.480247 -286.874712)
			(xy 158.8191 -286.874712) (xy 158.82306 -286.825658) (xy 158.834837 -286.777874) (xy 158.854128 -286.732598)
			(xy 158.880431 -286.691002) (xy 158.913066 -286.654165) (xy 158.951187 -286.62304) (xy 158.993808 -286.598433)
			(xy 159.039824 -286.580981) (xy 159.088043 -286.571137) (xy 159.137218 -286.569156) (xy 159.186073 -286.575088)
			(xy 159.233344 -286.58878) (xy 159.277806 -286.609878) (xy 159.318309 -286.637834) (xy 159.353802 -286.671926)
			(xy 159.383367 -286.71127) (xy 159.406238 -286.754847) (xy 159.421822 -286.801528) (xy 159.429717 -286.850105)
			(xy 159.430212 -286.874712) (xy 159.76906 -286.874712) (xy 159.77302 -286.825658) (xy 159.784797 -286.777874)
			(xy 159.804088 -286.732598) (xy 159.830391 -286.691002) (xy 159.863026 -286.654165) (xy 159.901147 -286.62304)
			(xy 159.943768 -286.598433) (xy 159.989784 -286.580981) (xy 160.038003 -286.571137) (xy 160.087178 -286.569156)
			(xy 160.136033 -286.575088) (xy 160.183304 -286.58878) (xy 160.227766 -286.609878) (xy 160.268269 -286.637834)
			(xy 160.303762 -286.671926) (xy 160.333327 -286.71127) (xy 160.356198 -286.754847) (xy 160.371782 -286.801528)
			(xy 160.379677 -286.850105) (xy 160.380172 -286.874712) (xy 160.379677 -286.899319) (xy 160.371782 -286.947896)
			(xy 160.356198 -286.994577) (xy 160.333327 -287.038154) (xy 160.303762 -287.077498) (xy 160.268269 -287.11159)
			(xy 160.227766 -287.139546) (xy 160.183304 -287.160644) (xy 160.136033 -287.174336) (xy 160.087178 -287.180268)
			(xy 160.038003 -287.178287) (xy 159.989784 -287.168443) (xy 159.943768 -287.150991) (xy 159.901147 -287.126384)
			(xy 159.863026 -287.095259) (xy 159.830391 -287.058422) (xy 159.804088 -287.016826) (xy 159.784797 -286.97155)
			(xy 159.77302 -286.923766) (xy 159.76906 -286.874712) (xy 159.430212 -286.874712) (xy 159.429717 -286.899319)
			(xy 159.421822 -286.947896) (xy 159.406238 -286.994577) (xy 159.383367 -287.038154) (xy 159.353802 -287.077498)
			(xy 159.318309 -287.11159) (xy 159.277806 -287.139546) (xy 159.233344 -287.160644) (xy 159.186073 -287.174336)
			(xy 159.137218 -287.180268) (xy 159.088043 -287.178287) (xy 159.039824 -287.168443) (xy 158.993808 -287.150991)
			(xy 158.951187 -287.126384) (xy 158.913066 -287.095259) (xy 158.880431 -287.058422) (xy 158.854128 -287.016826)
			(xy 158.834837 -286.97155) (xy 158.82306 -286.923766) (xy 158.8191 -286.874712) (xy 158.480247 -286.874712)
			(xy 158.480252 -286.874966) (xy 158.479757 -286.899573) (xy 158.471862 -286.94815) (xy 158.456278 -286.994831)
			(xy 158.433407 -287.038408) (xy 158.403842 -287.077752) (xy 158.368349 -287.111844) (xy 158.327846 -287.1398)
			(xy 158.283384 -287.160898) (xy 158.236113 -287.17459) (xy 158.187258 -287.180522) (xy 158.138083 -287.178541)
			(xy 158.089864 -287.168697) (xy 158.043848 -287.151245) (xy 158.001227 -287.126638) (xy 157.963106 -287.095513)
			(xy 157.930471 -287.058676) (xy 157.904168 -287.01708) (xy 157.884877 -286.971804) (xy 157.8731 -286.92402)
			(xy 157.86914 -286.874966) (xy 157.530292 -286.874966) (xy 157.529797 -286.899573) (xy 157.521902 -286.94815)
			(xy 157.506318 -286.994831) (xy 157.483447 -287.038408) (xy 157.453882 -287.077752) (xy 157.418389 -287.111844)
			(xy 157.377886 -287.1398) (xy 157.333424 -287.160898) (xy 157.286153 -287.17459) (xy 157.237298 -287.180522)
			(xy 157.188123 -287.178541) (xy 157.139904 -287.168697) (xy 157.093888 -287.151245) (xy 157.051267 -287.126638)
			(xy 157.013146 -287.095513) (xy 156.980511 -287.058676) (xy 156.954208 -287.01708) (xy 156.934917 -286.971804)
			(xy 156.92314 -286.92402) (xy 156.91918 -286.874966) (xy 156.580332 -286.874966) (xy 156.579837 -286.899573)
			(xy 156.571942 -286.94815) (xy 156.556358 -286.994831) (xy 156.533487 -287.038408) (xy 156.503922 -287.077752)
			(xy 156.468429 -287.111844) (xy 156.427926 -287.1398) (xy 156.383464 -287.160898) (xy 156.336193 -287.17459)
			(xy 156.287338 -287.180522) (xy 156.238163 -287.178541) (xy 156.189944 -287.168697) (xy 156.143928 -287.151245)
			(xy 156.101307 -287.126638) (xy 156.063186 -287.095513) (xy 156.030551 -287.058676) (xy 156.004248 -287.01708)
			(xy 155.984957 -286.971804) (xy 155.97318 -286.92402) (xy 155.96922 -286.874966) (xy 155.630372 -286.874966)
			(xy 155.629877 -286.899573) (xy 155.621982 -286.94815) (xy 155.606398 -286.994831) (xy 155.583527 -287.038408)
			(xy 155.553962 -287.077752) (xy 155.518469 -287.111844) (xy 155.477966 -287.1398) (xy 155.433504 -287.160898)
			(xy 155.386233 -287.17459) (xy 155.337378 -287.180522) (xy 155.288203 -287.178541) (xy 155.239984 -287.168697)
			(xy 155.193968 -287.151245) (xy 155.151347 -287.126638) (xy 155.113226 -287.095513) (xy 155.080591 -287.058676)
			(xy 155.054288 -287.01708) (xy 155.034997 -286.971804) (xy 155.02322 -286.92402) (xy 155.01926 -286.874966)
			(xy 154.705812 -286.874966) (xy 154.705423 -286.897899) (xy 154.699087 -286.943324) (xy 154.686534 -286.987438)
			(xy 154.677618 -287.00857) (xy 154.673605 -287.018718) (xy 154.6737 -287.040519) (xy 154.682852 -287.060305)
			(xy 154.690826 -287.067752) (xy 155.448 -287.824926) (xy 156.91918 -287.824926) (xy 156.92314 -287.775872)
			(xy 156.934917 -287.728088) (xy 156.954208 -287.682812) (xy 156.980511 -287.641216) (xy 157.013146 -287.604379)
			(xy 157.051267 -287.573254) (xy 157.093888 -287.548647) (xy 157.139904 -287.531195) (xy 157.188123 -287.521351)
			(xy 157.237298 -287.51937) (xy 157.286153 -287.525302) (xy 157.333424 -287.538994) (xy 157.377886 -287.560092)
			(xy 157.418389 -287.588048) (xy 157.453882 -287.62214) (xy 157.483447 -287.661484) (xy 157.506318 -287.705061)
			(xy 157.521902 -287.751742) (xy 157.529797 -287.800319) (xy 157.530292 -287.824926) (xy 160.719274 -287.824926)
			(xy 160.723234 -287.775872) (xy 160.735011 -287.728088) (xy 160.754302 -287.682812) (xy 160.780605 -287.641216)
			(xy 160.81324 -287.604379) (xy 160.851361 -287.573254) (xy 160.893982 -287.548647) (xy 160.939998 -287.531195)
			(xy 160.988217 -287.521351) (xy 161.037392 -287.51937) (xy 161.086247 -287.525302) (xy 161.133518 -287.538994)
			(xy 161.17798 -287.560092) (xy 161.218483 -287.588048) (xy 161.253976 -287.62214) (xy 161.283541 -287.661484)
			(xy 161.306412 -287.705061) (xy 161.321996 -287.751742) (xy 161.329891 -287.800319) (xy 161.330386 -287.824926)
			(xy 161.329891 -287.849533) (xy 161.321996 -287.89811) (xy 161.306412 -287.944791) (xy 161.283541 -287.988368)
			(xy 161.253976 -288.027712) (xy 161.218483 -288.061804) (xy 161.17798 -288.08976) (xy 161.133518 -288.110858)
			(xy 161.086247 -288.12455) (xy 161.037392 -288.130482) (xy 160.988217 -288.128501) (xy 160.939998 -288.118657)
			(xy 160.893982 -288.101205) (xy 160.851361 -288.076598) (xy 160.81324 -288.045473) (xy 160.780605 -288.008636)
			(xy 160.754302 -287.96704) (xy 160.735011 -287.921764) (xy 160.723234 -287.87398) (xy 160.719274 -287.824926)
			(xy 157.530292 -287.824926) (xy 157.529797 -287.849533) (xy 157.521902 -287.89811) (xy 157.506318 -287.944791)
			(xy 157.483447 -287.988368) (xy 157.453882 -288.027712) (xy 157.418389 -288.061804) (xy 157.377886 -288.08976)
			(xy 157.333424 -288.110858) (xy 157.286153 -288.12455) (xy 157.237298 -288.130482) (xy 157.188123 -288.128501)
			(xy 157.139904 -288.118657) (xy 157.093888 -288.101205) (xy 157.051267 -288.076598) (xy 157.013146 -288.045473)
			(xy 156.980511 -288.008636) (xy 156.954208 -287.96704) (xy 156.934917 -287.921764) (xy 156.92314 -287.87398)
			(xy 156.91918 -287.824926) (xy 155.448 -287.824926) (xy 156.084778 -288.461704) (xy 156.090417 -288.466886)
			(xy 156.103979 -288.473978) (xy 156.111448 -288.475674) (xy 156.111448 -288.475928) (xy 156.118844 -288.477016)
			(xy 156.133692 -288.475339) (xy 156.140658 -288.472626) (xy 156.14142 -288.472372) (xy 156.162555 -288.463463)
			(xy 156.206667 -288.450904) (xy 156.252091 -288.444558) (xy 156.275024 -288.444178) (xy 156.30101 -288.444689)
			(xy 156.352343 -288.452823) (xy 156.401771 -288.468886) (xy 156.448078 -288.492483) (xy 156.490124 -288.523033)
			(xy 156.526874 -288.559783) (xy 156.557423 -288.60183) (xy 156.581018 -288.648138) (xy 156.59708 -288.697567)
			(xy 156.605211 -288.7489) (xy 156.605732 -288.774886) (xy 158.8191 -288.774886) (xy 158.82306 -288.725832)
			(xy 158.834837 -288.678048) (xy 158.854128 -288.632772) (xy 158.880431 -288.591176) (xy 158.913066 -288.554339)
			(xy 158.951187 -288.523214) (xy 158.993808 -288.498607) (xy 159.039824 -288.481155) (xy 159.088043 -288.471311)
			(xy 159.137218 -288.46933) (xy 159.186073 -288.475262) (xy 159.233344 -288.488954) (xy 159.277806 -288.510052)
			(xy 159.318309 -288.538008) (xy 159.353802 -288.5721) (xy 159.383367 -288.611444) (xy 159.406238 -288.655021)
			(xy 159.421822 -288.701702) (xy 159.429717 -288.750279) (xy 159.430212 -288.774886) (xy 159.76906 -288.774886)
			(xy 159.77302 -288.725832) (xy 159.784797 -288.678048) (xy 159.804088 -288.632772) (xy 159.830391 -288.591176)
			(xy 159.863026 -288.554339) (xy 159.901147 -288.523214) (xy 159.943768 -288.498607) (xy 159.989784 -288.481155)
			(xy 160.038003 -288.471311) (xy 160.087178 -288.46933) (xy 160.136033 -288.475262) (xy 160.183304 -288.488954)
			(xy 160.227766 -288.510052) (xy 160.268269 -288.538008) (xy 160.303762 -288.5721) (xy 160.333327 -288.611444)
			(xy 160.356198 -288.655021) (xy 160.371782 -288.701702) (xy 160.379677 -288.750279) (xy 160.380172 -288.774886)
			(xy 160.719274 -288.774886) (xy 160.723234 -288.725832) (xy 160.735011 -288.678048) (xy 160.754302 -288.632772)
			(xy 160.780605 -288.591176) (xy 160.81324 -288.554339) (xy 160.851361 -288.523214) (xy 160.893982 -288.498607)
			(xy 160.939998 -288.481155) (xy 160.988217 -288.471311) (xy 161.037392 -288.46933) (xy 161.086247 -288.475262)
			(xy 161.133518 -288.488954) (xy 161.17798 -288.510052) (xy 161.218483 -288.538008) (xy 161.253976 -288.5721)
			(xy 161.283541 -288.611444) (xy 161.306412 -288.655021) (xy 161.321996 -288.701702) (xy 161.329891 -288.750279)
			(xy 161.330386 -288.774886) (xy 161.669234 -288.774886) (xy 161.673194 -288.725832) (xy 161.684971 -288.678048)
			(xy 161.704262 -288.632772) (xy 161.730565 -288.591176) (xy 161.7632 -288.554339) (xy 161.801321 -288.523214)
			(xy 161.843942 -288.498607) (xy 161.889958 -288.481155) (xy 161.938177 -288.471311) (xy 161.987352 -288.46933)
			(xy 162.036207 -288.475262) (xy 162.083478 -288.488954) (xy 162.12794 -288.510052) (xy 162.168443 -288.538008)
			(xy 162.203936 -288.5721) (xy 162.233501 -288.611444) (xy 162.256372 -288.655021) (xy 162.271956 -288.701702)
			(xy 162.279851 -288.750279) (xy 162.280346 -288.774886) (xy 162.279851 -288.799493) (xy 162.271956 -288.84807)
			(xy 162.256372 -288.894751) (xy 162.233501 -288.938328) (xy 162.203936 -288.977672) (xy 162.168443 -289.011764)
			(xy 162.12794 -289.03972) (xy 162.083478 -289.060818) (xy 162.036207 -289.07451) (xy 161.987352 -289.080442)
			(xy 161.938177 -289.078461) (xy 161.889958 -289.068617) (xy 161.843942 -289.051165) (xy 161.801321 -289.026558)
			(xy 161.7632 -288.995433) (xy 161.730565 -288.958596) (xy 161.704262 -288.917) (xy 161.684971 -288.871724)
			(xy 161.673194 -288.82394) (xy 161.669234 -288.774886) (xy 161.330386 -288.774886) (xy 161.329891 -288.799493)
			(xy 161.321996 -288.84807) (xy 161.306412 -288.894751) (xy 161.283541 -288.938328) (xy 161.253976 -288.977672)
			(xy 161.218483 -289.011764) (xy 161.17798 -289.03972) (xy 161.133518 -289.060818) (xy 161.086247 -289.07451)
			(xy 161.037392 -289.080442) (xy 160.988217 -289.078461) (xy 160.939998 -289.068617) (xy 160.893982 -289.051165)
			(xy 160.851361 -289.026558) (xy 160.81324 -288.995433) (xy 160.780605 -288.958596) (xy 160.754302 -288.917)
			(xy 160.735011 -288.871724) (xy 160.723234 -288.82394) (xy 160.719274 -288.774886) (xy 160.380172 -288.774886)
			(xy 160.379677 -288.799493) (xy 160.371782 -288.84807) (xy 160.356198 -288.894751) (xy 160.333327 -288.938328)
			(xy 160.303762 -288.977672) (xy 160.268269 -289.011764) (xy 160.227766 -289.03972) (xy 160.183304 -289.060818)
			(xy 160.136033 -289.07451) (xy 160.087178 -289.080442) (xy 160.038003 -289.078461) (xy 159.989784 -289.068617)
			(xy 159.943768 -289.051165) (xy 159.901147 -289.026558) (xy 159.863026 -288.995433) (xy 159.830391 -288.958596)
			(xy 159.804088 -288.917) (xy 159.784797 -288.871724) (xy 159.77302 -288.82394) (xy 159.76906 -288.774886)
			(xy 159.430212 -288.774886) (xy 159.429717 -288.799493) (xy 159.421822 -288.84807) (xy 159.406238 -288.894751)
			(xy 159.383367 -288.938328) (xy 159.353802 -288.977672) (xy 159.318309 -289.011764) (xy 159.277806 -289.03972)
			(xy 159.233344 -289.060818) (xy 159.186073 -289.07451) (xy 159.137218 -289.080442) (xy 159.088043 -289.078461)
			(xy 159.039824 -289.068617) (xy 158.993808 -289.051165) (xy 158.951187 -289.026558) (xy 158.913066 -288.995433)
			(xy 158.880431 -288.958596) (xy 158.854128 -288.917) (xy 158.834837 -288.871724) (xy 158.82306 -288.82394)
			(xy 158.8191 -288.774886) (xy 156.605732 -288.774886) (xy 156.605341 -288.797818) (xy 156.599004 -288.843243)
			(xy 156.586449 -288.887356) (xy 156.577538 -288.90849) (xy 156.573528 -288.918637) (xy 156.57363 -288.940432)
			(xy 156.582789 -288.960209) (xy 156.590746 -288.967672) (xy 157.034738 -289.411664) (xy 157.040377 -289.416845)
			(xy 157.053939 -289.42394) (xy 157.061408 -289.425634) (xy 157.061408 -289.425888) (xy 157.068805 -289.426982)
			(xy 157.083658 -289.425317) (xy 157.090618 -289.422586) (xy 157.09138 -289.422332) (xy 157.112516 -289.413428)
			(xy 157.156629 -289.400878) (xy 157.202052 -289.394541) (xy 157.224984 -289.394138) (xy 157.250973 -289.39462)
			(xy 157.302311 -289.40275) (xy 157.351744 -289.418811) (xy 157.398056 -289.442409) (xy 157.440106 -289.472961)
			(xy 157.476858 -289.509717) (xy 157.507407 -289.551769) (xy 157.531001 -289.598083) (xy 157.547057 -289.647519)
			(xy 157.555182 -289.698857) (xy 157.555692 -289.724846) (xy 157.86914 -289.724846) (xy 157.8731 -289.675792)
			(xy 157.884877 -289.628008) (xy 157.904168 -289.582732) (xy 157.930471 -289.541136) (xy 157.963106 -289.504299)
			(xy 158.001227 -289.473174) (xy 158.043848 -289.448567) (xy 158.089864 -289.431115) (xy 158.138083 -289.421271)
			(xy 158.187258 -289.41929) (xy 158.236113 -289.425222) (xy 158.283384 -289.438914) (xy 158.327846 -289.460012)
			(xy 158.368349 -289.487968) (xy 158.403842 -289.52206) (xy 158.433407 -289.561404) (xy 158.456278 -289.604981)
			(xy 158.471862 -289.651662) (xy 158.479757 -289.700239) (xy 158.480252 -289.724846) (xy 158.8191 -289.724846)
			(xy 158.82306 -289.675792) (xy 158.834837 -289.628008) (xy 158.854128 -289.582732) (xy 158.880431 -289.541136)
			(xy 158.913066 -289.504299) (xy 158.951187 -289.473174) (xy 158.993808 -289.448567) (xy 159.039824 -289.431115)
			(xy 159.088043 -289.421271) (xy 159.137218 -289.41929) (xy 159.186073 -289.425222) (xy 159.233344 -289.438914)
			(xy 159.277806 -289.460012) (xy 159.318309 -289.487968) (xy 159.353802 -289.52206) (xy 159.383367 -289.561404)
			(xy 159.406238 -289.604981) (xy 159.421822 -289.651662) (xy 159.429717 -289.700239) (xy 159.430212 -289.724846)
			(xy 159.76906 -289.724846) (xy 159.77302 -289.675792) (xy 159.784797 -289.628008) (xy 159.804088 -289.582732)
			(xy 159.830391 -289.541136) (xy 159.863026 -289.504299) (xy 159.901147 -289.473174) (xy 159.943768 -289.448567)
			(xy 159.989784 -289.431115) (xy 160.038003 -289.421271) (xy 160.087178 -289.41929) (xy 160.136033 -289.425222)
			(xy 160.183304 -289.438914) (xy 160.227766 -289.460012) (xy 160.268269 -289.487968) (xy 160.303762 -289.52206)
			(xy 160.333327 -289.561404) (xy 160.356198 -289.604981) (xy 160.371782 -289.651662) (xy 160.379677 -289.700239)
			(xy 160.380172 -289.724846) (xy 160.719274 -289.724846) (xy 160.723234 -289.675792) (xy 160.735011 -289.628008)
			(xy 160.754302 -289.582732) (xy 160.780605 -289.541136) (xy 160.81324 -289.504299) (xy 160.851361 -289.473174)
			(xy 160.893982 -289.448567) (xy 160.939998 -289.431115) (xy 160.988217 -289.421271) (xy 161.037392 -289.41929)
			(xy 161.086247 -289.425222) (xy 161.133518 -289.438914) (xy 161.17798 -289.460012) (xy 161.218483 -289.487968)
			(xy 161.253976 -289.52206) (xy 161.283541 -289.561404) (xy 161.306412 -289.604981) (xy 161.321996 -289.651662)
			(xy 161.329891 -289.700239) (xy 161.330386 -289.724846) (xy 161.669234 -289.724846) (xy 161.673194 -289.675792)
			(xy 161.684971 -289.628008) (xy 161.704262 -289.582732) (xy 161.730565 -289.541136) (xy 161.7632 -289.504299)
			(xy 161.801321 -289.473174) (xy 161.843942 -289.448567) (xy 161.889958 -289.431115) (xy 161.938177 -289.421271)
			(xy 161.987352 -289.41929) (xy 162.036207 -289.425222) (xy 162.083478 -289.438914) (xy 162.12794 -289.460012)
			(xy 162.168443 -289.487968) (xy 162.203936 -289.52206) (xy 162.233501 -289.561404) (xy 162.256372 -289.604981)
			(xy 162.271956 -289.651662) (xy 162.279851 -289.700239) (xy 162.280346 -289.724846) (xy 162.619194 -289.724846)
			(xy 162.623154 -289.675792) (xy 162.634931 -289.628008) (xy 162.654222 -289.582732) (xy 162.680525 -289.541136)
			(xy 162.71316 -289.504299) (xy 162.751281 -289.473174) (xy 162.793902 -289.448567) (xy 162.839918 -289.431115)
			(xy 162.888137 -289.421271) (xy 162.937312 -289.41929) (xy 162.986167 -289.425222) (xy 163.033438 -289.438914)
			(xy 163.0779 -289.460012) (xy 163.118403 -289.487968) (xy 163.153896 -289.52206) (xy 163.183461 -289.561404)
			(xy 163.206332 -289.604981) (xy 163.221916 -289.651662) (xy 163.229811 -289.700239) (xy 163.230306 -289.724846)
			(xy 163.229811 -289.749453) (xy 163.221916 -289.79803) (xy 163.206332 -289.844711) (xy 163.183461 -289.888288)
			(xy 163.153896 -289.927632) (xy 163.118403 -289.961724) (xy 163.0779 -289.98968) (xy 163.033438 -290.010778)
			(xy 162.986167 -290.02447) (xy 162.937312 -290.030402) (xy 162.888137 -290.028421) (xy 162.839918 -290.018577)
			(xy 162.793902 -290.001125) (xy 162.751281 -289.976518) (xy 162.71316 -289.945393) (xy 162.680525 -289.908556)
			(xy 162.654222 -289.86696) (xy 162.634931 -289.821684) (xy 162.623154 -289.7739) (xy 162.619194 -289.724846)
			(xy 162.280346 -289.724846) (xy 162.279851 -289.749453) (xy 162.271956 -289.79803) (xy 162.256372 -289.844711)
			(xy 162.233501 -289.888288) (xy 162.203936 -289.927632) (xy 162.168443 -289.961724) (xy 162.12794 -289.98968)
			(xy 162.083478 -290.010778) (xy 162.036207 -290.02447) (xy 161.987352 -290.030402) (xy 161.938177 -290.028421)
			(xy 161.889958 -290.018577) (xy 161.843942 -290.001125) (xy 161.801321 -289.976518) (xy 161.7632 -289.945393)
			(xy 161.730565 -289.908556) (xy 161.704262 -289.86696) (xy 161.684971 -289.821684) (xy 161.673194 -289.7739)
			(xy 161.669234 -289.724846) (xy 161.330386 -289.724846) (xy 161.329891 -289.749453) (xy 161.321996 -289.79803)
			(xy 161.306412 -289.844711) (xy 161.283541 -289.888288) (xy 161.253976 -289.927632) (xy 161.218483 -289.961724)
			(xy 161.17798 -289.98968) (xy 161.133518 -290.010778) (xy 161.086247 -290.02447) (xy 161.037392 -290.030402)
			(xy 160.988217 -290.028421) (xy 160.939998 -290.018577) (xy 160.893982 -290.001125) (xy 160.851361 -289.976518)
			(xy 160.81324 -289.945393) (xy 160.780605 -289.908556) (xy 160.754302 -289.86696) (xy 160.735011 -289.821684)
			(xy 160.723234 -289.7739) (xy 160.719274 -289.724846) (xy 160.380172 -289.724846) (xy 160.379677 -289.749453)
			(xy 160.371782 -289.79803) (xy 160.356198 -289.844711) (xy 160.333327 -289.888288) (xy 160.303762 -289.927632)
			(xy 160.268269 -289.961724) (xy 160.227766 -289.98968) (xy 160.183304 -290.010778) (xy 160.136033 -290.02447)
			(xy 160.087178 -290.030402) (xy 160.038003 -290.028421) (xy 159.989784 -290.018577) (xy 159.943768 -290.001125)
			(xy 159.901147 -289.976518) (xy 159.863026 -289.945393) (xy 159.830391 -289.908556) (xy 159.804088 -289.86696)
			(xy 159.784797 -289.821684) (xy 159.77302 -289.7739) (xy 159.76906 -289.724846) (xy 159.430212 -289.724846)
			(xy 159.429717 -289.749453) (xy 159.421822 -289.79803) (xy 159.406238 -289.844711) (xy 159.383367 -289.888288)
			(xy 159.353802 -289.927632) (xy 159.318309 -289.961724) (xy 159.277806 -289.98968) (xy 159.233344 -290.010778)
			(xy 159.186073 -290.02447) (xy 159.137218 -290.030402) (xy 159.088043 -290.028421) (xy 159.039824 -290.018577)
			(xy 158.993808 -290.001125) (xy 158.951187 -289.976518) (xy 158.913066 -289.945393) (xy 158.880431 -289.908556)
			(xy 158.854128 -289.86696) (xy 158.834837 -289.821684) (xy 158.82306 -289.7739) (xy 158.8191 -289.724846)
			(xy 158.480252 -289.724846) (xy 158.479757 -289.749453) (xy 158.471862 -289.79803) (xy 158.456278 -289.844711)
			(xy 158.433407 -289.888288) (xy 158.403842 -289.927632) (xy 158.368349 -289.961724) (xy 158.327846 -289.98968)
			(xy 158.283384 -290.010778) (xy 158.236113 -290.02447) (xy 158.187258 -290.030402) (xy 158.138083 -290.028421)
			(xy 158.089864 -290.018577) (xy 158.043848 -290.001125) (xy 158.001227 -289.976518) (xy 157.963106 -289.945393)
			(xy 157.930471 -289.908556) (xy 157.904168 -289.86696) (xy 157.884877 -289.821684) (xy 157.8731 -289.7739)
			(xy 157.86914 -289.724846) (xy 157.555692 -289.724846) (xy 157.555304 -289.747779) (xy 157.548971 -289.793205)
			(xy 157.536419 -289.83732) (xy 157.527498 -289.85845) (xy 157.523504 -289.868594) (xy 157.523628 -289.890374)
			(xy 157.532792 -289.910132) (xy 157.540706 -289.917632) (xy 157.984698 -290.361624) (xy 157.990333 -290.366813)
			(xy 158.003893 -290.373923) (xy 158.011368 -290.375594) (xy 158.011368 -290.375848) (xy 158.018764 -290.376933)
			(xy 158.03361 -290.375251) (xy 158.040578 -290.372546) (xy 158.04134 -290.372292) (xy 158.062475 -290.363384)
			(xy 158.106588 -290.350826) (xy 158.152012 -290.344483) (xy 158.174944 -290.344098) (xy 158.200929 -290.344611)
			(xy 158.252258 -290.352747) (xy 158.301682 -290.368812) (xy 158.347985 -290.39241) (xy 158.390026 -290.422961)
			(xy 158.426772 -290.459712) (xy 158.457316 -290.501758) (xy 158.480907 -290.548064) (xy 158.496965 -290.597491)
			(xy 158.505093 -290.648821) (xy 158.505652 -290.674806) (xy 158.8191 -290.674806) (xy 158.82306 -290.625752)
			(xy 158.834837 -290.577968) (xy 158.854128 -290.532692) (xy 158.880431 -290.491096) (xy 158.913066 -290.454259)
			(xy 158.951187 -290.423134) (xy 158.993808 -290.398527) (xy 159.039824 -290.381075) (xy 159.088043 -290.371231)
			(xy 159.137218 -290.36925) (xy 159.186073 -290.375182) (xy 159.233344 -290.388874) (xy 159.277806 -290.409972)
			(xy 159.318309 -290.437928) (xy 159.353802 -290.47202) (xy 159.383367 -290.511364) (xy 159.406238 -290.554941)
			(xy 159.421822 -290.601622) (xy 159.429717 -290.650199) (xy 159.430212 -290.674806) (xy 159.76906 -290.674806)
			(xy 159.77302 -290.625752) (xy 159.784797 -290.577968) (xy 159.804088 -290.532692) (xy 159.830391 -290.491096)
			(xy 159.863026 -290.454259) (xy 159.901147 -290.423134) (xy 159.943768 -290.398527) (xy 159.989784 -290.381075)
			(xy 160.038003 -290.371231) (xy 160.087178 -290.36925) (xy 160.136033 -290.375182) (xy 160.183304 -290.388874)
			(xy 160.227766 -290.409972) (xy 160.268269 -290.437928) (xy 160.303762 -290.47202) (xy 160.333327 -290.511364)
			(xy 160.356198 -290.554941) (xy 160.371782 -290.601622) (xy 160.379677 -290.650199) (xy 160.380172 -290.674806)
			(xy 160.719274 -290.674806) (xy 160.723234 -290.625752) (xy 160.735011 -290.577968) (xy 160.754302 -290.532692)
			(xy 160.780605 -290.491096) (xy 160.81324 -290.454259) (xy 160.851361 -290.423134) (xy 160.893982 -290.398527)
			(xy 160.939998 -290.381075) (xy 160.988217 -290.371231) (xy 161.037392 -290.36925) (xy 161.086247 -290.375182)
			(xy 161.133518 -290.388874) (xy 161.17798 -290.409972) (xy 161.218483 -290.437928) (xy 161.253976 -290.47202)
			(xy 161.283541 -290.511364) (xy 161.306412 -290.554941) (xy 161.321996 -290.601622) (xy 161.329891 -290.650199)
			(xy 161.330386 -290.674806) (xy 161.669234 -290.674806) (xy 161.673194 -290.625752) (xy 161.684971 -290.577968)
			(xy 161.704262 -290.532692) (xy 161.730565 -290.491096) (xy 161.7632 -290.454259) (xy 161.801321 -290.423134)
			(xy 161.843942 -290.398527) (xy 161.889958 -290.381075) (xy 161.938177 -290.371231) (xy 161.987352 -290.36925)
			(xy 162.036207 -290.375182) (xy 162.083478 -290.388874) (xy 162.12794 -290.409972) (xy 162.168443 -290.437928)
			(xy 162.203936 -290.47202) (xy 162.233501 -290.511364) (xy 162.256372 -290.554941) (xy 162.271956 -290.601622)
			(xy 162.279851 -290.650199) (xy 162.280346 -290.674806) (xy 162.619194 -290.674806) (xy 162.623154 -290.625752)
			(xy 162.634931 -290.577968) (xy 162.654222 -290.532692) (xy 162.680525 -290.491096) (xy 162.71316 -290.454259)
			(xy 162.751281 -290.423134) (xy 162.793902 -290.398527) (xy 162.839918 -290.381075) (xy 162.888137 -290.371231)
			(xy 162.937312 -290.36925) (xy 162.986167 -290.375182) (xy 163.033438 -290.388874) (xy 163.0779 -290.409972)
			(xy 163.118403 -290.437928) (xy 163.153896 -290.47202) (xy 163.183461 -290.511364) (xy 163.206332 -290.554941)
			(xy 163.221916 -290.601622) (xy 163.229811 -290.650199) (xy 163.230306 -290.674806) (xy 163.229811 -290.699413)
			(xy 163.221916 -290.74799) (xy 163.206332 -290.794671) (xy 163.183461 -290.838248) (xy 163.153896 -290.877592)
			(xy 163.118403 -290.911684) (xy 163.0779 -290.93964) (xy 163.033438 -290.960738) (xy 162.986167 -290.97443)
			(xy 162.937312 -290.980362) (xy 162.888137 -290.978381) (xy 162.839918 -290.968537) (xy 162.793902 -290.951085)
			(xy 162.751281 -290.926478) (xy 162.71316 -290.895353) (xy 162.680525 -290.858516) (xy 162.654222 -290.81692)
			(xy 162.634931 -290.771644) (xy 162.623154 -290.72386) (xy 162.619194 -290.674806) (xy 162.280346 -290.674806)
			(xy 162.279851 -290.699413) (xy 162.271956 -290.74799) (xy 162.256372 -290.794671) (xy 162.233501 -290.838248)
			(xy 162.203936 -290.877592) (xy 162.168443 -290.911684) (xy 162.12794 -290.93964) (xy 162.083478 -290.960738)
			(xy 162.036207 -290.97443) (xy 161.987352 -290.980362) (xy 161.938177 -290.978381) (xy 161.889958 -290.968537)
			(xy 161.843942 -290.951085) (xy 161.801321 -290.926478) (xy 161.7632 -290.895353) (xy 161.730565 -290.858516)
			(xy 161.704262 -290.81692) (xy 161.684971 -290.771644) (xy 161.673194 -290.72386) (xy 161.669234 -290.674806)
			(xy 161.330386 -290.674806) (xy 161.329891 -290.699413) (xy 161.321996 -290.74799) (xy 161.306412 -290.794671)
			(xy 161.283541 -290.838248) (xy 161.253976 -290.877592) (xy 161.218483 -290.911684) (xy 161.17798 -290.93964)
			(xy 161.133518 -290.960738) (xy 161.086247 -290.97443) (xy 161.037392 -290.980362) (xy 160.988217 -290.978381)
			(xy 160.939998 -290.968537) (xy 160.893982 -290.951085) (xy 160.851361 -290.926478) (xy 160.81324 -290.895353)
			(xy 160.780605 -290.858516) (xy 160.754302 -290.81692) (xy 160.735011 -290.771644) (xy 160.723234 -290.72386)
			(xy 160.719274 -290.674806) (xy 160.380172 -290.674806) (xy 160.379677 -290.699413) (xy 160.371782 -290.74799)
			(xy 160.356198 -290.794671) (xy 160.333327 -290.838248) (xy 160.303762 -290.877592) (xy 160.268269 -290.911684)
			(xy 160.227766 -290.93964) (xy 160.183304 -290.960738) (xy 160.136033 -290.97443) (xy 160.087178 -290.980362)
			(xy 160.038003 -290.978381) (xy 159.989784 -290.968537) (xy 159.943768 -290.951085) (xy 159.901147 -290.926478)
			(xy 159.863026 -290.895353) (xy 159.830391 -290.858516) (xy 159.804088 -290.81692) (xy 159.784797 -290.771644)
			(xy 159.77302 -290.72386) (xy 159.76906 -290.674806) (xy 159.430212 -290.674806) (xy 159.429717 -290.699413)
			(xy 159.421822 -290.74799) (xy 159.406238 -290.794671) (xy 159.383367 -290.838248) (xy 159.353802 -290.877592)
			(xy 159.318309 -290.911684) (xy 159.277806 -290.93964) (xy 159.233344 -290.960738) (xy 159.186073 -290.97443)
			(xy 159.137218 -290.980362) (xy 159.088043 -290.978381) (xy 159.039824 -290.968537) (xy 158.993808 -290.951085)
			(xy 158.951187 -290.926478) (xy 158.913066 -290.895353) (xy 158.880431 -290.858516) (xy 158.854128 -290.81692)
			(xy 158.834837 -290.771644) (xy 158.82306 -290.72386) (xy 158.8191 -290.674806) (xy 158.505652 -290.674806)
			(xy 158.50526 -290.697738) (xy 158.498918 -290.743161) (xy 158.486358 -290.787272) (xy 158.477458 -290.80841)
			(xy 158.473452 -290.818555) (xy 158.473561 -290.840345) (xy 158.482726 -290.860113) (xy 158.490666 -290.867592)
			(xy 158.934658 -291.311584) (xy 158.940295 -291.31677) (xy 158.953856 -291.32387) (xy 158.961328 -291.325554)
			(xy 158.961328 -291.325808) (xy 158.968725 -291.326898) (xy 158.983575 -291.325229) (xy 158.990538 -291.322506)
			(xy 158.9913 -291.322252) (xy 159.012436 -291.313349) (xy 159.056549 -291.300801) (xy 159.101973 -291.294466)
			(xy 159.124904 -291.294058) (xy 159.150892 -291.294568) (xy 159.202228 -291.302699) (xy 159.25166 -291.31876)
			(xy 159.297972 -291.342355) (xy 159.340022 -291.372904) (xy 159.376776 -291.409655) (xy 159.407329 -291.451703)
			(xy 159.430929 -291.498012) (xy 159.446994 -291.547443) (xy 159.45513 -291.598778) (xy 159.455612 -291.624766)
			(xy 159.76906 -291.624766) (xy 159.77302 -291.575712) (xy 159.784797 -291.527928) (xy 159.804088 -291.482652)
			(xy 159.830391 -291.441056) (xy 159.863026 -291.404219) (xy 159.901147 -291.373094) (xy 159.943768 -291.348487)
			(xy 159.989784 -291.331035) (xy 160.038003 -291.321191) (xy 160.087178 -291.31921) (xy 160.136033 -291.325142)
			(xy 160.183304 -291.338834) (xy 160.227766 -291.359932) (xy 160.268269 -291.387888) (xy 160.303762 -291.42198)
			(xy 160.333327 -291.461324) (xy 160.356198 -291.504901) (xy 160.371782 -291.551582) (xy 160.379677 -291.600159)
			(xy 160.380172 -291.624766) (xy 160.719274 -291.624766) (xy 160.723234 -291.575712) (xy 160.735011 -291.527928)
			(xy 160.754302 -291.482652) (xy 160.780605 -291.441056) (xy 160.81324 -291.404219) (xy 160.851361 -291.373094)
			(xy 160.893982 -291.348487) (xy 160.939998 -291.331035) (xy 160.988217 -291.321191) (xy 161.037392 -291.31921)
			(xy 161.086247 -291.325142) (xy 161.133518 -291.338834) (xy 161.17798 -291.359932) (xy 161.218483 -291.387888)
			(xy 161.253976 -291.42198) (xy 161.283541 -291.461324) (xy 161.306412 -291.504901) (xy 161.321996 -291.551582)
			(xy 161.329891 -291.600159) (xy 161.330386 -291.624766) (xy 161.669234 -291.624766) (xy 161.673194 -291.575712)
			(xy 161.684971 -291.527928) (xy 161.704262 -291.482652) (xy 161.730565 -291.441056) (xy 161.7632 -291.404219)
			(xy 161.801321 -291.373094) (xy 161.843942 -291.348487) (xy 161.889958 -291.331035) (xy 161.938177 -291.321191)
			(xy 161.987352 -291.31921) (xy 162.036207 -291.325142) (xy 162.083478 -291.338834) (xy 162.12794 -291.359932)
			(xy 162.168443 -291.387888) (xy 162.203936 -291.42198) (xy 162.233501 -291.461324) (xy 162.256372 -291.504901)
			(xy 162.271956 -291.551582) (xy 162.279851 -291.600159) (xy 162.280346 -291.624766) (xy 162.279851 -291.649373)
			(xy 162.271956 -291.69795) (xy 162.256372 -291.744631) (xy 162.233501 -291.788208) (xy 162.203936 -291.827552)
			(xy 162.168443 -291.861644) (xy 162.12794 -291.8896) (xy 162.083478 -291.910698) (xy 162.036207 -291.92439)
			(xy 161.987352 -291.930322) (xy 161.938177 -291.928341) (xy 161.889958 -291.918497) (xy 161.843942 -291.901045)
			(xy 161.801321 -291.876438) (xy 161.7632 -291.845313) (xy 161.730565 -291.808476) (xy 161.704262 -291.76688)
			(xy 161.684971 -291.721604) (xy 161.673194 -291.67382) (xy 161.669234 -291.624766) (xy 161.330386 -291.624766)
			(xy 161.329891 -291.649373) (xy 161.321996 -291.69795) (xy 161.306412 -291.744631) (xy 161.283541 -291.788208)
			(xy 161.253976 -291.827552) (xy 161.218483 -291.861644) (xy 161.17798 -291.8896) (xy 161.133518 -291.910698)
			(xy 161.086247 -291.92439) (xy 161.037392 -291.930322) (xy 160.988217 -291.928341) (xy 160.939998 -291.918497)
			(xy 160.893982 -291.901045) (xy 160.851361 -291.876438) (xy 160.81324 -291.845313) (xy 160.780605 -291.808476)
			(xy 160.754302 -291.76688) (xy 160.735011 -291.721604) (xy 160.723234 -291.67382) (xy 160.719274 -291.624766)
			(xy 160.380172 -291.624766) (xy 160.379677 -291.649373) (xy 160.371782 -291.69795) (xy 160.356198 -291.744631)
			(xy 160.333327 -291.788208) (xy 160.303762 -291.827552) (xy 160.268269 -291.861644) (xy 160.227766 -291.8896)
			(xy 160.183304 -291.910698) (xy 160.136033 -291.92439) (xy 160.087178 -291.930322) (xy 160.038003 -291.928341)
			(xy 159.989784 -291.918497) (xy 159.943768 -291.901045) (xy 159.901147 -291.876438) (xy 159.863026 -291.845313)
			(xy 159.830391 -291.808476) (xy 159.804088 -291.76688) (xy 159.784797 -291.721604) (xy 159.77302 -291.67382)
			(xy 159.76906 -291.624766) (xy 159.455612 -291.624766) (xy 159.455223 -291.647699) (xy 159.448887 -291.693124)
			(xy 159.436334 -291.737238) (xy 159.427418 -291.75837) (xy 159.423405 -291.768518) (xy 159.4235 -291.790319)
			(xy 159.432652 -291.810105) (xy 159.440626 -291.817552) (xy 159.884872 -292.261798) (xy 159.889853 -292.266435)
			(xy 159.9017 -292.273122) (xy 159.90824 -292.275006) (xy 159.919162 -292.277292) (xy 159.934402 -292.275514)
			(xy 159.94126 -292.272466) (xy 159.962396 -292.26356) (xy 160.006508 -292.251006) (xy 160.051932 -292.244666)
			(xy 160.074864 -292.244272) (xy 160.100856 -292.244752) (xy 160.1522 -292.252879) (xy 160.20164 -292.268938)
			(xy 160.24796 -292.292533) (xy 160.290018 -292.323085) (xy 160.326779 -292.359839) (xy 160.357337 -292.401892)
			(xy 160.380941 -292.448208) (xy 160.397008 -292.497646) (xy 160.405143 -292.548988) (xy 160.405572 -292.57498)
			(xy 160.719274 -292.57498) (xy 160.723234 -292.525926) (xy 160.735011 -292.478142) (xy 160.754302 -292.432866)
			(xy 160.780605 -292.39127) (xy 160.81324 -292.354433) (xy 160.851361 -292.323308) (xy 160.893982 -292.298701)
			(xy 160.939998 -292.281249) (xy 160.988217 -292.271405) (xy 161.037392 -292.269424) (xy 161.086247 -292.275356)
			(xy 161.133518 -292.289048) (xy 161.17798 -292.310146) (xy 161.218483 -292.338102) (xy 161.253976 -292.372194)
			(xy 161.283541 -292.411538) (xy 161.306412 -292.455115) (xy 161.321996 -292.501796) (xy 161.329891 -292.550373)
			(xy 161.330386 -292.57498) (xy 161.669234 -292.57498) (xy 161.673194 -292.525926) (xy 161.684971 -292.478142)
			(xy 161.704262 -292.432866) (xy 161.730565 -292.39127) (xy 161.7632 -292.354433) (xy 161.801321 -292.323308)
			(xy 161.843942 -292.298701) (xy 161.889958 -292.281249) (xy 161.938177 -292.271405) (xy 161.987352 -292.269424)
			(xy 162.036207 -292.275356) (xy 162.083478 -292.289048) (xy 162.12794 -292.310146) (xy 162.168443 -292.338102)
			(xy 162.203936 -292.372194) (xy 162.233501 -292.411538) (xy 162.256372 -292.455115) (xy 162.271956 -292.501796)
			(xy 162.279851 -292.550373) (xy 162.280346 -292.57498) (xy 162.619194 -292.57498) (xy 162.623154 -292.525926)
			(xy 162.634931 -292.478142) (xy 162.654222 -292.432866) (xy 162.680525 -292.39127) (xy 162.71316 -292.354433)
			(xy 162.751281 -292.323308) (xy 162.793902 -292.298701) (xy 162.839918 -292.281249) (xy 162.888137 -292.271405)
			(xy 162.937312 -292.269424) (xy 162.986167 -292.275356) (xy 163.033438 -292.289048) (xy 163.0779 -292.310146)
			(xy 163.118403 -292.338102) (xy 163.153896 -292.372194) (xy 163.183461 -292.411538) (xy 163.206332 -292.455115)
			(xy 163.221916 -292.501796) (xy 163.229811 -292.550373) (xy 163.230306 -292.57498) (xy 163.229811 -292.599587)
			(xy 163.221916 -292.648164) (xy 163.206332 -292.694845) (xy 163.183461 -292.738422) (xy 163.153896 -292.777766)
			(xy 163.118403 -292.811858) (xy 163.0779 -292.839814) (xy 163.033438 -292.860912) (xy 162.986167 -292.874604)
			(xy 162.937312 -292.880536) (xy 162.888137 -292.878555) (xy 162.839918 -292.868711) (xy 162.793902 -292.851259)
			(xy 162.751281 -292.826652) (xy 162.71316 -292.795527) (xy 162.680525 -292.75869) (xy 162.654222 -292.717094)
			(xy 162.634931 -292.671818) (xy 162.623154 -292.624034) (xy 162.619194 -292.57498) (xy 162.280346 -292.57498)
			(xy 162.279851 -292.599587) (xy 162.271956 -292.648164) (xy 162.256372 -292.694845) (xy 162.233501 -292.738422)
			(xy 162.203936 -292.777766) (xy 162.168443 -292.811858) (xy 162.12794 -292.839814) (xy 162.083478 -292.860912)
			(xy 162.036207 -292.874604) (xy 161.987352 -292.880536) (xy 161.938177 -292.878555) (xy 161.889958 -292.868711)
			(xy 161.843942 -292.851259) (xy 161.801321 -292.826652) (xy 161.7632 -292.795527) (xy 161.730565 -292.75869)
			(xy 161.704262 -292.717094) (xy 161.684971 -292.671818) (xy 161.673194 -292.624034) (xy 161.669234 -292.57498)
			(xy 161.330386 -292.57498) (xy 161.329891 -292.599587) (xy 161.321996 -292.648164) (xy 161.306412 -292.694845)
			(xy 161.283541 -292.738422) (xy 161.253976 -292.777766) (xy 161.218483 -292.811858) (xy 161.17798 -292.839814)
			(xy 161.133518 -292.860912) (xy 161.086247 -292.874604) (xy 161.037392 -292.880536) (xy 160.988217 -292.878555)
			(xy 160.939998 -292.868711) (xy 160.893982 -292.851259) (xy 160.851361 -292.826652) (xy 160.81324 -292.795527)
			(xy 160.780605 -292.75869) (xy 160.754302 -292.717094) (xy 160.735011 -292.671818) (xy 160.723234 -292.624034)
			(xy 160.719274 -292.57498) (xy 160.405572 -292.57498) (xy 160.405181 -292.597912) (xy 160.398844 -292.643337)
			(xy 160.386287 -292.68745) (xy 160.377378 -292.708584) (xy 160.37433 -292.715442) (xy 160.372552 -292.730682)
			(xy 160.374838 -292.741604) (xy 160.376716 -292.748145) (xy 160.383414 -292.759986) (xy 160.388046 -292.764972)
			(xy 161.45129 -293.828216) (xy 161.458135 -293.835615) (xy 161.465865 -293.854213) (xy 161.466276 -293.864284)
			(xy 161.466276 -293.90594) (xy 161.46677 -293.915944) (xy 161.474436 -293.934426) (xy 161.488587 -293.948573)
			(xy 161.507072 -293.956233) (xy 161.517076 -293.95674) (xy 161.696146 -293.95674)
		)
		(stroke
			(width 0)
			(type solid)
		)
		(fill yes)
		(layer "In11.Cu")
		(net "PCEPLL5_VDDA18_PEX1")
	)
	(gr_poly
		(pts
			(xy 293.793418 -281.307794) (xy 293.803867 -281.307235) (xy 293.823015 -281.298848) (xy 293.830502 -281.291538)
			(xy 293.881556 -281.23642) (xy 293.887103 -281.229904) (xy 293.893869 -281.214196) (xy 293.894764 -281.205686)
			(xy 293.894764 -281.198828) (xy 293.89451 -281.19705) (xy 293.893748 -281.175206) (xy 293.893748 -280.225246)
			(xy 293.894228 -280.199235) (xy 293.90236 -280.147852) (xy 293.91843 -280.098374) (xy 293.942044 -280.052019)
			(xy 293.972619 -280.00993) (xy 294.009403 -279.973143) (xy 294.051488 -279.942563) (xy 294.09784 -279.918944)
			(xy 294.147317 -279.902868) (xy 294.198699 -279.894731) (xy 294.22471 -279.894284) (xy 294.234064 -279.894328)
			(xy 294.252744 -279.895346) (xy 294.262048 -279.896316) (xy 294.273511 -279.897105) (xy 294.295188 -279.889555)
			(xy 294.303704 -279.881838) (xy 294.359838 -279.825958) (xy 294.367449 -279.817525) (xy 294.375078 -279.79616)
			(xy 294.37457 -279.78481) (xy 294.37457 -279.784556) (xy 294.372792 -279.749504) (xy 294.373296 -279.723805)
			(xy 294.381334 -279.673038) (xy 294.397214 -279.624154) (xy 294.420544 -279.578355) (xy 294.450749 -279.536769)
			(xy 294.487088 -279.500418) (xy 294.528665 -279.470199) (xy 294.574456 -279.446854) (xy 294.623335 -279.430959)
			(xy 294.674099 -279.422904) (xy 294.725498 -279.422888) (xy 294.776266 -279.430911) (xy 294.825155 -279.446776)
			(xy 294.870961 -279.470092) (xy 294.912557 -279.500286) (xy 294.948918 -279.536613) (xy 294.97915 -279.578181)
			(xy 295.002508 -279.623965) (xy 295.018418 -279.67284) (xy 295.026488 -279.723601) (xy 295.02652 -279.775)
			(xy 295.018512 -279.825771) (xy 295.002661 -279.874665) (xy 294.979359 -279.920477) (xy 294.949178 -279.962082)
			(xy 294.912861 -279.998454) (xy 294.871303 -280.028698) (xy 294.825525 -280.05207) (xy 294.776656 -280.067995)
			(xy 294.725897 -280.07608) (xy 294.700198 -280.076656) (xy 294.69969 -280.076656) (xy 294.6654 -280.074624)
			(xy 294.664892 -280.074624) (xy 294.653462 -280.073354) (xy 294.631872 -280.081228) (xy 294.559482 -280.153872)
			(xy 294.552116 -280.175716) (xy 294.55237 -280.179018) (xy 294.553913 -280.190513) (xy 294.555569 -280.213649)
			(xy 294.555672 -280.225246) (xy 294.555672 -280.273252) (xy 294.556091 -280.283977) (xy 294.564774 -280.303583)
			(xy 294.572436 -280.311098) (xy 294.628062 -280.36139) (xy 294.636324 -280.368123) (xy 294.656532 -280.374823)
			(xy 294.667178 -280.374344) (xy 294.667432 -280.374344) (xy 294.69969 -280.37282) (xy 294.725379 -280.373297)
			(xy 294.776124 -280.381333) (xy 294.824988 -280.397208) (xy 294.870766 -280.420532) (xy 294.912333 -280.450731)
			(xy 294.948663 -280.48706) (xy 294.978862 -280.528625) (xy 295.002188 -280.574403) (xy 295.018065 -280.623266)
			(xy 295.026102 -280.674011) (xy 295.026102 -280.725389) (xy 295.018065 -280.776134) (xy 295.002188 -280.824997)
			(xy 294.978862 -280.870775) (xy 294.948663 -280.91234) (xy 294.912333 -280.948669) (xy 294.870766 -280.978868)
			(xy 294.824988 -281.002192) (xy 294.776124 -281.018067) (xy 294.725379 -281.026103) (xy 294.69969 -281.026616)
			(xy 294.667432 -281.025092) (xy 294.667178 -281.025092) (xy 294.656511 -281.024475) (xy 294.636242 -281.031173)
			(xy 294.628062 -281.038046) (xy 294.572436 -281.088338) (xy 294.564896 -281.095937) (xy 294.556249 -281.115493)
			(xy 294.555672 -281.126184) (xy 294.555672 -281.175206) (xy 294.55491 -281.196796) (xy 294.554656 -281.198574)
			(xy 294.554656 -281.199082) (xy 294.553894 -281.209496) (xy 294.55745 -281.219402) (xy 294.559331 -281.224159)
			(xy 294.56471 -281.232859) (xy 294.568118 -281.236674) (xy 294.621204 -281.293824) (xy 294.628469 -281.300178)
			(xy 294.646361 -281.307371) (xy 294.656002 -281.307794) (xy 295.693338 -281.307794) (xy 295.703785 -281.307231)
			(xy 295.722928 -281.298839) (xy 295.730422 -281.291538) (xy 295.781476 -281.23642) (xy 295.787022 -281.229903)
			(xy 295.793784 -281.214195) (xy 295.794684 -281.205686) (xy 295.794684 -281.198828) (xy 295.79443 -281.19705)
			(xy 295.793668 -281.175206) (xy 295.793668 -280.225246) (xy 295.794148 -280.199235) (xy 295.80228 -280.147853)
			(xy 295.818351 -280.098377) (xy 295.841965 -280.052024) (xy 295.87254 -280.009936) (xy 295.909324 -279.973151)
			(xy 295.95141 -279.942573) (xy 295.997762 -279.918957) (xy 296.047238 -279.902884) (xy 296.098619 -279.894749)
			(xy 296.12463 -279.894284) (xy 296.134048 -279.89432) (xy 296.152855 -279.895336) (xy 296.162222 -279.896316)
			(xy 296.173652 -279.897586) (xy 296.195496 -279.89022) (xy 296.260012 -279.825958) (xy 296.267626 -279.817526)
			(xy 296.275259 -279.796161) (xy 296.274744 -279.78481) (xy 296.274744 -279.784556) (xy 296.272712 -279.749504)
			(xy 296.273216 -279.723796) (xy 296.281259 -279.673014) (xy 296.297147 -279.624115) (xy 296.32049 -279.578303)
			(xy 296.350711 -279.536707) (xy 296.387067 -279.500351) (xy 296.428663 -279.47013) (xy 296.474475 -279.446787)
			(xy 296.523374 -279.430899) (xy 296.574156 -279.422856) (xy 296.625572 -279.422856) (xy 296.676354 -279.430899)
			(xy 296.725253 -279.446787) (xy 296.771065 -279.47013) (xy 296.812661 -279.500351) (xy 296.849017 -279.536707)
			(xy 296.879238 -279.578303) (xy 296.902581 -279.624115) (xy 296.918469 -279.673014) (xy 296.926512 -279.723796)
			(xy 296.927016 -279.749504) (xy 296.926513 -279.775198) (xy 296.918477 -279.825953) (xy 296.902603 -279.874828)
			(xy 296.879282 -279.920619) (xy 296.849088 -279.9622) (xy 296.812763 -279.998549) (xy 296.771202 -280.02877)
			(xy 296.725426 -280.052121) (xy 296.676562 -280.068027) (xy 296.625811 -280.076096) (xy 296.600118 -280.076656)
			(xy 296.59961 -280.076656) (xy 296.56532 -280.074624) (xy 296.564812 -280.074624) (xy 296.553636 -280.073354)
			(xy 296.532046 -280.080974) (xy 296.459402 -280.154126) (xy 296.452036 -280.175716) (xy 296.45229 -280.179018)
			(xy 296.453833 -280.190513) (xy 296.455489 -280.213649) (xy 296.455592 -280.225246) (xy 296.455592 -280.273252)
			(xy 296.456011 -280.283976) (xy 296.464697 -280.30358) (xy 296.472356 -280.311098) (xy 296.527982 -280.36139)
			(xy 296.536245 -280.368119) (xy 296.556452 -280.374811) (xy 296.567098 -280.374344) (xy 296.567352 -280.374344)
			(xy 296.599864 -280.37282) (xy 296.625554 -280.373295) (xy 296.676303 -280.381328) (xy 296.72517 -280.397201)
			(xy 296.770952 -280.420524) (xy 296.812522 -280.450721) (xy 296.848855 -280.487051) (xy 296.879058 -280.528617)
			(xy 296.902385 -280.574397) (xy 296.918264 -280.623262) (xy 296.926302 -280.67401) (xy 296.926302 -280.72539)
			(xy 296.918264 -280.776138) (xy 296.902385 -280.825003) (xy 296.879058 -280.870783) (xy 296.848855 -280.912349)
			(xy 296.812522 -280.948679) (xy 296.770952 -280.978876) (xy 296.72517 -281.002199) (xy 296.676303 -281.018072)
			(xy 296.625554 -281.026105) (xy 296.599864 -281.026616) (xy 296.567352 -281.025092) (xy 296.567098 -281.025092)
			(xy 296.556437 -281.024491) (xy 296.53619 -281.031213) (xy 296.527982 -281.038046) (xy 296.472356 -281.088338)
			(xy 296.464813 -281.095936) (xy 296.456163 -281.115492) (xy 296.455592 -281.126184) (xy 296.455592 -281.175206)
			(xy 296.45483 -281.196796) (xy 296.454576 -281.198574) (xy 296.454576 -281.199082) (xy 296.453814 -281.209496)
			(xy 296.45737 -281.219402) (xy 296.459252 -281.224159) (xy 296.464632 -281.232857) (xy 296.468038 -281.236674)
			(xy 296.521124 -281.293824) (xy 296.52839 -281.300174) (xy 296.546282 -281.307361) (xy 296.555922 -281.307794)
			(xy 297.593258 -281.307794) (xy 297.603704 -281.307227) (xy 297.622841 -281.29883) (xy 297.630342 -281.291538)
			(xy 297.681396 -281.23642) (xy 297.68694 -281.229902) (xy 297.6937 -281.214194) (xy 297.694604 -281.205686)
			(xy 297.694604 -281.198828) (xy 297.69435 -281.19705) (xy 297.693588 -281.175206) (xy 297.693588 -280.225246)
			(xy 297.694094 -280.199235) (xy 297.702225 -280.147853) (xy 297.718294 -280.098375) (xy 297.741905 -280.05202)
			(xy 297.772476 -280.009929) (xy 297.809256 -279.973139) (xy 297.851338 -279.942555) (xy 297.897686 -279.918931)
			(xy 297.947159 -279.902848) (xy 297.998539 -279.894702) (xy 298.02455 -279.894284) (xy 298.033968 -279.89432)
			(xy 298.052775 -279.895337) (xy 298.062142 -279.896316) (xy 298.073572 -279.897586) (xy 298.095416 -279.89022)
			(xy 298.159932 -279.825958) (xy 298.167543 -279.817525) (xy 298.175174 -279.796161) (xy 298.174664 -279.78481)
			(xy 298.174664 -279.784556) (xy 298.172632 -279.749504) (xy 298.173136 -279.723796) (xy 298.181179 -279.673014)
			(xy 298.197067 -279.624115) (xy 298.22041 -279.578303) (xy 298.250631 -279.536707) (xy 298.286987 -279.500351)
			(xy 298.328583 -279.47013) (xy 298.374395 -279.446787) (xy 298.423294 -279.430899) (xy 298.474076 -279.422856)
			(xy 298.525492 -279.422856) (xy 298.576274 -279.430899) (xy 298.625173 -279.446787) (xy 298.670985 -279.47013)
			(xy 298.712581 -279.500351) (xy 298.748937 -279.536707) (xy 298.779158 -279.578303) (xy 298.802501 -279.624115)
			(xy 298.818389 -279.673014) (xy 298.826432 -279.723796) (xy 298.826936 -279.749504) (xy 298.826433 -279.775198)
			(xy 298.818397 -279.825955) (xy 298.802523 -279.874831) (xy 298.779203 -279.920624) (xy 298.749009 -279.962207)
			(xy 298.712685 -279.998557) (xy 298.671123 -280.02878) (xy 298.625347 -280.052134) (xy 298.576483 -280.068042)
			(xy 298.525732 -280.076114) (xy 298.500038 -280.076656) (xy 298.49953 -280.076656) (xy 298.46524 -280.074624)
			(xy 298.464732 -280.074624) (xy 298.453556 -280.073354) (xy 298.431966 -280.080974) (xy 298.359322 -280.154126)
			(xy 298.351956 -280.175716) (xy 298.35221 -280.179018) (xy 298.353753 -280.190513) (xy 298.355409 -280.213649)
			(xy 298.355512 -280.225246) (xy 298.355512 -280.273252) (xy 298.355932 -280.283975) (xy 298.36462 -280.303577)
			(xy 298.372276 -280.311098) (xy 298.427902 -280.36139) (xy 298.436166 -280.368116) (xy 298.456372 -280.3748)
			(xy 298.467018 -280.374344) (xy 298.467272 -280.374344) (xy 298.499784 -280.37282) (xy 298.525473 -280.373297)
			(xy 298.576219 -280.381332) (xy 298.625084 -280.397207) (xy 298.670863 -280.42053) (xy 298.71243 -280.450729)
			(xy 298.748761 -280.487058) (xy 298.778961 -280.528623) (xy 298.802287 -280.574401) (xy 298.818165 -280.623265)
			(xy 298.826202 -280.674011) (xy 298.826202 -280.725389) (xy 298.818165 -280.776135) (xy 298.802287 -280.824999)
			(xy 298.778961 -280.870777) (xy 298.748761 -280.912342) (xy 298.71243 -280.948671) (xy 298.670863 -280.97887)
			(xy 298.625084 -281.002193) (xy 298.576219 -281.018068) (xy 298.525473 -281.026103) (xy 298.499784 -281.026616)
			(xy 298.467272 -281.025092) (xy 298.467018 -281.025092) (xy 298.456355 -281.024487) (xy 298.436103 -281.031203)
			(xy 298.427902 -281.038046) (xy 298.372276 -281.088338) (xy 298.364731 -281.095935) (xy 298.356077 -281.115491)
			(xy 298.355512 -281.126184) (xy 298.355512 -281.175206) (xy 298.35475 -281.196796) (xy 298.354496 -281.198574)
			(xy 298.354496 -281.199082) (xy 298.353734 -281.209496) (xy 298.35729 -281.219402) (xy 298.359173 -281.224158)
			(xy 298.364554 -281.232855) (xy 298.367958 -281.236674) (xy 298.421044 -281.293824) (xy 298.428311 -281.300171)
			(xy 298.446203 -281.307351) (xy 298.455842 -281.307794) (xy 299.493432 -281.307794) (xy 299.50388 -281.307232)
			(xy 299.523024 -281.298842) (xy 299.530516 -281.291538) (xy 299.58157 -281.23642) (xy 299.587116 -281.229903)
			(xy 299.59388 -281.214195) (xy 299.594778 -281.205686) (xy 299.594778 -281.198828) (xy 299.594016 -281.175206)
			(xy 299.594016 -280.225246) (xy 299.594496 -280.199255) (xy 299.602621 -280.147912) (xy 299.61868 -280.098473)
			(xy 299.642276 -280.052155) (xy 299.672827 -280.0101) (xy 299.709583 -279.973342) (xy 299.751637 -279.942787)
			(xy 299.797953 -279.919188) (xy 299.847391 -279.903127) (xy 299.898733 -279.894997) (xy 299.924724 -279.894538)
			(xy 299.934078 -279.894582) (xy 299.952758 -279.895599) (xy 299.962062 -279.89657) (xy 299.973525 -279.897356)
			(xy 299.995203 -279.889808) (xy 300.003718 -279.882092) (xy 300.068234 -279.81783) (xy 300.075854 -279.79624)
			(xy 300.074584 -279.78481) (xy 300.072552 -279.749504) (xy 300.073056 -279.723796) (xy 300.081099 -279.673014)
			(xy 300.096987 -279.624115) (xy 300.12033 -279.578303) (xy 300.150551 -279.536707) (xy 300.186907 -279.500351)
			(xy 300.228503 -279.47013) (xy 300.274315 -279.446787) (xy 300.323214 -279.430899) (xy 300.373996 -279.422856)
			(xy 300.425412 -279.422856) (xy 300.476194 -279.430899) (xy 300.525093 -279.446787) (xy 300.570905 -279.47013)
			(xy 300.612501 -279.500351) (xy 300.648857 -279.536707) (xy 300.679078 -279.578303) (xy 300.702421 -279.624115)
			(xy 300.718309 -279.673014) (xy 300.726352 -279.723796) (xy 300.726856 -279.749504) (xy 300.726353 -279.775199)
			(xy 300.718317 -279.825957) (xy 300.702444 -279.874834) (xy 300.679124 -279.920628) (xy 300.64893 -279.962213)
			(xy 300.612606 -279.998565) (xy 300.571045 -280.028791) (xy 300.525269 -280.052146) (xy 300.476404 -280.068057)
			(xy 300.425653 -280.076133) (xy 300.399958 -280.076656) (xy 300.39945 -280.076656) (xy 300.36516 -280.074624)
			(xy 300.364652 -280.074624) (xy 300.353476 -280.073354) (xy 300.331886 -280.080974) (xy 300.259242 -280.154126)
			(xy 300.251876 -280.175716) (xy 300.25213 -280.179018) (xy 300.253673 -280.190513) (xy 300.255325 -280.213649)
			(xy 300.255432 -280.225246) (xy 300.255432 -280.273252) (xy 300.255853 -280.283975) (xy 300.264543 -280.303575)
			(xy 300.272196 -280.311098) (xy 300.327822 -280.36139) (xy 300.336087 -280.368112) (xy 300.356292 -280.374789)
			(xy 300.366938 -280.374344) (xy 300.367192 -280.374344) (xy 300.399704 -280.37282) (xy 300.42539 -280.373324)
			(xy 300.47613 -280.381361) (xy 300.524988 -280.397236) (xy 300.570761 -280.420559) (xy 300.612322 -280.450756)
			(xy 300.648647 -280.487081) (xy 300.678843 -280.528643) (xy 300.702165 -280.574416) (xy 300.71804 -280.623274)
			(xy 300.726076 -280.674014) (xy 300.726076 -280.725386) (xy 300.71804 -280.776126) (xy 300.702165 -280.824984)
			(xy 300.678843 -280.870757) (xy 300.648647 -280.912319) (xy 300.612322 -280.948644) (xy 300.570761 -280.978841)
			(xy 300.524988 -281.002164) (xy 300.47613 -281.018039) (xy 300.42539 -281.026076) (xy 300.399704 -281.026616)
			(xy 300.367192 -281.025092) (xy 300.366938 -281.025092) (xy 300.356274 -281.024483) (xy 300.336016 -281.031193)
			(xy 300.327822 -281.038046) (xy 300.272196 -281.088338) (xy 300.264661 -281.095939) (xy 300.256021 -281.115495)
			(xy 300.255432 -281.126184) (xy 300.255432 -281.175206) (xy 300.25467 -281.198828) (xy 300.25467 -281.199082)
			(xy 300.254481 -281.209463) (xy 300.261417 -281.229011) (xy 300.268132 -281.236928) (xy 300.290484 -281.260804)
			(xy 300.32071 -281.293316) (xy 300.328034 -281.299874) (xy 300.346198 -281.307343) (xy 300.356016 -281.307794)
			(xy 301.393352 -281.307794) (xy 301.403798 -281.307229) (xy 301.422937 -281.298833) (xy 301.430436 -281.291538)
			(xy 301.48149 -281.23642) (xy 301.487035 -281.229902) (xy 301.493796 -281.214195) (xy 301.494698 -281.205686)
			(xy 301.494698 -281.198828) (xy 301.493936 -281.175206) (xy 301.493936 -280.225246) (xy 301.494416 -280.199256)
			(xy 301.502542 -280.147914) (xy 301.5186 -280.098476) (xy 301.542196 -280.05216) (xy 301.572748 -280.010106)
			(xy 301.609504 -279.97335) (xy 301.651558 -279.942797) (xy 301.697874 -279.919201) (xy 301.747312 -279.903142)
			(xy 301.798654 -279.895016) (xy 301.824644 -279.894538) (xy 301.834062 -279.894574) (xy 301.852869 -279.895591)
			(xy 301.862236 -279.89657) (xy 301.873666 -279.89784) (xy 301.895256 -279.890474) (xy 301.968408 -279.81783)
			(xy 301.976028 -279.79624) (xy 301.974758 -279.78481) (xy 301.97298 -279.749504) (xy 301.973483 -279.723803)
			(xy 301.981522 -279.673035) (xy 301.997403 -279.624148) (xy 302.020734 -279.578347) (xy 302.050941 -279.536759)
			(xy 302.087282 -279.500407) (xy 302.12886 -279.470187) (xy 302.174654 -279.446842) (xy 302.223536 -279.430946)
			(xy 302.274302 -279.422891) (xy 302.325703 -279.422876) (xy 302.376474 -279.4309) (xy 302.425365 -279.446767)
			(xy 302.471172 -279.470084) (xy 302.512769 -279.50028) (xy 302.549131 -279.53661) (xy 302.579364 -279.57818)
			(xy 302.602722 -279.623967) (xy 302.618632 -279.672844) (xy 302.626701 -279.723608) (xy 302.626731 -279.775009)
			(xy 302.618722 -279.825782) (xy 302.602869 -279.874678) (xy 302.579565 -279.920492) (xy 302.549381 -279.962098)
			(xy 302.513062 -279.99847) (xy 302.4715 -280.028715) (xy 302.42572 -280.052086) (xy 302.376848 -280.06801)
			(xy 302.326086 -280.076094) (xy 302.300386 -280.076656) (xy 302.299878 -280.076656) (xy 302.26508 -280.074624)
			(xy 302.264572 -280.074624) (xy 302.253396 -280.073354) (xy 302.231806 -280.080974) (xy 302.159162 -280.154126)
			(xy 302.151796 -280.175716) (xy 302.15205 -280.179018) (xy 302.153593 -280.190513) (xy 302.155245 -280.213649)
			(xy 302.155352 -280.225246) (xy 302.155352 -280.273252) (xy 302.155922 -280.28394) (xy 302.164595 -280.303481)
			(xy 302.172116 -280.311098) (xy 302.236124 -280.368756) (xy 302.256444 -280.37536) (xy 302.267112 -280.374344)
			(xy 302.299878 -280.37282) (xy 302.325568 -280.373296) (xy 302.376314 -280.381331) (xy 302.42518 -280.397205)
			(xy 302.47096 -280.420528) (xy 302.512528 -280.450726) (xy 302.548859 -280.487056) (xy 302.57906 -280.528621)
			(xy 302.602387 -280.5744) (xy 302.618264 -280.623264) (xy 302.626302 -280.67401) (xy 302.626302 -280.72539)
			(xy 302.618264 -280.776136) (xy 302.602387 -280.825) (xy 302.57906 -280.870779) (xy 302.548859 -280.912344)
			(xy 302.512528 -280.948674) (xy 302.47096 -280.978872) (xy 302.42518 -281.002195) (xy 302.376314 -281.018069)
			(xy 302.325568 -281.026104) (xy 302.299878 -281.026616) (xy 302.267112 -281.025092) (xy 302.256444 -281.024076)
			(xy 302.236124 -281.03068) (xy 302.172116 -281.088338) (xy 302.164465 -281.095859) (xy 302.1558 -281.115463)
			(xy 302.155352 -281.126184) (xy 302.155352 -281.175206) (xy 302.15459 -281.198828) (xy 302.15459 -281.199082)
			(xy 302.154402 -281.209463) (xy 302.16134 -281.229009) (xy 302.168052 -281.236928) (xy 302.190404 -281.260804)
			(xy 302.22063 -281.293316) (xy 302.227955 -281.299871) (xy 302.246119 -281.307333) (xy 302.255936 -281.307794)
			(xy 303.293272 -281.307794) (xy 303.303716 -281.307225) (xy 303.32285 -281.298824) (xy 303.330356 -281.291538)
			(xy 303.38141 -281.23642) (xy 303.386953 -281.229902) (xy 303.393711 -281.214194) (xy 303.394618 -281.205686)
			(xy 303.394618 -281.198828) (xy 303.393856 -281.175206) (xy 303.393856 -280.225246) (xy 303.394336 -280.199253)
			(xy 303.402461 -280.147907) (xy 303.418519 -280.098464) (xy 303.442113 -280.052142) (xy 303.472664 -280.010081)
			(xy 303.509419 -279.973318) (xy 303.551472 -279.942756) (xy 303.597788 -279.91915) (xy 303.647227 -279.90308)
			(xy 303.698571 -279.894942) (xy 303.724564 -279.894538) (xy 303.733982 -279.894575) (xy 303.752789 -279.895593)
			(xy 303.762156 -279.89657) (xy 303.773586 -279.89784) (xy 303.795176 -279.890474) (xy 303.868328 -279.81783)
			(xy 303.875948 -279.79624) (xy 303.874678 -279.78481) (xy 303.8729 -279.749504) (xy 303.873404 -279.723796)
			(xy 303.881445 -279.673012) (xy 303.897331 -279.624112) (xy 303.92067 -279.578298) (xy 303.950888 -279.536698)
			(xy 303.987241 -279.500337) (xy 304.028833 -279.47011) (xy 304.074642 -279.44676) (xy 304.123539 -279.430863)
			(xy 304.174321 -279.42281) (xy 304.225737 -279.422798) (xy 304.276522 -279.43083) (xy 304.325426 -279.446705)
			(xy 304.371245 -279.470035) (xy 304.412851 -279.500244) (xy 304.449219 -279.536589) (xy 304.479455 -279.578176)
			(xy 304.502814 -279.62398) (xy 304.518721 -279.672873) (xy 304.526785 -279.723653) (xy 304.526807 -279.77507)
			(xy 304.518786 -279.825857) (xy 304.50292 -279.874764) (xy 304.4796 -279.920587) (xy 304.449399 -279.962199)
			(xy 304.413062 -279.998575) (xy 304.371482 -280.02882) (xy 304.325683 -280.052188) (xy 304.276792 -280.068106)
			(xy 304.226014 -280.07618) (xy 304.200306 -280.076656) (xy 304.199798 -280.076656) (xy 304.165 -280.074624)
			(xy 304.164492 -280.074624) (xy 304.153316 -280.073354) (xy 304.131726 -280.080974) (xy 304.059082 -280.154126)
			(xy 304.051716 -280.175716) (xy 304.05197 -280.179018) (xy 304.053513 -280.190513) (xy 304.055166 -280.213649)
			(xy 304.055272 -280.225246) (xy 304.055272 -280.273252) (xy 304.05584 -280.283942) (xy 304.064503 -280.303492)
			(xy 304.072036 -280.311098) (xy 304.136044 -280.368756) (xy 304.156364 -280.37536) (xy 304.167032 -280.374344)
			(xy 304.199798 -280.37282) (xy 304.225487 -280.373298) (xy 304.276231 -280.381335) (xy 304.325094 -280.397211)
			(xy 304.370871 -280.420535) (xy 304.412436 -280.450734) (xy 304.448765 -280.487063) (xy 304.478964 -280.528627)
			(xy 304.502289 -280.574405) (xy 304.518165 -280.623267) (xy 304.526202 -280.674011) (xy 304.526202 -280.725389)
			(xy 304.518165 -280.776133) (xy 304.502289 -280.824995) (xy 304.478964 -280.870773) (xy 304.448765 -280.912337)
			(xy 304.412436 -280.948666) (xy 304.370871 -280.978865) (xy 304.325094 -281.002189) (xy 304.276231 -281.018065)
			(xy 304.225487 -281.026102) (xy 304.199798 -281.026616) (xy 304.167032 -281.025092) (xy 304.156364 -281.024076)
			(xy 304.136044 -281.03068) (xy 304.072036 -281.088338) (xy 304.064382 -281.095857) (xy 304.055714 -281.115462)
			(xy 304.055272 -281.126184) (xy 304.055272 -281.175206) (xy 304.05451 -281.198828) (xy 304.05451 -281.199082)
			(xy 304.054322 -281.209462) (xy 304.061262 -281.229007) (xy 304.067972 -281.236928) (xy 304.090324 -281.260804)
			(xy 304.12055 -281.293316) (xy 304.127876 -281.299867) (xy 304.14604 -281.307322) (xy 304.155856 -281.307794)
			(xy 305.193446 -281.307794) (xy 305.203893 -281.30723) (xy 305.223033 -281.298836) (xy 305.23053 -281.291538)
			(xy 305.281584 -281.23642) (xy 305.287129 -281.229903) (xy 305.293891 -281.214195) (xy 305.294792 -281.205686)
			(xy 305.294792 -281.198828) (xy 305.294538 -281.19705) (xy 305.293776 -281.175206) (xy 305.293776 -280.225246)
			(xy 305.294256 -280.199235) (xy 305.302388 -280.147854) (xy 305.318459 -280.098378) (xy 305.342073 -280.052025)
			(xy 305.372649 -280.009939) (xy 305.409432 -279.973154) (xy 305.451519 -279.942577) (xy 305.497871 -279.918962)
			(xy 305.547346 -279.90289) (xy 305.598728 -279.894757) (xy 305.624738 -279.894284) (xy 305.634092 -279.894325)
			(xy 305.652773 -279.89534) (xy 305.662076 -279.896316) (xy 305.673537 -279.897099) (xy 305.695205 -279.88954)
			(xy 305.703732 -279.881838) (xy 305.759866 -279.825958) (xy 305.767485 -279.817528) (xy 305.775126 -279.796162)
			(xy 305.774598 -279.78481) (xy 305.774598 -279.784556) (xy 305.77282 -279.749504) (xy 305.773324 -279.723798)
			(xy 305.781364 -279.673018) (xy 305.797249 -279.624121) (xy 305.820586 -279.57831) (xy 305.850801 -279.536713)
			(xy 305.887151 -279.500355) (xy 305.92874 -279.470129) (xy 305.974545 -279.44678) (xy 306.023438 -279.430884)
			(xy 306.074216 -279.42283) (xy 306.125628 -279.422818) (xy 306.17641 -279.430847) (xy 306.225311 -279.446721)
			(xy 306.271127 -279.470047) (xy 306.31273 -279.500253) (xy 306.349097 -279.536595) (xy 306.379332 -279.578177)
			(xy 306.402691 -279.623976) (xy 306.418599 -279.672866) (xy 306.426664 -279.723642) (xy 306.426688 -279.775054)
			(xy 306.41867 -279.825838) (xy 306.402808 -279.874742) (xy 306.379491 -279.920564) (xy 306.349295 -279.962174)
			(xy 306.312962 -279.998549) (xy 306.271386 -280.028793) (xy 306.225592 -280.052163) (xy 306.176706 -280.068082)
			(xy 306.125932 -280.076158) (xy 306.100226 -280.076656) (xy 306.099718 -280.076656) (xy 306.065428 -280.074624)
			(xy 306.06492 -280.074624) (xy 306.05349 -280.073354) (xy 306.0319 -280.081228) (xy 305.95951 -280.153872)
			(xy 305.952144 -280.175716) (xy 305.952398 -280.179018) (xy 305.953941 -280.190513) (xy 305.955597 -280.213649)
			(xy 305.9557 -280.225246) (xy 305.9557 -280.273252) (xy 305.95612 -280.283976) (xy 305.964806 -280.303579)
			(xy 305.972464 -280.311098) (xy 306.02809 -280.36139) (xy 306.036353 -280.368118) (xy 306.05656 -280.374807)
			(xy 306.067206 -280.374344) (xy 306.06746 -280.374344) (xy 306.099718 -280.37282) (xy 306.125403 -280.373325)
			(xy 306.176142 -280.381364) (xy 306.224997 -280.39724) (xy 306.270768 -280.420564) (xy 306.312327 -280.450761)
			(xy 306.348651 -280.487086) (xy 306.378845 -280.528647) (xy 306.402166 -280.574419) (xy 306.41804 -280.623276)
			(xy 306.426076 -280.674015) (xy 306.426076 -280.725385) (xy 306.41804 -280.776124) (xy 306.402166 -280.824981)
			(xy 306.378845 -280.870753) (xy 306.348651 -280.912314) (xy 306.312327 -280.948639) (xy 306.270768 -280.978836)
			(xy 306.224997 -281.00216) (xy 306.176142 -281.018036) (xy 306.125403 -281.026075) (xy 306.099718 -281.026616)
			(xy 306.06746 -281.025092) (xy 306.067206 -281.025092) (xy 306.056544 -281.02449) (xy 306.036295 -281.031209)
			(xy 306.02809 -281.038046) (xy 305.972464 -281.088338) (xy 305.964921 -281.095936) (xy 305.956269 -281.115492)
			(xy 305.9557 -281.126184) (xy 305.9557 -281.175206) (xy 305.954938 -281.196796) (xy 305.954684 -281.198574)
			(xy 305.954684 -281.199082) (xy 305.953922 -281.209496) (xy 305.957478 -281.219402) (xy 305.95936 -281.224159)
			(xy 305.964741 -281.232856) (xy 305.968146 -281.236674) (xy 306.021232 -281.293824) (xy 306.028498 -281.300173)
			(xy 306.04639 -281.307357) (xy 306.05603 -281.307794) (xy 307.093366 -281.307794) (xy 307.103811 -281.307226)
			(xy 307.122946 -281.298827) (xy 307.13045 -281.291538) (xy 307.181504 -281.23642) (xy 307.187047 -281.229902)
			(xy 307.193806 -281.214194) (xy 307.194712 -281.205686) (xy 307.194712 -281.198828) (xy 307.194458 -281.19705)
			(xy 307.193696 -281.175206) (xy 307.193696 -280.225246) (xy 307.194176 -280.199233) (xy 307.202307 -280.147847)
			(xy 307.218377 -280.098366) (xy 307.24199 -280.052008) (xy 307.272564 -280.009914) (xy 307.309347 -279.973122)
			(xy 307.351432 -279.942536) (xy 307.397784 -279.918911) (xy 307.447261 -279.902828) (xy 307.498645 -279.894683)
			(xy 307.524658 -279.894284) (xy 307.534076 -279.89432) (xy 307.552883 -279.895338) (xy 307.56225 -279.896316)
			(xy 307.57368 -279.897586) (xy 307.595524 -279.89022) (xy 307.66004 -279.825958) (xy 307.667663 -279.81753)
			(xy 307.675307 -279.796162) (xy 307.674772 -279.78481) (xy 307.674772 -279.784556) (xy 307.67274 -279.749504)
			(xy 307.673244 -279.723796) (xy 307.681287 -279.673014) (xy 307.697175 -279.624115) (xy 307.720518 -279.578303)
			(xy 307.750739 -279.536707) (xy 307.787095 -279.500351) (xy 307.828691 -279.47013) (xy 307.874503 -279.446787)
			(xy 307.923402 -279.430899) (xy 307.974184 -279.422856) (xy 308.0256 -279.422856) (xy 308.076382 -279.430899)
			(xy 308.125281 -279.446787) (xy 308.171093 -279.47013) (xy 308.212689 -279.500351) (xy 308.249045 -279.536707)
			(xy 308.279266 -279.578303) (xy 308.302609 -279.624115) (xy 308.318497 -279.673014) (xy 308.32654 -279.723796)
			(xy 308.327044 -279.749504) (xy 308.326541 -279.775199) (xy 308.318505 -279.825956) (xy 308.302632 -279.874832)
			(xy 308.279311 -279.920625) (xy 308.249118 -279.962209) (xy 308.212793 -279.99856) (xy 308.171232 -280.028785)
			(xy 308.125456 -280.052139) (xy 308.076591 -280.068048) (xy 308.02584 -280.076122) (xy 308.000146 -280.076656)
			(xy 307.999638 -280.076656) (xy 307.965348 -280.074624) (xy 307.96484 -280.074624) (xy 307.953664 -280.073354)
			(xy 307.932074 -280.080974) (xy 307.85943 -280.154126) (xy 307.852064 -280.175716) (xy 307.852318 -280.179018)
			(xy 307.853861 -280.190513) (xy 307.855516 -280.213649) (xy 307.85562 -280.225246) (xy 307.85562 -280.273252)
			(xy 307.85604 -280.283975) (xy 307.864729 -280.303576) (xy 307.872384 -280.311098) (xy 307.92801 -280.36139)
			(xy 307.936274 -280.368114) (xy 307.95648 -280.374796) (xy 307.967126 -280.374344) (xy 307.96738 -280.374344)
			(xy 307.999892 -280.37282) (xy 308.025581 -280.373297) (xy 308.076326 -280.381333) (xy 308.125189 -280.397209)
			(xy 308.170968 -280.420533) (xy 308.212533 -280.450731) (xy 308.248863 -280.48706) (xy 308.279063 -280.528626)
			(xy 308.302388 -280.574403) (xy 308.318265 -280.623266) (xy 308.326302 -280.674011) (xy 308.326302 -280.725389)
			(xy 308.318265 -280.776134) (xy 308.302388 -280.824997) (xy 308.279063 -280.870774) (xy 308.248863 -280.91234)
			(xy 308.212533 -280.948669) (xy 308.170968 -280.978867) (xy 308.125189 -281.002191) (xy 308.076326 -281.018067)
			(xy 308.025581 -281.026103) (xy 307.999892 -281.026616) (xy 307.96738 -281.025092) (xy 307.967126 -281.025092)
			(xy 307.956463 -281.024485) (xy 307.936208 -281.031199) (xy 307.92801 -281.038046) (xy 307.872384 -281.088338)
			(xy 307.86485 -281.09594) (xy 307.856212 -281.115495) (xy 307.85562 -281.126184) (xy 307.85562 -281.175206)
			(xy 307.854858 -281.196796) (xy 307.854604 -281.198574) (xy 307.854604 -281.199082) (xy 307.853842 -281.209496)
			(xy 307.857398 -281.219402) (xy 307.859281 -281.224158) (xy 307.864663 -281.232854) (xy 307.868066 -281.236674)
			(xy 307.921152 -281.293824) (xy 307.928419 -281.30017) (xy 307.946312 -281.307347) (xy 307.95595 -281.307794)
			(xy 308.993286 -281.307794) (xy 309.003729 -281.307222) (xy 309.022858 -281.298818) (xy 309.03037 -281.291538)
			(xy 309.081424 -281.23642) (xy 309.086975 -281.229905) (xy 309.093744 -281.214197) (xy 309.094632 -281.205686)
			(xy 309.094632 -281.198828) (xy 309.094378 -281.19705) (xy 309.093616 -281.175206) (xy 309.093616 -280.225246)
			(xy 309.094096 -280.199234) (xy 309.102228 -280.147849) (xy 309.118298 -280.098369) (xy 309.141911 -280.052012)
			(xy 309.172485 -280.00992) (xy 309.209268 -279.97313) (xy 309.251354 -279.942547) (xy 309.297706 -279.918924)
			(xy 309.347183 -279.902843) (xy 309.398566 -279.894701) (xy 309.424578 -279.894284) (xy 309.433996 -279.894321)
			(xy 309.452803 -279.89534) (xy 309.46217 -279.896316) (xy 309.4736 -279.897586) (xy 309.495444 -279.89022)
			(xy 309.55996 -279.825958) (xy 309.56758 -279.817529) (xy 309.575222 -279.796162) (xy 309.574692 -279.78481)
			(xy 309.574692 -279.784556) (xy 309.57266 -279.749504) (xy 309.573164 -279.723796) (xy 309.581207 -279.673014)
			(xy 309.597095 -279.624115) (xy 309.620438 -279.578303) (xy 309.650659 -279.536707) (xy 309.687015 -279.500351)
			(xy 309.728611 -279.47013) (xy 309.774423 -279.446787) (xy 309.823322 -279.430899) (xy 309.874104 -279.422856)
			(xy 309.92552 -279.422856) (xy 309.976302 -279.430899) (xy 310.025201 -279.446787) (xy 310.071013 -279.47013)
			(xy 310.112609 -279.500351) (xy 310.148965 -279.536707) (xy 310.179186 -279.578303) (xy 310.202529 -279.624115)
			(xy 310.218417 -279.673014) (xy 310.22646 -279.723796) (xy 310.226964 -279.749504) (xy 310.226461 -279.775199)
			(xy 310.226419 -279.775466) (xy 311.473084 -279.775466) (xy 311.473084 -279.72405) (xy 311.481127 -279.673268)
			(xy 311.497015 -279.624369) (xy 311.520358 -279.578557) (xy 311.550579 -279.536961) (xy 311.586935 -279.500605)
			(xy 311.628531 -279.470384) (xy 311.674343 -279.447041) (xy 311.723242 -279.431153) (xy 311.774024 -279.42311)
			(xy 311.82544 -279.42311) (xy 311.876222 -279.431153) (xy 311.925121 -279.447041) (xy 311.970933 -279.470384)
			(xy 312.012529 -279.500605) (xy 312.048885 -279.536961) (xy 312.079106 -279.578557) (xy 312.102449 -279.624369)
			(xy 312.118337 -279.673268) (xy 312.12638 -279.72405) (xy 312.126884 -279.749758) (xy 312.12638 -279.775466)
			(xy 313.373258 -279.775466) (xy 313.373258 -279.72405) (xy 313.381301 -279.673268) (xy 313.397189 -279.624369)
			(xy 313.420532 -279.578557) (xy 313.450753 -279.536961) (xy 313.487109 -279.500605) (xy 313.528705 -279.470384)
			(xy 313.574517 -279.447041) (xy 313.623416 -279.431153) (xy 313.674198 -279.42311) (xy 313.725614 -279.42311)
			(xy 313.776396 -279.431153) (xy 313.825295 -279.447041) (xy 313.871107 -279.470384) (xy 313.912703 -279.500605)
			(xy 313.949059 -279.536961) (xy 313.97928 -279.578557) (xy 314.002623 -279.624369) (xy 314.018511 -279.673268)
			(xy 314.026554 -279.72405) (xy 314.027058 -279.749758) (xy 314.026554 -279.775466) (xy 314.323218 -279.775466)
			(xy 314.323218 -279.72405) (xy 314.331261 -279.673268) (xy 314.347149 -279.624369) (xy 314.370492 -279.578557)
			(xy 314.400713 -279.536961) (xy 314.437069 -279.500605) (xy 314.478665 -279.470384) (xy 314.524477 -279.447041)
			(xy 314.573376 -279.431153) (xy 314.624158 -279.42311) (xy 314.675574 -279.42311) (xy 314.726356 -279.431153)
			(xy 314.775255 -279.447041) (xy 314.821067 -279.470384) (xy 314.862663 -279.500605) (xy 314.899019 -279.536961)
			(xy 314.92924 -279.578557) (xy 314.952583 -279.624369) (xy 314.968471 -279.673268) (xy 314.976514 -279.72405)
			(xy 314.977018 -279.749758) (xy 314.976514 -279.775466) (xy 314.968471 -279.826248) (xy 314.952583 -279.875147)
			(xy 314.92924 -279.920959) (xy 314.899019 -279.962555) (xy 314.862663 -279.998911) (xy 314.821067 -280.029132)
			(xy 314.775255 -280.052475) (xy 314.726356 -280.068363) (xy 314.675574 -280.076406) (xy 314.624158 -280.076406)
			(xy 314.573376 -280.068363) (xy 314.524477 -280.052475) (xy 314.478665 -280.029132) (xy 314.437069 -279.998911)
			(xy 314.400713 -279.962555) (xy 314.370492 -279.920959) (xy 314.347149 -279.875147) (xy 314.331261 -279.826248)
			(xy 314.323218 -279.775466) (xy 314.026554 -279.775466) (xy 314.018511 -279.826248) (xy 314.002623 -279.875147)
			(xy 313.97928 -279.920959) (xy 313.949059 -279.962555) (xy 313.912703 -279.998911) (xy 313.871107 -280.029132)
			(xy 313.825295 -280.052475) (xy 313.776396 -280.068363) (xy 313.725614 -280.076406) (xy 313.674198 -280.076406)
			(xy 313.623416 -280.068363) (xy 313.574517 -280.052475) (xy 313.528705 -280.029132) (xy 313.487109 -279.998911)
			(xy 313.450753 -279.962555) (xy 313.420532 -279.920959) (xy 313.397189 -279.875147) (xy 313.381301 -279.826248)
			(xy 313.373258 -279.775466) (xy 312.12638 -279.775466) (xy 312.118337 -279.826248) (xy 312.102449 -279.875147)
			(xy 312.079106 -279.920959) (xy 312.048885 -279.962555) (xy 312.012529 -279.998911) (xy 311.970933 -280.029132)
			(xy 311.925121 -280.052475) (xy 311.876222 -280.068363) (xy 311.82544 -280.076406) (xy 311.774024 -280.076406)
			(xy 311.723242 -280.068363) (xy 311.674343 -280.052475) (xy 311.628531 -280.029132) (xy 311.586935 -279.998911)
			(xy 311.550579 -279.962555) (xy 311.520358 -279.920959) (xy 311.497015 -279.875147) (xy 311.481127 -279.826248)
			(xy 311.473084 -279.775466) (xy 310.226419 -279.775466) (xy 310.218425 -279.825957) (xy 310.202552 -279.874835)
			(xy 310.179232 -279.92063) (xy 310.149039 -279.962215) (xy 310.112715 -279.998568) (xy 310.071154 -280.028795)
			(xy 310.025378 -280.052151) (xy 309.976513 -280.068064) (xy 309.925761 -280.07614) (xy 309.900066 -280.076656)
			(xy 309.899558 -280.076656) (xy 309.865268 -280.074624) (xy 309.86476 -280.074624) (xy 309.853584 -280.073354)
			(xy 309.831994 -280.080974) (xy 309.75935 -280.154126) (xy 309.751984 -280.175716) (xy 309.752238 -280.179018)
			(xy 309.753781 -280.190513) (xy 309.755436 -280.213649) (xy 309.75554 -280.225246) (xy 309.75554 -280.273252)
			(xy 309.755961 -280.283975) (xy 309.764652 -280.303574) (xy 309.772304 -280.311098) (xy 309.82793 -280.36139)
			(xy 309.836195 -280.368111) (xy 309.8564 -280.374784) (xy 309.867046 -280.374344) (xy 309.8673 -280.374344)
			(xy 309.899812 -280.37282) (xy 309.925498 -280.373325) (xy 309.976237 -280.381363) (xy 310.025093 -280.397239)
			(xy 310.070865 -280.420562) (xy 310.112425 -280.450758) (xy 310.148749 -280.487084) (xy 310.178944 -280.528645)
			(xy 310.202266 -280.574418) (xy 310.21814 -280.623275) (xy 310.226176 -280.674014) (xy 310.226176 -280.725386)
			(xy 310.22617 -280.725426) (xy 311.473084 -280.725426) (xy 311.473084 -280.67401) (xy 311.481127 -280.623228)
			(xy 311.497015 -280.574329) (xy 311.520358 -280.528517) (xy 311.550579 -280.486921) (xy 311.586935 -280.450565)
			(xy 311.628531 -280.420344) (xy 311.674343 -280.397001) (xy 311.723242 -280.381113) (xy 311.774024 -280.37307)
			(xy 311.82544 -280.37307) (xy 311.876222 -280.381113) (xy 311.925121 -280.397001) (xy 311.970933 -280.420344)
			(xy 312.012529 -280.450565) (xy 312.048885 -280.486921) (xy 312.079106 -280.528517) (xy 312.102449 -280.574329)
			(xy 312.118337 -280.623228) (xy 312.12638 -280.67401) (xy 312.126884 -280.699718) (xy 312.12638 -280.725426)
			(xy 312.118337 -280.776208) (xy 312.102449 -280.825107) (xy 312.079106 -280.870919) (xy 312.048885 -280.912515)
			(xy 312.012529 -280.948871) (xy 311.970933 -280.979092) (xy 311.925121 -281.002435) (xy 311.876222 -281.018323)
			(xy 311.82544 -281.026366) (xy 311.774024 -281.026366) (xy 311.723242 -281.018323) (xy 311.674343 -281.002435)
			(xy 311.628531 -280.979092) (xy 311.586935 -280.948871) (xy 311.550579 -280.912515) (xy 311.520358 -280.870919)
			(xy 311.497015 -280.825107) (xy 311.481127 -280.776208) (xy 311.473084 -280.725426) (xy 310.22617 -280.725426)
			(xy 310.21814 -280.776125) (xy 310.202266 -280.824982) (xy 310.178944 -280.870755) (xy 310.148749 -280.912316)
			(xy 310.112425 -280.948642) (xy 310.070865 -280.978838) (xy 310.025093 -281.002161) (xy 309.976237 -281.018037)
			(xy 309.925498 -281.026075) (xy 309.899812 -281.026616) (xy 309.8673 -281.025092) (xy 309.867046 -281.025092)
			(xy 309.856381 -281.024481) (xy 309.836121 -281.031189) (xy 309.82793 -281.038046) (xy 309.772304 -281.088338)
			(xy 309.764768 -281.095939) (xy 309.756126 -281.115494) (xy 309.75554 -281.126184) (xy 309.75554 -281.175206)
			(xy 309.754778 -281.196796) (xy 309.754524 -281.198574) (xy 309.754524 -281.199082) (xy 309.753762 -281.209496)
			(xy 309.757318 -281.219402) (xy 309.759198 -281.22416) (xy 309.764574 -281.232862) (xy 309.767986 -281.236674)
			(xy 309.821072 -281.293824) (xy 309.828335 -281.300183) (xy 309.846227 -281.307387) (xy 309.85587 -281.307794)
			(xy 313.743594 -281.307794) (xy 313.754045 -281.307239) (xy 313.7732 -281.298858) (xy 313.780678 -281.291538)
			(xy 313.831732 -281.23642) (xy 313.837282 -281.229905) (xy 313.844051 -281.214197) (xy 313.84494 -281.205686)
			(xy 313.84494 -281.198828) (xy 313.844686 -281.19705) (xy 313.843924 -281.175206) (xy 313.843924 -281.174698)
			(xy 313.844455 -281.14874) (xy 313.852615 -281.097468) (xy 313.868688 -281.048102) (xy 313.892278 -281.001854)
			(xy 313.922806 -280.95986) (xy 313.959521 -280.923154) (xy 314.001522 -280.892636) (xy 314.047776 -280.869057)
			(xy 314.097146 -280.852997) (xy 314.14842 -280.844849) (xy 314.174378 -280.844244) (xy 315.124846 -280.844244)
			(xy 315.150825 -280.844756) (xy 315.202144 -280.852883) (xy 315.251563 -280.868929) (xy 315.297867 -280.892501)
			(xy 315.339918 -280.92302) (xy 315.376684 -280.959735) (xy 315.40726 -281.001744) (xy 315.430896 -281.048015)
			(xy 315.447011 -281.097412) (xy 315.455208 -281.14872) (xy 315.455808 -281.174698) (xy 315.455808 -281.175206)
			(xy 315.455046 -281.196796) (xy 315.454792 -281.198574) (xy 315.454792 -281.199082) (xy 315.45403 -281.209496)
			(xy 315.457586 -281.219402) (xy 315.459469 -281.224158) (xy 315.46485 -281.232855) (xy 315.468254 -281.236674)
			(xy 315.52134 -281.293824) (xy 315.528607 -281.300172) (xy 315.546499 -281.307353) (xy 315.556138 -281.307794)
			(xy 323.944488 -281.307794) (xy 323.95414 -281.306778) (xy 323.961385 -281.305152) (xy 323.974557 -281.298314)
			(xy 323.980048 -281.293316) (xy 329.179174 -276.09419) (xy 329.184157 -276.088689) (xy 329.190995 -276.075522)
			(xy 329.192636 -276.068282) (xy 329.193652 -276.05863) (xy 329.193652 -262.486394) (xy 329.193491 -262.480383)
			(xy 329.190679 -262.468694) (xy 329.188064 -262.46328) (xy 329.186223 -262.459807) (xy 329.181627 -262.45343)
			(xy 329.17892 -262.45058) (xy 322.274184 -255.545844) (xy 322.271333 -255.543138) (xy 322.264954 -255.538547)
			(xy 322.261484 -255.5367) (xy 322.256058 -255.534114) (xy 322.244378 -255.531284) (xy 322.23837 -255.531112)
			(xy 317.203328 -255.531112) (xy 317.192152 -255.533652) (xy 317.187072 -255.536192) (xy 317.160766 -255.548498)
			(xy 317.10536 -255.565901) (xy 317.047961 -255.574729) (xy 317.018924 -255.575308) (xy 316.989884 -255.574769)
			(xy 316.932475 -255.565958) (xy 316.877074 -255.548524) (xy 316.850776 -255.536192) (xy 316.845696 -255.533652)
			(xy 316.83452 -255.531112) (xy 293.562786 -255.531112) (xy 293.550936 -255.531727) (xy 293.529724 -255.542299)
			(xy 293.515449 -255.561217) (xy 293.512748 -255.572768) (xy 293.164044 -257.469894) (xy 304.342292 -257.469894)
			(xy 304.342746 -257.442966) (xy 304.350333 -257.389648) (xy 304.36534 -257.337926) (xy 304.38747 -257.288827)
			(xy 304.416283 -257.243327) (xy 304.451206 -257.20233) (xy 304.47107 -257.184144) (xy 304.478182 -257.177794)
			(xy 304.486564 -257.161792) (xy 304.496978 -257.076448) (xy 304.49266 -257.058414) (xy 304.487326 -257.050794)
			(xy 304.47154 -257.026901) (xy 304.446598 -256.975351) (xy 304.429642 -256.920653) (xy 304.421052 -256.864035)
			(xy 304.420524 -256.835402) (xy 304.420524 -256.834894) (xy 304.42101 -256.807643) (xy 304.428766 -256.753695)
			(xy 304.444121 -256.7014) (xy 304.466763 -256.651823) (xy 304.496229 -256.605973) (xy 304.53192 -256.564782)
			(xy 304.573111 -256.529091) (xy 304.618961 -256.499625) (xy 304.668538 -256.476983) (xy 304.720833 -256.461628)
			(xy 304.774781 -256.453872) (xy 304.829283 -256.453872) (xy 304.883231 -256.461628) (xy 304.935526 -256.476983)
			(xy 304.985103 -256.499625) (xy 305.030953 -256.529091) (xy 305.072144 -256.564782) (xy 305.107835 -256.605973)
			(xy 305.137301 -256.651823) (xy 305.159943 -256.7014) (xy 305.175298 -256.753695) (xy 305.183054 -256.807643)
			(xy 305.18354 -256.834894) (xy 305.286408 -256.834894) (xy 305.290479 -256.779272) (xy 305.302605 -256.724835)
			(xy 305.322528 -256.672744) (xy 305.349824 -256.624109) (xy 305.38391 -256.579966) (xy 305.424059 -256.541257)
			(xy 305.469417 -256.508806) (xy 305.519017 -256.483305) (xy 305.571801 -256.465298) (xy 305.626644 -256.455168)
			(xy 305.682378 -256.453131) (xy 305.737815 -256.459231) (xy 305.791772 -256.473337) (xy 305.843101 -256.495149)
			(xy 305.890707 -256.524203) (xy 305.933575 -256.559878) (xy 305.970792 -256.601415) (xy 306.001565 -256.647928)
			(xy 306.025237 -256.698425) (xy 306.041305 -256.751832) (xy 306.049425 -256.807008) (xy 306.049934 -256.834894)
			(xy 306.049425 -256.86278) (xy 306.041305 -256.917956) (xy 306.025237 -256.971363) (xy 306.001565 -257.02186)
			(xy 305.970792 -257.068373) (xy 305.933575 -257.10991) (xy 305.890707 -257.145585) (xy 305.843101 -257.174639)
			(xy 305.791772 -257.196451) (xy 305.737815 -257.210557) (xy 305.682378 -257.216657) (xy 305.626644 -257.21462)
			(xy 305.571801 -257.20449) (xy 305.519017 -257.186483) (xy 305.469417 -257.160982) (xy 305.424059 -257.128531)
			(xy 305.38391 -257.089822) (xy 305.349824 -257.045679) (xy 305.322528 -256.997044) (xy 305.302605 -256.944953)
			(xy 305.290479 -256.890516) (xy 305.286408 -256.834894) (xy 305.18354 -256.834894) (xy 305.183067 -256.861821)
			(xy 305.175483 -256.915138) (xy 305.160479 -256.966859) (xy 305.138352 -257.015958) (xy 305.109543 -257.061458)
			(xy 305.074624 -257.102457) (xy 305.054762 -257.120644) (xy 305.04765 -257.126994) (xy 305.039268 -257.142996)
			(xy 305.028854 -257.22834) (xy 305.033172 -257.246374) (xy 305.038506 -257.253994) (xy 305.054278 -257.277896)
			(xy 305.079225 -257.329441) (xy 305.096185 -257.384137) (xy 305.104778 -257.440754) (xy 305.105308 -257.469386)
			(xy 305.105308 -257.469894) (xy 305.104822 -257.497145) (xy 305.097066 -257.551093) (xy 305.081711 -257.603388)
			(xy 305.059069 -257.652965) (xy 305.029603 -257.698815) (xy 304.993912 -257.740006) (xy 304.97176 -257.7592)
			(xy 316.101982 -257.7592) (xy 316.106053 -257.703578) (xy 316.118179 -257.649141) (xy 316.138102 -257.59705)
			(xy 316.165398 -257.548415) (xy 316.199484 -257.504272) (xy 316.239633 -257.465563) (xy 316.284991 -257.433112)
			(xy 316.334591 -257.407611) (xy 316.387375 -257.389604) (xy 316.442218 -257.379474) (xy 316.497952 -257.377437)
			(xy 316.553389 -257.383537) (xy 316.607346 -257.397643) (xy 316.658675 -257.419455) (xy 316.706281 -257.448509)
			(xy 316.749149 -257.484184) (xy 316.786366 -257.525721) (xy 316.817139 -257.572234) (xy 316.840811 -257.622731)
			(xy 316.842743 -257.629152) (xy 317.752982 -257.629152) (xy 317.757053 -257.57353) (xy 317.769179 -257.519093)
			(xy 317.789102 -257.467002) (xy 317.816398 -257.418367) (xy 317.850484 -257.374224) (xy 317.890633 -257.335515)
			(xy 317.935991 -257.303064) (xy 317.985591 -257.277563) (xy 318.038375 -257.259556) (xy 318.093218 -257.249426)
			(xy 318.148952 -257.247389) (xy 318.204389 -257.253489) (xy 318.258346 -257.267595) (xy 318.309675 -257.289407)
			(xy 318.357281 -257.318461) (xy 318.400149 -257.354136) (xy 318.437366 -257.395673) (xy 318.468139 -257.442186)
			(xy 318.491811 -257.492683) (xy 318.507879 -257.54609) (xy 318.515999 -257.601266) (xy 318.516508 -257.629152)
			(xy 318.515999 -257.657038) (xy 318.507879 -257.712214) (xy 318.491811 -257.765621) (xy 318.468139 -257.816118)
			(xy 318.437366 -257.862631) (xy 318.400149 -257.904168) (xy 318.357281 -257.939843) (xy 318.309675 -257.968897)
			(xy 318.258346 -257.990709) (xy 318.204389 -258.004815) (xy 318.148952 -258.010915) (xy 318.093218 -258.008878)
			(xy 318.038375 -257.998748) (xy 317.985591 -257.980741) (xy 317.935991 -257.95524) (xy 317.890633 -257.922789)
			(xy 317.850484 -257.88408) (xy 317.816398 -257.839937) (xy 317.789102 -257.791302) (xy 317.769179 -257.739211)
			(xy 317.757053 -257.684774) (xy 317.752982 -257.629152) (xy 316.842743 -257.629152) (xy 316.856879 -257.676138)
			(xy 316.864999 -257.731314) (xy 316.865508 -257.7592) (xy 316.864999 -257.787086) (xy 316.856879 -257.842262)
			(xy 316.840811 -257.895669) (xy 316.817139 -257.946166) (xy 316.786366 -257.992679) (xy 316.749149 -258.034216)
			(xy 316.706281 -258.069891) (xy 316.658675 -258.098945) (xy 316.607346 -258.120757) (xy 316.553389 -258.134863)
			(xy 316.497952 -258.140963) (xy 316.442218 -258.138926) (xy 316.387375 -258.128796) (xy 316.334591 -258.110789)
			(xy 316.284991 -258.085288) (xy 316.239633 -258.052837) (xy 316.199484 -258.014128) (xy 316.165398 -257.969985)
			(xy 316.138102 -257.92135) (xy 316.118179 -257.869259) (xy 316.106053 -257.814822) (xy 316.101982 -257.7592)
			(xy 304.97176 -257.7592) (xy 304.952721 -257.775697) (xy 304.906871 -257.805163) (xy 304.857294 -257.827805)
			(xy 304.804999 -257.84316) (xy 304.751051 -257.850916) (xy 304.696549 -257.850916) (xy 304.642601 -257.84316)
			(xy 304.590306 -257.827805) (xy 304.540729 -257.805163) (xy 304.494879 -257.775697) (xy 304.453688 -257.740006)
			(xy 304.417997 -257.698815) (xy 304.388531 -257.652965) (xy 304.365889 -257.603388) (xy 304.350534 -257.551093)
			(xy 304.342778 -257.497145) (xy 304.342292 -257.469894) (xy 293.164044 -257.469894) (xy 292.894661 -258.935474)
			(xy 304.875182 -258.935474) (xy 304.879253 -258.879852) (xy 304.891379 -258.825415) (xy 304.911302 -258.773324)
			(xy 304.938598 -258.724689) (xy 304.972684 -258.680546) (xy 305.012833 -258.641837) (xy 305.058191 -258.609386)
			(xy 305.107791 -258.583885) (xy 305.160575 -258.565878) (xy 305.215418 -258.555748) (xy 305.271152 -258.553711)
			(xy 305.326589 -258.559811) (xy 305.380546 -258.573917) (xy 305.431875 -258.595729) (xy 305.479481 -258.624783)
			(xy 305.522349 -258.660458) (xy 305.559566 -258.701995) (xy 305.590339 -258.748508) (xy 305.614011 -258.799005)
			(xy 305.630079 -258.852412) (xy 305.638199 -258.907588) (xy 305.638708 -258.935474) (xy 305.638199 -258.96336)
			(xy 305.630079 -259.018536) (xy 305.614011 -259.071943) (xy 305.590339 -259.12244) (xy 305.559566 -259.168953)
			(xy 305.522349 -259.21049) (xy 305.479481 -259.246165) (xy 305.431875 -259.275219) (xy 305.380546 -259.297031)
			(xy 305.326589 -259.311137) (xy 305.271152 -259.317237) (xy 305.215418 -259.3152) (xy 305.160575 -259.30507)
			(xy 305.107791 -259.287063) (xy 305.058191 -259.261562) (xy 305.012833 -259.229111) (xy 304.972684 -259.190402)
			(xy 304.938598 -259.146259) (xy 304.911302 -259.097624) (xy 304.891379 -259.045533) (xy 304.879253 -258.991096)
			(xy 304.875182 -258.935474) (xy 292.894661 -258.935474) (xy 292.577564 -260.660642) (xy 317.663574 -260.660642)
			(xy 317.667645 -260.60502) (xy 317.679771 -260.550583) (xy 317.699694 -260.498492) (xy 317.72699 -260.449857)
			(xy 317.761076 -260.405714) (xy 317.801225 -260.367005) (xy 317.846583 -260.334554) (xy 317.896183 -260.309053)
			(xy 317.948967 -260.291046) (xy 318.00381 -260.280916) (xy 318.059544 -260.278879) (xy 318.114981 -260.284979)
			(xy 318.168938 -260.299085) (xy 318.220267 -260.320897) (xy 318.267873 -260.349951) (xy 318.310741 -260.385626)
			(xy 318.347958 -260.427163) (xy 318.378731 -260.473676) (xy 318.402403 -260.524173) (xy 318.418471 -260.57758)
			(xy 318.426591 -260.632756) (xy 318.4271 -260.660642) (xy 318.426591 -260.688528) (xy 318.418471 -260.743704)
			(xy 318.402403 -260.797111) (xy 318.378731 -260.847608) (xy 318.347958 -260.894121) (xy 318.310741 -260.935658)
			(xy 318.267873 -260.971333) (xy 318.220267 -261.000387) (xy 318.168938 -261.022199) (xy 318.114981 -261.036305)
			(xy 318.059544 -261.042405) (xy 318.00381 -261.040368) (xy 317.948967 -261.030238) (xy 317.896183 -261.012231)
			(xy 317.846583 -260.98673) (xy 317.801225 -260.954279) (xy 317.761076 -260.91557) (xy 317.72699 -260.871427)
			(xy 317.699694 -260.822792) (xy 317.679771 -260.770701) (xy 317.667645 -260.716264) (xy 317.663574 -260.660642)
			(xy 292.577564 -260.660642) (xy 292.503939 -261.0612) (xy 316.178182 -261.0612) (xy 316.182253 -261.005578)
			(xy 316.194379 -260.951141) (xy 316.214302 -260.89905) (xy 316.241598 -260.850415) (xy 316.275684 -260.806272)
			(xy 316.315833 -260.767563) (xy 316.361191 -260.735112) (xy 316.410791 -260.709611) (xy 316.463575 -260.691604)
			(xy 316.518418 -260.681474) (xy 316.574152 -260.679437) (xy 316.629589 -260.685537) (xy 316.683546 -260.699643)
			(xy 316.734875 -260.721455) (xy 316.782481 -260.750509) (xy 316.825349 -260.786184) (xy 316.862566 -260.827721)
			(xy 316.893339 -260.874234) (xy 316.917011 -260.924731) (xy 316.933079 -260.978138) (xy 316.941199 -261.033314)
			(xy 316.941708 -261.0612) (xy 316.941199 -261.089086) (xy 316.933079 -261.144262) (xy 316.917011 -261.197669)
			(xy 316.893339 -261.248166) (xy 316.862566 -261.294679) (xy 316.825349 -261.336216) (xy 316.782481 -261.371891)
			(xy 316.734875 -261.400945) (xy 316.683546 -261.422757) (xy 316.629589 -261.436863) (xy 316.574152 -261.442963)
			(xy 316.518418 -261.440926) (xy 316.463575 -261.430796) (xy 316.410791 -261.412789) (xy 316.361191 -261.387288)
			(xy 316.315833 -261.354837) (xy 316.275684 -261.316128) (xy 316.241598 -261.271985) (xy 316.214302 -261.22335)
			(xy 316.194379 -261.171259) (xy 316.182253 -261.116822) (xy 316.178182 -261.0612) (xy 292.503939 -261.0612)
			(xy 291.563806 -266.175998) (xy 291.563044 -266.185142) (xy 291.563044 -270.89989) (xy 319.082429 -270.89989)
			(xy 319.086418 -270.75135) (xy 319.098375 -270.603237) (xy 319.118265 -270.45598) (xy 319.14603 -270.310004)
			(xy 319.181591 -270.165727) (xy 319.224845 -270.023568) (xy 319.275667 -269.883935) (xy 319.333911 -269.747232)
			(xy 319.399409 -269.613852) (xy 319.471972 -269.48418) (xy 319.55139 -269.35859) (xy 319.637435 -269.237443)
			(xy 319.729859 -269.12109) (xy 319.828395 -269.009866) (xy 319.932759 -268.904091) (xy 320.042651 -268.804071)
			(xy 320.157752 -268.710093) (xy 320.277732 -268.622429) (xy 320.402245 -268.541332) (xy 320.530931 -268.467035)
			(xy 320.66342 -268.399753) (xy 320.799329 -268.339679) (xy 320.938267 -268.286987) (xy 321.079833 -268.241828)
			(xy 321.223619 -268.204333) (xy 321.36921 -268.174611) (xy 321.516186 -268.152746) (xy 321.664125 -268.138802)
			(xy 321.812598 -268.132818) (xy 321.961179 -268.134813) (xy 322.109438 -268.144781) (xy 322.256949 -268.162692)
			(xy 322.403285 -268.188495) (xy 322.548026 -268.222115) (xy 322.690753 -268.263457) (xy 322.831056 -268.3124)
			(xy 322.968529 -268.368803) (xy 323.102776 -268.432504) (xy 323.233411 -268.50332) (xy 323.360056 -268.581045)
			(xy 323.482346 -268.665456) (xy 323.599929 -268.756309) (xy 323.712466 -268.853343) (xy 323.819633 -268.956278)
			(xy 323.92112 -269.064817) (xy 324.016634 -269.178646) (xy 324.105901 -269.297439) (xy 324.188662 -269.420851)
			(xy 324.26468 -269.548529) (xy 324.333735 -269.680102) (xy 324.395628 -269.815193) (xy 324.450181 -269.95341)
			(xy 324.497236 -270.094357) (xy 324.536658 -270.237627) (xy 324.568332 -270.382806) (xy 324.592168 -270.529475)
			(xy 324.608097 -270.677213) (xy 324.616073 -270.825593) (xy 324.616572 -270.89989) (xy 324.616073 -270.974187)
			(xy 324.608097 -271.122567) (xy 324.592168 -271.270305) (xy 324.568332 -271.416974) (xy 324.536658 -271.562153)
			(xy 324.497236 -271.705423) (xy 324.450181 -271.84637) (xy 324.395628 -271.984587) (xy 324.333735 -272.119678)
			(xy 324.26468 -272.251251) (xy 324.188662 -272.378929) (xy 324.105901 -272.502341) (xy 324.016634 -272.621134)
			(xy 323.92112 -272.734963) (xy 323.819633 -272.843502) (xy 323.712466 -272.946437) (xy 323.599929 -273.043471)
			(xy 323.482346 -273.134324) (xy 323.360056 -273.218735) (xy 323.233411 -273.29646) (xy 323.102776 -273.367276)
			(xy 322.968529 -273.430977) (xy 322.831056 -273.48738) (xy 322.690753 -273.536323) (xy 322.548026 -273.577665)
			(xy 322.403285 -273.611285) (xy 322.256949 -273.637088) (xy 322.109438 -273.654999) (xy 321.961179 -273.664967)
			(xy 321.812598 -273.666962) (xy 321.664125 -273.660978) (xy 321.516186 -273.647034) (xy 321.36921 -273.625169)
			(xy 321.223619 -273.595447) (xy 321.079833 -273.557952) (xy 320.938267 -273.512793) (xy 320.799329 -273.460101)
			(xy 320.66342 -273.400027) (xy 320.530931 -273.332745) (xy 320.402245 -273.258448) (xy 320.277732 -273.177351)
			(xy 320.157752 -273.089687) (xy 320.042651 -272.995709) (xy 319.932759 -272.895689) (xy 319.828395 -272.789914)
			(xy 319.729859 -272.67869) (xy 319.637435 -272.562337) (xy 319.55139 -272.44119) (xy 319.471972 -272.3156)
			(xy 319.399409 -272.185928) (xy 319.333911 -272.052548) (xy 319.275667 -271.915845) (xy 319.224845 -271.776212)
			(xy 319.181591 -271.634053) (xy 319.14603 -271.489776) (xy 319.118265 -271.3438) (xy 319.098375 -271.196543)
			(xy 319.086418 -271.04843) (xy 319.082429 -270.89989) (xy 291.563044 -270.89989) (xy 291.563044 -271.399)
			(xy 291.562548 -271.445205) (xy 291.554041 -271.537222) (xy 291.537045 -271.628055) (xy 291.511707 -271.716923)
			(xy 291.49548 -271.760188) (xy 291.493879 -271.764593) (xy 291.492096 -271.773792) (xy 291.491924 -271.778476)
			(xy 291.491924 -272.755868) (xy 291.492403 -272.765206) (xy 291.49919 -272.782611) (xy 291.511738 -272.796451)
			(xy 291.519864 -272.80108) (xy 291.601144 -272.841974) (xy 291.609734 -272.845771) (xy 291.628416 -272.847528)
			(xy 291.646482 -272.842453) (xy 291.65423 -272.837148) (xy 291.675486 -272.821975) (xy 291.721812 -272.797873)
			(xy 291.771384 -272.781452) (xy 291.822938 -272.773131) (xy 291.849048 -272.772632) (xy 291.849556 -272.772632)
			(xy 291.875246 -272.773106) (xy 291.925993 -272.781138) (xy 291.97486 -272.79701) (xy 292.020641 -272.820331)
			(xy 292.062211 -272.850528) (xy 292.098544 -272.886856) (xy 292.128746 -272.928421) (xy 292.152073 -272.974199)
			(xy 292.167952 -273.023064) (xy 292.17599 -273.07381) (xy 292.17599 -273.12519) (xy 292.175942 -273.125492)
			(xy 293.422828 -273.125492) (xy 293.422828 -273.074076) (xy 293.430871 -273.023294) (xy 293.446759 -272.974395)
			(xy 293.470102 -272.928583) (xy 293.500323 -272.886987) (xy 293.536679 -272.850631) (xy 293.578275 -272.82041)
			(xy 293.624087 -272.797067) (xy 293.672986 -272.781179) (xy 293.723768 -272.773136) (xy 293.775184 -272.773136)
			(xy 293.825966 -272.781179) (xy 293.874865 -272.797067) (xy 293.920677 -272.82041) (xy 293.962273 -272.850631)
			(xy 293.998629 -272.886987) (xy 294.02885 -272.928583) (xy 294.052193 -272.974395) (xy 294.068081 -273.023294)
			(xy 294.076124 -273.074076) (xy 294.076628 -273.099784) (xy 294.076124 -273.125492) (xy 295.323002 -273.125492)
			(xy 295.323002 -273.074076) (xy 295.331045 -273.023294) (xy 295.346933 -272.974395) (xy 295.370276 -272.928583)
			(xy 295.400497 -272.886987) (xy 295.436853 -272.850631) (xy 295.478449 -272.82041) (xy 295.524261 -272.797067)
			(xy 295.57316 -272.781179) (xy 295.623942 -272.773136) (xy 295.675358 -272.773136) (xy 295.72614 -272.781179)
			(xy 295.775039 -272.797067) (xy 295.820851 -272.82041) (xy 295.862447 -272.850631) (xy 295.898803 -272.886987)
			(xy 295.929024 -272.928583) (xy 295.952367 -272.974395) (xy 295.968255 -273.023294) (xy 295.976298 -273.074076)
			(xy 295.976802 -273.099784) (xy 295.976298 -273.125492) (xy 297.222922 -273.125492) (xy 297.222922 -273.074076)
			(xy 297.230965 -273.023294) (xy 297.246853 -272.974395) (xy 297.270196 -272.928583) (xy 297.300417 -272.886987)
			(xy 297.336773 -272.850631) (xy 297.378369 -272.82041) (xy 297.424181 -272.797067) (xy 297.47308 -272.781179)
			(xy 297.523862 -272.773136) (xy 297.575278 -272.773136) (xy 297.62606 -272.781179) (xy 297.674959 -272.797067)
			(xy 297.720771 -272.82041) (xy 297.762367 -272.850631) (xy 297.798723 -272.886987) (xy 297.828944 -272.928583)
			(xy 297.852287 -272.974395) (xy 297.868175 -273.023294) (xy 297.876218 -273.074076) (xy 297.876722 -273.099784)
			(xy 297.876218 -273.125492) (xy 299.122842 -273.125492) (xy 299.122842 -273.074076) (xy 299.130885 -273.023294)
			(xy 299.146773 -272.974395) (xy 299.170116 -272.928583) (xy 299.200337 -272.886987) (xy 299.236693 -272.850631)
			(xy 299.278289 -272.82041) (xy 299.324101 -272.797067) (xy 299.373 -272.781179) (xy 299.423782 -272.773136)
			(xy 299.475198 -272.773136) (xy 299.52598 -272.781179) (xy 299.574879 -272.797067) (xy 299.620691 -272.82041)
			(xy 299.662287 -272.850631) (xy 299.698643 -272.886987) (xy 299.728864 -272.928583) (xy 299.752207 -272.974395)
			(xy 299.768095 -273.023294) (xy 299.776138 -273.074076) (xy 299.776642 -273.099784) (xy 299.776138 -273.125492)
			(xy 301.023016 -273.125492) (xy 301.023016 -273.074076) (xy 301.031059 -273.023294) (xy 301.046947 -272.974395)
			(xy 301.07029 -272.928583) (xy 301.100511 -272.886987) (xy 301.136867 -272.850631) (xy 301.178463 -272.82041)
			(xy 301.224275 -272.797067) (xy 301.273174 -272.781179) (xy 301.323956 -272.773136) (xy 301.375372 -272.773136)
			(xy 301.426154 -272.781179) (xy 301.475053 -272.797067) (xy 301.520865 -272.82041) (xy 301.562461 -272.850631)
			(xy 301.598817 -272.886987) (xy 301.629038 -272.928583) (xy 301.652381 -272.974395) (xy 301.668269 -273.023294)
			(xy 301.676312 -273.074076) (xy 301.676816 -273.099784) (xy 301.676312 -273.125492) (xy 302.922936 -273.125492)
			(xy 302.922936 -273.074076) (xy 302.930979 -273.023294) (xy 302.946867 -272.974395) (xy 302.97021 -272.928583)
			(xy 303.000431 -272.886987) (xy 303.036787 -272.850631) (xy 303.078383 -272.82041) (xy 303.124195 -272.797067)
			(xy 303.173094 -272.781179) (xy 303.223876 -272.773136) (xy 303.275292 -272.773136) (xy 303.326074 -272.781179)
			(xy 303.374973 -272.797067) (xy 303.420785 -272.82041) (xy 303.462381 -272.850631) (xy 303.498737 -272.886987)
			(xy 303.528958 -272.928583) (xy 303.552301 -272.974395) (xy 303.568189 -273.023294) (xy 303.576232 -273.074076)
			(xy 303.576736 -273.099784) (xy 303.576232 -273.125492) (xy 304.822856 -273.125492) (xy 304.822856 -273.074076)
			(xy 304.830899 -273.023294) (xy 304.846787 -272.974395) (xy 304.87013 -272.928583) (xy 304.900351 -272.886987)
			(xy 304.936707 -272.850631) (xy 304.978303 -272.82041) (xy 305.024115 -272.797067) (xy 305.073014 -272.781179)
			(xy 305.123796 -272.773136) (xy 305.175212 -272.773136) (xy 305.225994 -272.781179) (xy 305.274893 -272.797067)
			(xy 305.320705 -272.82041) (xy 305.362301 -272.850631) (xy 305.398657 -272.886987) (xy 305.428878 -272.928583)
			(xy 305.452221 -272.974395) (xy 305.468109 -273.023294) (xy 305.476152 -273.074076) (xy 305.476656 -273.099784)
			(xy 305.476152 -273.125492) (xy 306.72303 -273.125492) (xy 306.72303 -273.074076) (xy 306.731073 -273.023294)
			(xy 306.746961 -272.974395) (xy 306.770304 -272.928583) (xy 306.800525 -272.886987) (xy 306.836881 -272.850631)
			(xy 306.878477 -272.82041) (xy 306.924289 -272.797067) (xy 306.973188 -272.781179) (xy 307.02397 -272.773136)
			(xy 307.075386 -272.773136) (xy 307.126168 -272.781179) (xy 307.175067 -272.797067) (xy 307.220879 -272.82041)
			(xy 307.262475 -272.850631) (xy 307.298831 -272.886987) (xy 307.329052 -272.928583) (xy 307.352395 -272.974395)
			(xy 307.368283 -273.023294) (xy 307.376326 -273.074076) (xy 307.37683 -273.099784) (xy 307.376326 -273.125492)
			(xy 308.62295 -273.125492) (xy 308.62295 -273.074076) (xy 308.630993 -273.023294) (xy 308.646881 -272.974395)
			(xy 308.670224 -272.928583) (xy 308.700445 -272.886987) (xy 308.736801 -272.850631) (xy 308.778397 -272.82041)
			(xy 308.824209 -272.797067) (xy 308.873108 -272.781179) (xy 308.92389 -272.773136) (xy 308.975306 -272.773136)
			(xy 309.026088 -272.781179) (xy 309.074987 -272.797067) (xy 309.120799 -272.82041) (xy 309.162395 -272.850631)
			(xy 309.198751 -272.886987) (xy 309.228972 -272.928583) (xy 309.252315 -272.974395) (xy 309.268203 -273.023294)
			(xy 309.276246 -273.074076) (xy 309.27675 -273.099784) (xy 309.276246 -273.125492) (xy 310.52287 -273.125492)
			(xy 310.52287 -273.074076) (xy 310.530913 -273.023294) (xy 310.546801 -272.974395) (xy 310.570144 -272.928583)
			(xy 310.600365 -272.886987) (xy 310.636721 -272.850631) (xy 310.678317 -272.82041) (xy 310.724129 -272.797067)
			(xy 310.773028 -272.781179) (xy 310.82381 -272.773136) (xy 310.875226 -272.773136) (xy 310.926008 -272.781179)
			(xy 310.974907 -272.797067) (xy 311.020719 -272.82041) (xy 311.062315 -272.850631) (xy 311.098671 -272.886987)
			(xy 311.128892 -272.928583) (xy 311.152235 -272.974395) (xy 311.168123 -273.023294) (xy 311.176166 -273.074076)
			(xy 311.17667 -273.099784) (xy 311.176166 -273.125492) (xy 312.42279 -273.125492) (xy 312.42279 -273.074076)
			(xy 312.430833 -273.023294) (xy 312.446721 -272.974395) (xy 312.470064 -272.928583) (xy 312.500285 -272.886987)
			(xy 312.536641 -272.850631) (xy 312.578237 -272.82041) (xy 312.624049 -272.797067) (xy 312.672948 -272.781179)
			(xy 312.72373 -272.773136) (xy 312.775146 -272.773136) (xy 312.825928 -272.781179) (xy 312.874827 -272.797067)
			(xy 312.920639 -272.82041) (xy 312.962235 -272.850631) (xy 312.998591 -272.886987) (xy 313.028812 -272.928583)
			(xy 313.052155 -272.974395) (xy 313.068043 -273.023294) (xy 313.076086 -273.074076) (xy 313.07659 -273.099784)
			(xy 313.076086 -273.125492) (xy 313.068043 -273.176274) (xy 313.052155 -273.225173) (xy 313.028812 -273.270985)
			(xy 312.998591 -273.312581) (xy 312.962235 -273.348937) (xy 312.920639 -273.379158) (xy 312.874827 -273.402501)
			(xy 312.825928 -273.418389) (xy 312.775146 -273.426432) (xy 312.72373 -273.426432) (xy 312.672948 -273.418389)
			(xy 312.624049 -273.402501) (xy 312.578237 -273.379158) (xy 312.536641 -273.348937) (xy 312.500285 -273.312581)
			(xy 312.470064 -273.270985) (xy 312.446721 -273.225173) (xy 312.430833 -273.176274) (xy 312.42279 -273.125492)
			(xy 311.176166 -273.125492) (xy 311.168123 -273.176274) (xy 311.152235 -273.225173) (xy 311.128892 -273.270985)
			(xy 311.098671 -273.312581) (xy 311.062315 -273.348937) (xy 311.020719 -273.379158) (xy 310.974907 -273.402501)
			(xy 310.926008 -273.418389) (xy 310.875226 -273.426432) (xy 310.82381 -273.426432) (xy 310.773028 -273.418389)
			(xy 310.724129 -273.402501) (xy 310.678317 -273.379158) (xy 310.636721 -273.348937) (xy 310.600365 -273.312581)
			(xy 310.570144 -273.270985) (xy 310.546801 -273.225173) (xy 310.530913 -273.176274) (xy 310.52287 -273.125492)
			(xy 309.276246 -273.125492) (xy 309.268203 -273.176274) (xy 309.252315 -273.225173) (xy 309.228972 -273.270985)
			(xy 309.198751 -273.312581) (xy 309.162395 -273.348937) (xy 309.120799 -273.379158) (xy 309.074987 -273.402501)
			(xy 309.026088 -273.418389) (xy 308.975306 -273.426432) (xy 308.92389 -273.426432) (xy 308.873108 -273.418389)
			(xy 308.824209 -273.402501) (xy 308.778397 -273.379158) (xy 308.736801 -273.348937) (xy 308.700445 -273.312581)
			(xy 308.670224 -273.270985) (xy 308.646881 -273.225173) (xy 308.630993 -273.176274) (xy 308.62295 -273.125492)
			(xy 307.376326 -273.125492) (xy 307.368283 -273.176274) (xy 307.352395 -273.225173) (xy 307.329052 -273.270985)
			(xy 307.298831 -273.312581) (xy 307.262475 -273.348937) (xy 307.220879 -273.379158) (xy 307.175067 -273.402501)
			(xy 307.126168 -273.418389) (xy 307.075386 -273.426432) (xy 307.02397 -273.426432) (xy 306.973188 -273.418389)
			(xy 306.924289 -273.402501) (xy 306.878477 -273.379158) (xy 306.836881 -273.348937) (xy 306.800525 -273.312581)
			(xy 306.770304 -273.270985) (xy 306.746961 -273.225173) (xy 306.731073 -273.176274) (xy 306.72303 -273.125492)
			(xy 305.476152 -273.125492) (xy 305.468109 -273.176274) (xy 305.452221 -273.225173) (xy 305.428878 -273.270985)
			(xy 305.398657 -273.312581) (xy 305.362301 -273.348937) (xy 305.320705 -273.379158) (xy 305.274893 -273.402501)
			(xy 305.225994 -273.418389) (xy 305.175212 -273.426432) (xy 305.123796 -273.426432) (xy 305.073014 -273.418389)
			(xy 305.024115 -273.402501) (xy 304.978303 -273.379158) (xy 304.936707 -273.348937) (xy 304.900351 -273.312581)
			(xy 304.87013 -273.270985) (xy 304.846787 -273.225173) (xy 304.830899 -273.176274) (xy 304.822856 -273.125492)
			(xy 303.576232 -273.125492) (xy 303.568189 -273.176274) (xy 303.552301 -273.225173) (xy 303.528958 -273.270985)
			(xy 303.498737 -273.312581) (xy 303.462381 -273.348937) (xy 303.420785 -273.379158) (xy 303.374973 -273.402501)
			(xy 303.326074 -273.418389) (xy 303.275292 -273.426432) (xy 303.223876 -273.426432) (xy 303.173094 -273.418389)
			(xy 303.124195 -273.402501) (xy 303.078383 -273.379158) (xy 303.036787 -273.348937) (xy 303.000431 -273.312581)
			(xy 302.97021 -273.270985) (xy 302.946867 -273.225173) (xy 302.930979 -273.176274) (xy 302.922936 -273.125492)
			(xy 301.676312 -273.125492) (xy 301.668269 -273.176274) (xy 301.652381 -273.225173) (xy 301.629038 -273.270985)
			(xy 301.598817 -273.312581) (xy 301.562461 -273.348937) (xy 301.520865 -273.379158) (xy 301.475053 -273.402501)
			(xy 301.426154 -273.418389) (xy 301.375372 -273.426432) (xy 301.323956 -273.426432) (xy 301.273174 -273.418389)
			(xy 301.224275 -273.402501) (xy 301.178463 -273.379158) (xy 301.136867 -273.348937) (xy 301.100511 -273.312581)
			(xy 301.07029 -273.270985) (xy 301.046947 -273.225173) (xy 301.031059 -273.176274) (xy 301.023016 -273.125492)
			(xy 299.776138 -273.125492) (xy 299.768095 -273.176274) (xy 299.752207 -273.225173) (xy 299.728864 -273.270985)
			(xy 299.698643 -273.312581) (xy 299.662287 -273.348937) (xy 299.620691 -273.379158) (xy 299.574879 -273.402501)
			(xy 299.52598 -273.418389) (xy 299.475198 -273.426432) (xy 299.423782 -273.426432) (xy 299.373 -273.418389)
			(xy 299.324101 -273.402501) (xy 299.278289 -273.379158) (xy 299.236693 -273.348937) (xy 299.200337 -273.312581)
			(xy 299.170116 -273.270985) (xy 299.146773 -273.225173) (xy 299.130885 -273.176274) (xy 299.122842 -273.125492)
			(xy 297.876218 -273.125492) (xy 297.868175 -273.176274) (xy 297.852287 -273.225173) (xy 297.828944 -273.270985)
			(xy 297.798723 -273.312581) (xy 297.762367 -273.348937) (xy 297.720771 -273.379158) (xy 297.674959 -273.402501)
			(xy 297.62606 -273.418389) (xy 297.575278 -273.426432) (xy 297.523862 -273.426432) (xy 297.47308 -273.418389)
			(xy 297.424181 -273.402501) (xy 297.378369 -273.379158) (xy 297.336773 -273.348937) (xy 297.300417 -273.312581)
			(xy 297.270196 -273.270985) (xy 297.246853 -273.225173) (xy 297.230965 -273.176274) (xy 297.222922 -273.125492)
			(xy 295.976298 -273.125492) (xy 295.968255 -273.176274) (xy 295.952367 -273.225173) (xy 295.929024 -273.270985)
			(xy 295.898803 -273.312581) (xy 295.862447 -273.348937) (xy 295.820851 -273.379158) (xy 295.775039 -273.402501)
			(xy 295.72614 -273.418389) (xy 295.675358 -273.426432) (xy 295.623942 -273.426432) (xy 295.57316 -273.418389)
			(xy 295.524261 -273.402501) (xy 295.478449 -273.379158) (xy 295.436853 -273.348937) (xy 295.400497 -273.312581)
			(xy 295.370276 -273.270985) (xy 295.346933 -273.225173) (xy 295.331045 -273.176274) (xy 295.323002 -273.125492)
			(xy 294.076124 -273.125492) (xy 294.068081 -273.176274) (xy 294.052193 -273.225173) (xy 294.02885 -273.270985)
			(xy 293.998629 -273.312581) (xy 293.962273 -273.348937) (xy 293.920677 -273.379158) (xy 293.874865 -273.402501)
			(xy 293.825966 -273.418389) (xy 293.775184 -273.426432) (xy 293.723768 -273.426432) (xy 293.672986 -273.418389)
			(xy 293.624087 -273.402501) (xy 293.578275 -273.379158) (xy 293.536679 -273.348937) (xy 293.500323 -273.312581)
			(xy 293.470102 -273.270985) (xy 293.446759 -273.225173) (xy 293.430871 -273.176274) (xy 293.422828 -273.125492)
			(xy 292.175942 -273.125492) (xy 292.167952 -273.175936) (xy 292.152073 -273.224801) (xy 292.128746 -273.270579)
			(xy 292.098544 -273.312144) (xy 292.062211 -273.348472) (xy 292.020641 -273.378669) (xy 291.97486 -273.40199)
			(xy 291.925993 -273.417862) (xy 291.875246 -273.425894) (xy 291.849556 -273.426428) (xy 291.849048 -273.426428)
			(xy 291.822942 -273.425892) (xy 291.771398 -273.41755) (xy 291.721832 -273.401134) (xy 291.6755 -273.377059)
			(xy 291.65423 -273.361912) (xy 291.646469 -273.356628) (xy 291.628414 -273.351541) (xy 291.609738 -273.353302)
			(xy 291.601144 -273.357086) (xy 291.519864 -273.39798) (xy 291.511691 -273.402549) (xy 291.499107 -273.416391)
			(xy 291.492359 -273.433838) (xy 291.491924 -273.443192) (xy 291.491924 -273.705828) (xy 291.492396 -273.71517)
			(xy 291.499175 -273.732586) (xy 291.511721 -273.746438) (xy 291.519864 -273.75104) (xy 291.601144 -273.791934)
			(xy 291.609734 -273.795733) (xy 291.628416 -273.797491) (xy 291.646481 -273.792413) (xy 291.65423 -273.787108)
			(xy 291.675485 -273.771933) (xy 291.72181 -273.747826) (xy 291.771382 -273.731402) (xy 291.822937 -273.723079)
			(xy 291.849048 -273.722592) (xy 291.849556 -273.722592) (xy 291.875249 -273.723066) (xy 291.926003 -273.731098)
			(xy 291.974875 -273.746972) (xy 292.020663 -273.770297) (xy 292.062237 -273.800497) (xy 292.098574 -273.83683)
			(xy 292.12878 -273.8784) (xy 292.152111 -273.924184) (xy 292.167991 -273.973054) (xy 292.17603 -274.023807)
			(xy 292.17603 -274.075193) (xy 292.175989 -274.075452) (xy 293.422828 -274.075452) (xy 293.422828 -274.024036)
			(xy 293.430871 -273.973254) (xy 293.446759 -273.924355) (xy 293.470102 -273.878543) (xy 293.500323 -273.836947)
			(xy 293.536679 -273.800591) (xy 293.578275 -273.77037) (xy 293.624087 -273.747027) (xy 293.672986 -273.731139)
			(xy 293.723768 -273.723096) (xy 293.775184 -273.723096) (xy 293.825966 -273.731139) (xy 293.874865 -273.747027)
			(xy 293.920677 -273.77037) (xy 293.962273 -273.800591) (xy 293.998629 -273.836947) (xy 294.02885 -273.878543)
			(xy 294.052193 -273.924355) (xy 294.068081 -273.973254) (xy 294.076124 -274.024036) (xy 294.076628 -274.049744)
			(xy 294.076124 -274.075452) (xy 295.323002 -274.075452) (xy 295.323002 -274.024036) (xy 295.331045 -273.973254)
			(xy 295.346933 -273.924355) (xy 295.370276 -273.878543) (xy 295.400497 -273.836947) (xy 295.436853 -273.800591)
			(xy 295.478449 -273.77037) (xy 295.524261 -273.747027) (xy 295.57316 -273.731139) (xy 295.623942 -273.723096)
			(xy 295.675358 -273.723096) (xy 295.72614 -273.731139) (xy 295.775039 -273.747027) (xy 295.820851 -273.77037)
			(xy 295.862447 -273.800591) (xy 295.898803 -273.836947) (xy 295.929024 -273.878543) (xy 295.952367 -273.924355)
			(xy 295.968255 -273.973254) (xy 295.976298 -274.024036) (xy 295.976802 -274.049744) (xy 295.976298 -274.075452)
			(xy 297.222922 -274.075452) (xy 297.222922 -274.024036) (xy 297.230965 -273.973254) (xy 297.246853 -273.924355)
			(xy 297.270196 -273.878543) (xy 297.300417 -273.836947) (xy 297.336773 -273.800591) (xy 297.378369 -273.77037)
			(xy 297.424181 -273.747027) (xy 297.47308 -273.731139) (xy 297.523862 -273.723096) (xy 297.575278 -273.723096)
			(xy 297.62606 -273.731139) (xy 297.674959 -273.747027) (xy 297.720771 -273.77037) (xy 297.762367 -273.800591)
			(xy 297.798723 -273.836947) (xy 297.828944 -273.878543) (xy 297.852287 -273.924355) (xy 297.868175 -273.973254)
			(xy 297.876218 -274.024036) (xy 297.876722 -274.049744) (xy 297.876218 -274.075452) (xy 299.122842 -274.075452)
			(xy 299.122842 -274.024036) (xy 299.130885 -273.973254) (xy 299.146773 -273.924355) (xy 299.170116 -273.878543)
			(xy 299.200337 -273.836947) (xy 299.236693 -273.800591) (xy 299.278289 -273.77037) (xy 299.324101 -273.747027)
			(xy 299.373 -273.731139) (xy 299.423782 -273.723096) (xy 299.475198 -273.723096) (xy 299.52598 -273.731139)
			(xy 299.574879 -273.747027) (xy 299.620691 -273.77037) (xy 299.662287 -273.800591) (xy 299.698643 -273.836947)
			(xy 299.728864 -273.878543) (xy 299.752207 -273.924355) (xy 299.768095 -273.973254) (xy 299.776138 -274.024036)
			(xy 299.776642 -274.049744) (xy 299.776138 -274.075452) (xy 301.023016 -274.075452) (xy 301.023016 -274.024036)
			(xy 301.031059 -273.973254) (xy 301.046947 -273.924355) (xy 301.07029 -273.878543) (xy 301.100511 -273.836947)
			(xy 301.136867 -273.800591) (xy 301.178463 -273.77037) (xy 301.224275 -273.747027) (xy 301.273174 -273.731139)
			(xy 301.323956 -273.723096) (xy 301.375372 -273.723096) (xy 301.426154 -273.731139) (xy 301.475053 -273.747027)
			(xy 301.520865 -273.77037) (xy 301.562461 -273.800591) (xy 301.598817 -273.836947) (xy 301.629038 -273.878543)
			(xy 301.652381 -273.924355) (xy 301.668269 -273.973254) (xy 301.676312 -274.024036) (xy 301.676816 -274.049744)
			(xy 301.676312 -274.075452) (xy 302.922936 -274.075452) (xy 302.922936 -274.024036) (xy 302.930979 -273.973254)
			(xy 302.946867 -273.924355) (xy 302.97021 -273.878543) (xy 303.000431 -273.836947) (xy 303.036787 -273.800591)
			(xy 303.078383 -273.77037) (xy 303.124195 -273.747027) (xy 303.173094 -273.731139) (xy 303.223876 -273.723096)
			(xy 303.275292 -273.723096) (xy 303.326074 -273.731139) (xy 303.374973 -273.747027) (xy 303.420785 -273.77037)
			(xy 303.462381 -273.800591) (xy 303.498737 -273.836947) (xy 303.528958 -273.878543) (xy 303.552301 -273.924355)
			(xy 303.568189 -273.973254) (xy 303.576232 -274.024036) (xy 303.576736 -274.049744) (xy 303.576232 -274.075452)
			(xy 304.822856 -274.075452) (xy 304.822856 -274.024036) (xy 304.830899 -273.973254) (xy 304.846787 -273.924355)
			(xy 304.87013 -273.878543) (xy 304.900351 -273.836947) (xy 304.936707 -273.800591) (xy 304.978303 -273.77037)
			(xy 305.024115 -273.747027) (xy 305.073014 -273.731139) (xy 305.123796 -273.723096) (xy 305.175212 -273.723096)
			(xy 305.225994 -273.731139) (xy 305.274893 -273.747027) (xy 305.320705 -273.77037) (xy 305.362301 -273.800591)
			(xy 305.398657 -273.836947) (xy 305.428878 -273.878543) (xy 305.452221 -273.924355) (xy 305.468109 -273.973254)
			(xy 305.476152 -274.024036) (xy 305.476656 -274.049744) (xy 305.476152 -274.075452) (xy 306.72303 -274.075452)
			(xy 306.72303 -274.024036) (xy 306.731073 -273.973254) (xy 306.746961 -273.924355) (xy 306.770304 -273.878543)
			(xy 306.800525 -273.836947) (xy 306.836881 -273.800591) (xy 306.878477 -273.77037) (xy 306.924289 -273.747027)
			(xy 306.973188 -273.731139) (xy 307.02397 -273.723096) (xy 307.075386 -273.723096) (xy 307.126168 -273.731139)
			(xy 307.175067 -273.747027) (xy 307.220879 -273.77037) (xy 307.262475 -273.800591) (xy 307.298831 -273.836947)
			(xy 307.329052 -273.878543) (xy 307.352395 -273.924355) (xy 307.368283 -273.973254) (xy 307.376326 -274.024036)
			(xy 307.37683 -274.049744) (xy 307.376326 -274.075452) (xy 308.62295 -274.075452) (xy 308.62295 -274.024036)
			(xy 308.630993 -273.973254) (xy 308.646881 -273.924355) (xy 308.670224 -273.878543) (xy 308.700445 -273.836947)
			(xy 308.736801 -273.800591) (xy 308.778397 -273.77037) (xy 308.824209 -273.747027) (xy 308.873108 -273.731139)
			(xy 308.92389 -273.723096) (xy 308.975306 -273.723096) (xy 309.026088 -273.731139) (xy 309.074987 -273.747027)
			(xy 309.120799 -273.77037) (xy 309.162395 -273.800591) (xy 309.198751 -273.836947) (xy 309.228972 -273.878543)
			(xy 309.252315 -273.924355) (xy 309.268203 -273.973254) (xy 309.276246 -274.024036) (xy 309.27675 -274.049744)
			(xy 309.276246 -274.075452) (xy 310.52287 -274.075452) (xy 310.52287 -274.024036) (xy 310.530913 -273.973254)
			(xy 310.546801 -273.924355) (xy 310.570144 -273.878543) (xy 310.600365 -273.836947) (xy 310.636721 -273.800591)
			(xy 310.678317 -273.77037) (xy 310.724129 -273.747027) (xy 310.773028 -273.731139) (xy 310.82381 -273.723096)
			(xy 310.875226 -273.723096) (xy 310.926008 -273.731139) (xy 310.974907 -273.747027) (xy 311.020719 -273.77037)
			(xy 311.062315 -273.800591) (xy 311.098671 -273.836947) (xy 311.128892 -273.878543) (xy 311.152235 -273.924355)
			(xy 311.168123 -273.973254) (xy 311.176166 -274.024036) (xy 311.17667 -274.049744) (xy 311.176166 -274.075452)
			(xy 312.42279 -274.075452) (xy 312.42279 -274.024036) (xy 312.430833 -273.973254) (xy 312.446721 -273.924355)
			(xy 312.470064 -273.878543) (xy 312.500285 -273.836947) (xy 312.536641 -273.800591) (xy 312.578237 -273.77037)
			(xy 312.624049 -273.747027) (xy 312.672948 -273.731139) (xy 312.72373 -273.723096) (xy 312.775146 -273.723096)
			(xy 312.825928 -273.731139) (xy 312.874827 -273.747027) (xy 312.920639 -273.77037) (xy 312.962235 -273.800591)
			(xy 312.998591 -273.836947) (xy 313.028812 -273.878543) (xy 313.052155 -273.924355) (xy 313.068043 -273.973254)
			(xy 313.076086 -274.024036) (xy 313.07659 -274.049744) (xy 313.076086 -274.075452) (xy 313.068043 -274.126234)
			(xy 313.052155 -274.175133) (xy 313.028812 -274.220945) (xy 312.998591 -274.262541) (xy 312.962235 -274.298897)
			(xy 312.920639 -274.329118) (xy 312.874827 -274.352461) (xy 312.825928 -274.368349) (xy 312.775146 -274.376392)
			(xy 312.72373 -274.376392) (xy 312.672948 -274.368349) (xy 312.624049 -274.352461) (xy 312.578237 -274.329118)
			(xy 312.536641 -274.298897) (xy 312.500285 -274.262541) (xy 312.470064 -274.220945) (xy 312.446721 -274.175133)
			(xy 312.430833 -274.126234) (xy 312.42279 -274.075452) (xy 311.176166 -274.075452) (xy 311.168123 -274.126234)
			(xy 311.152235 -274.175133) (xy 311.128892 -274.220945) (xy 311.098671 -274.262541) (xy 311.062315 -274.298897)
			(xy 311.020719 -274.329118) (xy 310.974907 -274.352461) (xy 310.926008 -274.368349) (xy 310.875226 -274.376392)
			(xy 310.82381 -274.376392) (xy 310.773028 -274.368349) (xy 310.724129 -274.352461) (xy 310.678317 -274.329118)
			(xy 310.636721 -274.298897) (xy 310.600365 -274.262541) (xy 310.570144 -274.220945) (xy 310.546801 -274.175133)
			(xy 310.530913 -274.126234) (xy 310.52287 -274.075452) (xy 309.276246 -274.075452) (xy 309.268203 -274.126234)
			(xy 309.252315 -274.175133) (xy 309.228972 -274.220945) (xy 309.198751 -274.262541) (xy 309.162395 -274.298897)
			(xy 309.120799 -274.329118) (xy 309.074987 -274.352461) (xy 309.026088 -274.368349) (xy 308.975306 -274.376392)
			(xy 308.92389 -274.376392) (xy 308.873108 -274.368349) (xy 308.824209 -274.352461) (xy 308.778397 -274.329118)
			(xy 308.736801 -274.298897) (xy 308.700445 -274.262541) (xy 308.670224 -274.220945) (xy 308.646881 -274.175133)
			(xy 308.630993 -274.126234) (xy 308.62295 -274.075452) (xy 307.376326 -274.075452) (xy 307.368283 -274.126234)
			(xy 307.352395 -274.175133) (xy 307.329052 -274.220945) (xy 307.298831 -274.262541) (xy 307.262475 -274.298897)
			(xy 307.220879 -274.329118) (xy 307.175067 -274.352461) (xy 307.126168 -274.368349) (xy 307.075386 -274.376392)
			(xy 307.02397 -274.376392) (xy 306.973188 -274.368349) (xy 306.924289 -274.352461) (xy 306.878477 -274.329118)
			(xy 306.836881 -274.298897) (xy 306.800525 -274.262541) (xy 306.770304 -274.220945) (xy 306.746961 -274.175133)
			(xy 306.731073 -274.126234) (xy 306.72303 -274.075452) (xy 305.476152 -274.075452) (xy 305.468109 -274.126234)
			(xy 305.452221 -274.175133) (xy 305.428878 -274.220945) (xy 305.398657 -274.262541) (xy 305.362301 -274.298897)
			(xy 305.320705 -274.329118) (xy 305.274893 -274.352461) (xy 305.225994 -274.368349) (xy 305.175212 -274.376392)
			(xy 305.123796 -274.376392) (xy 305.073014 -274.368349) (xy 305.024115 -274.352461) (xy 304.978303 -274.329118)
			(xy 304.936707 -274.298897) (xy 304.900351 -274.262541) (xy 304.87013 -274.220945) (xy 304.846787 -274.175133)
			(xy 304.830899 -274.126234) (xy 304.822856 -274.075452) (xy 303.576232 -274.075452) (xy 303.568189 -274.126234)
			(xy 303.552301 -274.175133) (xy 303.528958 -274.220945) (xy 303.498737 -274.262541) (xy 303.462381 -274.298897)
			(xy 303.420785 -274.329118) (xy 303.374973 -274.352461) (xy 303.326074 -274.368349) (xy 303.275292 -274.376392)
			(xy 303.223876 -274.376392) (xy 303.173094 -274.368349) (xy 303.124195 -274.352461) (xy 303.078383 -274.329118)
			(xy 303.036787 -274.298897) (xy 303.000431 -274.262541) (xy 302.97021 -274.220945) (xy 302.946867 -274.175133)
			(xy 302.930979 -274.126234) (xy 302.922936 -274.075452) (xy 301.676312 -274.075452) (xy 301.668269 -274.126234)
			(xy 301.652381 -274.175133) (xy 301.629038 -274.220945) (xy 301.598817 -274.262541) (xy 301.562461 -274.298897)
			(xy 301.520865 -274.329118) (xy 301.475053 -274.352461) (xy 301.426154 -274.368349) (xy 301.375372 -274.376392)
			(xy 301.323956 -274.376392) (xy 301.273174 -274.368349) (xy 301.224275 -274.352461) (xy 301.178463 -274.329118)
			(xy 301.136867 -274.298897) (xy 301.100511 -274.262541) (xy 301.07029 -274.220945) (xy 301.046947 -274.175133)
			(xy 301.031059 -274.126234) (xy 301.023016 -274.075452) (xy 299.776138 -274.075452) (xy 299.768095 -274.126234)
			(xy 299.752207 -274.175133) (xy 299.728864 -274.220945) (xy 299.698643 -274.262541) (xy 299.662287 -274.298897)
			(xy 299.620691 -274.329118) (xy 299.574879 -274.352461) (xy 299.52598 -274.368349) (xy 299.475198 -274.376392)
			(xy 299.423782 -274.376392) (xy 299.373 -274.368349) (xy 299.324101 -274.352461) (xy 299.278289 -274.329118)
			(xy 299.236693 -274.298897) (xy 299.200337 -274.262541) (xy 299.170116 -274.220945) (xy 299.146773 -274.175133)
			(xy 299.130885 -274.126234) (xy 299.122842 -274.075452) (xy 297.876218 -274.075452) (xy 297.868175 -274.126234)
			(xy 297.852287 -274.175133) (xy 297.828944 -274.220945) (xy 297.798723 -274.262541) (xy 297.762367 -274.298897)
			(xy 297.720771 -274.329118) (xy 297.674959 -274.352461) (xy 297.62606 -274.368349) (xy 297.575278 -274.376392)
			(xy 297.523862 -274.376392) (xy 297.47308 -274.368349) (xy 297.424181 -274.352461) (xy 297.378369 -274.329118)
			(xy 297.336773 -274.298897) (xy 297.300417 -274.262541) (xy 297.270196 -274.220945) (xy 297.246853 -274.175133)
			(xy 297.230965 -274.126234) (xy 297.222922 -274.075452) (xy 295.976298 -274.075452) (xy 295.968255 -274.126234)
			(xy 295.952367 -274.175133) (xy 295.929024 -274.220945) (xy 295.898803 -274.262541) (xy 295.862447 -274.298897)
			(xy 295.820851 -274.329118) (xy 295.775039 -274.352461) (xy 295.72614 -274.368349) (xy 295.675358 -274.376392)
			(xy 295.623942 -274.376392) (xy 295.57316 -274.368349) (xy 295.524261 -274.352461) (xy 295.478449 -274.329118)
			(xy 295.436853 -274.298897) (xy 295.400497 -274.262541) (xy 295.370276 -274.220945) (xy 295.346933 -274.175133)
			(xy 295.331045 -274.126234) (xy 295.323002 -274.075452) (xy 294.076124 -274.075452) (xy 294.068081 -274.126234)
			(xy 294.052193 -274.175133) (xy 294.02885 -274.220945) (xy 293.998629 -274.262541) (xy 293.962273 -274.298897)
			(xy 293.920677 -274.329118) (xy 293.874865 -274.352461) (xy 293.825966 -274.368349) (xy 293.775184 -274.376392)
			(xy 293.723768 -274.376392) (xy 293.672986 -274.368349) (xy 293.624087 -274.352461) (xy 293.578275 -274.329118)
			(xy 293.536679 -274.298897) (xy 293.500323 -274.262541) (xy 293.470102 -274.220945) (xy 293.446759 -274.175133)
			(xy 293.430871 -274.126234) (xy 293.422828 -274.075452) (xy 292.175989 -274.075452) (xy 292.167991 -274.125946)
			(xy 292.152111 -274.174816) (xy 292.12878 -274.2206) (xy 292.098574 -274.26217) (xy 292.062237 -274.298503)
			(xy 292.020663 -274.328703) (xy 291.974875 -274.352028) (xy 291.926003 -274.367902) (xy 291.875249 -274.375934)
			(xy 291.849556 -274.376388) (xy 291.849048 -274.376388) (xy 291.822942 -274.375852) (xy 291.771399 -274.367509)
			(xy 291.721834 -274.351091) (xy 291.675503 -274.327014) (xy 291.65423 -274.311872) (xy 291.646471 -274.306583)
			(xy 291.628414 -274.301489) (xy 291.609736 -274.303253) (xy 291.601144 -274.307046) (xy 291.519864 -274.34794)
			(xy 291.511686 -274.352507) (xy 291.499091 -274.366347) (xy 291.49233 -274.383796) (xy 291.491924 -274.393152)
			(xy 291.491924 -275.025412) (xy 292.472868 -275.025412) (xy 292.472868 -274.973996) (xy 292.480911 -274.923214)
			(xy 292.496799 -274.874315) (xy 292.520142 -274.828503) (xy 292.550363 -274.786907) (xy 292.586719 -274.750551)
			(xy 292.628315 -274.72033) (xy 292.674127 -274.696987) (xy 292.723026 -274.681099) (xy 292.773808 -274.673056)
			(xy 292.825224 -274.673056) (xy 292.876006 -274.681099) (xy 292.924905 -274.696987) (xy 292.970717 -274.72033)
			(xy 293.012313 -274.750551) (xy 293.048669 -274.786907) (xy 293.07889 -274.828503) (xy 293.102233 -274.874315)
			(xy 293.118121 -274.923214) (xy 293.126164 -274.973996) (xy 293.126668 -274.999704) (xy 293.126164 -275.025412)
			(xy 293.126124 -275.025666) (xy 294.372788 -275.025666) (xy 294.372788 -274.97425) (xy 294.380831 -274.923468)
			(xy 294.396719 -274.874569) (xy 294.420062 -274.828757) (xy 294.450283 -274.787161) (xy 294.486639 -274.750805)
			(xy 294.528235 -274.720584) (xy 294.574047 -274.697241) (xy 294.622946 -274.681353) (xy 294.673728 -274.67331)
			(xy 294.725144 -274.67331) (xy 294.775926 -274.681353) (xy 294.824825 -274.697241) (xy 294.870637 -274.720584)
			(xy 294.912233 -274.750805) (xy 294.948589 -274.787161) (xy 294.97881 -274.828757) (xy 295.002153 -274.874569)
			(xy 295.018041 -274.923468) (xy 295.026084 -274.97425) (xy 295.026588 -274.999958) (xy 295.026089 -275.025412)
			(xy 296.272962 -275.025412) (xy 296.272962 -274.973996) (xy 296.281005 -274.923214) (xy 296.296893 -274.874315)
			(xy 296.320236 -274.828503) (xy 296.350457 -274.786907) (xy 296.386813 -274.750551) (xy 296.428409 -274.72033)
			(xy 296.474221 -274.696987) (xy 296.52312 -274.681099) (xy 296.573902 -274.673056) (xy 296.625318 -274.673056)
			(xy 296.6761 -274.681099) (xy 296.724999 -274.696987) (xy 296.770811 -274.72033) (xy 296.812407 -274.750551)
			(xy 296.848763 -274.786907) (xy 296.878984 -274.828503) (xy 296.902327 -274.874315) (xy 296.918215 -274.923214)
			(xy 296.926258 -274.973996) (xy 296.926762 -274.999704) (xy 296.926258 -275.025412) (xy 296.926218 -275.025666)
			(xy 298.172882 -275.025666) (xy 298.172882 -274.97425) (xy 298.180925 -274.923468) (xy 298.196813 -274.874569)
			(xy 298.220156 -274.828757) (xy 298.250377 -274.787161) (xy 298.286733 -274.750805) (xy 298.328329 -274.720584)
			(xy 298.374141 -274.697241) (xy 298.42304 -274.681353) (xy 298.473822 -274.67331) (xy 298.525238 -274.67331)
			(xy 298.57602 -274.681353) (xy 298.624919 -274.697241) (xy 298.670731 -274.720584) (xy 298.712327 -274.750805)
			(xy 298.748683 -274.787161) (xy 298.778904 -274.828757) (xy 298.802247 -274.874569) (xy 298.818135 -274.923468)
			(xy 298.826178 -274.97425) (xy 298.826682 -274.999958) (xy 298.826183 -275.025412) (xy 300.072802 -275.025412)
			(xy 300.072802 -274.973996) (xy 300.080845 -274.923214) (xy 300.096733 -274.874315) (xy 300.120076 -274.828503)
			(xy 300.150297 -274.786907) (xy 300.186653 -274.750551) (xy 300.228249 -274.72033) (xy 300.274061 -274.696987)
			(xy 300.32296 -274.681099) (xy 300.373742 -274.673056) (xy 300.425158 -274.673056) (xy 300.47594 -274.681099)
			(xy 300.524839 -274.696987) (xy 300.570651 -274.72033) (xy 300.612247 -274.750551) (xy 300.648603 -274.786907)
			(xy 300.678824 -274.828503) (xy 300.702167 -274.874315) (xy 300.718055 -274.923214) (xy 300.726098 -274.973996)
			(xy 300.726602 -274.999704) (xy 300.726098 -275.025412) (xy 300.726058 -275.025666) (xy 301.972722 -275.025666)
			(xy 301.972722 -274.97425) (xy 301.980765 -274.923468) (xy 301.996653 -274.874569) (xy 302.019996 -274.828757)
			(xy 302.050217 -274.787161) (xy 302.086573 -274.750805) (xy 302.128169 -274.720584) (xy 302.173981 -274.697241)
			(xy 302.22288 -274.681353) (xy 302.273662 -274.67331) (xy 302.325078 -274.67331) (xy 302.37586 -274.681353)
			(xy 302.424759 -274.697241) (xy 302.470571 -274.720584) (xy 302.512167 -274.750805) (xy 302.548523 -274.787161)
			(xy 302.578744 -274.828757) (xy 302.602087 -274.874569) (xy 302.617975 -274.923468) (xy 302.626018 -274.97425)
			(xy 302.626522 -274.999958) (xy 302.626023 -275.025412) (xy 303.872896 -275.025412) (xy 303.872896 -274.973996)
			(xy 303.880939 -274.923214) (xy 303.896827 -274.874315) (xy 303.92017 -274.828503) (xy 303.950391 -274.786907)
			(xy 303.986747 -274.750551) (xy 304.028343 -274.72033) (xy 304.074155 -274.696987) (xy 304.123054 -274.681099)
			(xy 304.173836 -274.673056) (xy 304.225252 -274.673056) (xy 304.276034 -274.681099) (xy 304.324933 -274.696987)
			(xy 304.370745 -274.72033) (xy 304.412341 -274.750551) (xy 304.448697 -274.786907) (xy 304.478918 -274.828503)
			(xy 304.502261 -274.874315) (xy 304.518149 -274.923214) (xy 304.526192 -274.973996) (xy 304.526696 -274.999704)
			(xy 304.526192 -275.025412) (xy 304.526152 -275.025666) (xy 305.772816 -275.025666) (xy 305.772816 -274.97425)
			(xy 305.780859 -274.923468) (xy 305.796747 -274.874569) (xy 305.82009 -274.828757) (xy 305.850311 -274.787161)
			(xy 305.886667 -274.750805) (xy 305.928263 -274.720584) (xy 305.974075 -274.697241) (xy 306.022974 -274.681353)
			(xy 306.073756 -274.67331) (xy 306.125172 -274.67331) (xy 306.175954 -274.681353) (xy 306.224853 -274.697241)
			(xy 306.270665 -274.720584) (xy 306.312261 -274.750805) (xy 306.348617 -274.787161) (xy 306.378838 -274.828757)
			(xy 306.402181 -274.874569) (xy 306.418069 -274.923468) (xy 306.426112 -274.97425) (xy 306.426616 -274.999958)
			(xy 306.426117 -275.025412) (xy 307.67299 -275.025412) (xy 307.67299 -274.973996) (xy 307.681033 -274.923214)
			(xy 307.696921 -274.874315) (xy 307.720264 -274.828503) (xy 307.750485 -274.786907) (xy 307.786841 -274.750551)
			(xy 307.828437 -274.72033) (xy 307.874249 -274.696987) (xy 307.923148 -274.681099) (xy 307.97393 -274.673056)
			(xy 308.025346 -274.673056) (xy 308.076128 -274.681099) (xy 308.125027 -274.696987) (xy 308.170839 -274.72033)
			(xy 308.212435 -274.750551) (xy 308.248791 -274.786907) (xy 308.279012 -274.828503) (xy 308.302355 -274.874315)
			(xy 308.318243 -274.923214) (xy 308.326286 -274.973996) (xy 308.32679 -274.999704) (xy 308.326286 -275.025412)
			(xy 308.326246 -275.025666) (xy 309.57291 -275.025666) (xy 309.57291 -274.97425) (xy 309.580953 -274.923468)
			(xy 309.596841 -274.874569) (xy 309.620184 -274.828757) (xy 309.650405 -274.787161) (xy 309.686761 -274.750805)
			(xy 309.728357 -274.720584) (xy 309.774169 -274.697241) (xy 309.823068 -274.681353) (xy 309.87385 -274.67331)
			(xy 309.925266 -274.67331) (xy 309.976048 -274.681353) (xy 310.024947 -274.697241) (xy 310.070759 -274.720584)
			(xy 310.112355 -274.750805) (xy 310.148711 -274.787161) (xy 310.178932 -274.828757) (xy 310.202275 -274.874569)
			(xy 310.218163 -274.923468) (xy 310.226206 -274.97425) (xy 310.22671 -274.999958) (xy 310.226206 -275.025666)
			(xy 311.47283 -275.025666) (xy 311.47283 -274.97425) (xy 311.480873 -274.923468) (xy 311.496761 -274.874569)
			(xy 311.520104 -274.828757) (xy 311.550325 -274.787161) (xy 311.586681 -274.750805) (xy 311.628277 -274.720584)
			(xy 311.674089 -274.697241) (xy 311.722988 -274.681353) (xy 311.77377 -274.67331) (xy 311.825186 -274.67331)
			(xy 311.875968 -274.681353) (xy 311.924867 -274.697241) (xy 311.970679 -274.720584) (xy 312.012275 -274.750805)
			(xy 312.048631 -274.787161) (xy 312.078852 -274.828757) (xy 312.102195 -274.874569) (xy 312.118083 -274.923468)
			(xy 312.126126 -274.97425) (xy 312.12663 -274.999958) (xy 312.126131 -275.025412) (xy 313.373258 -275.025412)
			(xy 313.373258 -274.973996) (xy 313.381301 -274.923214) (xy 313.397189 -274.874315) (xy 313.420532 -274.828503)
			(xy 313.450753 -274.786907) (xy 313.487109 -274.750551) (xy 313.528705 -274.72033) (xy 313.574517 -274.696987)
			(xy 313.623416 -274.681099) (xy 313.674198 -274.673056) (xy 313.725614 -274.673056) (xy 313.776396 -274.681099)
			(xy 313.825295 -274.696987) (xy 313.871107 -274.72033) (xy 313.912703 -274.750551) (xy 313.949059 -274.786907)
			(xy 313.97928 -274.828503) (xy 314.002623 -274.874315) (xy 314.018511 -274.923214) (xy 314.026554 -274.973996)
			(xy 314.027058 -274.999704) (xy 314.026554 -275.025412) (xy 314.323218 -275.025412) (xy 314.323218 -274.973996)
			(xy 314.331261 -274.923214) (xy 314.347149 -274.874315) (xy 314.370492 -274.828503) (xy 314.400713 -274.786907)
			(xy 314.437069 -274.750551) (xy 314.478665 -274.72033) (xy 314.524477 -274.696987) (xy 314.573376 -274.681099)
			(xy 314.624158 -274.673056) (xy 314.675574 -274.673056) (xy 314.726356 -274.681099) (xy 314.775255 -274.696987)
			(xy 314.821067 -274.72033) (xy 314.862663 -274.750551) (xy 314.899019 -274.786907) (xy 314.92924 -274.828503)
			(xy 314.952583 -274.874315) (xy 314.968471 -274.923214) (xy 314.976514 -274.973996) (xy 314.977018 -274.999704)
			(xy 314.976514 -275.025412) (xy 314.968471 -275.076194) (xy 314.952583 -275.125093) (xy 314.92924 -275.170905)
			(xy 314.899019 -275.212501) (xy 314.862663 -275.248857) (xy 314.821067 -275.279078) (xy 314.775255 -275.302421)
			(xy 314.726356 -275.318309) (xy 314.675574 -275.326352) (xy 314.624158 -275.326352) (xy 314.573376 -275.318309)
			(xy 314.524477 -275.302421) (xy 314.478665 -275.279078) (xy 314.437069 -275.248857) (xy 314.400713 -275.212501)
			(xy 314.370492 -275.170905) (xy 314.347149 -275.125093) (xy 314.331261 -275.076194) (xy 314.323218 -275.025412)
			(xy 314.026554 -275.025412) (xy 314.018511 -275.076194) (xy 314.002623 -275.125093) (xy 313.97928 -275.170905)
			(xy 313.949059 -275.212501) (xy 313.912703 -275.248857) (xy 313.871107 -275.279078) (xy 313.825295 -275.302421)
			(xy 313.776396 -275.318309) (xy 313.725614 -275.326352) (xy 313.674198 -275.326352) (xy 313.623416 -275.318309)
			(xy 313.574517 -275.302421) (xy 313.528705 -275.279078) (xy 313.487109 -275.248857) (xy 313.450753 -275.212501)
			(xy 313.420532 -275.170905) (xy 313.397189 -275.125093) (xy 313.381301 -275.076194) (xy 313.373258 -275.025412)
			(xy 312.126131 -275.025412) (xy 312.126126 -275.025666) (xy 312.118083 -275.076448) (xy 312.102195 -275.125347)
			(xy 312.078852 -275.171159) (xy 312.048631 -275.212755) (xy 312.012275 -275.249111) (xy 311.970679 -275.279332)
			(xy 311.924867 -275.302675) (xy 311.875968 -275.318563) (xy 311.825186 -275.326606) (xy 311.77377 -275.326606)
			(xy 311.722988 -275.318563) (xy 311.674089 -275.302675) (xy 311.628277 -275.279332) (xy 311.586681 -275.249111)
			(xy 311.550325 -275.212755) (xy 311.520104 -275.171159) (xy 311.496761 -275.125347) (xy 311.480873 -275.076448)
			(xy 311.47283 -275.025666) (xy 310.226206 -275.025666) (xy 310.218163 -275.076448) (xy 310.202275 -275.125347)
			(xy 310.178932 -275.171159) (xy 310.148711 -275.212755) (xy 310.112355 -275.249111) (xy 310.070759 -275.279332)
			(xy 310.024947 -275.302675) (xy 309.976048 -275.318563) (xy 309.925266 -275.326606) (xy 309.87385 -275.326606)
			(xy 309.823068 -275.318563) (xy 309.774169 -275.302675) (xy 309.728357 -275.279332) (xy 309.686761 -275.249111)
			(xy 309.650405 -275.212755) (xy 309.620184 -275.171159) (xy 309.596841 -275.125347) (xy 309.580953 -275.076448)
			(xy 309.57291 -275.025666) (xy 308.326246 -275.025666) (xy 308.318243 -275.076194) (xy 308.302355 -275.125093)
			(xy 308.279012 -275.170905) (xy 308.248791 -275.212501) (xy 308.212435 -275.248857) (xy 308.170839 -275.279078)
			(xy 308.125027 -275.302421) (xy 308.076128 -275.318309) (xy 308.025346 -275.326352) (xy 307.97393 -275.326352)
			(xy 307.923148 -275.318309) (xy 307.874249 -275.302421) (xy 307.828437 -275.279078) (xy 307.786841 -275.248857)
			(xy 307.750485 -275.212501) (xy 307.720264 -275.170905) (xy 307.696921 -275.125093) (xy 307.681033 -275.076194)
			(xy 307.67299 -275.025412) (xy 306.426117 -275.025412) (xy 306.426112 -275.025666) (xy 306.418069 -275.076448)
			(xy 306.402181 -275.125347) (xy 306.378838 -275.171159) (xy 306.348617 -275.212755) (xy 306.312261 -275.249111)
			(xy 306.270665 -275.279332) (xy 306.224853 -275.302675) (xy 306.175954 -275.318563) (xy 306.125172 -275.326606)
			(xy 306.073756 -275.326606) (xy 306.022974 -275.318563) (xy 305.974075 -275.302675) (xy 305.928263 -275.279332)
			(xy 305.886667 -275.249111) (xy 305.850311 -275.212755) (xy 305.82009 -275.171159) (xy 305.796747 -275.125347)
			(xy 305.780859 -275.076448) (xy 305.772816 -275.025666) (xy 304.526152 -275.025666) (xy 304.518149 -275.076194)
			(xy 304.502261 -275.125093) (xy 304.478918 -275.170905) (xy 304.448697 -275.212501) (xy 304.412341 -275.248857)
			(xy 304.370745 -275.279078) (xy 304.324933 -275.302421) (xy 304.276034 -275.318309) (xy 304.225252 -275.326352)
			(xy 304.173836 -275.326352) (xy 304.123054 -275.318309) (xy 304.074155 -275.302421) (xy 304.028343 -275.279078)
			(xy 303.986747 -275.248857) (xy 303.950391 -275.212501) (xy 303.92017 -275.170905) (xy 303.896827 -275.125093)
			(xy 303.880939 -275.076194) (xy 303.872896 -275.025412) (xy 302.626023 -275.025412) (xy 302.626018 -275.025666)
			(xy 302.617975 -275.076448) (xy 302.602087 -275.125347) (xy 302.578744 -275.171159) (xy 302.548523 -275.212755)
			(xy 302.512167 -275.249111) (xy 302.470571 -275.279332) (xy 302.424759 -275.302675) (xy 302.37586 -275.318563)
			(xy 302.325078 -275.326606) (xy 302.273662 -275.326606) (xy 302.22288 -275.318563) (xy 302.173981 -275.302675)
			(xy 302.128169 -275.279332) (xy 302.086573 -275.249111) (xy 302.050217 -275.212755) (xy 302.019996 -275.171159)
			(xy 301.996653 -275.125347) (xy 301.980765 -275.076448) (xy 301.972722 -275.025666) (xy 300.726058 -275.025666)
			(xy 300.718055 -275.076194) (xy 300.702167 -275.125093) (xy 300.678824 -275.170905) (xy 300.648603 -275.212501)
			(xy 300.612247 -275.248857) (xy 300.570651 -275.279078) (xy 300.524839 -275.302421) (xy 300.47594 -275.318309)
			(xy 300.425158 -275.326352) (xy 300.373742 -275.326352) (xy 300.32296 -275.318309) (xy 300.274061 -275.302421)
			(xy 300.228249 -275.279078) (xy 300.186653 -275.248857) (xy 300.150297 -275.212501) (xy 300.120076 -275.170905)
			(xy 300.096733 -275.125093) (xy 300.080845 -275.076194) (xy 300.072802 -275.025412) (xy 298.826183 -275.025412)
			(xy 298.826178 -275.025666) (xy 298.818135 -275.076448) (xy 298.802247 -275.125347) (xy 298.778904 -275.171159)
			(xy 298.748683 -275.212755) (xy 298.712327 -275.249111) (xy 298.670731 -275.279332) (xy 298.624919 -275.302675)
			(xy 298.57602 -275.318563) (xy 298.525238 -275.326606) (xy 298.473822 -275.326606) (xy 298.42304 -275.318563)
			(xy 298.374141 -275.302675) (xy 298.328329 -275.279332) (xy 298.286733 -275.249111) (xy 298.250377 -275.212755)
			(xy 298.220156 -275.171159) (xy 298.196813 -275.125347) (xy 298.180925 -275.076448) (xy 298.172882 -275.025666)
			(xy 296.926218 -275.025666) (xy 296.918215 -275.076194) (xy 296.902327 -275.125093) (xy 296.878984 -275.170905)
			(xy 296.848763 -275.212501) (xy 296.812407 -275.248857) (xy 296.770811 -275.279078) (xy 296.724999 -275.302421)
			(xy 296.6761 -275.318309) (xy 296.625318 -275.326352) (xy 296.573902 -275.326352) (xy 296.52312 -275.318309)
			(xy 296.474221 -275.302421) (xy 296.428409 -275.279078) (xy 296.386813 -275.248857) (xy 296.350457 -275.212501)
			(xy 296.320236 -275.170905) (xy 296.296893 -275.125093) (xy 296.281005 -275.076194) (xy 296.272962 -275.025412)
			(xy 295.026089 -275.025412) (xy 295.026084 -275.025666) (xy 295.018041 -275.076448) (xy 295.002153 -275.125347)
			(xy 294.97881 -275.171159) (xy 294.948589 -275.212755) (xy 294.912233 -275.249111) (xy 294.870637 -275.279332)
			(xy 294.824825 -275.302675) (xy 294.775926 -275.318563) (xy 294.725144 -275.326606) (xy 294.673728 -275.326606)
			(xy 294.622946 -275.318563) (xy 294.574047 -275.302675) (xy 294.528235 -275.279332) (xy 294.486639 -275.249111)
			(xy 294.450283 -275.212755) (xy 294.420062 -275.171159) (xy 294.396719 -275.125347) (xy 294.380831 -275.076448)
			(xy 294.372788 -275.025666) (xy 293.126124 -275.025666) (xy 293.118121 -275.076194) (xy 293.102233 -275.125093)
			(xy 293.07889 -275.170905) (xy 293.048669 -275.212501) (xy 293.012313 -275.248857) (xy 292.970717 -275.279078)
			(xy 292.924905 -275.302421) (xy 292.876006 -275.318309) (xy 292.825224 -275.326352) (xy 292.773808 -275.326352)
			(xy 292.723026 -275.318309) (xy 292.674127 -275.302421) (xy 292.628315 -275.279078) (xy 292.586719 -275.248857)
			(xy 292.550363 -275.212501) (xy 292.520142 -275.170905) (xy 292.496799 -275.125093) (xy 292.480911 -275.076194)
			(xy 292.472868 -275.025412) (xy 291.491924 -275.025412) (xy 291.491924 -275.975372) (xy 292.472868 -275.975372)
			(xy 292.472868 -275.923956) (xy 292.480911 -275.873174) (xy 292.496799 -275.824275) (xy 292.520142 -275.778463)
			(xy 292.550363 -275.736867) (xy 292.586719 -275.700511) (xy 292.628315 -275.67029) (xy 292.674127 -275.646947)
			(xy 292.723026 -275.631059) (xy 292.773808 -275.623016) (xy 292.825224 -275.623016) (xy 292.876006 -275.631059)
			(xy 292.924905 -275.646947) (xy 292.970717 -275.67029) (xy 293.012313 -275.700511) (xy 293.048669 -275.736867)
			(xy 293.07889 -275.778463) (xy 293.102233 -275.824275) (xy 293.118121 -275.873174) (xy 293.126164 -275.923956)
			(xy 293.126668 -275.949664) (xy 293.126164 -275.975372) (xy 293.126124 -275.975626) (xy 294.372788 -275.975626)
			(xy 294.372788 -275.92421) (xy 294.380831 -275.873428) (xy 294.396719 -275.824529) (xy 294.420062 -275.778717)
			(xy 294.450283 -275.737121) (xy 294.486639 -275.700765) (xy 294.528235 -275.670544) (xy 294.574047 -275.647201)
			(xy 294.622946 -275.631313) (xy 294.673728 -275.62327) (xy 294.725144 -275.62327) (xy 294.775926 -275.631313)
			(xy 294.824825 -275.647201) (xy 294.870637 -275.670544) (xy 294.912233 -275.700765) (xy 294.948589 -275.737121)
			(xy 294.97881 -275.778717) (xy 295.002153 -275.824529) (xy 295.018041 -275.873428) (xy 295.026084 -275.92421)
			(xy 295.026588 -275.949918) (xy 295.026089 -275.975372) (xy 296.272962 -275.975372) (xy 296.272962 -275.923956)
			(xy 296.281005 -275.873174) (xy 296.296893 -275.824275) (xy 296.320236 -275.778463) (xy 296.350457 -275.736867)
			(xy 296.386813 -275.700511) (xy 296.428409 -275.67029) (xy 296.474221 -275.646947) (xy 296.52312 -275.631059)
			(xy 296.573902 -275.623016) (xy 296.625318 -275.623016) (xy 296.6761 -275.631059) (xy 296.724999 -275.646947)
			(xy 296.770811 -275.67029) (xy 296.812407 -275.700511) (xy 296.848763 -275.736867) (xy 296.878984 -275.778463)
			(xy 296.902327 -275.824275) (xy 296.918215 -275.873174) (xy 296.926258 -275.923956) (xy 296.926762 -275.949664)
			(xy 296.926258 -275.975372) (xy 296.926218 -275.975626) (xy 298.172882 -275.975626) (xy 298.172882 -275.92421)
			(xy 298.180925 -275.873428) (xy 298.196813 -275.824529) (xy 298.220156 -275.778717) (xy 298.250377 -275.737121)
			(xy 298.286733 -275.700765) (xy 298.328329 -275.670544) (xy 298.374141 -275.647201) (xy 298.42304 -275.631313)
			(xy 298.473822 -275.62327) (xy 298.525238 -275.62327) (xy 298.57602 -275.631313) (xy 298.624919 -275.647201)
			(xy 298.670731 -275.670544) (xy 298.712327 -275.700765) (xy 298.748683 -275.737121) (xy 298.778904 -275.778717)
			(xy 298.802247 -275.824529) (xy 298.818135 -275.873428) (xy 298.826178 -275.92421) (xy 298.826682 -275.949918)
			(xy 298.826183 -275.975372) (xy 300.072802 -275.975372) (xy 300.072802 -275.923956) (xy 300.080845 -275.873174)
			(xy 300.096733 -275.824275) (xy 300.120076 -275.778463) (xy 300.150297 -275.736867) (xy 300.186653 -275.700511)
			(xy 300.228249 -275.67029) (xy 300.274061 -275.646947) (xy 300.32296 -275.631059) (xy 300.373742 -275.623016)
			(xy 300.425158 -275.623016) (xy 300.47594 -275.631059) (xy 300.524839 -275.646947) (xy 300.570651 -275.67029)
			(xy 300.612247 -275.700511) (xy 300.648603 -275.736867) (xy 300.678824 -275.778463) (xy 300.702167 -275.824275)
			(xy 300.718055 -275.873174) (xy 300.726098 -275.923956) (xy 300.726602 -275.949664) (xy 300.726098 -275.975372)
			(xy 300.726058 -275.975626) (xy 301.972722 -275.975626) (xy 301.972722 -275.92421) (xy 301.980765 -275.873428)
			(xy 301.996653 -275.824529) (xy 302.019996 -275.778717) (xy 302.050217 -275.737121) (xy 302.086573 -275.700765)
			(xy 302.128169 -275.670544) (xy 302.173981 -275.647201) (xy 302.22288 -275.631313) (xy 302.273662 -275.62327)
			(xy 302.325078 -275.62327) (xy 302.37586 -275.631313) (xy 302.424759 -275.647201) (xy 302.470571 -275.670544)
			(xy 302.512167 -275.700765) (xy 302.548523 -275.737121) (xy 302.578744 -275.778717) (xy 302.602087 -275.824529)
			(xy 302.617975 -275.873428) (xy 302.626018 -275.92421) (xy 302.626522 -275.949918) (xy 302.626023 -275.975372)
			(xy 303.872896 -275.975372) (xy 303.872896 -275.923956) (xy 303.880939 -275.873174) (xy 303.896827 -275.824275)
			(xy 303.92017 -275.778463) (xy 303.950391 -275.736867) (xy 303.986747 -275.700511) (xy 304.028343 -275.67029)
			(xy 304.074155 -275.646947) (xy 304.123054 -275.631059) (xy 304.173836 -275.623016) (xy 304.225252 -275.623016)
			(xy 304.276034 -275.631059) (xy 304.324933 -275.646947) (xy 304.370745 -275.67029) (xy 304.412341 -275.700511)
			(xy 304.448697 -275.736867) (xy 304.478918 -275.778463) (xy 304.502261 -275.824275) (xy 304.518149 -275.873174)
			(xy 304.526192 -275.923956) (xy 304.526696 -275.949664) (xy 304.526192 -275.975372) (xy 304.526152 -275.975626)
			(xy 305.772816 -275.975626) (xy 305.772816 -275.92421) (xy 305.780859 -275.873428) (xy 305.796747 -275.824529)
			(xy 305.82009 -275.778717) (xy 305.850311 -275.737121) (xy 305.886667 -275.700765) (xy 305.928263 -275.670544)
			(xy 305.974075 -275.647201) (xy 306.022974 -275.631313) (xy 306.073756 -275.62327) (xy 306.125172 -275.62327)
			(xy 306.175954 -275.631313) (xy 306.224853 -275.647201) (xy 306.270665 -275.670544) (xy 306.312261 -275.700765)
			(xy 306.348617 -275.737121) (xy 306.378838 -275.778717) (xy 306.402181 -275.824529) (xy 306.418069 -275.873428)
			(xy 306.426112 -275.92421) (xy 306.426616 -275.949918) (xy 306.426117 -275.975372) (xy 307.67299 -275.975372)
			(xy 307.67299 -275.923956) (xy 307.681033 -275.873174) (xy 307.696921 -275.824275) (xy 307.720264 -275.778463)
			(xy 307.750485 -275.736867) (xy 307.786841 -275.700511) (xy 307.828437 -275.67029) (xy 307.874249 -275.646947)
			(xy 307.923148 -275.631059) (xy 307.97393 -275.623016) (xy 308.025346 -275.623016) (xy 308.076128 -275.631059)
			(xy 308.125027 -275.646947) (xy 308.170839 -275.67029) (xy 308.212435 -275.700511) (xy 308.248791 -275.736867)
			(xy 308.279012 -275.778463) (xy 308.302355 -275.824275) (xy 308.318243 -275.873174) (xy 308.326286 -275.923956)
			(xy 308.32679 -275.949664) (xy 308.326286 -275.975372) (xy 308.326246 -275.975626) (xy 309.57291 -275.975626)
			(xy 309.57291 -275.92421) (xy 309.580953 -275.873428) (xy 309.596841 -275.824529) (xy 309.620184 -275.778717)
			(xy 309.650405 -275.737121) (xy 309.686761 -275.700765) (xy 309.728357 -275.670544) (xy 309.774169 -275.647201)
			(xy 309.823068 -275.631313) (xy 309.87385 -275.62327) (xy 309.925266 -275.62327) (xy 309.976048 -275.631313)
			(xy 310.024947 -275.647201) (xy 310.070759 -275.670544) (xy 310.112355 -275.700765) (xy 310.148711 -275.737121)
			(xy 310.178932 -275.778717) (xy 310.202275 -275.824529) (xy 310.218163 -275.873428) (xy 310.226206 -275.92421)
			(xy 310.22671 -275.949918) (xy 310.226206 -275.975626) (xy 311.47283 -275.975626) (xy 311.47283 -275.92421)
			(xy 311.480873 -275.873428) (xy 311.496761 -275.824529) (xy 311.520104 -275.778717) (xy 311.550325 -275.737121)
			(xy 311.586681 -275.700765) (xy 311.628277 -275.670544) (xy 311.674089 -275.647201) (xy 311.722988 -275.631313)
			(xy 311.77377 -275.62327) (xy 311.825186 -275.62327) (xy 311.875968 -275.631313) (xy 311.924867 -275.647201)
			(xy 311.970679 -275.670544) (xy 312.012275 -275.700765) (xy 312.048631 -275.737121) (xy 312.078852 -275.778717)
			(xy 312.102195 -275.824529) (xy 312.118083 -275.873428) (xy 312.126126 -275.92421) (xy 312.12663 -275.949918)
			(xy 312.126126 -275.975626) (xy 312.118083 -276.026408) (xy 312.102195 -276.075307) (xy 312.078852 -276.121119)
			(xy 312.048631 -276.162715) (xy 312.012275 -276.199071) (xy 311.970679 -276.229292) (xy 311.924867 -276.252635)
			(xy 311.875968 -276.268523) (xy 311.825186 -276.276566) (xy 311.77377 -276.276566) (xy 311.722988 -276.268523)
			(xy 311.674089 -276.252635) (xy 311.628277 -276.229292) (xy 311.586681 -276.199071) (xy 311.550325 -276.162715)
			(xy 311.520104 -276.121119) (xy 311.496761 -276.075307) (xy 311.480873 -276.026408) (xy 311.47283 -275.975626)
			(xy 310.226206 -275.975626) (xy 310.218163 -276.026408) (xy 310.202275 -276.075307) (xy 310.178932 -276.121119)
			(xy 310.148711 -276.162715) (xy 310.112355 -276.199071) (xy 310.070759 -276.229292) (xy 310.024947 -276.252635)
			(xy 309.976048 -276.268523) (xy 309.925266 -276.276566) (xy 309.87385 -276.276566) (xy 309.823068 -276.268523)
			(xy 309.774169 -276.252635) (xy 309.728357 -276.229292) (xy 309.686761 -276.199071) (xy 309.650405 -276.162715)
			(xy 309.620184 -276.121119) (xy 309.596841 -276.075307) (xy 309.580953 -276.026408) (xy 309.57291 -275.975626)
			(xy 308.326246 -275.975626) (xy 308.318243 -276.026154) (xy 308.302355 -276.075053) (xy 308.279012 -276.120865)
			(xy 308.248791 -276.162461) (xy 308.212435 -276.198817) (xy 308.170839 -276.229038) (xy 308.125027 -276.252381)
			(xy 308.076128 -276.268269) (xy 308.025346 -276.276312) (xy 307.97393 -276.276312) (xy 307.923148 -276.268269)
			(xy 307.874249 -276.252381) (xy 307.828437 -276.229038) (xy 307.786841 -276.198817) (xy 307.750485 -276.162461)
			(xy 307.720264 -276.120865) (xy 307.696921 -276.075053) (xy 307.681033 -276.026154) (xy 307.67299 -275.975372)
			(xy 306.426117 -275.975372) (xy 306.426112 -275.975626) (xy 306.418069 -276.026408) (xy 306.402181 -276.075307)
			(xy 306.378838 -276.121119) (xy 306.348617 -276.162715) (xy 306.312261 -276.199071) (xy 306.270665 -276.229292)
			(xy 306.224853 -276.252635) (xy 306.175954 -276.268523) (xy 306.125172 -276.276566) (xy 306.073756 -276.276566)
			(xy 306.022974 -276.268523) (xy 305.974075 -276.252635) (xy 305.928263 -276.229292) (xy 305.886667 -276.199071)
			(xy 305.850311 -276.162715) (xy 305.82009 -276.121119) (xy 305.796747 -276.075307) (xy 305.780859 -276.026408)
			(xy 305.772816 -275.975626) (xy 304.526152 -275.975626) (xy 304.518149 -276.026154) (xy 304.502261 -276.075053)
			(xy 304.478918 -276.120865) (xy 304.448697 -276.162461) (xy 304.412341 -276.198817) (xy 304.370745 -276.229038)
			(xy 304.324933 -276.252381) (xy 304.276034 -276.268269) (xy 304.225252 -276.276312) (xy 304.173836 -276.276312)
			(xy 304.123054 -276.268269) (xy 304.074155 -276.252381) (xy 304.028343 -276.229038) (xy 303.986747 -276.198817)
			(xy 303.950391 -276.162461) (xy 303.92017 -276.120865) (xy 303.896827 -276.075053) (xy 303.880939 -276.026154)
			(xy 303.872896 -275.975372) (xy 302.626023 -275.975372) (xy 302.626018 -275.975626) (xy 302.617975 -276.026408)
			(xy 302.602087 -276.075307) (xy 302.578744 -276.121119) (xy 302.548523 -276.162715) (xy 302.512167 -276.199071)
			(xy 302.470571 -276.229292) (xy 302.424759 -276.252635) (xy 302.37586 -276.268523) (xy 302.325078 -276.276566)
			(xy 302.273662 -276.276566) (xy 302.22288 -276.268523) (xy 302.173981 -276.252635) (xy 302.128169 -276.229292)
			(xy 302.086573 -276.199071) (xy 302.050217 -276.162715) (xy 302.019996 -276.121119) (xy 301.996653 -276.075307)
			(xy 301.980765 -276.026408) (xy 301.972722 -275.975626) (xy 300.726058 -275.975626) (xy 300.718055 -276.026154)
			(xy 300.702167 -276.075053) (xy 300.678824 -276.120865) (xy 300.648603 -276.162461) (xy 300.612247 -276.198817)
			(xy 300.570651 -276.229038) (xy 300.524839 -276.252381) (xy 300.47594 -276.268269) (xy 300.425158 -276.276312)
			(xy 300.373742 -276.276312) (xy 300.32296 -276.268269) (xy 300.274061 -276.252381) (xy 300.228249 -276.229038)
			(xy 300.186653 -276.198817) (xy 300.150297 -276.162461) (xy 300.120076 -276.120865) (xy 300.096733 -276.075053)
			(xy 300.080845 -276.026154) (xy 300.072802 -275.975372) (xy 298.826183 -275.975372) (xy 298.826178 -275.975626)
			(xy 298.818135 -276.026408) (xy 298.802247 -276.075307) (xy 298.778904 -276.121119) (xy 298.748683 -276.162715)
			(xy 298.712327 -276.199071) (xy 298.670731 -276.229292) (xy 298.624919 -276.252635) (xy 298.57602 -276.268523)
			(xy 298.525238 -276.276566) (xy 298.473822 -276.276566) (xy 298.42304 -276.268523) (xy 298.374141 -276.252635)
			(xy 298.328329 -276.229292) (xy 298.286733 -276.199071) (xy 298.250377 -276.162715) (xy 298.220156 -276.121119)
			(xy 298.196813 -276.075307) (xy 298.180925 -276.026408) (xy 298.172882 -275.975626) (xy 296.926218 -275.975626)
			(xy 296.918215 -276.026154) (xy 296.902327 -276.075053) (xy 296.878984 -276.120865) (xy 296.848763 -276.162461)
			(xy 296.812407 -276.198817) (xy 296.770811 -276.229038) (xy 296.724999 -276.252381) (xy 296.6761 -276.268269)
			(xy 296.625318 -276.276312) (xy 296.573902 -276.276312) (xy 296.52312 -276.268269) (xy 296.474221 -276.252381)
			(xy 296.428409 -276.229038) (xy 296.386813 -276.198817) (xy 296.350457 -276.162461) (xy 296.320236 -276.120865)
			(xy 296.296893 -276.075053) (xy 296.281005 -276.026154) (xy 296.272962 -275.975372) (xy 295.026089 -275.975372)
			(xy 295.026084 -275.975626) (xy 295.018041 -276.026408) (xy 295.002153 -276.075307) (xy 294.97881 -276.121119)
			(xy 294.948589 -276.162715) (xy 294.912233 -276.199071) (xy 294.870637 -276.229292) (xy 294.824825 -276.252635)
			(xy 294.775926 -276.268523) (xy 294.725144 -276.276566) (xy 294.673728 -276.276566) (xy 294.622946 -276.268523)
			(xy 294.574047 -276.252635) (xy 294.528235 -276.229292) (xy 294.486639 -276.199071) (xy 294.450283 -276.162715)
			(xy 294.420062 -276.121119) (xy 294.396719 -276.075307) (xy 294.380831 -276.026408) (xy 294.372788 -275.975626)
			(xy 293.126124 -275.975626) (xy 293.118121 -276.026154) (xy 293.102233 -276.075053) (xy 293.07889 -276.120865)
			(xy 293.048669 -276.162461) (xy 293.012313 -276.198817) (xy 292.970717 -276.229038) (xy 292.924905 -276.252381)
			(xy 292.876006 -276.268269) (xy 292.825224 -276.276312) (xy 292.773808 -276.276312) (xy 292.723026 -276.268269)
			(xy 292.674127 -276.252381) (xy 292.628315 -276.229038) (xy 292.586719 -276.198817) (xy 292.550363 -276.162461)
			(xy 292.520142 -276.120865) (xy 292.496799 -276.075053) (xy 292.480911 -276.026154) (xy 292.472868 -275.975372)
			(xy 291.491924 -275.975372) (xy 291.491924 -276.925586) (xy 313.373258 -276.925586) (xy 313.373258 -276.87417)
			(xy 313.381301 -276.823388) (xy 313.397189 -276.774489) (xy 313.420532 -276.728677) (xy 313.450753 -276.687081)
			(xy 313.487109 -276.650725) (xy 313.528705 -276.620504) (xy 313.574517 -276.597161) (xy 313.623416 -276.581273)
			(xy 313.674198 -276.57323) (xy 313.725614 -276.57323) (xy 313.776396 -276.581273) (xy 313.825295 -276.597161)
			(xy 313.871107 -276.620504) (xy 313.912703 -276.650725) (xy 313.949059 -276.687081) (xy 313.97928 -276.728677)
			(xy 314.002623 -276.774489) (xy 314.018511 -276.823388) (xy 314.026554 -276.87417) (xy 314.027058 -276.899878)
			(xy 314.026554 -276.925586) (xy 314.323218 -276.925586) (xy 314.323218 -276.87417) (xy 314.331261 -276.823388)
			(xy 314.347149 -276.774489) (xy 314.370492 -276.728677) (xy 314.400713 -276.687081) (xy 314.437069 -276.650725)
			(xy 314.478665 -276.620504) (xy 314.524477 -276.597161) (xy 314.573376 -276.581273) (xy 314.624158 -276.57323)
			(xy 314.675574 -276.57323) (xy 314.726356 -276.581273) (xy 314.775255 -276.597161) (xy 314.821067 -276.620504)
			(xy 314.862663 -276.650725) (xy 314.899019 -276.687081) (xy 314.92924 -276.728677) (xy 314.952583 -276.774489)
			(xy 314.968471 -276.823388) (xy 314.976514 -276.87417) (xy 314.977018 -276.899878) (xy 314.976514 -276.925586)
			(xy 314.968471 -276.976368) (xy 314.952583 -277.025267) (xy 314.92924 -277.071079) (xy 314.899019 -277.112675)
			(xy 314.862663 -277.149031) (xy 314.821067 -277.179252) (xy 314.775255 -277.202595) (xy 314.726356 -277.218483)
			(xy 314.675574 -277.226526) (xy 314.624158 -277.226526) (xy 314.573376 -277.218483) (xy 314.524477 -277.202595)
			(xy 314.478665 -277.179252) (xy 314.437069 -277.149031) (xy 314.400713 -277.112675) (xy 314.370492 -277.071079)
			(xy 314.347149 -277.025267) (xy 314.331261 -276.976368) (xy 314.323218 -276.925586) (xy 314.026554 -276.925586)
			(xy 314.018511 -276.976368) (xy 314.002623 -277.025267) (xy 313.97928 -277.071079) (xy 313.949059 -277.112675)
			(xy 313.912703 -277.149031) (xy 313.871107 -277.179252) (xy 313.825295 -277.202595) (xy 313.776396 -277.218483)
			(xy 313.725614 -277.226526) (xy 313.674198 -277.226526) (xy 313.623416 -277.218483) (xy 313.574517 -277.202595)
			(xy 313.528705 -277.179252) (xy 313.487109 -277.149031) (xy 313.450753 -277.112675) (xy 313.420532 -277.071079)
			(xy 313.397189 -277.025267) (xy 313.381301 -276.976368) (xy 313.373258 -276.925586) (xy 291.491924 -276.925586)
			(xy 291.491924 -277.506176) (xy 291.492404 -277.515513) (xy 291.499193 -277.532916) (xy 291.511742 -277.546754)
			(xy 291.519864 -277.551388) (xy 291.601144 -277.592282) (xy 291.609734 -277.596079) (xy 291.628416 -277.597835)
			(xy 291.646482 -277.592761) (xy 291.65423 -277.587456) (xy 291.675486 -277.572283) (xy 291.721811 -277.54818)
			(xy 291.771384 -277.531758) (xy 291.822938 -277.523438) (xy 291.849048 -277.52294) (xy 291.849556 -277.52294)
			(xy 291.875245 -277.523414) (xy 291.925992 -277.531446) (xy 291.974857 -277.547317) (xy 292.020637 -277.570638)
			(xy 292.062205 -277.600834) (xy 292.098538 -277.637161) (xy 292.128739 -277.678725) (xy 292.152066 -277.724503)
			(xy 292.167944 -277.773366) (xy 292.175982 -277.824111) (xy 292.175982 -277.875489) (xy 292.175973 -277.875546)
			(xy 293.422828 -277.875546) (xy 293.422828 -277.82413) (xy 293.430871 -277.773348) (xy 293.446759 -277.724449)
			(xy 293.470102 -277.678637) (xy 293.500323 -277.637041) (xy 293.536679 -277.600685) (xy 293.578275 -277.570464)
			(xy 293.624087 -277.547121) (xy 293.672986 -277.531233) (xy 293.723768 -277.52319) (xy 293.775184 -277.52319)
			(xy 293.825966 -277.531233) (xy 293.874865 -277.547121) (xy 293.920677 -277.570464) (xy 293.962273 -277.600685)
			(xy 293.998629 -277.637041) (xy 294.02885 -277.678637) (xy 294.052193 -277.724449) (xy 294.068081 -277.773348)
			(xy 294.076124 -277.82413) (xy 294.076628 -277.849838) (xy 294.076124 -277.875546) (xy 295.323002 -277.875546)
			(xy 295.323002 -277.82413) (xy 295.331045 -277.773348) (xy 295.346933 -277.724449) (xy 295.370276 -277.678637)
			(xy 295.400497 -277.637041) (xy 295.436853 -277.600685) (xy 295.478449 -277.570464) (xy 295.524261 -277.547121)
			(xy 295.57316 -277.531233) (xy 295.623942 -277.52319) (xy 295.675358 -277.52319) (xy 295.72614 -277.531233)
			(xy 295.775039 -277.547121) (xy 295.820851 -277.570464) (xy 295.862447 -277.600685) (xy 295.898803 -277.637041)
			(xy 295.929024 -277.678637) (xy 295.952367 -277.724449) (xy 295.968255 -277.773348) (xy 295.976298 -277.82413)
			(xy 295.976802 -277.849838) (xy 295.976298 -277.875546) (xy 297.222922 -277.875546) (xy 297.222922 -277.82413)
			(xy 297.230965 -277.773348) (xy 297.246853 -277.724449) (xy 297.270196 -277.678637) (xy 297.300417 -277.637041)
			(xy 297.336773 -277.600685) (xy 297.378369 -277.570464) (xy 297.424181 -277.547121) (xy 297.47308 -277.531233)
			(xy 297.523862 -277.52319) (xy 297.575278 -277.52319) (xy 297.62606 -277.531233) (xy 297.674959 -277.547121)
			(xy 297.720771 -277.570464) (xy 297.762367 -277.600685) (xy 297.798723 -277.637041) (xy 297.828944 -277.678637)
			(xy 297.852287 -277.724449) (xy 297.868175 -277.773348) (xy 297.876218 -277.82413) (xy 297.876722 -277.849838)
			(xy 297.876218 -277.875546) (xy 299.122842 -277.875546) (xy 299.122842 -277.82413) (xy 299.130885 -277.773348)
			(xy 299.146773 -277.724449) (xy 299.170116 -277.678637) (xy 299.200337 -277.637041) (xy 299.236693 -277.600685)
			(xy 299.278289 -277.570464) (xy 299.324101 -277.547121) (xy 299.373 -277.531233) (xy 299.423782 -277.52319)
			(xy 299.475198 -277.52319) (xy 299.52598 -277.531233) (xy 299.574879 -277.547121) (xy 299.620691 -277.570464)
			(xy 299.662287 -277.600685) (xy 299.698643 -277.637041) (xy 299.728864 -277.678637) (xy 299.752207 -277.724449)
			(xy 299.768095 -277.773348) (xy 299.776138 -277.82413) (xy 299.776642 -277.849838) (xy 299.776138 -277.875546)
			(xy 301.023016 -277.875546) (xy 301.023016 -277.82413) (xy 301.031059 -277.773348) (xy 301.046947 -277.724449)
			(xy 301.07029 -277.678637) (xy 301.100511 -277.637041) (xy 301.136867 -277.600685) (xy 301.178463 -277.570464)
			(xy 301.224275 -277.547121) (xy 301.273174 -277.531233) (xy 301.323956 -277.52319) (xy 301.375372 -277.52319)
			(xy 301.426154 -277.531233) (xy 301.475053 -277.547121) (xy 301.520865 -277.570464) (xy 301.562461 -277.600685)
			(xy 301.598817 -277.637041) (xy 301.629038 -277.678637) (xy 301.652381 -277.724449) (xy 301.668269 -277.773348)
			(xy 301.676312 -277.82413) (xy 301.676816 -277.849838) (xy 301.676312 -277.875546) (xy 302.922936 -277.875546)
			(xy 302.922936 -277.82413) (xy 302.930979 -277.773348) (xy 302.946867 -277.724449) (xy 302.97021 -277.678637)
			(xy 303.000431 -277.637041) (xy 303.036787 -277.600685) (xy 303.078383 -277.570464) (xy 303.124195 -277.547121)
			(xy 303.173094 -277.531233) (xy 303.223876 -277.52319) (xy 303.275292 -277.52319) (xy 303.326074 -277.531233)
			(xy 303.374973 -277.547121) (xy 303.420785 -277.570464) (xy 303.462381 -277.600685) (xy 303.498737 -277.637041)
			(xy 303.528958 -277.678637) (xy 303.552301 -277.724449) (xy 303.568189 -277.773348) (xy 303.576232 -277.82413)
			(xy 303.576736 -277.849838) (xy 303.576232 -277.875546) (xy 304.822856 -277.875546) (xy 304.822856 -277.82413)
			(xy 304.830899 -277.773348) (xy 304.846787 -277.724449) (xy 304.87013 -277.678637) (xy 304.900351 -277.637041)
			(xy 304.936707 -277.600685) (xy 304.978303 -277.570464) (xy 305.024115 -277.547121) (xy 305.073014 -277.531233)
			(xy 305.123796 -277.52319) (xy 305.175212 -277.52319) (xy 305.225994 -277.531233) (xy 305.274893 -277.547121)
			(xy 305.320705 -277.570464) (xy 305.362301 -277.600685) (xy 305.398657 -277.637041) (xy 305.428878 -277.678637)
			(xy 305.452221 -277.724449) (xy 305.468109 -277.773348) (xy 305.476152 -277.82413) (xy 305.476656 -277.849838)
			(xy 305.476152 -277.875546) (xy 306.72303 -277.875546) (xy 306.72303 -277.82413) (xy 306.731073 -277.773348)
			(xy 306.746961 -277.724449) (xy 306.770304 -277.678637) (xy 306.800525 -277.637041) (xy 306.836881 -277.600685)
			(xy 306.878477 -277.570464) (xy 306.924289 -277.547121) (xy 306.973188 -277.531233) (xy 307.02397 -277.52319)
			(xy 307.075386 -277.52319) (xy 307.126168 -277.531233) (xy 307.175067 -277.547121) (xy 307.220879 -277.570464)
			(xy 307.262475 -277.600685) (xy 307.298831 -277.637041) (xy 307.329052 -277.678637) (xy 307.352395 -277.724449)
			(xy 307.368283 -277.773348) (xy 307.376326 -277.82413) (xy 307.37683 -277.849838) (xy 307.376326 -277.875546)
			(xy 308.62295 -277.875546) (xy 308.62295 -277.82413) (xy 308.630993 -277.773348) (xy 308.646881 -277.724449)
			(xy 308.670224 -277.678637) (xy 308.700445 -277.637041) (xy 308.736801 -277.600685) (xy 308.778397 -277.570464)
			(xy 308.824209 -277.547121) (xy 308.873108 -277.531233) (xy 308.92389 -277.52319) (xy 308.975306 -277.52319)
			(xy 309.026088 -277.531233) (xy 309.074987 -277.547121) (xy 309.120799 -277.570464) (xy 309.162395 -277.600685)
			(xy 309.198751 -277.637041) (xy 309.228972 -277.678637) (xy 309.252315 -277.724449) (xy 309.268203 -277.773348)
			(xy 309.276246 -277.82413) (xy 309.27675 -277.849838) (xy 309.276246 -277.875546) (xy 310.52287 -277.875546)
			(xy 310.52287 -277.82413) (xy 310.530913 -277.773348) (xy 310.546801 -277.724449) (xy 310.570144 -277.678637)
			(xy 310.600365 -277.637041) (xy 310.636721 -277.600685) (xy 310.678317 -277.570464) (xy 310.724129 -277.547121)
			(xy 310.773028 -277.531233) (xy 310.82381 -277.52319) (xy 310.875226 -277.52319) (xy 310.926008 -277.531233)
			(xy 310.974907 -277.547121) (xy 311.020719 -277.570464) (xy 311.062315 -277.600685) (xy 311.098671 -277.637041)
			(xy 311.128892 -277.678637) (xy 311.152235 -277.724449) (xy 311.168123 -277.773348) (xy 311.176166 -277.82413)
			(xy 311.17667 -277.849838) (xy 311.176166 -277.875546) (xy 312.423044 -277.875546) (xy 312.423044 -277.82413)
			(xy 312.431087 -277.773348) (xy 312.446975 -277.724449) (xy 312.470318 -277.678637) (xy 312.500539 -277.637041)
			(xy 312.536895 -277.600685) (xy 312.578491 -277.570464) (xy 312.624303 -277.547121) (xy 312.673202 -277.531233)
			(xy 312.723984 -277.52319) (xy 312.7754 -277.52319) (xy 312.826182 -277.531233) (xy 312.875081 -277.547121)
			(xy 312.920893 -277.570464) (xy 312.962489 -277.600685) (xy 312.998845 -277.637041) (xy 313.029066 -277.678637)
			(xy 313.052409 -277.724449) (xy 313.068297 -277.773348) (xy 313.07634 -277.82413) (xy 313.076844 -277.849838)
			(xy 313.07634 -277.875546) (xy 313.068297 -277.926328) (xy 313.052409 -277.975227) (xy 313.029066 -278.021039)
			(xy 312.998845 -278.062635) (xy 312.962489 -278.098991) (xy 312.920893 -278.129212) (xy 312.875081 -278.152555)
			(xy 312.826182 -278.168443) (xy 312.7754 -278.176486) (xy 312.723984 -278.176486) (xy 312.673202 -278.168443)
			(xy 312.624303 -278.152555) (xy 312.578491 -278.129212) (xy 312.536895 -278.098991) (xy 312.500539 -278.062635)
			(xy 312.470318 -278.021039) (xy 312.446975 -277.975227) (xy 312.431087 -277.926328) (xy 312.423044 -277.875546)
			(xy 311.176166 -277.875546) (xy 311.168123 -277.926328) (xy 311.152235 -277.975227) (xy 311.128892 -278.021039)
			(xy 311.098671 -278.062635) (xy 311.062315 -278.098991) (xy 311.020719 -278.129212) (xy 310.974907 -278.152555)
			(xy 310.926008 -278.168443) (xy 310.875226 -278.176486) (xy 310.82381 -278.176486) (xy 310.773028 -278.168443)
			(xy 310.724129 -278.152555) (xy 310.678317 -278.129212) (xy 310.636721 -278.098991) (xy 310.600365 -278.062635)
			(xy 310.570144 -278.021039) (xy 310.546801 -277.975227) (xy 310.530913 -277.926328) (xy 310.52287 -277.875546)
			(xy 309.276246 -277.875546) (xy 309.268203 -277.926328) (xy 309.252315 -277.975227) (xy 309.228972 -278.021039)
			(xy 309.198751 -278.062635) (xy 309.162395 -278.098991) (xy 309.120799 -278.129212) (xy 309.074987 -278.152555)
			(xy 309.026088 -278.168443) (xy 308.975306 -278.176486) (xy 308.92389 -278.176486) (xy 308.873108 -278.168443)
			(xy 308.824209 -278.152555) (xy 308.778397 -278.129212) (xy 308.736801 -278.098991) (xy 308.700445 -278.062635)
			(xy 308.670224 -278.021039) (xy 308.646881 -277.975227) (xy 308.630993 -277.926328) (xy 308.62295 -277.875546)
			(xy 307.376326 -277.875546) (xy 307.368283 -277.926328) (xy 307.352395 -277.975227) (xy 307.329052 -278.021039)
			(xy 307.298831 -278.062635) (xy 307.262475 -278.098991) (xy 307.220879 -278.129212) (xy 307.175067 -278.152555)
			(xy 307.126168 -278.168443) (xy 307.075386 -278.176486) (xy 307.02397 -278.176486) (xy 306.973188 -278.168443)
			(xy 306.924289 -278.152555) (xy 306.878477 -278.129212) (xy 306.836881 -278.098991) (xy 306.800525 -278.062635)
			(xy 306.770304 -278.021039) (xy 306.746961 -277.975227) (xy 306.731073 -277.926328) (xy 306.72303 -277.875546)
			(xy 305.476152 -277.875546) (xy 305.468109 -277.926328) (xy 305.452221 -277.975227) (xy 305.428878 -278.021039)
			(xy 305.398657 -278.062635) (xy 305.362301 -278.098991) (xy 305.320705 -278.129212) (xy 305.274893 -278.152555)
			(xy 305.225994 -278.168443) (xy 305.175212 -278.176486) (xy 305.123796 -278.176486) (xy 305.073014 -278.168443)
			(xy 305.024115 -278.152555) (xy 304.978303 -278.129212) (xy 304.936707 -278.098991) (xy 304.900351 -278.062635)
			(xy 304.87013 -278.021039) (xy 304.846787 -277.975227) (xy 304.830899 -277.926328) (xy 304.822856 -277.875546)
			(xy 303.576232 -277.875546) (xy 303.568189 -277.926328) (xy 303.552301 -277.975227) (xy 303.528958 -278.021039)
			(xy 303.498737 -278.062635) (xy 303.462381 -278.098991) (xy 303.420785 -278.129212) (xy 303.374973 -278.152555)
			(xy 303.326074 -278.168443) (xy 303.275292 -278.176486) (xy 303.223876 -278.176486) (xy 303.173094 -278.168443)
			(xy 303.124195 -278.152555) (xy 303.078383 -278.129212) (xy 303.036787 -278.098991) (xy 303.000431 -278.062635)
			(xy 302.97021 -278.021039) (xy 302.946867 -277.975227) (xy 302.930979 -277.926328) (xy 302.922936 -277.875546)
			(xy 301.676312 -277.875546) (xy 301.668269 -277.926328) (xy 301.652381 -277.975227) (xy 301.629038 -278.021039)
			(xy 301.598817 -278.062635) (xy 301.562461 -278.098991) (xy 301.520865 -278.129212) (xy 301.475053 -278.152555)
			(xy 301.426154 -278.168443) (xy 301.375372 -278.176486) (xy 301.323956 -278.176486) (xy 301.273174 -278.168443)
			(xy 301.224275 -278.152555) (xy 301.178463 -278.129212) (xy 301.136867 -278.098991) (xy 301.100511 -278.062635)
			(xy 301.07029 -278.021039) (xy 301.046947 -277.975227) (xy 301.031059 -277.926328) (xy 301.023016 -277.875546)
			(xy 299.776138 -277.875546) (xy 299.768095 -277.926328) (xy 299.752207 -277.975227) (xy 299.728864 -278.021039)
			(xy 299.698643 -278.062635) (xy 299.662287 -278.098991) (xy 299.620691 -278.129212) (xy 299.574879 -278.152555)
			(xy 299.52598 -278.168443) (xy 299.475198 -278.176486) (xy 299.423782 -278.176486) (xy 299.373 -278.168443)
			(xy 299.324101 -278.152555) (xy 299.278289 -278.129212) (xy 299.236693 -278.098991) (xy 299.200337 -278.062635)
			(xy 299.170116 -278.021039) (xy 299.146773 -277.975227) (xy 299.130885 -277.926328) (xy 299.122842 -277.875546)
			(xy 297.876218 -277.875546) (xy 297.868175 -277.926328) (xy 297.852287 -277.975227) (xy 297.828944 -278.021039)
			(xy 297.798723 -278.062635) (xy 297.762367 -278.098991) (xy 297.720771 -278.129212) (xy 297.674959 -278.152555)
			(xy 297.62606 -278.168443) (xy 297.575278 -278.176486) (xy 297.523862 -278.176486) (xy 297.47308 -278.168443)
			(xy 297.424181 -278.152555) (xy 297.378369 -278.129212) (xy 297.336773 -278.098991) (xy 297.300417 -278.062635)
			(xy 297.270196 -278.021039) (xy 297.246853 -277.975227) (xy 297.230965 -277.926328) (xy 297.222922 -277.875546)
			(xy 295.976298 -277.875546) (xy 295.968255 -277.926328) (xy 295.952367 -277.975227) (xy 295.929024 -278.021039)
			(xy 295.898803 -278.062635) (xy 295.862447 -278.098991) (xy 295.820851 -278.129212) (xy 295.775039 -278.152555)
			(xy 295.72614 -278.168443) (xy 295.675358 -278.176486) (xy 295.623942 -278.176486) (xy 295.57316 -278.168443)
			(xy 295.524261 -278.152555) (xy 295.478449 -278.129212) (xy 295.436853 -278.098991) (xy 295.400497 -278.062635)
			(xy 295.370276 -278.021039) (xy 295.346933 -277.975227) (xy 295.331045 -277.926328) (xy 295.323002 -277.875546)
			(xy 294.076124 -277.875546) (xy 294.068081 -277.926328) (xy 294.052193 -277.975227) (xy 294.02885 -278.021039)
			(xy 293.998629 -278.062635) (xy 293.962273 -278.098991) (xy 293.920677 -278.129212) (xy 293.874865 -278.152555)
			(xy 293.825966 -278.168443) (xy 293.775184 -278.176486) (xy 293.723768 -278.176486) (xy 293.672986 -278.168443)
			(xy 293.624087 -278.152555) (xy 293.578275 -278.129212) (xy 293.536679 -278.098991) (xy 293.500323 -278.062635)
			(xy 293.470102 -278.021039) (xy 293.446759 -277.975227) (xy 293.430871 -277.926328) (xy 293.422828 -277.875546)
			(xy 292.175973 -277.875546) (xy 292.167944 -277.926234) (xy 292.152066 -277.975097) (xy 292.128739 -278.020875)
			(xy 292.098538 -278.062439) (xy 292.062205 -278.098766) (xy 292.020637 -278.128962) (xy 291.974857 -278.152283)
			(xy 291.925992 -278.168154) (xy 291.875245 -278.176186) (xy 291.849556 -278.176736) (xy 291.849048 -278.176736)
			(xy 291.822942 -278.1762) (xy 291.771398 -278.167858) (xy 291.721832 -278.151442) (xy 291.675499 -278.127368)
			(xy 291.65423 -278.11222) (xy 291.646469 -278.106935) (xy 291.628414 -278.101847) (xy 291.609738 -278.103609)
			(xy 291.601144 -278.107394) (xy 291.519864 -278.148288) (xy 291.511692 -278.152857) (xy 291.49911 -278.166699)
			(xy 291.492365 -278.184147) (xy 291.491924 -278.1935) (xy 291.491924 -278.456136) (xy 291.492397 -278.465477)
			(xy 291.499178 -278.482891) (xy 291.511724 -278.49674) (xy 291.519864 -278.501348) (xy 291.601144 -278.542242)
			(xy 291.609734 -278.546041) (xy 291.628416 -278.547799) (xy 291.646481 -278.542721) (xy 291.65423 -278.537416)
			(xy 291.675484 -278.52224) (xy 291.72181 -278.498133) (xy 291.771382 -278.481708) (xy 291.822937 -278.473386)
			(xy 291.849048 -278.4729) (xy 291.849556 -278.4729) (xy 291.875248 -278.473375) (xy 291.926001 -278.481407)
			(xy 291.974872 -278.49728) (xy 292.020658 -278.520604) (xy 292.062231 -278.550803) (xy 292.098568 -278.587135)
			(xy 292.128773 -278.628704) (xy 292.152103 -278.674487) (xy 292.167983 -278.723356) (xy 292.176022 -278.774108)
			(xy 292.176022 -278.825492) (xy 292.17602 -278.825506) (xy 293.422828 -278.825506) (xy 293.422828 -278.77409)
			(xy 293.430871 -278.723308) (xy 293.446759 -278.674409) (xy 293.470102 -278.628597) (xy 293.500323 -278.587001)
			(xy 293.536679 -278.550645) (xy 293.578275 -278.520424) (xy 293.624087 -278.497081) (xy 293.672986 -278.481193)
			(xy 293.723768 -278.47315) (xy 293.775184 -278.47315) (xy 293.825966 -278.481193) (xy 293.874865 -278.497081)
			(xy 293.920677 -278.520424) (xy 293.962273 -278.550645) (xy 293.998629 -278.587001) (xy 294.02885 -278.628597)
			(xy 294.052193 -278.674409) (xy 294.068081 -278.723308) (xy 294.076124 -278.77409) (xy 294.076628 -278.799798)
			(xy 294.076124 -278.825506) (xy 295.323002 -278.825506) (xy 295.323002 -278.77409) (xy 295.331045 -278.723308)
			(xy 295.346933 -278.674409) (xy 295.370276 -278.628597) (xy 295.400497 -278.587001) (xy 295.436853 -278.550645)
			(xy 295.478449 -278.520424) (xy 295.524261 -278.497081) (xy 295.57316 -278.481193) (xy 295.623942 -278.47315)
			(xy 295.675358 -278.47315) (xy 295.72614 -278.481193) (xy 295.775039 -278.497081) (xy 295.820851 -278.520424)
			(xy 295.862447 -278.550645) (xy 295.898803 -278.587001) (xy 295.929024 -278.628597) (xy 295.952367 -278.674409)
			(xy 295.968255 -278.723308) (xy 295.976298 -278.77409) (xy 295.976802 -278.799798) (xy 295.976298 -278.825506)
			(xy 297.222922 -278.825506) (xy 297.222922 -278.77409) (xy 297.230965 -278.723308) (xy 297.246853 -278.674409)
			(xy 297.270196 -278.628597) (xy 297.300417 -278.587001) (xy 297.336773 -278.550645) (xy 297.378369 -278.520424)
			(xy 297.424181 -278.497081) (xy 297.47308 -278.481193) (xy 297.523862 -278.47315) (xy 297.575278 -278.47315)
			(xy 297.62606 -278.481193) (xy 297.674959 -278.497081) (xy 297.720771 -278.520424) (xy 297.762367 -278.550645)
			(xy 297.798723 -278.587001) (xy 297.828944 -278.628597) (xy 297.852287 -278.674409) (xy 297.868175 -278.723308)
			(xy 297.876218 -278.77409) (xy 297.876722 -278.799798) (xy 297.876218 -278.825506) (xy 299.122842 -278.825506)
			(xy 299.122842 -278.77409) (xy 299.130885 -278.723308) (xy 299.146773 -278.674409) (xy 299.170116 -278.628597)
			(xy 299.200337 -278.587001) (xy 299.236693 -278.550645) (xy 299.278289 -278.520424) (xy 299.324101 -278.497081)
			(xy 299.373 -278.481193) (xy 299.423782 -278.47315) (xy 299.475198 -278.47315) (xy 299.52598 -278.481193)
			(xy 299.574879 -278.497081) (xy 299.620691 -278.520424) (xy 299.662287 -278.550645) (xy 299.698643 -278.587001)
			(xy 299.728864 -278.628597) (xy 299.752207 -278.674409) (xy 299.768095 -278.723308) (xy 299.776138 -278.77409)
			(xy 299.776642 -278.799798) (xy 299.776138 -278.825506) (xy 301.023016 -278.825506) (xy 301.023016 -278.77409)
			(xy 301.031059 -278.723308) (xy 301.046947 -278.674409) (xy 301.07029 -278.628597) (xy 301.100511 -278.587001)
			(xy 301.136867 -278.550645) (xy 301.178463 -278.520424) (xy 301.224275 -278.497081) (xy 301.273174 -278.481193)
			(xy 301.323956 -278.47315) (xy 301.375372 -278.47315) (xy 301.426154 -278.481193) (xy 301.475053 -278.497081)
			(xy 301.520865 -278.520424) (xy 301.562461 -278.550645) (xy 301.598817 -278.587001) (xy 301.629038 -278.628597)
			(xy 301.652381 -278.674409) (xy 301.668269 -278.723308) (xy 301.676312 -278.77409) (xy 301.676816 -278.799798)
			(xy 301.676312 -278.825506) (xy 302.922936 -278.825506) (xy 302.922936 -278.77409) (xy 302.930979 -278.723308)
			(xy 302.946867 -278.674409) (xy 302.97021 -278.628597) (xy 303.000431 -278.587001) (xy 303.036787 -278.550645)
			(xy 303.078383 -278.520424) (xy 303.124195 -278.497081) (xy 303.173094 -278.481193) (xy 303.223876 -278.47315)
			(xy 303.275292 -278.47315) (xy 303.326074 -278.481193) (xy 303.374973 -278.497081) (xy 303.420785 -278.520424)
			(xy 303.462381 -278.550645) (xy 303.498737 -278.587001) (xy 303.528958 -278.628597) (xy 303.552301 -278.674409)
			(xy 303.568189 -278.723308) (xy 303.576232 -278.77409) (xy 303.576736 -278.799798) (xy 303.576232 -278.825506)
			(xy 304.822856 -278.825506) (xy 304.822856 -278.77409) (xy 304.830899 -278.723308) (xy 304.846787 -278.674409)
			(xy 304.87013 -278.628597) (xy 304.900351 -278.587001) (xy 304.936707 -278.550645) (xy 304.978303 -278.520424)
			(xy 305.024115 -278.497081) (xy 305.073014 -278.481193) (xy 305.123796 -278.47315) (xy 305.175212 -278.47315)
			(xy 305.225994 -278.481193) (xy 305.274893 -278.497081) (xy 305.320705 -278.520424) (xy 305.362301 -278.550645)
			(xy 305.398657 -278.587001) (xy 305.428878 -278.628597) (xy 305.452221 -278.674409) (xy 305.468109 -278.723308)
			(xy 305.476152 -278.77409) (xy 305.476656 -278.799798) (xy 305.476152 -278.825506) (xy 306.72303 -278.825506)
			(xy 306.72303 -278.77409) (xy 306.731073 -278.723308) (xy 306.746961 -278.674409) (xy 306.770304 -278.628597)
			(xy 306.800525 -278.587001) (xy 306.836881 -278.550645) (xy 306.878477 -278.520424) (xy 306.924289 -278.497081)
			(xy 306.973188 -278.481193) (xy 307.02397 -278.47315) (xy 307.075386 -278.47315) (xy 307.126168 -278.481193)
			(xy 307.175067 -278.497081) (xy 307.220879 -278.520424) (xy 307.262475 -278.550645) (xy 307.298831 -278.587001)
			(xy 307.329052 -278.628597) (xy 307.352395 -278.674409) (xy 307.368283 -278.723308) (xy 307.376326 -278.77409)
			(xy 307.37683 -278.799798) (xy 307.376326 -278.825506) (xy 308.62295 -278.825506) (xy 308.62295 -278.77409)
			(xy 308.630993 -278.723308) (xy 308.646881 -278.674409) (xy 308.670224 -278.628597) (xy 308.700445 -278.587001)
			(xy 308.736801 -278.550645) (xy 308.778397 -278.520424) (xy 308.824209 -278.497081) (xy 308.873108 -278.481193)
			(xy 308.92389 -278.47315) (xy 308.975306 -278.47315) (xy 309.026088 -278.481193) (xy 309.074987 -278.497081)
			(xy 309.120799 -278.520424) (xy 309.162395 -278.550645) (xy 309.198751 -278.587001) (xy 309.228972 -278.628597)
			(xy 309.252315 -278.674409) (xy 309.268203 -278.723308) (xy 309.276246 -278.77409) (xy 309.27675 -278.799798)
			(xy 309.276246 -278.825506) (xy 310.52287 -278.825506) (xy 310.52287 -278.77409) (xy 310.530913 -278.723308)
			(xy 310.546801 -278.674409) (xy 310.570144 -278.628597) (xy 310.600365 -278.587001) (xy 310.636721 -278.550645)
			(xy 310.678317 -278.520424) (xy 310.724129 -278.497081) (xy 310.773028 -278.481193) (xy 310.82381 -278.47315)
			(xy 310.875226 -278.47315) (xy 310.926008 -278.481193) (xy 310.974907 -278.497081) (xy 311.020719 -278.520424)
			(xy 311.062315 -278.550645) (xy 311.098671 -278.587001) (xy 311.128892 -278.628597) (xy 311.152235 -278.674409)
			(xy 311.168123 -278.723308) (xy 311.176166 -278.77409) (xy 311.17667 -278.799798) (xy 311.176166 -278.825506)
			(xy 312.423044 -278.825506) (xy 312.423044 -278.77409) (xy 312.431087 -278.723308) (xy 312.446975 -278.674409)
			(xy 312.470318 -278.628597) (xy 312.500539 -278.587001) (xy 312.536895 -278.550645) (xy 312.578491 -278.520424)
			(xy 312.624303 -278.497081) (xy 312.673202 -278.481193) (xy 312.723984 -278.47315) (xy 312.7754 -278.47315)
			(xy 312.826182 -278.481193) (xy 312.875081 -278.497081) (xy 312.920893 -278.520424) (xy 312.962489 -278.550645)
			(xy 312.998845 -278.587001) (xy 313.029066 -278.628597) (xy 313.052409 -278.674409) (xy 313.068297 -278.723308)
			(xy 313.07634 -278.77409) (xy 313.076844 -278.799798) (xy 313.07634 -278.825506) (xy 313.068297 -278.876288)
			(xy 313.052409 -278.925187) (xy 313.029066 -278.970999) (xy 312.998845 -279.012595) (xy 312.962489 -279.048951)
			(xy 312.920893 -279.079172) (xy 312.875081 -279.102515) (xy 312.826182 -279.118403) (xy 312.7754 -279.126446)
			(xy 312.723984 -279.126446) (xy 312.673202 -279.118403) (xy 312.624303 -279.102515) (xy 312.578491 -279.079172)
			(xy 312.536895 -279.048951) (xy 312.500539 -279.012595) (xy 312.470318 -278.970999) (xy 312.446975 -278.925187)
			(xy 312.431087 -278.876288) (xy 312.423044 -278.825506) (xy 311.176166 -278.825506) (xy 311.168123 -278.876288)
			(xy 311.152235 -278.925187) (xy 311.128892 -278.970999) (xy 311.098671 -279.012595) (xy 311.062315 -279.048951)
			(xy 311.020719 -279.079172) (xy 310.974907 -279.102515) (xy 310.926008 -279.118403) (xy 310.875226 -279.126446)
			(xy 310.82381 -279.126446) (xy 310.773028 -279.118403) (xy 310.724129 -279.102515) (xy 310.678317 -279.079172)
			(xy 310.636721 -279.048951) (xy 310.600365 -279.012595) (xy 310.570144 -278.970999) (xy 310.546801 -278.925187)
			(xy 310.530913 -278.876288) (xy 310.52287 -278.825506) (xy 309.276246 -278.825506) (xy 309.268203 -278.876288)
			(xy 309.252315 -278.925187) (xy 309.228972 -278.970999) (xy 309.198751 -279.012595) (xy 309.162395 -279.048951)
			(xy 309.120799 -279.079172) (xy 309.074987 -279.102515) (xy 309.026088 -279.118403) (xy 308.975306 -279.126446)
			(xy 308.92389 -279.126446) (xy 308.873108 -279.118403) (xy 308.824209 -279.102515) (xy 308.778397 -279.079172)
			(xy 308.736801 -279.048951) (xy 308.700445 -279.012595) (xy 308.670224 -278.970999) (xy 308.646881 -278.925187)
			(xy 308.630993 -278.876288) (xy 308.62295 -278.825506) (xy 307.376326 -278.825506) (xy 307.368283 -278.876288)
			(xy 307.352395 -278.925187) (xy 307.329052 -278.970999) (xy 307.298831 -279.012595) (xy 307.262475 -279.048951)
			(xy 307.220879 -279.079172) (xy 307.175067 -279.102515) (xy 307.126168 -279.118403) (xy 307.075386 -279.126446)
			(xy 307.02397 -279.126446) (xy 306.973188 -279.118403) (xy 306.924289 -279.102515) (xy 306.878477 -279.079172)
			(xy 306.836881 -279.048951) (xy 306.800525 -279.012595) (xy 306.770304 -278.970999) (xy 306.746961 -278.925187)
			(xy 306.731073 -278.876288) (xy 306.72303 -278.825506) (xy 305.476152 -278.825506) (xy 305.468109 -278.876288)
			(xy 305.452221 -278.925187) (xy 305.428878 -278.970999) (xy 305.398657 -279.012595) (xy 305.362301 -279.048951)
			(xy 305.320705 -279.079172) (xy 305.274893 -279.102515) (xy 305.225994 -279.118403) (xy 305.175212 -279.126446)
			(xy 305.123796 -279.126446) (xy 305.073014 -279.118403) (xy 305.024115 -279.102515) (xy 304.978303 -279.079172)
			(xy 304.936707 -279.048951) (xy 304.900351 -279.012595) (xy 304.87013 -278.970999) (xy 304.846787 -278.925187)
			(xy 304.830899 -278.876288) (xy 304.822856 -278.825506) (xy 303.576232 -278.825506) (xy 303.568189 -278.876288)
			(xy 303.552301 -278.925187) (xy 303.528958 -278.970999) (xy 303.498737 -279.012595) (xy 303.462381 -279.048951)
			(xy 303.420785 -279.079172) (xy 303.374973 -279.102515) (xy 303.326074 -279.118403) (xy 303.275292 -279.126446)
			(xy 303.223876 -279.126446) (xy 303.173094 -279.118403) (xy 303.124195 -279.102515) (xy 303.078383 -279.079172)
			(xy 303.036787 -279.048951) (xy 303.000431 -279.012595) (xy 302.97021 -278.970999) (xy 302.946867 -278.925187)
			(xy 302.930979 -278.876288) (xy 302.922936 -278.825506) (xy 301.676312 -278.825506) (xy 301.668269 -278.876288)
			(xy 301.652381 -278.925187) (xy 301.629038 -278.970999) (xy 301.598817 -279.012595) (xy 301.562461 -279.048951)
			(xy 301.520865 -279.079172) (xy 301.475053 -279.102515) (xy 301.426154 -279.118403) (xy 301.375372 -279.126446)
			(xy 301.323956 -279.126446) (xy 301.273174 -279.118403) (xy 301.224275 -279.102515) (xy 301.178463 -279.079172)
			(xy 301.136867 -279.048951) (xy 301.100511 -279.012595) (xy 301.07029 -278.970999) (xy 301.046947 -278.925187)
			(xy 301.031059 -278.876288) (xy 301.023016 -278.825506) (xy 299.776138 -278.825506) (xy 299.768095 -278.876288)
			(xy 299.752207 -278.925187) (xy 299.728864 -278.970999) (xy 299.698643 -279.012595) (xy 299.662287 -279.048951)
			(xy 299.620691 -279.079172) (xy 299.574879 -279.102515) (xy 299.52598 -279.118403) (xy 299.475198 -279.126446)
			(xy 299.423782 -279.126446) (xy 299.373 -279.118403) (xy 299.324101 -279.102515) (xy 299.278289 -279.079172)
			(xy 299.236693 -279.048951) (xy 299.200337 -279.012595) (xy 299.170116 -278.970999) (xy 299.146773 -278.925187)
			(xy 299.130885 -278.876288) (xy 299.122842 -278.825506) (xy 297.876218 -278.825506) (xy 297.868175 -278.876288)
			(xy 297.852287 -278.925187) (xy 297.828944 -278.970999) (xy 297.798723 -279.012595) (xy 297.762367 -279.048951)
			(xy 297.720771 -279.079172) (xy 297.674959 -279.102515) (xy 297.62606 -279.118403) (xy 297.575278 -279.126446)
			(xy 297.523862 -279.126446) (xy 297.47308 -279.118403) (xy 297.424181 -279.102515) (xy 297.378369 -279.079172)
			(xy 297.336773 -279.048951) (xy 297.300417 -279.012595) (xy 297.270196 -278.970999) (xy 297.246853 -278.925187)
			(xy 297.230965 -278.876288) (xy 297.222922 -278.825506) (xy 295.976298 -278.825506) (xy 295.968255 -278.876288)
			(xy 295.952367 -278.925187) (xy 295.929024 -278.970999) (xy 295.898803 -279.012595) (xy 295.862447 -279.048951)
			(xy 295.820851 -279.079172) (xy 295.775039 -279.102515) (xy 295.72614 -279.118403) (xy 295.675358 -279.126446)
			(xy 295.623942 -279.126446) (xy 295.57316 -279.118403) (xy 295.524261 -279.102515) (xy 295.478449 -279.079172)
			(xy 295.436853 -279.048951) (xy 295.400497 -279.012595) (xy 295.370276 -278.970999) (xy 295.346933 -278.925187)
			(xy 295.331045 -278.876288) (xy 295.323002 -278.825506) (xy 294.076124 -278.825506) (xy 294.068081 -278.876288)
			(xy 294.052193 -278.925187) (xy 294.02885 -278.970999) (xy 293.998629 -279.012595) (xy 293.962273 -279.048951)
			(xy 293.920677 -279.079172) (xy 293.874865 -279.102515) (xy 293.825966 -279.118403) (xy 293.775184 -279.126446)
			(xy 293.723768 -279.126446) (xy 293.672986 -279.118403) (xy 293.624087 -279.102515) (xy 293.578275 -279.079172)
			(xy 293.536679 -279.048951) (xy 293.500323 -279.012595) (xy 293.470102 -278.970999) (xy 293.446759 -278.925187)
			(xy 293.430871 -278.876288) (xy 293.422828 -278.825506) (xy 292.17602 -278.825506) (xy 292.167983 -278.876244)
			(xy 292.152103 -278.925113) (xy 292.128773 -278.970896) (xy 292.098568 -279.012465) (xy 292.062231 -279.048797)
			(xy 292.020658 -279.078996) (xy 291.974872 -279.10232) (xy 291.926001 -279.118193) (xy 291.875248 -279.126225)
			(xy 291.849556 -279.126696) (xy 291.84092 -279.126696) (xy 291.827204 -279.126442) (xy 291.803328 -279.139396)
			(xy 291.743384 -279.238456) (xy 291.742876 -279.265634) (xy 291.74948 -279.277572) (xy 291.764059 -279.304265)
			(xy 291.790241 -279.359169) (xy 291.801804 -279.3873) (xy 291.805992 -279.396468) (xy 291.820155 -279.410789)
			(xy 291.838725 -279.418586) (xy 291.848794 -279.41905) (xy 291.84981 -279.41905) (xy 291.875798 -279.41956)
			(xy 291.927134 -279.427692) (xy 291.976566 -279.443753) (xy 292.022877 -279.467349) (xy 292.064927 -279.497898)
			(xy 292.101681 -279.534649) (xy 292.132234 -279.576696) (xy 292.155835 -279.623005) (xy 292.171901 -279.672435)
			(xy 292.180037 -279.72377) (xy 292.180518 -279.749758) (xy 292.180033 -279.775384) (xy 292.172119 -279.826021)
			(xy 292.156492 -279.874832) (xy 292.133523 -279.920649) (xy 292.103763 -279.962376) (xy 292.067924 -279.999014)
			(xy 292.026864 -280.029686) (xy 291.981564 -280.053659) (xy 291.933109 -280.070359) (xy 291.907976 -280.075386)
			(xy 291.897295 -280.077816) (xy 291.879284 -280.090242) (xy 291.868048 -280.10902) (xy 291.86632 -280.119836)
			(xy 291.863591 -280.143608) (xy 291.856097 -280.190874) (xy 291.851334 -280.214324) (xy 291.850391 -280.219489)
			(xy 291.850399 -280.229986) (xy 291.851334 -280.235152) (xy 291.8561 -280.258601) (xy 291.863594 -280.305867)
			(xy 291.86632 -280.32964) (xy 291.868036 -280.340464) (xy 291.879259 -280.359262) (xy 291.897284 -280.37169)
			(xy 291.907976 -280.37409) (xy 291.930582 -280.378916) (xy 291.939662 -280.380789) (xy 291.958061 -280.378633)
			(xy 291.974488 -280.37007) (xy 291.986792 -280.356223) (xy 291.993364 -280.338903) (xy 291.993828 -280.32964)
			(xy 291.993828 -280.225246) (xy 291.994308 -280.199255) (xy 292.002433 -280.147913) (xy 292.018492 -280.098475)
			(xy 292.042088 -280.052158) (xy 292.07264 -280.010103) (xy 292.109396 -279.973347) (xy 292.151449 -279.942793)
			(xy 292.197766 -279.919196) (xy 292.247204 -279.903136) (xy 292.298545 -279.895009) (xy 292.324536 -279.894538)
			(xy 292.333954 -279.894574) (xy 292.352761 -279.89559) (xy 292.362128 -279.89657) (xy 292.373558 -279.89784)
			(xy 292.395148 -279.890474) (xy 292.4683 -279.81783) (xy 292.47592 -279.79624) (xy 292.47465 -279.78481)
			(xy 292.472872 -279.749504) (xy 292.473375 -279.723803) (xy 292.481414 -279.673033) (xy 292.497295 -279.624145)
			(xy 292.520627 -279.578342) (xy 292.550836 -279.536753) (xy 292.587177 -279.5004) (xy 292.628758 -279.470179)
			(xy 292.674553 -279.446833) (xy 292.723436 -279.430938) (xy 292.774204 -279.422883) (xy 292.825606 -279.422868)
			(xy 292.876378 -279.430893) (xy 292.925271 -279.44676) (xy 292.97108 -279.47008) (xy 293.012677 -279.500276)
			(xy 293.04904 -279.536608) (xy 293.079273 -279.57818) (xy 293.102632 -279.623968) (xy 293.118541 -279.672847)
			(xy 293.12661 -279.723612) (xy 293.126639 -279.775015) (xy 293.118628 -279.82579) (xy 293.102775 -279.874686)
			(xy 293.079468 -279.920502) (xy 293.049283 -279.962108) (xy 293.012962 -279.998481) (xy 292.971398 -280.028725)
			(xy 292.925616 -280.052096) (xy 292.876742 -280.06802) (xy 292.825979 -280.076102) (xy 292.800278 -280.076656)
			(xy 292.79977 -280.076656) (xy 292.764972 -280.074624) (xy 292.764464 -280.074624) (xy 292.753288 -280.073354)
			(xy 292.731698 -280.080974) (xy 292.659054 -280.154126) (xy 292.651688 -280.175716) (xy 292.651942 -280.179018)
			(xy 292.653485 -280.190513) (xy 292.655137 -280.213649) (xy 292.655244 -280.225246) (xy 292.655244 -280.273252)
			(xy 292.655814 -280.28394) (xy 292.664485 -280.303482) (xy 292.672008 -280.311098) (xy 292.736016 -280.368756)
			(xy 292.756336 -280.37536) (xy 292.767004 -280.374344) (xy 292.79977 -280.37282) (xy 292.82546 -280.373296)
			(xy 292.876208 -280.381329) (xy 292.925074 -280.397203) (xy 292.970855 -280.420526) (xy 293.012424 -280.450724)
			(xy 293.048757 -280.487053) (xy 293.078959 -280.528619) (xy 293.102286 -280.574398) (xy 293.118164 -280.623263)
			(xy 293.126202 -280.67401) (xy 293.126202 -280.72539) (xy 293.118164 -280.776137) (xy 293.102286 -280.825002)
			(xy 293.078959 -280.870781) (xy 293.048757 -280.912347) (xy 293.012424 -280.948676) (xy 292.970855 -280.978874)
			(xy 292.925074 -281.002197) (xy 292.876208 -281.018071) (xy 292.82546 -281.026104) (xy 292.79977 -281.026616)
			(xy 292.767004 -281.025092) (xy 292.756336 -281.024076) (xy 292.736016 -281.03068) (xy 292.672008 -281.088338)
			(xy 292.664358 -281.095859) (xy 292.655695 -281.115464) (xy 292.655244 -281.126184) (xy 292.655244 -281.175206)
			(xy 292.654482 -281.198828) (xy 292.654482 -281.199082) (xy 292.654294 -281.209463) (xy 292.661231 -281.22901)
			(xy 292.667944 -281.236928) (xy 292.690296 -281.260804) (xy 292.720522 -281.293316) (xy 292.727846 -281.299872)
			(xy 292.74601 -281.307337) (xy 292.755828 -281.307794)
		)
		(stroke
			(width 0)
			(type solid)
		)
		(fill yes)
		(layer "In11.Cu")
		(net "GND")
	)
	(gr_poly
		(pts
			(xy 337.32089 -216.702894) (xy 337.332009 -216.701759) (xy 337.351761 -216.691352) (xy 337.35899 -216.682828)
			(xy 337.362292 -216.677494) (xy 337.406488 -216.601548) (xy 337.409603 -216.595729) (xy 337.413071 -216.582997)
			(xy 337.413346 -216.576402) (xy 337.4136 -216.56294) (xy 337.406742 -216.551002) (xy 337.393107 -216.525871)
			(xy 337.373747 -216.472078) (xy 337.363923 -216.415757) (xy 337.363308 -216.387172) (xy 337.363818 -216.361185)
			(xy 337.371948 -216.30985) (xy 337.388009 -216.26042) (xy 337.411605 -216.21411) (xy 337.442155 -216.172062)
			(xy 337.478906 -216.135311) (xy 337.520954 -216.104761) (xy 337.567264 -216.081165) (xy 337.616694 -216.065104)
			(xy 337.668029 -216.056974) (xy 337.720003 -216.056974) (xy 337.771338 -216.065104) (xy 337.820768 -216.081165)
			(xy 337.867078 -216.104761) (xy 337.909126 -216.135311) (xy 337.945877 -216.172062) (xy 337.976427 -216.21411)
			(xy 338.000023 -216.26042) (xy 338.016084 -216.30985) (xy 338.024214 -216.361185) (xy 338.024724 -216.387172)
			(xy 338.024122 -216.415758) (xy 338.014296 -216.47208) (xy 337.994932 -216.525874) (xy 337.98129 -216.551002)
			(xy 337.977734 -216.557098) (xy 337.974432 -216.569798) (xy 337.974686 -216.576402) (xy 337.974912 -216.583003)
			(xy 337.978396 -216.59574) (xy 337.981544 -216.601548) (xy 338.02574 -216.677494) (xy 338.029042 -216.682828)
			(xy 338.036227 -216.691411) (xy 338.056 -216.701845) (xy 338.067142 -216.702894) (xy 338.12099 -216.702894)
			(xy 338.132109 -216.701759) (xy 338.151861 -216.691352) (xy 338.15909 -216.682828) (xy 338.162392 -216.677494)
			(xy 338.206588 -216.601548) (xy 338.209703 -216.595729) (xy 338.213171 -216.582997) (xy 338.213446 -216.576402)
			(xy 338.2137 -216.56294) (xy 338.206842 -216.551002) (xy 338.193207 -216.525871) (xy 338.173847 -216.472078)
			(xy 338.164023 -216.415757) (xy 338.163408 -216.387172) (xy 338.163918 -216.361185) (xy 338.172048 -216.30985)
			(xy 338.188109 -216.26042) (xy 338.211705 -216.21411) (xy 338.242255 -216.172062) (xy 338.279006 -216.135311)
			(xy 338.321054 -216.104761) (xy 338.367364 -216.081165) (xy 338.416794 -216.065104) (xy 338.468129 -216.056974)
			(xy 338.520103 -216.056974) (xy 338.571438 -216.065104) (xy 338.620868 -216.081165) (xy 338.667178 -216.104761)
			(xy 338.709226 -216.135311) (xy 338.745977 -216.172062) (xy 338.776527 -216.21411) (xy 338.800123 -216.26042)
			(xy 338.816184 -216.30985) (xy 338.824314 -216.361185) (xy 338.824824 -216.387172) (xy 338.824222 -216.415758)
			(xy 338.814396 -216.47208) (xy 338.795032 -216.525874) (xy 338.78139 -216.551002) (xy 338.777834 -216.557098)
			(xy 338.774532 -216.569798) (xy 338.774786 -216.576402) (xy 338.775012 -216.583003) (xy 338.778496 -216.59574)
			(xy 338.781644 -216.601548) (xy 338.82584 -216.677494) (xy 338.829142 -216.682828) (xy 338.836327 -216.691411)
			(xy 338.8561 -216.701845) (xy 338.867242 -216.702894) (xy 338.920836 -216.702894) (xy 338.931961 -216.701769)
			(xy 338.95173 -216.691375) (xy 338.958936 -216.682828) (xy 338.962238 -216.677494) (xy 339.006434 -216.601548)
			(xy 339.009547 -216.595728) (xy 339.013011 -216.582997) (xy 339.013292 -216.576402) (xy 339.013546 -216.56294)
			(xy 339.006688 -216.551002) (xy 338.993055 -216.52587) (xy 338.973698 -216.472077) (xy 338.963876 -216.415757)
			(xy 338.963254 -216.387172) (xy 338.963764 -216.361185) (xy 338.971894 -216.30985) (xy 338.987955 -216.26042)
			(xy 339.011551 -216.21411) (xy 339.042101 -216.172062) (xy 339.078852 -216.135311) (xy 339.1209 -216.104761)
			(xy 339.16721 -216.081165) (xy 339.21664 -216.065104) (xy 339.267975 -216.056974) (xy 339.319949 -216.056974)
			(xy 339.371284 -216.065104) (xy 339.420714 -216.081165) (xy 339.467024 -216.104761) (xy 339.509072 -216.135311)
			(xy 339.545823 -216.172062) (xy 339.576373 -216.21411) (xy 339.599969 -216.26042) (xy 339.61603 -216.30985)
			(xy 339.62416 -216.361185) (xy 339.62467 -216.387172) (xy 339.624068 -216.415759) (xy 339.614244 -216.472081)
			(xy 339.594882 -216.525876) (xy 339.581236 -216.551002) (xy 339.57768 -216.557098) (xy 339.574378 -216.569798)
			(xy 339.574632 -216.576402) (xy 339.574857 -216.583004) (xy 339.578338 -216.595742) (xy 339.58149 -216.601548)
			(xy 339.625686 -216.677494) (xy 339.628988 -216.682828) (xy 339.636176 -216.691404) (xy 339.65595 -216.70182)
			(xy 339.667088 -216.702894) (xy 345.343988 -216.702894) (xy 345.352116 -216.702132) (xy 345.352624 -216.702132)
			(xy 345.360144 -216.700534) (xy 345.373837 -216.693562) (xy 345.379548 -216.688416) (xy 345.418918 -216.649046)
			(xy 345.425729 -216.641702) (xy 345.433455 -216.623238) (xy 345.433904 -216.613232) (xy 345.433806 -216.609087)
			(xy 345.432397 -216.600917) (xy 345.43111 -216.596976) (xy 345.42603 -216.581482) (xy 345.421712 -216.575386)
			(xy 345.407866 -216.554524) (xy 345.385946 -216.509508) (xy 345.37105 -216.461706) (xy 345.363519 -216.412207)
			(xy 345.363038 -216.387172) (xy 345.363038 -216.38006) (xy 345.364067 -216.354439) (xy 345.373059 -216.303959)
			(xy 345.389736 -216.255472) (xy 345.413699 -216.210141) (xy 345.444372 -216.169053) (xy 345.481021 -216.133192)
			(xy 345.522766 -216.103419) (xy 345.568607 -216.080447) (xy 345.617445 -216.064828) (xy 345.668108 -216.056935)
			(xy 345.693746 -216.056464) (xy 345.694 -216.056464) (xy 345.719007 -216.056917) (xy 345.76845 -216.064446)
			(xy 345.816192 -216.079347) (xy 345.861141 -216.101278) (xy 345.88196 -216.115138) (xy 345.888056 -216.119456)
			(xy 345.90355 -216.124536) (xy 345.907497 -216.1258) (xy 345.915664 -216.127204) (xy 345.919806 -216.12733)
			(xy 345.929794 -216.126792) (xy 345.948227 -216.119081) (xy 345.95562 -216.112344) (xy 346.218764 -215.8492)
			(xy 346.225578 -215.841856) (xy 346.233316 -215.823394) (xy 346.23375 -215.813386) (xy 346.233657 -215.80924)
			(xy 346.232257 -215.801067) (xy 346.230956 -215.79713) (xy 346.225876 -215.781636) (xy 346.221558 -215.77554)
			(xy 346.207707 -215.754679) (xy 346.185777 -215.709665) (xy 346.170871 -215.661863) (xy 346.16333 -215.612362)
			(xy 346.162884 -215.587326) (xy 346.162884 -215.580214) (xy 346.163915 -215.554593) (xy 346.172913 -215.504116)
			(xy 346.189594 -215.455631) (xy 346.213558 -215.410303) (xy 346.244231 -215.369216) (xy 346.280878 -215.333356)
			(xy 346.322621 -215.303582) (xy 346.368459 -215.280607) (xy 346.417294 -215.264983) (xy 346.467955 -215.257083)
			(xy 346.493592 -215.256618) (xy 346.493846 -215.256618) (xy 346.518851 -215.257076) (xy 346.568291 -215.264612)
			(xy 346.616028 -215.27952) (xy 346.66097 -215.301459) (xy 346.681806 -215.315292) (xy 346.687902 -215.31961)
			(xy 346.703396 -215.32469) (xy 346.707343 -215.325951) (xy 346.71551 -215.327349) (xy 346.719652 -215.327484)
			(xy 346.729643 -215.326955) (xy 346.748086 -215.319252) (xy 346.755466 -215.312498) (xy 347.018864 -215.0491)
			(xy 347.025678 -215.041756) (xy 347.033416 -215.023294) (xy 347.03385 -215.013286) (xy 347.033757 -215.00914)
			(xy 347.032357 -215.000967) (xy 347.031056 -214.99703) (xy 347.025976 -214.981536) (xy 347.021658 -214.97544)
			(xy 347.007807 -214.954579) (xy 346.985877 -214.909565) (xy 346.970971 -214.861763) (xy 346.96343 -214.812262)
			(xy 346.962984 -214.787226) (xy 346.962984 -214.780114) (xy 346.964015 -214.754493) (xy 346.973013 -214.704016)
			(xy 346.989694 -214.655531) (xy 347.013658 -214.610203) (xy 347.044331 -214.569116) (xy 347.080978 -214.533256)
			(xy 347.122721 -214.503482) (xy 347.168559 -214.480507) (xy 347.217394 -214.464883) (xy 347.268055 -214.456983)
			(xy 347.293692 -214.456518) (xy 347.293946 -214.456518) (xy 347.318951 -214.456976) (xy 347.368391 -214.464512)
			(xy 347.416128 -214.47942) (xy 347.46107 -214.501359) (xy 347.481906 -214.515192) (xy 347.488002 -214.51951)
			(xy 347.503496 -214.52459) (xy 347.507443 -214.525851) (xy 347.51561 -214.527249) (xy 347.519752 -214.527384)
			(xy 347.529743 -214.526855) (xy 347.548186 -214.519152) (xy 347.555566 -214.512398) (xy 347.81871 -214.249254)
			(xy 347.825512 -214.241906) (xy 347.833226 -214.223443) (xy 347.833696 -214.21344) (xy 347.833599 -214.209295)
			(xy 347.832191 -214.201125) (xy 347.830902 -214.197184) (xy 347.825822 -214.18169) (xy 347.821504 -214.175594)
			(xy 347.807658 -214.154732) (xy 347.785737 -214.109716) (xy 347.770841 -214.061914) (xy 347.763308 -214.012415)
			(xy 347.76283 -213.98738) (xy 347.76283 -213.980268) (xy 347.763858 -213.954646) (xy 347.772849 -213.904165)
			(xy 347.789526 -213.855676) (xy 347.813488 -213.810344) (xy 347.844161 -213.769254) (xy 347.88081 -213.733391)
			(xy 347.922555 -213.703617) (xy 347.968397 -213.680643) (xy 348.017235 -213.665022) (xy 348.0679 -213.657127)
			(xy 348.093538 -213.656672) (xy 348.093792 -213.656672) (xy 348.118799 -213.657125) (xy 348.168243 -213.664653)
			(xy 348.215985 -213.679553) (xy 348.260934 -213.701484) (xy 348.281752 -213.715346) (xy 348.287848 -213.719664)
			(xy 348.303342 -213.724744) (xy 348.307289 -213.726008) (xy 348.315456 -213.727413) (xy 348.319598 -213.727538)
			(xy 348.329584 -213.726999) (xy 348.348011 -213.719279) (xy 348.355412 -213.712552) (xy 348.619064 -213.4489)
			(xy 348.625878 -213.441556) (xy 348.633616 -213.423094) (xy 348.63405 -213.413086) (xy 348.633957 -213.40894)
			(xy 348.632557 -213.400767) (xy 348.631256 -213.39683) (xy 348.626176 -213.381336) (xy 348.621858 -213.37524)
			(xy 348.608007 -213.354379) (xy 348.586077 -213.309365) (xy 348.571171 -213.261563) (xy 348.56363 -213.212062)
			(xy 348.563184 -213.187026) (xy 348.563184 -213.179914) (xy 348.564215 -213.154293) (xy 348.573213 -213.103816)
			(xy 348.589894 -213.055331) (xy 348.613858 -213.010003) (xy 348.644531 -212.968916) (xy 348.681178 -212.933056)
			(xy 348.722921 -212.903282) (xy 348.768759 -212.880307) (xy 348.817594 -212.864683) (xy 348.868255 -212.856783)
			(xy 348.893892 -212.856318) (xy 348.894146 -212.856318) (xy 348.919151 -212.856776) (xy 348.968591 -212.864312)
			(xy 349.016328 -212.87922) (xy 349.06127 -212.901159) (xy 349.082106 -212.914992) (xy 349.088202 -212.91931)
			(xy 349.103696 -212.92439) (xy 349.107643 -212.925651) (xy 349.11581 -212.927049) (xy 349.119952 -212.927184)
			(xy 349.129943 -212.926655) (xy 349.148386 -212.918952) (xy 349.155766 -212.912198) (xy 349.192342 -212.875622)
			(xy 349.199742 -212.86878) (xy 349.21834 -212.861057) (xy 349.22841 -212.860636) (xy 349.641922 -212.860636)
			(xy 349.645478 -212.860128) (xy 349.657474 -212.85847) (xy 349.681628 -212.856688) (xy 349.693738 -212.856572)
			(xy 349.705848 -212.856678) (xy 349.730004 -212.858454) (xy 349.741998 -212.860128) (xy 349.745554 -212.860636)
			(xy 350.441768 -212.860636) (xy 350.445324 -212.860128) (xy 350.45732 -212.858472) (xy 350.481474 -212.856693)
			(xy 350.493584 -212.856572) (xy 350.505694 -212.856679) (xy 350.529849 -212.858459) (xy 350.541844 -212.860128)
			(xy 350.5454 -212.860636) (xy 350.8502 -212.860636) (xy 350.858328 -212.859874) (xy 350.858836 -212.859874)
			(xy 350.866354 -212.858272) (xy 350.880039 -212.851292) (xy 350.88576 -212.846158) (xy 351.545398 -212.18652)
			(xy 351.545906 -212.186012) (xy 351.551102 -212.180335) (xy 351.558089 -212.16663) (xy 351.559622 -212.159088)
			(xy 351.559622 -212.15858) (xy 351.560384 -212.150452) (xy 351.560384 -211.186776) (xy 351.559736 -211.174223)
			(xy 351.547875 -211.152099) (xy 351.537778 -211.144612) (xy 351.467674 -211.097622) (xy 351.462349 -211.094294)
			(xy 351.450531 -211.090062) (xy 351.444306 -211.08924) (xy 351.43186 -211.08797) (xy 351.420176 -211.092796)
			(xy 351.419668 -211.092796) (xy 351.399618 -211.100719) (xy 351.357978 -211.111892) (xy 351.31524 -211.117559)
			(xy 351.293684 -211.117942) (xy 351.267695 -211.117431) (xy 351.216357 -211.109298) (xy 351.166924 -211.093234)
			(xy 351.120612 -211.069635) (xy 351.078561 -211.039081) (xy 351.041808 -211.002326) (xy 351.011257 -210.960275)
			(xy 350.98766 -210.913962) (xy 350.971598 -210.864527) (xy 350.963468 -210.813189) (xy 350.963468 -210.761211)
			(xy 350.971598 -210.709873) (xy 350.98766 -210.660438) (xy 351.011257 -210.614125) (xy 351.041808 -210.572074)
			(xy 351.078561 -210.535319) (xy 351.120612 -210.504765) (xy 351.166924 -210.481166) (xy 351.216357 -210.465102)
			(xy 351.267695 -210.456969) (xy 351.293684 -210.456526) (xy 351.318266 -210.456974) (xy 351.366888 -210.464249)
			(xy 351.413898 -210.47864) (xy 351.45826 -210.499831) (xy 351.498997 -210.527354) (xy 351.535211 -210.560605)
			(xy 351.550986 -210.579462) (xy 351.55124 -210.579716) (xy 351.558366 -210.587574) (xy 351.577266 -210.597152)
			(xy 351.587816 -210.598258) (xy 351.663 -210.602322) (xy 351.672881 -210.602395) (xy 351.691552 -210.595983)
			(xy 351.699322 -210.589876) (xy 353.301808 -208.98739) (xy 353.305417 -208.983897) (xy 353.313733 -208.978265)
			(xy 353.318318 -208.976214) (xy 353.335844 -208.968848) (xy 353.340408 -208.966841) (xy 353.348722 -208.961342)
			(xy 353.352354 -208.957926) (xy 354.93452 -207.37576) (xy 354.939346 -207.370172) (xy 354.944013 -207.363431)
			(xy 354.949192 -207.347885) (xy 354.949506 -207.339692) (xy 354.949506 -206.457804) (xy 354.949273 -206.451637)
			(xy 354.946194 -206.439689) (xy 354.94341 -206.434182) (xy 354.94341 -206.433674) (xy 354.937314 -206.424784)
			(xy 354.920009 -206.403925) (xy 354.890852 -206.35824) (xy 354.868453 -206.308888) (xy 354.853265 -206.256863)
			(xy 354.845592 -206.203212) (xy 354.84559 -206.149015) (xy 354.853259 -206.095364) (xy 354.868444 -206.043338)
			(xy 354.890839 -205.993984) (xy 354.919993 -205.948297) (xy 354.937314 -205.927452) (xy 354.94341 -205.918562)
			(xy 354.94341 -205.918054) (xy 354.946191 -205.912544) (xy 354.949278 -205.900599) (xy 354.949506 -205.894432)
			(xy 354.949506 -203.519532) (xy 354.949368 -203.514642) (xy 354.947447 -203.50505) (xy 354.945696 -203.500482)
			(xy 354.941886 -203.49083) (xy 354.93452 -203.483718) (xy 354.606352 -203.15555) (xy 354.600521 -203.150038)
			(xy 354.586276 -203.142669) (xy 354.578412 -203.141072) (xy 354.570284 -203.140564) (xy 347.870526 -203.140564)
			(xy 347.865446 -203.145136) (xy 347.04782 -203.962762) (xy 347.040902 -203.970346) (xy 347.033233 -203.989366)
			(xy 347.033606 -204.009871) (xy 347.037406 -204.019404) (xy 347.037406 -204.019912) (xy 347.039692 -204.02423)
			(xy 347.051997 -204.046146) (xy 347.071373 -204.092523) (xy 347.084485 -204.141045) (xy 347.091105 -204.190869)
			(xy 347.091508 -204.216) (xy 347.343982 -204.216) (xy 347.348053 -204.160378) (xy 347.360179 -204.105941)
			(xy 347.380102 -204.05385) (xy 347.407398 -204.005215) (xy 347.441484 -203.961072) (xy 347.481633 -203.922363)
			(xy 347.526991 -203.889912) (xy 347.576591 -203.864411) (xy 347.629375 -203.846404) (xy 347.684218 -203.836274)
			(xy 347.739952 -203.834237) (xy 347.795389 -203.840337) (xy 347.849346 -203.854443) (xy 347.900675 -203.876255)
			(xy 347.948281 -203.905309) (xy 347.991149 -203.940984) (xy 348.028366 -203.982521) (xy 348.059139 -204.029034)
			(xy 348.082811 -204.079531) (xy 348.098879 -204.132938) (xy 348.106999 -204.188114) (xy 348.107508 -204.216)
			(xy 348.359982 -204.216) (xy 348.364053 -204.160378) (xy 348.376179 -204.105941) (xy 348.396102 -204.05385)
			(xy 348.423398 -204.005215) (xy 348.457484 -203.961072) (xy 348.497633 -203.922363) (xy 348.542991 -203.889912)
			(xy 348.592591 -203.864411) (xy 348.645375 -203.846404) (xy 348.700218 -203.836274) (xy 348.755952 -203.834237)
			(xy 348.811389 -203.840337) (xy 348.865346 -203.854443) (xy 348.916675 -203.876255) (xy 348.964281 -203.905309)
			(xy 349.007149 -203.940984) (xy 349.044366 -203.982521) (xy 349.075139 -204.029034) (xy 349.098811 -204.079531)
			(xy 349.114879 -204.132938) (xy 349.122999 -204.188114) (xy 349.123508 -204.216) (xy 350.391982 -204.216)
			(xy 350.396053 -204.160378) (xy 350.408179 -204.105941) (xy 350.428102 -204.05385) (xy 350.455398 -204.005215)
			(xy 350.489484 -203.961072) (xy 350.529633 -203.922363) (xy 350.574991 -203.889912) (xy 350.624591 -203.864411)
			(xy 350.677375 -203.846404) (xy 350.732218 -203.836274) (xy 350.787952 -203.834237) (xy 350.843389 -203.840337)
			(xy 350.897346 -203.854443) (xy 350.948675 -203.876255) (xy 350.996281 -203.905309) (xy 351.039149 -203.940984)
			(xy 351.076366 -203.982521) (xy 351.107139 -204.029034) (xy 351.130811 -204.079531) (xy 351.146879 -204.132938)
			(xy 351.148038 -204.140816) (xy 351.747072 -204.140816) (xy 351.751143 -204.085194) (xy 351.763269 -204.030757)
			(xy 351.783192 -203.978666) (xy 351.810488 -203.930031) (xy 351.844574 -203.885888) (xy 351.884723 -203.847179)
			(xy 351.930081 -203.814728) (xy 351.979681 -203.789227) (xy 352.032465 -203.77122) (xy 352.087308 -203.76109)
			(xy 352.143042 -203.759053) (xy 352.198479 -203.765153) (xy 352.252436 -203.779259) (xy 352.303765 -203.801071)
			(xy 352.351371 -203.830125) (xy 352.394239 -203.8658) (xy 352.431456 -203.907337) (xy 352.462229 -203.95385)
			(xy 352.485901 -204.004347) (xy 352.501969 -204.057754) (xy 352.510089 -204.11293) (xy 352.510482 -204.134466)
			(xy 352.81438 -204.134466) (xy 352.818451 -204.078844) (xy 352.830577 -204.024407) (xy 352.8505 -203.972316)
			(xy 352.877796 -203.923681) (xy 352.911882 -203.879538) (xy 352.952031 -203.840829) (xy 352.997389 -203.808378)
			(xy 353.046989 -203.782877) (xy 353.099773 -203.76487) (xy 353.154616 -203.75474) (xy 353.21035 -203.752703)
			(xy 353.265787 -203.758803) (xy 353.319744 -203.772909) (xy 353.371073 -203.794721) (xy 353.418679 -203.823775)
			(xy 353.461547 -203.85945) (xy 353.498764 -203.900987) (xy 353.529537 -203.9475) (xy 353.553209 -203.997997)
			(xy 353.569277 -204.051404) (xy 353.577397 -204.10658) (xy 353.577906 -204.134466) (xy 353.577397 -204.162352)
			(xy 353.569277 -204.217528) (xy 353.553209 -204.270935) (xy 353.529537 -204.321432) (xy 353.498764 -204.367945)
			(xy 353.461547 -204.409482) (xy 353.418679 -204.445157) (xy 353.371073 -204.474211) (xy 353.319744 -204.496023)
			(xy 353.265787 -204.510129) (xy 353.21035 -204.516229) (xy 353.154616 -204.514192) (xy 353.099773 -204.504062)
			(xy 353.046989 -204.486055) (xy 352.997389 -204.460554) (xy 352.952031 -204.428103) (xy 352.911882 -204.389394)
			(xy 352.877796 -204.345251) (xy 352.8505 -204.296616) (xy 352.830577 -204.244525) (xy 352.818451 -204.190088)
			(xy 352.81438 -204.134466) (xy 352.510482 -204.134466) (xy 352.510598 -204.140816) (xy 352.510089 -204.168702)
			(xy 352.501969 -204.223878) (xy 352.485901 -204.277285) (xy 352.462229 -204.327782) (xy 352.431456 -204.374295)
			(xy 352.394239 -204.415832) (xy 352.351371 -204.451507) (xy 352.303765 -204.480561) (xy 352.252436 -204.502373)
			(xy 352.198479 -204.516479) (xy 352.143042 -204.522579) (xy 352.087308 -204.520542) (xy 352.032465 -204.510412)
			(xy 351.979681 -204.492405) (xy 351.930081 -204.466904) (xy 351.884723 -204.434453) (xy 351.844574 -204.395744)
			(xy 351.810488 -204.351601) (xy 351.783192 -204.302966) (xy 351.763269 -204.250875) (xy 351.751143 -204.196438)
			(xy 351.747072 -204.140816) (xy 351.148038 -204.140816) (xy 351.154999 -204.188114) (xy 351.155508 -204.216)
			(xy 351.154999 -204.243886) (xy 351.146879 -204.299062) (xy 351.130811 -204.352469) (xy 351.107139 -204.402966)
			(xy 351.076366 -204.449479) (xy 351.039149 -204.491016) (xy 350.996281 -204.526691) (xy 350.948675 -204.555745)
			(xy 350.897346 -204.577557) (xy 350.843389 -204.591663) (xy 350.787952 -204.597763) (xy 350.732218 -204.595726)
			(xy 350.677375 -204.585596) (xy 350.624591 -204.567589) (xy 350.574991 -204.542088) (xy 350.529633 -204.509637)
			(xy 350.489484 -204.470928) (xy 350.455398 -204.426785) (xy 350.428102 -204.37815) (xy 350.408179 -204.326059)
			(xy 350.396053 -204.271622) (xy 350.391982 -204.216) (xy 349.123508 -204.216) (xy 349.122999 -204.243886)
			(xy 349.114879 -204.299062) (xy 349.098811 -204.352469) (xy 349.075139 -204.402966) (xy 349.044366 -204.449479)
			(xy 349.007149 -204.491016) (xy 348.964281 -204.526691) (xy 348.916675 -204.555745) (xy 348.865346 -204.577557)
			(xy 348.811389 -204.591663) (xy 348.755952 -204.597763) (xy 348.700218 -204.595726) (xy 348.645375 -204.585596)
			(xy 348.592591 -204.567589) (xy 348.542991 -204.542088) (xy 348.497633 -204.509637) (xy 348.457484 -204.470928)
			(xy 348.423398 -204.426785) (xy 348.396102 -204.37815) (xy 348.376179 -204.326059) (xy 348.364053 -204.271622)
			(xy 348.359982 -204.216) (xy 348.107508 -204.216) (xy 348.106999 -204.243886) (xy 348.098879 -204.299062)
			(xy 348.082811 -204.352469) (xy 348.059139 -204.402966) (xy 348.028366 -204.449479) (xy 347.991149 -204.491016)
			(xy 347.948281 -204.526691) (xy 347.900675 -204.555745) (xy 347.849346 -204.577557) (xy 347.795389 -204.591663)
			(xy 347.739952 -204.597763) (xy 347.684218 -204.595726) (xy 347.629375 -204.585596) (xy 347.576591 -204.567589)
			(xy 347.526991 -204.542088) (xy 347.481633 -204.509637) (xy 347.441484 -204.470928) (xy 347.407398 -204.426785)
			(xy 347.380102 -204.37815) (xy 347.360179 -204.326059) (xy 347.348053 -204.271622) (xy 347.343982 -204.216)
			(xy 347.091508 -204.216) (xy 347.091022 -204.243251) (xy 347.083266 -204.297199) (xy 347.067911 -204.349494)
			(xy 347.045269 -204.399071) (xy 347.015803 -204.444921) (xy 346.980112 -204.486112) (xy 346.938921 -204.521803)
			(xy 346.893071 -204.551269) (xy 346.843494 -204.573911) (xy 346.791199 -204.589266) (xy 346.737251 -204.597022)
			(xy 346.71 -204.597508) (xy 346.701618 -204.597508) (xy 346.691204 -204.597254) (xy 346.68206 -204.60081)
			(xy 346.672408 -204.60589) (xy 346.664788 -204.611986) (xy 346.612972 -204.662786) (xy 346.606026 -204.670213)
			(xy 346.598168 -204.688949) (xy 346.597732 -204.699108) (xy 346.597732 -206.15148) (xy 346.835982 -206.15148)
			(xy 346.840053 -206.095858) (xy 346.852179 -206.041421) (xy 346.872102 -205.98933) (xy 346.899398 -205.940695)
			(xy 346.933484 -205.896552) (xy 346.973633 -205.857843) (xy 347.018991 -205.825392) (xy 347.068591 -205.799891)
			(xy 347.121375 -205.781884) (xy 347.176218 -205.771754) (xy 347.231952 -205.769717) (xy 347.287389 -205.775817)
			(xy 347.341346 -205.789923) (xy 347.392675 -205.811735) (xy 347.440281 -205.840789) (xy 347.483149 -205.876464)
			(xy 347.520366 -205.918001) (xy 347.551139 -205.964514) (xy 347.574811 -206.015011) (xy 347.590879 -206.068418)
			(xy 347.598999 -206.123594) (xy 347.599508 -206.15148) (xy 347.851982 -206.15148) (xy 347.856053 -206.095858)
			(xy 347.868179 -206.041421) (xy 347.888102 -205.98933) (xy 347.915398 -205.940695) (xy 347.949484 -205.896552)
			(xy 347.989633 -205.857843) (xy 348.034991 -205.825392) (xy 348.084591 -205.799891) (xy 348.137375 -205.781884)
			(xy 348.192218 -205.771754) (xy 348.247952 -205.769717) (xy 348.303389 -205.775817) (xy 348.357346 -205.789923)
			(xy 348.408675 -205.811735) (xy 348.456281 -205.840789) (xy 348.499149 -205.876464) (xy 348.536366 -205.918001)
			(xy 348.567139 -205.964514) (xy 348.590811 -206.015011) (xy 348.606879 -206.068418) (xy 348.614999 -206.123594)
			(xy 348.615508 -206.15148) (xy 348.615026 -206.177896) (xy 348.917004 -206.177896) (xy 348.921075 -206.122274)
			(xy 348.933201 -206.067837) (xy 348.953124 -206.015746) (xy 348.98042 -205.967111) (xy 349.014506 -205.922968)
			(xy 349.054655 -205.884259) (xy 349.100013 -205.851808) (xy 349.149613 -205.826307) (xy 349.202397 -205.8083)
			(xy 349.25724 -205.79817) (xy 349.312974 -205.796133) (xy 349.368411 -205.802233) (xy 349.422368 -205.816339)
			(xy 349.473697 -205.838151) (xy 349.521303 -205.867205) (xy 349.564171 -205.90288) (xy 349.601388 -205.944417)
			(xy 349.632161 -205.99093) (xy 349.655833 -206.041427) (xy 349.671901 -206.094834) (xy 349.680021 -206.15001)
			(xy 349.68053 -206.177896) (xy 349.680021 -206.205782) (xy 349.671901 -206.260958) (xy 349.655833 -206.314365)
			(xy 349.65277 -206.320898) (xy 350.500694 -206.320898) (xy 350.504765 -206.265276) (xy 350.516891 -206.210839)
			(xy 350.536814 -206.158748) (xy 350.56411 -206.110113) (xy 350.598196 -206.06597) (xy 350.638345 -206.027261)
			(xy 350.683703 -205.99481) (xy 350.733303 -205.969309) (xy 350.786087 -205.951302) (xy 350.84093 -205.941172)
			(xy 350.896664 -205.939135) (xy 350.952101 -205.945235) (xy 351.006058 -205.959341) (xy 351.057387 -205.981153)
			(xy 351.104993 -206.010207) (xy 351.147861 -206.045882) (xy 351.185078 -206.087419) (xy 351.215851 -206.133932)
			(xy 351.239523 -206.184429) (xy 351.240079 -206.186278) (xy 351.499422 -206.186278) (xy 351.503493 -206.130656)
			(xy 351.515619 -206.076219) (xy 351.535542 -206.024128) (xy 351.562838 -205.975493) (xy 351.596924 -205.93135)
			(xy 351.637073 -205.892641) (xy 351.682431 -205.86019) (xy 351.732031 -205.834689) (xy 351.784815 -205.816682)
			(xy 351.839658 -205.806552) (xy 351.895392 -205.804515) (xy 351.950829 -205.810615) (xy 352.004786 -205.824721)
			(xy 352.056115 -205.846533) (xy 352.103721 -205.875587) (xy 352.146589 -205.911262) (xy 352.183806 -205.952799)
			(xy 352.214579 -205.999312) (xy 352.238251 -206.049809) (xy 352.254319 -206.103216) (xy 352.262439 -206.158392)
			(xy 352.262948 -206.186278) (xy 352.262439 -206.214164) (xy 352.25645 -206.254858) (xy 352.942142 -206.254858)
			(xy 352.946213 -206.199236) (xy 352.958339 -206.144799) (xy 352.978262 -206.092708) (xy 353.005558 -206.044073)
			(xy 353.039644 -205.99993) (xy 353.079793 -205.961221) (xy 353.125151 -205.92877) (xy 353.174751 -205.903269)
			(xy 353.227535 -205.885262) (xy 353.282378 -205.875132) (xy 353.338112 -205.873095) (xy 353.393549 -205.879195)
			(xy 353.447506 -205.893301) (xy 353.498835 -205.915113) (xy 353.546441 -205.944167) (xy 353.589309 -205.979842)
			(xy 353.626526 -206.021379) (xy 353.657299 -206.067892) (xy 353.680971 -206.118389) (xy 353.697039 -206.171796)
			(xy 353.705159 -206.226972) (xy 353.705668 -206.254858) (xy 353.705159 -206.282744) (xy 353.697039 -206.33792)
			(xy 353.680971 -206.391327) (xy 353.657299 -206.441824) (xy 353.626526 -206.488337) (xy 353.589309 -206.529874)
			(xy 353.546441 -206.565549) (xy 353.498835 -206.594603) (xy 353.447506 -206.616415) (xy 353.393549 -206.630521)
			(xy 353.338112 -206.636621) (xy 353.282378 -206.634584) (xy 353.227535 -206.624454) (xy 353.174751 -206.606447)
			(xy 353.125151 -206.580946) (xy 353.079793 -206.548495) (xy 353.039644 -206.509786) (xy 353.005558 -206.465643)
			(xy 352.978262 -206.417008) (xy 352.958339 -206.364917) (xy 352.946213 -206.31048) (xy 352.942142 -206.254858)
			(xy 352.25645 -206.254858) (xy 352.254319 -206.26934) (xy 352.238251 -206.322747) (xy 352.214579 -206.373244)
			(xy 352.183806 -206.419757) (xy 352.146589 -206.461294) (xy 352.103721 -206.496969) (xy 352.056115 -206.526023)
			(xy 352.004786 -206.547835) (xy 351.950829 -206.561941) (xy 351.895392 -206.568041) (xy 351.839658 -206.566004)
			(xy 351.784815 -206.555874) (xy 351.732031 -206.537867) (xy 351.682431 -206.512366) (xy 351.637073 -206.479915)
			(xy 351.596924 -206.441206) (xy 351.562838 -206.397063) (xy 351.535542 -206.348428) (xy 351.515619 -206.296337)
			(xy 351.503493 -206.2419) (xy 351.499422 -206.186278) (xy 351.240079 -206.186278) (xy 351.255591 -206.237836)
			(xy 351.263711 -206.293012) (xy 351.26422 -206.320898) (xy 351.263711 -206.348784) (xy 351.255591 -206.40396)
			(xy 351.239523 -206.457367) (xy 351.215851 -206.507864) (xy 351.185078 -206.554377) (xy 351.147861 -206.595914)
			(xy 351.104993 -206.631589) (xy 351.057387 -206.660643) (xy 351.006058 -206.682455) (xy 350.952101 -206.696561)
			(xy 350.896664 -206.702661) (xy 350.84093 -206.700624) (xy 350.786087 -206.690494) (xy 350.733303 -206.672487)
			(xy 350.683703 -206.646986) (xy 350.638345 -206.614535) (xy 350.598196 -206.575826) (xy 350.56411 -206.531683)
			(xy 350.536814 -206.483048) (xy 350.516891 -206.430957) (xy 350.504765 -206.37652) (xy 350.500694 -206.320898)
			(xy 349.65277 -206.320898) (xy 349.632161 -206.364862) (xy 349.601388 -206.411375) (xy 349.564171 -206.452912)
			(xy 349.521303 -206.488587) (xy 349.473697 -206.517641) (xy 349.422368 -206.539453) (xy 349.368411 -206.553559)
			(xy 349.312974 -206.559659) (xy 349.25724 -206.557622) (xy 349.202397 -206.547492) (xy 349.149613 -206.529485)
			(xy 349.100013 -206.503984) (xy 349.054655 -206.471533) (xy 349.014506 -206.432824) (xy 348.98042 -206.388681)
			(xy 348.953124 -206.340046) (xy 348.933201 -206.287955) (xy 348.921075 -206.233518) (xy 348.917004 -206.177896)
			(xy 348.615026 -206.177896) (xy 348.614999 -206.179366) (xy 348.606879 -206.234542) (xy 348.590811 -206.287949)
			(xy 348.567139 -206.338446) (xy 348.536366 -206.384959) (xy 348.499149 -206.426496) (xy 348.456281 -206.462171)
			(xy 348.408675 -206.491225) (xy 348.357346 -206.513037) (xy 348.303389 -206.527143) (xy 348.247952 -206.533243)
			(xy 348.192218 -206.531206) (xy 348.137375 -206.521076) (xy 348.084591 -206.503069) (xy 348.034991 -206.477568)
			(xy 347.989633 -206.445117) (xy 347.949484 -206.406408) (xy 347.915398 -206.362265) (xy 347.888102 -206.31363)
			(xy 347.868179 -206.261539) (xy 347.856053 -206.207102) (xy 347.851982 -206.15148) (xy 347.599508 -206.15148)
			(xy 347.598999 -206.179366) (xy 347.590879 -206.234542) (xy 347.574811 -206.287949) (xy 347.551139 -206.338446)
			(xy 347.520366 -206.384959) (xy 347.483149 -206.426496) (xy 347.440281 -206.462171) (xy 347.392675 -206.491225)
			(xy 347.341346 -206.513037) (xy 347.287389 -206.527143) (xy 347.231952 -206.533243) (xy 347.176218 -206.531206)
			(xy 347.121375 -206.521076) (xy 347.068591 -206.503069) (xy 347.018991 -206.477568) (xy 346.973633 -206.445117)
			(xy 346.933484 -206.406408) (xy 346.899398 -206.362265) (xy 346.872102 -206.31363) (xy 346.852179 -206.261539)
			(xy 346.840053 -206.207102) (xy 346.835982 -206.15148) (xy 346.597732 -206.15148) (xy 346.597732 -206.411576)
			(xy 346.597227 -206.421627) (xy 346.589507 -206.440189) (xy 346.582746 -206.447644) (xy 345.71432 -207.31607)
			(xy 345.706919 -207.322907) (xy 345.68832 -207.330617) (xy 345.678252 -207.331056) (xy 335.76514 -207.331056)
			(xy 335.755076 -207.331492) (xy 335.736493 -207.339228) (xy 335.729072 -207.346042) (xy 333.144114 -209.931)
			(xy 338.911944 -209.931) (xy 338.916015 -209.875378) (xy 338.928141 -209.820941) (xy 338.948064 -209.76885)
			(xy 338.97536 -209.720215) (xy 339.009446 -209.676072) (xy 339.049595 -209.637363) (xy 339.094953 -209.604912)
			(xy 339.144553 -209.579411) (xy 339.197337 -209.561404) (xy 339.25218 -209.551274) (xy 339.307914 -209.549237)
			(xy 339.363351 -209.555337) (xy 339.417308 -209.569443) (xy 339.468637 -209.591255) (xy 339.516243 -209.620309)
			(xy 339.559111 -209.655984) (xy 339.577941 -209.677) (xy 342.517982 -209.677) (xy 342.522053 -209.621378)
			(xy 342.534179 -209.566941) (xy 342.554102 -209.51485) (xy 342.581398 -209.466215) (xy 342.615484 -209.422072)
			(xy 342.655633 -209.383363) (xy 342.700991 -209.350912) (xy 342.750591 -209.325411) (xy 342.803375 -209.307404)
			(xy 342.858218 -209.297274) (xy 342.913952 -209.295237) (xy 342.969389 -209.301337) (xy 343.023346 -209.315443)
			(xy 343.074675 -209.337255) (xy 343.122281 -209.366309) (xy 343.165149 -209.401984) (xy 343.202366 -209.443521)
			(xy 343.233139 -209.490034) (xy 343.256811 -209.540531) (xy 343.272879 -209.593938) (xy 343.280999 -209.649114)
			(xy 343.281508 -209.677) (xy 343.280999 -209.704886) (xy 343.272879 -209.760062) (xy 343.256811 -209.813469)
			(xy 343.233139 -209.863966) (xy 343.202366 -209.910479) (xy 343.165149 -209.952016) (xy 343.122281 -209.987691)
			(xy 343.074675 -210.016745) (xy 343.023346 -210.038557) (xy 342.969389 -210.052663) (xy 342.913952 -210.058763)
			(xy 342.858218 -210.056726) (xy 342.803375 -210.046596) (xy 342.750591 -210.028589) (xy 342.700991 -210.003088)
			(xy 342.655633 -209.970637) (xy 342.615484 -209.931928) (xy 342.581398 -209.887785) (xy 342.554102 -209.83915)
			(xy 342.534179 -209.787059) (xy 342.522053 -209.732622) (xy 342.517982 -209.677) (xy 339.577941 -209.677)
			(xy 339.596328 -209.697521) (xy 339.627101 -209.744034) (xy 339.650773 -209.794531) (xy 339.666841 -209.847938)
			(xy 339.674961 -209.903114) (xy 339.67547 -209.931) (xy 339.674961 -209.958886) (xy 339.666841 -210.014062)
			(xy 339.650773 -210.067469) (xy 339.627101 -210.117966) (xy 339.596328 -210.164479) (xy 339.559111 -210.206016)
			(xy 339.516243 -210.241691) (xy 339.468637 -210.270745) (xy 339.417308 -210.292557) (xy 339.363351 -210.306663)
			(xy 339.307914 -210.312763) (xy 339.25218 -210.310726) (xy 339.197337 -210.300596) (xy 339.144553 -210.282589)
			(xy 339.094953 -210.257088) (xy 339.049595 -210.224637) (xy 339.009446 -210.185928) (xy 338.97536 -210.141785)
			(xy 338.948064 -210.09315) (xy 338.928141 -210.041059) (xy 338.916015 -209.986622) (xy 338.911944 -209.931)
			(xy 333.144114 -209.931) (xy 333.137002 -209.938112) (xy 333.129608 -209.944968) (xy 333.111009 -209.952717)
			(xy 333.100934 -209.953098) (xy 332.729078 -209.953098) (xy 332.71901 -209.953525) (xy 332.700411 -209.961245)
			(xy 332.69301 -209.968084) (xy 332.286102 -210.374992) (xy 332.278736 -210.382104) (xy 332.274926 -210.391756)
			(xy 332.273167 -210.396322) (xy 332.271241 -210.405915) (xy 332.271116 -210.410806) (xy 332.271116 -210.813221)
			(xy 333.363826 -210.813221) (xy 333.363826 -210.761247) (xy 333.371956 -210.709912) (xy 333.388017 -210.660482)
			(xy 333.411613 -210.614172) (xy 333.442163 -210.572124) (xy 333.478914 -210.535373) (xy 333.520962 -210.504823)
			(xy 333.567272 -210.481227) (xy 333.616702 -210.465166) (xy 333.668037 -210.457036) (xy 333.720011 -210.457036)
			(xy 333.771346 -210.465166) (xy 333.820776 -210.481227) (xy 333.867086 -210.504823) (xy 333.909134 -210.535373)
			(xy 333.945885 -210.572124) (xy 333.976435 -210.614172) (xy 334.000031 -210.660482) (xy 334.016092 -210.709912)
			(xy 334.024222 -210.761247) (xy 334.024732 -210.787234) (xy 334.024222 -210.813221) (xy 334.163926 -210.813221)
			(xy 334.163926 -210.761247) (xy 334.172056 -210.709912) (xy 334.188117 -210.660482) (xy 334.211713 -210.614172)
			(xy 334.242263 -210.572124) (xy 334.279014 -210.535373) (xy 334.321062 -210.504823) (xy 334.367372 -210.481227)
			(xy 334.416802 -210.465166) (xy 334.468137 -210.457036) (xy 334.520111 -210.457036) (xy 334.571446 -210.465166)
			(xy 334.620876 -210.481227) (xy 334.667186 -210.504823) (xy 334.709234 -210.535373) (xy 334.745985 -210.572124)
			(xy 334.776535 -210.614172) (xy 334.800131 -210.660482) (xy 334.816192 -210.709912) (xy 334.824322 -210.761247)
			(xy 334.824832 -210.787234) (xy 334.824322 -210.813221) (xy 335.763872 -210.813221) (xy 335.763872 -210.761247)
			(xy 335.772002 -210.709912) (xy 335.788063 -210.660482) (xy 335.811659 -210.614172) (xy 335.842209 -210.572124)
			(xy 335.87896 -210.535373) (xy 335.921008 -210.504823) (xy 335.967318 -210.481227) (xy 336.016748 -210.465166)
			(xy 336.068083 -210.457036) (xy 336.120057 -210.457036) (xy 336.171392 -210.465166) (xy 336.220822 -210.481227)
			(xy 336.267132 -210.504823) (xy 336.30918 -210.535373) (xy 336.345931 -210.572124) (xy 336.376481 -210.614172)
			(xy 336.400077 -210.660482) (xy 336.416138 -210.709912) (xy 336.424268 -210.761247) (xy 336.424778 -210.787234)
			(xy 336.424268 -210.813221) (xy 338.963764 -210.813221) (xy 338.963764 -210.761247) (xy 338.971894 -210.709912)
			(xy 338.987955 -210.660482) (xy 339.011551 -210.614172) (xy 339.042101 -210.572124) (xy 339.078852 -210.535373)
			(xy 339.1209 -210.504823) (xy 339.16721 -210.481227) (xy 339.21664 -210.465166) (xy 339.267975 -210.457036)
			(xy 339.319949 -210.457036) (xy 339.371284 -210.465166) (xy 339.420714 -210.481227) (xy 339.467024 -210.504823)
			(xy 339.509072 -210.535373) (xy 339.545823 -210.572124) (xy 339.560735 -210.592649) (xy 342.538294 -210.592649)
			(xy 342.538294 -210.539351) (xy 342.546237 -210.486647) (xy 342.561947 -210.435717) (xy 342.585073 -210.387696)
			(xy 342.615097 -210.343659) (xy 342.651349 -210.304588) (xy 342.69302 -210.271357) (xy 342.739178 -210.244708)
			(xy 342.788792 -210.225236) (xy 342.840754 -210.213376) (xy 342.893904 -210.209393) (xy 342.947054 -210.213376)
			(xy 342.999016 -210.225236) (xy 343.04863 -210.244708) (xy 343.094788 -210.271357) (xy 343.136459 -210.304588)
			(xy 343.172711 -210.343659) (xy 343.202735 -210.387696) (xy 343.225861 -210.435717) (xy 343.241571 -210.486647)
			(xy 343.249514 -210.539351) (xy 343.250012 -210.566) (xy 343.249526 -210.591987) (xy 344.963752 -210.591987)
			(xy 344.963752 -210.540013) (xy 344.971882 -210.488678) (xy 344.987943 -210.439248) (xy 345.011539 -210.392938)
			(xy 345.042089 -210.35089) (xy 345.07884 -210.314139) (xy 345.120888 -210.283589) (xy 345.167198 -210.259993)
			(xy 345.216628 -210.243932) (xy 345.267963 -210.235802) (xy 345.319937 -210.235802) (xy 345.371272 -210.243932)
			(xy 345.420702 -210.259993) (xy 345.467012 -210.283589) (xy 345.50906 -210.314139) (xy 345.545811 -210.35089)
			(xy 345.576361 -210.392938) (xy 345.599957 -210.439248) (xy 345.616018 -210.488678) (xy 345.624148 -210.540013)
			(xy 345.624658 -210.566) (xy 345.624148 -210.591987) (xy 345.616018 -210.643322) (xy 345.599957 -210.692752)
			(xy 345.576361 -210.739062) (xy 345.545811 -210.78111) (xy 345.5137 -210.813221) (xy 346.163394 -210.813221)
			(xy 346.163394 -210.761247) (xy 346.171524 -210.709912) (xy 346.187585 -210.660482) (xy 346.211181 -210.614172)
			(xy 346.241731 -210.572124) (xy 346.278482 -210.535373) (xy 346.32053 -210.504823) (xy 346.36684 -210.481227)
			(xy 346.41627 -210.465166) (xy 346.467605 -210.457036) (xy 346.519579 -210.457036) (xy 346.570914 -210.465166)
			(xy 346.620344 -210.481227) (xy 346.666654 -210.504823) (xy 346.708702 -210.535373) (xy 346.745453 -210.572124)
			(xy 346.776003 -210.614172) (xy 346.799599 -210.660482) (xy 346.81566 -210.709912) (xy 346.82379 -210.761247)
			(xy 346.8243 -210.787234) (xy 346.82379 -210.813221) (xy 346.963494 -210.813221) (xy 346.963494 -210.761247)
			(xy 346.971624 -210.709912) (xy 346.987685 -210.660482) (xy 347.011281 -210.614172) (xy 347.041831 -210.572124)
			(xy 347.078582 -210.535373) (xy 347.12063 -210.504823) (xy 347.16694 -210.481227) (xy 347.21637 -210.465166)
			(xy 347.267705 -210.457036) (xy 347.319679 -210.457036) (xy 347.371014 -210.465166) (xy 347.420444 -210.481227)
			(xy 347.466754 -210.504823) (xy 347.508802 -210.535373) (xy 347.545553 -210.572124) (xy 347.576103 -210.614172)
			(xy 347.599699 -210.660482) (xy 347.61576 -210.709912) (xy 347.62389 -210.761247) (xy 347.6244 -210.787234)
			(xy 347.62389 -210.813221) (xy 347.76334 -210.813221) (xy 347.76334 -210.761247) (xy 347.77147 -210.709912)
			(xy 347.787531 -210.660482) (xy 347.811127 -210.614172) (xy 347.841677 -210.572124) (xy 347.878428 -210.535373)
			(xy 347.920476 -210.504823) (xy 347.966786 -210.481227) (xy 348.016216 -210.465166) (xy 348.067551 -210.457036)
			(xy 348.119525 -210.457036) (xy 348.17086 -210.465166) (xy 348.22029 -210.481227) (xy 348.2666 -210.504823)
			(xy 348.308648 -210.535373) (xy 348.345399 -210.572124) (xy 348.375949 -210.614172) (xy 348.399545 -210.660482)
			(xy 348.415606 -210.709912) (xy 348.423736 -210.761247) (xy 348.424246 -210.787234) (xy 348.423736 -210.813221)
			(xy 348.415606 -210.864556) (xy 348.399545 -210.913986) (xy 348.375949 -210.960296) (xy 348.345399 -211.002344)
			(xy 348.308648 -211.039095) (xy 348.2666 -211.069645) (xy 348.22029 -211.093241) (xy 348.17086 -211.109302)
			(xy 348.119525 -211.117432) (xy 348.067551 -211.117432) (xy 348.016216 -211.109302) (xy 347.966786 -211.093241)
			(xy 347.920476 -211.069645) (xy 347.878428 -211.039095) (xy 347.841677 -211.002344) (xy 347.811127 -210.960296)
			(xy 347.787531 -210.913986) (xy 347.77147 -210.864556) (xy 347.76334 -210.813221) (xy 347.62389 -210.813221)
			(xy 347.61576 -210.864556) (xy 347.599699 -210.913986) (xy 347.576103 -210.960296) (xy 347.545553 -211.002344)
			(xy 347.508802 -211.039095) (xy 347.466754 -211.069645) (xy 347.420444 -211.093241) (xy 347.371014 -211.109302)
			(xy 347.319679 -211.117432) (xy 347.267705 -211.117432) (xy 347.21637 -211.109302) (xy 347.16694 -211.093241)
			(xy 347.12063 -211.069645) (xy 347.078582 -211.039095) (xy 347.041831 -211.002344) (xy 347.011281 -210.960296)
			(xy 346.987685 -210.913986) (xy 346.971624 -210.864556) (xy 346.963494 -210.813221) (xy 346.82379 -210.813221)
			(xy 346.81566 -210.864556) (xy 346.799599 -210.913986) (xy 346.776003 -210.960296) (xy 346.745453 -211.002344)
			(xy 346.708702 -211.039095) (xy 346.666654 -211.069645) (xy 346.620344 -211.093241) (xy 346.570914 -211.109302)
			(xy 346.519579 -211.117432) (xy 346.467605 -211.117432) (xy 346.41627 -211.109302) (xy 346.36684 -211.093241)
			(xy 346.32053 -211.069645) (xy 346.278482 -211.039095) (xy 346.241731 -211.002344) (xy 346.211181 -210.960296)
			(xy 346.187585 -210.913986) (xy 346.171524 -210.864556) (xy 346.163394 -210.813221) (xy 345.5137 -210.813221)
			(xy 345.50906 -210.817861) (xy 345.467012 -210.848411) (xy 345.420702 -210.872007) (xy 345.371272 -210.888068)
			(xy 345.319937 -210.896198) (xy 345.267963 -210.896198) (xy 345.216628 -210.888068) (xy 345.167198 -210.872007)
			(xy 345.120888 -210.848411) (xy 345.07884 -210.817861) (xy 345.042089 -210.78111) (xy 345.011539 -210.739062)
			(xy 344.987943 -210.692752) (xy 344.971882 -210.643322) (xy 344.963752 -210.591987) (xy 343.249526 -210.591987)
			(xy 343.249514 -210.592649) (xy 343.241571 -210.645353) (xy 343.225861 -210.696283) (xy 343.202735 -210.744304)
			(xy 343.172711 -210.788341) (xy 343.136459 -210.827412) (xy 343.094788 -210.860643) (xy 343.04863 -210.887292)
			(xy 342.999016 -210.906764) (xy 342.947054 -210.918624) (xy 342.893904 -210.922608) (xy 342.840754 -210.918624)
			(xy 342.788792 -210.906764) (xy 342.739178 -210.887292) (xy 342.69302 -210.860643) (xy 342.651349 -210.827412)
			(xy 342.615097 -210.788341) (xy 342.585073 -210.744304) (xy 342.561947 -210.696283) (xy 342.546237 -210.645353)
			(xy 342.538294 -210.592649) (xy 339.560735 -210.592649) (xy 339.576373 -210.614172) (xy 339.599969 -210.660482)
			(xy 339.61603 -210.709912) (xy 339.62416 -210.761247) (xy 339.62467 -210.787234) (xy 339.62416 -210.813221)
			(xy 339.61603 -210.864556) (xy 339.599969 -210.913986) (xy 339.576373 -210.960296) (xy 339.545823 -211.002344)
			(xy 339.509072 -211.039095) (xy 339.467024 -211.069645) (xy 339.420714 -211.093241) (xy 339.371284 -211.109302)
			(xy 339.319949 -211.117432) (xy 339.267975 -211.117432) (xy 339.21664 -211.109302) (xy 339.16721 -211.093241)
			(xy 339.1209 -211.069645) (xy 339.078852 -211.039095) (xy 339.042101 -211.002344) (xy 339.011551 -210.960296)
			(xy 338.987955 -210.913986) (xy 338.971894 -210.864556) (xy 338.963764 -210.813221) (xy 336.424268 -210.813221)
			(xy 336.416138 -210.864556) (xy 336.400077 -210.913986) (xy 336.376481 -210.960296) (xy 336.345931 -211.002344)
			(xy 336.30918 -211.039095) (xy 336.267132 -211.069645) (xy 336.220822 -211.093241) (xy 336.171392 -211.109302)
			(xy 336.120057 -211.117432) (xy 336.068083 -211.117432) (xy 336.016748 -211.109302) (xy 335.967318 -211.093241)
			(xy 335.921008 -211.069645) (xy 335.87896 -211.039095) (xy 335.842209 -211.002344) (xy 335.811659 -210.960296)
			(xy 335.788063 -210.913986) (xy 335.772002 -210.864556) (xy 335.763872 -210.813221) (xy 334.824322 -210.813221)
			(xy 334.816192 -210.864556) (xy 334.800131 -210.913986) (xy 334.776535 -210.960296) (xy 334.745985 -211.002344)
			(xy 334.709234 -211.039095) (xy 334.667186 -211.069645) (xy 334.620876 -211.093241) (xy 334.571446 -211.109302)
			(xy 334.520111 -211.117432) (xy 334.468137 -211.117432) (xy 334.416802 -211.109302) (xy 334.367372 -211.093241)
			(xy 334.321062 -211.069645) (xy 334.279014 -211.039095) (xy 334.242263 -211.002344) (xy 334.211713 -210.960296)
			(xy 334.188117 -210.913986) (xy 334.172056 -210.864556) (xy 334.163926 -210.813221) (xy 334.024222 -210.813221)
			(xy 334.016092 -210.864556) (xy 334.000031 -210.913986) (xy 333.976435 -210.960296) (xy 333.945885 -211.002344)
			(xy 333.909134 -211.039095) (xy 333.867086 -211.069645) (xy 333.820776 -211.093241) (xy 333.771346 -211.109302)
			(xy 333.720011 -211.117432) (xy 333.668037 -211.117432) (xy 333.616702 -211.109302) (xy 333.567272 -211.093241)
			(xy 333.520962 -211.069645) (xy 333.478914 -211.039095) (xy 333.442163 -211.002344) (xy 333.411613 -210.960296)
			(xy 333.388017 -210.913986) (xy 333.371956 -210.864556) (xy 333.363826 -210.813221) (xy 332.271116 -210.813221)
			(xy 332.271116 -211.613321) (xy 333.363826 -211.613321) (xy 333.363826 -211.561347) (xy 333.371956 -211.510012)
			(xy 333.388017 -211.460582) (xy 333.411613 -211.414272) (xy 333.442163 -211.372224) (xy 333.478914 -211.335473)
			(xy 333.520962 -211.304923) (xy 333.567272 -211.281327) (xy 333.616702 -211.265266) (xy 333.668037 -211.257136)
			(xy 333.720011 -211.257136) (xy 333.771346 -211.265266) (xy 333.820776 -211.281327) (xy 333.867086 -211.304923)
			(xy 333.909134 -211.335473) (xy 333.945885 -211.372224) (xy 333.976435 -211.414272) (xy 334.000031 -211.460582)
			(xy 334.016092 -211.510012) (xy 334.024222 -211.561347) (xy 334.024732 -211.587334) (xy 334.024222 -211.613321)
			(xy 334.163926 -211.613321) (xy 334.163926 -211.561347) (xy 334.172056 -211.510012) (xy 334.188117 -211.460582)
			(xy 334.211713 -211.414272) (xy 334.242263 -211.372224) (xy 334.279014 -211.335473) (xy 334.321062 -211.304923)
			(xy 334.367372 -211.281327) (xy 334.416802 -211.265266) (xy 334.468137 -211.257136) (xy 334.520111 -211.257136)
			(xy 334.571446 -211.265266) (xy 334.620876 -211.281327) (xy 334.667186 -211.304923) (xy 334.709234 -211.335473)
			(xy 334.745985 -211.372224) (xy 334.776535 -211.414272) (xy 334.800131 -211.460582) (xy 334.816192 -211.510012)
			(xy 334.824322 -211.561347) (xy 334.824832 -211.587334) (xy 334.824322 -211.613321) (xy 335.763872 -211.613321)
			(xy 335.763872 -211.561347) (xy 335.772002 -211.510012) (xy 335.788063 -211.460582) (xy 335.811659 -211.414272)
			(xy 335.842209 -211.372224) (xy 335.87896 -211.335473) (xy 335.921008 -211.304923) (xy 335.967318 -211.281327)
			(xy 336.016748 -211.265266) (xy 336.068083 -211.257136) (xy 336.120057 -211.257136) (xy 336.171392 -211.265266)
			(xy 336.220822 -211.281327) (xy 336.267132 -211.304923) (xy 336.30918 -211.335473) (xy 336.345931 -211.372224)
			(xy 336.376481 -211.414272) (xy 336.400077 -211.460582) (xy 336.416138 -211.510012) (xy 336.424268 -211.561347)
			(xy 336.424778 -211.587334) (xy 336.424268 -211.613321) (xy 337.363818 -211.613321) (xy 337.363818 -211.561347)
			(xy 337.371948 -211.510012) (xy 337.388009 -211.460582) (xy 337.411605 -211.414272) (xy 337.442155 -211.372224)
			(xy 337.478906 -211.335473) (xy 337.520954 -211.304923) (xy 337.567264 -211.281327) (xy 337.616694 -211.265266)
			(xy 337.668029 -211.257136) (xy 337.720003 -211.257136) (xy 337.771338 -211.265266) (xy 337.820768 -211.281327)
			(xy 337.867078 -211.304923) (xy 337.909126 -211.335473) (xy 337.945877 -211.372224) (xy 337.976427 -211.414272)
			(xy 338.000023 -211.460582) (xy 338.016084 -211.510012) (xy 338.024214 -211.561347) (xy 338.024724 -211.587334)
			(xy 338.024214 -211.613321) (xy 338.963764 -211.613321) (xy 338.963764 -211.561347) (xy 338.971894 -211.510012)
			(xy 338.987955 -211.460582) (xy 339.011551 -211.414272) (xy 339.042101 -211.372224) (xy 339.078852 -211.335473)
			(xy 339.1209 -211.304923) (xy 339.16721 -211.281327) (xy 339.21664 -211.265266) (xy 339.267975 -211.257136)
			(xy 339.319949 -211.257136) (xy 339.371284 -211.265266) (xy 339.420714 -211.281327) (xy 339.467024 -211.304923)
			(xy 339.509072 -211.335473) (xy 339.545823 -211.372224) (xy 339.576373 -211.414272) (xy 339.599969 -211.460582)
			(xy 339.61603 -211.510012) (xy 339.62416 -211.561347) (xy 339.62467 -211.587334) (xy 339.62416 -211.613321)
			(xy 341.36381 -211.613321) (xy 341.36381 -211.561347) (xy 341.37194 -211.510012) (xy 341.388001 -211.460582)
			(xy 341.411597 -211.414272) (xy 341.442147 -211.372224) (xy 341.478898 -211.335473) (xy 341.520946 -211.304923)
			(xy 341.567256 -211.281327) (xy 341.616686 -211.265266) (xy 341.668021 -211.257136) (xy 341.719995 -211.257136)
			(xy 341.77133 -211.265266) (xy 341.82076 -211.281327) (xy 341.86707 -211.304923) (xy 341.909118 -211.335473)
			(xy 341.945869 -211.372224) (xy 341.976419 -211.414272) (xy 342.000015 -211.460582) (xy 342.016076 -211.510012)
			(xy 342.024206 -211.561347) (xy 342.024716 -211.587334) (xy 342.024206 -211.613321) (xy 344.563448 -211.613321)
			(xy 344.563448 -211.561347) (xy 344.571578 -211.510012) (xy 344.587639 -211.460582) (xy 344.611235 -211.414272)
			(xy 344.641785 -211.372224) (xy 344.678536 -211.335473) (xy 344.720584 -211.304923) (xy 344.766894 -211.281327)
			(xy 344.816324 -211.265266) (xy 344.867659 -211.257136) (xy 344.919633 -211.257136) (xy 344.970968 -211.265266)
			(xy 345.020398 -211.281327) (xy 345.066708 -211.304923) (xy 345.108756 -211.335473) (xy 345.145507 -211.372224)
			(xy 345.176057 -211.414272) (xy 345.199653 -211.460582) (xy 345.215714 -211.510012) (xy 345.223844 -211.561347)
			(xy 345.224354 -211.587334) (xy 345.223844 -211.613321) (xy 346.163394 -211.613321) (xy 346.163394 -211.561347)
			(xy 346.171524 -211.510012) (xy 346.187585 -211.460582) (xy 346.211181 -211.414272) (xy 346.241731 -211.372224)
			(xy 346.278482 -211.335473) (xy 346.32053 -211.304923) (xy 346.36684 -211.281327) (xy 346.41627 -211.265266)
			(xy 346.467605 -211.257136) (xy 346.519579 -211.257136) (xy 346.570914 -211.265266) (xy 346.620344 -211.281327)
			(xy 346.666654 -211.304923) (xy 346.708702 -211.335473) (xy 346.745453 -211.372224) (xy 346.776003 -211.414272)
			(xy 346.799599 -211.460582) (xy 346.81566 -211.510012) (xy 346.82379 -211.561347) (xy 346.8243 -211.587334)
			(xy 346.82379 -211.613321) (xy 346.963494 -211.613321) (xy 346.963494 -211.561347) (xy 346.971624 -211.510012)
			(xy 346.987685 -211.460582) (xy 347.011281 -211.414272) (xy 347.041831 -211.372224) (xy 347.078582 -211.335473)
			(xy 347.12063 -211.304923) (xy 347.16694 -211.281327) (xy 347.21637 -211.265266) (xy 347.267705 -211.257136)
			(xy 347.319679 -211.257136) (xy 347.371014 -211.265266) (xy 347.420444 -211.281327) (xy 347.466754 -211.304923)
			(xy 347.508802 -211.335473) (xy 347.545553 -211.372224) (xy 347.576103 -211.414272) (xy 347.599699 -211.460582)
			(xy 347.61576 -211.510012) (xy 347.62389 -211.561347) (xy 347.6244 -211.587334) (xy 347.62389 -211.613321)
			(xy 347.76334 -211.613321) (xy 347.76334 -211.561347) (xy 347.77147 -211.510012) (xy 347.787531 -211.460582)
			(xy 347.811127 -211.414272) (xy 347.841677 -211.372224) (xy 347.878428 -211.335473) (xy 347.920476 -211.304923)
			(xy 347.966786 -211.281327) (xy 348.016216 -211.265266) (xy 348.067551 -211.257136) (xy 348.119525 -211.257136)
			(xy 348.17086 -211.265266) (xy 348.22029 -211.281327) (xy 348.2666 -211.304923) (xy 348.308648 -211.335473)
			(xy 348.345399 -211.372224) (xy 348.375949 -211.414272) (xy 348.399545 -211.460582) (xy 348.415606 -211.510012)
			(xy 348.423736 -211.561347) (xy 348.424246 -211.587334) (xy 348.423736 -211.613321) (xy 348.56344 -211.613321)
			(xy 348.56344 -211.561347) (xy 348.57157 -211.510012) (xy 348.587631 -211.460582) (xy 348.611227 -211.414272)
			(xy 348.641777 -211.372224) (xy 348.678528 -211.335473) (xy 348.720576 -211.304923) (xy 348.766886 -211.281327)
			(xy 348.816316 -211.265266) (xy 348.867651 -211.257136) (xy 348.919625 -211.257136) (xy 348.97096 -211.265266)
			(xy 349.02039 -211.281327) (xy 349.0667 -211.304923) (xy 349.108748 -211.335473) (xy 349.145499 -211.372224)
			(xy 349.176049 -211.414272) (xy 349.199645 -211.460582) (xy 349.215706 -211.510012) (xy 349.223836 -211.561347)
			(xy 349.224346 -211.587334) (xy 349.223836 -211.613321) (xy 350.163386 -211.613321) (xy 350.163386 -211.561347)
			(xy 350.171516 -211.510012) (xy 350.187577 -211.460582) (xy 350.211173 -211.414272) (xy 350.241723 -211.372224)
			(xy 350.278474 -211.335473) (xy 350.320522 -211.304923) (xy 350.366832 -211.281327) (xy 350.416262 -211.265266)
			(xy 350.467597 -211.257136) (xy 350.519571 -211.257136) (xy 350.570906 -211.265266) (xy 350.620336 -211.281327)
			(xy 350.666646 -211.304923) (xy 350.708694 -211.335473) (xy 350.745445 -211.372224) (xy 350.775995 -211.414272)
			(xy 350.799591 -211.460582) (xy 350.815652 -211.510012) (xy 350.823782 -211.561347) (xy 350.824292 -211.587334)
			(xy 350.823782 -211.613321) (xy 350.815652 -211.664656) (xy 350.799591 -211.714086) (xy 350.775995 -211.760396)
			(xy 350.745445 -211.802444) (xy 350.708694 -211.839195) (xy 350.666646 -211.869745) (xy 350.620336 -211.893341)
			(xy 350.570906 -211.909402) (xy 350.519571 -211.917532) (xy 350.467597 -211.917532) (xy 350.416262 -211.909402)
			(xy 350.366832 -211.893341) (xy 350.320522 -211.869745) (xy 350.278474 -211.839195) (xy 350.241723 -211.802444)
			(xy 350.211173 -211.760396) (xy 350.187577 -211.714086) (xy 350.171516 -211.664656) (xy 350.163386 -211.613321)
			(xy 349.223836 -211.613321) (xy 349.215706 -211.664656) (xy 349.199645 -211.714086) (xy 349.176049 -211.760396)
			(xy 349.145499 -211.802444) (xy 349.108748 -211.839195) (xy 349.0667 -211.869745) (xy 349.02039 -211.893341)
			(xy 348.97096 -211.909402) (xy 348.919625 -211.917532) (xy 348.867651 -211.917532) (xy 348.816316 -211.909402)
			(xy 348.766886 -211.893341) (xy 348.720576 -211.869745) (xy 348.678528 -211.839195) (xy 348.641777 -211.802444)
			(xy 348.611227 -211.760396) (xy 348.587631 -211.714086) (xy 348.57157 -211.664656) (xy 348.56344 -211.613321)
			(xy 348.423736 -211.613321) (xy 348.415606 -211.664656) (xy 348.399545 -211.714086) (xy 348.375949 -211.760396)
			(xy 348.345399 -211.802444) (xy 348.308648 -211.839195) (xy 348.2666 -211.869745) (xy 348.22029 -211.893341)
			(xy 348.17086 -211.909402) (xy 348.119525 -211.917532) (xy 348.067551 -211.917532) (xy 348.016216 -211.909402)
			(xy 347.966786 -211.893341) (xy 347.920476 -211.869745) (xy 347.878428 -211.839195) (xy 347.841677 -211.802444)
			(xy 347.811127 -211.760396) (xy 347.787531 -211.714086) (xy 347.77147 -211.664656) (xy 347.76334 -211.613321)
			(xy 347.62389 -211.613321) (xy 347.61576 -211.664656) (xy 347.599699 -211.714086) (xy 347.576103 -211.760396)
			(xy 347.545553 -211.802444) (xy 347.508802 -211.839195) (xy 347.466754 -211.869745) (xy 347.420444 -211.893341)
			(xy 347.371014 -211.909402) (xy 347.319679 -211.917532) (xy 347.267705 -211.917532) (xy 347.21637 -211.909402)
			(xy 347.16694 -211.893341) (xy 347.12063 -211.869745) (xy 347.078582 -211.839195) (xy 347.041831 -211.802444)
			(xy 347.011281 -211.760396) (xy 346.987685 -211.714086) (xy 346.971624 -211.664656) (xy 346.963494 -211.613321)
			(xy 346.82379 -211.613321) (xy 346.81566 -211.664656) (xy 346.799599 -211.714086) (xy 346.776003 -211.760396)
			(xy 346.745453 -211.802444) (xy 346.708702 -211.839195) (xy 346.666654 -211.869745) (xy 346.620344 -211.893341)
			(xy 346.570914 -211.909402) (xy 346.519579 -211.917532) (xy 346.467605 -211.917532) (xy 346.41627 -211.909402)
			(xy 346.36684 -211.893341) (xy 346.32053 -211.869745) (xy 346.278482 -211.839195) (xy 346.241731 -211.802444)
			(xy 346.211181 -211.760396) (xy 346.187585 -211.714086) (xy 346.171524 -211.664656) (xy 346.163394 -211.613321)
			(xy 345.223844 -211.613321) (xy 345.215714 -211.664656) (xy 345.199653 -211.714086) (xy 345.176057 -211.760396)
			(xy 345.145507 -211.802444) (xy 345.108756 -211.839195) (xy 345.066708 -211.869745) (xy 345.020398 -211.893341)
			(xy 344.970968 -211.909402) (xy 344.919633 -211.917532) (xy 344.867659 -211.917532) (xy 344.816324 -211.909402)
			(xy 344.766894 -211.893341) (xy 344.720584 -211.869745) (xy 344.678536 -211.839195) (xy 344.641785 -211.802444)
			(xy 344.611235 -211.760396) (xy 344.587639 -211.714086) (xy 344.571578 -211.664656) (xy 344.563448 -211.613321)
			(xy 342.024206 -211.613321) (xy 342.016076 -211.664656) (xy 342.000015 -211.714086) (xy 341.976419 -211.760396)
			(xy 341.945869 -211.802444) (xy 341.909118 -211.839195) (xy 341.86707 -211.869745) (xy 341.82076 -211.893341)
			(xy 341.77133 -211.909402) (xy 341.719995 -211.917532) (xy 341.668021 -211.917532) (xy 341.616686 -211.909402)
			(xy 341.567256 -211.893341) (xy 341.520946 -211.869745) (xy 341.478898 -211.839195) (xy 341.442147 -211.802444)
			(xy 341.411597 -211.760396) (xy 341.388001 -211.714086) (xy 341.37194 -211.664656) (xy 341.36381 -211.613321)
			(xy 339.62416 -211.613321) (xy 339.61603 -211.664656) (xy 339.599969 -211.714086) (xy 339.576373 -211.760396)
			(xy 339.545823 -211.802444) (xy 339.509072 -211.839195) (xy 339.467024 -211.869745) (xy 339.420714 -211.893341)
			(xy 339.371284 -211.909402) (xy 339.319949 -211.917532) (xy 339.267975 -211.917532) (xy 339.21664 -211.909402)
			(xy 339.16721 -211.893341) (xy 339.1209 -211.869745) (xy 339.078852 -211.839195) (xy 339.042101 -211.802444)
			(xy 339.011551 -211.760396) (xy 338.987955 -211.714086) (xy 338.971894 -211.664656) (xy 338.963764 -211.613321)
			(xy 338.024214 -211.613321) (xy 338.016084 -211.664656) (xy 338.000023 -211.714086) (xy 337.976427 -211.760396)
			(xy 337.945877 -211.802444) (xy 337.909126 -211.839195) (xy 337.867078 -211.869745) (xy 337.820768 -211.893341)
			(xy 337.771338 -211.909402) (xy 337.720003 -211.917532) (xy 337.668029 -211.917532) (xy 337.616694 -211.909402)
			(xy 337.567264 -211.893341) (xy 337.520954 -211.869745) (xy 337.478906 -211.839195) (xy 337.442155 -211.802444)
			(xy 337.411605 -211.760396) (xy 337.388009 -211.714086) (xy 337.371948 -211.664656) (xy 337.363818 -211.613321)
			(xy 336.424268 -211.613321) (xy 336.416138 -211.664656) (xy 336.400077 -211.714086) (xy 336.376481 -211.760396)
			(xy 336.345931 -211.802444) (xy 336.30918 -211.839195) (xy 336.267132 -211.869745) (xy 336.220822 -211.893341)
			(xy 336.171392 -211.909402) (xy 336.120057 -211.917532) (xy 336.068083 -211.917532) (xy 336.016748 -211.909402)
			(xy 335.967318 -211.893341) (xy 335.921008 -211.869745) (xy 335.87896 -211.839195) (xy 335.842209 -211.802444)
			(xy 335.811659 -211.760396) (xy 335.788063 -211.714086) (xy 335.772002 -211.664656) (xy 335.763872 -211.613321)
			(xy 334.824322 -211.613321) (xy 334.816192 -211.664656) (xy 334.800131 -211.714086) (xy 334.776535 -211.760396)
			(xy 334.745985 -211.802444) (xy 334.709234 -211.839195) (xy 334.667186 -211.869745) (xy 334.620876 -211.893341)
			(xy 334.571446 -211.909402) (xy 334.520111 -211.917532) (xy 334.468137 -211.917532) (xy 334.416802 -211.909402)
			(xy 334.367372 -211.893341) (xy 334.321062 -211.869745) (xy 334.279014 -211.839195) (xy 334.242263 -211.802444)
			(xy 334.211713 -211.760396) (xy 334.188117 -211.714086) (xy 334.172056 -211.664656) (xy 334.163926 -211.613321)
			(xy 334.024222 -211.613321) (xy 334.016092 -211.664656) (xy 334.000031 -211.714086) (xy 333.976435 -211.760396)
			(xy 333.945885 -211.802444) (xy 333.909134 -211.839195) (xy 333.867086 -211.869745) (xy 333.820776 -211.893341)
			(xy 333.771346 -211.909402) (xy 333.720011 -211.917532) (xy 333.668037 -211.917532) (xy 333.616702 -211.909402)
			(xy 333.567272 -211.893341) (xy 333.520962 -211.869745) (xy 333.478914 -211.839195) (xy 333.442163 -211.802444)
			(xy 333.411613 -211.760396) (xy 333.388017 -211.714086) (xy 333.371956 -211.664656) (xy 333.363826 -211.613321)
			(xy 332.271116 -211.613321) (xy 332.271116 -211.88172) (xy 332.271878 -211.890864) (xy 332.273656 -211.900262)
			(xy 332.276196 -211.909406) (xy 332.279244 -211.917026) (xy 332.347824 -211.975192) (xy 332.356569 -211.981888)
			(xy 332.377765 -211.987797) (xy 332.388718 -211.986622) (xy 332.389226 -211.986622) (xy 332.404237 -211.984366)
			(xy 332.434499 -211.98195) (xy 332.449678 -211.981796) (xy 332.451456 -211.981796) (xy 332.478625 -211.982401)
			(xy 332.532383 -211.99036) (xy 332.584467 -212.005867) (xy 332.633823 -212.028607) (xy 332.679454 -212.058122)
			(xy 332.720434 -212.093812) (xy 332.755935 -212.134957) (xy 332.785239 -212.180723) (xy 332.807751 -212.230184)
			(xy 332.823017 -212.282339) (xy 332.830728 -212.336132) (xy 332.831186 -212.363304) (xy 332.830744 -212.389648)
			(xy 332.827479 -212.413167) (xy 333.363826 -212.413167) (xy 333.363826 -212.361193) (xy 333.371956 -212.309858)
			(xy 333.388017 -212.260428) (xy 333.411613 -212.214118) (xy 333.442163 -212.17207) (xy 333.478914 -212.135319)
			(xy 333.520962 -212.104769) (xy 333.567272 -212.081173) (xy 333.616702 -212.065112) (xy 333.668037 -212.056982)
			(xy 333.720011 -212.056982) (xy 333.771346 -212.065112) (xy 333.820776 -212.081173) (xy 333.867086 -212.104769)
			(xy 333.909134 -212.135319) (xy 333.945885 -212.17207) (xy 333.976435 -212.214118) (xy 334.000031 -212.260428)
			(xy 334.016092 -212.309858) (xy 334.024222 -212.361193) (xy 334.024732 -212.38718) (xy 334.024222 -212.413167)
			(xy 334.163926 -212.413167) (xy 334.163926 -212.361193) (xy 334.172056 -212.309858) (xy 334.188117 -212.260428)
			(xy 334.211713 -212.214118) (xy 334.242263 -212.17207) (xy 334.279014 -212.135319) (xy 334.321062 -212.104769)
			(xy 334.367372 -212.081173) (xy 334.416802 -212.065112) (xy 334.468137 -212.056982) (xy 334.520111 -212.056982)
			(xy 334.571446 -212.065112) (xy 334.620876 -212.081173) (xy 334.667186 -212.104769) (xy 334.709234 -212.135319)
			(xy 334.745985 -212.17207) (xy 334.776535 -212.214118) (xy 334.800131 -212.260428) (xy 334.816192 -212.309858)
			(xy 334.824322 -212.361193) (xy 334.824832 -212.38718) (xy 334.824322 -212.413167) (xy 334.963772 -212.413167)
			(xy 334.963772 -212.361193) (xy 334.971902 -212.309858) (xy 334.987963 -212.260428) (xy 335.011559 -212.214118)
			(xy 335.042109 -212.17207) (xy 335.07886 -212.135319) (xy 335.120908 -212.104769) (xy 335.167218 -212.081173)
			(xy 335.216648 -212.065112) (xy 335.267983 -212.056982) (xy 335.319957 -212.056982) (xy 335.371292 -212.065112)
			(xy 335.420722 -212.081173) (xy 335.467032 -212.104769) (xy 335.50908 -212.135319) (xy 335.545831 -212.17207)
			(xy 335.576381 -212.214118) (xy 335.599977 -212.260428) (xy 335.616038 -212.309858) (xy 335.624168 -212.361193)
			(xy 335.624678 -212.38718) (xy 335.624168 -212.413167) (xy 335.763872 -212.413167) (xy 335.763872 -212.361193)
			(xy 335.772002 -212.309858) (xy 335.788063 -212.260428) (xy 335.811659 -212.214118) (xy 335.842209 -212.17207)
			(xy 335.87896 -212.135319) (xy 335.921008 -212.104769) (xy 335.967318 -212.081173) (xy 336.016748 -212.065112)
			(xy 336.068083 -212.056982) (xy 336.120057 -212.056982) (xy 336.171392 -212.065112) (xy 336.220822 -212.081173)
			(xy 336.267132 -212.104769) (xy 336.30918 -212.135319) (xy 336.345931 -212.17207) (xy 336.376481 -212.214118)
			(xy 336.400077 -212.260428) (xy 336.416138 -212.309858) (xy 336.424268 -212.361193) (xy 336.424778 -212.38718)
			(xy 336.424268 -212.413167) (xy 336.563972 -212.413167) (xy 336.563972 -212.361193) (xy 336.572102 -212.309858)
			(xy 336.588163 -212.260428) (xy 336.611759 -212.214118) (xy 336.642309 -212.17207) (xy 336.67906 -212.135319)
			(xy 336.721108 -212.104769) (xy 336.767418 -212.081173) (xy 336.816848 -212.065112) (xy 336.868183 -212.056982)
			(xy 336.920157 -212.056982) (xy 336.971492 -212.065112) (xy 337.020922 -212.081173) (xy 337.067232 -212.104769)
			(xy 337.10928 -212.135319) (xy 337.146031 -212.17207) (xy 337.176581 -212.214118) (xy 337.200177 -212.260428)
			(xy 337.216238 -212.309858) (xy 337.224368 -212.361193) (xy 337.224878 -212.38718) (xy 337.224368 -212.413167)
			(xy 337.363818 -212.413167) (xy 337.363818 -212.361193) (xy 337.371948 -212.309858) (xy 337.388009 -212.260428)
			(xy 337.411605 -212.214118) (xy 337.442155 -212.17207) (xy 337.478906 -212.135319) (xy 337.520954 -212.104769)
			(xy 337.567264 -212.081173) (xy 337.616694 -212.065112) (xy 337.668029 -212.056982) (xy 337.720003 -212.056982)
			(xy 337.771338 -212.065112) (xy 337.820768 -212.081173) (xy 337.867078 -212.104769) (xy 337.909126 -212.135319)
			(xy 337.945877 -212.17207) (xy 337.976427 -212.214118) (xy 338.000023 -212.260428) (xy 338.016084 -212.309858)
			(xy 338.024214 -212.361193) (xy 338.024724 -212.38718) (xy 338.024214 -212.413167) (xy 338.163918 -212.413167)
			(xy 338.163918 -212.361193) (xy 338.172048 -212.309858) (xy 338.188109 -212.260428) (xy 338.211705 -212.214118)
			(xy 338.242255 -212.17207) (xy 338.279006 -212.135319) (xy 338.321054 -212.104769) (xy 338.367364 -212.081173)
			(xy 338.416794 -212.065112) (xy 338.468129 -212.056982) (xy 338.520103 -212.056982) (xy 338.571438 -212.065112)
			(xy 338.620868 -212.081173) (xy 338.667178 -212.104769) (xy 338.709226 -212.135319) (xy 338.745977 -212.17207)
			(xy 338.776527 -212.214118) (xy 338.800123 -212.260428) (xy 338.816184 -212.309858) (xy 338.824314 -212.361193)
			(xy 338.824824 -212.38718) (xy 338.824314 -212.413167) (xy 338.963764 -212.413167) (xy 338.963764 -212.361193)
			(xy 338.971894 -212.309858) (xy 338.987955 -212.260428) (xy 339.011551 -212.214118) (xy 339.042101 -212.17207)
			(xy 339.078852 -212.135319) (xy 339.1209 -212.104769) (xy 339.16721 -212.081173) (xy 339.21664 -212.065112)
			(xy 339.267975 -212.056982) (xy 339.319949 -212.056982) (xy 339.371284 -212.065112) (xy 339.420714 -212.081173)
			(xy 339.467024 -212.104769) (xy 339.509072 -212.135319) (xy 339.545823 -212.17207) (xy 339.576373 -212.214118)
			(xy 339.599969 -212.260428) (xy 339.61603 -212.309858) (xy 339.62416 -212.361193) (xy 339.62467 -212.38718)
			(xy 339.62416 -212.413167) (xy 339.763864 -212.413167) (xy 339.763864 -212.361193) (xy 339.771994 -212.309858)
			(xy 339.788055 -212.260428) (xy 339.811651 -212.214118) (xy 339.842201 -212.17207) (xy 339.878952 -212.135319)
			(xy 339.921 -212.104769) (xy 339.96731 -212.081173) (xy 340.01674 -212.065112) (xy 340.068075 -212.056982)
			(xy 340.120049 -212.056982) (xy 340.171384 -212.065112) (xy 340.220814 -212.081173) (xy 340.267124 -212.104769)
			(xy 340.309172 -212.135319) (xy 340.345923 -212.17207) (xy 340.376473 -212.214118) (xy 340.400069 -212.260428)
			(xy 340.41613 -212.309858) (xy 340.42426 -212.361193) (xy 340.42477 -212.38718) (xy 340.42426 -212.413167)
			(xy 340.563964 -212.413167) (xy 340.563964 -212.361193) (xy 340.572094 -212.309858) (xy 340.588155 -212.260428)
			(xy 340.611751 -212.214118) (xy 340.642301 -212.17207) (xy 340.679052 -212.135319) (xy 340.7211 -212.104769)
			(xy 340.76741 -212.081173) (xy 340.81684 -212.065112) (xy 340.868175 -212.056982) (xy 340.920149 -212.056982)
			(xy 340.971484 -212.065112) (xy 341.020914 -212.081173) (xy 341.067224 -212.104769) (xy 341.109272 -212.135319)
			(xy 341.146023 -212.17207) (xy 341.176573 -212.214118) (xy 341.200169 -212.260428) (xy 341.21623 -212.309858)
			(xy 341.22436 -212.361193) (xy 341.22487 -212.38718) (xy 341.22436 -212.413167) (xy 341.36381 -212.413167)
			(xy 341.36381 -212.361193) (xy 341.37194 -212.309858) (xy 341.388001 -212.260428) (xy 341.411597 -212.214118)
			(xy 341.442147 -212.17207) (xy 341.478898 -212.135319) (xy 341.520946 -212.104769) (xy 341.567256 -212.081173)
			(xy 341.616686 -212.065112) (xy 341.668021 -212.056982) (xy 341.719995 -212.056982) (xy 341.77133 -212.065112)
			(xy 341.82076 -212.081173) (xy 341.86707 -212.104769) (xy 341.909118 -212.135319) (xy 341.945869 -212.17207)
			(xy 341.976419 -212.214118) (xy 342.000015 -212.260428) (xy 342.016076 -212.309858) (xy 342.024206 -212.361193)
			(xy 342.024716 -212.38718) (xy 342.024206 -212.413167) (xy 342.963502 -212.413167) (xy 342.963502 -212.361193)
			(xy 342.971632 -212.309858) (xy 342.987693 -212.260428) (xy 343.011289 -212.214118) (xy 343.041839 -212.17207)
			(xy 343.07859 -212.135319) (xy 343.120638 -212.104769) (xy 343.166948 -212.081173) (xy 343.216378 -212.065112)
			(xy 343.267713 -212.056982) (xy 343.319687 -212.056982) (xy 343.371022 -212.065112) (xy 343.420452 -212.081173)
			(xy 343.466762 -212.104769) (xy 343.50881 -212.135319) (xy 343.545561 -212.17207) (xy 343.576111 -212.214118)
			(xy 343.599707 -212.260428) (xy 343.615768 -212.309858) (xy 343.623898 -212.361193) (xy 343.624408 -212.38718)
			(xy 343.623898 -212.413167) (xy 343.763348 -212.413167) (xy 343.763348 -212.361193) (xy 343.771478 -212.309858)
			(xy 343.787539 -212.260428) (xy 343.811135 -212.214118) (xy 343.841685 -212.17207) (xy 343.878436 -212.135319)
			(xy 343.920484 -212.104769) (xy 343.966794 -212.081173) (xy 344.016224 -212.065112) (xy 344.067559 -212.056982)
			(xy 344.119533 -212.056982) (xy 344.170868 -212.065112) (xy 344.220298 -212.081173) (xy 344.266608 -212.104769)
			(xy 344.308656 -212.135319) (xy 344.345407 -212.17207) (xy 344.375957 -212.214118) (xy 344.399553 -212.260428)
			(xy 344.415614 -212.309858) (xy 344.423744 -212.361193) (xy 344.424254 -212.38718) (xy 344.423744 -212.413167)
			(xy 344.563448 -212.413167) (xy 344.563448 -212.361193) (xy 344.571578 -212.309858) (xy 344.587639 -212.260428)
			(xy 344.611235 -212.214118) (xy 344.641785 -212.17207) (xy 344.678536 -212.135319) (xy 344.720584 -212.104769)
			(xy 344.766894 -212.081173) (xy 344.816324 -212.065112) (xy 344.867659 -212.056982) (xy 344.919633 -212.056982)
			(xy 344.970968 -212.065112) (xy 345.020398 -212.081173) (xy 345.066708 -212.104769) (xy 345.108756 -212.135319)
			(xy 345.145507 -212.17207) (xy 345.176057 -212.214118) (xy 345.199653 -212.260428) (xy 345.215714 -212.309858)
			(xy 345.223844 -212.361193) (xy 345.224354 -212.38718) (xy 345.223844 -212.413167) (xy 345.363548 -212.413167)
			(xy 345.363548 -212.361193) (xy 345.371678 -212.309858) (xy 345.387739 -212.260428) (xy 345.411335 -212.214118)
			(xy 345.441885 -212.17207) (xy 345.478636 -212.135319) (xy 345.520684 -212.104769) (xy 345.566994 -212.081173)
			(xy 345.616424 -212.065112) (xy 345.667759 -212.056982) (xy 345.719733 -212.056982) (xy 345.771068 -212.065112)
			(xy 345.820498 -212.081173) (xy 345.866808 -212.104769) (xy 345.908856 -212.135319) (xy 345.945607 -212.17207)
			(xy 345.976157 -212.214118) (xy 345.999753 -212.260428) (xy 346.015814 -212.309858) (xy 346.023944 -212.361193)
			(xy 346.024454 -212.38718) (xy 346.023944 -212.413167) (xy 346.163394 -212.413167) (xy 346.163394 -212.361193)
			(xy 346.171524 -212.309858) (xy 346.187585 -212.260428) (xy 346.211181 -212.214118) (xy 346.241731 -212.17207)
			(xy 346.278482 -212.135319) (xy 346.32053 -212.104769) (xy 346.36684 -212.081173) (xy 346.41627 -212.065112)
			(xy 346.467605 -212.056982) (xy 346.519579 -212.056982) (xy 346.570914 -212.065112) (xy 346.620344 -212.081173)
			(xy 346.666654 -212.104769) (xy 346.708702 -212.135319) (xy 346.745453 -212.17207) (xy 346.776003 -212.214118)
			(xy 346.799599 -212.260428) (xy 346.81566 -212.309858) (xy 346.82379 -212.361193) (xy 346.8243 -212.38718)
			(xy 346.82379 -212.413167) (xy 346.963494 -212.413167) (xy 346.963494 -212.361193) (xy 346.971624 -212.309858)
			(xy 346.987685 -212.260428) (xy 347.011281 -212.214118) (xy 347.041831 -212.17207) (xy 347.078582 -212.135319)
			(xy 347.12063 -212.104769) (xy 347.16694 -212.081173) (xy 347.21637 -212.065112) (xy 347.267705 -212.056982)
			(xy 347.319679 -212.056982) (xy 347.371014 -212.065112) (xy 347.420444 -212.081173) (xy 347.466754 -212.104769)
			(xy 347.508802 -212.135319) (xy 347.545553 -212.17207) (xy 347.576103 -212.214118) (xy 347.599699 -212.260428)
			(xy 347.61576 -212.309858) (xy 347.62389 -212.361193) (xy 347.6244 -212.38718) (xy 347.62389 -212.413167)
			(xy 347.76334 -212.413167) (xy 347.76334 -212.361193) (xy 347.77147 -212.309858) (xy 347.787531 -212.260428)
			(xy 347.811127 -212.214118) (xy 347.841677 -212.17207) (xy 347.878428 -212.135319) (xy 347.920476 -212.104769)
			(xy 347.966786 -212.081173) (xy 348.016216 -212.065112) (xy 348.067551 -212.056982) (xy 348.119525 -212.056982)
			(xy 348.17086 -212.065112) (xy 348.22029 -212.081173) (xy 348.2666 -212.104769) (xy 348.308648 -212.135319)
			(xy 348.345399 -212.17207) (xy 348.375949 -212.214118) (xy 348.399545 -212.260428) (xy 348.415606 -212.309858)
			(xy 348.423736 -212.361193) (xy 348.424246 -212.38718) (xy 348.423736 -212.413167) (xy 348.56344 -212.413167)
			(xy 348.56344 -212.361193) (xy 348.57157 -212.309858) (xy 348.587631 -212.260428) (xy 348.611227 -212.214118)
			(xy 348.641777 -212.17207) (xy 348.678528 -212.135319) (xy 348.720576 -212.104769) (xy 348.766886 -212.081173)
			(xy 348.816316 -212.065112) (xy 348.867651 -212.056982) (xy 348.919625 -212.056982) (xy 348.97096 -212.065112)
			(xy 349.02039 -212.081173) (xy 349.0667 -212.104769) (xy 349.108748 -212.135319) (xy 349.145499 -212.17207)
			(xy 349.176049 -212.214118) (xy 349.199645 -212.260428) (xy 349.215706 -212.309858) (xy 349.223836 -212.361193)
			(xy 349.224346 -212.38718) (xy 349.223836 -212.413167) (xy 349.36354 -212.413167) (xy 349.36354 -212.361193)
			(xy 349.37167 -212.309858) (xy 349.387731 -212.260428) (xy 349.411327 -212.214118) (xy 349.441877 -212.17207)
			(xy 349.478628 -212.135319) (xy 349.520676 -212.104769) (xy 349.566986 -212.081173) (xy 349.616416 -212.065112)
			(xy 349.667751 -212.056982) (xy 349.719725 -212.056982) (xy 349.77106 -212.065112) (xy 349.82049 -212.081173)
			(xy 349.8668 -212.104769) (xy 349.908848 -212.135319) (xy 349.945599 -212.17207) (xy 349.976149 -212.214118)
			(xy 349.999745 -212.260428) (xy 350.015806 -212.309858) (xy 350.023936 -212.361193) (xy 350.024446 -212.38718)
			(xy 350.023936 -212.413167) (xy 350.015806 -212.464502) (xy 349.999745 -212.513932) (xy 349.976149 -212.560242)
			(xy 349.945599 -212.60229) (xy 349.908848 -212.639041) (xy 349.8668 -212.669591) (xy 349.82049 -212.693187)
			(xy 349.77106 -212.709248) (xy 349.719725 -212.717378) (xy 349.667751 -212.717378) (xy 349.616416 -212.709248)
			(xy 349.566986 -212.693187) (xy 349.520676 -212.669591) (xy 349.478628 -212.639041) (xy 349.441877 -212.60229)
			(xy 349.411327 -212.560242) (xy 349.387731 -212.513932) (xy 349.37167 -212.464502) (xy 349.36354 -212.413167)
			(xy 349.223836 -212.413167) (xy 349.215706 -212.464502) (xy 349.199645 -212.513932) (xy 349.176049 -212.560242)
			(xy 349.145499 -212.60229) (xy 349.108748 -212.639041) (xy 349.0667 -212.669591) (xy 349.02039 -212.693187)
			(xy 348.97096 -212.709248) (xy 348.919625 -212.717378) (xy 348.867651 -212.717378) (xy 348.816316 -212.709248)
			(xy 348.766886 -212.693187) (xy 348.720576 -212.669591) (xy 348.678528 -212.639041) (xy 348.641777 -212.60229)
			(xy 348.611227 -212.560242) (xy 348.587631 -212.513932) (xy 348.57157 -212.464502) (xy 348.56344 -212.413167)
			(xy 348.423736 -212.413167) (xy 348.415606 -212.464502) (xy 348.399545 -212.513932) (xy 348.375949 -212.560242)
			(xy 348.345399 -212.60229) (xy 348.308648 -212.639041) (xy 348.2666 -212.669591) (xy 348.22029 -212.693187)
			(xy 348.17086 -212.709248) (xy 348.119525 -212.717378) (xy 348.067551 -212.717378) (xy 348.016216 -212.709248)
			(xy 347.966786 -212.693187) (xy 347.920476 -212.669591) (xy 347.878428 -212.639041) (xy 347.841677 -212.60229)
			(xy 347.811127 -212.560242) (xy 347.787531 -212.513932) (xy 347.77147 -212.464502) (xy 347.76334 -212.413167)
			(xy 347.62389 -212.413167) (xy 347.61576 -212.464502) (xy 347.599699 -212.513932) (xy 347.576103 -212.560242)
			(xy 347.545553 -212.60229) (xy 347.508802 -212.639041) (xy 347.466754 -212.669591) (xy 347.420444 -212.693187)
			(xy 347.371014 -212.709248) (xy 347.319679 -212.717378) (xy 347.267705 -212.717378) (xy 347.21637 -212.709248)
			(xy 347.16694 -212.693187) (xy 347.12063 -212.669591) (xy 347.078582 -212.639041) (xy 347.041831 -212.60229)
			(xy 347.011281 -212.560242) (xy 346.987685 -212.513932) (xy 346.971624 -212.464502) (xy 346.963494 -212.413167)
			(xy 346.82379 -212.413167) (xy 346.81566 -212.464502) (xy 346.799599 -212.513932) (xy 346.776003 -212.560242)
			(xy 346.745453 -212.60229) (xy 346.708702 -212.639041) (xy 346.666654 -212.669591) (xy 346.620344 -212.693187)
			(xy 346.570914 -212.709248) (xy 346.519579 -212.717378) (xy 346.467605 -212.717378) (xy 346.41627 -212.709248)
			(xy 346.36684 -212.693187) (xy 346.32053 -212.669591) (xy 346.278482 -212.639041) (xy 346.241731 -212.60229)
			(xy 346.211181 -212.560242) (xy 346.187585 -212.513932) (xy 346.171524 -212.464502) (xy 346.163394 -212.413167)
			(xy 346.023944 -212.413167) (xy 346.015814 -212.464502) (xy 345.999753 -212.513932) (xy 345.976157 -212.560242)
			(xy 345.945607 -212.60229) (xy 345.908856 -212.639041) (xy 345.866808 -212.669591) (xy 345.820498 -212.693187)
			(xy 345.771068 -212.709248) (xy 345.719733 -212.717378) (xy 345.667759 -212.717378) (xy 345.616424 -212.709248)
			(xy 345.566994 -212.693187) (xy 345.520684 -212.669591) (xy 345.478636 -212.639041) (xy 345.441885 -212.60229)
			(xy 345.411335 -212.560242) (xy 345.387739 -212.513932) (xy 345.371678 -212.464502) (xy 345.363548 -212.413167)
			(xy 345.223844 -212.413167) (xy 345.215714 -212.464502) (xy 345.199653 -212.513932) (xy 345.176057 -212.560242)
			(xy 345.145507 -212.60229) (xy 345.108756 -212.639041) (xy 345.066708 -212.669591) (xy 345.020398 -212.693187)
			(xy 344.970968 -212.709248) (xy 344.919633 -212.717378) (xy 344.867659 -212.717378) (xy 344.816324 -212.709248)
			(xy 344.766894 -212.693187) (xy 344.720584 -212.669591) (xy 344.678536 -212.639041) (xy 344.641785 -212.60229)
			(xy 344.611235 -212.560242) (xy 344.587639 -212.513932) (xy 344.571578 -212.464502) (xy 344.563448 -212.413167)
			(xy 344.423744 -212.413167) (xy 344.415614 -212.464502) (xy 344.399553 -212.513932) (xy 344.375957 -212.560242)
			(xy 344.345407 -212.60229) (xy 344.308656 -212.639041) (xy 344.266608 -212.669591) (xy 344.220298 -212.693187)
			(xy 344.170868 -212.709248) (xy 344.119533 -212.717378) (xy 344.067559 -212.717378) (xy 344.016224 -212.709248)
			(xy 343.966794 -212.693187) (xy 343.920484 -212.669591) (xy 343.878436 -212.639041) (xy 343.841685 -212.60229)
			(xy 343.811135 -212.560242) (xy 343.787539 -212.513932) (xy 343.771478 -212.464502) (xy 343.763348 -212.413167)
			(xy 343.623898 -212.413167) (xy 343.615768 -212.464502) (xy 343.599707 -212.513932) (xy 343.576111 -212.560242)
			(xy 343.545561 -212.60229) (xy 343.50881 -212.639041) (xy 343.466762 -212.669591) (xy 343.420452 -212.693187)
			(xy 343.371022 -212.709248) (xy 343.319687 -212.717378) (xy 343.267713 -212.717378) (xy 343.216378 -212.709248)
			(xy 343.166948 -212.693187) (xy 343.120638 -212.669591) (xy 343.07859 -212.639041) (xy 343.041839 -212.60229)
			(xy 343.011289 -212.560242) (xy 342.987693 -212.513932) (xy 342.971632 -212.464502) (xy 342.963502 -212.413167)
			(xy 342.024206 -212.413167) (xy 342.016076 -212.464502) (xy 342.000015 -212.513932) (xy 341.976419 -212.560242)
			(xy 341.945869 -212.60229) (xy 341.909118 -212.639041) (xy 341.86707 -212.669591) (xy 341.82076 -212.693187)
			(xy 341.77133 -212.709248) (xy 341.719995 -212.717378) (xy 341.668021 -212.717378) (xy 341.616686 -212.709248)
			(xy 341.567256 -212.693187) (xy 341.520946 -212.669591) (xy 341.478898 -212.639041) (xy 341.442147 -212.60229)
			(xy 341.411597 -212.560242) (xy 341.388001 -212.513932) (xy 341.37194 -212.464502) (xy 341.36381 -212.413167)
			(xy 341.22436 -212.413167) (xy 341.21623 -212.464502) (xy 341.200169 -212.513932) (xy 341.176573 -212.560242)
			(xy 341.146023 -212.60229) (xy 341.109272 -212.639041) (xy 341.067224 -212.669591) (xy 341.020914 -212.693187)
			(xy 340.971484 -212.709248) (xy 340.920149 -212.717378) (xy 340.868175 -212.717378) (xy 340.81684 -212.709248)
			(xy 340.76741 -212.693187) (xy 340.7211 -212.669591) (xy 340.679052 -212.639041) (xy 340.642301 -212.60229)
			(xy 340.611751 -212.560242) (xy 340.588155 -212.513932) (xy 340.572094 -212.464502) (xy 340.563964 -212.413167)
			(xy 340.42426 -212.413167) (xy 340.41613 -212.464502) (xy 340.400069 -212.513932) (xy 340.376473 -212.560242)
			(xy 340.345923 -212.60229) (xy 340.309172 -212.639041) (xy 340.267124 -212.669591) (xy 340.220814 -212.693187)
			(xy 340.171384 -212.709248) (xy 340.120049 -212.717378) (xy 340.068075 -212.717378) (xy 340.01674 -212.709248)
			(xy 339.96731 -212.693187) (xy 339.921 -212.669591) (xy 339.878952 -212.639041) (xy 339.842201 -212.60229)
			(xy 339.811651 -212.560242) (xy 339.788055 -212.513932) (xy 339.771994 -212.464502) (xy 339.763864 -212.413167)
			(xy 339.62416 -212.413167) (xy 339.61603 -212.464502) (xy 339.599969 -212.513932) (xy 339.576373 -212.560242)
			(xy 339.545823 -212.60229) (xy 339.509072 -212.639041) (xy 339.467024 -212.669591) (xy 339.420714 -212.693187)
			(xy 339.371284 -212.709248) (xy 339.319949 -212.717378) (xy 339.267975 -212.717378) (xy 339.21664 -212.709248)
			(xy 339.16721 -212.693187) (xy 339.1209 -212.669591) (xy 339.078852 -212.639041) (xy 339.042101 -212.60229)
			(xy 339.011551 -212.560242) (xy 338.987955 -212.513932) (xy 338.971894 -212.464502) (xy 338.963764 -212.413167)
			(xy 338.824314 -212.413167) (xy 338.816184 -212.464502) (xy 338.800123 -212.513932) (xy 338.776527 -212.560242)
			(xy 338.745977 -212.60229) (xy 338.709226 -212.639041) (xy 338.667178 -212.669591) (xy 338.620868 -212.693187)
			(xy 338.571438 -212.709248) (xy 338.520103 -212.717378) (xy 338.468129 -212.717378) (xy 338.416794 -212.709248)
			(xy 338.367364 -212.693187) (xy 338.321054 -212.669591) (xy 338.279006 -212.639041) (xy 338.242255 -212.60229)
			(xy 338.211705 -212.560242) (xy 338.188109 -212.513932) (xy 338.172048 -212.464502) (xy 338.163918 -212.413167)
			(xy 338.024214 -212.413167) (xy 338.016084 -212.464502) (xy 338.000023 -212.513932) (xy 337.976427 -212.560242)
			(xy 337.945877 -212.60229) (xy 337.909126 -212.639041) (xy 337.867078 -212.669591) (xy 337.820768 -212.693187)
			(xy 337.771338 -212.709248) (xy 337.720003 -212.717378) (xy 337.668029 -212.717378) (xy 337.616694 -212.709248)
			(xy 337.567264 -212.693187) (xy 337.520954 -212.669591) (xy 337.478906 -212.639041) (xy 337.442155 -212.60229)
			(xy 337.411605 -212.560242) (xy 337.388009 -212.513932) (xy 337.371948 -212.464502) (xy 337.363818 -212.413167)
			(xy 337.224368 -212.413167) (xy 337.216238 -212.464502) (xy 337.200177 -212.513932) (xy 337.176581 -212.560242)
			(xy 337.146031 -212.60229) (xy 337.10928 -212.639041) (xy 337.067232 -212.669591) (xy 337.020922 -212.693187)
			(xy 336.971492 -212.709248) (xy 336.920157 -212.717378) (xy 336.868183 -212.717378) (xy 336.816848 -212.709248)
			(xy 336.767418 -212.693187) (xy 336.721108 -212.669591) (xy 336.67906 -212.639041) (xy 336.642309 -212.60229)
			(xy 336.611759 -212.560242) (xy 336.588163 -212.513932) (xy 336.572102 -212.464502) (xy 336.563972 -212.413167)
			(xy 336.424268 -212.413167) (xy 336.416138 -212.464502) (xy 336.400077 -212.513932) (xy 336.376481 -212.560242)
			(xy 336.345931 -212.60229) (xy 336.30918 -212.639041) (xy 336.267132 -212.669591) (xy 336.220822 -212.693187)
			(xy 336.171392 -212.709248) (xy 336.120057 -212.717378) (xy 336.068083 -212.717378) (xy 336.016748 -212.709248)
			(xy 335.967318 -212.693187) (xy 335.921008 -212.669591) (xy 335.87896 -212.639041) (xy 335.842209 -212.60229)
			(xy 335.811659 -212.560242) (xy 335.788063 -212.513932) (xy 335.772002 -212.464502) (xy 335.763872 -212.413167)
			(xy 335.624168 -212.413167) (xy 335.616038 -212.464502) (xy 335.599977 -212.513932) (xy 335.576381 -212.560242)
			(xy 335.545831 -212.60229) (xy 335.50908 -212.639041) (xy 335.467032 -212.669591) (xy 335.420722 -212.693187)
			(xy 335.371292 -212.709248) (xy 335.319957 -212.717378) (xy 335.267983 -212.717378) (xy 335.216648 -212.709248)
			(xy 335.167218 -212.693187) (xy 335.120908 -212.669591) (xy 335.07886 -212.639041) (xy 335.042109 -212.60229)
			(xy 335.011559 -212.560242) (xy 334.987963 -212.513932) (xy 334.971902 -212.464502) (xy 334.963772 -212.413167)
			(xy 334.824322 -212.413167) (xy 334.816192 -212.464502) (xy 334.800131 -212.513932) (xy 334.776535 -212.560242)
			(xy 334.745985 -212.60229) (xy 334.709234 -212.639041) (xy 334.667186 -212.669591) (xy 334.620876 -212.693187)
			(xy 334.571446 -212.709248) (xy 334.520111 -212.717378) (xy 334.468137 -212.717378) (xy 334.416802 -212.709248)
			(xy 334.367372 -212.693187) (xy 334.321062 -212.669591) (xy 334.279014 -212.639041) (xy 334.242263 -212.60229)
			(xy 334.211713 -212.560242) (xy 334.188117 -212.513932) (xy 334.172056 -212.464502) (xy 334.163926 -212.413167)
			(xy 334.024222 -212.413167) (xy 334.016092 -212.464502) (xy 334.000031 -212.513932) (xy 333.976435 -212.560242)
			(xy 333.945885 -212.60229) (xy 333.909134 -212.639041) (xy 333.867086 -212.669591) (xy 333.820776 -212.693187)
			(xy 333.771346 -212.709248) (xy 333.720011 -212.717378) (xy 333.668037 -212.717378) (xy 333.616702 -212.709248)
			(xy 333.567272 -212.693187) (xy 333.520962 -212.669591) (xy 333.478914 -212.639041) (xy 333.442163 -212.60229)
			(xy 333.411613 -212.560242) (xy 333.388017 -212.513932) (xy 333.371956 -212.464502) (xy 333.363826 -212.413167)
			(xy 332.827479 -212.413167) (xy 332.8235 -212.441837) (xy 332.80915 -212.492533) (xy 332.787967 -212.540776)
			(xy 332.760354 -212.585649) (xy 332.726833 -212.6263) (xy 332.688043 -212.661956) (xy 332.644718 -212.691941)
			(xy 332.621382 -212.704172) (xy 332.620874 -212.704172) (xy 332.620874 -212.704426) (xy 332.615702 -212.707215)
			(xy 332.606722 -212.71479) (xy 332.603094 -212.719412) (xy 332.598522 -212.727032) (xy 332.596839 -212.730542)
			(xy 332.594417 -212.737939) (xy 332.593696 -212.741764) (xy 332.580742 -212.82279) (xy 332.579737 -212.830726)
			(xy 332.582201 -212.846522) (xy 332.585568 -212.853778) (xy 332.587451 -212.857331) (xy 332.592174 -212.863838)
			(xy 332.594966 -212.866732) (xy 332.925166 -213.196932) (xy 332.932011 -213.204331) (xy 332.935724 -213.213267)
			(xy 334.163926 -213.213267) (xy 334.163926 -213.161293) (xy 334.172056 -213.109958) (xy 334.188117 -213.060528)
			(xy 334.211713 -213.014218) (xy 334.242263 -212.97217) (xy 334.279014 -212.935419) (xy 334.321062 -212.904869)
			(xy 334.367372 -212.881273) (xy 334.416802 -212.865212) (xy 334.468137 -212.857082) (xy 334.520111 -212.857082)
			(xy 334.571446 -212.865212) (xy 334.620876 -212.881273) (xy 334.667186 -212.904869) (xy 334.709234 -212.935419)
			(xy 334.745985 -212.97217) (xy 334.776535 -213.014218) (xy 334.800131 -213.060528) (xy 334.816192 -213.109958)
			(xy 334.824322 -213.161293) (xy 334.824832 -213.18728) (xy 334.824322 -213.213267) (xy 334.963772 -213.213267)
			(xy 334.963772 -213.161293) (xy 334.971902 -213.109958) (xy 334.987963 -213.060528) (xy 335.011559 -213.014218)
			(xy 335.042109 -212.97217) (xy 335.07886 -212.935419) (xy 335.120908 -212.904869) (xy 335.167218 -212.881273)
			(xy 335.216648 -212.865212) (xy 335.267983 -212.857082) (xy 335.319957 -212.857082) (xy 335.371292 -212.865212)
			(xy 335.420722 -212.881273) (xy 335.467032 -212.904869) (xy 335.50908 -212.935419) (xy 335.545831 -212.97217)
			(xy 335.576381 -213.014218) (xy 335.599977 -213.060528) (xy 335.616038 -213.109958) (xy 335.624168 -213.161293)
			(xy 335.624678 -213.18728) (xy 335.624173 -213.213013) (xy 335.763618 -213.213013) (xy 335.763618 -213.161039)
			(xy 335.771748 -213.109704) (xy 335.787809 -213.060274) (xy 335.811405 -213.013964) (xy 335.841955 -212.971916)
			(xy 335.878706 -212.935165) (xy 335.920754 -212.904615) (xy 335.967064 -212.881019) (xy 336.016494 -212.864958)
			(xy 336.067829 -212.856828) (xy 336.119803 -212.856828) (xy 336.171138 -212.864958) (xy 336.220568 -212.881019)
			(xy 336.266878 -212.904615) (xy 336.308926 -212.935165) (xy 336.345677 -212.971916) (xy 336.376227 -213.013964)
			(xy 336.399823 -213.060274) (xy 336.415884 -213.109704) (xy 336.424014 -213.161039) (xy 336.424524 -213.187026)
			(xy 336.424014 -213.213013) (xy 336.423974 -213.213267) (xy 336.563972 -213.213267) (xy 336.563972 -213.161293)
			(xy 336.572102 -213.109958) (xy 336.588163 -213.060528) (xy 336.611759 -213.014218) (xy 336.642309 -212.97217)
			(xy 336.67906 -212.935419) (xy 336.721108 -212.904869) (xy 336.767418 -212.881273) (xy 336.816848 -212.865212)
			(xy 336.868183 -212.857082) (xy 336.920157 -212.857082) (xy 336.971492 -212.865212) (xy 337.020922 -212.881273)
			(xy 337.067232 -212.904869) (xy 337.10928 -212.935419) (xy 337.146031 -212.97217) (xy 337.176581 -213.014218)
			(xy 337.200177 -213.060528) (xy 337.216238 -213.109958) (xy 337.224368 -213.161293) (xy 337.224878 -213.18728)
			(xy 337.224368 -213.213267) (xy 337.363818 -213.213267) (xy 337.363818 -213.161293) (xy 337.371948 -213.109958)
			(xy 337.388009 -213.060528) (xy 337.411605 -213.014218) (xy 337.442155 -212.97217) (xy 337.478906 -212.935419)
			(xy 337.520954 -212.904869) (xy 337.567264 -212.881273) (xy 337.616694 -212.865212) (xy 337.668029 -212.857082)
			(xy 337.720003 -212.857082) (xy 337.771338 -212.865212) (xy 337.820768 -212.881273) (xy 337.867078 -212.904869)
			(xy 337.909126 -212.935419) (xy 337.945877 -212.97217) (xy 337.976427 -213.014218) (xy 338.000023 -213.060528)
			(xy 338.016084 -213.109958) (xy 338.024214 -213.161293) (xy 338.024724 -213.18728) (xy 338.024214 -213.213267)
			(xy 338.963764 -213.213267) (xy 338.963764 -213.161293) (xy 338.971894 -213.109958) (xy 338.987955 -213.060528)
			(xy 339.011551 -213.014218) (xy 339.042101 -212.97217) (xy 339.078852 -212.935419) (xy 339.1209 -212.904869)
			(xy 339.16721 -212.881273) (xy 339.21664 -212.865212) (xy 339.267975 -212.857082) (xy 339.319949 -212.857082)
			(xy 339.371284 -212.865212) (xy 339.420714 -212.881273) (xy 339.467024 -212.904869) (xy 339.509072 -212.935419)
			(xy 339.545823 -212.97217) (xy 339.576373 -213.014218) (xy 339.599969 -213.060528) (xy 339.61603 -213.109958)
			(xy 339.62416 -213.161293) (xy 339.62467 -213.18728) (xy 339.624165 -213.213013) (xy 339.76361 -213.213013)
			(xy 339.76361 -213.161039) (xy 339.77174 -213.109704) (xy 339.787801 -213.060274) (xy 339.811397 -213.013964)
			(xy 339.841947 -212.971916) (xy 339.878698 -212.935165) (xy 339.920746 -212.904615) (xy 339.967056 -212.881019)
			(xy 340.016486 -212.864958) (xy 340.067821 -212.856828) (xy 340.119795 -212.856828) (xy 340.17113 -212.864958)
			(xy 340.22056 -212.881019) (xy 340.26687 -212.904615) (xy 340.308918 -212.935165) (xy 340.345669 -212.971916)
			(xy 340.376219 -213.013964) (xy 340.399815 -213.060274) (xy 340.415876 -213.109704) (xy 340.424006 -213.161039)
			(xy 340.424516 -213.187026) (xy 340.424006 -213.213013) (xy 340.423966 -213.213267) (xy 340.563964 -213.213267)
			(xy 340.563964 -213.161293) (xy 340.572094 -213.109958) (xy 340.588155 -213.060528) (xy 340.611751 -213.014218)
			(xy 340.642301 -212.97217) (xy 340.679052 -212.935419) (xy 340.7211 -212.904869) (xy 340.76741 -212.881273)
			(xy 340.81684 -212.865212) (xy 340.868175 -212.857082) (xy 340.920149 -212.857082) (xy 340.971484 -212.865212)
			(xy 341.020914 -212.881273) (xy 341.067224 -212.904869) (xy 341.109272 -212.935419) (xy 341.146023 -212.97217)
			(xy 341.176573 -213.014218) (xy 341.200169 -213.060528) (xy 341.21623 -213.109958) (xy 341.22436 -213.161293)
			(xy 341.22487 -213.18728) (xy 341.22436 -213.213267) (xy 342.963502 -213.213267) (xy 342.963502 -213.161293)
			(xy 342.971632 -213.109958) (xy 342.987693 -213.060528) (xy 343.011289 -213.014218) (xy 343.041839 -212.97217)
			(xy 343.07859 -212.935419) (xy 343.120638 -212.904869) (xy 343.166948 -212.881273) (xy 343.216378 -212.865212)
			(xy 343.267713 -212.857082) (xy 343.319687 -212.857082) (xy 343.371022 -212.865212) (xy 343.420452 -212.881273)
			(xy 343.466762 -212.904869) (xy 343.50881 -212.935419) (xy 343.545561 -212.97217) (xy 343.576111 -213.014218)
			(xy 343.599707 -213.060528) (xy 343.615768 -213.109958) (xy 343.623898 -213.161293) (xy 343.624408 -213.18728)
			(xy 343.623898 -213.213267) (xy 343.763348 -213.213267) (xy 343.763348 -213.161293) (xy 343.771478 -213.109958)
			(xy 343.787539 -213.060528) (xy 343.811135 -213.014218) (xy 343.841685 -212.97217) (xy 343.878436 -212.935419)
			(xy 343.920484 -212.904869) (xy 343.966794 -212.881273) (xy 344.016224 -212.865212) (xy 344.067559 -212.857082)
			(xy 344.119533 -212.857082) (xy 344.170868 -212.865212) (xy 344.220298 -212.881273) (xy 344.266608 -212.904869)
			(xy 344.308656 -212.935419) (xy 344.345407 -212.97217) (xy 344.375957 -213.014218) (xy 344.399553 -213.060528)
			(xy 344.415614 -213.109958) (xy 344.423744 -213.161293) (xy 344.424254 -213.18728) (xy 344.423749 -213.213013)
			(xy 344.563702 -213.213013) (xy 344.563702 -213.161039) (xy 344.571832 -213.109704) (xy 344.587893 -213.060274)
			(xy 344.611489 -213.013964) (xy 344.642039 -212.971916) (xy 344.67879 -212.935165) (xy 344.720838 -212.904615)
			(xy 344.767148 -212.881019) (xy 344.816578 -212.864958) (xy 344.867913 -212.856828) (xy 344.919887 -212.856828)
			(xy 344.971222 -212.864958) (xy 345.020652 -212.881019) (xy 345.066962 -212.904615) (xy 345.10901 -212.935165)
			(xy 345.145761 -212.971916) (xy 345.176311 -213.013964) (xy 345.199907 -213.060274) (xy 345.215968 -213.109704)
			(xy 345.224098 -213.161039) (xy 345.224608 -213.187026) (xy 345.224098 -213.213013) (xy 345.224058 -213.213267)
			(xy 345.363548 -213.213267) (xy 345.363548 -213.161293) (xy 345.371678 -213.109958) (xy 345.387739 -213.060528)
			(xy 345.411335 -213.014218) (xy 345.441885 -212.97217) (xy 345.478636 -212.935419) (xy 345.520684 -212.904869)
			(xy 345.566994 -212.881273) (xy 345.616424 -212.865212) (xy 345.667759 -212.857082) (xy 345.719733 -212.857082)
			(xy 345.771068 -212.865212) (xy 345.820498 -212.881273) (xy 345.866808 -212.904869) (xy 345.908856 -212.935419)
			(xy 345.945607 -212.97217) (xy 345.976157 -213.014218) (xy 345.999753 -213.060528) (xy 346.015814 -213.109958)
			(xy 346.023944 -213.161293) (xy 346.024454 -213.18728) (xy 346.023944 -213.213267) (xy 346.963494 -213.213267)
			(xy 346.963494 -213.161293) (xy 346.971624 -213.109958) (xy 346.987685 -213.060528) (xy 347.011281 -213.014218)
			(xy 347.041831 -212.97217) (xy 347.078582 -212.935419) (xy 347.12063 -212.904869) (xy 347.16694 -212.881273)
			(xy 347.21637 -212.865212) (xy 347.267705 -212.857082) (xy 347.319679 -212.857082) (xy 347.371014 -212.865212)
			(xy 347.420444 -212.881273) (xy 347.466754 -212.904869) (xy 347.508802 -212.935419) (xy 347.545553 -212.97217)
			(xy 347.576103 -213.014218) (xy 347.599699 -213.060528) (xy 347.61576 -213.109958) (xy 347.62389 -213.161293)
			(xy 347.6244 -213.18728) (xy 347.62389 -213.213267) (xy 347.76334 -213.213267) (xy 347.76334 -213.161293)
			(xy 347.77147 -213.109958) (xy 347.787531 -213.060528) (xy 347.811127 -213.014218) (xy 347.841677 -212.97217)
			(xy 347.878428 -212.935419) (xy 347.920476 -212.904869) (xy 347.966786 -212.881273) (xy 348.016216 -212.865212)
			(xy 348.067551 -212.857082) (xy 348.119525 -212.857082) (xy 348.17086 -212.865212) (xy 348.22029 -212.881273)
			(xy 348.2666 -212.904869) (xy 348.308648 -212.935419) (xy 348.345399 -212.97217) (xy 348.375949 -213.014218)
			(xy 348.399545 -213.060528) (xy 348.415606 -213.109958) (xy 348.423736 -213.161293) (xy 348.424246 -213.18728)
			(xy 348.423736 -213.213267) (xy 348.415606 -213.264602) (xy 348.399545 -213.314032) (xy 348.375949 -213.360342)
			(xy 348.345399 -213.40239) (xy 348.308648 -213.439141) (xy 348.2666 -213.469691) (xy 348.22029 -213.493287)
			(xy 348.17086 -213.509348) (xy 348.119525 -213.517478) (xy 348.067551 -213.517478) (xy 348.016216 -213.509348)
			(xy 347.966786 -213.493287) (xy 347.920476 -213.469691) (xy 347.878428 -213.439141) (xy 347.841677 -213.40239)
			(xy 347.811127 -213.360342) (xy 347.787531 -213.314032) (xy 347.77147 -213.264602) (xy 347.76334 -213.213267)
			(xy 347.62389 -213.213267) (xy 347.61576 -213.264602) (xy 347.599699 -213.314032) (xy 347.576103 -213.360342)
			(xy 347.545553 -213.40239) (xy 347.508802 -213.439141) (xy 347.466754 -213.469691) (xy 347.420444 -213.493287)
			(xy 347.371014 -213.509348) (xy 347.319679 -213.517478) (xy 347.267705 -213.517478) (xy 347.21637 -213.509348)
			(xy 347.16694 -213.493287) (xy 347.12063 -213.469691) (xy 347.078582 -213.439141) (xy 347.041831 -213.40239)
			(xy 347.011281 -213.360342) (xy 346.987685 -213.314032) (xy 346.971624 -213.264602) (xy 346.963494 -213.213267)
			(xy 346.023944 -213.213267) (xy 346.015814 -213.264602) (xy 345.999753 -213.314032) (xy 345.976157 -213.360342)
			(xy 345.945607 -213.40239) (xy 345.908856 -213.439141) (xy 345.866808 -213.469691) (xy 345.820498 -213.493287)
			(xy 345.771068 -213.509348) (xy 345.719733 -213.517478) (xy 345.667759 -213.517478) (xy 345.616424 -213.509348)
			(xy 345.566994 -213.493287) (xy 345.520684 -213.469691) (xy 345.478636 -213.439141) (xy 345.441885 -213.40239)
			(xy 345.411335 -213.360342) (xy 345.387739 -213.314032) (xy 345.371678 -213.264602) (xy 345.363548 -213.213267)
			(xy 345.224058 -213.213267) (xy 345.215968 -213.264348) (xy 345.199907 -213.313778) (xy 345.176311 -213.360088)
			(xy 345.145761 -213.402136) (xy 345.10901 -213.438887) (xy 345.066962 -213.469437) (xy 345.020652 -213.493033)
			(xy 344.971222 -213.509094) (xy 344.919887 -213.517224) (xy 344.867913 -213.517224) (xy 344.816578 -213.509094)
			(xy 344.767148 -213.493033) (xy 344.720838 -213.469437) (xy 344.67879 -213.438887) (xy 344.642039 -213.402136)
			(xy 344.611489 -213.360088) (xy 344.587893 -213.313778) (xy 344.571832 -213.264348) (xy 344.563702 -213.213013)
			(xy 344.423749 -213.213013) (xy 344.423744 -213.213267) (xy 344.415614 -213.264602) (xy 344.399553 -213.314032)
			(xy 344.375957 -213.360342) (xy 344.345407 -213.40239) (xy 344.308656 -213.439141) (xy 344.266608 -213.469691)
			(xy 344.220298 -213.493287) (xy 344.170868 -213.509348) (xy 344.119533 -213.517478) (xy 344.067559 -213.517478)
			(xy 344.016224 -213.509348) (xy 343.966794 -213.493287) (xy 343.920484 -213.469691) (xy 343.878436 -213.439141)
			(xy 343.841685 -213.40239) (xy 343.811135 -213.360342) (xy 343.787539 -213.314032) (xy 343.771478 -213.264602)
			(xy 343.763348 -213.213267) (xy 343.623898 -213.213267) (xy 343.615768 -213.264602) (xy 343.599707 -213.314032)
			(xy 343.576111 -213.360342) (xy 343.545561 -213.40239) (xy 343.50881 -213.439141) (xy 343.466762 -213.469691)
			(xy 343.420452 -213.493287) (xy 343.371022 -213.509348) (xy 343.319687 -213.517478) (xy 343.267713 -213.517478)
			(xy 343.216378 -213.509348) (xy 343.166948 -213.493287) (xy 343.120638 -213.469691) (xy 343.07859 -213.439141)
			(xy 343.041839 -213.40239) (xy 343.011289 -213.360342) (xy 342.987693 -213.314032) (xy 342.971632 -213.264602)
			(xy 342.963502 -213.213267) (xy 341.22436 -213.213267) (xy 341.21623 -213.264602) (xy 341.200169 -213.314032)
			(xy 341.176573 -213.360342) (xy 341.146023 -213.40239) (xy 341.109272 -213.439141) (xy 341.067224 -213.469691)
			(xy 341.020914 -213.493287) (xy 340.971484 -213.509348) (xy 340.920149 -213.517478) (xy 340.868175 -213.517478)
			(xy 340.81684 -213.509348) (xy 340.76741 -213.493287) (xy 340.7211 -213.469691) (xy 340.679052 -213.439141)
			(xy 340.642301 -213.40239) (xy 340.611751 -213.360342) (xy 340.588155 -213.314032) (xy 340.572094 -213.264602)
			(xy 340.563964 -213.213267) (xy 340.423966 -213.213267) (xy 340.415876 -213.264348) (xy 340.399815 -213.313778)
			(xy 340.376219 -213.360088) (xy 340.345669 -213.402136) (xy 340.308918 -213.438887) (xy 340.26687 -213.469437)
			(xy 340.22056 -213.493033) (xy 340.17113 -213.509094) (xy 340.119795 -213.517224) (xy 340.067821 -213.517224)
			(xy 340.016486 -213.509094) (xy 339.967056 -213.493033) (xy 339.920746 -213.469437) (xy 339.878698 -213.438887)
			(xy 339.841947 -213.402136) (xy 339.811397 -213.360088) (xy 339.787801 -213.313778) (xy 339.77174 -213.264348)
			(xy 339.76361 -213.213013) (xy 339.624165 -213.213013) (xy 339.62416 -213.213267) (xy 339.61603 -213.264602)
			(xy 339.599969 -213.314032) (xy 339.576373 -213.360342) (xy 339.545823 -213.40239) (xy 339.509072 -213.439141)
			(xy 339.467024 -213.469691) (xy 339.420714 -213.493287) (xy 339.371284 -213.509348) (xy 339.319949 -213.517478)
			(xy 339.267975 -213.517478) (xy 339.21664 -213.509348) (xy 339.16721 -213.493287) (xy 339.1209 -213.469691)
			(xy 339.078852 -213.439141) (xy 339.042101 -213.40239) (xy 339.011551 -213.360342) (xy 338.987955 -213.314032)
			(xy 338.971894 -213.264602) (xy 338.963764 -213.213267) (xy 338.024214 -213.213267) (xy 338.016084 -213.264602)
			(xy 338.000023 -213.314032) (xy 337.976427 -213.360342) (xy 337.945877 -213.40239) (xy 337.909126 -213.439141)
			(xy 337.867078 -213.469691) (xy 337.820768 -213.493287) (xy 337.771338 -213.509348) (xy 337.720003 -213.517478)
			(xy 337.668029 -213.517478) (xy 337.616694 -213.509348) (xy 337.567264 -213.493287) (xy 337.520954 -213.469691)
			(xy 337.478906 -213.439141) (xy 337.442155 -213.40239) (xy 337.411605 -213.360342) (xy 337.388009 -213.314032)
			(xy 337.371948 -213.264602) (xy 337.363818 -213.213267) (xy 337.224368 -213.213267) (xy 337.216238 -213.264602)
			(xy 337.200177 -213.314032) (xy 337.176581 -213.360342) (xy 337.146031 -213.40239) (xy 337.10928 -213.439141)
			(xy 337.067232 -213.469691) (xy 337.020922 -213.493287) (xy 336.971492 -213.509348) (xy 336.920157 -213.517478)
			(xy 336.868183 -213.517478) (xy 336.816848 -213.509348) (xy 336.767418 -213.493287) (xy 336.721108 -213.469691)
			(xy 336.67906 -213.439141) (xy 336.642309 -213.40239) (xy 336.611759 -213.360342) (xy 336.588163 -213.314032)
			(xy 336.572102 -213.264602) (xy 336.563972 -213.213267) (xy 336.423974 -213.213267) (xy 336.415884 -213.264348)
			(xy 336.399823 -213.313778) (xy 336.376227 -213.360088) (xy 336.345677 -213.402136) (xy 336.308926 -213.438887)
			(xy 336.266878 -213.469437) (xy 336.220568 -213.493033) (xy 336.171138 -213.509094) (xy 336.119803 -213.517224)
			(xy 336.067829 -213.517224) (xy 336.016494 -213.509094) (xy 335.967064 -213.493033) (xy 335.920754 -213.469437)
			(xy 335.878706 -213.438887) (xy 335.841955 -213.402136) (xy 335.811405 -213.360088) (xy 335.787809 -213.313778)
			(xy 335.771748 -213.264348) (xy 335.763618 -213.213013) (xy 335.624173 -213.213013) (xy 335.624168 -213.213267)
			(xy 335.616038 -213.264602) (xy 335.599977 -213.314032) (xy 335.576381 -213.360342) (xy 335.545831 -213.40239)
			(xy 335.50908 -213.439141) (xy 335.467032 -213.469691) (xy 335.420722 -213.493287) (xy 335.371292 -213.509348)
			(xy 335.319957 -213.517478) (xy 335.267983 -213.517478) (xy 335.216648 -213.509348) (xy 335.167218 -213.493287)
			(xy 335.120908 -213.469691) (xy 335.07886 -213.439141) (xy 335.042109 -213.40239) (xy 335.011559 -213.360342)
			(xy 334.987963 -213.314032) (xy 334.971902 -213.264602) (xy 334.963772 -213.213267) (xy 334.824322 -213.213267)
			(xy 334.816192 -213.264602) (xy 334.800131 -213.314032) (xy 334.776535 -213.360342) (xy 334.745985 -213.40239)
			(xy 334.709234 -213.439141) (xy 334.667186 -213.469691) (xy 334.620876 -213.493287) (xy 334.571446 -213.509348)
			(xy 334.520111 -213.517478) (xy 334.468137 -213.517478) (xy 334.416802 -213.509348) (xy 334.367372 -213.493287)
			(xy 334.321062 -213.469691) (xy 334.279014 -213.439141) (xy 334.242263 -213.40239) (xy 334.211713 -213.360342)
			(xy 334.188117 -213.314032) (xy 334.172056 -213.264602) (xy 334.163926 -213.213267) (xy 332.935724 -213.213267)
			(xy 332.939739 -213.222929) (xy 332.940152 -213.233) (xy 332.940152 -213.52129) (xy 332.940452 -213.529959)
			(xy 332.946164 -213.546325) (xy 332.951328 -213.553294) (xy 332.953106 -213.555326) (xy 332.97622 -213.578694)
			(xy 332.983332 -213.584536) (xy 332.991206 -213.589108) (xy 332.999588 -213.592918) (xy 333.008986 -213.59368)
			(xy 333.03661 -213.595953) (xy 333.090716 -213.607966) (xy 333.142312 -213.628207) (xy 333.190154 -213.656188)
			(xy 333.233089 -213.691236) (xy 333.270084 -213.732506) (xy 333.285592 -213.755478) (xy 333.288894 -213.760558)
			(xy 333.297022 -213.768432) (xy 333.301848 -213.77148) (xy 333.30691 -213.77431) (xy 333.317935 -213.777897)
			(xy 333.323692 -213.778592) (xy 333.3242 -213.778592) (xy 333.404972 -213.784688) (xy 333.411068 -213.784688)
			(xy 333.415368 -213.784424) (xy 333.423794 -213.782634) (xy 333.427832 -213.781132) (xy 333.433674 -213.778846)
			(xy 333.442818 -213.772242) (xy 333.446882 -213.76767) (xy 333.465876 -213.747184) (xy 333.509478 -213.712268)
			(xy 333.558325 -213.68517) (xy 333.61103 -213.666662) (xy 333.666094 -213.657267) (xy 333.694024 -213.656672)
			(xy 333.718784 -213.657107) (xy 333.767752 -213.664483) (xy 333.815072 -213.679082) (xy 333.859684 -213.700577)
			(xy 333.90059 -213.728487) (xy 333.936875 -213.762187) (xy 333.967726 -213.800922) (xy 333.992454 -213.843827)
			(xy 334.001872 -213.86673) (xy 334.005682 -213.876636) (xy 334.022954 -213.893654) (xy 334.032246 -213.902117)
			(xy 334.056245 -213.909471) (xy 334.068674 -213.907624) (xy 334.151478 -213.891114) (xy 334.160368 -213.888574)
			(xy 334.16406 -213.887022) (xy 334.170952 -213.882943) (xy 334.174084 -213.880446) (xy 334.17891 -213.876636)
			(xy 334.186022 -213.86673) (xy 334.188562 -213.860634) (xy 334.198312 -213.838315) (xy 334.223402 -213.79657)
			(xy 334.254336 -213.75895) (xy 334.290447 -213.726268) (xy 334.330956 -213.699228) (xy 334.374989 -213.678414)
			(xy 334.421596 -213.664274) (xy 334.469772 -213.657114) (xy 334.494124 -213.656672) (xy 334.520111 -213.657183)
			(xy 334.571443 -213.665317) (xy 334.620872 -213.68138) (xy 334.66718 -213.704976) (xy 334.709226 -213.735526)
			(xy 334.745976 -213.772277) (xy 334.776526 -213.814324) (xy 334.800122 -213.860632) (xy 334.816184 -213.910061)
			(xy 334.824317 -213.961393) (xy 334.824832 -213.98738) (xy 334.824401 -214.011735) (xy 334.824159 -214.013367)
			(xy 334.963772 -214.013367) (xy 334.963772 -213.961393) (xy 334.971902 -213.910058) (xy 334.987963 -213.860628)
			(xy 335.011559 -213.814318) (xy 335.042109 -213.77227) (xy 335.07886 -213.735519) (xy 335.120908 -213.704969)
			(xy 335.167218 -213.681373) (xy 335.216648 -213.665312) (xy 335.267983 -213.657182) (xy 335.319957 -213.657182)
			(xy 335.371292 -213.665312) (xy 335.420722 -213.681373) (xy 335.467032 -213.704969) (xy 335.50908 -213.735519)
			(xy 335.545831 -213.77227) (xy 335.576381 -213.814318) (xy 335.599977 -213.860628) (xy 335.616038 -213.910058)
			(xy 335.624168 -213.961393) (xy 335.624678 -213.98738) (xy 335.624168 -214.013367) (xy 335.616038 -214.064702)
			(xy 335.599977 -214.114132) (xy 335.576381 -214.160442) (xy 335.545831 -214.20249) (xy 335.50908 -214.239241)
			(xy 335.467032 -214.269791) (xy 335.420722 -214.293387) (xy 335.371292 -214.309448) (xy 335.319957 -214.317578)
			(xy 335.267983 -214.317578) (xy 335.216648 -214.309448) (xy 335.167218 -214.293387) (xy 335.120908 -214.269791)
			(xy 335.07886 -214.239241) (xy 335.042109 -214.20249) (xy 335.011559 -214.160442) (xy 334.987963 -214.114132)
			(xy 334.971902 -214.064702) (xy 334.963772 -214.013367) (xy 334.824159 -214.013367) (xy 334.817262 -214.059919)
			(xy 334.803134 -214.106535) (xy 334.782324 -214.150576) (xy 334.755281 -214.19109) (xy 334.722589 -214.2272)
			(xy 334.684957 -214.258126) (xy 334.643196 -214.2832) (xy 334.62087 -214.292942) (xy 334.614774 -214.295482)
			(xy 334.604868 -214.302594) (xy 334.601058 -214.30742) (xy 334.598556 -214.310548) (xy 334.594476 -214.317441)
			(xy 334.59293 -214.321136) (xy 334.59039 -214.330026) (xy 334.57388 -214.41283) (xy 334.572128 -214.425258)
			(xy 334.579434 -214.449241) (xy 334.58785 -214.45855) (xy 334.8228 -214.6935) (xy 334.832096 -214.701947)
			(xy 334.856089 -214.709273) (xy 334.86852 -214.70747) (xy 334.951324 -214.69096) (xy 334.960214 -214.68842)
			(xy 334.963905 -214.686866) (xy 334.970796 -214.682786) (xy 334.97393 -214.680292) (xy 334.978756 -214.676482)
			(xy 334.985868 -214.666576) (xy 334.988408 -214.66048) (xy 334.998157 -214.63816) (xy 335.023245 -214.596414)
			(xy 335.054178 -214.558794) (xy 335.09029 -214.526112) (xy 335.130799 -214.499074) (xy 335.174834 -214.478262)
			(xy 335.221442 -214.464126) (xy 335.269618 -214.456972) (xy 335.29397 -214.456518) (xy 335.31996 -214.456999)
			(xy 335.371301 -214.465127) (xy 335.420738 -214.481186) (xy 335.467053 -214.504783) (xy 335.509107 -214.535335)
			(xy 335.545862 -214.57209) (xy 335.576415 -214.614143) (xy 335.600012 -214.660459) (xy 335.616072 -214.709895)
			(xy 335.624201 -214.761236) (xy 335.624678 -214.787226) (xy 335.62433 -214.807899) (xy 335.619114 -214.848915)
			(xy 335.614264 -214.869014) (xy 335.613502 -214.87257) (xy 335.612102 -214.88303) (xy 335.616953 -214.903543)
			(xy 335.629683 -214.920344) (xy 335.638648 -214.92591) (xy 335.656198 -214.936177) (xy 335.688573 -214.960772)
			(xy 335.703164 -214.974932) (xy 335.712308 -214.984076) (xy 335.719674 -214.990916) (xy 335.738207 -214.998658)
			(xy 335.758291 -214.998658) (xy 335.776824 -214.990916) (xy 335.78419 -214.984076) (xy 335.789778 -214.978488)
			(xy 335.79689 -214.964518) (xy 335.79816 -214.957152) (xy 335.799293 -214.949473) (xy 335.797359 -214.934081)
			(xy 335.79435 -214.926926) (xy 335.794096 -214.926672) (xy 335.784414 -214.904802) (xy 335.770742 -214.85897)
			(xy 335.763809 -214.811647) (xy 335.763362 -214.787734) (xy 335.763362 -214.787226) (xy 335.763793 -214.762872)
			(xy 335.770933 -214.714691) (xy 335.785062 -214.668078) (xy 335.805875 -214.624041) (xy 335.832921 -214.583533)
			(xy 335.865616 -214.54743) (xy 335.903253 -214.516512) (xy 335.945017 -214.491449) (xy 335.967324 -214.481664)
			(xy 335.973166 -214.479378) (xy 335.983326 -214.471758) (xy 335.987136 -214.46744) (xy 335.990911 -214.462475)
			(xy 335.996174 -214.451171) (xy 335.99755 -214.445088) (xy 336.01406 -214.36203) (xy 336.015872 -214.349539)
			(xy 336.008556 -214.325415) (xy 336.00009 -214.316056) (xy 335.983326 -214.299038) (xy 335.97342 -214.295228)
			(xy 335.950542 -214.285761) (xy 335.907656 -214.26102) (xy 335.868936 -214.230166) (xy 335.835245 -214.193885)
			(xy 335.807338 -214.15299) (xy 335.785835 -214.108392) (xy 335.771219 -214.061089) (xy 335.763815 -214.012135)
			(xy 335.763362 -213.98738) (xy 335.763873 -213.961393) (xy 335.772006 -213.910059) (xy 335.788068 -213.860629)
			(xy 335.811665 -213.81432) (xy 335.842214 -213.772273) (xy 335.878965 -213.735521) (xy 335.921012 -213.70497)
			(xy 335.96732 -213.681372) (xy 336.016749 -213.665308) (xy 336.068083 -213.657174) (xy 336.09407 -213.656672)
			(xy 336.118828 -213.65711) (xy 336.167792 -213.664493) (xy 336.215106 -213.679096) (xy 336.259713 -213.700594)
			(xy 336.300613 -213.728505) (xy 336.336892 -213.762206) (xy 336.367739 -213.800941) (xy 336.392462 -213.843844)
			(xy 336.401918 -213.86673) (xy 336.405728 -213.876636) (xy 336.423 -213.893654) (xy 336.432294 -213.902107)
			(xy 336.456289 -213.90944) (xy 336.46872 -213.907624) (xy 336.551524 -213.891114) (xy 336.560414 -213.888574)
			(xy 336.564104 -213.887019) (xy 336.570993 -213.882935) (xy 336.57413 -213.880446) (xy 336.578956 -213.876636)
			(xy 336.586068 -213.86673) (xy 336.588608 -213.860634) (xy 336.598359 -213.838317) (xy 336.62345 -213.796576)
			(xy 336.654386 -213.758961) (xy 336.690498 -213.726284) (xy 336.731007 -213.699249) (xy 336.77504 -213.678441)
			(xy 336.821646 -213.664307) (xy 336.869819 -213.657154) (xy 336.89417 -213.656672) (xy 336.920162 -213.657153)
			(xy 336.971508 -213.665281) (xy 337.020949 -213.681341) (xy 337.067269 -213.704939) (xy 337.109327 -213.735493)
			(xy 337.146088 -213.77225) (xy 337.176645 -213.814305) (xy 337.200247 -213.860623) (xy 337.216312 -213.910063)
			(xy 337.224445 -213.961408) (xy 337.224445 -214.013367) (xy 337.363818 -214.013367) (xy 337.363818 -213.961393)
			(xy 337.371948 -213.910058) (xy 337.388009 -213.860628) (xy 337.411605 -213.814318) (xy 337.442155 -213.77227)
			(xy 337.478906 -213.735519) (xy 337.520954 -213.704969) (xy 337.567264 -213.681373) (xy 337.616694 -213.665312)
			(xy 337.668029 -213.657182) (xy 337.720003 -213.657182) (xy 337.771338 -213.665312) (xy 337.820768 -213.681373)
			(xy 337.867078 -213.704969) (xy 337.909126 -213.735519) (xy 337.945877 -213.77227) (xy 337.976427 -213.814318)
			(xy 338.000023 -213.860628) (xy 338.016084 -213.910058) (xy 338.024214 -213.961393) (xy 338.024724 -213.98738)
			(xy 338.024214 -214.013367) (xy 338.163918 -214.013367) (xy 338.163918 -213.961393) (xy 338.172048 -213.910058)
			(xy 338.188109 -213.860628) (xy 338.211705 -213.814318) (xy 338.242255 -213.77227) (xy 338.279006 -213.735519)
			(xy 338.321054 -213.704969) (xy 338.367364 -213.681373) (xy 338.416794 -213.665312) (xy 338.468129 -213.657182)
			(xy 338.520103 -213.657182) (xy 338.571438 -213.665312) (xy 338.620868 -213.681373) (xy 338.667178 -213.704969)
			(xy 338.709226 -213.735519) (xy 338.745977 -213.77227) (xy 338.776527 -213.814318) (xy 338.800123 -213.860628)
			(xy 338.816184 -213.910058) (xy 338.824314 -213.961393) (xy 338.824824 -213.98738) (xy 338.824314 -214.013367)
			(xy 338.963764 -214.013367) (xy 338.963764 -213.961393) (xy 338.971894 -213.910058) (xy 338.987955 -213.860628)
			(xy 339.011551 -213.814318) (xy 339.042101 -213.77227) (xy 339.078852 -213.735519) (xy 339.1209 -213.704969)
			(xy 339.16721 -213.681373) (xy 339.21664 -213.665312) (xy 339.267975 -213.657182) (xy 339.319949 -213.657182)
			(xy 339.371284 -213.665312) (xy 339.420714 -213.681373) (xy 339.467024 -213.704969) (xy 339.509072 -213.735519)
			(xy 339.545823 -213.77227) (xy 339.576373 -213.814318) (xy 339.599969 -213.860628) (xy 339.61603 -213.910058)
			(xy 339.62416 -213.961393) (xy 339.62467 -213.98738) (xy 339.62416 -214.013367) (xy 339.763864 -214.013367)
			(xy 339.763864 -213.961393) (xy 339.771994 -213.910058) (xy 339.788055 -213.860628) (xy 339.811651 -213.814318)
			(xy 339.842201 -213.77227) (xy 339.878952 -213.735519) (xy 339.921 -213.704969) (xy 339.96731 -213.681373)
			(xy 340.01674 -213.665312) (xy 340.068075 -213.657182) (xy 340.120049 -213.657182) (xy 340.171384 -213.665312)
			(xy 340.220814 -213.681373) (xy 340.267124 -213.704969) (xy 340.309172 -213.735519) (xy 340.345923 -213.77227)
			(xy 340.376473 -213.814318) (xy 340.400069 -213.860628) (xy 340.41613 -213.910058) (xy 340.42426 -213.961393)
			(xy 340.42477 -213.98738) (xy 340.42426 -214.013367) (xy 340.563964 -214.013367) (xy 340.563964 -213.961393)
			(xy 340.572094 -213.910058) (xy 340.588155 -213.860628) (xy 340.611751 -213.814318) (xy 340.642301 -213.77227)
			(xy 340.679052 -213.735519) (xy 340.7211 -213.704969) (xy 340.76741 -213.681373) (xy 340.81684 -213.665312)
			(xy 340.868175 -213.657182) (xy 340.920149 -213.657182) (xy 340.971484 -213.665312) (xy 341.020914 -213.681373)
			(xy 341.067224 -213.704969) (xy 341.109272 -213.735519) (xy 341.146023 -213.77227) (xy 341.176573 -213.814318)
			(xy 341.200169 -213.860628) (xy 341.21623 -213.910058) (xy 341.22436 -213.961393) (xy 341.22487 -213.98738)
			(xy 341.22436 -214.013367) (xy 341.36381 -214.013367) (xy 341.36381 -213.961393) (xy 341.37194 -213.910058)
			(xy 341.388001 -213.860628) (xy 341.411597 -213.814318) (xy 341.442147 -213.77227) (xy 341.478898 -213.735519)
			(xy 341.520946 -213.704969) (xy 341.567256 -213.681373) (xy 341.616686 -213.665312) (xy 341.668021 -213.657182)
			(xy 341.719995 -213.657182) (xy 341.77133 -213.665312) (xy 341.82076 -213.681373) (xy 341.86707 -213.704969)
			(xy 341.909118 -213.735519) (xy 341.945869 -213.77227) (xy 341.976419 -213.814318) (xy 342.000015 -213.860628)
			(xy 342.016076 -213.910058) (xy 342.024206 -213.961393) (xy 342.024716 -213.98738) (xy 342.024206 -214.013367)
			(xy 342.963502 -214.013367) (xy 342.963502 -213.961393) (xy 342.971632 -213.910058) (xy 342.987693 -213.860628)
			(xy 343.011289 -213.814318) (xy 343.041839 -213.77227) (xy 343.07859 -213.735519) (xy 343.120638 -213.704969)
			(xy 343.166948 -213.681373) (xy 343.216378 -213.665312) (xy 343.267713 -213.657182) (xy 343.319687 -213.657182)
			(xy 343.371022 -213.665312) (xy 343.420452 -213.681373) (xy 343.466762 -213.704969) (xy 343.50881 -213.735519)
			(xy 343.545561 -213.77227) (xy 343.576111 -213.814318) (xy 343.599707 -213.860628) (xy 343.615768 -213.910058)
			(xy 343.623898 -213.961393) (xy 343.624408 -213.98738) (xy 343.623898 -214.013367) (xy 343.763348 -214.013367)
			(xy 343.763348 -213.961393) (xy 343.771478 -213.910058) (xy 343.787539 -213.860628) (xy 343.811135 -213.814318)
			(xy 343.841685 -213.77227) (xy 343.878436 -213.735519) (xy 343.920484 -213.704969) (xy 343.966794 -213.681373)
			(xy 344.016224 -213.665312) (xy 344.067559 -213.657182) (xy 344.119533 -213.657182) (xy 344.170868 -213.665312)
			(xy 344.220298 -213.681373) (xy 344.266608 -213.704969) (xy 344.308656 -213.735519) (xy 344.345407 -213.77227)
			(xy 344.375957 -213.814318) (xy 344.399553 -213.860628) (xy 344.415614 -213.910058) (xy 344.423744 -213.961393)
			(xy 344.424254 -213.98738) (xy 344.423744 -214.013367) (xy 344.563448 -214.013367) (xy 344.563448 -213.961393)
			(xy 344.571578 -213.910058) (xy 344.587639 -213.860628) (xy 344.611235 -213.814318) (xy 344.641785 -213.77227)
			(xy 344.678536 -213.735519) (xy 344.720584 -213.704969) (xy 344.766894 -213.681373) (xy 344.816324 -213.665312)
			(xy 344.867659 -213.657182) (xy 344.919633 -213.657182) (xy 344.970968 -213.665312) (xy 345.020398 -213.681373)
			(xy 345.066708 -213.704969) (xy 345.108756 -213.735519) (xy 345.145507 -213.77227) (xy 345.176057 -213.814318)
			(xy 345.199653 -213.860628) (xy 345.215714 -213.910058) (xy 345.223844 -213.961393) (xy 345.224354 -213.98738)
			(xy 345.223844 -214.013367) (xy 345.363548 -214.013367) (xy 345.363548 -213.961393) (xy 345.371678 -213.910058)
			(xy 345.387739 -213.860628) (xy 345.411335 -213.814318) (xy 345.441885 -213.77227) (xy 345.478636 -213.735519)
			(xy 345.520684 -213.704969) (xy 345.566994 -213.681373) (xy 345.616424 -213.665312) (xy 345.667759 -213.657182)
			(xy 345.719733 -213.657182) (xy 345.771068 -213.665312) (xy 345.820498 -213.681373) (xy 345.866808 -213.704969)
			(xy 345.908856 -213.735519) (xy 345.945607 -213.77227) (xy 345.976157 -213.814318) (xy 345.999753 -213.860628)
			(xy 346.015814 -213.910058) (xy 346.023944 -213.961393) (xy 346.024454 -213.98738) (xy 346.023944 -214.013367)
			(xy 346.163394 -214.013367) (xy 346.163394 -213.961393) (xy 346.171524 -213.910058) (xy 346.187585 -213.860628)
			(xy 346.211181 -213.814318) (xy 346.241731 -213.77227) (xy 346.278482 -213.735519) (xy 346.32053 -213.704969)
			(xy 346.36684 -213.681373) (xy 346.41627 -213.665312) (xy 346.467605 -213.657182) (xy 346.519579 -213.657182)
			(xy 346.570914 -213.665312) (xy 346.620344 -213.681373) (xy 346.666654 -213.704969) (xy 346.708702 -213.735519)
			(xy 346.745453 -213.77227) (xy 346.776003 -213.814318) (xy 346.799599 -213.860628) (xy 346.81566 -213.910058)
			(xy 346.82379 -213.961393) (xy 346.8243 -213.98738) (xy 346.82379 -214.013367) (xy 346.963494 -214.013367)
			(xy 346.963494 -213.961393) (xy 346.971624 -213.910058) (xy 346.987685 -213.860628) (xy 347.011281 -213.814318)
			(xy 347.041831 -213.77227) (xy 347.078582 -213.735519) (xy 347.12063 -213.704969) (xy 347.16694 -213.681373)
			(xy 347.21637 -213.665312) (xy 347.267705 -213.657182) (xy 347.319679 -213.657182) (xy 347.371014 -213.665312)
			(xy 347.420444 -213.681373) (xy 347.466754 -213.704969) (xy 347.508802 -213.735519) (xy 347.545553 -213.77227)
			(xy 347.576103 -213.814318) (xy 347.599699 -213.860628) (xy 347.61576 -213.910058) (xy 347.62389 -213.961393)
			(xy 347.6244 -213.98738) (xy 347.62389 -214.013367) (xy 347.61576 -214.064702) (xy 347.599699 -214.114132)
			(xy 347.576103 -214.160442) (xy 347.545553 -214.20249) (xy 347.508802 -214.239241) (xy 347.466754 -214.269791)
			(xy 347.420444 -214.293387) (xy 347.371014 -214.309448) (xy 347.319679 -214.317578) (xy 347.267705 -214.317578)
			(xy 347.21637 -214.309448) (xy 347.16694 -214.293387) (xy 347.12063 -214.269791) (xy 347.078582 -214.239241)
			(xy 347.041831 -214.20249) (xy 347.011281 -214.160442) (xy 346.987685 -214.114132) (xy 346.971624 -214.064702)
			(xy 346.963494 -214.013367) (xy 346.82379 -214.013367) (xy 346.81566 -214.064702) (xy 346.799599 -214.114132)
			(xy 346.776003 -214.160442) (xy 346.745453 -214.20249) (xy 346.708702 -214.239241) (xy 346.666654 -214.269791)
			(xy 346.620344 -214.293387) (xy 346.570914 -214.309448) (xy 346.519579 -214.317578) (xy 346.467605 -214.317578)
			(xy 346.41627 -214.309448) (xy 346.36684 -214.293387) (xy 346.32053 -214.269791) (xy 346.278482 -214.239241)
			(xy 346.241731 -214.20249) (xy 346.211181 -214.160442) (xy 346.187585 -214.114132) (xy 346.171524 -214.064702)
			(xy 346.163394 -214.013367) (xy 346.023944 -214.013367) (xy 346.015814 -214.064702) (xy 345.999753 -214.114132)
			(xy 345.976157 -214.160442) (xy 345.945607 -214.20249) (xy 345.908856 -214.239241) (xy 345.866808 -214.269791)
			(xy 345.820498 -214.293387) (xy 345.771068 -214.309448) (xy 345.719733 -214.317578) (xy 345.667759 -214.317578)
			(xy 345.616424 -214.309448) (xy 345.566994 -214.293387) (xy 345.520684 -214.269791) (xy 345.478636 -214.239241)
			(xy 345.441885 -214.20249) (xy 345.411335 -214.160442) (xy 345.387739 -214.114132) (xy 345.371678 -214.064702)
			(xy 345.363548 -214.013367) (xy 345.223844 -214.013367) (xy 345.215714 -214.064702) (xy 345.199653 -214.114132)
			(xy 345.176057 -214.160442) (xy 345.145507 -214.20249) (xy 345.108756 -214.239241) (xy 345.066708 -214.269791)
			(xy 345.020398 -214.293387) (xy 344.970968 -214.309448) (xy 344.919633 -214.317578) (xy 344.867659 -214.317578)
			(xy 344.816324 -214.309448) (xy 344.766894 -214.293387) (xy 344.720584 -214.269791) (xy 344.678536 -214.239241)
			(xy 344.641785 -214.20249) (xy 344.611235 -214.160442) (xy 344.587639 -214.114132) (xy 344.571578 -214.064702)
			(xy 344.563448 -214.013367) (xy 344.423744 -214.013367) (xy 344.415614 -214.064702) (xy 344.399553 -214.114132)
			(xy 344.375957 -214.160442) (xy 344.345407 -214.20249) (xy 344.308656 -214.239241) (xy 344.266608 -214.269791)
			(xy 344.220298 -214.293387) (xy 344.170868 -214.309448) (xy 344.119533 -214.317578) (xy 344.067559 -214.317578)
			(xy 344.016224 -214.309448) (xy 343.966794 -214.293387) (xy 343.920484 -214.269791) (xy 343.878436 -214.239241)
			(xy 343.841685 -214.20249) (xy 343.811135 -214.160442) (xy 343.787539 -214.114132) (xy 343.771478 -214.064702)
			(xy 343.763348 -214.013367) (xy 343.623898 -214.013367) (xy 343.615768 -214.064702) (xy 343.599707 -214.114132)
			(xy 343.576111 -214.160442) (xy 343.545561 -214.20249) (xy 343.50881 -214.239241) (xy 343.466762 -214.269791)
			(xy 343.420452 -214.293387) (xy 343.371022 -214.309448) (xy 343.319687 -214.317578) (xy 343.267713 -214.317578)
			(xy 343.216378 -214.309448) (xy 343.166948 -214.293387) (xy 343.120638 -214.269791) (xy 343.07859 -214.239241)
			(xy 343.041839 -214.20249) (xy 343.011289 -214.160442) (xy 342.987693 -214.114132) (xy 342.971632 -214.064702)
			(xy 342.963502 -214.013367) (xy 342.024206 -214.013367) (xy 342.016076 -214.064702) (xy 342.000015 -214.114132)
			(xy 341.976419 -214.160442) (xy 341.945869 -214.20249) (xy 341.909118 -214.239241) (xy 341.86707 -214.269791)
			(xy 341.82076 -214.293387) (xy 341.77133 -214.309448) (xy 341.719995 -214.317578) (xy 341.668021 -214.317578)
			(xy 341.616686 -214.309448) (xy 341.567256 -214.293387) (xy 341.520946 -214.269791) (xy 341.478898 -214.239241)
			(xy 341.442147 -214.20249) (xy 341.411597 -214.160442) (xy 341.388001 -214.114132) (xy 341.37194 -214.064702)
			(xy 341.36381 -214.013367) (xy 341.22436 -214.013367) (xy 341.21623 -214.064702) (xy 341.200169 -214.114132)
			(xy 341.176573 -214.160442) (xy 341.146023 -214.20249) (xy 341.109272 -214.239241) (xy 341.067224 -214.269791)
			(xy 341.020914 -214.293387) (xy 340.971484 -214.309448) (xy 340.920149 -214.317578) (xy 340.868175 -214.317578)
			(xy 340.81684 -214.309448) (xy 340.76741 -214.293387) (xy 340.7211 -214.269791) (xy 340.679052 -214.239241)
			(xy 340.642301 -214.20249) (xy 340.611751 -214.160442) (xy 340.588155 -214.114132) (xy 340.572094 -214.064702)
			(xy 340.563964 -214.013367) (xy 340.42426 -214.013367) (xy 340.41613 -214.064702) (xy 340.400069 -214.114132)
			(xy 340.376473 -214.160442) (xy 340.345923 -214.20249) (xy 340.309172 -214.239241) (xy 340.267124 -214.269791)
			(xy 340.220814 -214.293387) (xy 340.171384 -214.309448) (xy 340.120049 -214.317578) (xy 340.068075 -214.317578)
			(xy 340.01674 -214.309448) (xy 339.96731 -214.293387) (xy 339.921 -214.269791) (xy 339.878952 -214.239241)
			(xy 339.842201 -214.20249) (xy 339.811651 -214.160442) (xy 339.788055 -214.114132) (xy 339.771994 -214.064702)
			(xy 339.763864 -214.013367) (xy 339.62416 -214.013367) (xy 339.61603 -214.064702) (xy 339.599969 -214.114132)
			(xy 339.576373 -214.160442) (xy 339.545823 -214.20249) (xy 339.509072 -214.239241) (xy 339.467024 -214.269791)
			(xy 339.420714 -214.293387) (xy 339.371284 -214.309448) (xy 339.319949 -214.317578) (xy 339.267975 -214.317578)
			(xy 339.21664 -214.309448) (xy 339.16721 -214.293387) (xy 339.1209 -214.269791) (xy 339.078852 -214.239241)
			(xy 339.042101 -214.20249) (xy 339.011551 -214.160442) (xy 338.987955 -214.114132) (xy 338.971894 -214.064702)
			(xy 338.963764 -214.013367) (xy 338.824314 -214.013367) (xy 338.816184 -214.064702) (xy 338.800123 -214.114132)
			(xy 338.776527 -214.160442) (xy 338.745977 -214.20249) (xy 338.709226 -214.239241) (xy 338.667178 -214.269791)
			(xy 338.620868 -214.293387) (xy 338.571438 -214.309448) (xy 338.520103 -214.317578) (xy 338.468129 -214.317578)
			(xy 338.416794 -214.309448) (xy 338.367364 -214.293387) (xy 338.321054 -214.269791) (xy 338.279006 -214.239241)
			(xy 338.242255 -214.20249) (xy 338.211705 -214.160442) (xy 338.188109 -214.114132) (xy 338.172048 -214.064702)
			(xy 338.163918 -214.013367) (xy 338.024214 -214.013367) (xy 338.016084 -214.064702) (xy 338.000023 -214.114132)
			(xy 337.976427 -214.160442) (xy 337.945877 -214.20249) (xy 337.909126 -214.239241) (xy 337.867078 -214.269791)
			(xy 337.820768 -214.293387) (xy 337.771338 -214.309448) (xy 337.720003 -214.317578) (xy 337.668029 -214.317578)
			(xy 337.616694 -214.309448) (xy 337.567264 -214.293387) (xy 337.520954 -214.269791) (xy 337.478906 -214.239241)
			(xy 337.442155 -214.20249) (xy 337.411605 -214.160442) (xy 337.388009 -214.114132) (xy 337.371948 -214.064702)
			(xy 337.363818 -214.013367) (xy 337.224445 -214.013367) (xy 337.224445 -214.013392) (xy 337.216312 -214.064737)
			(xy 337.200247 -214.114177) (xy 337.176645 -214.160495) (xy 337.146088 -214.20255) (xy 337.109327 -214.239307)
			(xy 337.067269 -214.269861) (xy 337.020949 -214.293459) (xy 336.971508 -214.309519) (xy 336.920162 -214.317647)
			(xy 336.89417 -214.318088) (xy 336.870548 -214.317326) (xy 336.870294 -214.317326) (xy 336.859876 -214.317047)
			(xy 336.840207 -214.32387) (xy 336.832194 -214.330534) (xy 336.7913 -214.36838) (xy 336.791808 -214.386414)
			(xy 336.791808 -214.409274) (xy 336.79242 -214.421694) (xy 336.803997 -214.443672) (xy 336.813906 -214.451184)
			(xy 336.820361 -214.455284) (xy 336.834965 -214.459797) (xy 336.842608 -214.460074) (xy 336.846164 -214.460074)
			(xy 336.849466 -214.459566) (xy 336.860588 -214.458148) (xy 336.882959 -214.456625) (xy 336.89417 -214.456518)
			(xy 336.920159 -214.456999) (xy 336.971497 -214.465126) (xy 337.020932 -214.481184) (xy 337.067245 -214.504778)
			(xy 337.109298 -214.535328) (xy 337.146053 -214.57208) (xy 337.176606 -214.614129) (xy 337.200205 -214.660441)
			(xy 337.216267 -214.709874) (xy 337.224399 -214.761211) (xy 337.224399 -214.813189) (xy 337.224395 -214.813213)
			(xy 337.363818 -214.813213) (xy 337.363818 -214.761239) (xy 337.371948 -214.709904) (xy 337.388009 -214.660474)
			(xy 337.411605 -214.614164) (xy 337.442155 -214.572116) (xy 337.478906 -214.535365) (xy 337.520954 -214.504815)
			(xy 337.567264 -214.481219) (xy 337.616694 -214.465158) (xy 337.668029 -214.457028) (xy 337.720003 -214.457028)
			(xy 337.771338 -214.465158) (xy 337.820768 -214.481219) (xy 337.867078 -214.504815) (xy 337.909126 -214.535365)
			(xy 337.945877 -214.572116) (xy 337.976427 -214.614164) (xy 338.000023 -214.660474) (xy 338.016084 -214.709904)
			(xy 338.024214 -214.761239) (xy 338.024724 -214.787226) (xy 338.024214 -214.813213) (xy 338.163918 -214.813213)
			(xy 338.163918 -214.761239) (xy 338.172048 -214.709904) (xy 338.188109 -214.660474) (xy 338.211705 -214.614164)
			(xy 338.242255 -214.572116) (xy 338.279006 -214.535365) (xy 338.321054 -214.504815) (xy 338.367364 -214.481219)
			(xy 338.416794 -214.465158) (xy 338.468129 -214.457028) (xy 338.520103 -214.457028) (xy 338.571438 -214.465158)
			(xy 338.620868 -214.481219) (xy 338.667178 -214.504815) (xy 338.709226 -214.535365) (xy 338.745977 -214.572116)
			(xy 338.776527 -214.614164) (xy 338.800123 -214.660474) (xy 338.816184 -214.709904) (xy 338.824314 -214.761239)
			(xy 338.824824 -214.787226) (xy 338.824314 -214.813213) (xy 338.963764 -214.813213) (xy 338.963764 -214.761239)
			(xy 338.971894 -214.709904) (xy 338.987955 -214.660474) (xy 339.011551 -214.614164) (xy 339.042101 -214.572116)
			(xy 339.078852 -214.535365) (xy 339.1209 -214.504815) (xy 339.16721 -214.481219) (xy 339.21664 -214.465158)
			(xy 339.267975 -214.457028) (xy 339.319949 -214.457028) (xy 339.371284 -214.465158) (xy 339.420714 -214.481219)
			(xy 339.467024 -214.504815) (xy 339.509072 -214.535365) (xy 339.545823 -214.572116) (xy 339.576373 -214.614164)
			(xy 339.599969 -214.660474) (xy 339.61603 -214.709904) (xy 339.62416 -214.761239) (xy 339.62467 -214.787226)
			(xy 339.62416 -214.813213) (xy 339.763864 -214.813213) (xy 339.763864 -214.761239) (xy 339.771994 -214.709904)
			(xy 339.788055 -214.660474) (xy 339.811651 -214.614164) (xy 339.842201 -214.572116) (xy 339.878952 -214.535365)
			(xy 339.921 -214.504815) (xy 339.96731 -214.481219) (xy 340.01674 -214.465158) (xy 340.068075 -214.457028)
			(xy 340.120049 -214.457028) (xy 340.171384 -214.465158) (xy 340.220814 -214.481219) (xy 340.267124 -214.504815)
			(xy 340.309172 -214.535365) (xy 340.345923 -214.572116) (xy 340.376473 -214.614164) (xy 340.400069 -214.660474)
			(xy 340.41613 -214.709904) (xy 340.42426 -214.761239) (xy 340.42477 -214.787226) (xy 340.42426 -214.813213)
			(xy 340.563964 -214.813213) (xy 340.563964 -214.761239) (xy 340.572094 -214.709904) (xy 340.588155 -214.660474)
			(xy 340.611751 -214.614164) (xy 340.642301 -214.572116) (xy 340.679052 -214.535365) (xy 340.7211 -214.504815)
			(xy 340.76741 -214.481219) (xy 340.81684 -214.465158) (xy 340.868175 -214.457028) (xy 340.920149 -214.457028)
			(xy 340.971484 -214.465158) (xy 341.020914 -214.481219) (xy 341.067224 -214.504815) (xy 341.109272 -214.535365)
			(xy 341.146023 -214.572116) (xy 341.176573 -214.614164) (xy 341.200169 -214.660474) (xy 341.21623 -214.709904)
			(xy 341.22436 -214.761239) (xy 341.22487 -214.787226) (xy 341.22436 -214.813213) (xy 341.36381 -214.813213)
			(xy 341.36381 -214.761239) (xy 341.37194 -214.709904) (xy 341.388001 -214.660474) (xy 341.411597 -214.614164)
			(xy 341.442147 -214.572116) (xy 341.478898 -214.535365) (xy 341.520946 -214.504815) (xy 341.567256 -214.481219)
			(xy 341.616686 -214.465158) (xy 341.668021 -214.457028) (xy 341.719995 -214.457028) (xy 341.77133 -214.465158)
			(xy 341.82076 -214.481219) (xy 341.86707 -214.504815) (xy 341.909118 -214.535365) (xy 341.945869 -214.572116)
			(xy 341.976419 -214.614164) (xy 342.000015 -214.660474) (xy 342.016076 -214.709904) (xy 342.024206 -214.761239)
			(xy 342.024716 -214.787226) (xy 342.024206 -214.813213) (xy 342.963502 -214.813213) (xy 342.963502 -214.761239)
			(xy 342.971632 -214.709904) (xy 342.987693 -214.660474) (xy 343.011289 -214.614164) (xy 343.041839 -214.572116)
			(xy 343.07859 -214.535365) (xy 343.120638 -214.504815) (xy 343.166948 -214.481219) (xy 343.216378 -214.465158)
			(xy 343.267713 -214.457028) (xy 343.319687 -214.457028) (xy 343.371022 -214.465158) (xy 343.420452 -214.481219)
			(xy 343.466762 -214.504815) (xy 343.50881 -214.535365) (xy 343.545561 -214.572116) (xy 343.576111 -214.614164)
			(xy 343.599707 -214.660474) (xy 343.615768 -214.709904) (xy 343.623898 -214.761239) (xy 343.624408 -214.787226)
			(xy 343.623898 -214.813213) (xy 343.763348 -214.813213) (xy 343.763348 -214.761239) (xy 343.771478 -214.709904)
			(xy 343.787539 -214.660474) (xy 343.811135 -214.614164) (xy 343.841685 -214.572116) (xy 343.878436 -214.535365)
			(xy 343.920484 -214.504815) (xy 343.966794 -214.481219) (xy 344.016224 -214.465158) (xy 344.067559 -214.457028)
			(xy 344.119533 -214.457028) (xy 344.170868 -214.465158) (xy 344.220298 -214.481219) (xy 344.266608 -214.504815)
			(xy 344.308656 -214.535365) (xy 344.345407 -214.572116) (xy 344.375957 -214.614164) (xy 344.399553 -214.660474)
			(xy 344.415614 -214.709904) (xy 344.423744 -214.761239) (xy 344.424254 -214.787226) (xy 344.423744 -214.813213)
			(xy 344.563448 -214.813213) (xy 344.563448 -214.761239) (xy 344.571578 -214.709904) (xy 344.587639 -214.660474)
			(xy 344.611235 -214.614164) (xy 344.641785 -214.572116) (xy 344.678536 -214.535365) (xy 344.720584 -214.504815)
			(xy 344.766894 -214.481219) (xy 344.816324 -214.465158) (xy 344.867659 -214.457028) (xy 344.919633 -214.457028)
			(xy 344.970968 -214.465158) (xy 345.020398 -214.481219) (xy 345.066708 -214.504815) (xy 345.108756 -214.535365)
			(xy 345.145507 -214.572116) (xy 345.176057 -214.614164) (xy 345.199653 -214.660474) (xy 345.215714 -214.709904)
			(xy 345.223844 -214.761239) (xy 345.224354 -214.787226) (xy 345.223844 -214.813213) (xy 345.363548 -214.813213)
			(xy 345.363548 -214.761239) (xy 345.371678 -214.709904) (xy 345.387739 -214.660474) (xy 345.411335 -214.614164)
			(xy 345.441885 -214.572116) (xy 345.478636 -214.535365) (xy 345.520684 -214.504815) (xy 345.566994 -214.481219)
			(xy 345.616424 -214.465158) (xy 345.667759 -214.457028) (xy 345.719733 -214.457028) (xy 345.771068 -214.465158)
			(xy 345.820498 -214.481219) (xy 345.866808 -214.504815) (xy 345.908856 -214.535365) (xy 345.945607 -214.572116)
			(xy 345.976157 -214.614164) (xy 345.999753 -214.660474) (xy 346.015814 -214.709904) (xy 346.023944 -214.761239)
			(xy 346.024454 -214.787226) (xy 346.023944 -214.813213) (xy 346.163394 -214.813213) (xy 346.163394 -214.761239)
			(xy 346.171524 -214.709904) (xy 346.187585 -214.660474) (xy 346.211181 -214.614164) (xy 346.241731 -214.572116)
			(xy 346.278482 -214.535365) (xy 346.32053 -214.504815) (xy 346.36684 -214.481219) (xy 346.41627 -214.465158)
			(xy 346.467605 -214.457028) (xy 346.519579 -214.457028) (xy 346.570914 -214.465158) (xy 346.620344 -214.481219)
			(xy 346.666654 -214.504815) (xy 346.708702 -214.535365) (xy 346.745453 -214.572116) (xy 346.776003 -214.614164)
			(xy 346.799599 -214.660474) (xy 346.81566 -214.709904) (xy 346.82379 -214.761239) (xy 346.8243 -214.787226)
			(xy 346.82379 -214.813213) (xy 346.81566 -214.864548) (xy 346.799599 -214.913978) (xy 346.776003 -214.960288)
			(xy 346.745453 -215.002336) (xy 346.708702 -215.039087) (xy 346.666654 -215.069637) (xy 346.620344 -215.093233)
			(xy 346.570914 -215.109294) (xy 346.519579 -215.117424) (xy 346.467605 -215.117424) (xy 346.41627 -215.109294)
			(xy 346.36684 -215.093233) (xy 346.32053 -215.069637) (xy 346.278482 -215.039087) (xy 346.241731 -215.002336)
			(xy 346.211181 -214.960288) (xy 346.187585 -214.913978) (xy 346.171524 -214.864548) (xy 346.163394 -214.813213)
			(xy 346.023944 -214.813213) (xy 346.015814 -214.864548) (xy 345.999753 -214.913978) (xy 345.976157 -214.960288)
			(xy 345.945607 -215.002336) (xy 345.908856 -215.039087) (xy 345.866808 -215.069637) (xy 345.820498 -215.093233)
			(xy 345.771068 -215.109294) (xy 345.719733 -215.117424) (xy 345.667759 -215.117424) (xy 345.616424 -215.109294)
			(xy 345.566994 -215.093233) (xy 345.520684 -215.069637) (xy 345.478636 -215.039087) (xy 345.441885 -215.002336)
			(xy 345.411335 -214.960288) (xy 345.387739 -214.913978) (xy 345.371678 -214.864548) (xy 345.363548 -214.813213)
			(xy 345.223844 -214.813213) (xy 345.215714 -214.864548) (xy 345.199653 -214.913978) (xy 345.176057 -214.960288)
			(xy 345.145507 -215.002336) (xy 345.108756 -215.039087) (xy 345.066708 -215.069637) (xy 345.020398 -215.093233)
			(xy 344.970968 -215.109294) (xy 344.919633 -215.117424) (xy 344.867659 -215.117424) (xy 344.816324 -215.109294)
			(xy 344.766894 -215.093233) (xy 344.720584 -215.069637) (xy 344.678536 -215.039087) (xy 344.641785 -215.002336)
			(xy 344.611235 -214.960288) (xy 344.587639 -214.913978) (xy 344.571578 -214.864548) (xy 344.563448 -214.813213)
			(xy 344.423744 -214.813213) (xy 344.415614 -214.864548) (xy 344.399553 -214.913978) (xy 344.375957 -214.960288)
			(xy 344.345407 -215.002336) (xy 344.308656 -215.039087) (xy 344.266608 -215.069637) (xy 344.220298 -215.093233)
			(xy 344.170868 -215.109294) (xy 344.119533 -215.117424) (xy 344.067559 -215.117424) (xy 344.016224 -215.109294)
			(xy 343.966794 -215.093233) (xy 343.920484 -215.069637) (xy 343.878436 -215.039087) (xy 343.841685 -215.002336)
			(xy 343.811135 -214.960288) (xy 343.787539 -214.913978) (xy 343.771478 -214.864548) (xy 343.763348 -214.813213)
			(xy 343.623898 -214.813213) (xy 343.615768 -214.864548) (xy 343.599707 -214.913978) (xy 343.576111 -214.960288)
			(xy 343.545561 -215.002336) (xy 343.50881 -215.039087) (xy 343.466762 -215.069637) (xy 343.420452 -215.093233)
			(xy 343.371022 -215.109294) (xy 343.319687 -215.117424) (xy 343.267713 -215.117424) (xy 343.216378 -215.109294)
			(xy 343.166948 -215.093233) (xy 343.120638 -215.069637) (xy 343.07859 -215.039087) (xy 343.041839 -215.002336)
			(xy 343.011289 -214.960288) (xy 342.987693 -214.913978) (xy 342.971632 -214.864548) (xy 342.963502 -214.813213)
			(xy 342.024206 -214.813213) (xy 342.016076 -214.864548) (xy 342.000015 -214.913978) (xy 341.976419 -214.960288)
			(xy 341.945869 -215.002336) (xy 341.909118 -215.039087) (xy 341.86707 -215.069637) (xy 341.82076 -215.093233)
			(xy 341.77133 -215.109294) (xy 341.719995 -215.117424) (xy 341.668021 -215.117424) (xy 341.616686 -215.109294)
			(xy 341.567256 -215.093233) (xy 341.520946 -215.069637) (xy 341.478898 -215.039087) (xy 341.442147 -215.002336)
			(xy 341.411597 -214.960288) (xy 341.388001 -214.913978) (xy 341.37194 -214.864548) (xy 341.36381 -214.813213)
			(xy 341.22436 -214.813213) (xy 341.21623 -214.864548) (xy 341.200169 -214.913978) (xy 341.176573 -214.960288)
			(xy 341.146023 -215.002336) (xy 341.109272 -215.039087) (xy 341.067224 -215.069637) (xy 341.020914 -215.093233)
			(xy 340.971484 -215.109294) (xy 340.920149 -215.117424) (xy 340.868175 -215.117424) (xy 340.81684 -215.109294)
			(xy 340.76741 -215.093233) (xy 340.7211 -215.069637) (xy 340.679052 -215.039087) (xy 340.642301 -215.002336)
			(xy 340.611751 -214.960288) (xy 340.588155 -214.913978) (xy 340.572094 -214.864548) (xy 340.563964 -214.813213)
			(xy 340.42426 -214.813213) (xy 340.41613 -214.864548) (xy 340.400069 -214.913978) (xy 340.376473 -214.960288)
			(xy 340.345923 -215.002336) (xy 340.309172 -215.039087) (xy 340.267124 -215.069637) (xy 340.220814 -215.093233)
			(xy 340.171384 -215.109294) (xy 340.120049 -215.117424) (xy 340.068075 -215.117424) (xy 340.01674 -215.109294)
			(xy 339.96731 -215.093233) (xy 339.921 -215.069637) (xy 339.878952 -215.039087) (xy 339.842201 -215.002336)
			(xy 339.811651 -214.960288) (xy 339.788055 -214.913978) (xy 339.771994 -214.864548) (xy 339.763864 -214.813213)
			(xy 339.62416 -214.813213) (xy 339.61603 -214.864548) (xy 339.599969 -214.913978) (xy 339.576373 -214.960288)
			(xy 339.545823 -215.002336) (xy 339.509072 -215.039087) (xy 339.467024 -215.069637) (xy 339.420714 -215.093233)
			(xy 339.371284 -215.109294) (xy 339.319949 -215.117424) (xy 339.267975 -215.117424) (xy 339.21664 -215.109294)
			(xy 339.16721 -215.093233) (xy 339.1209 -215.069637) (xy 339.078852 -215.039087) (xy 339.042101 -215.002336)
			(xy 339.011551 -214.960288) (xy 338.987955 -214.913978) (xy 338.971894 -214.864548) (xy 338.963764 -214.813213)
			(xy 338.824314 -214.813213) (xy 338.816184 -214.864548) (xy 338.800123 -214.913978) (xy 338.776527 -214.960288)
			(xy 338.745977 -215.002336) (xy 338.709226 -215.039087) (xy 338.667178 -215.069637) (xy 338.620868 -215.093233)
			(xy 338.571438 -215.109294) (xy 338.520103 -215.117424) (xy 338.468129 -215.117424) (xy 338.416794 -215.109294)
			(xy 338.367364 -215.093233) (xy 338.321054 -215.069637) (xy 338.279006 -215.039087) (xy 338.242255 -215.002336)
			(xy 338.211705 -214.960288) (xy 338.188109 -214.913978) (xy 338.172048 -214.864548) (xy 338.163918 -214.813213)
			(xy 338.024214 -214.813213) (xy 338.016084 -214.864548) (xy 338.000023 -214.913978) (xy 337.976427 -214.960288)
			(xy 337.945877 -215.002336) (xy 337.909126 -215.039087) (xy 337.867078 -215.069637) (xy 337.820768 -215.093233)
			(xy 337.771338 -215.109294) (xy 337.720003 -215.117424) (xy 337.668029 -215.117424) (xy 337.616694 -215.109294)
			(xy 337.567264 -215.093233) (xy 337.520954 -215.069637) (xy 337.478906 -215.039087) (xy 337.442155 -215.002336)
			(xy 337.411605 -214.960288) (xy 337.388009 -214.913978) (xy 337.371948 -214.864548) (xy 337.363818 -214.813213)
			(xy 337.224395 -214.813213) (xy 337.216267 -214.864526) (xy 337.200205 -214.913959) (xy 337.176606 -214.960271)
			(xy 337.146053 -215.00232) (xy 337.109298 -215.039072) (xy 337.067245 -215.069622) (xy 337.020932 -215.093216)
			(xy 336.971497 -215.109274) (xy 336.920159 -215.117401) (xy 336.89417 -215.117934) (xy 336.882958 -215.117843)
			(xy 336.860587 -215.116317) (xy 336.849466 -215.114886) (xy 336.846164 -215.114378) (xy 336.842608 -215.114378)
			(xy 336.834964 -215.114637) (xy 336.82036 -215.119162) (xy 336.813906 -215.123268) (xy 336.804005 -215.130791)
			(xy 336.792413 -215.152759) (xy 336.791808 -215.165178) (xy 336.791808 -215.209374) (xy 336.79242 -215.221794)
			(xy 336.803997 -215.243772) (xy 336.813906 -215.251284) (xy 336.820361 -215.255384) (xy 336.834965 -215.259897)
			(xy 336.842608 -215.260174) (xy 336.846164 -215.260174) (xy 336.849466 -215.259666) (xy 336.860588 -215.258248)
			(xy 336.882959 -215.256725) (xy 336.89417 -215.256618) (xy 336.920159 -215.257099) (xy 336.971497 -215.265226)
			(xy 337.020932 -215.281284) (xy 337.067245 -215.304878) (xy 337.109298 -215.335428) (xy 337.146053 -215.37218)
			(xy 337.176606 -215.414229) (xy 337.200205 -215.460541) (xy 337.216267 -215.509974) (xy 337.224399 -215.561311)
			(xy 337.224399 -215.613289) (xy 337.224395 -215.613313) (xy 337.363818 -215.613313) (xy 337.363818 -215.561339)
			(xy 337.371948 -215.510004) (xy 337.388009 -215.460574) (xy 337.411605 -215.414264) (xy 337.442155 -215.372216)
			(xy 337.478906 -215.335465) (xy 337.520954 -215.304915) (xy 337.567264 -215.281319) (xy 337.616694 -215.265258)
			(xy 337.668029 -215.257128) (xy 337.720003 -215.257128) (xy 337.771338 -215.265258) (xy 337.820768 -215.281319)
			(xy 337.867078 -215.304915) (xy 337.909126 -215.335465) (xy 337.945877 -215.372216) (xy 337.976427 -215.414264)
			(xy 338.000023 -215.460574) (xy 338.016084 -215.510004) (xy 338.024214 -215.561339) (xy 338.024724 -215.587326)
			(xy 338.024214 -215.613313) (xy 338.163918 -215.613313) (xy 338.163918 -215.561339) (xy 338.172048 -215.510004)
			(xy 338.188109 -215.460574) (xy 338.211705 -215.414264) (xy 338.242255 -215.372216) (xy 338.279006 -215.335465)
			(xy 338.321054 -215.304915) (xy 338.367364 -215.281319) (xy 338.416794 -215.265258) (xy 338.468129 -215.257128)
			(xy 338.520103 -215.257128) (xy 338.571438 -215.265258) (xy 338.620868 -215.281319) (xy 338.667178 -215.304915)
			(xy 338.709226 -215.335465) (xy 338.745977 -215.372216) (xy 338.776527 -215.414264) (xy 338.800123 -215.460574)
			(xy 338.816184 -215.510004) (xy 338.824314 -215.561339) (xy 338.824824 -215.587326) (xy 338.824314 -215.613313)
			(xy 338.963764 -215.613313) (xy 338.963764 -215.561339) (xy 338.971894 -215.510004) (xy 338.987955 -215.460574)
			(xy 339.011551 -215.414264) (xy 339.042101 -215.372216) (xy 339.078852 -215.335465) (xy 339.1209 -215.304915)
			(xy 339.16721 -215.281319) (xy 339.21664 -215.265258) (xy 339.267975 -215.257128) (xy 339.319949 -215.257128)
			(xy 339.371284 -215.265258) (xy 339.420714 -215.281319) (xy 339.467024 -215.304915) (xy 339.509072 -215.335465)
			(xy 339.545823 -215.372216) (xy 339.576373 -215.414264) (xy 339.599969 -215.460574) (xy 339.61603 -215.510004)
			(xy 339.62416 -215.561339) (xy 339.62467 -215.587326) (xy 339.62416 -215.613313) (xy 339.763864 -215.613313)
			(xy 339.763864 -215.561339) (xy 339.771994 -215.510004) (xy 339.788055 -215.460574) (xy 339.811651 -215.414264)
			(xy 339.842201 -215.372216) (xy 339.878952 -215.335465) (xy 339.921 -215.304915) (xy 339.96731 -215.281319)
			(xy 340.01674 -215.265258) (xy 340.068075 -215.257128) (xy 340.120049 -215.257128) (xy 340.171384 -215.265258)
			(xy 340.220814 -215.281319) (xy 340.267124 -215.304915) (xy 340.309172 -215.335465) (xy 340.345923 -215.372216)
			(xy 340.376473 -215.414264) (xy 340.400069 -215.460574) (xy 340.41613 -215.510004) (xy 340.42426 -215.561339)
			(xy 340.42477 -215.587326) (xy 340.42426 -215.613313) (xy 340.563964 -215.613313) (xy 340.563964 -215.561339)
			(xy 340.572094 -215.510004) (xy 340.588155 -215.460574) (xy 340.611751 -215.414264) (xy 340.642301 -215.372216)
			(xy 340.679052 -215.335465) (xy 340.7211 -215.304915) (xy 340.76741 -215.281319) (xy 340.81684 -215.265258)
			(xy 340.868175 -215.257128) (xy 340.920149 -215.257128) (xy 340.971484 -215.265258) (xy 341.020914 -215.281319)
			(xy 341.067224 -215.304915) (xy 341.109272 -215.335465) (xy 341.146023 -215.372216) (xy 341.176573 -215.414264)
			(xy 341.200169 -215.460574) (xy 341.21623 -215.510004) (xy 341.22436 -215.561339) (xy 341.22487 -215.587326)
			(xy 341.22436 -215.613313) (xy 341.36381 -215.613313) (xy 341.36381 -215.561339) (xy 341.37194 -215.510004)
			(xy 341.388001 -215.460574) (xy 341.411597 -215.414264) (xy 341.442147 -215.372216) (xy 341.478898 -215.335465)
			(xy 341.520946 -215.304915) (xy 341.567256 -215.281319) (xy 341.616686 -215.265258) (xy 341.668021 -215.257128)
			(xy 341.719995 -215.257128) (xy 341.77133 -215.265258) (xy 341.82076 -215.281319) (xy 341.86707 -215.304915)
			(xy 341.909118 -215.335465) (xy 341.945869 -215.372216) (xy 341.976419 -215.414264) (xy 342.000015 -215.460574)
			(xy 342.016076 -215.510004) (xy 342.024206 -215.561339) (xy 342.024716 -215.587326) (xy 342.024206 -215.613313)
			(xy 342.963502 -215.613313) (xy 342.963502 -215.561339) (xy 342.971632 -215.510004) (xy 342.987693 -215.460574)
			(xy 343.011289 -215.414264) (xy 343.041839 -215.372216) (xy 343.07859 -215.335465) (xy 343.120638 -215.304915)
			(xy 343.166948 -215.281319) (xy 343.216378 -215.265258) (xy 343.267713 -215.257128) (xy 343.319687 -215.257128)
			(xy 343.371022 -215.265258) (xy 343.420452 -215.281319) (xy 343.466762 -215.304915) (xy 343.50881 -215.335465)
			(xy 343.545561 -215.372216) (xy 343.576111 -215.414264) (xy 343.599707 -215.460574) (xy 343.615768 -215.510004)
			(xy 343.623898 -215.561339) (xy 343.624408 -215.587326) (xy 343.623898 -215.613313) (xy 343.763348 -215.613313)
			(xy 343.763348 -215.561339) (xy 343.771478 -215.510004) (xy 343.787539 -215.460574) (xy 343.811135 -215.414264)
			(xy 343.841685 -215.372216) (xy 343.878436 -215.335465) (xy 343.920484 -215.304915) (xy 343.966794 -215.281319)
			(xy 344.016224 -215.265258) (xy 344.067559 -215.257128) (xy 344.119533 -215.257128) (xy 344.170868 -215.265258)
			(xy 344.220298 -215.281319) (xy 344.266608 -215.304915) (xy 344.308656 -215.335465) (xy 344.345407 -215.372216)
			(xy 344.375957 -215.414264) (xy 344.399553 -215.460574) (xy 344.415614 -215.510004) (xy 344.423744 -215.561339)
			(xy 344.424254 -215.587326) (xy 344.423744 -215.613313) (xy 344.563448 -215.613313) (xy 344.563448 -215.561339)
			(xy 344.571578 -215.510004) (xy 344.587639 -215.460574) (xy 344.611235 -215.414264) (xy 344.641785 -215.372216)
			(xy 344.678536 -215.335465) (xy 344.720584 -215.304915) (xy 344.766894 -215.281319) (xy 344.816324 -215.265258)
			(xy 344.867659 -215.257128) (xy 344.919633 -215.257128) (xy 344.970968 -215.265258) (xy 345.020398 -215.281319)
			(xy 345.066708 -215.304915) (xy 345.108756 -215.335465) (xy 345.145507 -215.372216) (xy 345.176057 -215.414264)
			(xy 345.199653 -215.460574) (xy 345.215714 -215.510004) (xy 345.223844 -215.561339) (xy 345.224354 -215.587326)
			(xy 345.223844 -215.613313) (xy 345.363548 -215.613313) (xy 345.363548 -215.561339) (xy 345.371678 -215.510004)
			(xy 345.387739 -215.460574) (xy 345.411335 -215.414264) (xy 345.441885 -215.372216) (xy 345.478636 -215.335465)
			(xy 345.520684 -215.304915) (xy 345.566994 -215.281319) (xy 345.616424 -215.265258) (xy 345.667759 -215.257128)
			(xy 345.719733 -215.257128) (xy 345.771068 -215.265258) (xy 345.820498 -215.281319) (xy 345.866808 -215.304915)
			(xy 345.908856 -215.335465) (xy 345.945607 -215.372216) (xy 345.976157 -215.414264) (xy 345.999753 -215.460574)
			(xy 346.015814 -215.510004) (xy 346.023944 -215.561339) (xy 346.024454 -215.587326) (xy 346.023944 -215.613313)
			(xy 346.015814 -215.664648) (xy 345.999753 -215.714078) (xy 345.976157 -215.760388) (xy 345.945607 -215.802436)
			(xy 345.908856 -215.839187) (xy 345.866808 -215.869737) (xy 345.820498 -215.893333) (xy 345.771068 -215.909394)
			(xy 345.719733 -215.917524) (xy 345.667759 -215.917524) (xy 345.616424 -215.909394) (xy 345.566994 -215.893333)
			(xy 345.520684 -215.869737) (xy 345.478636 -215.839187) (xy 345.441885 -215.802436) (xy 345.411335 -215.760388)
			(xy 345.387739 -215.714078) (xy 345.371678 -215.664648) (xy 345.363548 -215.613313) (xy 345.223844 -215.613313)
			(xy 345.215714 -215.664648) (xy 345.199653 -215.714078) (xy 345.176057 -215.760388) (xy 345.145507 -215.802436)
			(xy 345.108756 -215.839187) (xy 345.066708 -215.869737) (xy 345.020398 -215.893333) (xy 344.970968 -215.909394)
			(xy 344.919633 -215.917524) (xy 344.867659 -215.917524) (xy 344.816324 -215.909394) (xy 344.766894 -215.893333)
			(xy 344.720584 -215.869737) (xy 344.678536 -215.839187) (xy 344.641785 -215.802436) (xy 344.611235 -215.760388)
			(xy 344.587639 -215.714078) (xy 344.571578 -215.664648) (xy 344.563448 -215.613313) (xy 344.423744 -215.613313)
			(xy 344.415614 -215.664648) (xy 344.399553 -215.714078) (xy 344.375957 -215.760388) (xy 344.345407 -215.802436)
			(xy 344.308656 -215.839187) (xy 344.266608 -215.869737) (xy 344.220298 -215.893333) (xy 344.170868 -215.909394)
			(xy 344.119533 -215.917524) (xy 344.067559 -215.917524) (xy 344.016224 -215.909394) (xy 343.966794 -215.893333)
			(xy 343.920484 -215.869737) (xy 343.878436 -215.839187) (xy 343.841685 -215.802436) (xy 343.811135 -215.760388)
			(xy 343.787539 -215.714078) (xy 343.771478 -215.664648) (xy 343.763348 -215.613313) (xy 343.623898 -215.613313)
			(xy 343.615768 -215.664648) (xy 343.599707 -215.714078) (xy 343.576111 -215.760388) (xy 343.545561 -215.802436)
			(xy 343.50881 -215.839187) (xy 343.466762 -215.869737) (xy 343.420452 -215.893333) (xy 343.371022 -215.909394)
			(xy 343.319687 -215.917524) (xy 343.267713 -215.917524) (xy 343.216378 -215.909394) (xy 343.166948 -215.893333)
			(xy 343.120638 -215.869737) (xy 343.07859 -215.839187) (xy 343.041839 -215.802436) (xy 343.011289 -215.760388)
			(xy 342.987693 -215.714078) (xy 342.971632 -215.664648) (xy 342.963502 -215.613313) (xy 342.024206 -215.613313)
			(xy 342.016076 -215.664648) (xy 342.000015 -215.714078) (xy 341.976419 -215.760388) (xy 341.945869 -215.802436)
			(xy 341.909118 -215.839187) (xy 341.86707 -215.869737) (xy 341.82076 -215.893333) (xy 341.77133 -215.909394)
			(xy 341.719995 -215.917524) (xy 341.668021 -215.917524) (xy 341.616686 -215.909394) (xy 341.567256 -215.893333)
			(xy 341.520946 -215.869737) (xy 341.478898 -215.839187) (xy 341.442147 -215.802436) (xy 341.411597 -215.760388)
			(xy 341.388001 -215.714078) (xy 341.37194 -215.664648) (xy 341.36381 -215.613313) (xy 341.22436 -215.613313)
			(xy 341.21623 -215.664648) (xy 341.200169 -215.714078) (xy 341.176573 -215.760388) (xy 341.146023 -215.802436)
			(xy 341.109272 -215.839187) (xy 341.067224 -215.869737) (xy 341.020914 -215.893333) (xy 340.971484 -215.909394)
			(xy 340.920149 -215.917524) (xy 340.868175 -215.917524) (xy 340.81684 -215.909394) (xy 340.76741 -215.893333)
			(xy 340.7211 -215.869737) (xy 340.679052 -215.839187) (xy 340.642301 -215.802436) (xy 340.611751 -215.760388)
			(xy 340.588155 -215.714078) (xy 340.572094 -215.664648) (xy 340.563964 -215.613313) (xy 340.42426 -215.613313)
			(xy 340.41613 -215.664648) (xy 340.400069 -215.714078) (xy 340.376473 -215.760388) (xy 340.345923 -215.802436)
			(xy 340.309172 -215.839187) (xy 340.267124 -215.869737) (xy 340.220814 -215.893333) (xy 340.171384 -215.909394)
			(xy 340.120049 -215.917524) (xy 340.068075 -215.917524) (xy 340.01674 -215.909394) (xy 339.96731 -215.893333)
			(xy 339.921 -215.869737) (xy 339.878952 -215.839187) (xy 339.842201 -215.802436) (xy 339.811651 -215.760388)
			(xy 339.788055 -215.714078) (xy 339.771994 -215.664648) (xy 339.763864 -215.613313) (xy 339.62416 -215.613313)
			(xy 339.61603 -215.664648) (xy 339.599969 -215.714078) (xy 339.576373 -215.760388) (xy 339.545823 -215.802436)
			(xy 339.509072 -215.839187) (xy 339.467024 -215.869737) (xy 339.420714 -215.893333) (xy 339.371284 -215.909394)
			(xy 339.319949 -215.917524) (xy 339.267975 -215.917524) (xy 339.21664 -215.909394) (xy 339.16721 -215.893333)
			(xy 339.1209 -215.869737) (xy 339.078852 -215.839187) (xy 339.042101 -215.802436) (xy 339.011551 -215.760388)
			(xy 338.987955 -215.714078) (xy 338.971894 -215.664648) (xy 338.963764 -215.613313) (xy 338.824314 -215.613313)
			(xy 338.816184 -215.664648) (xy 338.800123 -215.714078) (xy 338.776527 -215.760388) (xy 338.745977 -215.802436)
			(xy 338.709226 -215.839187) (xy 338.667178 -215.869737) (xy 338.620868 -215.893333) (xy 338.571438 -215.909394)
			(xy 338.520103 -215.917524) (xy 338.468129 -215.917524) (xy 338.416794 -215.909394) (xy 338.367364 -215.893333)
			(xy 338.321054 -215.869737) (xy 338.279006 -215.839187) (xy 338.242255 -215.802436) (xy 338.211705 -215.760388)
			(xy 338.188109 -215.714078) (xy 338.172048 -215.664648) (xy 338.163918 -215.613313) (xy 338.024214 -215.613313)
			(xy 338.016084 -215.664648) (xy 338.000023 -215.714078) (xy 337.976427 -215.760388) (xy 337.945877 -215.802436)
			(xy 337.909126 -215.839187) (xy 337.867078 -215.869737) (xy 337.820768 -215.893333) (xy 337.771338 -215.909394)
			(xy 337.720003 -215.917524) (xy 337.668029 -215.917524) (xy 337.616694 -215.909394) (xy 337.567264 -215.893333)
			(xy 337.520954 -215.869737) (xy 337.478906 -215.839187) (xy 337.442155 -215.802436) (xy 337.411605 -215.760388)
			(xy 337.388009 -215.714078) (xy 337.371948 -215.664648) (xy 337.363818 -215.613313) (xy 337.224395 -215.613313)
			(xy 337.216267 -215.664626) (xy 337.200205 -215.714059) (xy 337.176606 -215.760371) (xy 337.146053 -215.80242)
			(xy 337.109298 -215.839172) (xy 337.067245 -215.869722) (xy 337.020932 -215.893316) (xy 336.971497 -215.909374)
			(xy 336.920159 -215.917501) (xy 336.89417 -215.918034) (xy 336.882958 -215.917943) (xy 336.860587 -215.916417)
			(xy 336.849466 -215.914986) (xy 336.846164 -215.914478) (xy 336.842608 -215.914478) (xy 336.834964 -215.914737)
			(xy 336.82036 -215.919262) (xy 336.813906 -215.923368) (xy 336.804005 -215.930891) (xy 336.792413 -215.952859)
			(xy 336.791808 -215.965278) (xy 336.791808 -216.00922) (xy 336.79243 -216.021635) (xy 336.804018 -216.043596)
			(xy 336.813906 -216.05113) (xy 336.82036 -216.055234) (xy 336.834964 -216.059751) (xy 336.842608 -216.06002)
			(xy 336.846164 -216.06002) (xy 336.849466 -216.059512) (xy 336.860588 -216.058093) (xy 336.882959 -216.056571)
			(xy 336.89417 -216.056464) (xy 336.920162 -216.056945) (xy 336.971505 -216.065072) (xy 337.020946 -216.081131)
			(xy 337.067265 -216.104727) (xy 337.109323 -216.135278) (xy 337.146084 -216.172033) (xy 337.176642 -216.214085)
			(xy 337.200246 -216.260401) (xy 337.216314 -216.309838) (xy 337.224451 -216.36118) (xy 337.224878 -216.387172)
			(xy 337.224276 -216.415759) (xy 337.214452 -216.472081) (xy 337.19509 -216.525876) (xy 337.181444 -216.551002)
			(xy 337.177888 -216.557098) (xy 337.174586 -216.569798) (xy 337.17484 -216.576402) (xy 337.175065 -216.583004)
			(xy 337.178547 -216.595742) (xy 337.181698 -216.601548) (xy 337.225894 -216.677494) (xy 337.229196 -216.682828)
			(xy 337.236385 -216.691403) (xy 337.256158 -216.701816) (xy 337.267296 -216.702894)
		)
		(stroke
			(width 0)
			(type solid)
		)
		(fill yes)
		(layer "In11.Cu")
		(net "P3V3_FPGA_VCCIO2")
	)
	(gr_poly
		(pts
			(xy 365.33201 -261.457948) (xy 365.342078 -261.457522) (xy 365.360675 -261.449799) (xy 365.368078 -261.442962)
			(xy 365.841026 -260.970268) (xy 365.841534 -260.96976) (xy 365.84812 -260.96238) (xy 365.855578 -260.944081)
			(xy 365.856012 -260.9342) (xy 365.856012 -259.87883) (xy 365.83493 -259.851398) (xy 365.818166 -259.84708)
			(xy 365.79133 -259.839522) (xy 365.740033 -259.817689) (xy 365.692459 -259.788624) (xy 365.649622 -259.752945)
			(xy 365.612433 -259.711411) (xy 365.581684 -259.664908) (xy 365.558031 -259.614424) (xy 365.541976 -259.561036)
			(xy 365.533862 -259.50588) (xy 365.533861 -259.45013) (xy 365.541974 -259.394973) (xy 365.558027 -259.341584)
			(xy 365.58168 -259.2911) (xy 365.612427 -259.244596) (xy 365.649615 -259.203061) (xy 365.692452 -259.167381)
			(xy 365.740025 -259.138315) (xy 365.791322 -259.116481) (xy 365.818166 -259.108956) (xy 365.83493 -259.104638)
			(xy 365.856012 -259.077206) (xy 365.856012 -256.985008) (xy 365.839756 -256.959862) (xy 365.825786 -256.953766)
			(xy 365.800857 -256.942146) (xy 365.754338 -256.912804) (xy 365.712512 -256.87709) (xy 365.676243 -256.835743)
			(xy 365.646284 -256.789619) (xy 365.623254 -256.739674) (xy 365.60763 -256.68694) (xy 365.599736 -256.63251)
			(xy 365.599734 -256.57751) (xy 365.607626 -256.523079) (xy 365.623247 -256.470345) (xy 365.646275 -256.420398)
			(xy 365.676231 -256.374272) (xy 365.712498 -256.332924) (xy 365.754322 -256.297207) (xy 365.80084 -256.267863)
			(xy 365.825786 -256.256282) (xy 365.834578 -256.251904) (xy 365.848227 -256.237807) (xy 365.855572 -256.219612)
			(xy 365.856012 -256.2098) (xy 365.856012 -252.420628) (xy 365.856449 -252.410564) (xy 365.864183 -252.39198)
			(xy 365.870998 -252.38456) (xy 367.477802 -250.777756) (xy 367.485198 -250.770904) (xy 367.503797 -250.763161)
			(xy 367.51387 -250.76277) (xy 385.996688 -250.76277) (xy 386.006759 -250.762348) (xy 386.025363 -250.754634)
			(xy 386.032756 -250.747784) (xy 387.561328 -249.219212) (xy 387.569206 -249.21043) (xy 387.576647 -249.188071)
			(xy 387.573362 -249.164736) (xy 387.56717 -249.154696) (xy 387.566154 -249.153172) (xy 387.564884 -249.150886)
			(xy 387.56463 -249.150378) (xy 387.56336 -249.1486) (xy 387.557658 -249.139158) (xy 387.547234 -249.119716)
			(xy 387.542532 -249.109738) (xy 387.537852 -249.100753) (xy 387.522874 -249.087136) (xy 387.503804 -249.080344)
			(xy 387.48359 -249.081427) (xy 387.465356 -249.090219) (xy 387.45192 -249.10536) (xy 387.448298 -249.114818)
			(xy 387.439361 -249.139574) (xy 387.41564 -249.186556) (xy 387.385686 -249.229833) (xy 387.350068 -249.268581)
			(xy 387.309463 -249.302067) (xy 387.26464 -249.329653) (xy 387.216451 -249.350816) (xy 387.16581 -249.365156)
			(xy 387.11368 -249.372399) (xy 387.087364 -249.372882) (xy 387.060116 -249.372393) (xy 387.006176 -249.364633)
			(xy 386.953889 -249.349276) (xy 386.90432 -249.326634) (xy 386.858477 -249.297169) (xy 386.817294 -249.26148)
			(xy 386.781609 -249.220294) (xy 386.752148 -249.174448) (xy 386.729511 -249.124877) (xy 386.714159 -249.072589)
			(xy 386.706404 -249.018648) (xy 386.706404 -248.964152) (xy 386.714159 -248.910211) (xy 386.729511 -248.857923)
			(xy 386.752148 -248.808352) (xy 386.781609 -248.762506) (xy 386.817294 -248.72132) (xy 386.858477 -248.685631)
			(xy 386.90432 -248.656166) (xy 386.953889 -248.633524) (xy 387.006176 -248.618167) (xy 387.060116 -248.610407)
			(xy 387.087364 -248.609866) (xy 387.116779 -248.610408) (xy 387.174912 -248.61944) (xy 387.230967 -248.637295)
			(xy 387.283614 -248.663549) (xy 387.331603 -248.697579) (xy 387.373794 -248.738578) (xy 387.39191 -248.761758)
			(xy 387.399784 -248.771918) (xy 387.42239 -248.782586) (xy 387.532118 -248.77649) (xy 387.553708 -248.763536)
			(xy 387.560312 -248.752614) (xy 387.575099 -248.728785) (xy 387.610563 -248.685343) (xy 387.652001 -248.647557)
			(xy 387.698523 -248.616243) (xy 387.749127 -248.592073) (xy 387.802723 -248.575569) (xy 387.858157 -248.567086)
			(xy 387.886194 -248.566432) (xy 387.890766 -248.566432) (xy 387.916987 -248.567057) (xy 387.968888 -248.574619)
			(xy 388.019264 -248.58922) (xy 388.067164 -248.610585) (xy 388.089648 -248.62409) (xy 388.095744 -248.6279)
			(xy 388.111746 -248.632218) (xy 388.120485 -248.634314) (xy 388.13839 -248.632907) (xy 388.1547 -248.625388)
			(xy 388.161276 -248.619264) (xy 388.53237 -248.24817) (xy 388.532878 -248.247662) (xy 388.53946 -248.24028)
			(xy 388.546912 -248.221982) (xy 388.547356 -248.212102) (xy 388.547356 -247.439688) (xy 388.547235 -247.434875)
			(xy 388.545449 -247.425415) (xy 388.5438 -247.420892) (xy 388.533894 -247.395746) (xy 388.528052 -247.389142)
			(xy 388.510493 -247.368409) (xy 388.480805 -247.322907) (xy 388.457868 -247.273656) (xy 388.442145 -247.22165)
			(xy 388.433953 -247.167941) (xy 388.433457 -247.113613) (xy 388.436612 -247.086628) (xy 388.440618 -247.060105)
			(xy 388.455099 -247.008455) (xy 388.476662 -246.95934) (xy 388.504883 -246.913723) (xy 388.521702 -246.892826)
			(xy 388.528306 -246.884952) (xy 388.534148 -246.866156) (xy 388.132574 -242.33886) (xy 388.125716 -242.323366)
			(xy 388.119874 -242.31727) (xy 388.10064 -242.295925) (xy 388.068144 -242.248542) (xy 388.043108 -242.196828)
			(xy 388.026096 -242.141948) (xy 388.017492 -242.08514) (xy 388.017004 -242.056412) (xy 388.017505 -242.028971)
			(xy 388.025409 -241.97466) (xy 388.040998 -241.922037) (xy 388.063951 -241.872184) (xy 388.078472 -241.848894)
			(xy 388.083044 -241.841528) (xy 388.087108 -241.825272) (xy 388.015226 -241.013234) (xy 388.005574 -240.995454)
			(xy 387.9977 -240.98885) (xy 387.97619 -240.970644) (xy 387.93825 -240.928979) (xy 387.906857 -240.882182)
			(xy 387.882696 -240.831273) (xy 387.866292 -240.777362) (xy 387.858004 -240.721624) (xy 387.857492 -240.693448)
			(xy 387.857968 -240.666386) (xy 387.865623 -240.612805) (xy 387.880772 -240.560843) (xy 387.903111 -240.511544)
			(xy 387.932191 -240.465895) (xy 387.94944 -240.445036) (xy 387.956298 -240.437162) (xy 387.962394 -240.418112)
			(xy 387.829044 -238.913924) (xy 387.82117 -238.897414) (xy 387.814566 -238.891064) (xy 387.796107 -238.872523)
			(xy 387.763928 -238.83127) (xy 387.737698 -238.786) (xy 387.717912 -238.737567) (xy 387.70494 -238.686881)
			(xy 387.701536 -238.66094) (xy 387.700774 -238.655098) (xy 387.698996 -238.617506) (xy 387.699564 -238.587794)
			(xy 387.708781 -238.52909) (xy 387.726994 -238.472526) (xy 387.753761 -238.419472) (xy 387.770624 -238.395002)
			(xy 387.775958 -238.387382) (xy 387.780784 -238.37011) (xy 387.71195 -237.594394) (xy 387.710763 -237.585572)
			(xy 387.703234 -237.569458) (xy 387.697218 -237.562898) (xy 385.883912 -235.749592) (xy 385.8768 -235.742226)
			(xy 385.858004 -235.734606) (xy 377.51385 -235.734606) (xy 377.507491 -235.734771) (xy 377.495155 -235.737856)
			(xy 377.489466 -235.740702) (xy 377.469908 -235.75137) (xy 377.461272 -235.757466) (xy 377.456192 -235.761784)
			(xy 377.452636 -235.76661) (xy 377.434506 -235.790247) (xy 377.392147 -235.832128) (xy 377.343795 -235.86692)
			(xy 377.290624 -235.893776) (xy 377.233927 -235.912045) (xy 377.17508 -235.921284) (xy 377.145296 -235.921804)
			(xy 377.115512 -235.921253) (xy 377.056662 -235.912036) (xy 376.999961 -235.89378) (xy 376.946789 -235.866928)
			(xy 376.898439 -235.832134) (xy 376.856088 -235.790245) (xy 376.837956 -235.76661) (xy 376.8344 -235.761784)
			(xy 376.82932 -235.757466) (xy 376.82043 -235.75137) (xy 376.800872 -235.740702) (xy 376.795185 -235.737849)
			(xy 376.782848 -235.734754) (xy 376.776488 -235.734606) (xy 369.224814 -235.734606) (xy 369.214751 -235.735045)
			(xy 369.19617 -235.742782) (xy 369.188746 -235.749592) (xy 368.733832 -236.204506) (xy 368.726198 -236.213142)
			(xy 368.718704 -236.234905) (xy 368.719354 -236.246416) (xy 368.728498 -236.323124) (xy 368.728498 -236.323632)
			(xy 368.729935 -236.331886) (xy 368.737322 -236.346913) (xy 368.742976 -236.353096) (xy 368.752882 -236.363002)
			(xy 368.757708 -236.36605) (xy 368.780822 -236.381094) (xy 368.822866 -236.416784) (xy 368.859335 -236.458153)
			(xy 368.889469 -236.504341) (xy 368.91264 -236.554386) (xy 368.928367 -236.607245) (xy 368.936321 -236.661818)
			(xy 368.936778 -236.689392) (xy 368.936315 -236.716644) (xy 368.928559 -236.770595) (xy 368.913203 -236.822892)
			(xy 368.89854 -236.855) (xy 376.934982 -236.855) (xy 376.939053 -236.799378) (xy 376.951179 -236.744941)
			(xy 376.971102 -236.69285) (xy 376.998398 -236.644215) (xy 377.032484 -236.600072) (xy 377.072633 -236.561363)
			(xy 377.117991 -236.528912) (xy 377.167591 -236.503411) (xy 377.220375 -236.485404) (xy 377.275218 -236.475274)
			(xy 377.330952 -236.473237) (xy 377.386389 -236.479337) (xy 377.440346 -236.493443) (xy 377.491675 -236.515255)
			(xy 377.539281 -236.544309) (xy 377.582149 -236.579984) (xy 377.600979 -236.601) (xy 383.284982 -236.601)
			(xy 383.289053 -236.545378) (xy 383.301179 -236.490941) (xy 383.321102 -236.43885) (xy 383.348398 -236.390215)
			(xy 383.382484 -236.346072) (xy 383.422633 -236.307363) (xy 383.467991 -236.274912) (xy 383.517591 -236.249411)
			(xy 383.570375 -236.231404) (xy 383.625218 -236.221274) (xy 383.680952 -236.219237) (xy 383.736389 -236.225337)
			(xy 383.790346 -236.239443) (xy 383.841675 -236.261255) (xy 383.889281 -236.290309) (xy 383.932149 -236.325984)
			(xy 383.969366 -236.367521) (xy 384.000139 -236.414034) (xy 384.023811 -236.464531) (xy 384.039879 -236.517938)
			(xy 384.047999 -236.573114) (xy 384.048508 -236.601) (xy 384.047999 -236.628886) (xy 384.039879 -236.684062)
			(xy 384.023811 -236.737469) (xy 384.000139 -236.787966) (xy 383.969366 -236.834479) (xy 383.932149 -236.876016)
			(xy 383.889281 -236.911691) (xy 383.841675 -236.940745) (xy 383.790346 -236.962557) (xy 383.736389 -236.976663)
			(xy 383.680952 -236.982763) (xy 383.625218 -236.980726) (xy 383.570375 -236.970596) (xy 383.517591 -236.952589)
			(xy 383.467991 -236.927088) (xy 383.422633 -236.894637) (xy 383.382484 -236.855928) (xy 383.348398 -236.811785)
			(xy 383.321102 -236.76315) (xy 383.301179 -236.711059) (xy 383.289053 -236.656622) (xy 383.284982 -236.601)
			(xy 377.600979 -236.601) (xy 377.619366 -236.621521) (xy 377.650139 -236.668034) (xy 377.673811 -236.718531)
			(xy 377.689879 -236.771938) (xy 377.697999 -236.827114) (xy 377.698508 -236.855) (xy 377.697999 -236.882886)
			(xy 377.689879 -236.938062) (xy 377.673811 -236.991469) (xy 377.650139 -237.041966) (xy 377.619366 -237.088479)
			(xy 377.582149 -237.130016) (xy 377.539281 -237.165691) (xy 377.491675 -237.194745) (xy 377.440346 -237.216557)
			(xy 377.386389 -237.230663) (xy 377.330952 -237.236763) (xy 377.275218 -237.234726) (xy 377.220375 -237.224596)
			(xy 377.167591 -237.206589) (xy 377.117991 -237.181088) (xy 377.072633 -237.148637) (xy 377.032484 -237.109928)
			(xy 376.998398 -237.065785) (xy 376.971102 -237.01715) (xy 376.951179 -236.965059) (xy 376.939053 -236.910622)
			(xy 376.934982 -236.855) (xy 368.89854 -236.855) (xy 368.890561 -236.872471) (xy 368.861093 -236.918323)
			(xy 368.825399 -236.959514) (xy 368.784205 -236.995206) (xy 368.738352 -237.024671) (xy 368.688771 -237.047311)
			(xy 368.636473 -237.062664) (xy 368.582522 -237.070417) (xy 368.55527 -237.0709) (xy 368.527694 -237.070418)
			(xy 368.473116 -237.062485) (xy 368.42025 -237.046773) (xy 368.370199 -237.02361) (xy 368.324005 -236.99348)
			(xy 368.282632 -236.957011) (xy 368.246944 -236.914963) (xy 368.231928 -236.89183) (xy 368.22888 -236.887004)
			(xy 368.212878 -236.871002) (xy 368.197638 -236.863636) (xy 368.189002 -236.86262) (xy 368.112294 -236.853476)
			(xy 368.100767 -236.85264) (xy 368.078952 -236.860195) (xy 368.070384 -236.867954) (xy 367.180368 -237.75797)
			(xy 370.937534 -237.75797) (xy 370.941605 -237.702348) (xy 370.953731 -237.647911) (xy 370.973654 -237.59582)
			(xy 371.00095 -237.547185) (xy 371.035036 -237.503042) (xy 371.075185 -237.464333) (xy 371.120543 -237.431882)
			(xy 371.170143 -237.406381) (xy 371.222927 -237.388374) (xy 371.27777 -237.378244) (xy 371.333504 -237.376207)
			(xy 371.388941 -237.382307) (xy 371.442898 -237.396413) (xy 371.494227 -237.418225) (xy 371.541833 -237.447279)
			(xy 371.584701 -237.482954) (xy 371.621918 -237.524491) (xy 371.652691 -237.571004) (xy 371.676363 -237.621501)
			(xy 371.692431 -237.674908) (xy 371.700551 -237.730084) (xy 371.70106 -237.75797) (xy 371.700551 -237.785856)
			(xy 371.692431 -237.841032) (xy 371.676363 -237.894439) (xy 371.652691 -237.944936) (xy 371.621918 -237.991449)
			(xy 371.584701 -238.032986) (xy 371.541833 -238.068661) (xy 371.494227 -238.097715) (xy 371.442898 -238.119527)
			(xy 371.388941 -238.133633) (xy 371.333504 -238.139733) (xy 371.27777 -238.137696) (xy 371.222927 -238.127566)
			(xy 371.170143 -238.109559) (xy 371.120543 -238.084058) (xy 371.075185 -238.051607) (xy 371.035036 -238.012898)
			(xy 371.00095 -237.968755) (xy 370.973654 -237.92012) (xy 370.953731 -237.868029) (xy 370.941605 -237.813592)
			(xy 370.937534 -237.75797) (xy 367.180368 -237.75797) (xy 367.001044 -237.937294) (xy 366.992562 -237.946648)
			(xy 366.985234 -237.970776) (xy 366.987074 -237.983268) (xy 367.006632 -238.078772) (xy 367.022888 -238.09833)
			(xy 367.034572 -238.103156) (xy 367.060581 -238.114264) (xy 367.109271 -238.143035) (xy 367.153178 -238.178682)
			(xy 367.191338 -238.220422) (xy 367.222914 -238.267341) (xy 367.247215 -238.318409) (xy 367.25771 -238.352838)
			(xy 381.07823 -238.352838) (xy 381.082301 -238.297216) (xy 381.094427 -238.242779) (xy 381.11435 -238.190688)
			(xy 381.141646 -238.142053) (xy 381.175732 -238.09791) (xy 381.215881 -238.059201) (xy 381.261239 -238.02675)
			(xy 381.310839 -238.001249) (xy 381.363623 -237.983242) (xy 381.418466 -237.973112) (xy 381.4742 -237.971075)
			(xy 381.529637 -237.977175) (xy 381.583594 -237.991281) (xy 381.599405 -237.998) (xy 383.030982 -237.998)
			(xy 383.035053 -237.942378) (xy 383.047179 -237.887941) (xy 383.067102 -237.83585) (xy 383.094398 -237.787215)
			(xy 383.128484 -237.743072) (xy 383.168633 -237.704363) (xy 383.213991 -237.671912) (xy 383.263591 -237.646411)
			(xy 383.316375 -237.628404) (xy 383.371218 -237.618274) (xy 383.426952 -237.616237) (xy 383.482389 -237.622337)
			(xy 383.536346 -237.636443) (xy 383.587675 -237.658255) (xy 383.635281 -237.687309) (xy 383.678149 -237.722984)
			(xy 383.715366 -237.764521) (xy 383.746139 -237.811034) (xy 383.769811 -237.861531) (xy 383.785879 -237.914938)
			(xy 383.793999 -237.970114) (xy 383.794508 -237.998) (xy 383.793999 -238.025886) (xy 383.785879 -238.081062)
			(xy 383.769811 -238.134469) (xy 383.746139 -238.184966) (xy 383.715366 -238.231479) (xy 383.678149 -238.273016)
			(xy 383.635281 -238.308691) (xy 383.587675 -238.337745) (xy 383.536346 -238.359557) (xy 383.482389 -238.373663)
			(xy 383.426952 -238.379763) (xy 383.371218 -238.377726) (xy 383.316375 -238.367596) (xy 383.263591 -238.349589)
			(xy 383.213991 -238.324088) (xy 383.168633 -238.291637) (xy 383.128484 -238.252928) (xy 383.094398 -238.208785)
			(xy 383.067102 -238.16015) (xy 383.047179 -238.108059) (xy 383.035053 -238.053622) (xy 383.030982 -237.998)
			(xy 381.599405 -237.998) (xy 381.634923 -238.013093) (xy 381.682529 -238.042147) (xy 381.725397 -238.077822)
			(xy 381.762614 -238.119359) (xy 381.793387 -238.165872) (xy 381.817059 -238.216369) (xy 381.833127 -238.269776)
			(xy 381.841247 -238.324952) (xy 381.841756 -238.352838) (xy 381.841247 -238.380724) (xy 381.833127 -238.4359)
			(xy 381.82648 -238.457994) (xy 384.263898 -238.457994) (xy 384.267969 -238.402372) (xy 384.280095 -238.347935)
			(xy 384.300018 -238.295844) (xy 384.327314 -238.247209) (xy 384.3614 -238.203066) (xy 384.401549 -238.164357)
			(xy 384.446907 -238.131906) (xy 384.496507 -238.106405) (xy 384.549291 -238.088398) (xy 384.604134 -238.078268)
			(xy 384.659868 -238.076231) (xy 384.715305 -238.082331) (xy 384.769262 -238.096437) (xy 384.820591 -238.118249)
			(xy 384.868197 -238.147303) (xy 384.911065 -238.182978) (xy 384.948282 -238.224515) (xy 384.979055 -238.271028)
			(xy 385.002727 -238.321525) (xy 385.018795 -238.374932) (xy 385.026915 -238.430108) (xy 385.027424 -238.457994)
			(xy 385.026915 -238.48588) (xy 385.018795 -238.541056) (xy 385.002727 -238.594463) (xy 384.979055 -238.64496)
			(xy 384.948282 -238.691473) (xy 384.911065 -238.73301) (xy 384.868197 -238.768685) (xy 384.820591 -238.797739)
			(xy 384.769262 -238.819551) (xy 384.715305 -238.833657) (xy 384.659868 -238.839757) (xy 384.604134 -238.83772)
			(xy 384.549291 -238.82759) (xy 384.496507 -238.809583) (xy 384.446907 -238.784082) (xy 384.401549 -238.751631)
			(xy 384.3614 -238.712922) (xy 384.327314 -238.668779) (xy 384.300018 -238.620144) (xy 384.280095 -238.568053)
			(xy 384.267969 -238.513616) (xy 384.263898 -238.457994) (xy 381.82648 -238.457994) (xy 381.817059 -238.489307)
			(xy 381.793387 -238.539804) (xy 381.762614 -238.586317) (xy 381.725397 -238.627854) (xy 381.682529 -238.663529)
			(xy 381.634923 -238.692583) (xy 381.583594 -238.714395) (xy 381.529637 -238.728501) (xy 381.4742 -238.734601)
			(xy 381.418466 -238.732564) (xy 381.363623 -238.722434) (xy 381.310839 -238.704427) (xy 381.261239 -238.678926)
			(xy 381.215881 -238.646475) (xy 381.175732 -238.607766) (xy 381.141646 -238.563623) (xy 381.11435 -238.514988)
			(xy 381.094427 -238.462897) (xy 381.082301 -238.40846) (xy 381.07823 -238.352838) (xy 367.25771 -238.352838)
			(xy 367.263706 -238.372507) (xy 367.272026 -238.428446) (xy 367.27257 -238.456724) (xy 367.272105 -238.483975)
			(xy 367.264345 -238.537921) (xy 367.248987 -238.590214) (xy 367.226342 -238.639789) (xy 367.196873 -238.685636)
			(xy 367.161179 -238.726823) (xy 367.119986 -238.76251) (xy 367.074134 -238.791972) (xy 367.024556 -238.814608)
			(xy 366.97226 -238.829958) (xy 366.918313 -238.837709) (xy 366.891062 -238.838232) (xy 366.862785 -238.837717)
			(xy 366.806852 -238.829368) (xy 366.752762 -238.812858) (xy 366.7017 -238.788548) (xy 366.654784 -238.756971)
			(xy 366.61304 -238.718817) (xy 366.577381 -238.674923) (xy 366.548589 -238.626248) (xy 366.537494 -238.600234)
			(xy 366.532668 -238.58855) (xy 366.51311 -238.572294) (xy 366.417606 -238.552736) (xy 366.405117 -238.55093)
			(xy 366.381001 -238.558254) (xy 366.371632 -238.566706) (xy 365.290354 -239.647984) (xy 375.566178 -239.647984)
			(xy 375.566664 -239.620733) (xy 375.57442 -239.566785) (xy 375.589775 -239.51449) (xy 375.612417 -239.464913)
			(xy 375.641883 -239.419063) (xy 375.677574 -239.377872) (xy 375.718765 -239.342181) (xy 375.764615 -239.312715)
			(xy 375.814192 -239.290073) (xy 375.866487 -239.274718) (xy 375.920435 -239.266962) (xy 375.974937 -239.266962)
			(xy 376.028885 -239.274718) (xy 376.08118 -239.290073) (xy 376.130757 -239.312715) (xy 376.176607 -239.342181)
			(xy 376.217798 -239.377872) (xy 376.253489 -239.419063) (xy 376.282955 -239.464913) (xy 376.305597 -239.51449)
			(xy 376.320952 -239.566785) (xy 376.328708 -239.620733) (xy 376.329194 -239.647984) (xy 376.328649 -239.677596)
			(xy 376.3195 -239.736109) (xy 376.314854 -239.7506) (xy 376.833892 -239.7506) (xy 376.834378 -239.723349)
			(xy 376.842134 -239.669401) (xy 376.857489 -239.617106) (xy 376.880131 -239.567529) (xy 376.909597 -239.521679)
			(xy 376.945288 -239.480488) (xy 376.986479 -239.444797) (xy 377.032329 -239.415331) (xy 377.081906 -239.392689)
			(xy 377.134201 -239.377334) (xy 377.188149 -239.369578) (xy 377.242651 -239.369578) (xy 377.296599 -239.377334)
			(xy 377.348894 -239.392689) (xy 377.398471 -239.415331) (xy 377.444321 -239.444797) (xy 377.485512 -239.480488)
			(xy 377.521203 -239.521679) (xy 377.533652 -239.54105) (xy 379.709932 -239.54105) (xy 379.714003 -239.485428)
			(xy 379.726129 -239.430991) (xy 379.746052 -239.3789) (xy 379.773348 -239.330265) (xy 379.807434 -239.286122)
			(xy 379.847583 -239.247413) (xy 379.892941 -239.214962) (xy 379.942541 -239.189461) (xy 379.995325 -239.171454)
			(xy 380.050168 -239.161324) (xy 380.105902 -239.159287) (xy 380.161339 -239.165387) (xy 380.215296 -239.179493)
			(xy 380.266625 -239.201305) (xy 380.314231 -239.230359) (xy 380.357099 -239.266034) (xy 380.394316 -239.307571)
			(xy 380.425089 -239.354084) (xy 380.448761 -239.404581) (xy 380.464829 -239.457988) (xy 380.472949 -239.513164)
			(xy 380.473458 -239.54105) (xy 380.472949 -239.568936) (xy 380.464829 -239.624112) (xy 380.448761 -239.677519)
			(xy 380.425089 -239.728016) (xy 380.394316 -239.774529) (xy 380.361592 -239.811052) (xy 383.030982 -239.811052)
			(xy 383.035053 -239.75543) (xy 383.047179 -239.700993) (xy 383.067102 -239.648902) (xy 383.094398 -239.600267)
			(xy 383.128484 -239.556124) (xy 383.168633 -239.517415) (xy 383.213991 -239.484964) (xy 383.263591 -239.459463)
			(xy 383.316375 -239.441456) (xy 383.371218 -239.431326) (xy 383.426952 -239.429289) (xy 383.482389 -239.435389)
			(xy 383.536346 -239.449495) (xy 383.587675 -239.471307) (xy 383.635281 -239.500361) (xy 383.678149 -239.536036)
			(xy 383.715366 -239.577573) (xy 383.746139 -239.624086) (xy 383.769811 -239.674583) (xy 383.785879 -239.72799)
			(xy 383.793999 -239.783166) (xy 383.794508 -239.811052) (xy 383.793999 -239.838938) (xy 383.785879 -239.894114)
			(xy 383.769811 -239.947521) (xy 383.746139 -239.998018) (xy 383.715366 -240.044531) (xy 383.678149 -240.086068)
			(xy 383.635281 -240.121743) (xy 383.587675 -240.150797) (xy 383.536346 -240.172609) (xy 383.482389 -240.186715)
			(xy 383.426952 -240.192815) (xy 383.371218 -240.190778) (xy 383.316375 -240.180648) (xy 383.263591 -240.162641)
			(xy 383.213991 -240.13714) (xy 383.168633 -240.104689) (xy 383.128484 -240.06598) (xy 383.094398 -240.021837)
			(xy 383.067102 -239.973202) (xy 383.047179 -239.921111) (xy 383.035053 -239.866674) (xy 383.030982 -239.811052)
			(xy 380.361592 -239.811052) (xy 380.357099 -239.816066) (xy 380.314231 -239.851741) (xy 380.266625 -239.880795)
			(xy 380.215296 -239.902607) (xy 380.161339 -239.916713) (xy 380.105902 -239.922813) (xy 380.050168 -239.920776)
			(xy 379.995325 -239.910646) (xy 379.942541 -239.892639) (xy 379.892941 -239.867138) (xy 379.847583 -239.834687)
			(xy 379.807434 -239.795978) (xy 379.773348 -239.751835) (xy 379.746052 -239.7032) (xy 379.726129 -239.651109)
			(xy 379.714003 -239.596672) (xy 379.709932 -239.54105) (xy 377.533652 -239.54105) (xy 377.550669 -239.567529)
			(xy 377.573311 -239.617106) (xy 377.588666 -239.669401) (xy 377.596422 -239.723349) (xy 377.596908 -239.7506)
			(xy 377.596442 -239.776633) (xy 377.589357 -239.828214) (xy 377.575331 -239.878355) (xy 377.554625 -239.926127)
			(xy 377.527622 -239.970643) (xy 377.511564 -239.991138) (xy 377.502985 -240.002322) (xy 377.491821 -240.028194)
			(xy 377.488158 -240.056133) (xy 377.492276 -240.084009) (xy 377.503862 -240.109696) (xy 377.52203 -240.131235)
			(xy 377.545397 -240.146984) (xy 377.572179 -240.155741) (xy 377.58624 -240.156746) (xy 377.612762 -240.158226)
			(xy 377.66503 -240.167703) (xy 377.715479 -240.184337) (xy 377.763133 -240.207808) (xy 377.807071 -240.237661)
			(xy 377.846444 -240.273319) (xy 377.880491 -240.314094) (xy 377.908554 -240.359197) (xy 377.930089 -240.407756)
			(xy 377.944682 -240.458833) (xy 377.95205 -240.51144) (xy 377.952508 -240.538) (xy 377.952022 -240.565251)
			(xy 377.944266 -240.619199) (xy 377.930818 -240.665) (xy 384.808982 -240.665) (xy 384.813053 -240.609378)
			(xy 384.825179 -240.554941) (xy 384.845102 -240.50285) (xy 384.872398 -240.454215) (xy 384.906484 -240.410072)
			(xy 384.946633 -240.371363) (xy 384.991991 -240.338912) (xy 385.041591 -240.313411) (xy 385.094375 -240.295404)
			(xy 385.149218 -240.285274) (xy 385.204952 -240.283237) (xy 385.260389 -240.289337) (xy 385.314346 -240.303443)
			(xy 385.365675 -240.325255) (xy 385.413281 -240.354309) (xy 385.456149 -240.389984) (xy 385.493366 -240.431521)
			(xy 385.524139 -240.478034) (xy 385.547811 -240.528531) (xy 385.563879 -240.581938) (xy 385.571999 -240.637114)
			(xy 385.572508 -240.665) (xy 386.078982 -240.665) (xy 386.083053 -240.609378) (xy 386.095179 -240.554941)
			(xy 386.115102 -240.50285) (xy 386.142398 -240.454215) (xy 386.176484 -240.410072) (xy 386.216633 -240.371363)
			(xy 386.261991 -240.338912) (xy 386.311591 -240.313411) (xy 386.364375 -240.295404) (xy 386.419218 -240.285274)
			(xy 386.474952 -240.283237) (xy 386.530389 -240.289337) (xy 386.584346 -240.303443) (xy 386.635675 -240.325255)
			(xy 386.683281 -240.354309) (xy 386.726149 -240.389984) (xy 386.763366 -240.431521) (xy 386.794139 -240.478034)
			(xy 386.817811 -240.528531) (xy 386.833879 -240.581938) (xy 386.841999 -240.637114) (xy 386.842508 -240.665)
			(xy 386.841999 -240.692886) (xy 386.833879 -240.748062) (xy 386.817811 -240.801469) (xy 386.794139 -240.851966)
			(xy 386.763366 -240.898479) (xy 386.726149 -240.940016) (xy 386.683281 -240.975691) (xy 386.635675 -241.004745)
			(xy 386.584346 -241.026557) (xy 386.530389 -241.040663) (xy 386.474952 -241.046763) (xy 386.419218 -241.044726)
			(xy 386.364375 -241.034596) (xy 386.311591 -241.016589) (xy 386.261991 -240.991088) (xy 386.216633 -240.958637)
			(xy 386.176484 -240.919928) (xy 386.142398 -240.875785) (xy 386.115102 -240.82715) (xy 386.095179 -240.775059)
			(xy 386.083053 -240.720622) (xy 386.078982 -240.665) (xy 385.572508 -240.665) (xy 385.571999 -240.692886)
			(xy 385.563879 -240.748062) (xy 385.547811 -240.801469) (xy 385.524139 -240.851966) (xy 385.493366 -240.898479)
			(xy 385.456149 -240.940016) (xy 385.413281 -240.975691) (xy 385.365675 -241.004745) (xy 385.314346 -241.026557)
			(xy 385.260389 -241.040663) (xy 385.204952 -241.046763) (xy 385.149218 -241.044726) (xy 385.094375 -241.034596)
			(xy 385.041591 -241.016589) (xy 384.991991 -240.991088) (xy 384.946633 -240.958637) (xy 384.906484 -240.919928)
			(xy 384.872398 -240.875785) (xy 384.845102 -240.82715) (xy 384.825179 -240.775059) (xy 384.813053 -240.720622)
			(xy 384.808982 -240.665) (xy 377.930818 -240.665) (xy 377.928911 -240.671494) (xy 377.906269 -240.721071)
			(xy 377.876803 -240.766921) (xy 377.841112 -240.808112) (xy 377.799921 -240.843803) (xy 377.754071 -240.873269)
			(xy 377.704494 -240.895911) (xy 377.652199 -240.911266) (xy 377.598251 -240.919022) (xy 377.543749 -240.919022)
			(xy 377.489801 -240.911266) (xy 377.437506 -240.895911) (xy 377.387929 -240.873269) (xy 377.342079 -240.843803)
			(xy 377.300888 -240.808112) (xy 377.265197 -240.766921) (xy 377.235731 -240.721071) (xy 377.213089 -240.671494)
			(xy 377.197734 -240.619199) (xy 377.189978 -240.565251) (xy 377.189492 -240.538) (xy 377.189958 -240.511967)
			(xy 377.197043 -240.460386) (xy 377.211069 -240.410245) (xy 377.231775 -240.362473) (xy 377.258778 -240.317957)
			(xy 377.274836 -240.297462) (xy 377.283415 -240.286278) (xy 377.294579 -240.260406) (xy 377.298242 -240.232467)
			(xy 377.294124 -240.204591) (xy 377.282538 -240.178904) (xy 377.26437 -240.157365) (xy 377.241003 -240.141616)
			(xy 377.214221 -240.132859) (xy 377.20016 -240.131854) (xy 377.173638 -240.130374) (xy 377.12137 -240.120897)
			(xy 377.070921 -240.104263) (xy 377.023267 -240.080792) (xy 376.979329 -240.050939) (xy 376.939956 -240.015281)
			(xy 376.905909 -239.974506) (xy 376.877846 -239.929403) (xy 376.856311 -239.880844) (xy 376.841718 -239.829767)
			(xy 376.83435 -239.77716) (xy 376.833892 -239.7506) (xy 376.314854 -239.7506) (xy 376.301419 -239.792505)
			(xy 376.274839 -239.845429) (xy 376.240401 -239.89361) (xy 376.198931 -239.935891) (xy 376.151425 -239.971256)
			(xy 376.125486 -239.98555) (xy 376.113296 -239.99239) (xy 376.092985 -240.011581) (xy 376.078637 -240.035561)
			(xy 376.071328 -240.062532) (xy 376.071605 -240.090474) (xy 376.079448 -240.117295) (xy 376.094268 -240.140985)
			(xy 376.114956 -240.15977) (xy 376.127264 -240.166398) (xy 376.150661 -240.178638) (xy 376.194185 -240.208533)
			(xy 376.233167 -240.244148) (xy 376.266861 -240.284802) (xy 376.294624 -240.329715) (xy 376.315924 -240.37803)
			(xy 376.330354 -240.428822) (xy 376.337637 -240.481119) (xy 376.338084 -240.50752) (xy 376.337598 -240.534771)
			(xy 376.329842 -240.588719) (xy 376.314487 -240.641014) (xy 376.291845 -240.690591) (xy 376.262379 -240.736441)
			(xy 376.226688 -240.777632) (xy 376.185497 -240.813323) (xy 376.139647 -240.842789) (xy 376.09007 -240.865431)
			(xy 376.037775 -240.880786) (xy 375.983827 -240.888542) (xy 375.929325 -240.888542) (xy 375.875377 -240.880786)
			(xy 375.823082 -240.865431) (xy 375.773505 -240.842789) (xy 375.727655 -240.813323) (xy 375.686464 -240.777632)
			(xy 375.650773 -240.736441) (xy 375.621307 -240.690591) (xy 375.598665 -240.641014) (xy 375.58331 -240.588719)
			(xy 375.575554 -240.534771) (xy 375.575068 -240.50752) (xy 375.575583 -240.477907) (xy 375.584733 -240.419391)
			(xy 375.602818 -240.362993) (xy 375.629401 -240.310067) (xy 375.663845 -240.261885) (xy 375.705321 -240.219606)
			(xy 375.752833 -240.184245) (xy 375.778776 -240.169954) (xy 375.790956 -240.163103) (xy 375.811255 -240.143908)
			(xy 375.825593 -240.119932) (xy 375.832897 -240.092966) (xy 375.83262 -240.065031) (xy 375.824784 -240.038216)
			(xy 375.809974 -240.014527) (xy 375.789299 -239.995739) (xy 375.776998 -239.989106) (xy 375.753594 -239.97688)
			(xy 375.710072 -239.946981) (xy 375.671091 -239.911363) (xy 375.637398 -239.870707) (xy 375.609637 -239.825792)
			(xy 375.588337 -239.777476) (xy 375.573908 -239.726683) (xy 375.566625 -239.674385) (xy 375.566178 -239.647984)
			(xy 365.290354 -239.647984) (xy 363.713268 -241.22507) (xy 363.705869 -241.231915) (xy 363.687271 -241.239642)
			(xy 363.6772 -241.240056) (xy 327.93178 -241.240056) (xy 327.904602 -241.26063) (xy 327.90003 -241.276886)
			(xy 327.893354 -241.298984) (xy 371.174008 -241.298984) (xy 371.178079 -241.243362) (xy 371.190205 -241.188925)
			(xy 371.210128 -241.136834) (xy 371.237424 -241.088199) (xy 371.27151 -241.044056) (xy 371.311659 -241.005347)
			(xy 371.357017 -240.972896) (xy 371.406617 -240.947395) (xy 371.459401 -240.929388) (xy 371.514244 -240.919258)
			(xy 371.569978 -240.917221) (xy 371.625415 -240.923321) (xy 371.679372 -240.937427) (xy 371.730701 -240.959239)
			(xy 371.778307 -240.988293) (xy 371.821175 -241.023968) (xy 371.858392 -241.065505) (xy 371.889165 -241.112018)
			(xy 371.905131 -241.146076) (xy 374.102628 -241.146076) (xy 374.106699 -241.090454) (xy 374.118825 -241.036017)
			(xy 374.138748 -240.983926) (xy 374.166044 -240.935291) (xy 374.20013 -240.891148) (xy 374.240279 -240.852439)
			(xy 374.285637 -240.819988) (xy 374.335237 -240.794487) (xy 374.388021 -240.77648) (xy 374.442864 -240.76635)
			(xy 374.498598 -240.764313) (xy 374.554035 -240.770413) (xy 374.607992 -240.784519) (xy 374.659321 -240.806331)
			(xy 374.706927 -240.835385) (xy 374.749795 -240.87106) (xy 374.787012 -240.912597) (xy 374.817785 -240.95911)
			(xy 374.841457 -241.009607) (xy 374.857525 -241.063014) (xy 374.865645 -241.11819) (xy 374.866154 -241.146076)
			(xy 374.865645 -241.173962) (xy 374.857525 -241.229138) (xy 374.841457 -241.282545) (xy 374.828035 -241.311176)
			(xy 379.62027 -241.311176) (xy 379.624341 -241.255554) (xy 379.636467 -241.201117) (xy 379.65639 -241.149026)
			(xy 379.683686 -241.100391) (xy 379.717772 -241.056248) (xy 379.757921 -241.017539) (xy 379.803279 -240.985088)
			(xy 379.852879 -240.959587) (xy 379.905663 -240.94158) (xy 379.960506 -240.93145) (xy 380.01624 -240.929413)
			(xy 380.071677 -240.935513) (xy 380.125634 -240.949619) (xy 380.176963 -240.971431) (xy 380.224569 -241.000485)
			(xy 380.267437 -241.03616) (xy 380.304654 -241.077697) (xy 380.335427 -241.12421) (xy 380.359099 -241.174707)
			(xy 380.375167 -241.228114) (xy 380.383287 -241.28329) (xy 380.383796 -241.311176) (xy 380.383287 -241.339062)
			(xy 380.375167 -241.394238) (xy 380.36531 -241.427) (xy 383.030982 -241.427) (xy 383.035053 -241.371378)
			(xy 383.047179 -241.316941) (xy 383.067102 -241.26485) (xy 383.094398 -241.216215) (xy 383.128484 -241.172072)
			(xy 383.168633 -241.133363) (xy 383.213991 -241.100912) (xy 383.263591 -241.075411) (xy 383.316375 -241.057404)
			(xy 383.371218 -241.047274) (xy 383.426952 -241.045237) (xy 383.482389 -241.051337) (xy 383.536346 -241.065443)
			(xy 383.587675 -241.087255) (xy 383.635281 -241.116309) (xy 383.678149 -241.151984) (xy 383.715366 -241.193521)
			(xy 383.746139 -241.240034) (xy 383.769811 -241.290531) (xy 383.785879 -241.343938) (xy 383.793999 -241.399114)
			(xy 383.794026 -241.400584) (xy 384.162552 -241.400584) (xy 384.166623 -241.344962) (xy 384.178749 -241.290525)
			(xy 384.198672 -241.238434) (xy 384.225968 -241.189799) (xy 384.260054 -241.145656) (xy 384.300203 -241.106947)
			(xy 384.345561 -241.074496) (xy 384.395161 -241.048995) (xy 384.447945 -241.030988) (xy 384.502788 -241.020858)
			(xy 384.558522 -241.018821) (xy 384.613959 -241.024921) (xy 384.667916 -241.039027) (xy 384.719245 -241.060839)
			(xy 384.766851 -241.089893) (xy 384.809719 -241.125568) (xy 384.846936 -241.167105) (xy 384.850836 -241.173)
			(xy 386.840982 -241.173) (xy 386.845053 -241.117378) (xy 386.857179 -241.062941) (xy 386.877102 -241.01085)
			(xy 386.904398 -240.962215) (xy 386.938484 -240.918072) (xy 386.978633 -240.879363) (xy 387.023991 -240.846912)
			(xy 387.073591 -240.821411) (xy 387.126375 -240.803404) (xy 387.181218 -240.793274) (xy 387.236952 -240.791237)
			(xy 387.292389 -240.797337) (xy 387.346346 -240.811443) (xy 387.397675 -240.833255) (xy 387.445281 -240.862309)
			(xy 387.488149 -240.897984) (xy 387.525366 -240.939521) (xy 387.556139 -240.986034) (xy 387.579811 -241.036531)
			(xy 387.595879 -241.089938) (xy 387.603999 -241.145114) (xy 387.604508 -241.173) (xy 387.603999 -241.200886)
			(xy 387.595879 -241.256062) (xy 387.579811 -241.309469) (xy 387.556139 -241.359966) (xy 387.525366 -241.406479)
			(xy 387.488149 -241.448016) (xy 387.445281 -241.483691) (xy 387.397675 -241.512745) (xy 387.346346 -241.534557)
			(xy 387.292389 -241.548663) (xy 387.236952 -241.554763) (xy 387.181218 -241.552726) (xy 387.126375 -241.542596)
			(xy 387.073591 -241.524589) (xy 387.023991 -241.499088) (xy 386.978633 -241.466637) (xy 386.938484 -241.427928)
			(xy 386.904398 -241.383785) (xy 386.877102 -241.33515) (xy 386.857179 -241.283059) (xy 386.845053 -241.228622)
			(xy 386.840982 -241.173) (xy 384.850836 -241.173) (xy 384.877709 -241.213618) (xy 384.901381 -241.264115)
			(xy 384.917449 -241.317522) (xy 384.925569 -241.372698) (xy 384.926078 -241.400584) (xy 384.925569 -241.42847)
			(xy 384.917449 -241.483646) (xy 384.901381 -241.537053) (xy 384.877709 -241.58755) (xy 384.846936 -241.634063)
			(xy 384.809719 -241.6756) (xy 384.766851 -241.711275) (xy 384.719245 -241.740329) (xy 384.667916 -241.762141)
			(xy 384.613959 -241.776247) (xy 384.558522 -241.782347) (xy 384.502788 -241.78031) (xy 384.447945 -241.77018)
			(xy 384.395161 -241.752173) (xy 384.345561 -241.726672) (xy 384.300203 -241.694221) (xy 384.260054 -241.655512)
			(xy 384.225968 -241.611369) (xy 384.198672 -241.562734) (xy 384.178749 -241.510643) (xy 384.166623 -241.456206)
			(xy 384.162552 -241.400584) (xy 383.794026 -241.400584) (xy 383.794508 -241.427) (xy 383.793999 -241.454886)
			(xy 383.785879 -241.510062) (xy 383.769811 -241.563469) (xy 383.746139 -241.613966) (xy 383.715366 -241.660479)
			(xy 383.678149 -241.702016) (xy 383.635281 -241.737691) (xy 383.587675 -241.766745) (xy 383.536346 -241.788557)
			(xy 383.482389 -241.802663) (xy 383.426952 -241.808763) (xy 383.371218 -241.806726) (xy 383.316375 -241.796596)
			(xy 383.263591 -241.778589) (xy 383.213991 -241.753088) (xy 383.168633 -241.720637) (xy 383.128484 -241.681928)
			(xy 383.094398 -241.637785) (xy 383.067102 -241.58915) (xy 383.047179 -241.537059) (xy 383.035053 -241.482622)
			(xy 383.030982 -241.427) (xy 380.36531 -241.427) (xy 380.359099 -241.447645) (xy 380.335427 -241.498142)
			(xy 380.304654 -241.544655) (xy 380.267437 -241.586192) (xy 380.224569 -241.621867) (xy 380.176963 -241.650921)
			(xy 380.125634 -241.672733) (xy 380.071677 -241.686839) (xy 380.01624 -241.692939) (xy 379.960506 -241.690902)
			(xy 379.905663 -241.680772) (xy 379.852879 -241.662765) (xy 379.803279 -241.637264) (xy 379.757921 -241.604813)
			(xy 379.717772 -241.566104) (xy 379.683686 -241.521961) (xy 379.65639 -241.473326) (xy 379.636467 -241.421235)
			(xy 379.624341 -241.366798) (xy 379.62027 -241.311176) (xy 374.828035 -241.311176) (xy 374.817785 -241.333042)
			(xy 374.787012 -241.379555) (xy 374.749795 -241.421092) (xy 374.706927 -241.456767) (xy 374.659321 -241.485821)
			(xy 374.607992 -241.507633) (xy 374.554035 -241.521739) (xy 374.498598 -241.527839) (xy 374.442864 -241.525802)
			(xy 374.388021 -241.515672) (xy 374.335237 -241.497665) (xy 374.285637 -241.472164) (xy 374.240279 -241.439713)
			(xy 374.20013 -241.401004) (xy 374.166044 -241.356861) (xy 374.138748 -241.308226) (xy 374.118825 -241.256135)
			(xy 374.106699 -241.201698) (xy 374.102628 -241.146076) (xy 371.905131 -241.146076) (xy 371.912837 -241.162515)
			(xy 371.928905 -241.215922) (xy 371.937025 -241.271098) (xy 371.937534 -241.298984) (xy 371.937025 -241.32687)
			(xy 371.928905 -241.382046) (xy 371.912837 -241.435453) (xy 371.889165 -241.48595) (xy 371.858392 -241.532463)
			(xy 371.821175 -241.574) (xy 371.778307 -241.609675) (xy 371.730701 -241.638729) (xy 371.679372 -241.660541)
			(xy 371.625415 -241.674647) (xy 371.569978 -241.680747) (xy 371.514244 -241.67871) (xy 371.459401 -241.66858)
			(xy 371.406617 -241.650573) (xy 371.357017 -241.625072) (xy 371.311659 -241.592621) (xy 371.27151 -241.553912)
			(xy 371.237424 -241.509769) (xy 371.210128 -241.461134) (xy 371.190205 -241.409043) (xy 371.178079 -241.354606)
			(xy 371.174008 -241.298984) (xy 327.893354 -241.298984) (xy 327.892089 -241.303172) (xy 327.869706 -241.353313)
			(xy 327.840368 -241.399728) (xy 327.804679 -241.441458) (xy 327.763377 -241.477642) (xy 327.717316 -241.507532)
			(xy 327.667445 -241.53051) (xy 327.614796 -241.546103) (xy 327.560455 -241.553988) (xy 327.533 -241.554508)
			(xy 327.505542 -241.55403) (xy 327.451194 -241.546154) (xy 327.398538 -241.530565) (xy 327.348661 -241.507586)
			(xy 327.302596 -241.47769) (xy 327.261294 -241.441498) (xy 327.22561 -241.399756) (xy 327.196282 -241.353328)
			(xy 327.173915 -241.303174) (xy 327.16597 -241.276886) (xy 327.161398 -241.26063) (xy 327.13422 -241.240056)
			(xy 325.977504 -241.240056) (xy 325.965172 -241.240639) (xy 325.943321 -241.252075) (xy 325.935848 -241.2619)
			(xy 325.925942 -241.276124) (xy 325.923402 -241.283744) (xy 325.923402 -241.283998) (xy 325.914212 -241.310725)
			(xy 325.889066 -241.36134) (xy 325.856734 -241.407695) (xy 325.817921 -241.448777) (xy 325.773476 -241.483688)
			(xy 325.724369 -241.511665) (xy 325.671675 -241.532097) (xy 325.616544 -241.544538) (xy 325.560182 -241.548715)
			(xy 325.50382 -241.544538) (xy 325.448689 -241.532097) (xy 325.395995 -241.511665) (xy 325.346888 -241.483688)
			(xy 325.302443 -241.448777) (xy 325.26363 -241.407695) (xy 325.231298 -241.36134) (xy 325.206152 -241.310725)
			(xy 325.196962 -241.283998) (xy 325.196962 -241.283744) (xy 325.194422 -241.276124) (xy 325.184516 -241.2619)
			(xy 325.176899 -241.252241) (xy 325.155138 -241.240851) (xy 325.14286 -241.240056) (xy 316.476888 -241.240056)
			(xy 316.46682 -241.239629) (xy 316.448223 -241.231907) (xy 316.44082 -241.22507) (xy 308.882034 -233.666284)
			(xy 308.874922 -233.658918) (xy 308.856126 -233.651298) (xy 299.514006 -233.651298) (xy 299.509116 -233.651439)
			(xy 299.499527 -233.653364) (xy 299.494956 -233.655108) (xy 299.485304 -233.658918) (xy 298.58335 -233.658918)
			(xy 298.573284 -233.659351) (xy 298.554695 -233.66708) (xy 298.547282 -233.673904) (xy 298.280582 -233.940604)
			(xy 298.273727 -233.947999) (xy 298.265981 -233.966598) (xy 298.265596 -233.976672) (xy 298.265596 -237.871)
			(xy 298.829982 -237.871) (xy 298.834053 -237.815378) (xy 298.846179 -237.760941) (xy 298.866102 -237.70885)
			(xy 298.893398 -237.660215) (xy 298.927484 -237.616072) (xy 298.967633 -237.577363) (xy 299.012991 -237.544912)
			(xy 299.062591 -237.519411) (xy 299.115375 -237.501404) (xy 299.170218 -237.491274) (xy 299.225952 -237.489237)
			(xy 299.281389 -237.495337) (xy 299.335346 -237.509443) (xy 299.386675 -237.531255) (xy 299.434281 -237.560309)
			(xy 299.477149 -237.595984) (xy 299.514366 -237.637521) (xy 299.545139 -237.684034) (xy 299.568811 -237.734531)
			(xy 299.584879 -237.787938) (xy 299.592999 -237.843114) (xy 299.593508 -237.871) (xy 299.593193 -237.888272)
			(xy 301.479456 -237.888272) (xy 301.483527 -237.83265) (xy 301.495653 -237.778213) (xy 301.515576 -237.726122)
			(xy 301.542872 -237.677487) (xy 301.576958 -237.633344) (xy 301.617107 -237.594635) (xy 301.662465 -237.562184)
			(xy 301.712065 -237.536683) (xy 301.764849 -237.518676) (xy 301.819692 -237.508546) (xy 301.875426 -237.506509)
			(xy 301.930863 -237.512609) (xy 301.98482 -237.526715) (xy 302.036149 -237.548527) (xy 302.083755 -237.577581)
			(xy 302.126623 -237.613256) (xy 302.16384 -237.654793) (xy 302.194613 -237.701306) (xy 302.218285 -237.751803)
			(xy 302.234353 -237.80521) (xy 302.236409 -237.819184) (xy 303.177954 -237.819184) (xy 303.182025 -237.763562)
			(xy 303.194151 -237.709125) (xy 303.214074 -237.657034) (xy 303.24137 -237.608399) (xy 303.275456 -237.564256)
			(xy 303.315605 -237.525547) (xy 303.360963 -237.493096) (xy 303.410563 -237.467595) (xy 303.463347 -237.449588)
			(xy 303.51819 -237.439458) (xy 303.573924 -237.437421) (xy 303.629361 -237.443521) (xy 303.683318 -237.457627)
			(xy 303.734647 -237.479439) (xy 303.782253 -237.508493) (xy 303.825121 -237.544168) (xy 303.862338 -237.585705)
			(xy 303.893111 -237.632218) (xy 303.916783 -237.682715) (xy 303.932851 -237.736122) (xy 303.940971 -237.791298)
			(xy 303.94148 -237.819184) (xy 303.940971 -237.84707) (xy 303.932851 -237.902246) (xy 303.916783 -237.955653)
			(xy 303.893111 -238.00615) (xy 303.862338 -238.052663) (xy 303.825121 -238.0942) (xy 303.782253 -238.129875)
			(xy 303.734647 -238.158929) (xy 303.683318 -238.180741) (xy 303.629361 -238.194847) (xy 303.573924 -238.200947)
			(xy 303.51819 -238.19891) (xy 303.463347 -238.18878) (xy 303.410563 -238.170773) (xy 303.360963 -238.145272)
			(xy 303.315605 -238.112821) (xy 303.275456 -238.074112) (xy 303.24137 -238.029969) (xy 303.214074 -237.981334)
			(xy 303.194151 -237.929243) (xy 303.182025 -237.874806) (xy 303.177954 -237.819184) (xy 302.236409 -237.819184)
			(xy 302.242473 -237.860386) (xy 302.242982 -237.888272) (xy 302.242473 -237.916158) (xy 302.234353 -237.971334)
			(xy 302.218285 -238.024741) (xy 302.194613 -238.075238) (xy 302.16384 -238.121751) (xy 302.126623 -238.163288)
			(xy 302.083755 -238.198963) (xy 302.036149 -238.228017) (xy 301.98482 -238.249829) (xy 301.930863 -238.263935)
			(xy 301.875426 -238.270035) (xy 301.819692 -238.267998) (xy 301.764849 -238.257868) (xy 301.712065 -238.239861)
			(xy 301.662465 -238.21436) (xy 301.617107 -238.181909) (xy 301.576958 -238.1432) (xy 301.542872 -238.099057)
			(xy 301.515576 -238.050422) (xy 301.495653 -237.998331) (xy 301.483527 -237.943894) (xy 301.479456 -237.888272)
			(xy 299.593193 -237.888272) (xy 299.592999 -237.898886) (xy 299.584879 -237.954062) (xy 299.568811 -238.007469)
			(xy 299.545139 -238.057966) (xy 299.514366 -238.104479) (xy 299.477149 -238.146016) (xy 299.434281 -238.181691)
			(xy 299.386675 -238.210745) (xy 299.335346 -238.232557) (xy 299.281389 -238.246663) (xy 299.225952 -238.252763)
			(xy 299.170218 -238.250726) (xy 299.115375 -238.240596) (xy 299.062591 -238.222589) (xy 299.012991 -238.197088)
			(xy 298.967633 -238.164637) (xy 298.927484 -238.125928) (xy 298.893398 -238.081785) (xy 298.866102 -238.03315)
			(xy 298.846179 -237.981059) (xy 298.834053 -237.926622) (xy 298.829982 -237.871) (xy 298.265596 -237.871)
			(xy 298.265596 -238.938562) (xy 301.679608 -238.938562) (xy 301.683679 -238.88294) (xy 301.695805 -238.828503)
			(xy 301.715728 -238.776412) (xy 301.743024 -238.727777) (xy 301.77711 -238.683634) (xy 301.817259 -238.644925)
			(xy 301.862617 -238.612474) (xy 301.912217 -238.586973) (xy 301.965001 -238.568966) (xy 302.019844 -238.558836)
			(xy 302.075578 -238.556799) (xy 302.131015 -238.562899) (xy 302.184972 -238.577005) (xy 302.236301 -238.598817)
			(xy 302.283907 -238.627871) (xy 302.326775 -238.663546) (xy 302.363992 -238.705083) (xy 302.394765 -238.751596)
			(xy 302.418437 -238.802093) (xy 302.434505 -238.8555) (xy 302.442625 -238.910676) (xy 302.442865 -238.92383)
			(xy 303.699924 -238.92383) (xy 303.703995 -238.868208) (xy 303.716121 -238.813771) (xy 303.736044 -238.76168)
			(xy 303.76334 -238.713045) (xy 303.797426 -238.668902) (xy 303.837575 -238.630193) (xy 303.882933 -238.597742)
			(xy 303.932533 -238.572241) (xy 303.985317 -238.554234) (xy 304.04016 -238.544104) (xy 304.095894 -238.542067)
			(xy 304.151331 -238.548167) (xy 304.205288 -238.562273) (xy 304.256617 -238.584085) (xy 304.304223 -238.613139)
			(xy 304.347091 -238.648814) (xy 304.384308 -238.690351) (xy 304.415081 -238.736864) (xy 304.438753 -238.787361)
			(xy 304.454821 -238.840768) (xy 304.462941 -238.895944) (xy 304.46345 -238.92383) (xy 304.462941 -238.951716)
			(xy 304.454821 -239.006892) (xy 304.438753 -239.060299) (xy 304.415081 -239.110796) (xy 304.384308 -239.157309)
			(xy 304.347091 -239.198846) (xy 304.304223 -239.234521) (xy 304.256617 -239.263575) (xy 304.205288 -239.285387)
			(xy 304.151331 -239.299493) (xy 304.095894 -239.305593) (xy 304.04016 -239.303556) (xy 303.985317 -239.293426)
			(xy 303.932533 -239.275419) (xy 303.882933 -239.249918) (xy 303.837575 -239.217467) (xy 303.797426 -239.178758)
			(xy 303.76334 -239.134615) (xy 303.736044 -239.08598) (xy 303.716121 -239.033889) (xy 303.703995 -238.979452)
			(xy 303.699924 -238.92383) (xy 302.442865 -238.92383) (xy 302.443134 -238.938562) (xy 302.442625 -238.966448)
			(xy 302.434505 -239.021624) (xy 302.418437 -239.075031) (xy 302.394765 -239.125528) (xy 302.363992 -239.172041)
			(xy 302.326775 -239.213578) (xy 302.283907 -239.249253) (xy 302.236301 -239.278307) (xy 302.184972 -239.300119)
			(xy 302.131015 -239.314225) (xy 302.075578 -239.320325) (xy 302.019844 -239.318288) (xy 301.965001 -239.308158)
			(xy 301.912217 -239.290151) (xy 301.862617 -239.26465) (xy 301.817259 -239.232199) (xy 301.77711 -239.19349)
			(xy 301.743024 -239.149347) (xy 301.715728 -239.100712) (xy 301.695805 -239.048621) (xy 301.683679 -238.994184)
			(xy 301.679608 -238.938562) (xy 298.265596 -238.938562) (xy 298.265596 -241.47018) (xy 304.320192 -241.47018)
			(xy 304.324263 -241.414558) (xy 304.336389 -241.360121) (xy 304.356312 -241.30803) (xy 304.383608 -241.259395)
			(xy 304.417694 -241.215252) (xy 304.457843 -241.176543) (xy 304.503201 -241.144092) (xy 304.552801 -241.118591)
			(xy 304.605585 -241.100584) (xy 304.660428 -241.090454) (xy 304.716162 -241.088417) (xy 304.771599 -241.094517)
			(xy 304.825556 -241.108623) (xy 304.876885 -241.130435) (xy 304.924491 -241.159489) (xy 304.967359 -241.195164)
			(xy 305.004576 -241.236701) (xy 305.035349 -241.283214) (xy 305.059021 -241.333711) (xy 305.075089 -241.387118)
			(xy 305.083209 -241.442294) (xy 305.083718 -241.47018) (xy 305.083209 -241.498066) (xy 305.075089 -241.553242)
			(xy 305.059021 -241.606649) (xy 305.035349 -241.657146) (xy 305.004576 -241.703659) (xy 304.967359 -241.745196)
			(xy 304.924491 -241.780871) (xy 304.876885 -241.809925) (xy 304.825556 -241.831737) (xy 304.771599 -241.845843)
			(xy 304.716162 -241.851943) (xy 304.660428 -241.849906) (xy 304.605585 -241.839776) (xy 304.552801 -241.821769)
			(xy 304.503201 -241.796268) (xy 304.457843 -241.763817) (xy 304.417694 -241.725108) (xy 304.383608 -241.680965)
			(xy 304.356312 -241.63233) (xy 304.336389 -241.580239) (xy 304.324263 -241.525802) (xy 304.320192 -241.47018)
			(xy 298.265596 -241.47018) (xy 298.265596 -241.862356) (xy 375.643138 -241.862356) (xy 375.647209 -241.806734)
			(xy 375.659335 -241.752297) (xy 375.679258 -241.700206) (xy 375.706554 -241.651571) (xy 375.74064 -241.607428)
			(xy 375.780789 -241.568719) (xy 375.826147 -241.536268) (xy 375.875747 -241.510767) (xy 375.928531 -241.49276)
			(xy 375.983374 -241.48263) (xy 376.039108 -241.480593) (xy 376.094545 -241.486693) (xy 376.148502 -241.500799)
			(xy 376.199831 -241.522611) (xy 376.247437 -241.551665) (xy 376.290305 -241.58734) (xy 376.327522 -241.628877)
			(xy 376.358295 -241.67539) (xy 376.381967 -241.725887) (xy 376.398035 -241.779294) (xy 376.406155 -241.83447)
			(xy 376.406664 -241.862356) (xy 376.406155 -241.890242) (xy 376.398035 -241.945418) (xy 376.381967 -241.998825)
			(xy 376.358295 -242.049322) (xy 376.327522 -242.095835) (xy 376.290305 -242.137372) (xy 376.247437 -242.173047)
			(xy 376.199831 -242.202101) (xy 376.148502 -242.223913) (xy 376.094545 -242.238019) (xy 376.039108 -242.244119)
			(xy 375.983374 -242.242082) (xy 375.928531 -242.231952) (xy 375.875747 -242.213945) (xy 375.826147 -242.188444)
			(xy 375.780789 -242.155993) (xy 375.74064 -242.117284) (xy 375.706554 -242.073141) (xy 375.679258 -242.024506)
			(xy 375.659335 -241.972415) (xy 375.647209 -241.917978) (xy 375.643138 -241.862356) (xy 298.265596 -241.862356)
			(xy 298.265596 -242.311174) (xy 379.62027 -242.311174) (xy 379.624341 -242.255552) (xy 379.636467 -242.201115)
			(xy 379.65639 -242.149024) (xy 379.683686 -242.100389) (xy 379.717772 -242.056246) (xy 379.757921 -242.017537)
			(xy 379.803279 -241.985086) (xy 379.852879 -241.959585) (xy 379.905663 -241.941578) (xy 379.960506 -241.931448)
			(xy 380.01624 -241.929411) (xy 380.071677 -241.935511) (xy 380.125634 -241.949617) (xy 380.176963 -241.971429)
			(xy 380.224569 -242.000483) (xy 380.267437 -242.036158) (xy 380.304654 -242.077695) (xy 380.335427 -242.124208)
			(xy 380.359099 -242.174705) (xy 380.375167 -242.228112) (xy 380.383287 -242.283288) (xy 380.383796 -242.311174)
			(xy 380.383287 -242.33906) (xy 380.375167 -242.394236) (xy 380.359099 -242.447643) (xy 380.335427 -242.49814)
			(xy 380.304654 -242.544653) (xy 380.267437 -242.58619) (xy 380.224569 -242.621865) (xy 380.176963 -242.650919)
			(xy 380.125634 -242.672731) (xy 380.071677 -242.686837) (xy 380.01624 -242.692937) (xy 379.960506 -242.6909)
			(xy 379.905663 -242.68077) (xy 379.852879 -242.662763) (xy 379.803279 -242.637262) (xy 379.757921 -242.604811)
			(xy 379.717772 -242.566102) (xy 379.683686 -242.521959) (xy 379.65639 -242.473324) (xy 379.636467 -242.421233)
			(xy 379.624341 -242.366796) (xy 379.62027 -242.311174) (xy 298.265596 -242.311174) (xy 298.265596 -244.186202)
			(xy 327.47915 -244.186202) (xy 327.483221 -244.13058) (xy 327.495347 -244.076143) (xy 327.51527 -244.024052)
			(xy 327.542566 -243.975417) (xy 327.576652 -243.931274) (xy 327.616801 -243.892565) (xy 327.662159 -243.860114)
			(xy 327.711759 -243.834613) (xy 327.764543 -243.816606) (xy 327.819386 -243.806476) (xy 327.87512 -243.804439)
			(xy 327.930557 -243.810539) (xy 327.984514 -243.824645) (xy 328.020648 -243.84) (xy 329.944982 -243.84)
			(xy 329.949053 -243.784378) (xy 329.961179 -243.729941) (xy 329.981102 -243.67785) (xy 330.008398 -243.629215)
			(xy 330.042484 -243.585072) (xy 330.082633 -243.546363) (xy 330.127991 -243.513912) (xy 330.177591 -243.488411)
			(xy 330.230375 -243.470404) (xy 330.285218 -243.460274) (xy 330.340952 -243.458237) (xy 330.396389 -243.464337)
			(xy 330.450346 -243.478443) (xy 330.501675 -243.500255) (xy 330.549281 -243.529309) (xy 330.592149 -243.564984)
			(xy 330.629366 -243.606521) (xy 330.660139 -243.653034) (xy 330.683811 -243.703531) (xy 330.699879 -243.756938)
			(xy 330.707999 -243.812114) (xy 330.708508 -243.84) (xy 330.707999 -243.867886) (xy 330.70462 -243.890849)
			(xy 330.8114 -243.890849) (xy 330.8114 -243.836351) (xy 330.819156 -243.782409) (xy 330.834509 -243.730119)
			(xy 330.857147 -243.680546) (xy 330.886609 -243.634699) (xy 330.922297 -243.593512) (xy 330.963482 -243.557823)
			(xy 331.009327 -243.528358) (xy 331.058898 -243.505716) (xy 331.111187 -243.49036) (xy 331.165129 -243.482602)
			(xy 331.192378 -243.482114) (xy 331.218436 -243.482575) (xy 331.270067 -243.489671) (xy 331.320249 -243.503734)
			(xy 331.368049 -243.524501) (xy 331.412574 -243.551585) (xy 331.452995 -243.584482) (xy 331.488559 -243.622578)
			(xy 331.518602 -243.665163) (xy 331.53096 -243.688108) (xy 331.537732 -243.700374) (xy 331.556893 -243.720808)
			(xy 331.580886 -243.735267) (xy 331.607904 -243.742662) (xy 331.635916 -243.742438) (xy 331.662813 -243.734611)
			(xy 331.686571 -243.71977) (xy 331.696314 -243.709698) (xy 331.714465 -243.690498) (xy 331.755142 -243.656777)
			(xy 331.800082 -243.628992) (xy 331.848427 -243.607674) (xy 331.899251 -243.593232) (xy 331.951582 -243.585941)
			(xy 331.978 -243.585492) (xy 332.005251 -243.585978) (xy 332.059199 -243.593734) (xy 332.111494 -243.609089)
			(xy 332.161071 -243.631731) (xy 332.206921 -243.661197) (xy 332.248112 -243.696888) (xy 332.283803 -243.738079)
			(xy 332.313269 -243.783929) (xy 332.335911 -243.833506) (xy 332.337818 -243.84) (xy 333.739996 -243.84)
			(xy 333.744067 -243.784378) (xy 333.756193 -243.729941) (xy 333.776116 -243.67785) (xy 333.803412 -243.629215)
			(xy 333.837498 -243.585072) (xy 333.877647 -243.546363) (xy 333.923005 -243.513912) (xy 333.972605 -243.488411)
			(xy 334.025389 -243.470404) (xy 334.080232 -243.460274) (xy 334.135966 -243.458237) (xy 334.191403 -243.464337)
			(xy 334.24536 -243.478443) (xy 334.296689 -243.500255) (xy 334.344295 -243.529309) (xy 334.387163 -243.564984)
			(xy 334.42438 -243.606521) (xy 334.455153 -243.653034) (xy 334.478825 -243.703531) (xy 334.494893 -243.756938)
			(xy 334.503013 -243.812114) (xy 334.503522 -243.84) (xy 334.503013 -243.867886) (xy 334.494893 -243.923062)
			(xy 334.478825 -243.976469) (xy 334.477053 -243.980249) (xy 336.308708 -243.980249) (xy 336.308708 -243.925751)
			(xy 336.316464 -243.871807) (xy 336.331818 -243.819517) (xy 336.354457 -243.769944) (xy 336.383921 -243.724097)
			(xy 336.41961 -243.68291) (xy 336.460797 -243.647221) (xy 336.506644 -243.617757) (xy 336.556217 -243.595118)
			(xy 336.608507 -243.579764) (xy 336.662451 -243.572008) (xy 336.6897 -243.571522) (xy 336.717479 -243.572056)
			(xy 336.772448 -243.580122) (xy 336.825663 -243.596083) (xy 336.875997 -243.619601) (xy 336.922384 -243.650177)
			(xy 336.943446 -243.668296) (xy 336.952336 -243.675916) (xy 336.973926 -243.682266) (xy 337.074256 -243.666518)
			(xy 337.093052 -243.653818) (xy 337.098894 -243.643658) (xy 337.113732 -243.61946) (xy 337.149341 -243.575263)
			(xy 337.191108 -243.536832) (xy 337.238109 -243.505015) (xy 337.289306 -243.480515) (xy 337.343569 -243.463874)
			(xy 337.399699 -243.455459) (xy 337.428078 -243.454936) (xy 337.455335 -243.455309) (xy 337.509295 -243.463065)
			(xy 337.561601 -243.478421) (xy 337.61119 -243.501065) (xy 337.62755 -243.511578) (xy 354.422708 -243.511578)
			(xy 354.426779 -243.455956) (xy 354.438905 -243.401519) (xy 354.458828 -243.349428) (xy 354.486124 -243.300793)
			(xy 354.52021 -243.25665) (xy 354.560359 -243.217941) (xy 354.605717 -243.18549) (xy 354.655317 -243.159989)
			(xy 354.708101 -243.141982) (xy 354.762944 -243.131852) (xy 354.818678 -243.129815) (xy 354.874115 -243.135915)
			(xy 354.928072 -243.150021) (xy 354.979401 -243.171833) (xy 355.027007 -243.200887) (xy 355.069875 -243.236562)
			(xy 355.107092 -243.278099) (xy 355.137865 -243.324612) (xy 355.161537 -243.375109) (xy 355.177605 -243.428516)
			(xy 355.185725 -243.483692) (xy 355.186234 -243.511578) (xy 355.185725 -243.539464) (xy 355.182315 -243.562632)
			(xy 358.60177 -243.562632) (xy 358.605841 -243.50701) (xy 358.617967 -243.452573) (xy 358.63789 -243.400482)
			(xy 358.665186 -243.351847) (xy 358.699272 -243.307704) (xy 358.739421 -243.268995) (xy 358.784779 -243.236544)
			(xy 358.834379 -243.211043) (xy 358.887163 -243.193036) (xy 358.942006 -243.182906) (xy 358.99774 -243.180869)
			(xy 359.053177 -243.186969) (xy 359.107134 -243.201075) (xy 359.158463 -243.222887) (xy 359.206069 -243.251941)
			(xy 359.248937 -243.287616) (xy 359.286154 -243.329153) (xy 359.316927 -243.375666) (xy 359.340599 -243.426163)
			(xy 359.34681 -243.446808) (xy 360.475528 -243.446808) (xy 360.479599 -243.391186) (xy 360.491725 -243.336749)
			(xy 360.511648 -243.284658) (xy 360.538944 -243.236023) (xy 360.57303 -243.19188) (xy 360.613179 -243.153171)
			(xy 360.658537 -243.12072) (xy 360.708137 -243.095219) (xy 360.760921 -243.077212) (xy 360.815764 -243.067082)
			(xy 360.871498 -243.065045) (xy 360.926935 -243.071145) (xy 360.980892 -243.085251) (xy 361.032221 -243.107063)
			(xy 361.079827 -243.136117) (xy 361.122695 -243.171792) (xy 361.159912 -243.213329) (xy 361.185154 -243.251482)
			(xy 365.131856 -243.251482) (xy 365.135927 -243.19586) (xy 365.148053 -243.141423) (xy 365.167976 -243.089332)
			(xy 365.195272 -243.040697) (xy 365.229358 -242.996554) (xy 365.269507 -242.957845) (xy 365.314865 -242.925394)
			(xy 365.364465 -242.899893) (xy 365.417249 -242.881886) (xy 365.472092 -242.871756) (xy 365.527826 -242.869719)
			(xy 365.583263 -242.875819) (xy 365.63722 -242.889925) (xy 365.688549 -242.911737) (xy 365.736155 -242.940791)
			(xy 365.779023 -242.976466) (xy 365.81624 -243.018003) (xy 365.847013 -243.064516) (xy 365.870685 -243.115013)
			(xy 365.886753 -243.16842) (xy 365.894873 -243.223596) (xy 365.895382 -243.251482) (xy 365.894873 -243.279368)
			(xy 365.886753 -243.334544) (xy 365.870685 -243.387951) (xy 365.847013 -243.438448) (xy 365.81624 -243.484961)
			(xy 365.779023 -243.526498) (xy 365.736155 -243.562173) (xy 365.688549 -243.591227) (xy 365.63722 -243.613039)
			(xy 365.583263 -243.627145) (xy 365.527826 -243.633245) (xy 365.472092 -243.631208) (xy 365.417249 -243.621078)
			(xy 365.364465 -243.603071) (xy 365.314865 -243.57757) (xy 365.269507 -243.545119) (xy 365.229358 -243.50641)
			(xy 365.195272 -243.462267) (xy 365.167976 -243.413632) (xy 365.148053 -243.361541) (xy 365.135927 -243.307104)
			(xy 365.131856 -243.251482) (xy 361.185154 -243.251482) (xy 361.190685 -243.259842) (xy 361.214357 -243.310339)
			(xy 361.230425 -243.363746) (xy 361.238545 -243.418922) (xy 361.239054 -243.446808) (xy 361.238545 -243.474694)
			(xy 361.230425 -243.52987) (xy 361.214357 -243.583277) (xy 361.190685 -243.633774) (xy 361.159912 -243.680287)
			(xy 361.122695 -243.721824) (xy 361.079827 -243.757499) (xy 361.032221 -243.786553) (xy 360.980892 -243.808365)
			(xy 360.926935 -243.822471) (xy 360.871498 -243.828571) (xy 360.815764 -243.826534) (xy 360.760921 -243.816404)
			(xy 360.708137 -243.798397) (xy 360.658537 -243.772896) (xy 360.613179 -243.740445) (xy 360.57303 -243.701736)
			(xy 360.538944 -243.657593) (xy 360.511648 -243.608958) (xy 360.491725 -243.556867) (xy 360.479599 -243.50243)
			(xy 360.475528 -243.446808) (xy 359.34681 -243.446808) (xy 359.356667 -243.47957) (xy 359.364787 -243.534746)
			(xy 359.365296 -243.562632) (xy 359.364787 -243.590518) (xy 359.356667 -243.645694) (xy 359.340599 -243.699101)
			(xy 359.316927 -243.749598) (xy 359.286154 -243.796111) (xy 359.248937 -243.837648) (xy 359.206069 -243.873323)
			(xy 359.158463 -243.902377) (xy 359.133107 -243.913152) (xy 370.00129 -243.913152) (xy 370.005361 -243.85753)
			(xy 370.017487 -243.803093) (xy 370.03741 -243.751002) (xy 370.064706 -243.702367) (xy 370.098792 -243.658224)
			(xy 370.138941 -243.619515) (xy 370.184299 -243.587064) (xy 370.233899 -243.561563) (xy 370.286683 -243.543556)
			(xy 370.341526 -243.533426) (xy 370.39726 -243.531389) (xy 370.452697 -243.537489) (xy 370.506654 -243.551595)
			(xy 370.557983 -243.573407) (xy 370.605589 -243.602461) (xy 370.648457 -243.638136) (xy 370.685674 -243.679673)
			(xy 370.716447 -243.726186) (xy 370.740119 -243.776683) (xy 370.756187 -243.83009) (xy 370.764307 -243.885266)
			(xy 370.764816 -243.913152) (xy 370.764399 -243.936012) (xy 370.966492 -243.936012) (xy 370.966992 -243.909945)
			(xy 370.974097 -243.858297) (xy 370.988163 -243.808095) (xy 371.008928 -243.760274) (xy 371.036006 -243.715723)
			(xy 371.068893 -243.67527) (xy 371.106979 -243.639668) (xy 371.149554 -243.609579) (xy 371.172486 -243.597176)
			(xy 371.184593 -243.590351) (xy 371.204888 -243.571382) (xy 371.219316 -243.547643) (xy 371.226807 -243.520893)
			(xy 371.226808 -243.493113) (xy 371.219318 -243.466362) (xy 371.204891 -243.442622) (xy 371.184597 -243.423652)
			(xy 371.172486 -243.416836) (xy 371.14956 -243.404416) (xy 371.106966 -243.374344) (xy 371.068863 -243.338753)
			(xy 371.035961 -243.298305) (xy 371.008872 -243.253755) (xy 370.988101 -243.205931) (xy 370.974036 -243.155724)
			(xy 370.966936 -243.10407) (xy 370.966492 -243.078) (xy 370.966978 -243.050749) (xy 370.974734 -242.996801)
			(xy 370.990089 -242.944506) (xy 371.012731 -242.894929) (xy 371.042197 -242.849079) (xy 371.077888 -242.807888)
			(xy 371.119079 -242.772197) (xy 371.164929 -242.742731) (xy 371.214506 -242.720089) (xy 371.266801 -242.704734)
			(xy 371.320749 -242.696978) (xy 371.375251 -242.696978) (xy 371.429199 -242.704734) (xy 371.481494 -242.720089)
			(xy 371.531071 -242.742731) (xy 371.576921 -242.772197) (xy 371.618112 -242.807888) (xy 371.653803 -242.849079)
			(xy 371.683269 -242.894929) (xy 371.705911 -242.944506) (xy 371.721266 -242.996801) (xy 371.729022 -243.050749)
			(xy 371.729508 -243.078) (xy 371.729018 -243.104068) (xy 371.721911 -243.155716) (xy 371.719489 -243.16436)
			(xy 385.973572 -243.16436) (xy 385.977643 -243.108738) (xy 385.989769 -243.054301) (xy 386.009692 -243.00221)
			(xy 386.036988 -242.953575) (xy 386.071074 -242.909432) (xy 386.111223 -242.870723) (xy 386.156581 -242.838272)
			(xy 386.206181 -242.812771) (xy 386.258965 -242.794764) (xy 386.313808 -242.784634) (xy 386.369542 -242.782597)
			(xy 386.424979 -242.788697) (xy 386.478936 -242.802803) (xy 386.530265 -242.824615) (xy 386.577871 -242.853669)
			(xy 386.620739 -242.889344) (xy 386.657956 -242.930881) (xy 386.688729 -242.977394) (xy 386.712401 -243.027891)
			(xy 386.728469 -243.081298) (xy 386.736589 -243.136474) (xy 386.737098 -243.16436) (xy 386.97357 -243.16436)
			(xy 386.977641 -243.108738) (xy 386.989767 -243.054301) (xy 387.00969 -243.00221) (xy 387.036986 -242.953575)
			(xy 387.071072 -242.909432) (xy 387.111221 -242.870723) (xy 387.156579 -242.838272) (xy 387.206179 -242.812771)
			(xy 387.258963 -242.794764) (xy 387.313806 -242.784634) (xy 387.36954 -242.782597) (xy 387.424977 -242.788697)
			(xy 387.478934 -242.802803) (xy 387.530263 -242.824615) (xy 387.577869 -242.853669) (xy 387.620737 -242.889344)
			(xy 387.657954 -242.930881) (xy 387.688727 -242.977394) (xy 387.712399 -243.027891) (xy 387.728467 -243.081298)
			(xy 387.736587 -243.136474) (xy 387.737096 -243.16436) (xy 387.736587 -243.192246) (xy 387.728467 -243.247422)
			(xy 387.712399 -243.300829) (xy 387.688727 -243.351326) (xy 387.657954 -243.397839) (xy 387.620737 -243.439376)
			(xy 387.577869 -243.475051) (xy 387.530263 -243.504105) (xy 387.478934 -243.525917) (xy 387.424977 -243.540023)
			(xy 387.36954 -243.546123) (xy 387.313806 -243.544086) (xy 387.258963 -243.533956) (xy 387.206179 -243.515949)
			(xy 387.156579 -243.490448) (xy 387.111221 -243.457997) (xy 387.071072 -243.419288) (xy 387.036986 -243.375145)
			(xy 387.00969 -243.32651) (xy 386.989767 -243.274419) (xy 386.977641 -243.219982) (xy 386.97357 -243.16436)
			(xy 386.737098 -243.16436) (xy 386.736589 -243.192246) (xy 386.728469 -243.247422) (xy 386.712401 -243.300829)
			(xy 386.688729 -243.351326) (xy 386.657956 -243.397839) (xy 386.620739 -243.439376) (xy 386.577871 -243.475051)
			(xy 386.530265 -243.504105) (xy 386.478936 -243.525917) (xy 386.424979 -243.540023) (xy 386.369542 -243.546123)
			(xy 386.313808 -243.544086) (xy 386.258965 -243.533956) (xy 386.206181 -243.515949) (xy 386.156581 -243.490448)
			(xy 386.111223 -243.457997) (xy 386.071074 -243.419288) (xy 386.036988 -243.375145) (xy 386.009692 -243.32651)
			(xy 385.989769 -243.274419) (xy 385.977643 -243.219982) (xy 385.973572 -243.16436) (xy 371.719489 -243.16436)
			(xy 371.707844 -243.205918) (xy 371.687077 -243.253739) (xy 371.659998 -243.29829) (xy 371.627109 -243.338742)
			(xy 371.589023 -243.374344) (xy 371.546447 -243.404434) (xy 371.523514 -243.416836) (xy 371.511396 -243.423644)
			(xy 371.491101 -243.442616) (xy 371.476672 -243.466358) (xy 371.469181 -243.493112) (xy 371.469182 -243.520894)
			(xy 371.476675 -243.547647) (xy 371.491104 -243.571389) (xy 371.511401 -243.590359) (xy 371.523514 -243.597176)
			(xy 371.546445 -243.609587) (xy 371.589039 -243.63966) (xy 371.627142 -243.675253) (xy 371.660044 -243.715702)
			(xy 371.687132 -243.760253) (xy 371.707902 -243.808079) (xy 371.721967 -243.858286) (xy 371.729064 -243.909942)
			(xy 371.729508 -243.936012) (xy 371.729022 -243.963263) (xy 371.721266 -244.017211) (xy 371.705911 -244.069506)
			(xy 371.683269 -244.119083) (xy 371.653803 -244.164933) (xy 371.618112 -244.206124) (xy 371.576921 -244.241815)
			(xy 371.531071 -244.271281) (xy 371.481494 -244.293923) (xy 371.429199 -244.309278) (xy 371.375251 -244.317034)
			(xy 371.320749 -244.317034) (xy 371.266801 -244.309278) (xy 371.214506 -244.293923) (xy 371.164929 -244.271281)
			(xy 371.119079 -244.241815) (xy 371.077888 -244.206124) (xy 371.042197 -244.164933) (xy 371.012731 -244.119083)
			(xy 370.990089 -244.069506) (xy 370.974734 -244.017211) (xy 370.966978 -243.963263) (xy 370.966492 -243.936012)
			(xy 370.764399 -243.936012) (xy 370.764307 -243.941038) (xy 370.756187 -243.996214) (xy 370.740119 -244.049621)
			(xy 370.716447 -244.100118) (xy 370.685674 -244.146631) (xy 370.648457 -244.188168) (xy 370.605589 -244.223843)
			(xy 370.557983 -244.252897) (xy 370.506654 -244.274709) (xy 370.452697 -244.288815) (xy 370.39726 -244.294915)
			(xy 370.341526 -244.292878) (xy 370.286683 -244.282748) (xy 370.233899 -244.264741) (xy 370.184299 -244.23924)
			(xy 370.138941 -244.206789) (xy 370.098792 -244.16808) (xy 370.064706 -244.123937) (xy 370.03741 -244.075302)
			(xy 370.017487 -244.023211) (xy 370.005361 -243.968774) (xy 370.00129 -243.913152) (xy 359.133107 -243.913152)
			(xy 359.107134 -243.924189) (xy 359.053177 -243.938295) (xy 358.99774 -243.944395) (xy 358.942006 -243.942358)
			(xy 358.887163 -243.932228) (xy 358.834379 -243.914221) (xy 358.784779 -243.88872) (xy 358.739421 -243.856269)
			(xy 358.699272 -243.81756) (xy 358.665186 -243.773417) (xy 358.63789 -243.724782) (xy 358.617967 -243.672691)
			(xy 358.605841 -243.618254) (xy 358.60177 -243.562632) (xy 355.182315 -243.562632) (xy 355.177605 -243.59464)
			(xy 355.161537 -243.648047) (xy 355.137865 -243.698544) (xy 355.107092 -243.745057) (xy 355.069875 -243.786594)
			(xy 355.027007 -243.822269) (xy 354.979401 -243.851323) (xy 354.928072 -243.873135) (xy 354.874115 -243.887241)
			(xy 354.818678 -243.893341) (xy 354.762944 -243.891304) (xy 354.708101 -243.881174) (xy 354.655317 -243.863167)
			(xy 354.605717 -243.837666) (xy 354.560359 -243.805215) (xy 354.52021 -243.766506) (xy 354.486124 -243.722363)
			(xy 354.458828 -243.673728) (xy 354.438905 -243.621637) (xy 354.426779 -243.5672) (xy 354.422708 -243.511578)
			(xy 337.62755 -243.511578) (xy 337.657051 -243.530535) (xy 337.698251 -243.566233) (xy 337.733951 -243.607431)
			(xy 337.763425 -243.653291) (xy 337.786072 -243.702878) (xy 337.801431 -243.755184) (xy 337.809189 -243.809143)
			(xy 337.809189 -243.863657) (xy 337.801431 -243.917616) (xy 337.786072 -243.969922) (xy 337.763425 -244.019509)
			(xy 337.733951 -244.065369) (xy 337.698251 -244.106567) (xy 337.657051 -244.142265) (xy 337.61119 -244.171735)
			(xy 337.561601 -244.194379) (xy 337.509295 -244.209735) (xy 337.455335 -244.217491) (xy 337.428078 -244.217952)
			(xy 337.400299 -244.217437) (xy 337.345329 -244.209368) (xy 337.292113 -244.193402) (xy 337.241779 -244.16988)
			(xy 337.195394 -244.139299) (xy 337.174332 -244.121178) (xy 337.165442 -244.113558) (xy 337.143852 -244.107208)
			(xy 337.043522 -244.122956) (xy 337.024726 -244.135656) (xy 337.018884 -244.145816) (xy 337.004089 -244.170041)
			(xy 336.968469 -244.214234) (xy 336.961114 -244.221) (xy 338.072982 -244.221) (xy 338.077053 -244.165378)
			(xy 338.089179 -244.110941) (xy 338.109102 -244.05885) (xy 338.136398 -244.010215) (xy 338.170484 -243.966072)
			(xy 338.210633 -243.927363) (xy 338.255991 -243.894912) (xy 338.305591 -243.869411) (xy 338.358375 -243.851404)
			(xy 338.413218 -243.841274) (xy 338.468952 -243.839237) (xy 338.524389 -243.845337) (xy 338.578346 -243.859443)
			(xy 338.629675 -243.881255) (xy 338.677281 -243.910309) (xy 338.720149 -243.945984) (xy 338.757366 -243.987521)
			(xy 338.788139 -244.034034) (xy 338.811811 -244.084531) (xy 338.827879 -244.137938) (xy 338.835999 -244.193114)
			(xy 338.836508 -244.221) (xy 338.835999 -244.248886) (xy 338.827879 -244.304062) (xy 338.811811 -244.357469)
			(xy 338.810506 -244.360252) (xy 375.396969 -244.360252) (xy 375.396969 -244.305748) (xy 375.404726 -244.251797)
			(xy 375.420083 -244.1995) (xy 375.442725 -244.149921) (xy 375.472193 -244.104069) (xy 375.507887 -244.062877)
			(xy 375.54908 -244.027185) (xy 375.594933 -243.997719) (xy 375.644513 -243.975078) (xy 375.696811 -243.959723)
			(xy 375.750761 -243.951968) (xy 375.778014 -243.951506) (xy 375.80433 -243.951943) (xy 375.856465 -243.959169)
			(xy 375.90711 -243.973494) (xy 375.955305 -243.994648) (xy 376.000133 -244.022227) (xy 376.040743 -244.055709)
			(xy 376.076363 -244.094457) (xy 376.091704 -244.115844) (xy 376.100147 -244.127287) (xy 376.122073 -244.145375)
			(xy 376.148138 -244.156712) (xy 376.176319 -244.160417) (xy 376.204429 -244.156205) (xy 376.230285 -244.1444)
			(xy 376.251882 -244.12592) (xy 376.260106 -244.11432) (xy 376.275291 -244.092139) (xy 376.310954 -244.051916)
			(xy 376.351912 -244.017101) (xy 376.397353 -243.988384) (xy 376.446378 -243.966332) (xy 376.498013 -243.951385)
			(xy 376.551236 -243.943837) (xy 376.578114 -243.943378) (xy 376.605364 -243.943893) (xy 376.659308 -243.951651)
			(xy 376.711599 -243.967007) (xy 376.761172 -243.989648) (xy 376.807019 -244.019113) (xy 376.848206 -244.054804)
			(xy 376.883895 -244.095992) (xy 376.913359 -244.14184) (xy 376.935998 -244.191414) (xy 376.951352 -244.243706)
			(xy 376.959108 -244.29765) (xy 376.959108 -244.35215) (xy 376.951352 -244.406094) (xy 376.935998 -244.458386)
			(xy 376.913359 -244.50796) (xy 376.883895 -244.553808) (xy 376.848206 -244.594996) (xy 376.807019 -244.630687)
			(xy 376.761172 -244.660152) (xy 376.711599 -244.682793) (xy 376.659308 -244.698149) (xy 376.605364 -244.705907)
			(xy 376.578114 -244.706394) (xy 376.551796 -244.706011) (xy 376.499659 -244.698776) (xy 376.449012 -244.684441)
			(xy 376.400818 -244.663278) (xy 376.35599 -244.63569) (xy 376.315382 -244.602201) (xy 376.279763 -244.563446)
			(xy 376.264424 -244.542056) (xy 376.255947 -244.530641) (xy 376.234029 -244.512554) (xy 376.207971 -244.501215)
			(xy 376.179797 -244.497506) (xy 376.151693 -244.501713) (xy 376.12584 -244.513511) (xy 376.104246 -244.531984)
			(xy 376.096022 -244.54358) (xy 376.080819 -244.565748) (xy 376.045159 -244.605971) (xy 376.004204 -244.640787)
			(xy 375.958766 -244.669506) (xy 375.909744 -244.69156) (xy 375.858112 -244.70651) (xy 375.804891 -244.714061)
			(xy 375.778014 -244.714522) (xy 375.750761 -244.714032) (xy 375.696811 -244.706277) (xy 375.644513 -244.690922)
			(xy 375.594933 -244.668281) (xy 375.54908 -244.638815) (xy 375.507887 -244.603123) (xy 375.472193 -244.561931)
			(xy 375.442725 -244.516079) (xy 375.420083 -244.4665) (xy 375.404726 -244.414203) (xy 375.396969 -244.360252)
			(xy 338.810506 -244.360252) (xy 338.788139 -244.407966) (xy 338.757366 -244.454479) (xy 338.720149 -244.496016)
			(xy 338.677281 -244.531691) (xy 338.629675 -244.560745) (xy 338.578346 -244.582557) (xy 338.524389 -244.596663)
			(xy 338.468952 -244.602763) (xy 338.413218 -244.600726) (xy 338.358375 -244.590596) (xy 338.305591 -244.572589)
			(xy 338.255991 -244.547088) (xy 338.210633 -244.514637) (xy 338.170484 -244.475928) (xy 338.136398 -244.431785)
			(xy 338.109102 -244.38315) (xy 338.089179 -244.331059) (xy 338.077053 -244.276622) (xy 338.072982 -244.221)
			(xy 336.961114 -244.221) (xy 336.926694 -244.252661) (xy 336.879686 -244.284474) (xy 336.828483 -244.308969)
			(xy 336.774215 -244.325606) (xy 336.71808 -244.334017) (xy 336.6897 -244.334538) (xy 336.662451 -244.333992)
			(xy 336.608507 -244.326236) (xy 336.556217 -244.310882) (xy 336.506644 -244.288243) (xy 336.460797 -244.258779)
			(xy 336.41961 -244.22309) (xy 336.383921 -244.181903) (xy 336.354457 -244.136056) (xy 336.331818 -244.086483)
			(xy 336.316464 -244.034193) (xy 336.308708 -243.980249) (xy 334.477053 -243.980249) (xy 334.455153 -244.026966)
			(xy 334.42438 -244.073479) (xy 334.387163 -244.115016) (xy 334.344295 -244.150691) (xy 334.296689 -244.179745)
			(xy 334.24536 -244.201557) (xy 334.191403 -244.215663) (xy 334.135966 -244.221763) (xy 334.080232 -244.219726)
			(xy 334.025389 -244.209596) (xy 333.972605 -244.191589) (xy 333.923005 -244.166088) (xy 333.877647 -244.133637)
			(xy 333.837498 -244.094928) (xy 333.803412 -244.050785) (xy 333.776116 -244.00215) (xy 333.756193 -243.950059)
			(xy 333.744067 -243.895622) (xy 333.739996 -243.84) (xy 332.337818 -243.84) (xy 332.351266 -243.885801)
			(xy 332.359022 -243.939749) (xy 332.359022 -243.994251) (xy 332.351266 -244.048199) (xy 332.335911 -244.100494)
			(xy 332.313269 -244.150071) (xy 332.283803 -244.195921) (xy 332.248112 -244.237112) (xy 332.206921 -244.272803)
			(xy 332.161071 -244.302269) (xy 332.111494 -244.324911) (xy 332.059199 -244.340266) (xy 332.005251 -244.348022)
			(xy 331.978 -244.348508) (xy 331.95194 -244.348107) (xy 331.900305 -244.341006) (xy 331.850118 -244.326938)
			(xy 331.802317 -244.306163) (xy 331.757791 -244.27907) (xy 331.717371 -244.246164) (xy 331.681811 -244.208058)
			(xy 331.651773 -244.165464) (xy 331.639418 -244.142514) (xy 331.63254 -244.130312) (xy 331.613401 -244.109881)
			(xy 331.589431 -244.095419) (xy 331.562432 -244.088016) (xy 331.534438 -244.088228) (xy 331.507554 -244.096039)
			(xy 331.483805 -244.110862) (xy 331.474064 -244.120924) (xy 331.455928 -244.140139) (xy 331.415248 -244.173858)
			(xy 331.370304 -244.20164) (xy 331.321956 -244.222955) (xy 331.27113 -244.237395) (xy 331.218797 -244.244683)
			(xy 331.192378 -244.24513) (xy 331.165129 -244.244598) (xy 331.111187 -244.23684) (xy 331.058898 -244.221484)
			(xy 331.009327 -244.198842) (xy 330.963482 -244.169377) (xy 330.922297 -244.133688) (xy 330.886609 -244.092501)
			(xy 330.857147 -244.046654) (xy 330.834509 -243.997081) (xy 330.819156 -243.944791) (xy 330.8114 -243.890849)
			(xy 330.70462 -243.890849) (xy 330.699879 -243.923062) (xy 330.683811 -243.976469) (xy 330.660139 -244.026966)
			(xy 330.629366 -244.073479) (xy 330.592149 -244.115016) (xy 330.549281 -244.150691) (xy 330.501675 -244.179745)
			(xy 330.450346 -244.201557) (xy 330.396389 -244.215663) (xy 330.340952 -244.221763) (xy 330.285218 -244.219726)
			(xy 330.230375 -244.209596) (xy 330.177591 -244.191589) (xy 330.127991 -244.166088) (xy 330.082633 -244.133637)
			(xy 330.042484 -244.094928) (xy 330.008398 -244.050785) (xy 329.981102 -244.00215) (xy 329.961179 -243.950059)
			(xy 329.949053 -243.895622) (xy 329.944982 -243.84) (xy 328.020648 -243.84) (xy 328.035843 -243.846457)
			(xy 328.083449 -243.875511) (xy 328.126317 -243.911186) (xy 328.163534 -243.952723) (xy 328.194307 -243.999236)
			(xy 328.217979 -244.049733) (xy 328.234047 -244.10314) (xy 328.242167 -244.158316) (xy 328.242676 -244.186202)
			(xy 328.242167 -244.214088) (xy 328.234047 -244.269264) (xy 328.217979 -244.322671) (xy 328.194307 -244.373168)
			(xy 328.163534 -244.419681) (xy 328.126317 -244.461218) (xy 328.083449 -244.496893) (xy 328.035843 -244.525947)
			(xy 327.984514 -244.547759) (xy 327.930557 -244.561865) (xy 327.87512 -244.567965) (xy 327.819386 -244.565928)
			(xy 327.764543 -244.555798) (xy 327.711759 -244.537791) (xy 327.662159 -244.51229) (xy 327.616801 -244.479839)
			(xy 327.576652 -244.44113) (xy 327.542566 -244.396987) (xy 327.51527 -244.348352) (xy 327.495347 -244.296261)
			(xy 327.483221 -244.241824) (xy 327.47915 -244.186202) (xy 298.265596 -244.186202) (xy 298.265596 -244.7036)
			(xy 301.166782 -244.7036) (xy 301.170853 -244.647978) (xy 301.182979 -244.593541) (xy 301.202902 -244.54145)
			(xy 301.230198 -244.492815) (xy 301.264284 -244.448672) (xy 301.304433 -244.409963) (xy 301.349791 -244.377512)
			(xy 301.399391 -244.352011) (xy 301.452175 -244.334004) (xy 301.507018 -244.323874) (xy 301.562752 -244.321837)
			(xy 301.618189 -244.327937) (xy 301.672146 -244.342043) (xy 301.723475 -244.363855) (xy 301.771081 -244.392909)
			(xy 301.813949 -244.428584) (xy 301.851166 -244.470121) (xy 301.881939 -244.516634) (xy 301.905611 -244.567131)
			(xy 301.921679 -244.620538) (xy 301.929799 -244.675714) (xy 301.930308 -244.7036) (xy 301.929799 -244.731486)
			(xy 301.921679 -244.786662) (xy 301.905611 -244.840069) (xy 301.881939 -244.890566) (xy 301.851166 -244.937079)
			(xy 301.833234 -244.957092) (xy 335.178398 -244.957092) (xy 335.182469 -244.90147) (xy 335.194595 -244.847033)
			(xy 335.214518 -244.794942) (xy 335.241814 -244.746307) (xy 335.2759 -244.702164) (xy 335.316049 -244.663455)
			(xy 335.361407 -244.631004) (xy 335.411007 -244.605503) (xy 335.463791 -244.587496) (xy 335.518634 -244.577366)
			(xy 335.574368 -244.575329) (xy 335.629805 -244.581429) (xy 335.683762 -244.595535) (xy 335.735091 -244.617347)
			(xy 335.782697 -244.646401) (xy 335.825565 -244.682076) (xy 335.862782 -244.723613) (xy 335.893555 -244.770126)
			(xy 335.917227 -244.820623) (xy 335.933295 -244.87403) (xy 335.941415 -244.929206) (xy 335.941924 -244.957092)
			(xy 335.941415 -244.984978) (xy 335.933295 -245.040154) (xy 335.917227 -245.093561) (xy 335.893555 -245.144058)
			(xy 335.862782 -245.190571) (xy 335.825565 -245.232108) (xy 335.782697 -245.267783) (xy 335.735091 -245.296837)
			(xy 335.683762 -245.318649) (xy 335.629805 -245.332755) (xy 335.574368 -245.338855) (xy 335.518634 -245.336818)
			(xy 335.463791 -245.326688) (xy 335.411007 -245.308681) (xy 335.361407 -245.28318) (xy 335.316049 -245.250729)
			(xy 335.2759 -245.21202) (xy 335.241814 -245.167877) (xy 335.214518 -245.119242) (xy 335.194595 -245.067151)
			(xy 335.182469 -245.012714) (xy 335.178398 -244.957092) (xy 301.833234 -244.957092) (xy 301.813949 -244.978616)
			(xy 301.771081 -245.014291) (xy 301.723475 -245.043345) (xy 301.672146 -245.065157) (xy 301.618189 -245.079263)
			(xy 301.562752 -245.085363) (xy 301.507018 -245.083326) (xy 301.452175 -245.073196) (xy 301.399391 -245.055189)
			(xy 301.349791 -245.029688) (xy 301.304433 -244.997237) (xy 301.264284 -244.958528) (xy 301.230198 -244.914385)
			(xy 301.202902 -244.86575) (xy 301.182979 -244.813659) (xy 301.170853 -244.759222) (xy 301.166782 -244.7036)
			(xy 298.265596 -244.7036) (xy 298.265596 -245.341902) (xy 355.742238 -245.341902) (xy 355.746309 -245.28628)
			(xy 355.758435 -245.231843) (xy 355.778358 -245.179752) (xy 355.805654 -245.131117) (xy 355.83974 -245.086974)
			(xy 355.879889 -245.048265) (xy 355.925247 -245.015814) (xy 355.974847 -244.990313) (xy 356.027631 -244.972306)
			(xy 356.082474 -244.962176) (xy 356.138208 -244.960139) (xy 356.193645 -244.966239) (xy 356.247602 -244.980345)
			(xy 356.298931 -245.002157) (xy 356.346537 -245.031211) (xy 356.389405 -245.066886) (xy 356.426622 -245.108423)
			(xy 356.457395 -245.154936) (xy 356.481067 -245.205433) (xy 356.497135 -245.25884) (xy 356.502449 -245.294952)
			(xy 362.197089 -245.294952) (xy 362.197089 -245.240448) (xy 362.204847 -245.186498) (xy 362.220204 -245.134201)
			(xy 362.242847 -245.084623) (xy 362.272316 -245.038772) (xy 362.308011 -244.997582) (xy 362.349205 -244.961891)
			(xy 362.39506 -244.932427) (xy 362.444641 -244.909789) (xy 362.496939 -244.894438) (xy 362.55089 -244.886686)
			(xy 362.578142 -244.886226) (xy 362.607177 -244.886779) (xy 362.66458 -244.895559) (xy 362.719988 -244.912941)
			(xy 362.77212 -244.938522) (xy 362.819772 -244.971711) (xy 362.86184 -245.011741) (xy 362.897353 -245.057687)
			(xy 362.911898 -245.082822) (xy 362.918994 -245.094665) (xy 362.938396 -245.114293) (xy 362.962348 -245.128003)
			(xy 362.989098 -245.134794) (xy 363.01669 -245.134168) (xy 363.043105 -245.12617) (xy 363.06641 -245.111387)
			(xy 363.084902 -245.0909) (xy 363.091476 -245.078758) (xy 363.103729 -245.055302) (xy 363.133622 -245.011638)
			(xy 363.169261 -244.972523) (xy 363.209963 -244.938707) (xy 363.254946 -244.910838) (xy 363.303348 -244.889452)
			(xy 363.354241 -244.874958) (xy 363.406648 -244.867634) (xy 363.433106 -244.867176) (xy 363.460356 -244.867695)
			(xy 363.514301 -244.875452) (xy 363.566592 -244.890807) (xy 363.616167 -244.913447) (xy 363.626771 -244.920262)
			(xy 370.624352 -244.920262) (xy 370.628423 -244.86464) (xy 370.640549 -244.810203) (xy 370.660472 -244.758112)
			(xy 370.687768 -244.709477) (xy 370.721854 -244.665334) (xy 370.762003 -244.626625) (xy 370.807361 -244.594174)
			(xy 370.856961 -244.568673) (xy 370.909745 -244.550666) (xy 370.964588 -244.540536) (xy 371.020322 -244.538499)
			(xy 371.075759 -244.544599) (xy 371.129716 -244.558705) (xy 371.181045 -244.580517) (xy 371.228651 -244.609571)
			(xy 371.271519 -244.645246) (xy 371.308736 -244.686783) (xy 371.339509 -244.733296) (xy 371.363181 -244.783793)
			(xy 371.379249 -244.8372) (xy 371.387369 -244.892376) (xy 371.387878 -244.920262) (xy 371.387369 -244.948148)
			(xy 371.379249 -245.003324) (xy 371.363181 -245.056731) (xy 371.339509 -245.107228) (xy 371.308736 -245.153741)
			(xy 371.271519 -245.195278) (xy 371.228651 -245.230953) (xy 371.181045 -245.260007) (xy 371.129716 -245.281819)
			(xy 371.075759 -245.295925) (xy 371.020322 -245.302025) (xy 370.964588 -245.299988) (xy 370.909745 -245.289858)
			(xy 370.856961 -245.271851) (xy 370.807361 -245.24635) (xy 370.762003 -245.213899) (xy 370.721854 -245.17519)
			(xy 370.687768 -245.131047) (xy 370.660472 -245.082412) (xy 370.640549 -245.030321) (xy 370.628423 -244.975884)
			(xy 370.624352 -244.920262) (xy 363.626771 -244.920262) (xy 363.662014 -244.942912) (xy 363.703202 -244.978602)
			(xy 363.738891 -245.01979) (xy 363.768356 -245.065639) (xy 363.790996 -245.115213) (xy 363.80635 -245.167505)
			(xy 363.814106 -245.22145) (xy 363.814106 -245.27595) (xy 363.80635 -245.329895) (xy 363.790996 -245.382187)
			(xy 363.768356 -245.431761) (xy 363.738891 -245.47761) (xy 363.703202 -245.518798) (xy 363.673139 -245.544848)
			(xy 369.93398 -245.544848) (xy 369.938051 -245.489226) (xy 369.950177 -245.434789) (xy 369.9701 -245.382698)
			(xy 369.997396 -245.334063) (xy 370.031482 -245.28992) (xy 370.071631 -245.251211) (xy 370.116989 -245.21876)
			(xy 370.166589 -245.193259) (xy 370.219373 -245.175252) (xy 370.274216 -245.165122) (xy 370.32995 -245.163085)
			(xy 370.385387 -245.169185) (xy 370.439344 -245.183291) (xy 370.490673 -245.205103) (xy 370.538279 -245.234157)
			(xy 370.581147 -245.269832) (xy 370.618364 -245.311369) (xy 370.649137 -245.357882) (xy 370.655339 -245.371112)
			(xy 376.10618 -245.371112) (xy 376.110251 -245.31549) (xy 376.122377 -245.261053) (xy 376.1423 -245.208962)
			(xy 376.169596 -245.160327) (xy 376.203682 -245.116184) (xy 376.243831 -245.077475) (xy 376.289189 -245.045024)
			(xy 376.338789 -245.019523) (xy 376.391573 -245.001516) (xy 376.446416 -244.991386) (xy 376.50215 -244.989349)
			(xy 376.557587 -244.995449) (xy 376.611544 -245.009555) (xy 376.662873 -245.031367) (xy 376.710479 -245.060421)
			(xy 376.753347 -245.096096) (xy 376.790564 -245.137633) (xy 376.821337 -245.184146) (xy 376.845009 -245.234643)
			(xy 376.861077 -245.28805) (xy 376.869197 -245.343226) (xy 376.869576 -245.364) (xy 380.973582 -245.364)
			(xy 380.977653 -245.308378) (xy 380.989779 -245.253941) (xy 381.009702 -245.20185) (xy 381.036998 -245.153215)
			(xy 381.071084 -245.109072) (xy 381.111233 -245.070363) (xy 381.156591 -245.037912) (xy 381.206191 -245.012411)
			(xy 381.258975 -244.994404) (xy 381.313818 -244.984274) (xy 381.369552 -244.982237) (xy 381.424989 -244.988337)
			(xy 381.478946 -245.002443) (xy 381.530275 -245.024255) (xy 381.577881 -245.053309) (xy 381.620749 -245.088984)
			(xy 381.657966 -245.130521) (xy 381.688739 -245.177034) (xy 381.712411 -245.227531) (xy 381.728479 -245.280938)
			(xy 381.736599 -245.336114) (xy 381.736941 -245.354856) (xy 382.113534 -245.354856) (xy 382.117605 -245.299234)
			(xy 382.129731 -245.244797) (xy 382.149654 -245.192706) (xy 382.17695 -245.144071) (xy 382.211036 -245.099928)
			(xy 382.251185 -245.061219) (xy 382.296543 -245.028768) (xy 382.346143 -245.003267) (xy 382.398927 -244.98526)
			(xy 382.45377 -244.97513) (xy 382.509504 -244.973093) (xy 382.564941 -244.979193) (xy 382.618898 -244.993299)
			(xy 382.670227 -245.015111) (xy 382.717833 -245.044165) (xy 382.760701 -245.07984) (xy 382.797918 -245.121377)
			(xy 382.828691 -245.16789) (xy 382.852363 -245.218387) (xy 382.868431 -245.271794) (xy 382.876551 -245.32697)
			(xy 382.87706 -245.354856) (xy 382.876551 -245.382742) (xy 382.868431 -245.437918) (xy 382.852363 -245.491325)
			(xy 382.828691 -245.541822) (xy 382.797918 -245.588335) (xy 382.760701 -245.629872) (xy 382.717833 -245.665547)
			(xy 382.670227 -245.694601) (xy 382.618898 -245.716413) (xy 382.564941 -245.730519) (xy 382.509504 -245.736619)
			(xy 382.45377 -245.734582) (xy 382.398927 -245.724452) (xy 382.346143 -245.706445) (xy 382.296543 -245.680944)
			(xy 382.251185 -245.648493) (xy 382.211036 -245.609784) (xy 382.17695 -245.565641) (xy 382.149654 -245.517006)
			(xy 382.129731 -245.464915) (xy 382.117605 -245.410478) (xy 382.113534 -245.354856) (xy 381.736941 -245.354856)
			(xy 381.737108 -245.364) (xy 381.736599 -245.391886) (xy 381.728479 -245.447062) (xy 381.712411 -245.500469)
			(xy 381.688739 -245.550966) (xy 381.657966 -245.597479) (xy 381.620749 -245.639016) (xy 381.577881 -245.674691)
			(xy 381.530275 -245.703745) (xy 381.478946 -245.725557) (xy 381.424989 -245.739663) (xy 381.369552 -245.745763)
			(xy 381.313818 -245.743726) (xy 381.258975 -245.733596) (xy 381.206191 -245.715589) (xy 381.156591 -245.690088)
			(xy 381.111233 -245.657637) (xy 381.071084 -245.618928) (xy 381.036998 -245.574785) (xy 381.009702 -245.52615)
			(xy 380.989779 -245.474059) (xy 380.977653 -245.419622) (xy 380.973582 -245.364) (xy 376.869576 -245.364)
			(xy 376.869706 -245.371112) (xy 376.869197 -245.398998) (xy 376.861077 -245.454174) (xy 376.845009 -245.507581)
			(xy 376.821337 -245.558078) (xy 376.790564 -245.604591) (xy 376.753347 -245.646128) (xy 376.710479 -245.681803)
			(xy 376.662873 -245.710857) (xy 376.611544 -245.732669) (xy 376.557587 -245.746775) (xy 376.50215 -245.752875)
			(xy 376.446416 -245.750838) (xy 376.391573 -245.740708) (xy 376.338789 -245.722701) (xy 376.289189 -245.6972)
			(xy 376.243831 -245.664749) (xy 376.203682 -245.62604) (xy 376.169596 -245.581897) (xy 376.1423 -245.533262)
			(xy 376.122377 -245.481171) (xy 376.110251 -245.426734) (xy 376.10618 -245.371112) (xy 370.655339 -245.371112)
			(xy 370.672809 -245.408379) (xy 370.688877 -245.461786) (xy 370.696997 -245.516962) (xy 370.697506 -245.544848)
			(xy 370.696997 -245.572734) (xy 370.688877 -245.62791) (xy 370.672809 -245.681317) (xy 370.649137 -245.731814)
			(xy 370.618364 -245.778327) (xy 370.581147 -245.819864) (xy 370.538279 -245.855539) (xy 370.490673 -245.884593)
			(xy 370.439344 -245.906405) (xy 370.385387 -245.920511) (xy 370.32995 -245.926611) (xy 370.274216 -245.924574)
			(xy 370.219373 -245.914444) (xy 370.166589 -245.896437) (xy 370.116989 -245.870936) (xy 370.071631 -245.838485)
			(xy 370.031482 -245.799776) (xy 369.997396 -245.755633) (xy 369.9701 -245.706998) (xy 369.950177 -245.654907)
			(xy 369.938051 -245.60047) (xy 369.93398 -245.544848) (xy 363.673139 -245.544848) (xy 363.662014 -245.554488)
			(xy 363.616167 -245.583953) (xy 363.566592 -245.606593) (xy 363.514301 -245.621948) (xy 363.460356 -245.629705)
			(xy 363.433106 -245.630192) (xy 363.40407 -245.629672) (xy 363.346666 -245.620884) (xy 363.291258 -245.603496)
			(xy 363.239126 -245.577909) (xy 363.191475 -245.544715) (xy 363.149407 -245.504681) (xy 363.113894 -245.458733)
			(xy 363.09935 -245.433596) (xy 363.092187 -245.421795) (xy 363.072799 -245.402168) (xy 363.048859 -245.388455)
			(xy 363.02212 -245.38166) (xy 362.994538 -245.38228) (xy 362.968131 -245.39027) (xy 362.944832 -245.405044)
			(xy 362.926345 -245.425523) (xy 362.919772 -245.43766) (xy 362.907566 -245.461142) (xy 362.877666 -245.504806)
			(xy 362.84202 -245.54392) (xy 362.801311 -245.577734) (xy 362.756321 -245.605599) (xy 362.707913 -245.626982)
			(xy 362.657014 -245.64147) (xy 362.604602 -245.648788) (xy 362.578142 -245.649242) (xy 362.55089 -245.648714)
			(xy 362.496939 -245.640962) (xy 362.444641 -245.625611) (xy 362.39506 -245.602973) (xy 362.349205 -245.573509)
			(xy 362.308011 -245.537818) (xy 362.272316 -245.496628) (xy 362.242847 -245.450777) (xy 362.220204 -245.401199)
			(xy 362.204847 -245.348902) (xy 362.197089 -245.294952) (xy 356.502449 -245.294952) (xy 356.505255 -245.314016)
			(xy 356.505764 -245.341902) (xy 356.505255 -245.369788) (xy 356.497135 -245.424964) (xy 356.481067 -245.478371)
			(xy 356.457395 -245.528868) (xy 356.426622 -245.575381) (xy 356.389405 -245.616918) (xy 356.346537 -245.652593)
			(xy 356.298931 -245.681647) (xy 356.247602 -245.703459) (xy 356.193645 -245.717565) (xy 356.138208 -245.723665)
			(xy 356.082474 -245.721628) (xy 356.027631 -245.711498) (xy 355.974847 -245.693491) (xy 355.925247 -245.66799)
			(xy 355.879889 -245.635539) (xy 355.83974 -245.59683) (xy 355.805654 -245.552687) (xy 355.778358 -245.504052)
			(xy 355.758435 -245.451961) (xy 355.746309 -245.397524) (xy 355.742238 -245.341902) (xy 298.265596 -245.341902)
			(xy 298.265596 -245.776242) (xy 335.800698 -245.776242) (xy 335.804769 -245.72062) (xy 335.816895 -245.666183)
			(xy 335.836818 -245.614092) (xy 335.864114 -245.565457) (xy 335.8982 -245.521314) (xy 335.938349 -245.482605)
			(xy 335.983707 -245.450154) (xy 336.033307 -245.424653) (xy 336.086091 -245.406646) (xy 336.140934 -245.396516)
			(xy 336.196668 -245.394479) (xy 336.252105 -245.400579) (xy 336.306062 -245.414685) (xy 336.357391 -245.436497)
			(xy 336.404997 -245.465551) (xy 336.447865 -245.501226) (xy 336.485082 -245.542763) (xy 336.515855 -245.589276)
			(xy 336.539527 -245.639773) (xy 336.555595 -245.69318) (xy 336.563715 -245.748356) (xy 336.564224 -245.776242)
			(xy 336.563715 -245.804128) (xy 336.555595 -245.859304) (xy 336.539527 -245.912711) (xy 336.515855 -245.963208)
			(xy 336.485082 -246.009721) (xy 336.447865 -246.051258) (xy 336.404997 -246.086933) (xy 336.357391 -246.115987)
			(xy 336.306062 -246.137799) (xy 336.252105 -246.151905) (xy 336.196668 -246.158005) (xy 336.140934 -246.155968)
			(xy 336.086091 -246.145838) (xy 336.033307 -246.127831) (xy 335.983707 -246.10233) (xy 335.938349 -246.069879)
			(xy 335.8982 -246.03117) (xy 335.864114 -245.987027) (xy 335.836818 -245.938392) (xy 335.816895 -245.886301)
			(xy 335.804769 -245.831864) (xy 335.800698 -245.776242) (xy 298.265596 -245.776242) (xy 298.265596 -246.434864)
			(xy 329.197714 -246.434864) (xy 329.201785 -246.379242) (xy 329.213911 -246.324805) (xy 329.233834 -246.272714)
			(xy 329.26113 -246.224079) (xy 329.295216 -246.179936) (xy 329.335365 -246.141227) (xy 329.380723 -246.108776)
			(xy 329.430323 -246.083275) (xy 329.483107 -246.065268) (xy 329.53795 -246.055138) (xy 329.593684 -246.053101)
			(xy 329.649121 -246.059201) (xy 329.703078 -246.073307) (xy 329.754407 -246.095119) (xy 329.802013 -246.124173)
			(xy 329.844881 -246.159848) (xy 329.882098 -246.201385) (xy 329.912871 -246.247898) (xy 329.936543 -246.298395)
			(xy 329.952611 -246.351802) (xy 329.960731 -246.406978) (xy 329.96124 -246.434864) (xy 329.960731 -246.46275)
			(xy 329.952611 -246.517926) (xy 329.936543 -246.571333) (xy 329.912871 -246.62183) (xy 329.882098 -246.668343)
			(xy 329.844881 -246.70988) (xy 329.802013 -246.745555) (xy 329.754407 -246.774609) (xy 329.703078 -246.796421)
			(xy 329.649121 -246.810527) (xy 329.593684 -246.816627) (xy 329.53795 -246.81459) (xy 329.483107 -246.80446)
			(xy 329.430323 -246.786453) (xy 329.380723 -246.760952) (xy 329.335365 -246.728501) (xy 329.295216 -246.689792)
			(xy 329.26113 -246.645649) (xy 329.233834 -246.597014) (xy 329.213911 -246.544923) (xy 329.201785 -246.490486)
			(xy 329.197714 -246.434864) (xy 298.265596 -246.434864) (xy 298.265596 -247.711976) (xy 327.998326 -247.711976)
			(xy 328.002397 -247.656354) (xy 328.014523 -247.601917) (xy 328.034446 -247.549826) (xy 328.061742 -247.501191)
			(xy 328.095828 -247.457048) (xy 328.135977 -247.418339) (xy 328.181335 -247.385888) (xy 328.230935 -247.360387)
			(xy 328.283719 -247.34238) (xy 328.338562 -247.33225) (xy 328.394296 -247.330213) (xy 328.449733 -247.336313)
			(xy 328.50369 -247.350419) (xy 328.555019 -247.372231) (xy 328.602625 -247.401285) (xy 328.645493 -247.43696)
			(xy 328.68271 -247.478497) (xy 328.713483 -247.52501) (xy 328.737155 -247.575507) (xy 328.753223 -247.628914)
			(xy 328.761343 -247.68409) (xy 328.761852 -247.711976) (xy 328.761343 -247.739862) (xy 328.753223 -247.795038)
			(xy 328.737155 -247.848445) (xy 328.713483 -247.898942) (xy 328.68271 -247.945455) (xy 328.645493 -247.986992)
			(xy 328.602625 -248.022667) (xy 328.555019 -248.051721) (xy 328.50369 -248.073533) (xy 328.449733 -248.087639)
			(xy 328.394296 -248.093739) (xy 328.338562 -248.091702) (xy 328.283719 -248.081572) (xy 328.230935 -248.063565)
			(xy 328.181335 -248.038064) (xy 328.135977 -248.005613) (xy 328.095828 -247.966904) (xy 328.061742 -247.922761)
			(xy 328.034446 -247.874126) (xy 328.014523 -247.822035) (xy 328.002397 -247.767598) (xy 327.998326 -247.711976)
			(xy 298.265596 -247.711976) (xy 298.265596 -248.8806) (xy 327.741855 -248.8806) (xy 327.745821 -248.81252)
			(xy 327.757662 -248.74536) (xy 327.77722 -248.68003) (xy 327.804231 -248.617411) (xy 327.838327 -248.558352)
			(xy 327.87905 -248.50365) (xy 327.925848 -248.454045) (xy 327.978087 -248.410208) (xy 328.035063 -248.372733)
			(xy 328.096004 -248.342125) (xy 328.160086 -248.318798) (xy 328.226442 -248.303069) (xy 328.294176 -248.295149)
			(xy 328.328274 -248.294652) (xy 329.991466 -248.294652) (xy 330.001432 -248.294171) (xy 330.019868 -248.286599)
			(xy 330.02728 -248.27992) (xy 331.334364 -246.972836) (xy 331.357945 -246.949921) (xy 331.409355 -246.908927)
			(xy 331.465029 -246.873939) (xy 331.524266 -246.845399) (xy 331.586324 -246.823664) (xy 331.650424 -246.809007)
			(xy 331.715761 -246.801612) (xy 331.748638 -246.801132) (xy 332.606142 -246.801132) (xy 332.615529 -246.800722)
			(xy 332.633044 -246.793955) (xy 332.64698 -246.781371) (xy 332.651608 -246.773192) (xy 332.698852 -246.679212)
			(xy 332.696566 -246.650764) (xy 332.687676 -246.63908) (xy 332.669987 -246.614234) (xy 332.641871 -246.560114)
			(xy 332.622735 -246.502206) (xy 332.613068 -246.44199) (xy 332.612492 -246.411496) (xy 332.612978 -246.384245)
			(xy 332.620734 -246.330297) (xy 332.636089 -246.278002) (xy 332.658731 -246.228425) (xy 332.688197 -246.182575)
			(xy 332.723888 -246.141384) (xy 332.765079 -246.105693) (xy 332.810929 -246.076227) (xy 332.860506 -246.053585)
			(xy 332.912801 -246.03823) (xy 332.966749 -246.030474) (xy 333.021251 -246.030474) (xy 333.075199 -246.03823)
			(xy 333.127494 -246.053585) (xy 333.177071 -246.076227) (xy 333.222921 -246.105693) (xy 333.264112 -246.141384)
			(xy 333.299803 -246.182575) (xy 333.329269 -246.228425) (xy 333.351911 -246.278002) (xy 333.367266 -246.330297)
			(xy 333.374412 -246.38) (xy 375.333766 -246.38) (xy 375.337837 -246.324378) (xy 375.349963 -246.269941)
			(xy 375.369886 -246.21785) (xy 375.397182 -246.169215) (xy 375.431268 -246.125072) (xy 375.471417 -246.086363)
			(xy 375.516775 -246.053912) (xy 375.566375 -246.028411) (xy 375.619159 -246.010404) (xy 375.674002 -246.000274)
			(xy 375.729736 -245.998237) (xy 375.785173 -246.004337) (xy 375.83913 -246.018443) (xy 375.890459 -246.040255)
			(xy 375.92233 -246.059706) (xy 384.173982 -246.059706) (xy 384.178053 -246.004084) (xy 384.190179 -245.949647)
			(xy 384.210102 -245.897556) (xy 384.237398 -245.848921) (xy 384.271484 -245.804778) (xy 384.311633 -245.766069)
			(xy 384.356991 -245.733618) (xy 384.406591 -245.708117) (xy 384.459375 -245.69011) (xy 384.514218 -245.67998)
			(xy 384.569952 -245.677943) (xy 384.625389 -245.684043) (xy 384.679346 -245.698149) (xy 384.730675 -245.719961)
			(xy 384.778281 -245.749015) (xy 384.821149 -245.78469) (xy 384.858366 -245.826227) (xy 384.889139 -245.87274)
			(xy 384.912811 -245.923237) (xy 384.928879 -245.976644) (xy 384.936999 -246.03182) (xy 384.937508 -246.059706)
			(xy 384.936999 -246.087592) (xy 384.928879 -246.142768) (xy 384.912811 -246.196175) (xy 384.889139 -246.246672)
			(xy 384.858366 -246.293185) (xy 384.821149 -246.334722) (xy 384.778281 -246.370397) (xy 384.730675 -246.399451)
			(xy 384.679346 -246.421263) (xy 384.625389 -246.435369) (xy 384.569952 -246.441469) (xy 384.514218 -246.439432)
			(xy 384.459375 -246.429302) (xy 384.406591 -246.411295) (xy 384.356991 -246.385794) (xy 384.311633 -246.353343)
			(xy 384.271484 -246.314634) (xy 384.237398 -246.270491) (xy 384.210102 -246.221856) (xy 384.190179 -246.169765)
			(xy 384.178053 -246.115328) (xy 384.173982 -246.059706) (xy 375.92233 -246.059706) (xy 375.938065 -246.069309)
			(xy 375.980933 -246.104984) (xy 376.01815 -246.146521) (xy 376.048923 -246.193034) (xy 376.072595 -246.243531)
			(xy 376.088663 -246.296938) (xy 376.096783 -246.352114) (xy 376.097292 -246.38) (xy 376.096783 -246.407886)
			(xy 376.088663 -246.463062) (xy 376.072595 -246.516469) (xy 376.048923 -246.566966) (xy 376.01815 -246.613479)
			(xy 375.980933 -246.655016) (xy 375.938065 -246.690691) (xy 375.890459 -246.719745) (xy 375.83913 -246.741557)
			(xy 375.785173 -246.755663) (xy 375.729736 -246.761763) (xy 375.674002 -246.759726) (xy 375.619159 -246.749596)
			(xy 375.566375 -246.731589) (xy 375.516775 -246.706088) (xy 375.471417 -246.673637) (xy 375.431268 -246.634928)
			(xy 375.397182 -246.590785) (xy 375.369886 -246.54215) (xy 375.349963 -246.490059) (xy 375.337837 -246.435622)
			(xy 375.333766 -246.38) (xy 333.374412 -246.38) (xy 333.375022 -246.384245) (xy 333.375508 -246.411496)
			(xy 333.374937 -246.441989) (xy 333.365246 -246.502201) (xy 333.34611 -246.560107) (xy 333.318015 -246.614236)
			(xy 333.300324 -246.63908) (xy 333.291434 -246.650764) (xy 333.289148 -246.679212) (xy 333.336392 -246.773192)
			(xy 333.340945 -246.781436) (xy 333.354871 -246.794092) (xy 333.372447 -246.800813) (xy 333.381858 -246.801132)
			(xy 369.58016 -246.801132) (xy 369.613041 -246.801589) (xy 369.678388 -246.808952) (xy 369.7425 -246.82359)
			(xy 369.804567 -246.845319) (xy 369.86381 -246.873865) (xy 369.919481 -246.908869) (xy 369.97088 -246.94989)
			(xy 369.994434 -246.972836) (xy 370.463572 -247.441974) (xy 372.616982 -247.441974) (xy 372.621053 -247.386352)
			(xy 372.633179 -247.331915) (xy 372.653102 -247.279824) (xy 372.680398 -247.231189) (xy 372.714484 -247.187046)
			(xy 372.754633 -247.148337) (xy 372.799991 -247.115886) (xy 372.849591 -247.090385) (xy 372.902375 -247.072378)
			(xy 372.957218 -247.062248) (xy 373.012952 -247.060211) (xy 373.068389 -247.066311) (xy 373.122346 -247.080417)
			(xy 373.173675 -247.102229) (xy 373.221281 -247.131283) (xy 373.264149 -247.166958) (xy 373.301366 -247.208495)
			(xy 373.332139 -247.255008) (xy 373.355811 -247.305505) (xy 373.371879 -247.358912) (xy 373.377337 -247.396)
			(xy 374.648982 -247.396) (xy 374.653053 -247.340378) (xy 374.665179 -247.285941) (xy 374.685102 -247.23385)
			(xy 374.712398 -247.185215) (xy 374.746484 -247.141072) (xy 374.786633 -247.102363) (xy 374.831991 -247.069912)
			(xy 374.881591 -247.044411) (xy 374.934375 -247.026404) (xy 374.989218 -247.016274) (xy 375.044952 -247.014237)
			(xy 375.100389 -247.020337) (xy 375.154346 -247.034443) (xy 375.205675 -247.056255) (xy 375.253281 -247.085309)
			(xy 375.296149 -247.120984) (xy 375.333366 -247.162521) (xy 375.364139 -247.209034) (xy 375.387811 -247.259531)
			(xy 375.403879 -247.312938) (xy 375.411999 -247.368114) (xy 375.412508 -247.396) (xy 375.411999 -247.423886)
			(xy 375.403879 -247.479062) (xy 375.387811 -247.532469) (xy 375.364139 -247.582966) (xy 375.333366 -247.629479)
			(xy 375.300414 -247.666256) (xy 375.643138 -247.666256) (xy 375.647209 -247.610634) (xy 375.659335 -247.556197)
			(xy 375.679258 -247.504106) (xy 375.706554 -247.455471) (xy 375.74064 -247.411328) (xy 375.780789 -247.372619)
			(xy 375.826147 -247.340168) (xy 375.875747 -247.314667) (xy 375.928531 -247.29666) (xy 375.983374 -247.28653)
			(xy 376.039108 -247.284493) (xy 376.094545 -247.290593) (xy 376.148502 -247.304699) (xy 376.199831 -247.326511)
			(xy 376.247437 -247.355565) (xy 376.26123 -247.367044) (xy 376.865386 -247.367044) (xy 376.869457 -247.311422)
			(xy 376.881583 -247.256985) (xy 376.901506 -247.204894) (xy 376.928802 -247.156259) (xy 376.962888 -247.112116)
			(xy 377.003037 -247.073407) (xy 377.048395 -247.040956) (xy 377.097995 -247.015455) (xy 377.150779 -246.997448)
			(xy 377.205622 -246.987318) (xy 377.261356 -246.985281) (xy 377.316793 -246.991381) (xy 377.37075 -247.005487)
			(xy 377.393136 -247.015) (xy 377.950982 -247.015) (xy 377.955053 -246.959378) (xy 377.967179 -246.904941)
			(xy 377.987102 -246.85285) (xy 378.014398 -246.804215) (xy 378.048484 -246.760072) (xy 378.088633 -246.721363)
			(xy 378.133991 -246.688912) (xy 378.183591 -246.663411) (xy 378.236375 -246.645404) (xy 378.291218 -246.635274)
			(xy 378.346952 -246.633237) (xy 378.402389 -246.639337) (xy 378.456346 -246.653443) (xy 378.507675 -246.675255)
			(xy 378.555281 -246.704309) (xy 378.598149 -246.739984) (xy 378.635366 -246.781521) (xy 378.666139 -246.828034)
			(xy 378.689811 -246.878531) (xy 378.705879 -246.931938) (xy 378.713999 -246.987114) (xy 378.714508 -247.015)
			(xy 379.474982 -247.015) (xy 379.479053 -246.959378) (xy 379.491179 -246.904941) (xy 379.511102 -246.85285)
			(xy 379.538398 -246.804215) (xy 379.572484 -246.760072) (xy 379.612633 -246.721363) (xy 379.657991 -246.688912)
			(xy 379.707591 -246.663411) (xy 379.760375 -246.645404) (xy 379.815218 -246.635274) (xy 379.870952 -246.633237)
			(xy 379.926389 -246.639337) (xy 379.980346 -246.653443) (xy 380.031675 -246.675255) (xy 380.079281 -246.704309)
			(xy 380.122149 -246.739984) (xy 380.159366 -246.781521) (xy 380.190139 -246.828034) (xy 380.213811 -246.878531)
			(xy 380.229879 -246.931938) (xy 380.237999 -246.987114) (xy 380.238508 -247.015) (xy 380.237999 -247.042886)
			(xy 380.229879 -247.098062) (xy 380.213811 -247.151469) (xy 380.190139 -247.201966) (xy 380.159366 -247.248479)
			(xy 380.122149 -247.290016) (xy 380.079281 -247.325691) (xy 380.072286 -247.32996) (xy 383.346452 -247.32996)
			(xy 383.346892 -247.303603) (xy 383.35413 -247.25139) (xy 383.368491 -247.20067) (xy 383.389701 -247.152413)
			(xy 383.417355 -247.107536) (xy 383.450927 -247.066896) (xy 383.489776 -247.031267) (xy 383.533162 -247.001329)
			(xy 383.55651 -246.989092) (xy 383.569619 -246.982) (xy 383.591244 -246.961502) (xy 383.606034 -246.935635)
			(xy 383.612732 -246.906602) (xy 383.610767 -246.876871) (xy 383.600308 -246.848971) (xy 383.582243 -246.825276)
			(xy 383.57048 -246.816118) (xy 383.549876 -246.800661) (xy 383.512565 -246.765153) (xy 383.480374 -246.724945)
			(xy 383.453888 -246.68077) (xy 383.43359 -246.633431) (xy 383.41985 -246.583791) (xy 383.412916 -246.532753)
			(xy 383.412492 -246.507) (xy 383.412978 -246.479749) (xy 383.420734 -246.425801) (xy 383.436089 -246.373506)
			(xy 383.458731 -246.323929) (xy 383.488197 -246.278079) (xy 383.523888 -246.236888) (xy 383.565079 -246.201197)
			(xy 383.610929 -246.171731) (xy 383.660506 -246.149089) (xy 383.712801 -246.133734) (xy 383.766749 -246.125978)
			(xy 383.821251 -246.125978) (xy 383.875199 -246.133734) (xy 383.927494 -246.149089) (xy 383.977071 -246.171731)
			(xy 384.022921 -246.201197) (xy 384.064112 -246.236888) (xy 384.099803 -246.278079) (xy 384.129269 -246.323929)
			(xy 384.151911 -246.373506) (xy 384.167266 -246.425801) (xy 384.175022 -246.479749) (xy 384.175508 -246.507)
			(xy 384.175085 -246.533357) (xy 384.16784 -246.58557) (xy 384.153474 -246.636288) (xy 384.13226 -246.684544)
			(xy 384.104604 -246.72942) (xy 384.071031 -246.77006) (xy 384.032183 -246.805689) (xy 383.988797 -246.83563)
			(xy 383.96545 -246.847868) (xy 383.952373 -246.855018) (xy 383.930741 -246.8755) (xy 383.915943 -246.901354)
			(xy 383.909238 -246.93038) (xy 383.911197 -246.960106) (xy 383.921654 -246.988) (xy 383.939718 -247.011689)
			(xy 383.95148 -247.020842) (xy 383.972104 -247.036274) (xy 384.009415 -247.071786) (xy 384.041606 -247.111997)
			(xy 384.06809 -247.156177) (xy 384.088385 -247.203519) (xy 384.102121 -247.253164) (xy 384.109048 -247.304205)
			(xy 384.109468 -247.32996) (xy 384.108982 -247.357211) (xy 384.101226 -247.411159) (xy 384.085871 -247.463454)
			(xy 384.079209 -247.478042) (xy 386.969762 -247.478042) (xy 386.970356 -247.449365) (xy 386.978948 -247.392658)
			(xy 386.995932 -247.337876) (xy 387.020923 -247.286253) (xy 387.053359 -247.238952) (xy 387.092509 -247.197038)
			(xy 387.137492 -247.161456) (xy 387.187293 -247.133007) (xy 387.213856 -247.122188) (xy 387.227819 -247.116179)
			(xy 387.251708 -247.097414) (xy 387.269019 -247.072451) (xy 387.278219 -247.0435) (xy 387.278493 -247.013123)
			(xy 387.269818 -246.98401) (xy 387.25296 -246.958739) (xy 387.241542 -246.948706) (xy 387.219988 -246.930504)
			(xy 387.181981 -246.888814) (xy 387.150531 -246.84198) (xy 387.126324 -246.791024) (xy 387.109889 -246.737057)
			(xy 387.101585 -246.681257) (xy 387.10108 -246.65305) (xy 387.101566 -246.625799) (xy 387.109322 -246.571851)
			(xy 387.124677 -246.519556) (xy 387.147319 -246.469979) (xy 387.176785 -246.424129) (xy 387.212476 -246.382938)
			(xy 387.253667 -246.347247) (xy 387.299517 -246.317781) (xy 387.349094 -246.295139) (xy 387.401389 -246.279784)
			(xy 387.455337 -246.272028) (xy 387.509839 -246.272028) (xy 387.563787 -246.279784) (xy 387.616082 -246.295139)
			(xy 387.665659 -246.317781) (xy 387.711509 -246.347247) (xy 387.7527 -246.382938) (xy 387.788391 -246.424129)
			(xy 387.817857 -246.469979) (xy 387.840499 -246.519556) (xy 387.855854 -246.571851) (xy 387.86361 -246.625799)
			(xy 387.864096 -246.65305) (xy 387.863608 -246.681731) (xy 387.855001 -246.738444) (xy 387.838003 -246.79323)
			(xy 387.812996 -246.844855) (xy 387.780546 -246.892156) (xy 387.741381 -246.934068) (xy 387.696385 -246.969646)
			(xy 387.646571 -246.998089) (xy 387.620002 -247.008904) (xy 387.606044 -247.014919) (xy 387.582163 -247.033687)
			(xy 387.564858 -247.058649) (xy 387.555661 -247.087596) (xy 387.555385 -247.117969) (xy 387.564055 -247.147079)
			(xy 387.580903 -247.172351) (xy 387.592316 -247.182386) (xy 387.613857 -247.200602) (xy 387.651867 -247.242288)
			(xy 387.68332 -247.289118) (xy 387.707529 -247.340073) (xy 387.723966 -247.394038) (xy 387.732272 -247.449836)
			(xy 387.732778 -247.478042) (xy 387.732292 -247.505293) (xy 387.724536 -247.559241) (xy 387.709181 -247.611536)
			(xy 387.686539 -247.661113) (xy 387.657073 -247.706963) (xy 387.621382 -247.748154) (xy 387.580191 -247.783845)
			(xy 387.534341 -247.813311) (xy 387.484764 -247.835953) (xy 387.432469 -247.851308) (xy 387.378521 -247.859064)
			(xy 387.324019 -247.859064) (xy 387.270071 -247.851308) (xy 387.217776 -247.835953) (xy 387.168199 -247.813311)
			(xy 387.122349 -247.783845) (xy 387.081158 -247.748154) (xy 387.045467 -247.706963) (xy 387.016001 -247.661113)
			(xy 386.993359 -247.611536) (xy 386.978004 -247.559241) (xy 386.970248 -247.505293) (xy 386.969762 -247.478042)
			(xy 384.079209 -247.478042) (xy 384.063229 -247.513031) (xy 384.033763 -247.558881) (xy 383.998072 -247.600072)
			(xy 383.956881 -247.635763) (xy 383.911031 -247.665229) (xy 383.861454 -247.687871) (xy 383.809159 -247.703226)
			(xy 383.755211 -247.710982) (xy 383.700709 -247.710982) (xy 383.646761 -247.703226) (xy 383.594466 -247.687871)
			(xy 383.544889 -247.665229) (xy 383.499039 -247.635763) (xy 383.457848 -247.600072) (xy 383.422157 -247.558881)
			(xy 383.392691 -247.513031) (xy 383.370049 -247.463454) (xy 383.354694 -247.411159) (xy 383.346938 -247.357211)
			(xy 383.346452 -247.32996) (xy 380.072286 -247.32996) (xy 380.031675 -247.354745) (xy 379.980346 -247.376557)
			(xy 379.926389 -247.390663) (xy 379.870952 -247.396763) (xy 379.815218 -247.394726) (xy 379.760375 -247.384596)
			(xy 379.707591 -247.366589) (xy 379.657991 -247.341088) (xy 379.612633 -247.308637) (xy 379.572484 -247.269928)
			(xy 379.538398 -247.225785) (xy 379.511102 -247.17715) (xy 379.491179 -247.125059) (xy 379.479053 -247.070622)
			(xy 379.474982 -247.015) (xy 378.714508 -247.015) (xy 378.713999 -247.042886) (xy 378.705879 -247.098062)
			(xy 378.689811 -247.151469) (xy 378.666139 -247.201966) (xy 378.635366 -247.248479) (xy 378.598149 -247.290016)
			(xy 378.555281 -247.325691) (xy 378.507675 -247.354745) (xy 378.456346 -247.376557) (xy 378.402389 -247.390663)
			(xy 378.346952 -247.396763) (xy 378.291218 -247.394726) (xy 378.236375 -247.384596) (xy 378.183591 -247.366589)
			(xy 378.133991 -247.341088) (xy 378.088633 -247.308637) (xy 378.048484 -247.269928) (xy 378.014398 -247.225785)
			(xy 377.987102 -247.17715) (xy 377.967179 -247.125059) (xy 377.955053 -247.070622) (xy 377.950982 -247.015)
			(xy 377.393136 -247.015) (xy 377.422079 -247.027299) (xy 377.469685 -247.056353) (xy 377.512553 -247.092028)
			(xy 377.54977 -247.133565) (xy 377.580543 -247.180078) (xy 377.604215 -247.230575) (xy 377.620283 -247.283982)
			(xy 377.628403 -247.339158) (xy 377.628912 -247.367044) (xy 377.628403 -247.39493) (xy 377.620283 -247.450106)
			(xy 377.604215 -247.503513) (xy 377.580543 -247.55401) (xy 377.57518 -247.562116) (xy 378.728222 -247.562116)
			(xy 378.732293 -247.506494) (xy 378.744419 -247.452057) (xy 378.764342 -247.399966) (xy 378.791638 -247.351331)
			(xy 378.825724 -247.307188) (xy 378.865873 -247.268479) (xy 378.911231 -247.236028) (xy 378.960831 -247.210527)
			(xy 379.013615 -247.19252) (xy 379.068458 -247.18239) (xy 379.124192 -247.180353) (xy 379.179629 -247.186453)
			(xy 379.233586 -247.200559) (xy 379.284915 -247.222371) (xy 379.332521 -247.251425) (xy 379.375389 -247.2871)
			(xy 379.412606 -247.328637) (xy 379.443379 -247.37515) (xy 379.467051 -247.425647) (xy 379.483119 -247.479054)
			(xy 379.491239 -247.53423) (xy 379.491748 -247.562116) (xy 379.491239 -247.590002) (xy 379.483119 -247.645178)
			(xy 379.467051 -247.698585) (xy 379.443379 -247.749082) (xy 379.412606 -247.795595) (xy 379.375389 -247.837132)
			(xy 379.332521 -247.872807) (xy 379.284915 -247.901861) (xy 379.233586 -247.923673) (xy 379.179629 -247.937779)
			(xy 379.124192 -247.943879) (xy 379.068458 -247.941842) (xy 379.013615 -247.931712) (xy 378.960831 -247.913705)
			(xy 378.911231 -247.888204) (xy 378.865873 -247.855753) (xy 378.825724 -247.817044) (xy 378.791638 -247.772901)
			(xy 378.764342 -247.724266) (xy 378.744419 -247.672175) (xy 378.732293 -247.617738) (xy 378.728222 -247.562116)
			(xy 377.57518 -247.562116) (xy 377.54977 -247.600523) (xy 377.512553 -247.64206) (xy 377.469685 -247.677735)
			(xy 377.422079 -247.706789) (xy 377.37075 -247.728601) (xy 377.316793 -247.742707) (xy 377.261356 -247.748807)
			(xy 377.205622 -247.74677) (xy 377.150779 -247.73664) (xy 377.097995 -247.718633) (xy 377.048395 -247.693132)
			(xy 377.003037 -247.660681) (xy 376.962888 -247.621972) (xy 376.928802 -247.577829) (xy 376.901506 -247.529194)
			(xy 376.881583 -247.477103) (xy 376.869457 -247.422666) (xy 376.865386 -247.367044) (xy 376.26123 -247.367044)
			(xy 376.290305 -247.39124) (xy 376.327522 -247.432777) (xy 376.358295 -247.47929) (xy 376.381967 -247.529787)
			(xy 376.398035 -247.583194) (xy 376.406155 -247.63837) (xy 376.406664 -247.666256) (xy 376.406155 -247.694142)
			(xy 376.398035 -247.749318) (xy 376.381967 -247.802725) (xy 376.358295 -247.853222) (xy 376.327522 -247.899735)
			(xy 376.290305 -247.941272) (xy 376.247437 -247.976947) (xy 376.199831 -248.006001) (xy 376.148502 -248.027813)
			(xy 376.094545 -248.041919) (xy 376.039108 -248.048019) (xy 375.983374 -248.045982) (xy 375.928531 -248.035852)
			(xy 375.875747 -248.017845) (xy 375.826147 -247.992344) (xy 375.780789 -247.959893) (xy 375.74064 -247.921184)
			(xy 375.706554 -247.877041) (xy 375.679258 -247.828406) (xy 375.659335 -247.776315) (xy 375.647209 -247.721878)
			(xy 375.643138 -247.666256) (xy 375.300414 -247.666256) (xy 375.296149 -247.671016) (xy 375.253281 -247.706691)
			(xy 375.205675 -247.735745) (xy 375.154346 -247.757557) (xy 375.100389 -247.771663) (xy 375.044952 -247.777763)
			(xy 374.989218 -247.775726) (xy 374.934375 -247.765596) (xy 374.881591 -247.747589) (xy 374.831991 -247.722088)
			(xy 374.786633 -247.689637) (xy 374.746484 -247.650928) (xy 374.712398 -247.606785) (xy 374.685102 -247.55815)
			(xy 374.665179 -247.506059) (xy 374.653053 -247.451622) (xy 374.648982 -247.396) (xy 373.377337 -247.396)
			(xy 373.379999 -247.414088) (xy 373.380508 -247.441974) (xy 373.379999 -247.46986) (xy 373.371879 -247.525036)
			(xy 373.355811 -247.578443) (xy 373.332139 -247.62894) (xy 373.301366 -247.675453) (xy 373.264149 -247.71699)
			(xy 373.221281 -247.752665) (xy 373.173675 -247.781719) (xy 373.122346 -247.803531) (xy 373.068389 -247.817637)
			(xy 373.012952 -247.823737) (xy 372.957218 -247.8217) (xy 372.902375 -247.81157) (xy 372.849591 -247.793563)
			(xy 372.799991 -247.768062) (xy 372.754633 -247.735611) (xy 372.714484 -247.696902) (xy 372.680398 -247.652759)
			(xy 372.653102 -247.604124) (xy 372.633179 -247.552033) (xy 372.621053 -247.497596) (xy 372.616982 -247.441974)
			(xy 370.463572 -247.441974) (xy 370.581682 -247.560084) (xy 370.604595 -247.58366) (xy 370.645581 -247.635068)
			(xy 370.680549 -247.690743) (xy 370.709061 -247.749984) (xy 370.730758 -247.812047) (xy 370.745366 -247.876149)
			(xy 370.752702 -247.941485) (xy 370.753132 -247.974358) (xy 370.752604 -248.009762) (xy 370.744076 -248.080054)
			(xy 370.727139 -248.148806) (xy 370.702039 -248.215016) (xy 370.669143 -248.277719) (xy 370.640109 -248.319798)
			(xy 385.663184 -248.319798) (xy 385.667255 -248.264176) (xy 385.679381 -248.209739) (xy 385.699304 -248.157648)
			(xy 385.7266 -248.109013) (xy 385.760686 -248.06487) (xy 385.800835 -248.026161) (xy 385.846193 -247.99371)
			(xy 385.895793 -247.968209) (xy 385.948577 -247.950202) (xy 386.00342 -247.940072) (xy 386.059154 -247.938035)
			(xy 386.114591 -247.944135) (xy 386.168548 -247.958241) (xy 386.219877 -247.980053) (xy 386.267483 -248.009107)
			(xy 386.310351 -248.044782) (xy 386.347568 -248.086319) (xy 386.378341 -248.132832) (xy 386.402013 -248.183329)
			(xy 386.418081 -248.236736) (xy 386.426201 -248.291912) (xy 386.42671 -248.319798) (xy 386.426201 -248.347684)
			(xy 386.418081 -248.40286) (xy 386.402013 -248.456267) (xy 386.378341 -248.506764) (xy 386.347568 -248.553277)
			(xy 386.310351 -248.594814) (xy 386.267483 -248.630489) (xy 386.219877 -248.659543) (xy 386.168548 -248.681355)
			(xy 386.114591 -248.695461) (xy 386.059154 -248.701561) (xy 386.00342 -248.699524) (xy 385.948577 -248.689394)
			(xy 385.895793 -248.671387) (xy 385.846193 -248.645886) (xy 385.800835 -248.613435) (xy 385.760686 -248.574726)
			(xy 385.7266 -248.530583) (xy 385.699304 -248.481948) (xy 385.679381 -248.429857) (xy 385.667255 -248.37542)
			(xy 385.663184 -248.319798) (xy 370.640109 -248.319798) (xy 370.62893 -248.336) (xy 370.581986 -248.38901)
			(xy 370.528997 -248.435976) (xy 370.470733 -248.476213) (xy 370.408044 -248.509136) (xy 370.341845 -248.534264)
			(xy 370.2731 -248.551231) (xy 370.202812 -248.559789) (xy 370.167408 -248.560336) (xy 370.134526 -248.55991)
			(xy 370.069177 -248.552542) (xy 370.005065 -248.5379) (xy 369.942997 -248.516166) (xy 369.883755 -248.487615)
			(xy 369.828085 -248.452606) (xy 369.776687 -248.411581) (xy 369.753134 -248.388632) (xy 369.352322 -247.98782)
			(xy 369.344916 -247.981135) (xy 369.326475 -247.973564) (xy 369.316508 -247.973088) (xy 366.447832 -247.973088)
			(xy 366.418368 -248.001282) (xy 366.417606 -248.021856) (xy 366.416042 -248.049817) (xy 366.405861 -248.104883)
			(xy 366.387737 -248.157868) (xy 366.36206 -248.207633) (xy 366.329383 -248.253109) (xy 366.290406 -248.293318)
			(xy 366.245969 -248.327395) (xy 366.197027 -248.354607) (xy 366.144631 -248.374371) (xy 366.089909 -248.38626)
			(xy 366.062006 -248.388632) (xy 366.049814 -248.389394) (xy 366.02924 -248.401586) (xy 365.972344 -248.49201)
			(xy 365.970058 -248.515886) (xy 365.97463 -248.527316) (xy 365.983169 -248.549826) (xy 365.995172 -248.596449)
			(xy 366.001203 -248.644214) (xy 366.001554 -248.668286) (xy 366.00091 -248.699659) (xy 365.990636 -248.761558)
			(xy 365.970377 -248.820943) (xy 365.956088 -248.84888) (xy 365.952544 -248.855484) (xy 372.001286 -248.855484)
			(xy 372.005357 -248.799862) (xy 372.017483 -248.745425) (xy 372.037406 -248.693334) (xy 372.064702 -248.644699)
			(xy 372.098788 -248.600556) (xy 372.138937 -248.561847) (xy 372.184295 -248.529396) (xy 372.233895 -248.503895)
			(xy 372.286679 -248.485888) (xy 372.341522 -248.475758) (xy 372.397256 -248.473721) (xy 372.452693 -248.479821)
			(xy 372.50665 -248.493927) (xy 372.557979 -248.515739) (xy 372.605585 -248.544793) (xy 372.648453 -248.580468)
			(xy 372.68567 -248.622005) (xy 372.716443 -248.668518) (xy 372.740115 -248.719015) (xy 372.756183 -248.772422)
			(xy 372.764303 -248.827598) (xy 372.764812 -248.855484) (xy 372.764303 -248.88337) (xy 372.756183 -248.938546)
			(xy 372.740115 -248.991953) (xy 372.734552 -249.00382) (xy 373.276366 -249.00382) (xy 373.280437 -248.948198)
			(xy 373.292563 -248.893761) (xy 373.312486 -248.84167) (xy 373.339782 -248.793035) (xy 373.373868 -248.748892)
			(xy 373.414017 -248.710183) (xy 373.459375 -248.677732) (xy 373.508975 -248.652231) (xy 373.561759 -248.634224)
			(xy 373.616602 -248.624094) (xy 373.672336 -248.622057) (xy 373.727773 -248.628157) (xy 373.78173 -248.642263)
			(xy 373.833059 -248.664075) (xy 373.880665 -248.693129) (xy 373.923533 -248.728804) (xy 373.96075 -248.770341)
			(xy 373.991523 -248.816854) (xy 374.015195 -248.867351) (xy 374.031263 -248.920758) (xy 374.039383 -248.975934)
			(xy 374.039892 -249.00382) (xy 374.292366 -249.00382) (xy 374.296437 -248.948198) (xy 374.308563 -248.893761)
			(xy 374.328486 -248.84167) (xy 374.355782 -248.793035) (xy 374.389868 -248.748892) (xy 374.430017 -248.710183)
			(xy 374.475375 -248.677732) (xy 374.524975 -248.652231) (xy 374.577759 -248.634224) (xy 374.632602 -248.624094)
			(xy 374.688336 -248.622057) (xy 374.743773 -248.628157) (xy 374.79773 -248.642263) (xy 374.849059 -248.664075)
			(xy 374.896665 -248.693129) (xy 374.939533 -248.728804) (xy 374.97675 -248.770341) (xy 375.007523 -248.816854)
			(xy 375.031195 -248.867351) (xy 375.047263 -248.920758) (xy 375.055383 -248.975934) (xy 375.055892 -249.00382)
			(xy 375.055383 -249.031706) (xy 375.047263 -249.086882) (xy 375.031195 -249.140289) (xy 375.007523 -249.190786)
			(xy 374.97675 -249.237299) (xy 374.939533 -249.278836) (xy 374.896665 -249.314511) (xy 374.849059 -249.343565)
			(xy 374.79773 -249.365377) (xy 374.743773 -249.379483) (xy 374.688336 -249.385583) (xy 374.632602 -249.383546)
			(xy 374.577759 -249.373416) (xy 374.524975 -249.355409) (xy 374.475375 -249.329908) (xy 374.430017 -249.297457)
			(xy 374.389868 -249.258748) (xy 374.355782 -249.214605) (xy 374.328486 -249.16597) (xy 374.308563 -249.113879)
			(xy 374.296437 -249.059442) (xy 374.292366 -249.00382) (xy 374.039892 -249.00382) (xy 374.039383 -249.031706)
			(xy 374.031263 -249.086882) (xy 374.015195 -249.140289) (xy 373.991523 -249.190786) (xy 373.96075 -249.237299)
			(xy 373.923533 -249.278836) (xy 373.880665 -249.314511) (xy 373.833059 -249.343565) (xy 373.78173 -249.365377)
			(xy 373.727773 -249.379483) (xy 373.672336 -249.385583) (xy 373.616602 -249.383546) (xy 373.561759 -249.373416)
			(xy 373.508975 -249.355409) (xy 373.459375 -249.329908) (xy 373.414017 -249.297457) (xy 373.373868 -249.258748)
			(xy 373.339782 -249.214605) (xy 373.312486 -249.16597) (xy 373.292563 -249.113879) (xy 373.280437 -249.059442)
			(xy 373.276366 -249.00382) (xy 372.734552 -249.00382) (xy 372.716443 -249.04245) (xy 372.68567 -249.088963)
			(xy 372.648453 -249.1305) (xy 372.605585 -249.166175) (xy 372.557979 -249.195229) (xy 372.50665 -249.217041)
			(xy 372.452693 -249.231147) (xy 372.397256 -249.237247) (xy 372.341522 -249.23521) (xy 372.286679 -249.22508)
			(xy 372.233895 -249.207073) (xy 372.184295 -249.181572) (xy 372.138937 -249.149121) (xy 372.098788 -249.110412)
			(xy 372.064702 -249.066269) (xy 372.037406 -249.017634) (xy 372.017483 -248.965543) (xy 372.005357 -248.911106)
			(xy 372.001286 -248.855484) (xy 365.952544 -248.855484) (xy 365.9505 -248.859294) (xy 365.949738 -248.882916)
			(xy 365.992918 -248.978166) (xy 366.011206 -248.993152) (xy 366.02289 -248.995946) (xy 366.050582 -249.002858)
			(xy 366.103705 -249.023723) (xy 366.153124 -249.052271) (xy 366.197738 -249.087864) (xy 366.236551 -249.129708)
			(xy 366.268695 -249.176868) (xy 366.293452 -249.228292) (xy 366.310271 -249.28283) (xy 366.318775 -249.339266)
			(xy 366.319308 -249.367802) (xy 366.318822 -249.395053) (xy 366.311066 -249.449001) (xy 366.295711 -249.501296)
			(xy 366.273069 -249.550873) (xy 366.243603 -249.596723) (xy 366.207912 -249.637914) (xy 366.166721 -249.673605)
			(xy 366.120871 -249.703071) (xy 366.071294 -249.725713) (xy 366.018999 -249.741068) (xy 365.965051 -249.748824)
			(xy 365.910549 -249.748824) (xy 365.856601 -249.741068) (xy 365.804306 -249.725713) (xy 365.754729 -249.703071)
			(xy 365.708879 -249.673605) (xy 365.667688 -249.637914) (xy 365.631997 -249.596723) (xy 365.602531 -249.550873)
			(xy 365.579889 -249.501296) (xy 365.564534 -249.449001) (xy 365.556778 -249.395053) (xy 365.556292 -249.367802)
			(xy 365.556926 -249.336429) (xy 365.567204 -249.274529) (xy 365.587466 -249.215144) (xy 365.601758 -249.187208)
			(xy 365.607346 -249.176794) (xy 365.608108 -249.153172) (xy 365.564928 -249.057922) (xy 365.54664 -249.042936)
			(xy 365.534956 -249.040142) (xy 365.507251 -249.033279) (xy 365.454128 -249.012405) (xy 365.404709 -248.98385)
			(xy 365.360096 -248.948249) (xy 365.321286 -248.9064) (xy 365.289144 -248.859234) (xy 365.264388 -248.807806)
			(xy 365.247572 -248.753263) (xy 365.239069 -248.696824) (xy 365.238538 -248.668286) (xy 365.239084 -248.639586)
			(xy 365.247657 -248.58283) (xy 365.264638 -248.528) (xy 365.289643 -248.476333) (xy 365.322108 -248.428997)
			(xy 365.361299 -248.387059) (xy 365.406332 -248.351468) (xy 365.456189 -248.323026) (xy 365.509746 -248.302376)
			(xy 365.565792 -248.289984) (xy 365.594392 -248.28754) (xy 365.606584 -248.286778) (xy 365.627158 -248.274586)
			(xy 365.684054 -248.184162) (xy 365.68634 -248.160286) (xy 365.681768 -248.148856) (xy 365.670347 -248.118289)
			(xy 365.656936 -248.054435) (xy 365.655098 -248.021856) (xy 365.654336 -248.001282) (xy 365.624872 -247.973088)
			(xy 361.00385 -247.973088) (xy 360.992104 -247.973724) (xy 360.97106 -247.984173) (xy 360.963464 -247.993154)
			(xy 360.90733 -248.067576) (xy 360.903012 -248.09069) (xy 360.906314 -248.102374) (xy 360.913084 -248.12794)
			(xy 360.920355 -248.180324) (xy 360.920792 -248.206768) (xy 360.920306 -248.234019) (xy 360.91255 -248.287967)
			(xy 360.897195 -248.340262) (xy 360.874553 -248.389839) (xy 360.845087 -248.435689) (xy 360.809396 -248.47688)
			(xy 360.768205 -248.512571) (xy 360.722355 -248.542037) (xy 360.672778 -248.564679) (xy 360.620483 -248.580034)
			(xy 360.566535 -248.58779) (xy 360.512033 -248.58779) (xy 360.458085 -248.580034) (xy 360.40579 -248.564679)
			(xy 360.356213 -248.542037) (xy 360.310363 -248.512571) (xy 360.269172 -248.47688) (xy 360.233481 -248.435689)
			(xy 360.204015 -248.389839) (xy 360.181373 -248.340262) (xy 360.166018 -248.287967) (xy 360.158262 -248.234019)
			(xy 360.157776 -248.206768) (xy 360.158206 -248.180324) (xy 360.16547 -248.127937) (xy 360.172254 -248.102374)
			(xy 360.175556 -248.09069) (xy 360.171238 -248.067576) (xy 360.115104 -247.993154) (xy 360.10755 -247.984124)
			(xy 360.086479 -247.973676) (xy 360.074718 -247.973088) (xy 332.01229 -247.973088) (xy 332.00232 -247.973536)
			(xy 331.983883 -247.98113) (xy 331.976476 -247.98782) (xy 331.077316 -248.88698) (xy 331.77556 -248.88698)
			(xy 331.779631 -248.831358) (xy 331.791757 -248.776921) (xy 331.81168 -248.72483) (xy 331.838976 -248.676195)
			(xy 331.873062 -248.632052) (xy 331.913211 -248.593343) (xy 331.958569 -248.560892) (xy 332.008169 -248.535391)
			(xy 332.060953 -248.517384) (xy 332.115796 -248.507254) (xy 332.17153 -248.505217) (xy 332.226967 -248.511317)
			(xy 332.280924 -248.525423) (xy 332.332253 -248.547235) (xy 332.379859 -248.576289) (xy 332.422727 -248.611964)
			(xy 332.459944 -248.653501) (xy 332.490717 -248.700014) (xy 332.514389 -248.750511) (xy 332.530457 -248.803918)
			(xy 332.538577 -248.859094) (xy 332.539086 -248.88698) (xy 332.538577 -248.914866) (xy 332.530457 -248.970042)
			(xy 332.514389 -249.023449) (xy 332.490717 -249.073946) (xy 332.459944 -249.120459) (xy 332.422727 -249.161996)
			(xy 332.379859 -249.197671) (xy 332.332253 -249.226725) (xy 332.280924 -249.248537) (xy 332.226967 -249.262643)
			(xy 332.17153 -249.268743) (xy 332.115796 -249.266706) (xy 332.060953 -249.256576) (xy 332.008169 -249.238569)
			(xy 331.958569 -249.213068) (xy 331.913211 -249.180617) (xy 331.873062 -249.141908) (xy 331.838976 -249.097765)
			(xy 331.81168 -249.04913) (xy 331.791757 -248.997039) (xy 331.779631 -248.942602) (xy 331.77556 -248.88698)
			(xy 331.077316 -248.88698) (xy 330.669392 -249.294904) (xy 330.645839 -249.317847) (xy 330.594422 -249.358839)
			(xy 330.538744 -249.393822) (xy 330.479501 -249.422357) (xy 330.417439 -249.444088) (xy 330.353336 -249.45874)
			(xy 330.287996 -249.466131) (xy 330.255118 -249.466608) (xy 328.328274 -249.466608) (xy 328.294176 -249.466051)
			(xy 328.226442 -249.458131) (xy 328.160086 -249.442402) (xy 328.096004 -249.419075) (xy 328.035063 -249.388467)
			(xy 327.978087 -249.350992) (xy 327.925848 -249.307155) (xy 327.87905 -249.25755) (xy 327.838327 -249.202848)
			(xy 327.804231 -249.143789) (xy 327.77722 -249.08117) (xy 327.757662 -249.01584) (xy 327.745821 -248.94868)
			(xy 327.741855 -248.8806) (xy 298.265596 -248.8806) (xy 298.265596 -250.263406) (xy 304.873658 -250.263406)
			(xy 304.877729 -250.207784) (xy 304.889855 -250.153347) (xy 304.909778 -250.101256) (xy 304.937074 -250.052621)
			(xy 304.97116 -250.008478) (xy 305.011309 -249.969769) (xy 305.056667 -249.937318) (xy 305.106267 -249.911817)
			(xy 305.159051 -249.89381) (xy 305.213894 -249.88368) (xy 305.269628 -249.881643) (xy 305.325065 -249.887743)
			(xy 305.379022 -249.901849) (xy 305.430351 -249.923661) (xy 305.477957 -249.952715) (xy 305.520825 -249.98839)
			(xy 305.558042 -250.029927) (xy 305.588815 -250.07644) (xy 305.612487 -250.126937) (xy 305.628555 -250.180344)
			(xy 305.636675 -250.23552) (xy 305.637184 -250.263406) (xy 305.636675 -250.291292) (xy 305.628555 -250.346468)
			(xy 305.612487 -250.399875) (xy 305.588815 -250.450372) (xy 305.558042 -250.496885) (xy 305.520825 -250.538422)
			(xy 305.477957 -250.574097) (xy 305.430351 -250.603151) (xy 305.379022 -250.624963) (xy 305.325065 -250.639069)
			(xy 305.269628 -250.645169) (xy 305.213894 -250.643132) (xy 305.159051 -250.633002) (xy 305.106267 -250.614995)
			(xy 305.056667 -250.589494) (xy 305.011309 -250.557043) (xy 304.97116 -250.518334) (xy 304.937074 -250.474191)
			(xy 304.909778 -250.425556) (xy 304.889855 -250.373465) (xy 304.877729 -250.319028) (xy 304.873658 -250.263406)
			(xy 298.265596 -250.263406) (xy 298.265596 -250.985274) (xy 303.34026 -250.985274) (xy 303.344331 -250.929652)
			(xy 303.356457 -250.875215) (xy 303.37638 -250.823124) (xy 303.403676 -250.774489) (xy 303.437762 -250.730346)
			(xy 303.477911 -250.691637) (xy 303.523269 -250.659186) (xy 303.572869 -250.633685) (xy 303.625653 -250.615678)
			(xy 303.680496 -250.605548) (xy 303.73623 -250.603511) (xy 303.791667 -250.609611) (xy 303.845624 -250.623717)
			(xy 303.896953 -250.645529) (xy 303.944559 -250.674583) (xy 303.957742 -250.685554) (xy 331.738986 -250.685554)
			(xy 331.739472 -250.658303) (xy 331.747228 -250.604355) (xy 331.762583 -250.55206) (xy 331.785225 -250.502483)
			(xy 331.814691 -250.456633) (xy 331.850382 -250.415442) (xy 331.891573 -250.379751) (xy 331.937423 -250.350285)
			(xy 331.987 -250.327643) (xy 332.039295 -250.312288) (xy 332.093243 -250.304532) (xy 332.147745 -250.304532)
			(xy 332.201693 -250.312288) (xy 332.253988 -250.327643) (xy 332.303565 -250.350285) (xy 332.349415 -250.379751)
			(xy 332.390606 -250.415442) (xy 332.426297 -250.456633) (xy 332.455763 -250.502483) (xy 332.478405 -250.55206)
			(xy 332.49376 -250.604355) (xy 332.501516 -250.658303) (xy 332.502002 -250.685554) (xy 332.501422 -250.714975)
			(xy 332.492381 -250.773118) (xy 332.474521 -250.829183) (xy 332.448266 -250.881843) (xy 332.414239 -250.929847)
			(xy 332.373245 -250.972059) (xy 332.362453 -250.980194) (xy 334.149954 -250.980194) (xy 334.15044 -250.952943)
			(xy 334.158196 -250.898995) (xy 334.173551 -250.8467) (xy 334.196193 -250.797123) (xy 334.225659 -250.751273)
			(xy 334.26135 -250.710082) (xy 334.302541 -250.674391) (xy 334.348391 -250.644925) (xy 334.397968 -250.622283)
			(xy 334.450263 -250.606928) (xy 334.504211 -250.599172) (xy 334.558713 -250.599172) (xy 334.612661 -250.606928)
			(xy 334.664956 -250.622283) (xy 334.714533 -250.644925) (xy 334.760383 -250.674391) (xy 334.801574 -250.710082)
			(xy 334.837265 -250.751273) (xy 334.866731 -250.797123) (xy 334.889373 -250.8467) (xy 334.904728 -250.898995)
			(xy 334.912484 -250.952943) (xy 334.91297 -250.980194) (xy 334.912716 -250.99645) (xy 334.911954 -251.01042)
			(xy 334.924654 -251.034296) (xy 335.023968 -251.095764) (xy 335.051146 -251.096272) (xy 335.063338 -251.089668)
			(xy 335.091799 -251.074706) (xy 335.152473 -251.053433) (xy 335.21585 -251.042611) (xy 335.247996 -251.041916)
			(xy 335.281667 -251.042574) (xy 335.347973 -251.054337) (xy 335.379822 -251.065284) (xy 335.390998 -251.069602)
			(xy 335.41462 -251.067062) (xy 335.503012 -251.01042) (xy 335.515204 -250.9901) (xy 335.51622 -250.978162)
			(xy 335.51895 -250.949813) (xy 335.5318 -250.89433) (xy 335.552758 -250.841374) (xy 335.581357 -250.792124)
			(xy 335.616963 -250.747675) (xy 335.658783 -250.709015) (xy 335.705886 -250.677003) (xy 335.757227 -250.652353)
			(xy 335.811662 -250.635611) (xy 335.867982 -250.62715) (xy 335.896458 -250.626626) (xy 335.9253 -250.627162)
			(xy 335.982323 -250.635868) (xy 336.037386 -250.653058) (xy 336.089234 -250.67834) (xy 336.136686 -250.711139)
			(xy 336.17866 -250.750706) (xy 336.214201 -250.79614) (xy 336.242498 -250.846406) (xy 336.262907 -250.900359)
			(xy 336.274963 -250.956768) (xy 336.277204 -250.985528) (xy 336.277966 -250.996704) (xy 336.28838 -251.016262)
			(xy 336.367882 -251.07646) (xy 336.389726 -251.081286) (xy 336.400648 -251.078746) (xy 336.420899 -251.07456)
			(xy 336.462013 -251.070109) (xy 336.48269 -251.069856) (xy 336.51508 -251.070566) (xy 336.578925 -251.081543)
			(xy 336.60969 -251.0917) (xy 336.62112 -251.095764) (xy 336.644488 -251.092716) (xy 336.732626 -251.033788)
			(xy 336.74431 -251.013214) (xy 336.744818 -251.001022) (xy 336.746881 -250.972103) (xy 336.758612 -250.915328)
			(xy 336.7788 -250.860981) (xy 336.806978 -250.810316) (xy 336.842498 -250.764497) (xy 336.884543 -250.72458)
			(xy 336.932143 -250.691485) (xy 336.984203 -250.665974) (xy 337.039523 -250.648634) (xy 337.096831 -250.639864)
			(xy 337.125818 -250.639326) (xy 337.152086 -250.639759) (xy 337.204123 -250.646981) (xy 337.254679 -250.661271)
			(xy 337.302796 -250.682359) (xy 337.347567 -250.709848) (xy 337.368134 -250.726194) (xy 337.3755 -250.73229)
			(xy 337.393534 -250.738132) (xy 337.481164 -250.733306) (xy 337.498436 -250.725432) (xy 337.505294 -250.718574)
			(xy 337.526954 -250.697269) (xy 337.575808 -250.661154) (xy 337.629769 -250.633239) (xy 337.687472 -250.61423)
			(xy 337.747459 -250.604606) (xy 337.777836 -250.60402) (xy 337.80741 -250.604557) (xy 337.865856 -250.613646)
			(xy 337.922198 -250.631647) (xy 337.975087 -250.658128) (xy 338.023255 -250.692455) (xy 338.04479 -250.712732)
			(xy 338.051648 -250.71959) (xy 338.06892 -250.726956) (xy 338.156804 -250.72975) (xy 338.174584 -250.723654)
			(xy 338.18195 -250.717304) (xy 338.202818 -250.70001) (xy 338.248496 -250.670844) (xy 338.297844 -250.648439)
			(xy 338.349868 -250.633248) (xy 338.403518 -250.625577) (xy 338.430616 -250.625102) (xy 338.457868 -250.625563)
			(xy 338.511817 -250.633322) (xy 338.564113 -250.64868) (xy 338.613691 -250.671323) (xy 338.659542 -250.700792)
			(xy 338.700732 -250.736486) (xy 338.736423 -250.777679) (xy 338.765889 -250.823532) (xy 338.78853 -250.873111)
			(xy 338.803884 -250.925408) (xy 338.811639 -250.979358) (xy 338.812124 -251.00661) (xy 338.811938 -251.023272)
			(xy 338.809014 -251.056467) (xy 338.806282 -251.072904) (xy 338.803996 -251.086366) (xy 338.81314 -251.111766)
			(xy 338.90077 -251.186188) (xy 338.927186 -251.191014) (xy 338.94014 -251.186442) (xy 338.970851 -251.176359)
			(xy 339.034568 -251.165508) (xy 339.066886 -251.164852) (xy 339.091965 -251.165232) (xy 339.14169 -251.1718)
			(xy 339.190131 -251.18481) (xy 339.213444 -251.194062) (xy 339.226398 -251.19965) (xy 339.25383 -251.19584)
			(xy 339.34527 -251.122688) (xy 339.355176 -251.09678) (xy 339.352636 -251.083064) (xy 339.350003 -251.066874)
			(xy 339.347206 -251.034188) (xy 339.347048 -251.017786) (xy 339.34757 -250.990534) (xy 339.355329 -250.936584)
			(xy 339.370687 -250.884288) (xy 339.393331 -250.83471) (xy 339.422801 -250.788859) (xy 339.458496 -250.747669)
			(xy 339.499689 -250.711978) (xy 339.545543 -250.682513) (xy 339.595124 -250.659874) (xy 339.647421 -250.644521)
			(xy 339.701372 -250.636768) (xy 339.755876 -250.636771) (xy 339.809826 -250.644531) (xy 339.862121 -250.659891)
			(xy 339.911699 -250.682536) (xy 339.957549 -250.712007) (xy 339.998738 -250.747703) (xy 340.034428 -250.788898)
			(xy 340.063892 -250.834752) (xy 340.08653 -250.884333) (xy 340.101881 -250.936631) (xy 340.109633 -250.990582)
			(xy 340.109628 -251.045086) (xy 340.101866 -251.099035) (xy 340.086506 -251.151331) (xy 340.063859 -251.200908)
			(xy 340.034387 -251.246757) (xy 339.99869 -251.287945) (xy 339.957494 -251.323634) (xy 339.911639 -251.353096)
			(xy 339.862058 -251.375733) (xy 339.809759 -251.391083) (xy 339.755808 -251.398834) (xy 339.728556 -251.399294)
			(xy 339.703478 -251.398897) (xy 339.653753 -251.392336) (xy 339.605312 -251.379332) (xy 339.581998 -251.370084)
			(xy 339.569044 -251.364496) (xy 339.541612 -251.368306) (xy 339.450172 -251.441458) (xy 339.440266 -251.467366)
			(xy 339.442806 -251.481082) (xy 339.445433 -251.497273) (xy 339.448233 -251.529958) (xy 339.448394 -251.54636)
			(xy 339.447908 -251.573611) (xy 339.440152 -251.627559) (xy 339.424797 -251.679854) (xy 339.402155 -251.729431)
			(xy 339.372689 -251.775281) (xy 339.336998 -251.816472) (xy 339.295807 -251.852163) (xy 339.249957 -251.881629)
			(xy 339.20038 -251.904271) (xy 339.148085 -251.919626) (xy 339.094137 -251.927382) (xy 339.039635 -251.927382)
			(xy 338.985687 -251.919626) (xy 338.933392 -251.904271) (xy 338.883815 -251.881629) (xy 338.837965 -251.852163)
			(xy 338.796774 -251.816472) (xy 338.761083 -251.775281) (xy 338.731617 -251.729431) (xy 338.708975 -251.679854)
			(xy 338.69362 -251.627559) (xy 338.685864 -251.573611) (xy 338.685378 -251.54636) (xy 338.68556 -251.529698)
			(xy 338.688487 -251.496503) (xy 338.69122 -251.480066) (xy 338.693506 -251.466604) (xy 338.684362 -251.441204)
			(xy 338.596732 -251.366782) (xy 338.570316 -251.361956) (xy 338.557362 -251.366528) (xy 338.52665 -251.376609)
			(xy 338.462934 -251.387461) (xy 338.430616 -251.388118) (xy 338.401041 -251.3876) (xy 338.342595 -251.378505)
			(xy 338.286253 -251.360499) (xy 338.233365 -251.334014) (xy 338.185197 -251.299684) (xy 338.163662 -251.279406)
			(xy 338.156804 -251.272548) (xy 338.139532 -251.265182) (xy 338.051648 -251.262388) (xy 338.033868 -251.268484)
			(xy 338.026502 -251.274834) (xy 338.015692 -251.283947) (xy 337.992936 -251.300729) (xy 337.981036 -251.308362)
			(xy 337.97113 -251.314712) (xy 337.958938 -251.334016) (xy 337.947508 -251.436378) (xy 337.954874 -251.457968)
			(xy 337.963256 -251.46635) (xy 337.984125 -251.487933) (xy 338.019455 -251.536473) (xy 338.046743 -251.589948)
			(xy 338.065315 -251.647039) (xy 338.074713 -251.706334) (xy 338.07527 -251.736352) (xy 338.074784 -251.763603)
			(xy 338.067028 -251.817551) (xy 338.051673 -251.869846) (xy 338.029031 -251.919423) (xy 337.999565 -251.965273)
			(xy 337.963874 -252.006464) (xy 337.922683 -252.042155) (xy 337.876833 -252.071621) (xy 337.827256 -252.094263)
			(xy 337.774961 -252.109618) (xy 337.721013 -252.117374) (xy 337.666511 -252.117374) (xy 337.612563 -252.109618)
			(xy 337.560268 -252.094263) (xy 337.510691 -252.071621) (xy 337.464841 -252.042155) (xy 337.42365 -252.006464)
			(xy 337.387959 -251.965273) (xy 337.358493 -251.919423) (xy 337.335851 -251.869846) (xy 337.320496 -251.817551)
			(xy 337.31274 -251.763603) (xy 337.312254 -251.736352) (xy 337.312713 -251.710024) (xy 337.319973 -251.657869)
			(xy 337.334334 -251.607208) (xy 337.355523 -251.559003) (xy 337.383138 -251.514168) (xy 337.416655 -251.473556)
			(xy 337.455438 -251.437937) (xy 337.498749 -251.407988) (xy 337.522058 -251.395738) (xy 337.529453 -251.391622)
			(xy 337.541262 -251.379516) (xy 337.548499 -251.36423) (xy 337.549744 -251.35586) (xy 337.556348 -251.29617)
			(xy 337.53552 -251.280168) (xy 337.528154 -251.274072) (xy 337.51012 -251.26823) (xy 337.42249 -251.273056)
			(xy 337.405218 -251.28093) (xy 337.39836 -251.287788) (xy 337.376669 -251.30906) (xy 337.327824 -251.345181)
			(xy 337.273871 -251.373103) (xy 337.216174 -251.39212) (xy 337.156193 -251.401752) (xy 337.125818 -251.402342)
			(xy 337.093428 -251.40163) (xy 337.029583 -251.390654) (xy 336.998818 -251.380498) (xy 336.987388 -251.376434)
			(xy 336.96402 -251.379482) (xy 336.875882 -251.43841) (xy 336.864198 -251.458984) (xy 336.86369 -251.471176)
			(xy 336.861617 -251.500094) (xy 336.849887 -251.556869) (xy 336.8297 -251.611214) (xy 336.801523 -251.66188)
			(xy 336.766003 -251.707698) (xy 336.72396 -251.747615) (xy 336.676361 -251.78071) (xy 336.624303 -251.806221)
			(xy 336.568983 -251.823562) (xy 336.511677 -251.832333) (xy 336.48269 -251.832872) (xy 336.453847 -251.832386)
			(xy 336.396822 -251.823672) (xy 336.341758 -251.806475) (xy 336.289909 -251.781186) (xy 336.242458 -251.748382)
			(xy 336.200484 -251.70881) (xy 336.164944 -251.663371) (xy 336.136648 -251.613101) (xy 336.11624 -251.559144)
			(xy 336.104185 -251.502731) (xy 336.101944 -251.47397) (xy 336.101182 -251.462794) (xy 336.090768 -251.443236)
			(xy 336.011266 -251.383038) (xy 335.989422 -251.378212) (xy 335.9785 -251.380752) (xy 335.958248 -251.38493)
			(xy 335.917135 -251.389387) (xy 335.896458 -251.389642) (xy 335.862788 -251.388966) (xy 335.796482 -251.377215)
			(xy 335.764632 -251.366274) (xy 335.753456 -251.361956) (xy 335.729834 -251.364496) (xy 335.641442 -251.421138)
			(xy 335.62925 -251.441458) (xy 335.628234 -251.453396) (xy 335.625514 -251.481747) (xy 335.612668 -251.537233)
			(xy 335.591712 -251.590192) (xy 335.563113 -251.639445) (xy 335.527507 -251.683896) (xy 335.485685 -251.722557)
			(xy 335.438578 -251.754568) (xy 335.387235 -251.779217) (xy 335.332796 -251.795956) (xy 335.276473 -251.804411)
			(xy 335.247996 -251.804932) (xy 335.217438 -251.804332) (xy 335.157106 -251.794579) (xy 335.099099 -251.775337)
			(xy 335.07172 -251.761752) (xy 335.062322 -251.756926) (xy 335.041494 -251.755402) (xy 334.951324 -251.786898)
			(xy 334.936084 -251.801122) (xy 334.931766 -251.811028) (xy 334.920225 -251.836087) (xy 334.890949 -251.88285)
			(xy 334.855245 -251.924911) (xy 334.813857 -251.961392) (xy 334.767648 -251.991534) (xy 334.71758 -252.014708)
			(xy 334.664697 -252.030432) (xy 334.610101 -252.038378) (xy 334.582516 -252.038866) (xy 334.555262 -252.03843)
			(xy 334.501308 -252.030674) (xy 334.449007 -252.015318) (xy 334.399424 -251.992674) (xy 334.353569 -251.963204)
			(xy 334.312375 -251.927507) (xy 334.276681 -251.886311) (xy 334.247214 -251.840453) (xy 334.224573 -251.790869)
			(xy 334.209221 -251.738567) (xy 334.201468 -251.684612) (xy 334.201008 -251.657358) (xy 334.201478 -251.630494)
			(xy 334.209021 -251.577299) (xy 334.223951 -251.525687) (xy 334.245973 -251.47668) (xy 334.274651 -251.431247)
			(xy 334.291686 -251.41047) (xy 334.29829 -251.402596) (xy 334.304386 -251.3838) (xy 334.297528 -251.29236)
			(xy 334.288638 -251.27458) (xy 334.281018 -251.267976) (xy 334.260831 -251.249765) (xy 334.225299 -251.208618)
			(xy 334.195968 -251.162842) (xy 334.173434 -251.113366) (xy 334.158153 -251.061192) (xy 334.150435 -251.007377)
			(xy 334.149954 -250.980194) (xy 332.362453 -250.980194) (xy 332.326257 -251.007478) (xy 332.30058 -251.02185)
			(xy 332.288653 -251.028799) (xy 332.268692 -251.047844) (xy 332.254569 -251.071545) (xy 332.247318 -251.098164)
			(xy 332.247471 -251.125752) (xy 332.255015 -251.15229) (xy 332.269399 -251.175833) (xy 332.289569 -251.194656)
			(xy 332.301596 -251.201428) (xy 332.324471 -251.21382) (xy 332.366918 -251.243902) (xy 332.404881 -251.279474)
			(xy 332.437658 -251.319876) (xy 332.464638 -251.364358) (xy 332.485323 -251.412095) (xy 332.499327 -251.4622)
			(xy 332.50639 -251.513743) (xy 332.506828 -251.539756) (xy 332.506342 -251.567007) (xy 332.498586 -251.620955)
			(xy 332.483231 -251.67325) (xy 332.460589 -251.722827) (xy 332.431123 -251.768677) (xy 332.395432 -251.809868)
			(xy 332.354241 -251.845559) (xy 332.308391 -251.875025) (xy 332.258814 -251.897667) (xy 332.206519 -251.913022)
			(xy 332.152571 -251.920778) (xy 332.098069 -251.920778) (xy 332.044121 -251.913022) (xy 331.991826 -251.897667)
			(xy 331.942249 -251.875025) (xy 331.896399 -251.845559) (xy 331.855208 -251.809868) (xy 331.819517 -251.768677)
			(xy 331.790051 -251.722827) (xy 331.767409 -251.67325) (xy 331.752054 -251.620955) (xy 331.744298 -251.567007)
			(xy 331.743812 -251.539756) (xy 331.744392 -251.510335) (xy 331.753433 -251.452192) (xy 331.771292 -251.396126)
			(xy 331.797546 -251.343466) (xy 331.831574 -251.295462) (xy 331.872568 -251.25325) (xy 331.919557 -251.217832)
			(xy 331.945234 -251.20346) (xy 331.957151 -251.196496) (xy 331.977108 -251.177452) (xy 331.991229 -251.153755)
			(xy 331.998479 -251.127139) (xy 331.998328 -251.099554) (xy 331.990786 -251.07302) (xy 331.976407 -251.049479)
			(xy 331.956242 -251.030655) (xy 331.944218 -251.023882) (xy 331.921327 -251.011519) (xy 331.878884 -250.981429)
			(xy 331.840924 -250.945851) (xy 331.808151 -250.905444) (xy 331.781173 -250.860958) (xy 331.760491 -250.813219)
			(xy 331.746488 -250.763112) (xy 331.739424 -250.711567) (xy 331.738986 -250.685554) (xy 303.957742 -250.685554)
			(xy 303.987427 -250.710258) (xy 304.024644 -250.751795) (xy 304.055417 -250.798308) (xy 304.079089 -250.848805)
			(xy 304.095157 -250.902212) (xy 304.103277 -250.957388) (xy 304.103786 -250.985274) (xy 304.103277 -251.01316)
			(xy 304.095157 -251.068336) (xy 304.079089 -251.121743) (xy 304.055417 -251.17224) (xy 304.024644 -251.218753)
			(xy 303.987427 -251.26029) (xy 303.944559 -251.295965) (xy 303.896953 -251.325019) (xy 303.845624 -251.346831)
			(xy 303.791667 -251.360937) (xy 303.73623 -251.367037) (xy 303.680496 -251.365) (xy 303.625653 -251.35487)
			(xy 303.572869 -251.336863) (xy 303.523269 -251.311362) (xy 303.477911 -251.278911) (xy 303.437762 -251.240202)
			(xy 303.403676 -251.196059) (xy 303.37638 -251.147424) (xy 303.356457 -251.095333) (xy 303.344331 -251.040896)
			(xy 303.34026 -250.985274) (xy 298.265596 -250.985274) (xy 298.265596 -253.671651) (xy 303.479178 -253.671651)
			(xy 303.479178 -253.617149) (xy 303.486934 -253.563201) (xy 303.502289 -253.510906) (xy 303.524931 -253.461329)
			(xy 303.554397 -253.415479) (xy 303.590088 -253.374288) (xy 303.631279 -253.338597) (xy 303.677129 -253.309131)
			(xy 303.726706 -253.286489) (xy 303.779001 -253.271134) (xy 303.832949 -253.263378) (xy 303.8602 -253.262892)
			(xy 303.88676 -253.263331) (xy 303.939368 -253.270696) (xy 303.990447 -253.285285) (xy 304.039009 -253.306815)
			(xy 304.084117 -253.33487) (xy 304.104802 -253.351538) (xy 304.112168 -253.357634) (xy 304.129694 -253.36373)
			(xy 304.216816 -253.360428) (xy 304.233834 -253.353062) (xy 304.240692 -253.346458) (xy 304.262164 -253.326307)
			(xy 304.310198 -253.292245) (xy 304.362893 -253.265965) (xy 304.419001 -253.248093) (xy 304.477187 -253.239051)
			(xy 304.50663 -253.238508) (xy 304.532382 -253.238954) (xy 304.583416 -253.245898) (xy 304.633053 -253.259641)
			(xy 304.680391 -253.279935) (xy 304.72457 -253.30641) (xy 304.764787 -253.338586) (xy 304.800312 -253.375878)
			(xy 304.815748 -253.396496) (xy 304.823368 -253.40691) (xy 304.846228 -253.418086) (xy 304.95748 -253.412498)
			(xy 304.97907 -253.39929) (xy 304.985674 -253.388114) (xy 305.000486 -253.363868) (xy 305.036116 -253.319614)
			(xy 305.077914 -253.281132) (xy 305.124956 -253.249274) (xy 305.176201 -253.224743) (xy 305.230518 -253.208082)
			(xy 305.286705 -253.19966) (xy 305.315112 -253.199138) (xy 305.342366 -253.199533) (xy 305.396319 -253.207292)
			(xy 305.448619 -253.22265) (xy 305.4982 -253.245294) (xy 305.544055 -253.274764) (xy 305.585248 -253.31046)
			(xy 305.620943 -253.351655) (xy 305.650412 -253.39751) (xy 305.673055 -253.447093) (xy 305.688411 -253.499393)
			(xy 305.696168 -253.553346) (xy 305.696168 -253.607854) (xy 305.688411 -253.661807) (xy 305.673055 -253.714107)
			(xy 305.650412 -253.76369) (xy 305.620943 -253.809545) (xy 305.585248 -253.85074) (xy 305.544055 -253.886436)
			(xy 305.4982 -253.915906) (xy 305.448619 -253.93855) (xy 305.396319 -253.953908) (xy 305.342366 -253.961667)
			(xy 305.315112 -253.962154) (xy 305.28936 -253.961693) (xy 305.238326 -253.954754) (xy 305.188689 -253.941014)
			(xy 305.14135 -253.920723) (xy 305.097171 -253.89425) (xy 305.056954 -253.862075) (xy 305.02143 -253.824783)
			(xy 305.005994 -253.804166) (xy 304.998374 -253.793752) (xy 304.975514 -253.782576) (xy 304.864262 -253.788164)
			(xy 304.842672 -253.801372) (xy 304.836068 -253.812548) (xy 304.821282 -253.836811) (xy 304.78565 -253.881067)
			(xy 304.743848 -253.919549) (xy 304.696802 -253.951407) (xy 304.645551 -253.975935) (xy 304.59123 -253.992591)
			(xy 304.535039 -254.001007) (xy 304.50663 -254.001524) (xy 304.48007 -254.001064) (xy 304.427463 -253.993703)
			(xy 304.376385 -253.979119) (xy 304.327823 -253.957594) (xy 304.282713 -253.929543) (xy 304.262028 -253.912878)
			(xy 304.254662 -253.906782) (xy 304.237136 -253.900686) (xy 304.150014 -253.903988) (xy 304.132996 -253.911354)
			(xy 304.126138 -253.917958) (xy 304.104655 -253.938097) (xy 304.056625 -253.972161) (xy 304.003931 -253.998442)
			(xy 303.947827 -254.016317) (xy 303.889642 -254.025362) (xy 303.8602 -254.025908) (xy 303.832949 -254.025422)
			(xy 303.779001 -254.017666) (xy 303.726706 -254.002311) (xy 303.677129 -253.979669) (xy 303.631279 -253.950203)
			(xy 303.590088 -253.914512) (xy 303.554397 -253.873321) (xy 303.524931 -253.827471) (xy 303.502289 -253.777894)
			(xy 303.486934 -253.725599) (xy 303.479178 -253.671651) (xy 298.265596 -253.671651) (xy 298.265596 -254.138938)
			(xy 298.266026 -254.149005) (xy 298.27375 -254.1676) (xy 298.280582 -254.175006) (xy 298.632626 -254.52705)
			(xy 298.640024 -254.533898) (xy 298.658622 -254.54163) (xy 298.668694 -254.542036) (xy 300.80712 -254.542036)
			(xy 300.81214 -254.542125) (xy 300.821993 -254.544041) (xy 300.826678 -254.545846) (xy 300.84395 -254.553212)
			(xy 300.848636 -254.555015) (xy 300.858488 -254.556942) (xy 300.863508 -254.557022) (xy 315.624972 -254.557022)
			(xy 315.633609 -254.556681) (xy 315.649895 -254.550925) (xy 315.663327 -254.540064) (xy 315.668152 -254.532892)
			(xy 315.70803 -254.468122) (xy 315.709904 -254.464951) (xy 315.712831 -254.458193) (xy 315.713872 -254.45466)
			(xy 315.71565 -254.441452) (xy 315.71565 -254.426974) (xy 315.71438 -254.415544) (xy 315.71184 -254.404876)
			(xy 315.710824 -254.399288) (xy 315.708284 -254.393954) (xy 315.69772 -254.369369) (xy 315.682813 -254.317978)
			(xy 315.675246 -254.265006) (xy 315.674756 -254.238252) (xy 315.674756 -254.23368) (xy 315.675536 -254.206151)
			(xy 315.684039 -254.15174) (xy 315.700274 -254.099116) (xy 315.723904 -254.049372) (xy 315.754438 -254.00354)
			(xy 315.791242 -253.962572) (xy 315.833552 -253.92732) (xy 315.880489 -253.898515) (xy 315.931079 -253.876755)
			(xy 315.984272 -253.862491) (xy 316.01156 -253.858776) (xy 316.024768 -253.857252) (xy 316.055756 -253.855982)
			(xy 316.056264 -253.855982) (xy 316.082997 -253.856435) (xy 316.135938 -253.863907) (xy 316.187317 -253.878695)
			(xy 316.23613 -253.90051) (xy 316.28142 -253.928924) (xy 316.3223 -253.963382) (xy 316.357971 -254.003209)
			(xy 316.373256 -254.025146) (xy 316.37351 -254.025654) (xy 316.379606 -254.03429) (xy 316.388242 -254.039878)
			(xy 316.392681 -254.042648) (xy 316.402412 -254.046487) (xy 316.407546 -254.047498) (xy 316.491112 -254.061214)
			(xy 316.511432 -254.056134) (xy 316.519814 -254.04953) (xy 316.539934 -254.034469) (xy 316.583378 -254.009199)
			(xy 316.629763 -253.989851) (xy 316.678288 -253.97676) (xy 316.728111 -253.970154) (xy 316.75324 -253.969774)
			(xy 316.78049 -253.970262) (xy 316.834434 -253.978024) (xy 316.886725 -253.993382) (xy 316.936299 -254.016025)
			(xy 316.982145 -254.045492) (xy 317.023332 -254.081183) (xy 317.059021 -254.122372) (xy 317.088485 -254.168221)
			(xy 317.111126 -254.217795) (xy 317.126481 -254.270087) (xy 317.134239 -254.324032) (xy 317.134748 -254.351282)
			(xy 317.134748 -254.352044) (xy 317.134463 -254.372593) (xy 317.130011 -254.413451) (xy 317.125858 -254.433578)
			(xy 317.123318 -254.445008) (xy 317.128652 -254.46736) (xy 317.185294 -254.537972) (xy 317.192927 -254.546483)
			(xy 317.213504 -254.556372) (xy 317.224918 -254.557022) (xy 342.027764 -254.557022) (xy 342.03783 -254.556588)
			(xy 342.056419 -254.54886) (xy 342.063832 -254.542036) (xy 345.75369 -250.852178) (xy 345.761084 -250.845321)
			(xy 345.779683 -250.837571) (xy 345.789758 -250.837192) (xy 347.859604 -250.837192) (xy 347.870798 -250.836601)
			(xy 347.891072 -250.827102) (xy 347.89872 -250.818904) (xy 347.899228 -250.818396) (xy 347.956378 -250.74626)
			(xy 347.961458 -250.723908) (xy 347.958664 -250.712478) (xy 347.954036 -250.691188) (xy 347.949074 -250.647903)
			(xy 347.948758 -250.626118) (xy 347.949244 -250.598867) (xy 347.957 -250.544919) (xy 347.972355 -250.492624)
			(xy 347.994997 -250.443047) (xy 348.024463 -250.397197) (xy 348.060154 -250.356006) (xy 348.101345 -250.320315)
			(xy 348.147195 -250.290849) (xy 348.196772 -250.268207) (xy 348.249067 -250.252852) (xy 348.303015 -250.245096)
			(xy 348.357517 -250.245096) (xy 348.411465 -250.252852) (xy 348.46376 -250.268207) (xy 348.513337 -250.290849)
			(xy 348.548662 -250.313551) (xy 358.022644 -250.313551) (xy 358.022644 -250.259049) (xy 358.0304 -250.2051)
			(xy 358.045754 -250.152805) (xy 358.068393 -250.103226) (xy 358.097858 -250.057374) (xy 358.133547 -250.016181)
			(xy 358.174736 -249.980487) (xy 358.220584 -249.951016) (xy 358.27016 -249.928371) (xy 358.322453 -249.91301)
			(xy 358.376401 -249.905247) (xy 358.403652 -249.904758) (xy 358.43065 -249.905222) (xy 358.484107 -249.912818)
			(xy 358.535959 -249.927878) (xy 358.585168 -249.950102) (xy 358.63075 -249.979046) (xy 358.671794 -250.014129)
			(xy 358.707478 -250.054652) (xy 358.722676 -250.07697) (xy 358.730722 -250.088301) (xy 358.75165 -250.106562)
			(xy 358.776724 -250.118507) (xy 358.80409 -250.123255) (xy 358.831724 -250.120453) (xy 358.857579 -250.110308)
			(xy 358.879745 -250.093572) (xy 358.888538 -250.082812) (xy 358.906665 -250.059774) (xy 358.948819 -250.019042)
			(xy 358.996711 -249.985241) (xy 359.049212 -249.959169) (xy 359.105085 -249.94144) (xy 359.163013 -249.932471)
			(xy 359.192322 -249.931936) (xy 359.219575 -249.932335) (xy 359.273527 -249.940095) (xy 359.325825 -249.955454)
			(xy 359.375405 -249.978099) (xy 359.421258 -250.007569) (xy 359.462451 -250.043265) (xy 359.498144 -250.084459)
			(xy 359.527611 -250.130314) (xy 359.550254 -250.179896) (xy 359.565609 -250.232195) (xy 359.573366 -250.286147)
			(xy 359.573366 -250.340653) (xy 359.565609 -250.394605) (xy 359.550254 -250.446904) (xy 359.527611 -250.496486)
			(xy 359.498144 -250.542341) (xy 359.462451 -250.583535) (xy 359.421258 -250.619231) (xy 359.375405 -250.648701)
			(xy 359.325825 -250.671346) (xy 359.273527 -250.686705) (xy 359.219575 -250.694465) (xy 359.192322 -250.694952)
			(xy 359.165324 -250.694503) (xy 359.111866 -250.686904) (xy 359.060014 -250.671841) (xy 359.010805 -250.649614)
			(xy 358.965223 -250.620669) (xy 358.92418 -250.585583) (xy 358.888496 -250.545059) (xy 358.873298 -250.52274)
			(xy 358.865283 -250.51139) (xy 358.844342 -250.493143) (xy 358.819262 -250.481209) (xy 358.791895 -250.476469)
			(xy 358.764263 -250.479273) (xy 358.738405 -250.489414) (xy 358.716234 -250.506143) (xy 358.707436 -250.516898)
			(xy 358.689269 -250.539902) (xy 358.647123 -250.580636) (xy 358.599239 -250.61444) (xy 358.546746 -250.640518)
			(xy 358.490881 -250.658255) (xy 358.432959 -250.667233) (xy 358.403652 -250.667774) (xy 358.376401 -250.667353)
			(xy 358.322453 -250.65959) (xy 358.27016 -250.644229) (xy 358.220584 -250.621584) (xy 358.174736 -250.592113)
			(xy 358.133547 -250.556419) (xy 358.097858 -250.515226) (xy 358.068393 -250.469374) (xy 358.045754 -250.419795)
			(xy 358.0304 -250.3675) (xy 358.022644 -250.313551) (xy 348.548662 -250.313551) (xy 348.559187 -250.320315)
			(xy 348.600378 -250.356006) (xy 348.636069 -250.397197) (xy 348.665535 -250.443047) (xy 348.688177 -250.492624)
			(xy 348.703532 -250.544919) (xy 348.711288 -250.598867) (xy 348.711774 -250.626118) (xy 348.711474 -250.647903)
			(xy 348.706505 -250.69119) (xy 348.701868 -250.712478) (xy 348.699074 -250.723908) (xy 348.704154 -250.74626)
			(xy 348.76105 -250.817888) (xy 348.768623 -250.826612) (xy 348.789388 -250.836683) (xy 348.800928 -250.837192)
			(xy 354.826824 -250.837192) (xy 354.83643 -250.83677) (xy 354.854299 -250.829709) (xy 354.861622 -250.823476)
			(xy 354.919534 -250.769374) (xy 354.927662 -250.752356) (xy 354.92817 -250.74245) (xy 354.930508 -250.715233)
			(xy 354.941985 -250.661826) (xy 354.960959 -250.6106) (xy 354.987043 -250.562603) (xy 355.019704 -250.518816)
			(xy 355.058274 -250.480132) (xy 355.101966 -250.447344) (xy 355.149886 -250.421119) (xy 355.201055 -250.401995)
			(xy 355.254429 -250.390362) (xy 355.308916 -250.386458) (xy 355.363403 -250.390362) (xy 355.416777 -250.401995)
			(xy 355.467946 -250.421119) (xy 355.515866 -250.447344) (xy 355.559558 -250.480132) (xy 355.598128 -250.518816)
			(xy 355.630789 -250.562603) (xy 355.656873 -250.6106) (xy 355.675847 -250.661826) (xy 355.687324 -250.715233)
			(xy 355.689662 -250.74245) (xy 355.69017 -250.752356) (xy 355.698298 -250.769374) (xy 355.75621 -250.823476)
			(xy 355.763501 -250.829757) (xy 355.781392 -250.836806) (xy 355.791008 -250.837192) (xy 358.246426 -250.837192)
			(xy 358.256494 -250.837619) (xy 358.275093 -250.84534) (xy 358.282494 -250.852178) (xy 360.186732 -252.756416)
			(xy 360.193583 -252.763812) (xy 360.201323 -252.782411) (xy 360.201718 -252.792484) (xy 360.201718 -253.178564)
			(xy 362.549438 -253.178564) (xy 362.553509 -253.122942) (xy 362.565635 -253.068505) (xy 362.585558 -253.016414)
			(xy 362.612854 -252.967779) (xy 362.64694 -252.923636) (xy 362.687089 -252.884927) (xy 362.732447 -252.852476)
			(xy 362.782047 -252.826975) (xy 362.834831 -252.808968) (xy 362.889674 -252.798838) (xy 362.945408 -252.796801)
			(xy 363.000845 -252.802901) (xy 363.054802 -252.817007) (xy 363.106131 -252.838819) (xy 363.153737 -252.867873)
			(xy 363.196605 -252.903548) (xy 363.233822 -252.945085) (xy 363.264595 -252.991598) (xy 363.288267 -253.042095)
			(xy 363.304335 -253.095502) (xy 363.312455 -253.150678) (xy 363.312964 -253.178564) (xy 363.312455 -253.20645)
			(xy 363.304335 -253.261626) (xy 363.288267 -253.315033) (xy 363.264595 -253.36553) (xy 363.233822 -253.412043)
			(xy 363.196605 -253.45358) (xy 363.153737 -253.489255) (xy 363.106131 -253.518309) (xy 363.054802 -253.540121)
			(xy 363.000845 -253.554227) (xy 362.945408 -253.560327) (xy 362.889674 -253.55829) (xy 362.834831 -253.54816)
			(xy 362.782047 -253.530153) (xy 362.732447 -253.504652) (xy 362.687089 -253.472201) (xy 362.64694 -253.433492)
			(xy 362.612854 -253.389349) (xy 362.585558 -253.340714) (xy 362.565635 -253.288623) (xy 362.553509 -253.234186)
			(xy 362.549438 -253.178564) (xy 360.201718 -253.178564) (xy 360.201718 -254.194564) (xy 360.485942 -254.194564)
			(xy 360.490013 -254.138942) (xy 360.502139 -254.084505) (xy 360.522062 -254.032414) (xy 360.549358 -253.983779)
			(xy 360.583444 -253.939636) (xy 360.623593 -253.900927) (xy 360.668951 -253.868476) (xy 360.718551 -253.842975)
			(xy 360.771335 -253.824968) (xy 360.826178 -253.814838) (xy 360.881912 -253.812801) (xy 360.937349 -253.818901)
			(xy 360.991306 -253.833007) (xy 361.042635 -253.854819) (xy 361.090241 -253.883873) (xy 361.133109 -253.919548)
			(xy 361.170326 -253.961085) (xy 361.201099 -254.007598) (xy 361.224771 -254.058095) (xy 361.240839 -254.111502)
			(xy 361.248959 -254.166678) (xy 361.249468 -254.194564) (xy 361.248959 -254.22245) (xy 361.240839 -254.277626)
			(xy 361.224771 -254.331033) (xy 361.201099 -254.38153) (xy 361.170326 -254.428043) (xy 361.133109 -254.46958)
			(xy 361.090241 -254.505255) (xy 361.042635 -254.534309) (xy 360.991306 -254.556121) (xy 360.937349 -254.570227)
			(xy 360.881912 -254.576327) (xy 360.826178 -254.57429) (xy 360.771335 -254.56416) (xy 360.718551 -254.546153)
			(xy 360.668951 -254.520652) (xy 360.623593 -254.488201) (xy 360.583444 -254.449492) (xy 360.549358 -254.405349)
			(xy 360.522062 -254.356714) (xy 360.502139 -254.304623) (xy 360.490013 -254.250186) (xy 360.485942 -254.194564)
			(xy 360.201718 -254.194564) (xy 360.201718 -255.210564) (xy 360.485942 -255.210564) (xy 360.490013 -255.154942)
			(xy 360.502139 -255.100505) (xy 360.522062 -255.048414) (xy 360.549358 -254.999779) (xy 360.583444 -254.955636)
			(xy 360.623593 -254.916927) (xy 360.668951 -254.884476) (xy 360.718551 -254.858975) (xy 360.771335 -254.840968)
			(xy 360.826178 -254.830838) (xy 360.881912 -254.828801) (xy 360.937349 -254.834901) (xy 360.991306 -254.849007)
			(xy 361.042635 -254.870819) (xy 361.090241 -254.899873) (xy 361.133109 -254.935548) (xy 361.170326 -254.977085)
			(xy 361.201099 -255.023598) (xy 361.224771 -255.074095) (xy 361.240839 -255.127502) (xy 361.248959 -255.182678)
			(xy 361.249468 -255.210564) (xy 361.248959 -255.23845) (xy 361.240839 -255.293626) (xy 361.224771 -255.347033)
			(xy 361.217303 -255.362964) (xy 364.277908 -255.362964) (xy 364.281979 -255.307342) (xy 364.294105 -255.252905)
			(xy 364.314028 -255.200814) (xy 364.341324 -255.152179) (xy 364.37541 -255.108036) (xy 364.415559 -255.069327)
			(xy 364.460917 -255.036876) (xy 364.510517 -255.011375) (xy 364.563301 -254.993368) (xy 364.618144 -254.983238)
			(xy 364.673878 -254.981201) (xy 364.729315 -254.987301) (xy 364.783272 -255.001407) (xy 364.834601 -255.023219)
			(xy 364.882207 -255.052273) (xy 364.925075 -255.087948) (xy 364.962292 -255.129485) (xy 364.993065 -255.175998)
			(xy 365.016737 -255.226495) (xy 365.032805 -255.279902) (xy 365.040925 -255.335078) (xy 365.041434 -255.362964)
			(xy 365.040925 -255.39085) (xy 365.032805 -255.446026) (xy 365.016737 -255.499433) (xy 364.993065 -255.54993)
			(xy 364.962292 -255.596443) (xy 364.925075 -255.63798) (xy 364.882207 -255.673655) (xy 364.834601 -255.702709)
			(xy 364.783272 -255.724521) (xy 364.729315 -255.738627) (xy 364.673878 -255.744727) (xy 364.618144 -255.74269)
			(xy 364.563301 -255.73256) (xy 364.510517 -255.714553) (xy 364.460917 -255.689052) (xy 364.415559 -255.656601)
			(xy 364.37541 -255.617892) (xy 364.341324 -255.573749) (xy 364.314028 -255.525114) (xy 364.294105 -255.473023)
			(xy 364.281979 -255.418586) (xy 364.277908 -255.362964) (xy 361.217303 -255.362964) (xy 361.201099 -255.39753)
			(xy 361.170326 -255.444043) (xy 361.133109 -255.48558) (xy 361.090241 -255.521255) (xy 361.042635 -255.550309)
			(xy 360.991306 -255.572121) (xy 360.937349 -255.586227) (xy 360.881912 -255.592327) (xy 360.826178 -255.59029)
			(xy 360.771335 -255.58016) (xy 360.718551 -255.562153) (xy 360.668951 -255.536652) (xy 360.623593 -255.504201)
			(xy 360.583444 -255.465492) (xy 360.549358 -255.421349) (xy 360.522062 -255.372714) (xy 360.502139 -255.320623)
			(xy 360.490013 -255.266186) (xy 360.485942 -255.210564) (xy 360.201718 -255.210564) (xy 360.201718 -258.131564)
			(xy 360.485942 -258.131564) (xy 360.490013 -258.075942) (xy 360.502139 -258.021505) (xy 360.522062 -257.969414)
			(xy 360.549358 -257.920779) (xy 360.583444 -257.876636) (xy 360.623593 -257.837927) (xy 360.668951 -257.805476)
			(xy 360.718551 -257.779975) (xy 360.771335 -257.761968) (xy 360.826178 -257.751838) (xy 360.881912 -257.749801)
			(xy 360.937349 -257.755901) (xy 360.991306 -257.770007) (xy 361.042635 -257.791819) (xy 361.090241 -257.820873)
			(xy 361.133109 -257.856548) (xy 361.170326 -257.898085) (xy 361.201099 -257.944598) (xy 361.224771 -257.995095)
			(xy 361.240839 -258.048502) (xy 361.248959 -258.103678) (xy 361.249468 -258.131564) (xy 361.248959 -258.15945)
			(xy 361.240839 -258.214626) (xy 361.224771 -258.268033) (xy 361.201099 -258.31853) (xy 361.170326 -258.365043)
			(xy 361.133109 -258.40658) (xy 361.090241 -258.442255) (xy 361.042635 -258.471309) (xy 360.991306 -258.493121)
			(xy 360.937349 -258.507227) (xy 360.881912 -258.513327) (xy 360.826178 -258.51129) (xy 360.771335 -258.50116)
			(xy 360.718551 -258.483153) (xy 360.668951 -258.457652) (xy 360.623593 -258.425201) (xy 360.583444 -258.386492)
			(xy 360.549358 -258.342349) (xy 360.522062 -258.293714) (xy 360.502139 -258.241623) (xy 360.490013 -258.187186)
			(xy 360.485942 -258.131564) (xy 360.201718 -258.131564) (xy 360.201718 -259.147564) (xy 362.539024 -259.147564)
			(xy 362.543095 -259.091942) (xy 362.555221 -259.037505) (xy 362.575144 -258.985414) (xy 362.60244 -258.936779)
			(xy 362.636526 -258.892636) (xy 362.676675 -258.853927) (xy 362.722033 -258.821476) (xy 362.771633 -258.795975)
			(xy 362.824417 -258.777968) (xy 362.87926 -258.767838) (xy 362.934994 -258.765801) (xy 362.990431 -258.771901)
			(xy 363.044388 -258.786007) (xy 363.095717 -258.807819) (xy 363.143323 -258.836873) (xy 363.186191 -258.872548)
			(xy 363.223408 -258.914085) (xy 363.254181 -258.960598) (xy 363.277853 -259.011095) (xy 363.293921 -259.064502)
			(xy 363.302041 -259.119678) (xy 363.30255 -259.147564) (xy 363.302041 -259.17545) (xy 363.293921 -259.230626)
			(xy 363.277853 -259.284033) (xy 363.254181 -259.33453) (xy 363.223408 -259.381043) (xy 363.186191 -259.42258)
			(xy 363.143323 -259.458255) (xy 363.095717 -259.487309) (xy 363.044388 -259.509121) (xy 362.990431 -259.523227)
			(xy 362.934994 -259.529327) (xy 362.87926 -259.52729) (xy 362.824417 -259.51716) (xy 362.771633 -259.499153)
			(xy 362.722033 -259.473652) (xy 362.676675 -259.441201) (xy 362.636526 -259.402492) (xy 362.60244 -259.358349)
			(xy 362.575144 -259.309714) (xy 362.555221 -259.257623) (xy 362.543095 -259.203186) (xy 362.539024 -259.147564)
			(xy 360.201718 -259.147564) (xy 360.201718 -260.71068) (xy 360.202189 -260.720552) (xy 360.209651 -260.738833)
			(xy 360.216196 -260.74624) (xy 360.21645 -260.746494) (xy 360.898186 -261.42823) (xy 360.912918 -261.435596)
			(xy 360.9213 -261.436866) (xy 360.938812 -261.439518) (xy 360.973286 -261.447659) (xy 360.990134 -261.453122)
			(xy 360.990896 -261.453376) (xy 360.995468 -261.4549) (xy 361.00385 -261.457948)
		)
		(stroke
			(width 0)
			(type solid)
		)
		(fill yes)
		(layer "In11.Cu")
		(net "P3V3_AUX")
	)
	(gr_poly
		(pts
			(xy 276.2885 -416.411918) (xy 276.295988 -416.411607) (xy 276.310309 -416.407209) (xy 276.316694 -416.403282)
			(xy 276.327108 -416.392868) (xy 276.33422 -416.383978) (xy 276.377654 -416.315906) (xy 276.380917 -416.310443)
			(xy 276.384901 -416.298362) (xy 276.385528 -416.29203) (xy 276.38629 -416.27933) (xy 276.380702 -416.267392)
			(xy 276.369416 -416.242016) (xy 276.353472 -416.188816) (xy 276.345393 -416.13387) (xy 276.344888 -416.106102)
			(xy 276.345374 -416.078851) (xy 276.35313 -416.024903) (xy 276.368485 -415.972608) (xy 276.391127 -415.923031)
			(xy 276.420593 -415.877181) (xy 276.456284 -415.83599) (xy 276.497475 -415.800299) (xy 276.543325 -415.770833)
			(xy 276.592902 -415.748191) (xy 276.645197 -415.732836) (xy 276.699145 -415.72508) (xy 276.753647 -415.72508)
			(xy 276.807595 -415.732836) (xy 276.85989 -415.748191) (xy 276.909467 -415.770833) (xy 276.955317 -415.800299)
			(xy 276.996508 -415.83599) (xy 277.032199 -415.877181) (xy 277.061665 -415.923031) (xy 277.084307 -415.972608)
			(xy 277.099662 -416.024903) (xy 277.107418 -416.078851) (xy 277.107904 -416.106102) (xy 277.107407 -416.133872)
			(xy 277.099351 -416.188824) (xy 277.083396 -416.242023) (xy 277.07209 -416.267392) (xy 277.06954 -416.273342)
			(xy 277.067216 -416.286072) (xy 277.067518 -416.292538) (xy 277.06828 -416.304984) (xy 277.095458 -416.347656)
			(xy 277.121366 -416.388296) (xy 277.12162 -416.38855) (xy 277.122636 -416.390074) (xy 277.130247 -416.399746)
			(xy 277.152008 -416.411161) (xy 277.164292 -416.411918) (xy 277.3045 -416.411918) (xy 277.311988 -416.411607)
			(xy 277.326309 -416.407209) (xy 277.332694 -416.403282) (xy 277.343108 -416.392868) (xy 277.35022 -416.383978)
			(xy 277.393654 -416.315906) (xy 277.396917 -416.310443) (xy 277.400901 -416.298362) (xy 277.401528 -416.29203)
			(xy 277.40229 -416.27933) (xy 277.396702 -416.267392) (xy 277.385416 -416.242016) (xy 277.369472 -416.188816)
			(xy 277.361393 -416.13387) (xy 277.360888 -416.106102) (xy 277.361374 -416.078851) (xy 277.36913 -416.024903)
			(xy 277.384485 -415.972608) (xy 277.407127 -415.923031) (xy 277.436593 -415.877181) (xy 277.472284 -415.83599)
			(xy 277.513475 -415.800299) (xy 277.559325 -415.770833) (xy 277.608902 -415.748191) (xy 277.661197 -415.732836)
			(xy 277.715145 -415.72508) (xy 277.769647 -415.72508) (xy 277.823595 -415.732836) (xy 277.87589 -415.748191)
			(xy 277.925467 -415.770833) (xy 277.971317 -415.800299) (xy 278.012508 -415.83599) (xy 278.048199 -415.877181)
			(xy 278.077665 -415.923031) (xy 278.100307 -415.972608) (xy 278.115662 -416.024903) (xy 278.123418 -416.078851)
			(xy 278.123904 -416.106102) (xy 278.123407 -416.133872) (xy 278.115351 -416.188824) (xy 278.099396 -416.242023)
			(xy 278.08809 -416.267392) (xy 278.08554 -416.273342) (xy 278.083216 -416.286072) (xy 278.083518 -416.292538)
			(xy 278.08428 -416.304984) (xy 278.111458 -416.347656) (xy 278.137366 -416.388296) (xy 278.13762 -416.38855)
			(xy 278.138636 -416.390074) (xy 278.146247 -416.399746) (xy 278.168008 -416.411161) (xy 278.180292 -416.411918)
			(xy 278.397462 -416.411918) (xy 278.407186 -416.411442) (xy 278.425215 -416.404136) (xy 278.432514 -416.397694)
			(xy 278.435963 -416.394264) (xy 278.441591 -416.386334) (xy 278.44369 -416.381946) (xy 278.46274 -416.339528)
			(xy 278.482298 -416.296094) (xy 278.486535 -416.284149) (xy 278.483982 -416.258965) (xy 278.477472 -416.248088)
			(xy 278.47544 -416.24504) (xy 278.475186 -416.244532) (xy 278.473154 -416.2425) (xy 278.455137 -416.221447)
			(xy 278.424738 -416.175117) (xy 278.401353 -416.124881) (xy 278.385471 -416.071793) (xy 278.377427 -416.016968)
			(xy 278.376888 -415.989262) (xy 278.377374 -415.962011) (xy 278.38513 -415.908063) (xy 278.400485 -415.855768)
			(xy 278.423127 -415.806191) (xy 278.452593 -415.760341) (xy 278.488284 -415.71915) (xy 278.529475 -415.683459)
			(xy 278.575325 -415.653993) (xy 278.624902 -415.631351) (xy 278.677197 -415.615996) (xy 278.731145 -415.60824)
			(xy 278.785647 -415.60824) (xy 278.839595 -415.615996) (xy 278.89189 -415.631351) (xy 278.941467 -415.653993)
			(xy 278.987317 -415.683459) (xy 279.028508 -415.71915) (xy 279.064199 -415.760341) (xy 279.093665 -415.806191)
			(xy 279.116307 -415.855768) (xy 279.131662 -415.908063) (xy 279.139418 -415.962011) (xy 279.139904 -415.989262)
			(xy 279.139392 -416.017135) (xy 279.131272 -416.072286) (xy 279.115214 -416.125668) (xy 279.091561 -416.176146)
			(xy 279.060814 -416.222646) (xy 279.042622 -416.24377) (xy 279.028906 -416.25901) (xy 279.02916 -416.262058)
			(xy 279.030176 -416.288982) (xy 279.034494 -416.302444) (xy 279.038558 -416.308286) (xy 279.044146 -416.317684)
			(xy 279.073102 -416.381946) (xy 279.077507 -416.390641) (xy 279.091548 -416.404136) (xy 279.109595 -416.411459)
			(xy 279.11933 -416.411918) (xy 279.399238 -416.411918) (xy 279.406343 -416.411725) (xy 279.420015 -416.407865)
			(xy 279.426162 -416.404298) (xy 279.43175 -416.400488) (xy 279.441402 -416.390074) (xy 279.485344 -416.29838)
			(xy 279.48749 -416.292729) (xy 279.489414 -416.280798) (xy 279.489154 -416.274758) (xy 279.4889 -416.272218)
			(xy 279.487122 -416.258502) (xy 279.48509 -416.255962) (xy 279.477724 -416.246818) (xy 279.461701 -416.226338)
			(xy 279.434762 -416.181861) (xy 279.41411 -416.134138) (xy 279.400129 -416.084053) (xy 279.393078 -416.032534)
			(xy 279.392634 -416.006534) (xy 279.392634 -416.00628) (xy 279.39312 -415.979011) (xy 279.400882 -415.925027)
			(xy 279.416247 -415.872697) (xy 279.438904 -415.823087) (xy 279.46839 -415.777206) (xy 279.504105 -415.735989)
			(xy 279.545322 -415.700274) (xy 279.591203 -415.670788) (xy 279.640813 -415.648131) (xy 279.693143 -415.632766)
			(xy 279.747127 -415.625004) (xy 279.801665 -415.625004) (xy 279.855649 -415.632766) (xy 279.907979 -415.648131)
			(xy 279.957589 -415.670788) (xy 280.00347 -415.700274) (xy 280.044687 -415.735989) (xy 280.080402 -415.777206)
			(xy 280.109888 -415.823087) (xy 280.132545 -415.872697) (xy 280.14791 -415.925027) (xy 280.155672 -415.979011)
			(xy 280.156158 -416.00628) (xy 280.155706 -416.033075) (xy 280.148213 -416.086138) (xy 280.13337 -416.137631)
			(xy 280.111469 -416.186541) (xy 280.082943 -416.231907) (xy 280.065988 -416.25266) (xy 280.065734 -416.252914)
			(xy 280.060908 -416.264852) (xy 280.059892 -416.272218) (xy 280.059204 -416.279366) (xy 280.061402 -416.293549)
			(xy 280.06421 -416.300158) (xy 280.065226 -416.30219) (xy 280.104088 -416.383216) (xy 280.105612 -416.38601)
			(xy 280.109233 -416.392025) (xy 280.119153 -416.401951) (xy 280.12517 -416.405568) (xy 280.127202 -416.406584)
			(xy 280.137616 -416.410394) (xy 280.149808 -416.411918) (xy 280.331164 -416.411918) (xy 280.33599 -416.411664)
			(xy 280.339984 -416.41118) (xy 280.347767 -416.40914) (xy 280.351484 -416.4076) (xy 280.354786 -416.406076)
			(xy 280.358261 -416.40416) (xy 280.364643 -416.399446) (xy 280.367486 -416.396678) (xy 280.371296 -416.39236)
			(xy 280.421334 -416.323272) (xy 280.426034 -416.315752) (xy 280.430468 -416.298597) (xy 280.42997 -416.289744)
			(xy 280.428954 -416.282886) (xy 280.428192 -416.280092) (xy 280.427684 -416.278822) (xy 280.41891 -416.250151)
			(xy 280.409464 -416.190944) (xy 280.408888 -416.160966) (xy 280.408888 -416.160204) (xy 280.409374 -416.132953)
			(xy 280.41713 -416.079005) (xy 280.432485 -416.02671) (xy 280.455127 -415.977133) (xy 280.484593 -415.931283)
			(xy 280.520284 -415.890092) (xy 280.561475 -415.854401) (xy 280.607325 -415.824935) (xy 280.656902 -415.802293)
			(xy 280.709197 -415.786938) (xy 280.763145 -415.779182) (xy 280.817647 -415.779182) (xy 280.871595 -415.786938)
			(xy 280.92389 -415.802293) (xy 280.973467 -415.824935) (xy 281.019317 -415.854401) (xy 281.060508 -415.890092)
			(xy 281.096199 -415.931283) (xy 281.125665 -415.977133) (xy 281.148307 -416.02671) (xy 281.163662 -416.079005)
			(xy 281.171418 -416.132953) (xy 281.171904 -416.160204) (xy 281.171904 -416.160966) (xy 281.171277 -416.19094)
			(xy 281.161842 -416.250142) (xy 281.153108 -416.278822) (xy 281.1526 -416.280092) (xy 281.151838 -416.282886)
			(xy 281.150822 -416.289744) (xy 281.150353 -416.298597) (xy 281.154762 -416.315754) (xy 281.159458 -416.323272)
			(xy 281.209496 -416.39236) (xy 281.213306 -416.396678) (xy 281.21613 -416.399468) (xy 281.222514 -416.404188)
			(xy 281.226006 -416.406076) (xy 281.229308 -416.4076) (xy 281.233016 -416.409167) (xy 281.240802 -416.411214)
			(xy 281.244802 -416.411664) (xy 281.249628 -416.411918) (xy 282.771342 -416.411918) (xy 282.77947 -416.411156)
			(xy 282.779978 -416.411156) (xy 282.787502 -416.409564) (xy 282.801205 -416.402604) (xy 282.806902 -416.39744)
			(xy 283.300678 -415.903664) (xy 283.305666 -415.898166) (xy 283.312511 -415.884999) (xy 283.31414 -415.877756)
			(xy 283.315156 -415.868104) (xy 283.315156 -393.566904) (xy 283.314506 -393.5544) (xy 283.302779 -393.53231)
			(xy 283.292804 -393.52474) (xy 283.262668 -393.503946) (xy 283.205205 -393.458562) (xy 283.177996 -393.434062)
			(xy 282.812744 -393.099036) (xy 282.780677 -393.068977) (xy 282.72137 -393.004101) (xy 282.667995 -392.934263)
			(xy 282.620964 -392.860004) (xy 282.6004 -392.82116) (xy 282.595943 -392.813357) (xy 282.582674 -392.801254)
			(xy 282.574492 -392.797538) (xy 282.53399 -392.780379) (xy 282.45588 -392.739918) (xy 282.381632 -392.692742)
			(xy 282.311823 -392.639215) (xy 282.27909 -392.609832) (xy 281.913838 -392.274806) (xy 281.881807 -392.244775)
			(xy 281.82257 -392.179956) (xy 281.769262 -392.11018) (xy 281.722295 -392.035987) (xy 281.701748 -391.997184)
			(xy 281.69729 -391.989383) (xy 281.684017 -391.977287) (xy 281.67584 -391.973562) (xy 281.635339 -391.956401)
			(xy 281.55723 -391.915938) (xy 281.482984 -391.86876) (xy 281.413177 -391.815232) (xy 281.380438 -391.785856)
			(xy 281.015186 -391.45083) (xy 280.98093 -391.418655) (xy 280.917967 -391.348873) (xy 280.861841 -391.273483)
			(xy 280.813048 -391.193152) (xy 280.772021 -391.108591) (xy 280.75509 -391.06475) (xy 280.752844 -391.059224)
			(xy 280.746166 -391.049343) (xy 280.741882 -391.045192) (xy 280.278332 -390.62025) (xy 280.246446 -390.590375)
			(xy 280.187461 -390.525902) (xy 280.134352 -390.456508) (xy 280.087528 -390.382727) (xy 280.067004 -390.344152)
			(xy 279.573736 -389.392414) (xy 279.564338 -389.382508) (xy 279.558242 -389.378698) (xy 279.53507 -389.364104)
			(xy 279.492776 -389.32932) (xy 279.455892 -389.288844) (xy 279.425176 -389.243509) (xy 279.401258 -389.194247)
			(xy 279.384632 -389.142072) (xy 279.375638 -389.088054) (xy 279.3746 -389.06069) (xy 279.374346 -389.050784)
			(xy 279.36952 -389.0391) (xy 279.367535 -389.035178) (xy 279.362429 -389.028023) (xy 279.35936 -389.024876)
			(xy 279.358598 -389.024368) (xy 278.966422 -388.650226) (xy 278.936103 -388.62068) (xy 278.880069 -388.557211)
			(xy 278.829669 -388.489183) (xy 278.785272 -388.417093) (xy 278.747204 -388.34147) (xy 278.715743 -388.262869)
			(xy 278.703024 -388.22249) (xy 278.700484 -388.213854) (xy 278.682958 -388.19074) (xy 278.672798 -388.181088)
			(xy 278.654002 -388.168896) (xy 278.650442 -388.166719) (xy 278.642784 -388.163405) (xy 278.638762 -388.162292)
			(xy 278.630888 -388.16026) (xy 278.621744 -388.161276) (xy 278.611613 -388.162259) (xy 278.591282 -388.163274)
			(xy 278.581104 -388.163308) (xy 278.58085 -388.163308) (xy 278.553657 -388.162737) (xy 278.499845 -388.154836)
			(xy 278.4477 -388.139373) (xy 278.39828 -388.116661) (xy 278.352586 -388.087161) (xy 278.311545 -388.05147)
			(xy 278.275989 -388.010313) (xy 278.246638 -387.964522) (xy 278.224088 -387.915028) (xy 278.208796 -387.862833)
			(xy 278.201072 -387.808995) (xy 278.200612 -387.7818) (xy 278.200358 -387.7818) (xy 278.200821 -387.754957)
			(xy 278.208357 -387.701804) (xy 278.223265 -387.65023) (xy 278.245252 -387.601254) (xy 278.273885 -387.555841)
			(xy 278.308597 -387.514888) (xy 278.348705 -387.479202) (xy 278.393417 -387.449488) (xy 278.441851 -387.426331)
			(xy 278.467312 -387.417818) (xy 278.470106 -387.416802) (xy 278.480949 -387.412024) (xy 278.497001 -387.394634)
			(xy 278.50362 -387.371912) (xy 278.50211 -387.36016) (xy 278.494236 -387.325616) (xy 278.488902 -387.301994)
			(xy 278.48433 -387.289802) (xy 278.33701 -387.00583) (xy 278.316708 -386.965605) (xy 278.282602 -386.882198)
			(xy 278.256161 -386.796053) (xy 278.237601 -386.707874) (xy 278.231854 -386.663184) (xy 278.231854 -386.662676)
			(xy 278.101298 -385.620514) (xy 278.100536 -385.615434) (xy 277.96744 -385.037838) (xy 277.963862 -385.02748)
			(xy 277.949533 -385.010929) (xy 277.929618 -385.001835) (xy 277.918672 -385.001262) (xy 273.896582 -385.001262)
			(xy 273.891704 -385.001355) (xy 273.882112 -385.003138) (xy 273.877532 -385.004818) (xy 273.868388 -385.008628)
			(xy 273.649694 -385.227322) (xy 273.646991 -385.230175) (xy 273.642404 -385.236556) (xy 273.64055 -385.240022)
			(xy 273.637962 -385.245448) (xy 273.635131 -385.257128) (xy 273.634962 -385.263136) (xy 273.634962 -387.752082)
			(xy 274.772374 -387.752082) (xy 274.77286 -387.724831) (xy 274.780616 -387.670883) (xy 274.795971 -387.618588)
			(xy 274.818613 -387.569011) (xy 274.848079 -387.523161) (xy 274.88377 -387.48197) (xy 274.924961 -387.446279)
			(xy 274.970811 -387.416813) (xy 275.020388 -387.394171) (xy 275.072683 -387.378816) (xy 275.126631 -387.37106)
			(xy 275.181133 -387.37106) (xy 275.235081 -387.378816) (xy 275.287376 -387.394171) (xy 275.336953 -387.416813)
			(xy 275.382803 -387.446279) (xy 275.423994 -387.48197) (xy 275.459685 -387.523161) (xy 275.489151 -387.569011)
			(xy 275.511793 -387.618588) (xy 275.527148 -387.670883) (xy 275.534904 -387.724831) (xy 275.53539 -387.752082)
			(xy 275.534896 -387.779556) (xy 275.527006 -387.833936) (xy 275.511388 -387.886618) (xy 275.488365 -387.936511)
			(xy 275.458415 -387.98258) (xy 275.440648 -388.003542) (xy 275.431935 -388.014333) (xy 275.419948 -388.039323)
			(xy 275.41512 -388.066616) (xy 275.417806 -388.094202) (xy 275.427809 -388.120051) (xy 275.444392 -388.14226)
			(xy 275.466334 -388.159194) (xy 275.479002 -388.164832) (xy 275.505069 -388.175866) (xy 275.553838 -388.2046)
			(xy 275.597824 -388.240227) (xy 275.636062 -388.281963) (xy 275.644431 -388.294372) (xy 276.866348 -388.294372)
			(xy 276.870419 -388.23875) (xy 276.882545 -388.184313) (xy 276.902468 -388.132222) (xy 276.929764 -388.083587)
			(xy 276.96385 -388.039444) (xy 277.003999 -388.000735) (xy 277.049357 -387.968284) (xy 277.098957 -387.942783)
			(xy 277.151741 -387.924776) (xy 277.206584 -387.914646) (xy 277.262318 -387.912609) (xy 277.317755 -387.918709)
			(xy 277.371712 -387.932815) (xy 277.423041 -387.954627) (xy 277.470647 -387.983681) (xy 277.513515 -388.019356)
			(xy 277.550732 -388.060893) (xy 277.581505 -388.107406) (xy 277.605177 -388.157903) (xy 277.621245 -388.21131)
			(xy 277.629365 -388.266486) (xy 277.629874 -388.294372) (xy 277.629365 -388.322258) (xy 277.621245 -388.377434)
			(xy 277.605177 -388.430841) (xy 277.581505 -388.481338) (xy 277.550732 -388.527851) (xy 277.513515 -388.569388)
			(xy 277.470647 -388.605063) (xy 277.423041 -388.634117) (xy 277.371712 -388.655929) (xy 277.317755 -388.670035)
			(xy 277.262318 -388.676135) (xy 277.206584 -388.674098) (xy 277.151741 -388.663968) (xy 277.098957 -388.645961)
			(xy 277.049357 -388.62046) (xy 277.003999 -388.588009) (xy 276.96385 -388.5493) (xy 276.929764 -388.505157)
			(xy 276.902468 -388.456522) (xy 276.882545 -388.404431) (xy 276.870419 -388.349994) (xy 276.866348 -388.294372)
			(xy 275.644431 -388.294372) (xy 275.667712 -388.328892) (xy 275.692079 -388.379983) (xy 275.708627 -388.434115)
			(xy 275.716992 -388.490098) (xy 275.717508 -388.5184) (xy 275.717022 -388.545651) (xy 275.709266 -388.599599)
			(xy 275.693911 -388.651894) (xy 275.671269 -388.701471) (xy 275.641803 -388.747321) (xy 275.606112 -388.788512)
			(xy 275.564921 -388.824203) (xy 275.519071 -388.853669) (xy 275.469494 -388.876311) (xy 275.417199 -388.891666)
			(xy 275.363251 -388.899422) (xy 275.308749 -388.899422) (xy 275.254801 -388.891666) (xy 275.202506 -388.876311)
			(xy 275.152929 -388.853669) (xy 275.107079 -388.824203) (xy 275.065888 -388.788512) (xy 275.030197 -388.747321)
			(xy 275.000731 -388.701471) (xy 274.978089 -388.651894) (xy 274.962734 -388.599599) (xy 274.954978 -388.545651)
			(xy 274.954492 -388.5184) (xy 274.95498 -388.490925) (xy 274.962872 -388.436546) (xy 274.978492 -388.383864)
			(xy 275.001516 -388.333971) (xy 275.031467 -388.287902) (xy 275.049234 -388.26694) (xy 275.057975 -388.25617)
			(xy 275.069963 -388.231174) (xy 275.07479 -388.203875) (xy 275.0721 -388.176283) (xy 275.062092 -388.15043)
			(xy 275.045502 -388.12822) (xy 275.023552 -388.111287) (xy 275.01088 -388.10565) (xy 274.984839 -388.094559)
			(xy 274.936074 -388.06583) (xy 274.892089 -388.030211) (xy 274.85385 -387.988483) (xy 274.822198 -387.941563)
			(xy 274.797826 -387.89048) (xy 274.781271 -387.836357) (xy 274.772895 -387.780381) (xy 274.772374 -387.752082)
			(xy 273.634962 -387.752082) (xy 273.634962 -389.0264) (xy 277.811482 -389.0264) (xy 277.815553 -388.970778)
			(xy 277.827679 -388.916341) (xy 277.847602 -388.86425) (xy 277.874898 -388.815615) (xy 277.908984 -388.771472)
			(xy 277.949133 -388.732763) (xy 277.994491 -388.700312) (xy 278.044091 -388.674811) (xy 278.096875 -388.656804)
			(xy 278.151718 -388.646674) (xy 278.207452 -388.644637) (xy 278.262889 -388.650737) (xy 278.316846 -388.664843)
			(xy 278.368175 -388.686655) (xy 278.415781 -388.715709) (xy 278.458649 -388.751384) (xy 278.495866 -388.792921)
			(xy 278.526639 -388.839434) (xy 278.550311 -388.889931) (xy 278.566379 -388.943338) (xy 278.574499 -388.998514)
			(xy 278.575008 -389.0264) (xy 278.574499 -389.054286) (xy 278.566379 -389.109462) (xy 278.550311 -389.162869)
			(xy 278.526639 -389.213366) (xy 278.495866 -389.259879) (xy 278.458649 -389.301416) (xy 278.415781 -389.337091)
			(xy 278.368175 -389.366145) (xy 278.316846 -389.387957) (xy 278.262889 -389.402063) (xy 278.207452 -389.408163)
			(xy 278.151718 -389.406126) (xy 278.096875 -389.395996) (xy 278.044091 -389.377989) (xy 277.994491 -389.352488)
			(xy 277.949133 -389.320037) (xy 277.908984 -389.281328) (xy 277.874898 -389.237185) (xy 277.847602 -389.18855)
			(xy 277.827679 -389.136459) (xy 277.815553 -389.082022) (xy 277.811482 -389.0264) (xy 273.634962 -389.0264)
			(xy 273.634962 -389.9916) (xy 278.200102 -389.9916) (xy 278.204173 -389.935978) (xy 278.216299 -389.881541)
			(xy 278.236222 -389.82945) (xy 278.263518 -389.780815) (xy 278.297604 -389.736672) (xy 278.337753 -389.697963)
			(xy 278.383111 -389.665512) (xy 278.432711 -389.640011) (xy 278.485495 -389.622004) (xy 278.540338 -389.611874)
			(xy 278.596072 -389.609837) (xy 278.651509 -389.615937) (xy 278.705466 -389.630043) (xy 278.756795 -389.651855)
			(xy 278.804401 -389.680909) (xy 278.847269 -389.716584) (xy 278.884486 -389.758121) (xy 278.915259 -389.804634)
			(xy 278.938931 -389.855131) (xy 278.954999 -389.908538) (xy 278.963119 -389.963714) (xy 278.963628 -389.9916)
			(xy 278.963119 -390.019486) (xy 278.954999 -390.074662) (xy 278.938931 -390.128069) (xy 278.915259 -390.178566)
			(xy 278.884486 -390.225079) (xy 278.847269 -390.266616) (xy 278.804401 -390.302291) (xy 278.756795 -390.331345)
			(xy 278.705466 -390.353157) (xy 278.651509 -390.367263) (xy 278.596072 -390.373363) (xy 278.540338 -390.371326)
			(xy 278.485495 -390.361196) (xy 278.432711 -390.343189) (xy 278.383111 -390.317688) (xy 278.337753 -390.285237)
			(xy 278.297604 -390.246528) (xy 278.263518 -390.202385) (xy 278.236222 -390.15375) (xy 278.216299 -390.101659)
			(xy 278.204173 -390.047222) (xy 278.200102 -389.9916) (xy 273.634962 -389.9916) (xy 273.634962 -392.7602)
			(xy 276.865332 -392.7602) (xy 276.869403 -392.704578) (xy 276.881529 -392.650141) (xy 276.901452 -392.59805)
			(xy 276.928748 -392.549415) (xy 276.962834 -392.505272) (xy 277.002983 -392.466563) (xy 277.048341 -392.434112)
			(xy 277.097941 -392.408611) (xy 277.150725 -392.390604) (xy 277.205568 -392.380474) (xy 277.261302 -392.378437)
			(xy 277.316739 -392.384537) (xy 277.370696 -392.398643) (xy 277.422025 -392.420455) (xy 277.469631 -392.449509)
			(xy 277.512499 -392.485184) (xy 277.549716 -392.526721) (xy 277.580489 -392.573234) (xy 277.604161 -392.623731)
			(xy 277.620229 -392.677138) (xy 277.628079 -392.730482) (xy 278.6667 -392.730482) (xy 278.670771 -392.67486)
			(xy 278.682897 -392.620423) (xy 278.70282 -392.568332) (xy 278.730116 -392.519697) (xy 278.764202 -392.475554)
			(xy 278.804351 -392.436845) (xy 278.849709 -392.404394) (xy 278.899309 -392.378893) (xy 278.952093 -392.360886)
			(xy 279.006936 -392.350756) (xy 279.06267 -392.348719) (xy 279.118107 -392.354819) (xy 279.172064 -392.368925)
			(xy 279.223393 -392.390737) (xy 279.270999 -392.419791) (xy 279.313867 -392.455466) (xy 279.351084 -392.497003)
			(xy 279.381857 -392.543516) (xy 279.405529 -392.594013) (xy 279.421597 -392.64742) (xy 279.429717 -392.702596)
			(xy 279.430226 -392.730482) (xy 279.429717 -392.758368) (xy 279.421597 -392.813544) (xy 279.405529 -392.866951)
			(xy 279.381857 -392.917448) (xy 279.351084 -392.963961) (xy 279.313867 -393.005498) (xy 279.270999 -393.041173)
			(xy 279.223393 -393.070227) (xy 279.172064 -393.092039) (xy 279.118107 -393.106145) (xy 279.06267 -393.112245)
			(xy 279.006936 -393.110208) (xy 278.952093 -393.100078) (xy 278.899309 -393.082071) (xy 278.849709 -393.05657)
			(xy 278.804351 -393.024119) (xy 278.764202 -392.98541) (xy 278.730116 -392.941267) (xy 278.70282 -392.892632)
			(xy 278.682897 -392.840541) (xy 278.670771 -392.786104) (xy 278.6667 -392.730482) (xy 277.628079 -392.730482)
			(xy 277.628349 -392.732314) (xy 277.628858 -392.7602) (xy 277.628349 -392.788086) (xy 277.620229 -392.843262)
			(xy 277.604161 -392.896669) (xy 277.580489 -392.947166) (xy 277.549716 -392.993679) (xy 277.512499 -393.035216)
			(xy 277.469631 -393.070891) (xy 277.422025 -393.099945) (xy 277.370696 -393.121757) (xy 277.316739 -393.135863)
			(xy 277.261302 -393.141963) (xy 277.205568 -393.139926) (xy 277.150725 -393.129796) (xy 277.097941 -393.111789)
			(xy 277.048341 -393.086288) (xy 277.002983 -393.053837) (xy 276.962834 -393.015128) (xy 276.928748 -392.970985)
			(xy 276.901452 -392.92235) (xy 276.881529 -392.870259) (xy 276.869403 -392.815822) (xy 276.865332 -392.7602)
			(xy 273.634962 -392.7602) (xy 273.634962 -394.762482) (xy 276.700486 -394.762482) (xy 276.704557 -394.70686)
			(xy 276.716683 -394.652423) (xy 276.736606 -394.600332) (xy 276.763902 -394.551697) (xy 276.797988 -394.507554)
			(xy 276.838137 -394.468845) (xy 276.883495 -394.436394) (xy 276.933095 -394.410893) (xy 276.985879 -394.392886)
			(xy 277.040722 -394.382756) (xy 277.096456 -394.380719) (xy 277.151893 -394.386819) (xy 277.20585 -394.400925)
			(xy 277.257179 -394.422737) (xy 277.304785 -394.451791) (xy 277.347653 -394.487466) (xy 277.38487 -394.529003)
			(xy 277.415643 -394.575516) (xy 277.439315 -394.626013) (xy 277.455383 -394.67942) (xy 277.463503 -394.734596)
			(xy 277.464012 -394.762482) (xy 279.240486 -394.762482) (xy 279.244557 -394.70686) (xy 279.256683 -394.652423)
			(xy 279.276606 -394.600332) (xy 279.303902 -394.551697) (xy 279.337988 -394.507554) (xy 279.378137 -394.468845)
			(xy 279.423495 -394.436394) (xy 279.473095 -394.410893) (xy 279.525879 -394.392886) (xy 279.580722 -394.382756)
			(xy 279.636456 -394.380719) (xy 279.691893 -394.386819) (xy 279.74585 -394.400925) (xy 279.797179 -394.422737)
			(xy 279.844785 -394.451791) (xy 279.887653 -394.487466) (xy 279.92487 -394.529003) (xy 279.955643 -394.575516)
			(xy 279.979315 -394.626013) (xy 279.995383 -394.67942) (xy 280.003503 -394.734596) (xy 280.004012 -394.762482)
			(xy 280.003503 -394.790368) (xy 279.995383 -394.845544) (xy 279.979315 -394.898951) (xy 279.955643 -394.949448)
			(xy 279.92487 -394.995961) (xy 279.887653 -395.037498) (xy 279.844785 -395.073173) (xy 279.797179 -395.102227)
			(xy 279.74585 -395.124039) (xy 279.691893 -395.138145) (xy 279.636456 -395.144245) (xy 279.580722 -395.142208)
			(xy 279.525879 -395.132078) (xy 279.473095 -395.114071) (xy 279.423495 -395.08857) (xy 279.378137 -395.056119)
			(xy 279.337988 -395.01741) (xy 279.303902 -394.973267) (xy 279.276606 -394.924632) (xy 279.256683 -394.872541)
			(xy 279.244557 -394.818104) (xy 279.240486 -394.762482) (xy 277.464012 -394.762482) (xy 277.463503 -394.790368)
			(xy 277.455383 -394.845544) (xy 277.439315 -394.898951) (xy 277.415643 -394.949448) (xy 277.38487 -394.995961)
			(xy 277.347653 -395.037498) (xy 277.304785 -395.073173) (xy 277.257179 -395.102227) (xy 277.20585 -395.124039)
			(xy 277.151893 -395.138145) (xy 277.096456 -395.144245) (xy 277.040722 -395.142208) (xy 276.985879 -395.132078)
			(xy 276.933095 -395.114071) (xy 276.883495 -395.08857) (xy 276.838137 -395.056119) (xy 276.797988 -395.01741)
			(xy 276.763902 -394.973267) (xy 276.736606 -394.924632) (xy 276.716683 -394.872541) (xy 276.704557 -394.818104)
			(xy 276.700486 -394.762482) (xy 273.634962 -394.762482) (xy 273.634962 -395.639544) (xy 273.63453 -395.64961)
			(xy 273.6268 -395.668199) (xy 273.619976 -395.675612) (xy 272.725388 -396.5702) (xy 276.876508 -396.5702)
			(xy 276.880579 -396.514578) (xy 276.892705 -396.460141) (xy 276.912628 -396.40805) (xy 276.939924 -396.359415)
			(xy 276.97401 -396.315272) (xy 277.014159 -396.276563) (xy 277.059517 -396.244112) (xy 277.109117 -396.218611)
			(xy 277.161901 -396.200604) (xy 277.216744 -396.190474) (xy 277.272478 -396.188437) (xy 277.327915 -396.194537)
			(xy 277.381872 -396.208643) (xy 277.433201 -396.230455) (xy 277.480807 -396.259509) (xy 277.523675 -396.295184)
			(xy 277.560892 -396.336721) (xy 277.591665 -396.383234) (xy 277.615337 -396.433731) (xy 277.631405 -396.487138)
			(xy 277.638134 -396.532862) (xy 278.858216 -396.532862) (xy 278.862287 -396.47724) (xy 278.874413 -396.422803)
			(xy 278.894336 -396.370712) (xy 278.921632 -396.322077) (xy 278.955718 -396.277934) (xy 278.995867 -396.239225)
			(xy 279.041225 -396.206774) (xy 279.090825 -396.181273) (xy 279.143609 -396.163266) (xy 279.198452 -396.153136)
			(xy 279.254186 -396.151099) (xy 279.309623 -396.157199) (xy 279.36358 -396.171305) (xy 279.414909 -396.193117)
			(xy 279.462515 -396.222171) (xy 279.505383 -396.257846) (xy 279.5426 -396.299383) (xy 279.573373 -396.345896)
			(xy 279.597045 -396.396393) (xy 279.613113 -396.4498) (xy 279.621233 -396.504976) (xy 279.621742 -396.532862)
			(xy 279.621233 -396.560748) (xy 279.613113 -396.615924) (xy 279.597045 -396.669331) (xy 279.573373 -396.719828)
			(xy 279.5426 -396.766341) (xy 279.505383 -396.807878) (xy 279.462515 -396.843553) (xy 279.414909 -396.872607)
			(xy 279.36358 -396.894419) (xy 279.309623 -396.908525) (xy 279.254186 -396.914625) (xy 279.198452 -396.912588)
			(xy 279.143609 -396.902458) (xy 279.090825 -396.884451) (xy 279.041225 -396.85895) (xy 278.995867 -396.826499)
			(xy 278.955718 -396.78779) (xy 278.921632 -396.743647) (xy 278.894336 -396.695012) (xy 278.874413 -396.642921)
			(xy 278.862287 -396.588484) (xy 278.858216 -396.532862) (xy 277.638134 -396.532862) (xy 277.639525 -396.542314)
			(xy 277.640034 -396.5702) (xy 277.639525 -396.598086) (xy 277.631405 -396.653262) (xy 277.615337 -396.706669)
			(xy 277.591665 -396.757166) (xy 277.560892 -396.803679) (xy 277.523675 -396.845216) (xy 277.480807 -396.880891)
			(xy 277.433201 -396.909945) (xy 277.381872 -396.931757) (xy 277.327915 -396.945863) (xy 277.272478 -396.951963)
			(xy 277.216744 -396.949926) (xy 277.161901 -396.939796) (xy 277.109117 -396.921789) (xy 277.059517 -396.896288)
			(xy 277.014159 -396.863837) (xy 276.97401 -396.825128) (xy 276.939924 -396.780985) (xy 276.912628 -396.73235)
			(xy 276.892705 -396.680259) (xy 276.880579 -396.625822) (xy 276.876508 -396.5702) (xy 272.725388 -396.5702)
			(xy 271.361916 -397.933672) (xy 279.755598 -397.933672) (xy 279.759669 -397.87805) (xy 279.771795 -397.823613)
			(xy 279.791718 -397.771522) (xy 279.819014 -397.722887) (xy 279.8531 -397.678744) (xy 279.893249 -397.640035)
			(xy 279.938607 -397.607584) (xy 279.988207 -397.582083) (xy 280.040991 -397.564076) (xy 280.095834 -397.553946)
			(xy 280.151568 -397.551909) (xy 280.207005 -397.558009) (xy 280.260962 -397.572115) (xy 280.312291 -397.593927)
			(xy 280.359897 -397.622981) (xy 280.402765 -397.658656) (xy 280.439982 -397.700193) (xy 280.470755 -397.746706)
			(xy 280.494427 -397.797203) (xy 280.510495 -397.85061) (xy 280.518615 -397.905786) (xy 280.519124 -397.933672)
			(xy 280.518615 -397.961558) (xy 280.510495 -398.016734) (xy 280.494427 -398.070141) (xy 280.470755 -398.120638)
			(xy 280.439982 -398.167151) (xy 280.402765 -398.208688) (xy 280.359897 -398.244363) (xy 280.312291 -398.273417)
			(xy 280.260962 -398.295229) (xy 280.207005 -398.309335) (xy 280.151568 -398.315435) (xy 280.095834 -398.313398)
			(xy 280.040991 -398.303268) (xy 279.988207 -398.285261) (xy 279.938607 -398.25976) (xy 279.893249 -398.227309)
			(xy 279.8531 -398.1886) (xy 279.819014 -398.144457) (xy 279.791718 -398.095822) (xy 279.771795 -398.043731)
			(xy 279.759669 -397.989294) (xy 279.755598 -397.933672) (xy 271.361916 -397.933672) (xy 270.640302 -398.655286)
			(xy 270.632904 -398.662134) (xy 270.614306 -398.669871) (xy 270.604234 -398.670272) (xy 266.4841 -398.670272)
			(xy 266.47403 -398.669848) (xy 266.455429 -398.662131) (xy 266.448032 -398.655286) (xy 265.236452 -397.443706)
			(xy 265.232388 -397.440912) (xy 265.151991 -397.385407) (xy 264.994894 -397.26923) (xy 264.842221 -397.147297)
			(xy 264.694182 -397.019776) (xy 264.550983 -396.886844) (xy 264.412821 -396.748685) (xy 264.279887 -396.605488)
			(xy 264.152364 -396.457452) (xy 264.030428 -396.304781) (xy 263.914248 -396.147686) (xy 263.858756 -396.06728)
			(xy 263.855962 -396.063216) (xy 260.166358 -392.373612) (xy 260.163505 -392.370909) (xy 260.157123 -392.366323)
			(xy 260.153658 -392.364468) (xy 260.148231 -392.361886) (xy 260.136551 -392.359064) (xy 260.130544 -392.35888)
			(xy 255.010158 -392.35888) (xy 255.00528 -392.358975) (xy 254.995691 -392.360763) (xy 254.991108 -392.362436)
			(xy 254.981964 -392.366246) (xy 254.61595 -392.73226) (xy 254.613242 -392.735109) (xy 254.608643 -392.741485)
			(xy 254.606806 -392.74496) (xy 254.604224 -392.750387) (xy 254.601404 -392.762067) (xy 254.601218 -392.768074)
			(xy 254.601218 -398.308322) (xy 254.600791 -398.318391) (xy 254.593073 -398.336991) (xy 254.586232 -398.34439)
			(xy 253.544578 -399.386044) (xy 253.537181 -399.392893) (xy 253.518582 -399.400628) (xy 253.50851 -399.40103)
			(xy 245.456964 -399.40103) (xy 245.452086 -399.401125) (xy 245.442496 -399.40291) (xy 245.437914 -399.404586)
			(xy 245.42877 -399.408396) (xy 245.053358 -399.783808) (xy 245.050652 -399.786659) (xy 245.046058 -399.793036)
			(xy 245.044214 -399.796508) (xy 245.041626 -399.801934) (xy 245.038794 -399.813613) (xy 245.038626 -399.819622)
			(xy 245.038626 -400.758406) (xy 245.038203 -400.768476) (xy 245.03049 -400.787082) (xy 245.02364 -400.794474)
			(xy 244.644926 -401.173188) (xy 277.12035 -401.173188) (xy 277.120836 -401.145937) (xy 277.128592 -401.091989)
			(xy 277.143947 -401.039694) (xy 277.166589 -400.990117) (xy 277.196055 -400.944267) (xy 277.231746 -400.903076)
			(xy 277.272937 -400.867385) (xy 277.318787 -400.837919) (xy 277.368364 -400.815277) (xy 277.420659 -400.799922)
			(xy 277.474607 -400.792166) (xy 277.529109 -400.792166) (xy 277.583057 -400.799922) (xy 277.635352 -400.815277)
			(xy 277.684929 -400.837919) (xy 277.730779 -400.867385) (xy 277.77197 -400.903076) (xy 277.807661 -400.944267)
			(xy 277.837127 -400.990117) (xy 277.859769 -401.039694) (xy 277.875124 -401.091989) (xy 277.88288 -401.145937)
			(xy 277.882895 -401.146772) (xy 279.138886 -401.146772) (xy 279.142957 -401.09115) (xy 279.155083 -401.036713)
			(xy 279.175006 -400.984622) (xy 279.202302 -400.935987) (xy 279.236388 -400.891844) (xy 279.276537 -400.853135)
			(xy 279.321895 -400.820684) (xy 279.371495 -400.795183) (xy 279.424279 -400.777176) (xy 279.479122 -400.767046)
			(xy 279.534856 -400.765009) (xy 279.590293 -400.771109) (xy 279.64425 -400.785215) (xy 279.695579 -400.807027)
			(xy 279.743185 -400.836081) (xy 279.786053 -400.871756) (xy 279.82327 -400.913293) (xy 279.854043 -400.959806)
			(xy 279.877715 -401.010303) (xy 279.893783 -401.06371) (xy 279.901903 -401.118886) (xy 279.902412 -401.146772)
			(xy 279.901903 -401.174658) (xy 279.893783 -401.229834) (xy 279.877715 -401.283241) (xy 279.854043 -401.333738)
			(xy 279.82327 -401.380251) (xy 279.786053 -401.421788) (xy 279.743185 -401.457463) (xy 279.695579 -401.486517)
			(xy 279.64425 -401.508329) (xy 279.590293 -401.522435) (xy 279.534856 -401.528535) (xy 279.479122 -401.526498)
			(xy 279.424279 -401.516368) (xy 279.371495 -401.498361) (xy 279.321895 -401.47286) (xy 279.276537 -401.440409)
			(xy 279.236388 -401.4017) (xy 279.202302 -401.357557) (xy 279.175006 -401.308922) (xy 279.155083 -401.256831)
			(xy 279.142957 -401.202394) (xy 279.138886 -401.146772) (xy 277.882895 -401.146772) (xy 277.883366 -401.173188)
			(xy 277.883366 -401.173442) (xy 277.882731 -401.204219) (xy 277.872821 -401.26497) (xy 277.853297 -401.323347)
			(xy 277.824664 -401.377836) (xy 277.806658 -401.402804) (xy 277.79821 -401.41486) (xy 277.787947 -401.442437)
			(xy 277.785972 -401.471796) (xy 277.79245 -401.5005) (xy 277.806842 -401.526165) (xy 277.827953 -401.546663)
			(xy 277.854033 -401.56029) (xy 277.86838 -401.563586) (xy 277.894092 -401.569098) (xy 277.943829 -401.586165)
			(xy 277.990751 -401.609903) (xy 278.033966 -401.63986) (xy 278.072657 -401.675471) (xy 278.10609 -401.716058)
			(xy 278.133631 -401.760853) (xy 278.154757 -401.809006) (xy 278.169069 -401.859605) (xy 278.176294 -401.91169)
			(xy 278.176736 -401.937982) (xy 278.17625 -401.965233) (xy 278.168494 -402.019181) (xy 278.153139 -402.071476)
			(xy 278.130497 -402.121053) (xy 278.101031 -402.166903) (xy 278.06534 -402.208094) (xy 278.024149 -402.243785)
			(xy 277.978299 -402.273251) (xy 277.928722 -402.295893) (xy 277.876427 -402.311248) (xy 277.822479 -402.319004)
			(xy 277.767977 -402.319004) (xy 277.714029 -402.311248) (xy 277.661734 -402.295893) (xy 277.612157 -402.273251)
			(xy 277.566307 -402.243785) (xy 277.525116 -402.208094) (xy 277.489425 -402.166903) (xy 277.459959 -402.121053)
			(xy 277.437317 -402.071476) (xy 277.421962 -402.019181) (xy 277.414206 -401.965233) (xy 277.41372 -401.937982)
			(xy 277.41372 -401.937728) (xy 277.414342 -401.906951) (xy 277.424256 -401.846199) (xy 277.443784 -401.787823)
			(xy 277.47242 -401.733334) (xy 277.490428 -401.708366) (xy 277.498921 -401.696339) (xy 277.509183 -401.668752)
			(xy 277.511153 -401.639385) (xy 277.504669 -401.610674) (xy 277.490269 -401.585004) (xy 277.469147 -401.564505)
			(xy 277.443058 -401.550878) (xy 277.428706 -401.547584) (xy 277.402985 -401.542111) (xy 277.353246 -401.52504)
			(xy 277.306323 -401.501298) (xy 277.263107 -401.471336) (xy 277.224416 -401.435721) (xy 277.190984 -401.39513)
			(xy 277.163445 -401.35033) (xy 277.142321 -401.302173) (xy 277.128012 -401.25157) (xy 277.12079 -401.199481)
			(xy 277.12035 -401.173188) (xy 244.644926 -401.173188) (xy 243.62664 -402.191474) (xy 243.619239 -402.198314)
			(xy 243.600641 -402.20603) (xy 243.590572 -402.20646) (xy 239.488726 -402.20646) (xy 239.483849 -402.206558)
			(xy 239.474261 -402.208351) (xy 239.469676 -402.210016) (xy 239.460532 -402.213826) (xy 238.291624 -403.382734)
			(xy 238.28892 -403.385586) (xy 238.284332 -403.391967) (xy 238.28248 -403.395434) (xy 238.279897 -403.400861)
			(xy 238.277072 -403.41254) (xy 238.276892 -403.418548) (xy 238.276892 -403.46249) (xy 275.581108 -403.46249)
			(xy 275.585179 -403.406868) (xy 275.597305 -403.352431) (xy 275.617228 -403.30034) (xy 275.644524 -403.251705)
			(xy 275.67861 -403.207562) (xy 275.718759 -403.168853) (xy 275.764117 -403.136402) (xy 275.813717 -403.110901)
			(xy 275.866501 -403.092894) (xy 275.921344 -403.082764) (xy 275.977078 -403.080727) (xy 276.032515 -403.086827)
			(xy 276.086472 -403.100933) (xy 276.137801 -403.122745) (xy 276.185407 -403.151799) (xy 276.228275 -403.187474)
			(xy 276.265492 -403.229011) (xy 276.296265 -403.275524) (xy 276.319937 -403.326021) (xy 276.336005 -403.379428)
			(xy 276.344125 -403.434604) (xy 276.344634 -403.46249) (xy 276.597108 -403.46249) (xy 276.601179 -403.406868)
			(xy 276.613305 -403.352431) (xy 276.633228 -403.30034) (xy 276.660524 -403.251705) (xy 276.69461 -403.207562)
			(xy 276.734759 -403.168853) (xy 276.780117 -403.136402) (xy 276.829717 -403.110901) (xy 276.882501 -403.092894)
			(xy 276.937344 -403.082764) (xy 276.993078 -403.080727) (xy 277.048515 -403.086827) (xy 277.102472 -403.100933)
			(xy 277.153801 -403.122745) (xy 277.201407 -403.151799) (xy 277.244275 -403.187474) (xy 277.281492 -403.229011)
			(xy 277.312265 -403.275524) (xy 277.335937 -403.326021) (xy 277.352005 -403.379428) (xy 277.360125 -403.434604)
			(xy 277.360634 -403.46249) (xy 277.360125 -403.490376) (xy 277.352005 -403.545552) (xy 277.335937 -403.598959)
			(xy 277.312265 -403.649456) (xy 277.281492 -403.695969) (xy 277.244275 -403.737506) (xy 277.201407 -403.773181)
			(xy 277.153801 -403.802235) (xy 277.102472 -403.824047) (xy 277.048515 -403.838153) (xy 276.993078 -403.844253)
			(xy 276.937344 -403.842216) (xy 276.882501 -403.832086) (xy 276.829717 -403.814079) (xy 276.780117 -403.788578)
			(xy 276.734759 -403.756127) (xy 276.69461 -403.717418) (xy 276.660524 -403.673275) (xy 276.633228 -403.62464)
			(xy 276.613305 -403.572549) (xy 276.601179 -403.518112) (xy 276.597108 -403.46249) (xy 276.344634 -403.46249)
			(xy 276.344125 -403.490376) (xy 276.336005 -403.545552) (xy 276.319937 -403.598959) (xy 276.296265 -403.649456)
			(xy 276.265492 -403.695969) (xy 276.228275 -403.737506) (xy 276.185407 -403.773181) (xy 276.137801 -403.802235)
			(xy 276.086472 -403.824047) (xy 276.032515 -403.838153) (xy 275.977078 -403.844253) (xy 275.921344 -403.842216)
			(xy 275.866501 -403.832086) (xy 275.813717 -403.814079) (xy 275.764117 -403.788578) (xy 275.718759 -403.756127)
			(xy 275.67861 -403.717418) (xy 275.644524 -403.673275) (xy 275.617228 -403.62464) (xy 275.597305 -403.572549)
			(xy 275.585179 -403.518112) (xy 275.581108 -403.46249) (xy 238.276892 -403.46249) (xy 238.276892 -403.97049)
			(xy 278.636984 -403.97049) (xy 278.637515 -403.944067) (xy 278.644823 -403.891728) (xy 278.659285 -403.840899)
			(xy 278.680623 -403.792552) (xy 278.708429 -403.747612) (xy 278.74217 -403.70694) (xy 278.781203 -403.671314)
			(xy 278.824778 -403.641415) (xy 278.872062 -403.617816) (xy 278.922151 -403.600969) (xy 278.974086 -403.591195)
			(xy 279.000458 -403.58949) (xy 279.015759 -403.588239) (xy 279.04459 -403.577725) (xy 279.069008 -403.559138)
			(xy 279.08682 -403.534149) (xy 279.096425 -403.505003) (xy 279.096959 -403.474319) (xy 279.093168 -403.459442)
			(xy 279.085948 -403.43317) (xy 279.078177 -403.379242) (xy 279.077674 -403.352) (xy 279.07816 -403.324749)
			(xy 279.085916 -403.270801) (xy 279.101271 -403.218506) (xy 279.123913 -403.168929) (xy 279.153379 -403.123079)
			(xy 279.18907 -403.081888) (xy 279.230261 -403.046197) (xy 279.276111 -403.016731) (xy 279.325688 -402.994089)
			(xy 279.377983 -402.978734) (xy 279.431931 -402.970978) (xy 279.486433 -402.970978) (xy 279.540381 -402.978734)
			(xy 279.592676 -402.994089) (xy 279.642253 -403.016731) (xy 279.688103 -403.046197) (xy 279.729294 -403.081888)
			(xy 279.764985 -403.123079) (xy 279.794451 -403.168929) (xy 279.817093 -403.218506) (xy 279.832448 -403.270801)
			(xy 279.840204 -403.324749) (xy 279.840613 -403.347682) (xy 280.093164 -403.347682) (xy 280.097235 -403.29206)
			(xy 280.109361 -403.237623) (xy 280.129284 -403.185532) (xy 280.15658 -403.136897) (xy 280.190666 -403.092754)
			(xy 280.230815 -403.054045) (xy 280.276173 -403.021594) (xy 280.325773 -402.996093) (xy 280.378557 -402.978086)
			(xy 280.4334 -402.967956) (xy 280.489134 -402.965919) (xy 280.544571 -402.972019) (xy 280.598528 -402.986125)
			(xy 280.649857 -403.007937) (xy 280.697463 -403.036991) (xy 280.740331 -403.072666) (xy 280.777548 -403.114203)
			(xy 280.808321 -403.160716) (xy 280.831993 -403.211213) (xy 280.848061 -403.26462) (xy 280.856181 -403.319796)
			(xy 280.85669 -403.347682) (xy 280.856181 -403.375568) (xy 280.848061 -403.430744) (xy 280.831993 -403.484151)
			(xy 280.808321 -403.534648) (xy 280.777548 -403.581161) (xy 280.740331 -403.622698) (xy 280.697463 -403.658373)
			(xy 280.649857 -403.687427) (xy 280.598528 -403.709239) (xy 280.544571 -403.723345) (xy 280.489134 -403.729445)
			(xy 280.4334 -403.727408) (xy 280.378557 -403.717278) (xy 280.325773 -403.699271) (xy 280.276173 -403.67377)
			(xy 280.230815 -403.641319) (xy 280.190666 -403.60261) (xy 280.15658 -403.558467) (xy 280.129284 -403.509832)
			(xy 280.109361 -403.457741) (xy 280.097235 -403.403304) (xy 280.093164 -403.347682) (xy 279.840613 -403.347682)
			(xy 279.84069 -403.352) (xy 279.840174 -403.378424) (xy 279.832867 -403.430764) (xy 279.818405 -403.481595)
			(xy 279.797067 -403.529944) (xy 279.76926 -403.574885) (xy 279.735516 -403.615558) (xy 279.696482 -403.651184)
			(xy 279.652904 -403.681082) (xy 279.605617 -403.70468) (xy 279.555526 -403.721526) (xy 279.503589 -403.731297)
			(xy 279.477216 -403.733) (xy 279.461915 -403.734244) (xy 279.433087 -403.744763) (xy 279.40867 -403.763352)
			(xy 279.39086 -403.788342) (xy 279.381255 -403.817488) (xy 279.380718 -403.84817) (xy 279.384506 -403.863048)
			(xy 279.391723 -403.889321) (xy 279.399497 -403.943248) (xy 279.4 -403.97049) (xy 279.399514 -403.997741)
			(xy 279.391758 -404.051689) (xy 279.376403 -404.103984) (xy 279.353761 -404.153561) (xy 279.324295 -404.199411)
			(xy 279.288604 -404.240602) (xy 279.247413 -404.276293) (xy 279.201563 -404.305759) (xy 279.151986 -404.328401)
			(xy 279.099691 -404.343756) (xy 279.045743 -404.351512) (xy 278.991241 -404.351512) (xy 278.937293 -404.343756)
			(xy 278.884998 -404.328401) (xy 278.835421 -404.305759) (xy 278.789571 -404.276293) (xy 278.74838 -404.240602)
			(xy 278.712689 -404.199411) (xy 278.683223 -404.153561) (xy 278.660581 -404.103984) (xy 278.645226 -404.051689)
			(xy 278.63747 -403.997741) (xy 278.636984 -403.97049) (xy 238.276892 -403.97049) (xy 238.276892 -404.674324)
			(xy 274.928582 -404.674324) (xy 274.932653 -404.618702) (xy 274.944779 -404.564265) (xy 274.964702 -404.512174)
			(xy 274.991998 -404.463539) (xy 275.026084 -404.419396) (xy 275.066233 -404.380687) (xy 275.111591 -404.348236)
			(xy 275.161191 -404.322735) (xy 275.213975 -404.304728) (xy 275.268818 -404.294598) (xy 275.324552 -404.292561)
			(xy 275.379989 -404.298661) (xy 275.433946 -404.312767) (xy 275.485275 -404.334579) (xy 275.532881 -404.363633)
			(xy 275.575749 -404.399308) (xy 275.612966 -404.440845) (xy 275.643739 -404.487358) (xy 275.667411 -404.537855)
			(xy 275.683479 -404.591262) (xy 275.691599 -404.646438) (xy 275.692108 -404.674324) (xy 275.691599 -404.70221)
			(xy 275.683479 -404.757386) (xy 275.667411 -404.810793) (xy 275.643739 -404.86129) (xy 275.612966 -404.907803)
			(xy 275.575749 -404.94934) (xy 275.532881 -404.985015) (xy 275.485275 -405.014069) (xy 275.433946 -405.035881)
			(xy 275.379989 -405.049987) (xy 275.324552 -405.056087) (xy 275.268818 -405.05405) (xy 275.213975 -405.04392)
			(xy 275.161191 -405.025913) (xy 275.111591 -405.000412) (xy 275.066233 -404.967961) (xy 275.026084 -404.929252)
			(xy 274.991998 -404.885109) (xy 274.964702 -404.836474) (xy 274.944779 -404.784383) (xy 274.932653 -404.729946)
			(xy 274.928582 -404.674324) (xy 238.276892 -404.674324) (xy 238.276892 -406.147016) (xy 275.691598 -406.147016)
			(xy 275.695669 -406.091394) (xy 275.707795 -406.036957) (xy 275.727718 -405.984866) (xy 275.755014 -405.936231)
			(xy 275.7891 -405.892088) (xy 275.829249 -405.853379) (xy 275.874607 -405.820928) (xy 275.924207 -405.795427)
			(xy 275.976991 -405.77742) (xy 276.031834 -405.76729) (xy 276.087568 -405.765253) (xy 276.143005 -405.771353)
			(xy 276.196962 -405.785459) (xy 276.248291 -405.807271) (xy 276.295897 -405.836325) (xy 276.338765 -405.872)
			(xy 276.375982 -405.913537) (xy 276.406755 -405.96005) (xy 276.430427 -406.010547) (xy 276.446495 -406.063954)
			(xy 276.454615 -406.11913) (xy 276.455124 -406.147016) (xy 276.454615 -406.174902) (xy 276.453107 -406.185151)
			(xy 276.708593 -406.185151) (xy 276.708593 -406.130649) (xy 276.71635 -406.076702) (xy 276.731705 -406.024408)
			(xy 276.754347 -405.974832) (xy 276.783813 -405.928983) (xy 276.819505 -405.887794) (xy 276.860695 -405.852104)
			(xy 276.906546 -405.822639) (xy 276.956123 -405.8) (xy 277.008418 -405.784646) (xy 277.062365 -405.776892)
			(xy 277.089616 -405.77643) (xy 277.118436 -405.776938) (xy 277.175418 -405.785624) (xy 277.230446 -405.802782)
			(xy 277.282267 -405.828021) (xy 277.329703 -405.860766) (xy 277.371675 -405.900274) (xy 277.407227 -405.945644)
			(xy 277.421848 -405.970486) (xy 277.427835 -405.979953) (xy 277.446013 -405.992998) (xy 277.4569 -405.995632)
			(xy 277.533862 -406.009602) (xy 277.544953 -406.011034) (xy 277.566561 -406.005374) (xy 277.575518 -405.99868)
			(xy 277.596164 -405.982058) (xy 277.641186 -405.954089) (xy 277.689649 -405.932626) (xy 277.740618 -405.918084)
			(xy 277.793111 -405.910743) (xy 277.819612 -405.910288) (xy 277.846862 -405.910783) (xy 277.900808 -405.91854)
			(xy 277.953101 -405.933896) (xy 278.002676 -405.956538) (xy 278.048525 -405.986004) (xy 278.089713 -406.021695)
			(xy 278.125403 -406.062885) (xy 278.154868 -406.108734) (xy 278.177508 -406.15831) (xy 278.192862 -406.210603)
			(xy 278.200618 -406.26455) (xy 278.200618 -406.31905) (xy 278.192862 -406.372997) (xy 278.177508 -406.42529)
			(xy 278.154868 -406.474866) (xy 278.125403 -406.520715) (xy 278.089713 -406.561905) (xy 278.048525 -406.597596)
			(xy 278.002676 -406.627062) (xy 277.953101 -406.649704) (xy 277.900808 -406.66506) (xy 277.846862 -406.672817)
			(xy 277.819612 -406.673304) (xy 277.790794 -406.672757) (xy 277.733814 -406.664075) (xy 277.678788 -406.646923)
			(xy 277.626967 -406.621691) (xy 277.579531 -406.588952) (xy 277.537558 -406.549451) (xy 277.502003 -406.504087)
			(xy 277.48738 -406.479248) (xy 277.481415 -406.469763) (xy 277.463222 -406.456726) (xy 277.452328 -406.454102)
			(xy 277.375366 -406.440132) (xy 277.364274 -406.43871) (xy 277.342667 -406.444361) (xy 277.33371 -406.451054)
			(xy 277.313058 -406.467668) (xy 277.268037 -406.495637) (xy 277.219575 -406.517101) (xy 277.168608 -406.531645)
			(xy 277.116117 -406.538989) (xy 277.089616 -406.539446) (xy 277.062365 -406.538908) (xy 277.008418 -406.531154)
			(xy 276.956123 -406.5158) (xy 276.906546 -406.493161) (xy 276.860695 -406.463696) (xy 276.819505 -406.428006)
			(xy 276.783813 -406.386817) (xy 276.754347 -406.340968) (xy 276.731705 -406.291392) (xy 276.71635 -406.239098)
			(xy 276.708593 -406.185151) (xy 276.453107 -406.185151) (xy 276.446495 -406.230078) (xy 276.430427 -406.283485)
			(xy 276.406755 -406.333982) (xy 276.375982 -406.380495) (xy 276.338765 -406.422032) (xy 276.295897 -406.457707)
			(xy 276.248291 -406.486761) (xy 276.196962 -406.508573) (xy 276.143005 -406.522679) (xy 276.087568 -406.528779)
			(xy 276.031834 -406.526742) (xy 275.976991 -406.516612) (xy 275.924207 -406.498605) (xy 275.874607 -406.473104)
			(xy 275.829249 -406.440653) (xy 275.7891 -406.401944) (xy 275.755014 -406.357801) (xy 275.727718 -406.309166)
			(xy 275.707795 -406.257075) (xy 275.695669 -406.202638) (xy 275.691598 -406.147016) (xy 238.276892 -406.147016)
			(xy 238.276892 -406.551892) (xy 274.490686 -406.551892) (xy 274.494757 -406.49627) (xy 274.506883 -406.441833)
			(xy 274.526806 -406.389742) (xy 274.554102 -406.341107) (xy 274.588188 -406.296964) (xy 274.628337 -406.258255)
			(xy 274.673695 -406.225804) (xy 274.723295 -406.200303) (xy 274.776079 -406.182296) (xy 274.830922 -406.172166)
			(xy 274.886656 -406.170129) (xy 274.942093 -406.176229) (xy 274.99605 -406.190335) (xy 275.047379 -406.212147)
			(xy 275.094985 -406.241201) (xy 275.137853 -406.276876) (xy 275.17507 -406.318413) (xy 275.205843 -406.364926)
			(xy 275.229515 -406.415423) (xy 275.245583 -406.46883) (xy 275.253703 -406.524006) (xy 275.254212 -406.551892)
			(xy 275.253703 -406.579778) (xy 275.245583 -406.634954) (xy 275.229515 -406.688361) (xy 275.205843 -406.738858)
			(xy 275.17507 -406.785371) (xy 275.137853 -406.826908) (xy 275.094985 -406.862583) (xy 275.047379 -406.891637)
			(xy 274.99605 -406.913449) (xy 274.942093 -406.927555) (xy 274.886656 -406.933655) (xy 274.830922 -406.931618)
			(xy 274.776079 -406.921488) (xy 274.723295 -406.903481) (xy 274.673695 -406.87798) (xy 274.628337 -406.845529)
			(xy 274.588188 -406.80682) (xy 274.554102 -406.762677) (xy 274.526806 -406.714042) (xy 274.506883 -406.661951)
			(xy 274.494757 -406.607514) (xy 274.490686 -406.551892) (xy 238.276892 -406.551892) (xy 238.276892 -406.943052)
			(xy 278.739598 -406.943052) (xy 278.743669 -406.88743) (xy 278.755795 -406.832993) (xy 278.775718 -406.780902)
			(xy 278.803014 -406.732267) (xy 278.8371 -406.688124) (xy 278.877249 -406.649415) (xy 278.922607 -406.616964)
			(xy 278.972207 -406.591463) (xy 279.024991 -406.573456) (xy 279.079834 -406.563326) (xy 279.135568 -406.561289)
			(xy 279.191005 -406.567389) (xy 279.244962 -406.581495) (xy 279.296291 -406.603307) (xy 279.343897 -406.632361)
			(xy 279.386765 -406.668036) (xy 279.423982 -406.709573) (xy 279.454755 -406.756086) (xy 279.478427 -406.806583)
			(xy 279.494495 -406.85999) (xy 279.502615 -406.915166) (xy 279.503124 -406.943052) (xy 279.502615 -406.970938)
			(xy 279.494495 -407.026114) (xy 279.478427 -407.079521) (xy 279.454755 -407.130018) (xy 279.423982 -407.176531)
			(xy 279.386765 -407.218068) (xy 279.343897 -407.253743) (xy 279.296291 -407.282797) (xy 279.244962 -407.304609)
			(xy 279.205567 -407.314908) (xy 280.953462 -407.314908) (xy 280.957533 -407.259286) (xy 280.969659 -407.204849)
			(xy 280.989582 -407.152758) (xy 281.016878 -407.104123) (xy 281.050964 -407.05998) (xy 281.091113 -407.021271)
			(xy 281.136471 -406.98882) (xy 281.186071 -406.963319) (xy 281.238855 -406.945312) (xy 281.293698 -406.935182)
			(xy 281.349432 -406.933145) (xy 281.404869 -406.939245) (xy 281.458826 -406.953351) (xy 281.510155 -406.975163)
			(xy 281.557761 -407.004217) (xy 281.600629 -407.039892) (xy 281.637846 -407.081429) (xy 281.668619 -407.127942)
			(xy 281.692291 -407.178439) (xy 281.708359 -407.231846) (xy 281.716479 -407.287022) (xy 281.716988 -407.314908)
			(xy 281.716479 -407.342794) (xy 281.708359 -407.39797) (xy 281.692291 -407.451377) (xy 281.668619 -407.501874)
			(xy 281.637846 -407.548387) (xy 281.600629 -407.589924) (xy 281.557761 -407.625599) (xy 281.510155 -407.654653)
			(xy 281.458826 -407.676465) (xy 281.404869 -407.690571) (xy 281.349432 -407.696671) (xy 281.293698 -407.694634)
			(xy 281.238855 -407.684504) (xy 281.186071 -407.666497) (xy 281.136471 -407.640996) (xy 281.091113 -407.608545)
			(xy 281.050964 -407.569836) (xy 281.016878 -407.525693) (xy 280.989582 -407.477058) (xy 280.969659 -407.424967)
			(xy 280.957533 -407.37053) (xy 280.953462 -407.314908) (xy 279.205567 -407.314908) (xy 279.191005 -407.318715)
			(xy 279.135568 -407.324815) (xy 279.079834 -407.322778) (xy 279.024991 -407.312648) (xy 278.972207 -407.294641)
			(xy 278.922607 -407.26914) (xy 278.877249 -407.236689) (xy 278.8371 -407.19798) (xy 278.803014 -407.153837)
			(xy 278.775718 -407.105202) (xy 278.755795 -407.053111) (xy 278.743669 -406.998674) (xy 278.739598 -406.943052)
			(xy 238.276892 -406.943052) (xy 238.276892 -408.165046) (xy 275.975316 -408.165046) (xy 275.979387 -408.109424)
			(xy 275.991513 -408.054987) (xy 276.011436 -408.002896) (xy 276.038732 -407.954261) (xy 276.072818 -407.910118)
			(xy 276.112967 -407.871409) (xy 276.158325 -407.838958) (xy 276.207925 -407.813457) (xy 276.260709 -407.79545)
			(xy 276.315552 -407.78532) (xy 276.371286 -407.783283) (xy 276.426723 -407.789383) (xy 276.48068 -407.803489)
			(xy 276.532009 -407.825301) (xy 276.579615 -407.854355) (xy 276.622483 -407.89003) (xy 276.6597 -407.931567)
			(xy 276.690473 -407.97808) (xy 276.714145 -408.028577) (xy 276.730213 -408.081984) (xy 276.738333 -408.13716)
			(xy 276.738842 -408.165046) (xy 276.738333 -408.192932) (xy 276.730213 -408.248108) (xy 276.714145 -408.301515)
			(xy 276.690473 -408.352012) (xy 276.6597 -408.398525) (xy 276.622483 -408.440062) (xy 276.579615 -408.475737)
			(xy 276.532009 -408.504791) (xy 276.48068 -408.526603) (xy 276.426723 -408.540709) (xy 276.371286 -408.546809)
			(xy 276.315552 -408.544772) (xy 276.260709 -408.534642) (xy 276.207925 -408.516635) (xy 276.158325 -408.491134)
			(xy 276.112967 -408.458683) (xy 276.072818 -408.419974) (xy 276.038732 -408.375831) (xy 276.011436 -408.327196)
			(xy 275.991513 -408.275105) (xy 275.979387 -408.220668) (xy 275.975316 -408.165046) (xy 238.276892 -408.165046)
			(xy 238.276892 -410.136086) (xy 279.512266 -410.136086) (xy 279.516337 -410.080464) (xy 279.528463 -410.026027)
			(xy 279.548386 -409.973936) (xy 279.575682 -409.925301) (xy 279.609768 -409.881158) (xy 279.649917 -409.842449)
			(xy 279.695275 -409.809998) (xy 279.744875 -409.784497) (xy 279.797659 -409.76649) (xy 279.852502 -409.75636)
			(xy 279.908236 -409.754323) (xy 279.963673 -409.760423) (xy 280.01763 -409.774529) (xy 280.068959 -409.796341)
			(xy 280.116565 -409.825395) (xy 280.159433 -409.86107) (xy 280.19665 -409.902607) (xy 280.227423 -409.94912)
			(xy 280.251095 -409.999617) (xy 280.267163 -410.053024) (xy 280.275283 -410.1082) (xy 280.275792 -410.136086)
			(xy 280.275283 -410.163972) (xy 280.267163 -410.219148) (xy 280.251095 -410.272555) (xy 280.227423 -410.323052)
			(xy 280.19665 -410.369565) (xy 280.159433 -410.411102) (xy 280.116565 -410.446777) (xy 280.068959 -410.475831)
			(xy 280.01763 -410.497643) (xy 279.963673 -410.511749) (xy 279.908236 -410.517849) (xy 279.852502 -410.515812)
			(xy 279.797659 -410.505682) (xy 279.744875 -410.487675) (xy 279.695275 -410.462174) (xy 279.649917 -410.429723)
			(xy 279.609768 -410.391014) (xy 279.575682 -410.346871) (xy 279.548386 -410.298236) (xy 279.528463 -410.246145)
			(xy 279.516337 -410.191708) (xy 279.512266 -410.136086) (xy 238.276892 -410.136086) (xy 238.276892 -412.594552)
			(xy 238.276459 -412.604618) (xy 238.268731 -412.623208) (xy 238.261906 -412.63062) (xy 237.119414 -413.773112)
			(xy 275.328378 -413.773112) (xy 275.332449 -413.71749) (xy 275.344575 -413.663053) (xy 275.364498 -413.610962)
			(xy 275.391794 -413.562327) (xy 275.42588 -413.518184) (xy 275.466029 -413.479475) (xy 275.511387 -413.447024)
			(xy 275.560987 -413.421523) (xy 275.613771 -413.403516) (xy 275.668614 -413.393386) (xy 275.724348 -413.391349)
			(xy 275.779785 -413.397449) (xy 275.833742 -413.411555) (xy 275.885071 -413.433367) (xy 275.932677 -413.462421)
			(xy 275.975545 -413.498096) (xy 276.012762 -413.539633) (xy 276.043535 -413.586146) (xy 276.044141 -413.587438)
			(xy 276.501604 -413.587438) (xy 276.505675 -413.531816) (xy 276.517801 -413.477379) (xy 276.537724 -413.425288)
			(xy 276.56502 -413.376653) (xy 276.599106 -413.33251) (xy 276.639255 -413.293801) (xy 276.684613 -413.26135)
			(xy 276.734213 -413.235849) (xy 276.786997 -413.217842) (xy 276.84184 -413.207712) (xy 276.897574 -413.205675)
			(xy 276.953011 -413.211775) (xy 277.006968 -413.225881) (xy 277.058297 -413.247693) (xy 277.105903 -413.276747)
			(xy 277.148771 -413.312422) (xy 277.185988 -413.353959) (xy 277.216761 -413.400472) (xy 277.240433 -413.450969)
			(xy 277.251535 -413.48787) (xy 278.240996 -413.48787) (xy 278.245067 -413.432248) (xy 278.257193 -413.377811)
			(xy 278.277116 -413.32572) (xy 278.304412 -413.277085) (xy 278.338498 -413.232942) (xy 278.378647 -413.194233)
			(xy 278.424005 -413.161782) (xy 278.473605 -413.136281) (xy 278.526389 -413.118274) (xy 278.581232 -413.108144)
			(xy 278.636966 -413.106107) (xy 278.692403 -413.112207) (xy 278.74636 -413.126313) (xy 278.797689 -413.148125)
			(xy 278.845295 -413.177179) (xy 278.888163 -413.212854) (xy 278.92538 -413.254391) (xy 278.956153 -413.300904)
			(xy 278.979825 -413.351401) (xy 278.995893 -413.404808) (xy 279.004013 -413.459984) (xy 279.004522 -413.48787)
			(xy 279.004013 -413.515756) (xy 278.995893 -413.570932) (xy 278.979825 -413.624339) (xy 278.956153 -413.674836)
			(xy 278.92538 -413.721349) (xy 278.888163 -413.762886) (xy 278.845295 -413.798561) (xy 278.797689 -413.827615)
			(xy 278.74636 -413.849427) (xy 278.692403 -413.863533) (xy 278.636966 -413.869633) (xy 278.581232 -413.867596)
			(xy 278.526389 -413.857466) (xy 278.473605 -413.839459) (xy 278.424005 -413.813958) (xy 278.378647 -413.781507)
			(xy 278.338498 -413.742798) (xy 278.304412 -413.698655) (xy 278.277116 -413.65002) (xy 278.257193 -413.597929)
			(xy 278.245067 -413.543492) (xy 278.240996 -413.48787) (xy 277.251535 -413.48787) (xy 277.256501 -413.504376)
			(xy 277.264621 -413.559552) (xy 277.26513 -413.587438) (xy 277.264621 -413.615324) (xy 277.256501 -413.6705)
			(xy 277.240433 -413.723907) (xy 277.216761 -413.774404) (xy 277.185988 -413.820917) (xy 277.148771 -413.862454)
			(xy 277.127327 -413.8803) (xy 280.408378 -413.8803) (xy 280.412449 -413.824678) (xy 280.424575 -413.770241)
			(xy 280.444498 -413.71815) (xy 280.471794 -413.669515) (xy 280.50588 -413.625372) (xy 280.546029 -413.586663)
			(xy 280.591387 -413.554212) (xy 280.640987 -413.528711) (xy 280.693771 -413.510704) (xy 280.748614 -413.500574)
			(xy 280.804348 -413.498537) (xy 280.859785 -413.504637) (xy 280.913742 -413.518743) (xy 280.965071 -413.540555)
			(xy 281.012677 -413.569609) (xy 281.055545 -413.605284) (xy 281.092762 -413.646821) (xy 281.123535 -413.693334)
			(xy 281.147207 -413.743831) (xy 281.163275 -413.797238) (xy 281.171395 -413.852414) (xy 281.171904 -413.8803)
			(xy 281.171395 -413.908186) (xy 281.163275 -413.963362) (xy 281.147207 -414.016769) (xy 281.123535 -414.067266)
			(xy 281.092762 -414.113779) (xy 281.055545 -414.155316) (xy 281.012677 -414.190991) (xy 280.965071 -414.220045)
			(xy 280.913742 -414.241857) (xy 280.859785 -414.255963) (xy 280.804348 -414.262063) (xy 280.748614 -414.260026)
			(xy 280.693771 -414.249896) (xy 280.640987 -414.231889) (xy 280.591387 -414.206388) (xy 280.546029 -414.173937)
			(xy 280.50588 -414.135228) (xy 280.471794 -414.091085) (xy 280.444498 -414.04245) (xy 280.424575 -413.990359)
			(xy 280.412449 -413.935922) (xy 280.408378 -413.8803) (xy 277.127327 -413.8803) (xy 277.105903 -413.898129)
			(xy 277.058297 -413.927183) (xy 277.006968 -413.948995) (xy 276.953011 -413.963101) (xy 276.897574 -413.969201)
			(xy 276.84184 -413.967164) (xy 276.786997 -413.957034) (xy 276.734213 -413.939027) (xy 276.684613 -413.913526)
			(xy 276.639255 -413.881075) (xy 276.599106 -413.842366) (xy 276.56502 -413.798223) (xy 276.537724 -413.749588)
			(xy 276.517801 -413.697497) (xy 276.505675 -413.64306) (xy 276.501604 -413.587438) (xy 276.044141 -413.587438)
			(xy 276.067207 -413.636643) (xy 276.083275 -413.69005) (xy 276.091395 -413.745226) (xy 276.091904 -413.773112)
			(xy 276.091395 -413.800998) (xy 276.083275 -413.856174) (xy 276.067207 -413.909581) (xy 276.043535 -413.960078)
			(xy 276.012762 -414.006591) (xy 275.975545 -414.048128) (xy 275.932677 -414.083803) (xy 275.885071 -414.112857)
			(xy 275.833742 -414.134669) (xy 275.779785 -414.148775) (xy 275.724348 -414.154875) (xy 275.668614 -414.152838)
			(xy 275.613771 -414.142708) (xy 275.560987 -414.124701) (xy 275.511387 -414.0992) (xy 275.466029 -414.066749)
			(xy 275.42588 -414.02804) (xy 275.391794 -413.983897) (xy 275.364498 -413.935262) (xy 275.344575 -413.883171)
			(xy 275.332449 -413.828734) (xy 275.328378 -413.773112) (xy 237.119414 -413.773112) (xy 236.54766 -414.344866)
			(xy 236.540261 -414.35171) (xy 236.521662 -414.359435) (xy 236.511592 -414.359852) (xy 207.049624 -414.359852)
			(xy 207.039561 -414.359414) (xy 207.020981 -414.351674) (xy 207.013556 -414.344866) (xy 203.817982 -411.149292)
			(xy 203.811128 -411.141897) (xy 203.803384 -411.123298) (xy 203.802996 -411.113224) (xy 203.802996 -376.04192)
			(xy 203.802825 -376.035767) (xy 203.799871 -376.023821) (xy 203.797154 -376.018298) (xy 203.79436 -376.012964)
			(xy 203.786486 -376.004074) (xy 203.714858 -375.953528) (xy 203.708717 -375.94992) (xy 203.695052 -375.945922)
			(xy 203.687934 -375.945654) (xy 203.676504 -375.945654) (xy 203.660756 -375.948194) (xy 203.657454 -375.94921)
			(xy 203.62983 -375.957276) (xy 203.572943 -375.965956) (xy 203.54417 -375.966482) (xy 203.543916 -375.966482)
			(xy 203.516664 -375.96602) (xy 203.462715 -375.958265) (xy 203.410419 -375.942912) (xy 203.36084 -375.920272)
			(xy 203.314988 -375.890806) (xy 203.273797 -375.855115) (xy 203.238104 -375.813925) (xy 203.208636 -375.768074)
			(xy 203.185994 -375.718496) (xy 203.170638 -375.6662) (xy 203.162881 -375.612252) (xy 203.162881 -375.557748)
			(xy 203.170638 -375.5038) (xy 203.185994 -375.451504) (xy 203.208636 -375.401926) (xy 203.238104 -375.356075)
			(xy 203.273797 -375.314885) (xy 203.314988 -375.279194) (xy 203.36084 -375.249728) (xy 203.410419 -375.227088)
			(xy 203.462715 -375.211735) (xy 203.516664 -375.20398) (xy 203.543916 -375.203466) (xy 203.54417 -375.203466)
			(xy 203.571602 -375.204482) (xy 203.596221 -375.206661) (xy 203.644637 -375.216594) (xy 203.668122 -375.224294)
			(xy 203.668376 -375.224294) (xy 203.674154 -375.226141) (xy 203.686227 -375.22729) (xy 203.692252 -375.22658)
			(xy 203.703936 -375.224802) (xy 203.783946 -375.167906) (xy 203.792461 -375.160275) (xy 203.802355 -375.139697)
			(xy 203.802996 -375.128282) (xy 203.802996 -372.661688) (xy 203.802637 -372.65365) (xy 203.797596 -372.638381)
			(xy 203.79309 -372.631716) (xy 203.788518 -372.625366) (xy 203.775564 -372.615968) (xy 203.767436 -372.613428)
			(xy 203.740458 -372.60441) (xy 203.689318 -372.579506) (xy 203.642441 -372.547287) (xy 203.600868 -372.508465)
			(xy 203.565519 -372.463901) (xy 203.537177 -372.414583) (xy 203.516472 -372.361603) (xy 203.503861 -372.306137)
			(xy 203.499625 -372.249414) (xy 203.503857 -372.19269) (xy 203.516464 -372.137223) (xy 203.537165 -372.084242)
			(xy 203.565503 -372.034922) (xy 203.600849 -371.990356) (xy 203.64242 -371.951531) (xy 203.689294 -371.919308)
			(xy 203.740432 -371.894401) (xy 203.767436 -371.885464) (xy 203.76769 -371.885464) (xy 203.775293 -371.88274)
			(xy 203.788381 -371.873292) (xy 203.793344 -371.866922) (xy 203.797916 -371.860572) (xy 203.802996 -371.845332)
			(xy 203.802996 -370.759482) (xy 203.80246 -370.744396) (xy 203.793663 -370.715535) (xy 203.776812 -370.690507)
			(xy 203.75338 -370.671499) (xy 203.725415 -370.660172) (xy 203.69536 -370.657516) (xy 203.665842 -370.663762)
			(xy 203.652374 -370.670582) (xy 203.624022 -370.685437) (xy 203.563584 -370.706498) (xy 203.500479 -370.717177)
			(xy 203.468478 -370.717826) (xy 203.441209 -370.717361) (xy 203.387226 -370.709596) (xy 203.334898 -370.694228)
			(xy 203.28529 -370.671568) (xy 203.239412 -370.642079) (xy 203.198197 -370.606361) (xy 203.162486 -370.565142)
			(xy 203.133004 -370.519259) (xy 203.110352 -370.469647) (xy 203.094992 -370.417317) (xy 203.087235 -370.363333)
			(xy 203.086716 -370.336064) (xy 203.086716 -370.335556) (xy 203.087224 -370.315998) (xy 203.087495 -370.301797)
			(xy 203.081103 -370.274134) (xy 203.067333 -370.249305) (xy 203.047251 -370.229234) (xy 203.022415 -370.215477)
			(xy 202.994748 -370.209101) (xy 202.980544 -370.209318) (xy 202.960986 -370.209826) (xy 202.960478 -370.209826)
			(xy 202.933212 -370.209338) (xy 202.879236 -370.201575) (xy 202.826914 -370.186209) (xy 202.777311 -370.163553)
			(xy 202.731437 -370.134069) (xy 202.690226 -370.098357) (xy 202.654516 -370.057144) (xy 202.625035 -370.011268)
			(xy 202.602383 -369.961663) (xy 202.58702 -369.90934) (xy 202.57926 -369.855363) (xy 202.57926 -369.800831)
			(xy 202.587021 -369.746855) (xy 202.602385 -369.694532) (xy 202.625038 -369.644928) (xy 202.654519 -369.599052)
			(xy 202.690229 -369.557839) (xy 202.731441 -369.522128) (xy 202.777315 -369.492644) (xy 202.826919 -369.469989)
			(xy 202.879241 -369.454624) (xy 202.933217 -369.446861) (xy 202.987749 -369.446859) (xy 203.041726 -369.454617)
			(xy 203.09405 -369.469978) (xy 203.143655 -369.492628) (xy 203.189532 -369.522108) (xy 203.230747 -369.557816)
			(xy 203.266461 -369.599025) (xy 203.295946 -369.644898) (xy 203.318604 -369.6945) (xy 203.333972 -369.746822)
			(xy 203.341737 -369.800798) (xy 203.34224 -369.828064) (xy 203.34224 -369.828572) (xy 203.341732 -369.84813)
			(xy 203.341452 -369.86234) (xy 203.34783 -369.890025) (xy 203.361594 -369.914878) (xy 203.381678 -369.934973)
			(xy 203.406523 -369.948751) (xy 203.434205 -369.955144) (xy 203.448412 -369.95481) (xy 203.46797 -369.954302)
			(xy 203.468986 -369.954302) (xy 203.488544 -369.95481) (xy 203.50275 -369.955088) (xy 203.530425 -369.948707)
			(xy 203.555267 -369.934941) (xy 203.575349 -369.914856) (xy 203.589112 -369.890013) (xy 203.595489 -369.862337)
			(xy 203.595224 -369.84813) (xy 203.594716 -369.828572) (xy 203.594716 -369.828064) (xy 203.595209 -369.80008)
			(xy 203.603388 -369.744711) (xy 203.619565 -369.691131) (xy 203.643394 -369.640488) (xy 203.674363 -369.593867)
			(xy 203.711808 -369.55227) (xy 203.754927 -369.516586) (xy 203.778612 -369.501674) (xy 203.782168 -369.499134)
			(xy 203.791431 -369.49153) (xy 203.802299 -369.470204) (xy 203.802996 -369.45824) (xy 203.802996 -368.455956)
			(xy 203.802363 -368.443969) (xy 203.791509 -368.422597) (xy 203.782168 -368.415062) (xy 203.778612 -368.412522)
			(xy 203.754927 -368.397608) (xy 203.711799 -368.361936) (xy 203.674348 -368.320342) (xy 203.643379 -368.273721)
			(xy 203.619557 -368.223074) (xy 203.603394 -368.169489) (xy 203.595237 -368.114117) (xy 203.594716 -368.086132)
			(xy 203.594716 -368.085624) (xy 203.595224 -368.066066) (xy 203.595504 -368.051859) (xy 203.589124 -368.024179)
			(xy 203.575359 -367.999333) (xy 203.555275 -367.979247) (xy 203.53043 -367.965479) (xy 203.502751 -367.959097)
			(xy 203.488544 -367.959386) (xy 203.468986 -367.959894) (xy 203.46797 -367.959894) (xy 203.448412 -367.959386)
			(xy 203.43421 -367.959114) (xy 203.406545 -367.965503) (xy 203.381713 -367.979272) (xy 203.361641 -367.999354)
			(xy 203.347884 -368.024193) (xy 203.341509 -368.051861) (xy 203.341732 -368.066066) (xy 203.34224 -368.085624)
			(xy 203.34224 -368.086132) (xy 203.341751 -368.113399) (xy 203.333986 -368.167377) (xy 203.318618 -368.219701)
			(xy 203.29596 -368.269305) (xy 203.266474 -368.31518) (xy 203.230759 -368.356392) (xy 203.189543 -368.392102)
			(xy 203.143665 -368.421583) (xy 203.094058 -368.444234) (xy 203.041732 -368.459596) (xy 202.987753 -368.467355)
			(xy 202.933219 -368.467353) (xy 202.87924 -368.45959) (xy 202.826916 -368.444224) (xy 202.777311 -368.421569)
			(xy 202.731434 -368.392085) (xy 202.690221 -368.356372) (xy 202.654509 -368.315158) (xy 202.625026 -368.269281)
			(xy 202.602372 -368.219675) (xy 202.587008 -368.16735) (xy 202.579247 -368.113371) (xy 202.579246 -368.058837)
			(xy 202.587006 -368.004858) (xy 202.602369 -367.952533) (xy 202.625022 -367.902926) (xy 202.654504 -367.857049)
			(xy 202.690215 -367.815834) (xy 202.731428 -367.78012) (xy 202.777304 -367.750635) (xy 202.826908 -367.727978)
			(xy 202.879233 -367.712612) (xy 202.933211 -367.704848) (xy 202.960478 -367.70437) (xy 202.960986 -367.70437)
			(xy 202.980544 -367.704878) (xy 202.994753 -367.705157) (xy 203.022436 -367.698776) (xy 203.047287 -367.685011)
			(xy 203.06738 -367.664928) (xy 203.081158 -367.640084) (xy 203.087552 -367.612405) (xy 203.087224 -367.598198)
			(xy 203.086716 -367.57864) (xy 203.086716 -367.578132) (xy 203.087177 -367.550859) (xy 203.094936 -367.496867)
			(xy 203.110299 -367.44453) (xy 203.132954 -367.394911) (xy 203.162441 -367.349022) (xy 203.198158 -367.307796)
			(xy 203.239379 -367.272073) (xy 203.285264 -367.24258) (xy 203.334879 -367.219918) (xy 203.387215 -367.204547)
			(xy 203.441205 -367.196781) (xy 203.468478 -367.19637) (xy 203.500479 -367.197021) (xy 203.563585 -367.207697)
			(xy 203.624025 -367.228753) (xy 203.652374 -367.243614) (xy 203.665844 -367.250411) (xy 203.695354 -367.256617)
			(xy 203.725391 -367.25394) (xy 203.753338 -367.242614) (xy 203.776764 -367.223624) (xy 203.793627 -367.198624)
			(xy 203.802461 -367.169791) (xy 203.802996 -367.154714) (xy 203.802996 -366.71885) (xy 203.803428 -366.708784)
			(xy 203.811155 -366.690192) (xy 203.817982 -366.682782) (xy 204.001624 -366.49914) (xy 204.009022 -366.492293)
			(xy 204.02762 -366.484561) (xy 204.037692 -366.484154) (xy 204.19314 -366.484154) (xy 204.208283 -366.483594)
			(xy 204.237236 -366.47471) (xy 204.262315 -366.457732) (xy 204.28132 -366.434151) (xy 204.292582 -366.406037)
			(xy 204.295112 -366.375857) (xy 204.288689 -366.34626) (xy 204.281786 -366.33277) (xy 204.270143 -366.311286)
			(xy 204.251813 -366.265989) (xy 204.239418 -366.218722) (xy 204.233161 -366.170259) (xy 204.232764 -366.145826)
			(xy 204.233226 -366.118554) (xy 204.240985 -366.064566) (xy 204.256349 -366.012232) (xy 204.279006 -365.962617)
			(xy 204.308493 -365.916732) (xy 204.344211 -365.875511) (xy 204.385432 -365.839793) (xy 204.431317 -365.810306)
			(xy 204.480932 -365.787649) (xy 204.533266 -365.772285) (xy 204.587254 -365.764526) (xy 204.614526 -365.764064)
			(xy 204.640058 -365.764474) (xy 204.690664 -365.771288) (xy 204.73991 -365.784792) (xy 204.786915 -365.804743)
			(xy 204.80909 -365.817404) (xy 204.821892 -365.824393) (xy 204.850171 -365.831494) (xy 204.879305 -365.830331)
			(xy 204.906929 -365.821) (xy 204.930799 -365.804258) (xy 204.94898 -365.781464) (xy 204.954886 -365.768128)
			(xy 204.956643 -365.763561) (xy 204.958566 -365.753969) (xy 204.958696 -365.749078) (xy 204.958696 -363.648498)
			(xy 204.962506 -363.644688) (xy 204.962506 -363.588554) (xy 204.962938 -363.578488) (xy 204.970665 -363.559896)
			(xy 204.977492 -363.552486) (xy 205.357476 -363.172502) (xy 205.364879 -363.165667) (xy 205.383477 -363.15796)
			(xy 205.393544 -363.157516) (xy 206.72298 -363.157516) (xy 206.731362 -363.156754) (xy 206.738971 -363.155247)
			(xy 206.752817 -363.148273) (xy 206.75854 -363.143038) (xy 208.116678 -361.7849) (xy 208.124081 -361.778066)
			(xy 208.142679 -361.77036) (xy 208.152746 -361.769914) (xy 209.828892 -361.769914) (xy 209.837274 -361.769152)
			(xy 209.844882 -361.767643) (xy 209.858726 -361.760666) (xy 209.864452 -361.755436) (xy 211.547456 -360.072432)
			(xy 211.552028 -360.067098) (xy 211.552028 -358.75976) (xy 211.551598 -358.749692) (xy 211.543877 -358.731096)
			(xy 211.537042 -358.723692) (xy 211.27593 -358.462834) (xy 211.268529 -358.455995) (xy 211.249931 -358.448281)
			(xy 211.239862 -358.447848) (xy 202.821794 -358.447848) (xy 202.795707 -358.447361) (xy 202.744176 -358.439194)
			(xy 202.694559 -358.42306) (xy 202.648079 -358.39936) (xy 202.605882 -358.368675) (xy 202.587098 -358.350566)
			(xy 202.313794 -358.077262) (xy 202.306398 -358.07041) (xy 202.287799 -358.062668) (xy 202.277726 -358.062276)
			(xy 201.73569 -358.062276) (xy 201.72562 -358.0627) (xy 201.707016 -358.070414) (xy 201.699622 -358.077262)
			(xy 200.465624 -359.311154) (xy 201.002385 -359.311154) (xy 201.010141 -359.257208) (xy 201.025495 -359.204915)
			(xy 201.048134 -359.15534) (xy 201.077598 -359.109491) (xy 201.113287 -359.068301) (xy 201.154475 -359.03261)
			(xy 201.200322 -359.003143) (xy 201.249897 -358.980502) (xy 201.302189 -358.965145) (xy 201.356134 -358.957387)
			(xy 201.410634 -358.957385) (xy 201.46458 -358.965138) (xy 201.516873 -358.98049) (xy 201.56645 -359.003128)
			(xy 201.6123 -359.032591) (xy 201.65349 -359.068278) (xy 201.689183 -359.109465) (xy 201.718651 -359.155312)
			(xy 201.741294 -359.204885) (xy 201.756652 -359.257177) (xy 201.764412 -359.311122) (xy 201.7649 -359.338372)
			(xy 201.7649 -359.33888) (xy 201.764514 -359.36276) (xy 201.758532 -359.410144) (xy 201.752962 -359.433368)
			(xy 201.750059 -359.446706) (xy 201.750476 -359.473984) (xy 201.758111 -359.500175) (xy 201.772418 -359.523403)
			(xy 201.792371 -359.542007) (xy 201.816543 -359.554654) (xy 201.843204 -359.560439) (xy 201.870444 -359.558948)
			(xy 201.883518 -359.555034) (xy 201.912952 -359.545795) (xy 201.973832 -359.535837) (xy 202.004676 -359.535222)
			(xy 202.005184 -359.535222) (xy 202.032436 -359.535661) (xy 202.086386 -359.543415) (xy 202.138683 -359.558768)
			(xy 202.188263 -359.581408) (xy 202.234117 -359.610873) (xy 202.27531 -359.646564) (xy 202.311005 -359.687754)
			(xy 202.340474 -359.733605) (xy 202.363119 -359.783182) (xy 202.378477 -359.835478) (xy 202.386237 -359.889427)
			(xy 202.38624 -359.943932) (xy 202.378486 -359.997882) (xy 202.363133 -360.050179) (xy 202.340494 -360.099759)
			(xy 202.31103 -360.145613) (xy 202.275339 -360.186807) (xy 202.23415 -360.222502) (xy 202.1883 -360.251972)
			(xy 202.138722 -360.274617) (xy 202.086427 -360.289976) (xy 202.032477 -360.297736) (xy 201.977973 -360.29774)
			(xy 201.924023 -360.289987) (xy 201.871725 -360.274635) (xy 201.822145 -360.251996) (xy 201.776291 -360.222532)
			(xy 201.735097 -360.186843) (xy 201.699401 -360.145653) (xy 201.66993 -360.099804) (xy 201.647285 -360.050226)
			(xy 201.631925 -359.997931) (xy 201.624164 -359.943982) (xy 201.623676 -359.91673) (xy 201.623676 -359.916222)
			(xy 201.62406 -359.892342) (xy 201.630043 -359.844958) (xy 201.635614 -359.821734) (xy 201.638546 -359.8084)
			(xy 201.63813 -359.781117) (xy 201.630493 -359.754921) (xy 201.616183 -359.731689) (xy 201.596224 -359.713083)
			(xy 201.572046 -359.700436) (xy 201.545379 -359.694654) (xy 201.518134 -359.696151) (xy 201.505058 -359.700068)
			(xy 201.475626 -359.709313) (xy 201.414744 -359.719267) (xy 201.3839 -359.71988) (xy 201.383392 -359.71988)
			(xy 201.356142 -359.719414) (xy 201.302196 -359.711657) (xy 201.249904 -359.696301) (xy 201.200329 -359.67366)
			(xy 201.154481 -359.644195) (xy 201.113293 -359.608505) (xy 201.077603 -359.567316) (xy 201.048138 -359.521467)
			(xy 201.025497 -359.471892) (xy 201.010143 -359.4196) (xy 201.002386 -359.365654) (xy 201.002385 -359.311154)
			(xy 200.465624 -359.311154) (xy 198.750682 -361.025948) (xy 198.743834 -361.033345) (xy 198.736104 -361.051944)
			(xy 198.735696 -361.062016) (xy 198.735696 -361.199176) (xy 199.934574 -361.199176) (xy 199.938645 -361.143554)
			(xy 199.950771 -361.089117) (xy 199.970694 -361.037026) (xy 199.99799 -360.988391) (xy 200.032076 -360.944248)
			(xy 200.072225 -360.905539) (xy 200.117583 -360.873088) (xy 200.167183 -360.847587) (xy 200.219967 -360.82958)
			(xy 200.27481 -360.81945) (xy 200.330544 -360.817413) (xy 200.385981 -360.823513) (xy 200.439938 -360.837619)
			(xy 200.491267 -360.859431) (xy 200.538873 -360.888485) (xy 200.581741 -360.92416) (xy 200.618958 -360.965697)
			(xy 200.649731 -361.01221) (xy 200.673403 -361.062707) (xy 200.689471 -361.116114) (xy 200.697591 -361.17129)
			(xy 200.6981 -361.199176) (xy 200.697591 -361.227062) (xy 200.689471 -361.282238) (xy 200.673403 -361.335645)
			(xy 200.649731 -361.386142) (xy 200.618958 -361.432655) (xy 200.581741 -361.474192) (xy 200.538873 -361.509867)
			(xy 200.491267 -361.538921) (xy 200.439938 -361.560733) (xy 200.385981 -361.574839) (xy 200.330544 -361.580939)
			(xy 200.27481 -361.578902) (xy 200.219967 -361.568772) (xy 200.167183 -361.550765) (xy 200.117583 -361.525264)
			(xy 200.072225 -361.492813) (xy 200.032076 -361.454104) (xy 199.99799 -361.409961) (xy 199.970694 -361.361326)
			(xy 199.950771 -361.309235) (xy 199.938645 -361.254798) (xy 199.934574 -361.199176) (xy 198.735696 -361.199176)
			(xy 198.735696 -361.442) (xy 198.736005 -361.450194) (xy 198.741187 -361.46574) (xy 198.745856 -361.47248)
			(xy 198.754097 -361.48278) (xy 198.774793 -361.499122) (xy 198.798988 -361.509609) (xy 198.825063 -361.513541)
			(xy 198.851274 -361.510654) (xy 198.863712 -361.506262) (xy 198.885702 -361.498143) (xy 198.931166 -361.486727)
			(xy 198.977688 -361.480978) (xy 199.001126 -361.480608) (xy 199.028882 -361.481109) (xy 199.083809 -361.489154)
			(xy 199.136991 -361.505071) (xy 199.187306 -361.528524) (xy 199.233692 -361.559019) (xy 199.275173 -361.595911)
			(xy 199.310871 -361.638423) (xy 199.340034 -361.685658) (xy 199.362048 -361.73662) (xy 199.36968 -361.76331)
			(xy 199.373573 -361.776169) (xy 199.387085 -361.79938) (xy 199.406176 -361.818271) (xy 199.429529 -361.831537)
			(xy 199.455531 -361.838262) (xy 199.482387 -361.837981) (xy 199.49541 -361.834684) (xy 199.520614 -361.828073)
			(xy 199.572228 -361.820934) (xy 199.59828 -361.82046) (xy 199.62555 -361.820922) (xy 199.679536 -361.828681)
			(xy 199.731868 -361.844045) (xy 199.781481 -361.8667) (xy 199.827365 -361.896186) (xy 199.868585 -361.931901)
			(xy 199.904302 -361.973119) (xy 199.93379 -362.019001) (xy 199.956448 -362.068613) (xy 199.971814 -362.120944)
			(xy 199.979577 -362.17493) (xy 199.979577 -362.22947) (xy 199.971814 -362.283456) (xy 199.956448 -362.335787)
			(xy 199.93379 -362.385399) (xy 199.904302 -362.431281) (xy 199.868585 -362.472499) (xy 199.827365 -362.508214)
			(xy 199.781481 -362.5377) (xy 199.731868 -362.560355) (xy 199.679536 -362.575719) (xy 199.62555 -362.583478)
			(xy 199.59828 -362.583984) (xy 199.570524 -362.583484) (xy 199.515597 -362.575439) (xy 199.462415 -362.559522)
			(xy 199.412099 -362.536069) (xy 199.365712 -362.505575) (xy 199.324232 -362.468682) (xy 199.288534 -362.42617)
			(xy 199.259371 -362.378934) (xy 199.237358 -362.327972) (xy 199.229726 -362.301282) (xy 199.225833 -362.288424)
			(xy 199.21232 -362.265212) (xy 199.193229 -362.246322) (xy 199.169876 -362.233056) (xy 199.143874 -362.226331)
			(xy 199.117018 -362.22661) (xy 199.103996 -362.229908) (xy 199.078792 -362.236519) (xy 199.027178 -362.24366)
			(xy 199.001126 -362.244132) (xy 198.97769 -362.243755) (xy 198.931173 -362.237983) (xy 198.885709 -362.226573)
			(xy 198.863712 -362.218478) (xy 198.851265 -362.214118) (xy 198.825058 -362.211237) (xy 198.798988 -362.215164)
			(xy 198.774793 -362.225636) (xy 198.754087 -362.241956) (xy 198.745856 -362.25226) (xy 198.741193 -362.259002)
			(xy 198.736024 -362.274548) (xy 198.735696 -362.28274) (xy 198.735696 -362.589572) (xy 200.18832 -362.589572)
			(xy 200.192391 -362.53395) (xy 200.204517 -362.479513) (xy 200.22444 -362.427422) (xy 200.251736 -362.378787)
			(xy 200.285822 -362.334644) (xy 200.325971 -362.295935) (xy 200.371329 -362.263484) (xy 200.420929 -362.237983)
			(xy 200.473713 -362.219976) (xy 200.528556 -362.209846) (xy 200.58429 -362.207809) (xy 200.639727 -362.213909)
			(xy 200.693684 -362.228015) (xy 200.745013 -362.249827) (xy 200.792619 -362.278881) (xy 200.835487 -362.314556)
			(xy 200.846352 -362.326682) (xy 205.892398 -362.326682) (xy 205.896469 -362.27106) (xy 205.908595 -362.216623)
			(xy 205.928518 -362.164532) (xy 205.955814 -362.115897) (xy 205.9899 -362.071754) (xy 206.030049 -362.033045)
			(xy 206.075407 -362.000594) (xy 206.125007 -361.975093) (xy 206.177791 -361.957086) (xy 206.232634 -361.946956)
			(xy 206.288368 -361.944919) (xy 206.343805 -361.951019) (xy 206.397762 -361.965125) (xy 206.449091 -361.986937)
			(xy 206.496697 -362.015991) (xy 206.539565 -362.051666) (xy 206.576782 -362.093203) (xy 206.607555 -362.139716)
			(xy 206.631227 -362.190213) (xy 206.647295 -362.24362) (xy 206.655415 -362.298796) (xy 206.655924 -362.326682)
			(xy 206.655415 -362.354568) (xy 206.647295 -362.409744) (xy 206.631227 -362.463151) (xy 206.607555 -362.513648)
			(xy 206.576782 -362.560161) (xy 206.539565 -362.601698) (xy 206.496697 -362.637373) (xy 206.449091 -362.666427)
			(xy 206.397762 -362.688239) (xy 206.343805 -362.702345) (xy 206.288368 -362.708445) (xy 206.232634 -362.706408)
			(xy 206.177791 -362.696278) (xy 206.125007 -362.678271) (xy 206.075407 -362.65277) (xy 206.030049 -362.620319)
			(xy 205.9899 -362.58161) (xy 205.955814 -362.537467) (xy 205.928518 -362.488832) (xy 205.908595 -362.436741)
			(xy 205.896469 -362.382304) (xy 205.892398 -362.326682) (xy 200.846352 -362.326682) (xy 200.872704 -362.356093)
			(xy 200.903477 -362.402606) (xy 200.927149 -362.453103) (xy 200.943217 -362.50651) (xy 200.951337 -362.561686)
			(xy 200.951846 -362.589572) (xy 200.951337 -362.617458) (xy 200.943217 -362.672634) (xy 200.927149 -362.726041)
			(xy 200.903477 -362.776538) (xy 200.872704 -362.823051) (xy 200.835487 -362.864588) (xy 200.792619 -362.900263)
			(xy 200.745013 -362.929317) (xy 200.693684 -362.951129) (xy 200.639727 -362.965235) (xy 200.58429 -362.971335)
			(xy 200.528556 -362.969298) (xy 200.473713 -362.959168) (xy 200.420929 -362.941161) (xy 200.371329 -362.91566)
			(xy 200.325971 -362.883209) (xy 200.285822 -362.8445) (xy 200.251736 -362.800357) (xy 200.22444 -362.751722)
			(xy 200.204517 -362.699631) (xy 200.192391 -362.645194) (xy 200.18832 -362.589572) (xy 198.735696 -362.589572)
			(xy 198.735696 -363.00791) (xy 201.156568 -363.00791) (xy 201.160639 -362.952288) (xy 201.172765 -362.897851)
			(xy 201.192688 -362.84576) (xy 201.219984 -362.797125) (xy 201.25407 -362.752982) (xy 201.294219 -362.714273)
			(xy 201.339577 -362.681822) (xy 201.389177 -362.656321) (xy 201.441961 -362.638314) (xy 201.496804 -362.628184)
			(xy 201.552538 -362.626147) (xy 201.607975 -362.632247) (xy 201.661932 -362.646353) (xy 201.713261 -362.668165)
			(xy 201.760867 -362.697219) (xy 201.803735 -362.732894) (xy 201.840952 -362.774431) (xy 201.871725 -362.820944)
			(xy 201.895397 -362.871441) (xy 201.911465 -362.924848) (xy 201.919585 -362.980024) (xy 201.920094 -363.00791)
			(xy 201.919585 -363.035796) (xy 201.911465 -363.090972) (xy 201.895397 -363.144379) (xy 201.871725 -363.194876)
			(xy 201.840952 -363.241389) (xy 201.803735 -363.282926) (xy 201.760867 -363.318601) (xy 201.713261 -363.347655)
			(xy 201.661932 -363.369467) (xy 201.607975 -363.383573) (xy 201.552538 -363.389673) (xy 201.496804 -363.387636)
			(xy 201.441961 -363.377506) (xy 201.389177 -363.359499) (xy 201.339577 -363.333998) (xy 201.294219 -363.301547)
			(xy 201.25407 -363.262838) (xy 201.219984 -363.218695) (xy 201.192688 -363.17006) (xy 201.172765 -363.117969)
			(xy 201.160639 -363.063532) (xy 201.156568 -363.00791) (xy 198.735696 -363.00791) (xy 198.735696 -363.644942)
			(xy 202.462636 -363.644942) (xy 202.466707 -363.58932) (xy 202.478833 -363.534883) (xy 202.498756 -363.482792)
			(xy 202.526052 -363.434157) (xy 202.560138 -363.390014) (xy 202.600287 -363.351305) (xy 202.645645 -363.318854)
			(xy 202.695245 -363.293353) (xy 202.748029 -363.275346) (xy 202.802872 -363.265216) (xy 202.858606 -363.263179)
			(xy 202.914043 -363.269279) (xy 202.968 -363.283385) (xy 203.019329 -363.305197) (xy 203.066935 -363.334251)
			(xy 203.109803 -363.369926) (xy 203.14702 -363.411463) (xy 203.177793 -363.457976) (xy 203.201465 -363.508473)
			(xy 203.217533 -363.56188) (xy 203.225653 -363.617056) (xy 203.226162 -363.644942) (xy 203.225653 -363.672828)
			(xy 203.217533 -363.728004) (xy 203.201465 -363.781411) (xy 203.177793 -363.831908) (xy 203.14702 -363.878421)
			(xy 203.109803 -363.919958) (xy 203.066935 -363.955633) (xy 203.019329 -363.984687) (xy 202.968 -364.006499)
			(xy 202.914043 -364.020605) (xy 202.858606 -364.026705) (xy 202.802872 -364.024668) (xy 202.748029 -364.014538)
			(xy 202.695245 -363.996531) (xy 202.645645 -363.97103) (xy 202.600287 -363.938579) (xy 202.560138 -363.89987)
			(xy 202.526052 -363.855727) (xy 202.498756 -363.807092) (xy 202.478833 -363.755001) (xy 202.466707 -363.700564)
			(xy 202.462636 -363.644942) (xy 198.735696 -363.644942) (xy 198.735696 -364.1852) (xy 199.46188 -364.1852)
			(xy 199.465951 -364.129578) (xy 199.478077 -364.075141) (xy 199.498 -364.02305) (xy 199.525296 -363.974415)
			(xy 199.559382 -363.930272) (xy 199.599531 -363.891563) (xy 199.644889 -363.859112) (xy 199.694489 -363.833611)
			(xy 199.747273 -363.815604) (xy 199.802116 -363.805474) (xy 199.85785 -363.803437) (xy 199.913287 -363.809537)
			(xy 199.967244 -363.823643) (xy 200.018573 -363.845455) (xy 200.066179 -363.874509) (xy 200.109047 -363.910184)
			(xy 200.146264 -363.951721) (xy 200.177037 -363.998234) (xy 200.200709 -364.048731) (xy 200.216777 -364.102138)
			(xy 200.224897 -364.157314) (xy 200.225406 -364.1852) (xy 200.224897 -364.213086) (xy 200.216777 -364.268262)
			(xy 200.200709 -364.321669) (xy 200.177037 -364.372166) (xy 200.146264 -364.418679) (xy 200.109047 -364.460216)
			(xy 200.066179 -364.495891) (xy 200.018573 -364.524945) (xy 199.967244 -364.546757) (xy 199.913287 -364.560863)
			(xy 199.85785 -364.566963) (xy 199.802116 -364.564926) (xy 199.747273 -364.554796) (xy 199.694489 -364.536789)
			(xy 199.644889 -364.511288) (xy 199.599531 -364.478837) (xy 199.559382 -364.440128) (xy 199.525296 -364.395985)
			(xy 199.498 -364.34735) (xy 199.478077 -364.295259) (xy 199.465951 -364.240822) (xy 199.46188 -364.1852)
			(xy 198.735696 -364.1852) (xy 198.735696 -365.038386) (xy 201.228958 -365.038386) (xy 201.233029 -364.982764)
			(xy 201.245155 -364.928327) (xy 201.265078 -364.876236) (xy 201.292374 -364.827601) (xy 201.32646 -364.783458)
			(xy 201.366609 -364.744749) (xy 201.411967 -364.712298) (xy 201.461567 -364.686797) (xy 201.514351 -364.66879)
			(xy 201.569194 -364.65866) (xy 201.624928 -364.656623) (xy 201.680365 -364.662723) (xy 201.734322 -364.676829)
			(xy 201.785651 -364.698641) (xy 201.833257 -364.727695) (xy 201.876125 -364.76337) (xy 201.913342 -364.804907)
			(xy 201.944115 -364.85142) (xy 201.967787 -364.901917) (xy 201.983855 -364.955324) (xy 201.991975 -365.0105)
			(xy 201.992484 -365.038386) (xy 201.991975 -365.066272) (xy 201.983855 -365.121448) (xy 201.967787 -365.174855)
			(xy 201.944115 -365.225352) (xy 201.913342 -365.271865) (xy 201.876125 -365.313402) (xy 201.833257 -365.349077)
			(xy 201.785651 -365.378131) (xy 201.734322 -365.399943) (xy 201.680365 -365.414049) (xy 201.624928 -365.420149)
			(xy 201.569194 -365.418112) (xy 201.514351 -365.407982) (xy 201.461567 -365.389975) (xy 201.411967 -365.364474)
			(xy 201.366609 -365.332023) (xy 201.32646 -365.293314) (xy 201.292374 -365.249171) (xy 201.265078 -365.200536)
			(xy 201.245155 -365.148445) (xy 201.233029 -365.094008) (xy 201.228958 -365.038386) (xy 198.735696 -365.038386)
			(xy 198.735696 -366.485447) (xy 199.693324 -366.485447) (xy 199.693324 -366.430953) (xy 199.701079 -366.377014)
			(xy 199.716431 -366.324728) (xy 199.739068 -366.275158) (xy 199.768528 -366.229314) (xy 199.804213 -366.18813)
			(xy 199.845395 -366.152443) (xy 199.891237 -366.122979) (xy 199.940805 -366.100339) (xy 199.993091 -366.084984)
			(xy 200.047029 -366.077226) (xy 200.074276 -366.076738) (xy 200.099405 -366.077117) (xy 200.149228 -366.083724)
			(xy 200.197752 -366.096816) (xy 200.244138 -366.116164) (xy 200.287582 -366.141433) (xy 200.307702 -366.156494)
			(xy 200.307956 -366.156748) (xy 200.315425 -366.161974) (xy 200.332852 -366.167276) (xy 200.351036 -366.166182)
			(xy 200.359518 -366.162844) (xy 200.441052 -366.126776) (xy 200.449254 -366.1228) (xy 200.462325 -366.110114)
			(xy 200.470129 -366.093655) (xy 200.471278 -366.084612) (xy 200.471278 -366.084358) (xy 200.474123 -366.05607)
			(xy 200.487093 -366.000718) (xy 200.508134 -365.947904) (xy 200.53678 -365.898798) (xy 200.572398 -365.854487)
			(xy 200.614197 -365.815953) (xy 200.661252 -365.784049) (xy 200.712521 -365.759482) (xy 200.766869 -365.742796)
			(xy 200.82309 -365.734361) (xy 200.851516 -365.733838) (xy 200.880176 -365.734359) (xy 200.93685 -365.742944)
			(xy 200.991605 -365.759903) (xy 201.04321 -365.784856) (xy 201.090505 -365.817241) (xy 201.132428 -365.856332)
			(xy 201.168038 -365.901249) (xy 201.182732 -365.925862) (xy 201.189082 -365.937292) (xy 201.211942 -365.951008)
			(xy 201.311764 -365.954056) (xy 201.320401 -365.954016) (xy 201.336867 -365.94884) (xy 201.350655 -365.938456)
			(xy 201.355706 -365.93145) (xy 201.355706 -365.930942) (xy 201.370938 -365.908696) (xy 201.406641 -365.868298)
			(xy 201.447672 -365.833325) (xy 201.493215 -365.804473) (xy 201.542365 -365.782315) (xy 201.594143 -365.767292)
			(xy 201.647519 -365.759704) (xy 201.674476 -365.759238) (xy 201.701733 -365.759607) (xy 201.755693 -365.767362)
			(xy 201.808 -365.782718) (xy 201.85759 -365.805362) (xy 201.903451 -365.834833) (xy 201.944652 -365.870531)
			(xy 201.980352 -365.911729) (xy 202.006902 -365.95304) (xy 202.97216 -365.95304) (xy 202.976231 -365.897418)
			(xy 202.988357 -365.842981) (xy 203.00828 -365.79089) (xy 203.035576 -365.742255) (xy 203.069662 -365.698112)
			(xy 203.109811 -365.659403) (xy 203.155169 -365.626952) (xy 203.204769 -365.601451) (xy 203.257553 -365.583444)
			(xy 203.312396 -365.573314) (xy 203.36813 -365.571277) (xy 203.423567 -365.577377) (xy 203.477524 -365.591483)
			(xy 203.528853 -365.613295) (xy 203.576459 -365.642349) (xy 203.619327 -365.678024) (xy 203.656544 -365.719561)
			(xy 203.687317 -365.766074) (xy 203.710989 -365.816571) (xy 203.727057 -365.869978) (xy 203.735177 -365.925154)
			(xy 203.735686 -365.95304) (xy 203.735177 -365.980926) (xy 203.727057 -366.036102) (xy 203.710989 -366.089509)
			(xy 203.687317 -366.140006) (xy 203.656544 -366.186519) (xy 203.619327 -366.228056) (xy 203.576459 -366.263731)
			(xy 203.528853 -366.292785) (xy 203.477524 -366.314597) (xy 203.423567 -366.328703) (xy 203.36813 -366.334803)
			(xy 203.312396 -366.332766) (xy 203.257553 -366.322636) (xy 203.204769 -366.304629) (xy 203.155169 -366.279128)
			(xy 203.109811 -366.246677) (xy 203.069662 -366.207968) (xy 203.035576 -366.163825) (xy 203.00828 -366.11519)
			(xy 202.988357 -366.063099) (xy 202.976231 -366.008662) (xy 202.97216 -365.95304) (xy 202.006902 -365.95304)
			(xy 202.009826 -365.957589) (xy 202.032473 -366.007177) (xy 202.047832 -366.059483) (xy 202.055591 -366.113443)
			(xy 202.055591 -366.167957) (xy 202.047832 -366.221917) (xy 202.032473 -366.274223) (xy 202.009826 -366.323811)
			(xy 201.980352 -366.369671) (xy 201.944652 -366.410869) (xy 201.903451 -366.446567) (xy 201.85759 -366.476038)
			(xy 201.808 -366.498682) (xy 201.755693 -366.514038) (xy 201.701733 -366.521793) (xy 201.674476 -366.522254)
			(xy 201.645815 -366.521743) (xy 201.58914 -366.513157) (xy 201.534386 -366.496196) (xy 201.482781 -366.471242)
			(xy 201.435486 -366.438855) (xy 201.393562 -366.399763) (xy 201.357953 -366.354843) (xy 201.34326 -366.33023)
			(xy 201.33691 -366.3188) (xy 201.31405 -366.305084) (xy 201.214228 -366.302036) (xy 201.205591 -366.302074)
			(xy 201.189125 -366.307252) (xy 201.175337 -366.317636) (xy 201.170286 -366.324642) (xy 201.170286 -366.32515)
			(xy 201.155056 -366.347398) (xy 201.119354 -366.387796) (xy 201.078322 -366.422769) (xy 201.032779 -366.451621)
			(xy 200.983629 -366.473779) (xy 200.93185 -366.488801) (xy 200.878473 -366.496389) (xy 200.851516 -366.496854)
			(xy 200.826386 -366.496481) (xy 200.776563 -366.489872) (xy 200.728039 -366.47678) (xy 200.681654 -366.457431)
			(xy 200.63821 -366.432159) (xy 200.61809 -366.417098) (xy 200.617836 -366.416844) (xy 200.610371 -366.411612)
			(xy 200.592941 -366.406313) (xy 200.574757 -366.407409) (xy 200.566274 -366.410748) (xy 200.48474 -366.446816)
			(xy 200.47654 -366.450794) (xy 200.463469 -366.46348) (xy 200.455664 -366.479938) (xy 200.454514 -366.48898)
			(xy 200.454514 -366.489234) (xy 200.45167 -366.517522) (xy 200.438701 -366.572875) (xy 200.41766 -366.625689)
			(xy 200.389014 -366.674796) (xy 200.353397 -366.719108) (xy 200.311597 -366.757642) (xy 200.264542 -366.789546)
			(xy 200.213272 -366.814112) (xy 200.158924 -366.830797) (xy 200.102702 -366.839232) (xy 200.074276 -366.839754)
			(xy 200.047029 -366.839174) (xy 199.993091 -366.831416) (xy 199.940805 -366.816061) (xy 199.891237 -366.793421)
			(xy 199.845395 -366.763957) (xy 199.804213 -366.72827) (xy 199.768528 -366.687086) (xy 199.739068 -366.641242)
			(xy 199.716431 -366.591672) (xy 199.701079 -366.539386) (xy 199.693324 -366.485447) (xy 198.735696 -366.485447)
			(xy 198.735696 -367.76533) (xy 200.369676 -367.76533) (xy 200.373747 -367.709708) (xy 200.385873 -367.655271)
			(xy 200.405796 -367.60318) (xy 200.433092 -367.554545) (xy 200.467178 -367.510402) (xy 200.507327 -367.471693)
			(xy 200.552685 -367.439242) (xy 200.602285 -367.413741) (xy 200.655069 -367.395734) (xy 200.709912 -367.385604)
			(xy 200.765646 -367.383567) (xy 200.821083 -367.389667) (xy 200.87504 -367.403773) (xy 200.926369 -367.425585)
			(xy 200.973975 -367.454639) (xy 201.016843 -367.490314) (xy 201.05406 -367.531851) (xy 201.084833 -367.578364)
			(xy 201.108505 -367.628861) (xy 201.124573 -367.682268) (xy 201.132693 -367.737444) (xy 201.133202 -367.76533)
			(xy 201.132693 -367.793216) (xy 201.124573 -367.848392) (xy 201.108505 -367.901799) (xy 201.084833 -367.952296)
			(xy 201.05406 -367.998809) (xy 201.016843 -368.040346) (xy 200.973975 -368.076021) (xy 200.926369 -368.105075)
			(xy 200.87504 -368.126887) (xy 200.821083 -368.140993) (xy 200.765646 -368.147093) (xy 200.709912 -368.145056)
			(xy 200.655069 -368.134926) (xy 200.602285 -368.116919) (xy 200.552685 -368.091418) (xy 200.507327 -368.058967)
			(xy 200.467178 -368.020258) (xy 200.433092 -367.976115) (xy 200.405796 -367.92748) (xy 200.385873 -367.875389)
			(xy 200.373747 -367.820952) (xy 200.369676 -367.76533) (xy 198.735696 -367.76533) (xy 198.735696 -368.533172)
			(xy 201.113134 -368.533172) (xy 201.117205 -368.47755) (xy 201.129331 -368.423113) (xy 201.149254 -368.371022)
			(xy 201.17655 -368.322387) (xy 201.210636 -368.278244) (xy 201.250785 -368.239535) (xy 201.296143 -368.207084)
			(xy 201.345743 -368.181583) (xy 201.398527 -368.163576) (xy 201.45337 -368.153446) (xy 201.509104 -368.151409)
			(xy 201.564541 -368.157509) (xy 201.618498 -368.171615) (xy 201.669827 -368.193427) (xy 201.717433 -368.222481)
			(xy 201.760301 -368.258156) (xy 201.797518 -368.299693) (xy 201.828291 -368.346206) (xy 201.851963 -368.396703)
			(xy 201.868031 -368.45011) (xy 201.876151 -368.505286) (xy 201.87666 -368.533172) (xy 201.876151 -368.561058)
			(xy 201.868031 -368.616234) (xy 201.851963 -368.669641) (xy 201.828291 -368.720138) (xy 201.797518 -368.766651)
			(xy 201.760301 -368.808188) (xy 201.717433 -368.843863) (xy 201.669827 -368.872917) (xy 201.618498 -368.894729)
			(xy 201.564541 -368.908835) (xy 201.509104 -368.914935) (xy 201.45337 -368.912898) (xy 201.398527 -368.902768)
			(xy 201.345743 -368.884761) (xy 201.296143 -368.85926) (xy 201.250785 -368.826809) (xy 201.210636 -368.7881)
			(xy 201.17655 -368.743957) (xy 201.149254 -368.695322) (xy 201.129331 -368.643231) (xy 201.117205 -368.588794)
			(xy 201.113134 -368.533172) (xy 198.735696 -368.533172) (xy 198.735696 -368.848132) (xy 198.736125 -368.8582)
			(xy 198.743847 -368.876796) (xy 198.750682 -368.8842) (xy 199.266302 -369.399566) (xy 199.273699 -369.406416)
			(xy 199.292297 -369.414155) (xy 199.30237 -369.414552) (xy 199.455024 -369.414552) (xy 199.463283 -369.414276)
			(xy 199.478964 -369.409095) (xy 199.485758 -369.404392) (xy 199.496464 -369.395722) (xy 199.513188 -369.373845)
			(xy 199.523463 -369.348296) (xy 199.52654 -369.32093) (xy 199.522197 -369.293737) (xy 199.510749 -369.268692)
			(xy 199.502268 -369.257834) (xy 199.485376 -369.237108) (xy 199.456948 -369.191824) (xy 199.435119 -369.143015)
			(xy 199.420317 -369.091637) (xy 199.412832 -369.038696) (xy 199.412352 -369.011962) (xy 199.412838 -368.984693)
			(xy 199.4206 -368.930709) (xy 199.435965 -368.878379) (xy 199.458622 -368.828769) (xy 199.488108 -368.782888)
			(xy 199.523823 -368.741671) (xy 199.56504 -368.705956) (xy 199.610921 -368.67647) (xy 199.660531 -368.653813)
			(xy 199.712861 -368.638448) (xy 199.766845 -368.630686) (xy 199.821383 -368.630686) (xy 199.875367 -368.638448)
			(xy 199.927697 -368.653813) (xy 199.977307 -368.67647) (xy 200.023188 -368.705956) (xy 200.064405 -368.741671)
			(xy 200.10012 -368.782888) (xy 200.129606 -368.828769) (xy 200.152263 -368.878379) (xy 200.167628 -368.930709)
			(xy 200.17539 -368.984693) (xy 200.175876 -369.011962) (xy 200.175409 -369.038696) (xy 200.167915 -369.091636)
			(xy 200.153108 -369.143014) (xy 200.13128 -369.191823) (xy 200.102856 -369.237111) (xy 200.08596 -369.257834)
			(xy 200.077421 -369.268659) (xy 200.065931 -369.293709) (xy 200.06157 -369.320921) (xy 200.064657 -369.348307)
			(xy 200.074965 -369.373866) (xy 200.091743 -369.39573) (xy 200.10247 -369.404392) (xy 200.109267 -369.409093)
			(xy 200.124945 -369.414286) (xy 200.133204 -369.414552) (xy 200.70953 -369.414552) (xy 200.715684 -369.414387)
			(xy 200.727635 -369.411441) (xy 200.733152 -369.40871) (xy 200.760723 -369.39487) (xy 200.819222 -369.375291)
			(xy 200.880108 -369.365369) (xy 200.910952 -369.364768) (xy 200.911206 -369.364768) (xy 200.938473 -369.365255)
			(xy 200.992452 -369.373017) (xy 201.044776 -369.388381) (xy 201.094382 -369.411036) (xy 201.140258 -369.44052)
			(xy 201.181472 -369.476232) (xy 201.217184 -369.517446) (xy 201.246667 -369.563323) (xy 201.269321 -369.612929)
			(xy 201.284685 -369.665254) (xy 201.292446 -369.719233) (xy 201.292446 -369.773767) (xy 201.284685 -369.827746)
			(xy 201.269321 -369.880071) (xy 201.246667 -369.929677) (xy 201.217184 -369.975554) (xy 201.181472 -370.016768)
			(xy 201.140258 -370.05248) (xy 201.094382 -370.081964) (xy 201.044776 -370.104619) (xy 200.992452 -370.119983)
			(xy 200.938473 -370.127745) (xy 200.911206 -370.128292) (xy 200.910952 -370.128292) (xy 200.880106 -370.127704)
			(xy 200.819217 -370.117788) (xy 200.760716 -370.098207) (xy 200.733152 -370.08435) (xy 200.727621 -370.081653)
			(xy 200.71568 -370.078693) (xy 200.70953 -370.078508) (xy 199.143874 -370.078508) (xy 199.124577 -370.078167)
			(xy 199.086254 -370.073582) (xy 199.06742 -370.069364) (xy 199.061578 -370.068094) (xy 199.031606 -370.068094)
			(xy 199.021618 -370.067557) (xy 199.003185 -370.059845) (xy 198.995792 -370.053108) (xy 198.979028 -370.036344)
			(xy 198.969884 -370.028978) (xy 198.953522 -370.018628) (xy 198.923088 -369.994692) (xy 198.909178 -369.981226)
			(xy 198.169276 -369.241324) (xy 198.155811 -369.227413) (xy 198.131875 -369.19698) (xy 198.121524 -369.180618)
			(xy 198.118222 -369.175538) (xy 198.097394 -369.15471) (xy 198.090583 -369.147365) (xy 198.082847 -369.128903)
			(xy 198.082408 -369.118896) (xy 198.082408 -369.088924) (xy 198.081138 -369.083082) (xy 198.076989 -369.064305)
			(xy 198.072529 -369.026109) (xy 198.072248 -369.006882) (xy 198.072248 -361.377484) (xy 198.071937 -361.369291)
			(xy 198.066755 -361.353745) (xy 198.062088 -361.347004) (xy 198.051946 -361.334451) (xy 198.02553 -361.315939)
			(xy 198.010272 -361.310682) (xy 198.009764 -361.310682) (xy 197.999341 -361.307871) (xy 197.977822 -361.306203)
			(xy 197.967092 -361.30738) (xy 197.958962 -361.308854) (xy 197.944192 -361.316237) (xy 197.938136 -361.321858)
			(xy 197.181978 -362.077762) (xy 197.175133 -362.08516) (xy 197.167409 -362.103759) (xy 197.166992 -362.11383)
			(xy 197.166992 -363.227366) (xy 197.167296 -363.235562) (xy 197.172469 -363.251114) (xy 197.177152 -363.257846)
			(xy 197.185462 -363.268265) (xy 197.206422 -363.284713) (xy 197.230925 -363.295175) (xy 197.257301 -363.298938)
			(xy 197.283752 -363.295744) (xy 197.308475 -363.285812) (xy 197.319392 -363.278166) (xy 197.344327 -363.260259)
			(xy 197.398716 -363.231801) (xy 197.456959 -363.212414) (xy 197.517554 -363.202597) (xy 197.548246 -363.201966)
			(xy 197.575511 -363.202455) (xy 197.629486 -363.210222) (xy 197.681806 -363.22559) (xy 197.731407 -363.248247)
			(xy 197.777279 -363.277732) (xy 197.818488 -363.313445) (xy 197.854195 -363.354658) (xy 197.883675 -363.400534)
			(xy 197.906326 -363.450137) (xy 197.921688 -363.502459) (xy 197.929448 -363.556435) (xy 197.929448 -363.610965)
			(xy 197.921688 -363.664941) (xy 197.906326 -363.717263) (xy 197.883675 -363.766866) (xy 197.854195 -363.812742)
			(xy 197.818488 -363.853955) (xy 197.777279 -363.889668) (xy 197.731407 -363.919153) (xy 197.681806 -363.94181)
			(xy 197.629486 -363.957178) (xy 197.575511 -363.964945) (xy 197.548246 -363.96549) (xy 197.517551 -363.964881)
			(xy 197.456952 -363.955065) (xy 197.398705 -363.935679) (xy 197.34431 -363.907223) (xy 197.319392 -363.88929)
			(xy 197.308475 -363.881644) (xy 197.283751 -363.871716) (xy 197.2573 -363.868524) (xy 197.230924 -363.872285)
			(xy 197.20642 -363.882744) (xy 197.185456 -363.899187) (xy 197.177152 -363.90961) (xy 197.172482 -363.91635)
			(xy 197.167298 -363.931896) (xy 197.166992 -363.94009) (xy 197.166992 -364.243366) (xy 197.167296 -364.251562)
			(xy 197.172469 -364.267114) (xy 197.177152 -364.273846) (xy 197.185462 -364.284265) (xy 197.206422 -364.300713)
			(xy 197.230925 -364.311175) (xy 197.257301 -364.314938) (xy 197.283752 -364.311744) (xy 197.308475 -364.301812)
			(xy 197.319392 -364.294166) (xy 197.344327 -364.276259) (xy 197.398716 -364.247801) (xy 197.456959 -364.228414)
			(xy 197.517554 -364.218597) (xy 197.548246 -364.217966) (xy 197.575511 -364.218455) (xy 197.629486 -364.226222)
			(xy 197.681806 -364.24159) (xy 197.731407 -364.264247) (xy 197.777279 -364.293732) (xy 197.818488 -364.329445)
			(xy 197.854195 -364.370658) (xy 197.883675 -364.416534) (xy 197.906326 -364.466137) (xy 197.921688 -364.518459)
			(xy 197.929448 -364.572435) (xy 197.929448 -364.626965) (xy 197.921688 -364.680941) (xy 197.906326 -364.733263)
			(xy 197.883675 -364.782866) (xy 197.854195 -364.828742) (xy 197.818488 -364.869955) (xy 197.777279 -364.905668)
			(xy 197.731407 -364.935153) (xy 197.681806 -364.95781) (xy 197.629486 -364.973178) (xy 197.575511 -364.980945)
			(xy 197.548246 -364.98149) (xy 197.517551 -364.980881) (xy 197.456952 -364.971065) (xy 197.398705 -364.951679)
			(xy 197.34431 -364.923223) (xy 197.319392 -364.90529) (xy 197.308475 -364.897644) (xy 197.283751 -364.887716)
			(xy 197.2573 -364.884524) (xy 197.230924 -364.888285) (xy 197.20642 -364.898744) (xy 197.185456 -364.915187)
			(xy 197.177152 -364.92561) (xy 197.172482 -364.93235) (xy 197.167298 -364.947896) (xy 197.166992 -364.95609)
			(xy 197.166992 -365.259366) (xy 197.167296 -365.267562) (xy 197.172469 -365.283114) (xy 197.177152 -365.289846)
			(xy 197.185462 -365.300265) (xy 197.206422 -365.316713) (xy 197.230925 -365.327175) (xy 197.257301 -365.330938)
			(xy 197.283752 -365.327744) (xy 197.308475 -365.317812) (xy 197.319392 -365.310166) (xy 197.344327 -365.292259)
			(xy 197.398716 -365.263801) (xy 197.456959 -365.244414) (xy 197.517554 -365.234597) (xy 197.548246 -365.233966)
			(xy 197.575511 -365.234455) (xy 197.629486 -365.242222) (xy 197.681806 -365.25759) (xy 197.731407 -365.280247)
			(xy 197.777279 -365.309732) (xy 197.818488 -365.345445) (xy 197.854195 -365.386658) (xy 197.883675 -365.432534)
			(xy 197.906326 -365.482137) (xy 197.921688 -365.534459) (xy 197.929448 -365.588435) (xy 197.929448 -365.642965)
			(xy 197.921688 -365.696941) (xy 197.906326 -365.749263) (xy 197.883675 -365.798866) (xy 197.854195 -365.844742)
			(xy 197.818488 -365.885955) (xy 197.777279 -365.921668) (xy 197.731407 -365.951153) (xy 197.681806 -365.97381)
			(xy 197.629486 -365.989178) (xy 197.575511 -365.996945) (xy 197.548246 -365.99749) (xy 197.517551 -365.996881)
			(xy 197.456952 -365.987065) (xy 197.398705 -365.967679) (xy 197.34431 -365.939223) (xy 197.319392 -365.92129)
			(xy 197.308475 -365.913644) (xy 197.283751 -365.903716) (xy 197.2573 -365.900524) (xy 197.230924 -365.904285)
			(xy 197.20642 -365.914744) (xy 197.185456 -365.931187) (xy 197.177152 -365.94161) (xy 197.172482 -365.94835)
			(xy 197.167298 -365.963896) (xy 197.166992 -365.97209) (xy 197.166992 -366.920526) (xy 197.167267 -366.928785)
			(xy 197.172444 -366.944469) (xy 197.177152 -366.95126) (xy 197.18527 -366.961411) (xy 197.205621 -366.977565)
			(xy 197.229395 -366.988048) (xy 197.255048 -366.992181) (xy 197.280912 -366.989693) (xy 197.29323 -366.98555)
			(xy 197.324847 -366.974749) (xy 197.390636 -366.963119) (xy 197.42404 -366.962436) (xy 197.451308 -366.962925)
			(xy 197.505287 -366.970691) (xy 197.557612 -366.98606) (xy 197.607218 -367.008719) (xy 197.653094 -367.038206)
			(xy 197.694307 -367.073922) (xy 197.730018 -367.115138) (xy 197.7595 -367.161018) (xy 197.782154 -367.210625)
			(xy 197.797517 -367.262952) (xy 197.805278 -367.316932) (xy 197.805278 -367.371468) (xy 197.797517 -367.425448)
			(xy 197.782154 -367.477775) (xy 197.7595 -367.527382) (xy 197.730018 -367.573262) (xy 197.694307 -367.614478)
			(xy 197.653094 -367.650194) (xy 197.607218 -367.679681) (xy 197.557612 -367.70234) (xy 197.505287 -367.717709)
			(xy 197.451308 -367.725475) (xy 197.42404 -367.72596) (xy 197.390636 -367.725273) (xy 197.324845 -367.713654)
			(xy 197.29323 -367.702846) (xy 197.280898 -367.698772) (xy 197.25505 -367.696323) (xy 197.229419 -367.700458)
			(xy 197.205652 -367.710911) (xy 197.185281 -367.727008) (xy 197.177152 -367.737136) (xy 197.172457 -367.743934)
			(xy 197.16728 -367.759613) (xy 197.166992 -367.76787) (xy 197.166992 -367.988342) (xy 197.167307 -367.996533)
			(xy 197.172499 -368.012072) (xy 197.177152 -368.018822) (xy 197.185409 -368.029107) (xy 197.206127 -368.045412)
			(xy 197.230334 -368.05586) (xy 197.25641 -368.059752) (xy 197.282612 -368.056829) (xy 197.30719 -368.047285)
			(xy 197.318122 -368.039904) (xy 197.342708 -368.022801) (xy 197.396089 -367.995653) (xy 197.453054 -367.977173)
			(xy 197.512206 -367.967814) (xy 197.54215 -367.96726) (xy 197.569422 -367.96772) (xy 197.623411 -367.975476)
			(xy 197.675747 -367.990837) (xy 197.725363 -368.01349) (xy 197.771251 -368.042975) (xy 197.812474 -368.07869)
			(xy 197.848195 -368.119909) (xy 197.877686 -368.165793) (xy 197.900346 -368.215406) (xy 197.915713 -368.26774)
			(xy 197.923476 -368.321728) (xy 197.923476 -368.376272) (xy 197.915713 -368.43026) (xy 197.900346 -368.482594)
			(xy 197.877686 -368.532207) (xy 197.848195 -368.578091) (xy 197.812474 -368.61931) (xy 197.771251 -368.655025)
			(xy 197.725363 -368.68451) (xy 197.675747 -368.707163) (xy 197.623411 -368.722524) (xy 197.569422 -368.73028)
			(xy 197.54215 -368.730784) (xy 197.512209 -368.730197) (xy 197.453061 -368.720839) (xy 197.3961 -368.702363)
			(xy 197.342722 -368.675219) (xy 197.318122 -368.65814) (xy 197.307208 -368.650745) (xy 197.282623 -368.641256)
			(xy 197.256428 -368.638364) (xy 197.230365 -368.642263) (xy 197.206164 -368.652694) (xy 197.185432 -368.668963)
			(xy 197.177152 -368.679222) (xy 197.172484 -368.685963) (xy 197.167304 -368.701509) (xy 197.166992 -368.709702)
			(xy 197.166992 -369.609624) (xy 197.338694 -369.609624) (xy 197.342765 -369.554002) (xy 197.354891 -369.499565)
			(xy 197.374814 -369.447474) (xy 197.40211 -369.398839) (xy 197.436196 -369.354696) (xy 197.476345 -369.315987)
			(xy 197.521703 -369.283536) (xy 197.571303 -369.258035) (xy 197.624087 -369.240028) (xy 197.67893 -369.229898)
			(xy 197.734664 -369.227861) (xy 197.790101 -369.233961) (xy 197.844058 -369.248067) (xy 197.895387 -369.269879)
			(xy 197.942993 -369.298933) (xy 197.985861 -369.334608) (xy 198.023078 -369.376145) (xy 198.053851 -369.422658)
			(xy 198.077523 -369.473155) (xy 198.093591 -369.526562) (xy 198.101711 -369.581738) (xy 198.10222 -369.609624)
			(xy 198.101711 -369.63751) (xy 198.093591 -369.692686) (xy 198.077523 -369.746093) (xy 198.053851 -369.79659)
			(xy 198.023078 -369.843103) (xy 197.985861 -369.88464) (xy 197.942993 -369.920315) (xy 197.895387 -369.949369)
			(xy 197.844058 -369.971181) (xy 197.790101 -369.985287) (xy 197.734664 -369.991387) (xy 197.67893 -369.98935)
			(xy 197.624087 -369.97922) (xy 197.571303 -369.961213) (xy 197.521703 -369.935712) (xy 197.476345 -369.903261)
			(xy 197.436196 -369.864552) (xy 197.40211 -369.820409) (xy 197.374814 -369.771774) (xy 197.354891 -369.719683)
			(xy 197.342765 -369.665246) (xy 197.338694 -369.609624) (xy 197.166992 -369.609624) (xy 197.166992 -369.726972)
			(xy 197.167428 -369.737037) (xy 197.17516 -369.755623) (xy 197.181978 -369.76304) (xy 198.140828 -370.72189)
			(xy 198.148228 -370.728733) (xy 198.166826 -370.736459) (xy 198.176896 -370.736876) (xy 198.661528 -370.736876)
			(xy 198.686674 -370.72062) (xy 198.69277 -370.707158) (xy 198.704617 -370.682709) (xy 198.7342 -370.637141)
			(xy 198.769942 -370.596226) (xy 198.811123 -370.56079) (xy 198.85691 -370.531548) (xy 198.906379 -370.50909)
			(xy 198.958532 -370.49387) (xy 199.012316 -370.486196) (xy 199.03948 -370.48567) (xy 199.066751 -370.486132)
			(xy 199.120738 -370.493892) (xy 199.173072 -370.509257) (xy 199.222685 -370.531914) (xy 199.268569 -370.561401)
			(xy 199.309789 -370.597119) (xy 199.345506 -370.63834) (xy 199.374992 -370.684225) (xy 199.397647 -370.73384)
			(xy 199.41301 -370.786173) (xy 199.420769 -370.840161) (xy 199.421242 -370.867432) (xy 199.420761 -370.894591)
			(xy 199.413059 -370.94836) (xy 199.405158 -370.975382) (xy 199.525634 -370.975382) (xy 199.529705 -370.91976)
			(xy 199.541831 -370.865323) (xy 199.561754 -370.813232) (xy 199.58905 -370.764597) (xy 199.623136 -370.720454)
			(xy 199.663285 -370.681745) (xy 199.708643 -370.649294) (xy 199.758243 -370.623793) (xy 199.811027 -370.605786)
			(xy 199.86587 -370.595656) (xy 199.921604 -370.593619) (xy 199.977041 -370.599719) (xy 200.030998 -370.613825)
			(xy 200.082327 -370.635637) (xy 200.129933 -370.664691) (xy 200.172801 -370.700366) (xy 200.210018 -370.741903)
			(xy 200.240791 -370.788416) (xy 200.264463 -370.838913) (xy 200.280531 -370.89232) (xy 200.288651 -370.947496)
			(xy 200.28916 -370.975382) (xy 200.288651 -371.003268) (xy 200.280531 -371.058444) (xy 200.264463 -371.111851)
			(xy 200.240791 -371.162348) (xy 200.210018 -371.208861) (xy 200.172801 -371.250398) (xy 200.129933 -371.286073)
			(xy 200.082327 -371.315127) (xy 200.030998 -371.336939) (xy 199.977041 -371.351045) (xy 199.921604 -371.357145)
			(xy 199.86587 -371.355108) (xy 199.811027 -371.344978) (xy 199.758243 -371.326971) (xy 199.708643 -371.30147)
			(xy 199.663285 -371.269019) (xy 199.623136 -371.23031) (xy 199.58905 -371.186167) (xy 199.561754 -371.137532)
			(xy 199.541831 -371.085441) (xy 199.529705 -371.031004) (xy 199.525634 -370.975382) (xy 199.405158 -370.975382)
			(xy 199.397815 -371.000495) (xy 199.375337 -371.049944) (xy 199.346078 -371.095708) (xy 199.310629 -371.136864)
			(xy 199.269706 -371.172581) (xy 199.224134 -371.202138) (xy 199.174833 -371.224938) (xy 199.148954 -371.233192)
			(xy 199.140318 -371.235986) (xy 199.073008 -371.303296) (xy 199.059097 -371.316762) (xy 199.028664 -371.340698)
			(xy 199.012302 -371.351048) (xy 199.003158 -371.358414) (xy 198.97725 -371.384322) (xy 198.969906 -371.391133)
			(xy 198.951442 -371.39886) (xy 198.941436 -371.399308) (xy 198.865998 -371.399308) (xy 198.863966 -371.399562)
			(xy 198.838566 -371.400324) (xy 198.018654 -371.400324) (xy 198.018146 -371.400324) (xy 197.992746 -371.399562)
			(xy 197.990714 -371.399308) (xy 197.918832 -371.399308) (xy 197.908842 -371.398776) (xy 197.890401 -371.391072)
			(xy 197.883018 -371.384322) (xy 197.857618 -371.358922) (xy 197.85203 -371.35562) (xy 197.833511 -371.344528)
			(xy 197.799238 -371.318285) (xy 197.783704 -371.303296) (xy 196.600572 -370.120164) (xy 196.585579 -370.104634)
			(xy 196.559331 -370.070362) (xy 196.548248 -370.051838) (xy 196.544946 -370.04625) (xy 196.52869 -370.029994)
			(xy 196.521881 -370.022648) (xy 196.514153 -370.004186) (xy 196.513704 -369.99418) (xy 196.513704 -369.967764)
			(xy 196.512434 -369.961922) (xy 196.508288 -369.943145) (xy 196.503833 -369.904949) (xy 196.503544 -369.885722)
			(xy 196.503544 -361.95508) (xy 196.503809 -361.935851) (xy 196.508266 -361.897653) (xy 196.512434 -361.87888)
			(xy 196.513704 -361.873038) (xy 196.513704 -361.773724) (xy 196.514119 -361.7637) (xy 196.521785 -361.745175)
			(xy 196.535959 -361.730996) (xy 196.55448 -361.723323) (xy 196.564504 -361.722924) (xy 196.591682 -361.722924)
			(xy 196.598794 -361.722416) (xy 198.0819 -360.23931) (xy 198.082408 -360.232452) (xy 198.082408 -360.156506)
			(xy 198.081943 -360.142662) (xy 198.074505 -360.115992) (xy 198.060173 -360.092302) (xy 198.040003 -360.073335)
			(xy 198.015478 -360.060485) (xy 197.988402 -360.054698) (xy 197.960767 -360.056399) (xy 197.947534 -360.060494)
			(xy 197.943216 -360.062018) (xy 197.941438 -360.06278) (xy 197.94093 -360.063034) (xy 197.916433 -360.073425)
			(xy 197.865284 -360.0881) (xy 197.812595 -360.095551) (xy 197.78599 -360.096054) (xy 197.758721 -360.095567)
			(xy 197.704739 -360.087804) (xy 197.652411 -360.072438) (xy 197.602803 -360.049781) (xy 197.556924 -360.020295)
			(xy 197.515708 -359.984579) (xy 197.479995 -359.943362) (xy 197.450511 -359.897481) (xy 197.427856 -359.847872)
			(xy 197.412492 -359.795543) (xy 197.404732 -359.741561) (xy 197.404228 -359.714292) (xy 197.404674 -359.687602)
			(xy 197.412113 -359.634743) (xy 197.426845 -359.583436) (xy 197.448582 -359.534682) (xy 197.476901 -359.489432)
			(xy 197.511248 -359.44857) (xy 197.550954 -359.412893) (xy 197.595244 -359.383096) (xy 197.643253 -359.359761)
			(xy 197.694046 -359.343343) (xy 197.746631 -359.334163) (xy 197.77329 -359.332784) (xy 197.781926 -359.33253)
			(xy 197.783958 -359.33253) (xy 197.78599 -359.33253) (xy 197.812615 -359.332998) (xy 197.865349 -359.340407)
			(xy 197.916541 -359.355069) (xy 197.965201 -359.3767) (xy 198.010385 -359.40488) (xy 198.051216 -359.439064)
			(xy 198.086903 -359.478587) (xy 198.116754 -359.522685) (xy 198.140191 -359.570501) (xy 198.156758 -359.621109)
			(xy 198.16191 -359.647236) (xy 198.162164 -359.649268) (xy 198.164975 -359.659737) (xy 198.177922 -359.677098)
			(xy 198.196872 -359.68758) (xy 198.20763 -359.688892) (xy 198.211694 -359.689146) (xy 198.625714 -359.689146)
			(xy 198.632572 -359.688638) (xy 201.098404 -357.222806) (xy 201.10408 -357.216712) (xy 201.111474 -357.201804)
			(xy 201.112882 -357.193596) (xy 201.11422 -357.180259) (xy 201.110671 -357.153699) (xy 201.100341 -357.128973)
			(xy 201.083941 -357.107782) (xy 201.073512 -357.099362) (xy 201.066726 -357.094619) (xy 201.05105 -357.089325)
			(xy 201.042778 -357.088948) (xy 200.848468 -357.088948) (xy 200.838401 -357.089378) (xy 200.81981 -357.097106)
			(xy 200.8124 -357.103934) (xy 199.426068 -358.490012) (xy 199.425814 -358.491282) (xy 199.424798 -358.494838)
			(xy 199.416713 -358.520937) (xy 199.394117 -358.570685) (xy 199.36466 -358.616703) (xy 199.328945 -358.658052)
			(xy 199.287701 -358.693888) (xy 199.241769 -358.72348) (xy 199.192089 -358.746221) (xy 199.139674 -358.761649)
			(xy 199.085595 -358.769449) (xy 199.058276 -358.76992) (xy 199.031007 -358.769455) (xy 198.977025 -358.76169)
			(xy 198.924698 -358.746321) (xy 198.87509 -358.723661) (xy 198.829213 -358.694172) (xy 198.787999 -358.658454)
			(xy 198.752288 -358.617234) (xy 198.722807 -358.571352) (xy 198.700156 -358.52174) (xy 198.684796 -358.46941)
			(xy 198.67704 -358.415427) (xy 198.676514 -358.388158) (xy 198.677003 -358.360898) (xy 198.684765 -358.306933)
			(xy 198.700124 -358.254621) (xy 198.72277 -358.205026) (xy 198.75224 -358.159157) (xy 198.787936 -358.117947)
			(xy 198.829132 -358.082235) (xy 198.874988 -358.052745) (xy 198.924574 -358.030079) (xy 198.95058 -358.02189)
			(xy 198.95693 -358.019858) (xy 200.454514 -356.52202) (xy 200.468649 -356.508326) (xy 200.499588 -356.484002)
			(xy 200.516236 -356.473506) (xy 200.525888 -356.465886) (xy 200.541382 -356.450392) (xy 200.548732 -356.443595)
			(xy 200.567195 -356.435894) (xy 200.577196 -356.435406) (xy 200.599802 -356.435406) (xy 200.61174 -356.433882)
			(xy 200.63082 -356.429598) (xy 200.669657 -356.425017) (xy 200.68921 -356.424738) (xy 200.689718 -356.424738)
			(xy 200.701148 -356.424992) (xy 202.606148 -356.424992) (xy 202.625445 -356.425334) (xy 202.663768 -356.429922)
			(xy 202.682602 -356.434136) (xy 202.688444 -356.435406) (xy 202.718416 -356.435406) (xy 202.728402 -356.435947)
			(xy 202.746829 -356.443665) (xy 202.75423 -356.450392) (xy 202.775058 -356.47122) (xy 202.780138 -356.474522)
			(xy 202.796499 -356.484873) (xy 202.826932 -356.50881) (xy 202.840844 -356.522274) (xy 203.289154 -356.970584)
			(xy 203.296266 -356.971092) (xy 203.90231 -356.971092) (xy 203.916653 -356.970601) (xy 203.944206 -356.96262)
			(xy 203.968452 -356.94729) (xy 203.987477 -356.925822) (xy 203.999782 -356.899909) (xy 204.004393 -356.871597)
			(xy 204.003148 -356.8573) (xy 204.001836 -356.845852) (xy 204.000436 -356.822849) (xy 204.000354 -356.811326)
			(xy 204.00084 -356.784057) (xy 204.008602 -356.730073) (xy 204.023967 -356.677743) (xy 204.046624 -356.628133)
			(xy 204.07611 -356.582252) (xy 204.111825 -356.541035) (xy 204.153042 -356.50532) (xy 204.198923 -356.475834)
			(xy 204.248533 -356.453177) (xy 204.300863 -356.437812) (xy 204.354847 -356.43005) (xy 204.409385 -356.43005)
			(xy 204.463369 -356.437812) (xy 204.515699 -356.453177) (xy 204.565309 -356.475834) (xy 204.61119 -356.50532)
			(xy 204.652407 -356.541035) (xy 204.688122 -356.582252) (xy 204.717608 -356.628133) (xy 204.740265 -356.677743)
			(xy 204.75563 -356.730073) (xy 204.763392 -356.784057) (xy 204.763878 -356.811326) (xy 204.76378 -356.822848)
			(xy 204.76238 -356.84585) (xy 204.761084 -356.8573) (xy 204.759848 -356.8716) (xy 204.764459 -356.899916)
			(xy 204.77676 -356.925835) (xy 204.795782 -356.947311) (xy 204.820025 -356.962653) (xy 204.847578 -356.97065)
			(xy 204.861922 -356.971092) (xy 211.901532 -356.971092) (xy 211.911517 -356.971635) (xy 211.929941 -356.979356)
			(xy 211.937346 -356.986078) (xy 212.008974 -357.057706) (xy 212.014054 -357.061008) (xy 212.030413 -357.071362)
			(xy 212.06084 -357.095304) (xy 212.07476 -357.10876) (xy 212.096858 -357.130858) (xy 236.132368 -357.130858)
			(xy 236.136439 -357.075236) (xy 236.148565 -357.020799) (xy 236.168488 -356.968708) (xy 236.195784 -356.920073)
			(xy 236.22987 -356.87593) (xy 236.270019 -356.837221) (xy 236.315377 -356.80477) (xy 236.364977 -356.779269)
			(xy 236.417761 -356.761262) (xy 236.472604 -356.751132) (xy 236.528338 -356.749095) (xy 236.583775 -356.755195)
			(xy 236.637732 -356.769301) (xy 236.689061 -356.791113) (xy 236.736667 -356.820167) (xy 236.779535 -356.855842)
			(xy 236.816752 -356.897379) (xy 236.847525 -356.943892) (xy 236.871197 -356.994389) (xy 236.887265 -357.047796)
			(xy 236.895385 -357.102972) (xy 236.895894 -357.130858) (xy 236.895385 -357.158744) (xy 236.890705 -357.190548)
			(xy 239.453672 -357.190548) (xy 239.457743 -357.134926) (xy 239.469869 -357.080489) (xy 239.489792 -357.028398)
			(xy 239.517088 -356.979763) (xy 239.551174 -356.93562) (xy 239.591323 -356.896911) (xy 239.636681 -356.86446)
			(xy 239.686281 -356.838959) (xy 239.739065 -356.820952) (xy 239.793908 -356.810822) (xy 239.849642 -356.808785)
			(xy 239.905079 -356.814885) (xy 239.959036 -356.828991) (xy 240.010365 -356.850803) (xy 240.057971 -356.879857)
			(xy 240.100839 -356.915532) (xy 240.138056 -356.957069) (xy 240.168829 -357.003582) (xy 240.192501 -357.054079)
			(xy 240.208569 -357.107486) (xy 240.216689 -357.162662) (xy 240.217198 -357.190548) (xy 240.469672 -357.190548)
			(xy 240.473743 -357.134926) (xy 240.485869 -357.080489) (xy 240.505792 -357.028398) (xy 240.533088 -356.979763)
			(xy 240.567174 -356.93562) (xy 240.607323 -356.896911) (xy 240.652681 -356.86446) (xy 240.702281 -356.838959)
			(xy 240.755065 -356.820952) (xy 240.809908 -356.810822) (xy 240.865642 -356.808785) (xy 240.921079 -356.814885)
			(xy 240.975036 -356.828991) (xy 241.026365 -356.850803) (xy 241.073971 -356.879857) (xy 241.116839 -356.915532)
			(xy 241.154056 -356.957069) (xy 241.184829 -357.003582) (xy 241.208501 -357.054079) (xy 241.224569 -357.107486)
			(xy 241.232689 -357.162662) (xy 241.233198 -357.190548) (xy 241.232689 -357.218434) (xy 241.224569 -357.27361)
			(xy 241.208501 -357.327017) (xy 241.184829 -357.377514) (xy 241.154056 -357.424027) (xy 241.116839 -357.465564)
			(xy 241.073971 -357.501239) (xy 241.026365 -357.530293) (xy 240.975036 -357.552105) (xy 240.921079 -357.566211)
			(xy 240.865642 -357.572311) (xy 240.809908 -357.570274) (xy 240.755065 -357.560144) (xy 240.702281 -357.542137)
			(xy 240.652681 -357.516636) (xy 240.607323 -357.484185) (xy 240.567174 -357.445476) (xy 240.533088 -357.401333)
			(xy 240.505792 -357.352698) (xy 240.485869 -357.300607) (xy 240.473743 -357.24617) (xy 240.469672 -357.190548)
			(xy 240.217198 -357.190548) (xy 240.216689 -357.218434) (xy 240.208569 -357.27361) (xy 240.192501 -357.327017)
			(xy 240.168829 -357.377514) (xy 240.138056 -357.424027) (xy 240.100839 -357.465564) (xy 240.057971 -357.501239)
			(xy 240.010365 -357.530293) (xy 239.959036 -357.552105) (xy 239.905079 -357.566211) (xy 239.849642 -357.572311)
			(xy 239.793908 -357.570274) (xy 239.739065 -357.560144) (xy 239.686281 -357.542137) (xy 239.636681 -357.516636)
			(xy 239.591323 -357.484185) (xy 239.551174 -357.445476) (xy 239.517088 -357.401333) (xy 239.489792 -357.352698)
			(xy 239.469869 -357.300607) (xy 239.457743 -357.24617) (xy 239.453672 -357.190548) (xy 236.890705 -357.190548)
			(xy 236.887265 -357.21392) (xy 236.871197 -357.267327) (xy 236.847525 -357.317824) (xy 236.816752 -357.364337)
			(xy 236.779535 -357.405874) (xy 236.736667 -357.441549) (xy 236.689061 -357.470603) (xy 236.637732 -357.492415)
			(xy 236.583775 -357.506521) (xy 236.528338 -357.512621) (xy 236.472604 -357.510584) (xy 236.417761 -357.500454)
			(xy 236.364977 -357.482447) (xy 236.315377 -357.456946) (xy 236.270019 -357.424495) (xy 236.22987 -357.385786)
			(xy 236.195784 -357.341643) (xy 236.168488 -357.293008) (xy 236.148565 -357.240917) (xy 236.136439 -357.18648)
			(xy 236.132368 -357.130858) (xy 212.096858 -357.130858) (xy 213.020262 -358.054262) (xy 240.979625 -358.054262)
			(xy 240.979625 -357.99975) (xy 240.987382 -357.945794) (xy 241.002739 -357.893491) (xy 241.025383 -357.843906)
			(xy 241.054854 -357.798048) (xy 241.090551 -357.756851) (xy 241.131748 -357.721154) (xy 241.177606 -357.691683)
			(xy 241.227191 -357.669039) (xy 241.279494 -357.653682) (xy 241.33345 -357.645925) (xy 241.360706 -357.645462)
			(xy 241.386106 -357.646224) (xy 241.400221 -357.646776) (xy 241.427834 -357.64085) (xy 241.452769 -357.627589)
			(xy 241.47312 -357.608007) (xy 241.487331 -357.583601) (xy 241.494315 -357.556237) (xy 241.493539 -357.528005)
			(xy 241.489738 -357.514398) (xy 241.481556 -357.486534) (xy 241.472755 -357.429134) (xy 241.472212 -357.400098)
			(xy 241.47268 -357.372847) (xy 241.480436 -357.3189) (xy 241.495791 -357.266607) (xy 241.518432 -357.21703)
			(xy 241.547898 -357.171181) (xy 241.583589 -357.129991) (xy 241.624778 -357.0943) (xy 241.670627 -357.064834)
			(xy 241.720204 -357.042193) (xy 241.772497 -357.026837) (xy 241.826444 -357.01908) (xy 241.880945 -357.019079)
			(xy 241.934892 -357.026835) (xy 241.987186 -357.042189) (xy 242.036763 -357.064829) (xy 242.082613 -357.094293)
			(xy 242.123804 -357.129983) (xy 242.159496 -357.171172) (xy 242.188963 -357.217021) (xy 242.211605 -357.266597)
			(xy 242.226961 -357.31889) (xy 242.234719 -357.372837) (xy 242.234721 -357.427338) (xy 242.226967 -357.481285)
			(xy 242.211614 -357.53358) (xy 242.188975 -357.583157) (xy 242.159511 -357.629008) (xy 242.123822 -357.670199)
			(xy 242.082634 -357.705891) (xy 242.036786 -357.735359) (xy 241.98721 -357.758002) (xy 241.934917 -357.77336)
			(xy 241.880971 -357.781119) (xy 241.85372 -357.781606) (xy 241.82832 -357.780844) (xy 241.814205 -357.780356)
			(xy 241.7866 -357.786274) (xy 241.76167 -357.799525) (xy 241.741322 -357.819096) (xy 241.72711 -357.84349)
			(xy 241.720122 -357.870844) (xy 241.720891 -357.899066) (xy 241.724688 -357.91267) (xy 241.732863 -357.940536)
			(xy 241.741668 -357.997935) (xy 241.742214 -358.02697) (xy 241.741777 -358.054226) (xy 241.734024 -358.108182)
			(xy 241.71867 -358.160487) (xy 241.696029 -358.210073) (xy 241.666561 -358.255933) (xy 241.630866 -358.297132)
			(xy 241.589671 -358.332832) (xy 241.543816 -358.362305) (xy 241.494232 -358.384953) (xy 241.441929 -358.400313)
			(xy 241.387974 -358.408074) (xy 241.333462 -358.408076) (xy 241.279506 -358.400321) (xy 241.227202 -358.384966)
			(xy 241.177616 -358.362323) (xy 241.131757 -358.332853) (xy 241.090559 -358.297158) (xy 241.054861 -358.255962)
			(xy 241.025389 -358.210105) (xy 241.002743 -358.16052) (xy 240.987384 -358.108218) (xy 240.979625 -358.054262)
			(xy 213.020262 -358.054262) (xy 214.908384 -359.942384) (xy 214.915496 -359.942892) (xy 224.238312 -359.942892)
			(xy 224.248299 -359.943432) (xy 224.266728 -359.951147) (xy 224.274126 -359.957878) (xy 225.182938 -360.866436)
			(xy 225.188439 -360.87142) (xy 225.201607 -360.878256) (xy 225.208846 -360.879898) (xy 225.218498 -360.880914)
			(xy 236.056678 -360.880914) (xy 236.066668 -360.880381) (xy 236.085107 -360.872674) (xy 236.092492 -360.865928)
			(xy 237.04804 -359.910634) (xy 237.055386 -359.903826) (xy 237.073849 -359.896103) (xy 237.083854 -359.895648)
			(xy 245.366032 -359.895648) (xy 245.376016 -359.895103) (xy 245.394434 -359.887376) (xy 245.401846 -359.880662)
			(xy 246.308372 -358.97439) (xy 246.317938 -358.96421) (xy 246.331604 -358.939856) (xy 246.338166 -358.912712)
			(xy 246.337134 -358.884806) (xy 246.328585 -358.858221) (xy 246.313157 -358.834943) (xy 246.292004 -358.816712)
			(xy 246.266705 -358.804889) (xy 246.253 -358.802178) (xy 246.211811 -358.794887) (xy 246.130922 -358.773561)
			(xy 246.052392 -358.744735) (xy 245.976916 -358.708663) (xy 245.90516 -358.665663) (xy 245.837759 -358.616117)
			(xy 245.775307 -358.560461) (xy 245.718356 -358.499187) (xy 245.66741 -358.432837) (xy 245.622919 -358.361996)
			(xy 245.585276 -358.287292) (xy 245.554813 -358.209382) (xy 245.531799 -358.128957) (xy 245.516438 -358.046726)
			(xy 245.508866 -357.963417) (xy 245.509149 -357.879764) (xy 245.517285 -357.796508) (xy 245.533203 -357.714383)
			(xy 245.55676 -357.634115) (xy 245.58775 -357.556414) (xy 245.625898 -357.481966) (xy 245.670868 -357.411428)
			(xy 245.722262 -357.345424) (xy 245.779626 -357.284538) (xy 245.842454 -357.229306) (xy 245.910189 -357.180217)
			(xy 245.982235 -357.137704) (xy 246.057953 -357.102144) (xy 246.136676 -357.07385) (xy 246.217708 -357.053072)
			(xy 246.300332 -357.039995) (xy 246.38382 -357.034732) (xy 246.467432 -357.037332) (xy 246.550432 -357.04777)
			(xy 246.632084 -357.065955) (xy 246.711669 -357.091727) (xy 246.788482 -357.124856) (xy 246.861845 -357.165052)
			(xy 246.93111 -357.211958) (xy 246.995666 -357.26516) (xy 247.054941 -357.324188) (xy 247.108412 -357.38852)
			(xy 247.155606 -357.457589) (xy 247.196107 -357.530784) (xy 247.229557 -357.607459) (xy 247.25566 -357.686935)
			(xy 247.274186 -357.768511) (xy 247.284971 -357.851466) (xy 247.287919 -357.935067) (xy 247.283005 -358.018575)
			(xy 247.277128 -358.05999) (xy 247.275383 -358.074508) (xy 247.27931 -358.103473) (xy 247.291273 -358.130143)
			(xy 247.310295 -358.152336) (xy 247.33482 -358.168239) (xy 247.362844 -358.17655) (xy 247.377458 -358.177084)
			(xy 250.490228 -358.177084) (xy 250.497086 -358.176576) (xy 253.310898 -355.363018) (xy 253.31801 -355.349048)
			(xy 253.319026 -355.343714) (xy 253.30785 -355.319076) (xy 253.297028 -355.294158) (xy 253.281761 -355.242024)
			(xy 253.274057 -355.18825) (xy 253.27356 -355.161088) (xy 253.27356 -355.160834) (xy 253.274046 -355.133565)
			(xy 253.281808 -355.079581) (xy 253.297173 -355.027251) (xy 253.31983 -354.977641) (xy 253.349316 -354.93176)
			(xy 253.385031 -354.890543) (xy 253.426248 -354.854828) (xy 253.472129 -354.825342) (xy 253.521739 -354.802685)
			(xy 253.574069 -354.78732) (xy 253.628053 -354.779558) (xy 253.682591 -354.779558) (xy 253.736575 -354.78732)
			(xy 253.788905 -354.802685) (xy 253.838515 -354.825342) (xy 253.884396 -354.854828) (xy 253.925613 -354.890543)
			(xy 253.961328 -354.93176) (xy 253.990814 -354.977641) (xy 254.013471 -355.027251) (xy 254.028836 -355.079581)
			(xy 254.036598 -355.133565) (xy 254.037084 -355.160834) (xy 254.037084 -355.161088) (xy 254.036492 -355.191933)
			(xy 254.026571 -355.252819) (xy 254.006984 -355.311317) (xy 253.993142 -355.338888) (xy 253.990445 -355.344419)
			(xy 253.987489 -355.35636) (xy 253.9873 -355.36251) (xy 253.9873 -355.487732) (xy 253.986959 -355.507029)
			(xy 253.982373 -355.545352) (xy 253.978156 -355.564186) (xy 253.976886 -355.570028) (xy 253.976886 -355.6)
			(xy 253.976348 -355.609987) (xy 253.968633 -355.628418) (xy 253.9619 -355.635814) (xy 253.941072 -355.656642)
			(xy 253.93777 -355.661722) (xy 253.927419 -355.678084) (xy 253.903483 -355.708517) (xy 253.890018 -355.722428)
			(xy 253.513336 -356.098856) (xy 253.507704 -356.104903) (xy 253.500327 -356.119679) (xy 253.498858 -356.127812)
			(xy 253.497341 -356.142252) (xy 253.501534 -356.17097) (xy 253.513633 -356.197349) (xy 253.532662 -356.219261)
			(xy 253.557085 -356.234939) (xy 253.584931 -356.243116) (xy 253.599442 -356.243636) (xy 264.36701 -356.243636)
			(xy 264.375392 -356.242874) (xy 264.382997 -356.24136) (xy 264.39683 -356.234372) (xy 264.40257 -356.229158)
			(xy 264.919968 -355.71176) (xy 264.924949 -355.706258) (xy 264.93178 -355.693089) (xy 264.93343 -355.685852)
			(xy 264.934446 -355.6762) (xy 264.934446 -352.652076) (xy 264.9347 -352.637344) (xy 264.934954 -352.625914)
			(xy 264.925556 -352.604832) (xy 264.91946 -352.599498) (xy 264.91946 -341.602568) (xy 264.919891 -341.592502)
			(xy 264.92762 -341.573911) (xy 264.934446 -341.5665) (xy 265.680444 -340.820502) (xy 265.687845 -340.813662)
			(xy 265.706443 -340.805944) (xy 265.716512 -340.805516) (xy 267.061442 -340.805516) (xy 267.066268 -340.805262)
			(xy 267.080492 -340.802976) (xy 267.08862 -340.798912) (xy 267.110718 -340.78672) (xy 267.115544 -340.781894)
			(xy 267.12799 -340.769956) (xy 267.131292 -340.764622) (xy 267.154044 -340.729149) (xy 267.204716 -340.661803)
			(xy 267.260932 -340.599011) (xy 267.291312 -340.569804) (xy 267.535406 -340.33968) (xy 267.567261 -340.310318)
			(xy 267.635294 -340.25667) (xy 267.707765 -340.209188) (xy 267.745718 -340.188296) (xy 267.905484 -340.102444)
			(xy 267.91666 -340.094062) (xy 268.336522 -339.674454) (xy 268.365427 -339.646166) (xy 268.427137 -339.593878)
			(xy 268.492906 -339.546797) (xy 268.562296 -339.505236) (xy 268.598396 -339.487002) (xy 268.599158 -339.486494)
			(xy 296.554906 -324.472808) (xy 296.566619 -324.46602) (xy 296.586239 -324.447382) (xy 296.600276 -324.424245)
			(xy 296.607744 -324.398234) (xy 296.608119 -324.371174) (xy 296.601375 -324.344966) (xy 296.587986 -324.321449)
			(xy 296.578782 -324.311518) (xy 296.097452 -323.830188) (xy 296.094598 -323.827486) (xy 296.088215 -323.822903)
			(xy 296.084752 -323.821044) (xy 296.079326 -323.818459) (xy 296.067646 -323.815634) (xy 296.061638 -323.815456)
			(xy 265.63701 -323.815456) (xy 265.631422 -323.816726) (xy 265.621262 -323.819012) (xy 265.615166 -323.820282)
			(xy 265.594338 -323.830442) (xy 265.591148 -323.832287) (xy 265.585286 -323.836752) (xy 265.582654 -323.839332)
			(xy 265.57859 -323.843396) (xy 265.576812 -323.845682) (xy 265.514501 -323.923688) (xy 265.384222 -324.075005)
			(xy 265.247699 -324.220713) (xy 265.105174 -324.360556) (xy 264.956899 -324.494286) (xy 264.803135 -324.621667)
			(xy 264.644153 -324.742474) (xy 264.480236 -324.856493) (xy 264.311672 -324.963524) (xy 264.138759 -325.063376)
			(xy 264.050526 -325.110094) (xy 263.964449 -325.154535) (xy 263.789236 -325.237216) (xy 263.610798 -325.312685)
			(xy 263.42943 -325.380815) (xy 263.245435 -325.441493) (xy 263.05912 -325.494618) (xy 262.870793 -325.540103)
			(xy 262.680768 -325.57787) (xy 262.489361 -325.607858) (xy 262.296891 -325.630017) (xy 262.103677 -325.64431)
			(xy 261.910041 -325.650712) (xy 261.716306 -325.649214) (xy 261.522792 -325.639818) (xy 261.329822 -325.622539)
			(xy 261.137718 -325.597407) (xy 260.946797 -325.564462) (xy 260.757379 -325.52376) (xy 260.569778 -325.475369)
			(xy 260.384307 -325.419368) (xy 260.201272 -325.355852) (xy 260.02098 -325.284926) (xy 259.84373 -325.206707)
			(xy 259.669816 -325.121326) (xy 259.499529 -325.028925) (xy 259.33315 -324.929657) (xy 259.170958 -324.823688)
			(xy 259.013221 -324.711194) (xy 258.860202 -324.592362) (xy 258.712156 -324.467389) (xy 258.569329 -324.336484)
			(xy 258.431957 -324.199864) (xy 258.365752 -324.129146) (xy 258.302486 -324.060208) (xy 258.180786 -323.918053)
			(xy 258.12242 -323.84492) (xy 258.121404 -323.843396) (xy 258.11353 -323.834252) (xy 258.10337 -323.829426)
			(xy 258.084574 -323.820536) (xy 258.079413 -323.818208) (xy 258.068389 -323.815634) (xy 258.06273 -323.815456)
			(xy 252.01372 -323.815456) (xy 252.008843 -323.815555) (xy 251.999256 -323.817348) (xy 251.99467 -323.819012)
			(xy 251.985526 -323.822822) (xy 251.980192 -323.828156) (xy 251.96165 -323.835776) (xy 248.501408 -323.835776)
			(xy 248.491338 -323.835354) (xy 248.472733 -323.827639) (xy 248.46534 -323.82079) (xy 246.943118 -322.298568)
			(xy 246.940269 -322.29586) (xy 246.933893 -322.291262) (xy 246.930418 -322.289424) (xy 246.924991 -322.286844)
			(xy 246.913311 -322.284028) (xy 246.907304 -322.283836) (xy 245.295166 -322.283836) (xy 245.290288 -322.28393)
			(xy 245.280698 -322.285716) (xy 245.276116 -322.287392) (xy 245.266972 -322.291202) (xy 245.263162 -322.295012)
			(xy 245.24462 -322.302632) (xy 240.706402 -322.302632) (xy 240.699514 -322.302371) (xy 240.686247 -322.298646)
			(xy 240.68024 -322.295266) (xy 240.676176 -322.292726) (xy 240.674144 -322.29171) (xy 240.664746 -322.288916)
			(xy 240.65357 -322.287646) (xy 234.158536 -322.287646) (xy 234.146688 -322.288259) (xy 234.125491 -322.298852)
			(xy 234.117896 -322.307966) (xy 234.117896 -323.349366) (xy 234.117368 -323.37539) (xy 234.109199 -323.426792)
			(xy 234.093105 -323.47629) (xy 234.06948 -323.522666) (xy 234.038902 -323.564786) (xy 234.020868 -323.583554)
			(xy 231.266238 -326.338184) (xy 231.247467 -326.356217) (xy 231.205351 -326.386799) (xy 231.158975 -326.410428)
			(xy 231.109478 -326.426524) (xy 231.058074 -326.434692) (xy 231.03205 -326.435212) (xy 228.712268 -326.435212)
			(xy 228.70414 -326.439276) (xy 228.676214 -326.453609) (xy 228.616836 -326.473951) (xy 228.554928 -326.484298)
			(xy 228.523546 -326.484996) (xy 228.496292 -326.484536) (xy 228.442338 -326.476784) (xy 228.390036 -326.461433)
			(xy 228.340452 -326.438794) (xy 228.294594 -326.409328) (xy 228.253397 -326.373635) (xy 228.2177 -326.332443)
			(xy 228.188228 -326.286589) (xy 228.165583 -326.237007) (xy 228.150225 -326.184707) (xy 228.142467 -326.130754)
			(xy 228.142467 -326.076246) (xy 228.150225 -326.022293) (xy 228.165583 -325.969993) (xy 228.188228 -325.920411)
			(xy 228.2177 -325.874557) (xy 228.253397 -325.833365) (xy 228.294594 -325.797672) (xy 228.340452 -325.768206)
			(xy 228.390036 -325.745567) (xy 228.442338 -325.730216) (xy 228.496292 -325.722464) (xy 228.523546 -325.72198)
			(xy 228.554928 -325.722662) (xy 228.616833 -325.733024) (xy 228.676207 -325.753379) (xy 228.70414 -325.7677)
			(xy 228.712268 -325.771764) (xy 230.873046 -325.771764) (xy 230.883112 -325.771332) (xy 230.901701 -325.763602)
			(xy 230.909114 -325.756778) (xy 231.04856 -325.617332) (xy 231.049068 -325.608696) (xy 231.049068 -325.607934)
			(xy 231.045004 -325.53402) (xy 231.042464 -325.520812) (xy 231.041448 -325.517764) (xy 231.039444 -325.512238)
			(xy 231.033288 -325.502229) (xy 231.029256 -325.497952) (xy 231.0257 -325.494396) (xy 231.023668 -325.492872)
			(xy 231.002368 -325.474646) (xy 230.964823 -325.433017) (xy 230.93377 -325.386345) (xy 230.909877 -325.335633)
			(xy 230.893658 -325.281972) (xy 230.885461 -325.226515) (xy 230.884984 -325.198486) (xy 230.885472 -325.170556)
			(xy 230.89362 -325.115295) (xy 230.909738 -325.061812) (xy 230.933483 -325.011251) (xy 230.964346 -324.964692)
			(xy 231.001669 -324.923132) (xy 231.044653 -324.887458) (xy 231.092379 -324.858434) (xy 231.143828 -324.836679)
			(xy 231.170734 -324.82917) (xy 231.170988 -324.82917) (xy 231.174544 -324.828154) (xy 231.181148 -324.82536)
			(xy 231.184703 -324.82348) (xy 231.191215 -324.818762) (xy 231.194102 -324.815962) (xy 233.111802 -322.898262)
			(xy 233.116788 -322.892762) (xy 233.123629 -322.879595) (xy 233.125264 -322.872354) (xy 233.12628 -322.862702)
			(xy 233.12628 -322.330572) (xy 233.12454 -322.321697) (xy 233.11574 -322.305911) (xy 233.101995 -322.294175)
			(xy 233.085026 -322.287956) (xy 233.075988 -322.287646) (xy 216.791032 -322.287646) (xy 216.780969 -322.287209)
			(xy 216.762387 -322.279471) (xy 216.754964 -322.27266) (xy 216.080848 -321.598544) (xy 216.077999 -321.595835)
			(xy 216.071624 -321.591236) (xy 216.068148 -321.5894) (xy 216.062721 -321.586818) (xy 216.051041 -321.583996)
			(xy 216.045034 -321.583812) (xy 210.513168 -321.583812) (xy 210.508556 -321.583914) (xy 210.499484 -321.585578)
			(xy 210.495134 -321.587114) (xy 210.487006 -321.590162) (xy 210.479894 -321.596258) (xy 210.459066 -321.614292)
			(xy 210.454748 -321.620896) (xy 210.442302 -321.641216) (xy 210.440778 -321.651376) (xy 210.424923 -321.747318)
			(xy 210.386354 -321.93794) (xy 210.340017 -322.126824) (xy 210.285989 -322.313653) (xy 210.22436 -322.498114)
			(xy 210.155234 -322.679899) (xy 210.078727 -322.858703) (xy 209.994966 -323.034226) (xy 209.904092 -323.206173)
			(xy 209.806257 -323.374258) (xy 209.701625 -323.538198) (xy 209.590372 -323.697719) (xy 209.472684 -323.852554)
			(xy 209.348758 -324.002442) (xy 209.218801 -324.147133) (xy 209.083032 -324.286384) (xy 208.941678 -324.419963)
			(xy 208.794976 -324.547644) (xy 208.643171 -324.669215) (xy 208.486519 -324.784472) (xy 208.32528 -324.893221)
			(xy 208.159727 -324.995281) (xy 207.990135 -325.090479) (xy 207.816789 -325.178658) (xy 207.63998 -325.259669)
			(xy 207.460004 -325.333375) (xy 207.277162 -325.399655) (xy 207.091761 -325.458397) (xy 206.904111 -325.509502)
			(xy 206.714527 -325.552884) (xy 206.523326 -325.588472) (xy 206.330829 -325.616205) (xy 206.137359 -325.636036)
			(xy 205.943239 -325.647934) (xy 205.748794 -325.651877) (xy 205.554352 -325.64786) (xy 205.360236 -325.635888)
			(xy 205.166773 -325.615983) (xy 204.974287 -325.588176) (xy 204.7831 -325.552516) (xy 204.593532 -325.509061)
			(xy 204.405902 -325.457885) (xy 204.220523 -325.399073) (xy 204.037706 -325.332723) (xy 203.857758 -325.258948)
			(xy 203.68098 -325.17787) (xy 203.507668 -325.089625) (xy 203.338113 -324.994362) (xy 203.172598 -324.892239)
			(xy 203.011401 -324.783428) (xy 202.854792 -324.668112) (xy 202.703034 -324.546483) (xy 202.55638 -324.418746)
			(xy 202.415077 -324.285113) (xy 202.279362 -324.14581) (xy 202.14946 -324.00107) (xy 202.025591 -323.851134)
			(xy 201.907962 -323.696255) (xy 201.79677 -323.536692) (xy 201.692201 -323.372712) (xy 201.59443 -323.20459)
			(xy 201.503621 -323.032607) (xy 201.419927 -322.857052) (xy 201.343488 -322.67822) (xy 201.274431 -322.496408)
			(xy 201.212872 -322.311923) (xy 201.158916 -322.125074) (xy 201.112651 -321.936172) (xy 201.074155 -321.745536)
			(xy 201.058272 -321.649598) (xy 201.05751 -321.644264) (xy 201.051922 -321.629532) (xy 201.046588 -321.620896)
			(xy 201.03973 -321.614038) (xy 201.019664 -321.596258) (xy 201.019156 -321.596258) (xy 201.019156 -321.596004)
			(xy 201.012072 -321.59041) (xy 200.995155 -321.584149) (xy 200.986136 -321.583812) (xy 176.819052 -321.583812)
			(xy 176.814175 -321.583908) (xy 176.804586 -321.585698) (xy 176.800002 -321.587368) (xy 176.790858 -321.591178)
			(xy 173.40707 -324.974966) (xy 173.404361 -324.977815) (xy 173.399761 -324.98419) (xy 173.397926 -324.987666)
			(xy 173.395344 -324.993093) (xy 173.392524 -325.004773) (xy 173.392338 -325.01078) (xy 173.392338 -327.38695)
			(xy 248.284236 -327.38695) (xy 248.288307 -327.331328) (xy 248.300433 -327.276891) (xy 248.320356 -327.2248)
			(xy 248.347652 -327.176165) (xy 248.381738 -327.132022) (xy 248.421887 -327.093313) (xy 248.467245 -327.060862)
			(xy 248.516845 -327.035361) (xy 248.569629 -327.017354) (xy 248.624472 -327.007224) (xy 248.680206 -327.005187)
			(xy 248.735643 -327.011287) (xy 248.7896 -327.025393) (xy 248.840929 -327.047205) (xy 248.888535 -327.076259)
			(xy 248.931403 -327.111934) (xy 248.96862 -327.153471) (xy 248.999393 -327.199984) (xy 249.023065 -327.250481)
			(xy 249.039133 -327.303888) (xy 249.047253 -327.359064) (xy 249.047762 -327.38695) (xy 249.047253 -327.414836)
			(xy 249.039133 -327.470012) (xy 249.023065 -327.523419) (xy 248.999393 -327.573916) (xy 248.96862 -327.620429)
			(xy 248.931403 -327.661966) (xy 248.888535 -327.697641) (xy 248.840929 -327.726695) (xy 248.7896 -327.748507)
			(xy 248.735643 -327.762613) (xy 248.680206 -327.768713) (xy 248.624472 -327.766676) (xy 248.569629 -327.756546)
			(xy 248.516845 -327.738539) (xy 248.467245 -327.713038) (xy 248.421887 -327.680587) (xy 248.381738 -327.641878)
			(xy 248.347652 -327.597735) (xy 248.320356 -327.5491) (xy 248.300433 -327.497009) (xy 248.288307 -327.442572)
			(xy 248.284236 -327.38695) (xy 173.392338 -327.38695) (xy 173.392338 -327.55967) (xy 173.392338 -327.560432)
			(xy 173.393107 -327.571748) (xy 173.403117 -327.592069) (xy 173.411642 -327.599548) (xy 173.416214 -327.603104)
			(xy 173.931472 -327.9013) (xy 247.264172 -327.9013) (xy 247.268243 -327.845678) (xy 247.280369 -327.791241)
			(xy 247.300292 -327.73915) (xy 247.327588 -327.690515) (xy 247.361674 -327.646372) (xy 247.401823 -327.607663)
			(xy 247.447181 -327.575212) (xy 247.496781 -327.549711) (xy 247.549565 -327.531704) (xy 247.604408 -327.521574)
			(xy 247.660142 -327.519537) (xy 247.715579 -327.525637) (xy 247.769536 -327.539743) (xy 247.820865 -327.561555)
			(xy 247.868471 -327.590609) (xy 247.911339 -327.626284) (xy 247.948556 -327.667821) (xy 247.979329 -327.714334)
			(xy 248.003001 -327.764831) (xy 248.019069 -327.818238) (xy 248.027189 -327.873414) (xy 248.027698 -327.9013)
			(xy 248.027189 -327.929186) (xy 248.019069 -327.984362) (xy 248.003001 -328.037769) (xy 247.979329 -328.088266)
			(xy 247.948556 -328.134779) (xy 247.911339 -328.176316) (xy 247.868471 -328.211991) (xy 247.820865 -328.241045)
			(xy 247.769536 -328.262857) (xy 247.715579 -328.276963) (xy 247.660142 -328.283063) (xy 247.604408 -328.281026)
			(xy 247.549565 -328.270896) (xy 247.496781 -328.252889) (xy 247.447181 -328.227388) (xy 247.401823 -328.194937)
			(xy 247.361674 -328.156228) (xy 247.327588 -328.112085) (xy 247.300292 -328.06345) (xy 247.280369 -328.011359)
			(xy 247.268243 -327.956922) (xy 247.264172 -327.9013) (xy 173.931472 -327.9013) (xy 175.002531 -328.521155)
			(xy 266.319437 -328.521155) (xy 266.319437 -328.466645) (xy 266.327194 -328.412691) (xy 266.342552 -328.36039)
			(xy 266.365196 -328.310807) (xy 266.394666 -328.264951) (xy 266.430362 -328.223757) (xy 266.471558 -328.188061)
			(xy 266.517414 -328.158592) (xy 266.566998 -328.135949) (xy 266.619299 -328.120593) (xy 266.673253 -328.112836)
			(xy 266.700508 -328.112374) (xy 266.729661 -328.112946) (xy 266.787288 -328.121812) (xy 266.842897 -328.139336)
			(xy 266.895195 -328.165112) (xy 266.942966 -328.198539) (xy 266.964414 -328.218292) (xy 266.97178 -328.225404)
			(xy 266.990068 -328.23277) (xy 267.071094 -328.231754) (xy 267.080842 -328.231227) (xy 267.098871 -328.223785)
			(xy 267.106146 -328.217276) (xy 267.1064 -328.217022) (xy 267.127992 -328.19632) (xy 267.176429 -328.161227)
			(xy 267.229752 -328.134126) (xy 267.286651 -328.115683) (xy 267.345733 -328.10635) (xy 267.37564 -328.10577)
			(xy 267.402888 -328.106303) (xy 267.456828 -328.114064) (xy 267.509115 -328.129421) (xy 267.558684 -328.152063)
			(xy 267.604527 -328.181529) (xy 267.64571 -328.217218) (xy 267.681395 -328.258405) (xy 267.710856 -328.304251)
			(xy 267.733493 -328.353823) (xy 267.748845 -328.406111) (xy 267.7566 -328.460052) (xy 267.7566 -328.514548)
			(xy 267.748845 -328.568489) (xy 267.733493 -328.620777) (xy 267.710856 -328.670349) (xy 267.681395 -328.716195)
			(xy 267.64571 -328.757382) (xy 267.604527 -328.793071) (xy 267.558684 -328.822537) (xy 267.509115 -328.845179)
			(xy 267.456828 -328.860536) (xy 267.402888 -328.868297) (xy 267.37564 -328.868786) (xy 267.346486 -328.868257)
			(xy 267.288856 -328.859383) (xy 267.233246 -328.841849) (xy 267.180949 -328.816063) (xy 267.13318 -328.782626)
			(xy 267.111734 -328.762868) (xy 267.104368 -328.755756) (xy 267.08608 -328.74839) (xy 267.005054 -328.749406)
			(xy 266.995306 -328.749941) (xy 266.977277 -328.757376) (xy 266.970002 -328.763884) (xy 266.969748 -328.764138)
			(xy 266.948128 -328.78481) (xy 266.8997 -328.819909) (xy 266.846384 -328.847016) (xy 266.78949 -328.865466)
			(xy 266.730413 -328.874806) (xy 266.700508 -328.87539) (xy 266.673253 -328.874964) (xy 266.619299 -328.867207)
			(xy 266.566998 -328.851851) (xy 266.517414 -328.829208) (xy 266.471558 -328.799739) (xy 266.430362 -328.764043)
			(xy 266.394666 -328.722849) (xy 266.365196 -328.676993) (xy 266.342552 -328.62741) (xy 266.327194 -328.575109)
			(xy 266.319437 -328.521155) (xy 175.002531 -328.521155) (xy 175.935449 -329.061064) (xy 225.609148 -329.061064)
			(xy 225.613219 -329.005442) (xy 225.625345 -328.951005) (xy 225.645268 -328.898914) (xy 225.672564 -328.850279)
			(xy 225.70665 -328.806136) (xy 225.746799 -328.767427) (xy 225.792157 -328.734976) (xy 225.841757 -328.709475)
			(xy 225.894541 -328.691468) (xy 225.949384 -328.681338) (xy 226.005118 -328.679301) (xy 226.060555 -328.685401)
			(xy 226.114512 -328.699507) (xy 226.165841 -328.721319) (xy 226.213447 -328.750373) (xy 226.256315 -328.786048)
			(xy 226.293532 -328.827585) (xy 226.324305 -328.874098) (xy 226.347977 -328.924595) (xy 226.364045 -328.978002)
			(xy 226.372165 -329.033178) (xy 226.372674 -329.061064) (xy 226.372165 -329.08895) (xy 226.364045 -329.144126)
			(xy 226.354723 -329.17511) (xy 240.475768 -329.17511) (xy 240.479839 -329.119488) (xy 240.491965 -329.065051)
			(xy 240.511888 -329.01296) (xy 240.539184 -328.964325) (xy 240.57327 -328.920182) (xy 240.613419 -328.881473)
			(xy 240.658777 -328.849022) (xy 240.708377 -328.823521) (xy 240.761161 -328.805514) (xy 240.816004 -328.795384)
			(xy 240.871738 -328.793347) (xy 240.927175 -328.799447) (xy 240.981132 -328.813553) (xy 241.032461 -328.835365)
			(xy 241.080067 -328.864419) (xy 241.122935 -328.900094) (xy 241.160152 -328.941631) (xy 241.190925 -328.988144)
			(xy 241.214597 -329.038641) (xy 241.230665 -329.092048) (xy 241.238785 -329.147224) (xy 241.239294 -329.17511)
			(xy 241.238785 -329.202996) (xy 241.230665 -329.258172) (xy 241.214597 -329.311579) (xy 241.190925 -329.362076)
			(xy 241.160152 -329.408589) (xy 241.122935 -329.450126) (xy 241.080067 -329.485801) (xy 241.032461 -329.514855)
			(xy 240.981132 -329.536667) (xy 240.927175 -329.550773) (xy 240.871738 -329.556873) (xy 240.816004 -329.554836)
			(xy 240.761161 -329.544706) (xy 240.708377 -329.526699) (xy 240.658777 -329.501198) (xy 240.613419 -329.468747)
			(xy 240.57327 -329.430038) (xy 240.539184 -329.385895) (xy 240.511888 -329.33726) (xy 240.491965 -329.285169)
			(xy 240.479839 -329.230732) (xy 240.475768 -329.17511) (xy 226.354723 -329.17511) (xy 226.347977 -329.197533)
			(xy 226.324305 -329.24803) (xy 226.293532 -329.294543) (xy 226.256315 -329.33608) (xy 226.213447 -329.371755)
			(xy 226.165841 -329.400809) (xy 226.114512 -329.422621) (xy 226.060555 -329.436727) (xy 226.005118 -329.442827)
			(xy 225.949384 -329.44079) (xy 225.894541 -329.43066) (xy 225.841757 -329.412653) (xy 225.792157 -329.387152)
			(xy 225.746799 -329.354701) (xy 225.70665 -329.315992) (xy 225.672564 -329.271849) (xy 225.645268 -329.223214)
			(xy 225.625345 -329.171123) (xy 225.613219 -329.116686) (xy 225.609148 -329.061064) (xy 175.935449 -329.061064)
			(xy 178.269034 -330.411582) (xy 221.258892 -330.411582) (xy 221.259349 -330.384211) (xy 221.26717 -330.330032)
			(xy 221.282661 -330.277529) (xy 221.305504 -330.227782) (xy 221.33523 -330.181816) (xy 221.352872 -330.160884)
			(xy 221.353126 -330.16063) (xy 221.358709 -330.153541) (xy 221.364957 -330.136626) (xy 221.365318 -330.12761)
			(xy 221.365318 -330.060554) (xy 221.364931 -330.05154) (xy 221.358704 -330.034623) (xy 221.353126 -330.027534)
			(xy 221.352872 -330.027534) (xy 221.352872 -330.02728) (xy 221.335253 -330.006332) (xy 221.305539 -329.960363)
			(xy 221.282699 -329.91062) (xy 221.267204 -329.858123) (xy 221.259369 -329.80395) (xy 221.258892 -329.776582)
			(xy 221.259378 -329.749331) (xy 221.267134 -329.695383) (xy 221.282489 -329.643088) (xy 221.305131 -329.593511)
			(xy 221.334597 -329.547661) (xy 221.370288 -329.50647) (xy 221.411479 -329.470779) (xy 221.457329 -329.441313)
			(xy 221.506906 -329.418671) (xy 221.559201 -329.403316) (xy 221.613149 -329.39556) (xy 221.667651 -329.39556)
			(xy 221.721599 -329.403316) (xy 221.773894 -329.418671) (xy 221.823471 -329.441313) (xy 221.869321 -329.470779)
			(xy 221.910512 -329.50647) (xy 221.946203 -329.547661) (xy 221.975669 -329.593511) (xy 221.998311 -329.643088)
			(xy 222.013666 -329.695383) (xy 222.021422 -329.749331) (xy 222.021908 -329.776582) (xy 222.021429 -329.803952)
			(xy 222.013614 -329.85813) (xy 222.009273 -329.872848) (xy 224.897186 -329.872848) (xy 224.901257 -329.817226)
			(xy 224.913383 -329.762789) (xy 224.933306 -329.710698) (xy 224.960602 -329.662063) (xy 224.994688 -329.61792)
			(xy 225.034837 -329.579211) (xy 225.080195 -329.54676) (xy 225.129795 -329.521259) (xy 225.182579 -329.503252)
			(xy 225.237422 -329.493122) (xy 225.293156 -329.491085) (xy 225.348593 -329.497185) (xy 225.40255 -329.511291)
			(xy 225.453879 -329.533103) (xy 225.501485 -329.562157) (xy 225.544353 -329.597832) (xy 225.58157 -329.639369)
			(xy 225.612343 -329.685882) (xy 225.636015 -329.736379) (xy 225.652083 -329.789786) (xy 225.660203 -329.844962)
			(xy 225.660712 -329.872848) (xy 225.660203 -329.900734) (xy 225.652083 -329.95591) (xy 225.636015 -330.009317)
			(xy 225.612343 -330.059814) (xy 225.58157 -330.106327) (xy 225.544353 -330.147864) (xy 225.534202 -330.156312)
			(xy 228.956614 -330.156312) (xy 228.960685 -330.10069) (xy 228.972811 -330.046253) (xy 228.992734 -329.994162)
			(xy 229.02003 -329.945527) (xy 229.054116 -329.901384) (xy 229.094265 -329.862675) (xy 229.139623 -329.830224)
			(xy 229.189223 -329.804723) (xy 229.242007 -329.786716) (xy 229.29685 -329.776586) (xy 229.352584 -329.774549)
			(xy 229.408021 -329.780649) (xy 229.461978 -329.794755) (xy 229.513307 -329.816567) (xy 229.560913 -329.845621)
			(xy 229.603781 -329.881296) (xy 229.640998 -329.922833) (xy 229.671771 -329.969346) (xy 229.683212 -329.993752)
			(xy 229.870506 -329.993752) (xy 229.874577 -329.93813) (xy 229.886703 -329.883693) (xy 229.906626 -329.831602)
			(xy 229.933922 -329.782967) (xy 229.968008 -329.738824) (xy 230.008157 -329.700115) (xy 230.053515 -329.667664)
			(xy 230.103115 -329.642163) (xy 230.155899 -329.624156) (xy 230.210742 -329.614026) (xy 230.266476 -329.611989)
			(xy 230.321913 -329.618089) (xy 230.37587 -329.632195) (xy 230.427199 -329.654007) (xy 230.474805 -329.683061)
			(xy 230.517673 -329.718736) (xy 230.55489 -329.760273) (xy 230.585663 -329.806786) (xy 230.609335 -329.857283)
			(xy 230.625403 -329.91069) (xy 230.633523 -329.965866) (xy 230.634032 -329.993752) (xy 230.633523 -330.021638)
			(xy 230.627609 -330.061824) (xy 230.958134 -330.061824) (xy 230.962205 -330.006202) (xy 230.974331 -329.951765)
			(xy 230.994254 -329.899674) (xy 231.02155 -329.851039) (xy 231.055636 -329.806896) (xy 231.095785 -329.768187)
			(xy 231.141143 -329.735736) (xy 231.190743 -329.710235) (xy 231.243527 -329.692228) (xy 231.29837 -329.682098)
			(xy 231.354104 -329.680061) (xy 231.409541 -329.686161) (xy 231.463498 -329.700267) (xy 231.514827 -329.722079)
			(xy 231.562433 -329.751133) (xy 231.605301 -329.786808) (xy 231.642518 -329.828345) (xy 231.673291 -329.874858)
			(xy 231.696963 -329.925355) (xy 231.713031 -329.978762) (xy 231.721151 -330.033938) (xy 231.72166 -330.061824)
			(xy 231.721151 -330.08971) (xy 231.713031 -330.144886) (xy 231.696963 -330.198293) (xy 231.673291 -330.24879)
			(xy 231.642518 -330.295303) (xy 231.605301 -330.33684) (xy 231.562433 -330.372515) (xy 231.514827 -330.401569)
			(xy 231.463498 -330.423381) (xy 231.409541 -330.437487) (xy 231.354104 -330.443587) (xy 231.29837 -330.44155)
			(xy 231.243527 -330.43142) (xy 231.190743 -330.413413) (xy 231.141143 -330.387912) (xy 231.095785 -330.355461)
			(xy 231.055636 -330.316752) (xy 231.02155 -330.272609) (xy 230.994254 -330.223974) (xy 230.974331 -330.171883)
			(xy 230.962205 -330.117446) (xy 230.958134 -330.061824) (xy 230.627609 -330.061824) (xy 230.625403 -330.076814)
			(xy 230.609335 -330.130221) (xy 230.585663 -330.180718) (xy 230.55489 -330.227231) (xy 230.517673 -330.268768)
			(xy 230.474805 -330.304443) (xy 230.427199 -330.333497) (xy 230.37587 -330.355309) (xy 230.321913 -330.369415)
			(xy 230.266476 -330.375515) (xy 230.210742 -330.373478) (xy 230.155899 -330.363348) (xy 230.103115 -330.345341)
			(xy 230.053515 -330.31984) (xy 230.008157 -330.287389) (xy 229.968008 -330.24868) (xy 229.933922 -330.204537)
			(xy 229.906626 -330.155902) (xy 229.886703 -330.103811) (xy 229.874577 -330.049374) (xy 229.870506 -329.993752)
			(xy 229.683212 -329.993752) (xy 229.695443 -330.019843) (xy 229.711511 -330.07325) (xy 229.719631 -330.128426)
			(xy 229.72014 -330.156312) (xy 229.719631 -330.184198) (xy 229.711511 -330.239374) (xy 229.695443 -330.292781)
			(xy 229.671771 -330.343278) (xy 229.640998 -330.389791) (xy 229.603781 -330.431328) (xy 229.560913 -330.467003)
			(xy 229.513307 -330.496057) (xy 229.461978 -330.517869) (xy 229.408021 -330.531975) (xy 229.352584 -330.538075)
			(xy 229.29685 -330.536038) (xy 229.242007 -330.525908) (xy 229.189223 -330.507901) (xy 229.139623 -330.4824)
			(xy 229.094265 -330.449949) (xy 229.054116 -330.41124) (xy 229.02003 -330.367097) (xy 228.992734 -330.318462)
			(xy 228.972811 -330.266371) (xy 228.960685 -330.211934) (xy 228.956614 -330.156312) (xy 225.534202 -330.156312)
			(xy 225.501485 -330.183539) (xy 225.453879 -330.212593) (xy 225.40255 -330.234405) (xy 225.348593 -330.248511)
			(xy 225.293156 -330.254611) (xy 225.237422 -330.252574) (xy 225.182579 -330.242444) (xy 225.129795 -330.224437)
			(xy 225.080195 -330.198936) (xy 225.034837 -330.166485) (xy 224.994688 -330.127776) (xy 224.960602 -330.083633)
			(xy 224.933306 -330.034998) (xy 224.913383 -329.982907) (xy 224.901257 -329.92847) (xy 224.897186 -329.872848)
			(xy 222.009273 -329.872848) (xy 221.998128 -329.910633) (xy 221.975289 -329.96038) (xy 221.945568 -330.006348)
			(xy 221.927928 -330.02728) (xy 221.927674 -330.027534) (xy 221.922106 -330.034633) (xy 221.915849 -330.05154)
			(xy 221.915482 -330.060554) (xy 221.915482 -330.12761) (xy 221.915838 -330.136627) (xy 221.922087 -330.153544)
			(xy 221.927674 -330.16063) (xy 221.927928 -330.16063) (xy 221.927928 -330.160884) (xy 221.945577 -330.181808)
			(xy 221.975287 -330.227783) (xy 221.99812 -330.277533) (xy 222.013609 -330.330035) (xy 222.021435 -330.384212)
			(xy 222.021908 -330.411582) (xy 222.021422 -330.438833) (xy 222.013666 -330.492781) (xy 221.998311 -330.545076)
			(xy 221.975669 -330.594653) (xy 221.946203 -330.640503) (xy 221.910512 -330.681694) (xy 221.869321 -330.717385)
			(xy 221.823471 -330.746851) (xy 221.773894 -330.769493) (xy 221.721599 -330.784848) (xy 221.667651 -330.792604)
			(xy 221.613149 -330.792604) (xy 221.559201 -330.784848) (xy 221.506906 -330.769493) (xy 221.457329 -330.746851)
			(xy 221.411479 -330.717385) (xy 221.370288 -330.681694) (xy 221.334597 -330.640503) (xy 221.305131 -330.594653)
			(xy 221.282489 -330.545076) (xy 221.267134 -330.492781) (xy 221.259378 -330.438833) (xy 221.258892 -330.411582)
			(xy 178.269034 -330.411582) (xy 179.350462 -331.037438) (xy 249.7615 -331.037438) (xy 249.765571 -330.981816)
			(xy 249.777697 -330.927379) (xy 249.79762 -330.875288) (xy 249.824916 -330.826653) (xy 249.859002 -330.78251)
			(xy 249.899151 -330.743801) (xy 249.944509 -330.71135) (xy 249.994109 -330.685849) (xy 250.046893 -330.667842)
			(xy 250.101736 -330.657712) (xy 250.15747 -330.655675) (xy 250.212907 -330.661775) (xy 250.266864 -330.675881)
			(xy 250.318193 -330.697693) (xy 250.365799 -330.726747) (xy 250.408667 -330.762422) (xy 250.445884 -330.803959)
			(xy 250.476657 -330.850472) (xy 250.500329 -330.900969) (xy 250.516397 -330.954376) (xy 250.524517 -331.009552)
			(xy 250.525026 -331.037438) (xy 250.524517 -331.065324) (xy 250.516397 -331.1205) (xy 250.500329 -331.173907)
			(xy 250.476657 -331.224404) (xy 250.445884 -331.270917) (xy 250.408667 -331.312454) (xy 250.365799 -331.348129)
			(xy 250.318193 -331.377183) (xy 250.266864 -331.398995) (xy 250.212907 -331.413101) (xy 250.15747 -331.419201)
			(xy 250.101736 -331.417164) (xy 250.046893 -331.407034) (xy 249.994109 -331.389027) (xy 249.944509 -331.363526)
			(xy 249.899151 -331.331075) (xy 249.859002 -331.292366) (xy 249.824916 -331.248223) (xy 249.79762 -331.199588)
			(xy 249.777697 -331.147497) (xy 249.765571 -331.09306) (xy 249.7615 -331.037438) (xy 179.350462 -331.037438)
			(xy 180.80363 -331.878432) (xy 239.366296 -331.878432) (xy 239.370367 -331.82281) (xy 239.382493 -331.768373)
			(xy 239.402416 -331.716282) (xy 239.429712 -331.667647) (xy 239.463798 -331.623504) (xy 239.503947 -331.584795)
			(xy 239.549305 -331.552344) (xy 239.598905 -331.526843) (xy 239.651689 -331.508836) (xy 239.706532 -331.498706)
			(xy 239.762266 -331.496669) (xy 239.817703 -331.502769) (xy 239.87166 -331.516875) (xy 239.922989 -331.538687)
			(xy 239.970595 -331.567741) (xy 240.013463 -331.603416) (xy 240.05068 -331.644953) (xy 240.081453 -331.691466)
			(xy 240.105125 -331.741963) (xy 240.121193 -331.79537) (xy 240.129313 -331.850546) (xy 240.129822 -331.878432)
			(xy 240.129313 -331.906318) (xy 240.121193 -331.961494) (xy 240.105125 -332.014901) (xy 240.081453 -332.065398)
			(xy 240.05068 -332.111911) (xy 240.013463 -332.153448) (xy 239.970595 -332.189123) (xy 239.922989 -332.218177)
			(xy 239.87166 -332.239989) (xy 239.817703 -332.254095) (xy 239.762266 -332.260195) (xy 239.706532 -332.258158)
			(xy 239.651689 -332.248028) (xy 239.598905 -332.230021) (xy 239.549305 -332.20452) (xy 239.503947 -332.172069)
			(xy 239.463798 -332.13336) (xy 239.429712 -332.089217) (xy 239.402416 -332.040582) (xy 239.382493 -331.988491)
			(xy 239.370367 -331.934054) (xy 239.366296 -331.878432) (xy 180.80363 -331.878432) (xy 182.032733 -332.589752)
			(xy 228.949232 -332.589752) (xy 228.949232 -332.535248) (xy 228.956988 -332.481298) (xy 228.972342 -332.429001)
			(xy 228.994983 -332.379421) (xy 229.024448 -332.333567) (xy 229.060138 -332.292374) (xy 229.101327 -332.256678)
			(xy 229.147177 -332.227207) (xy 229.196754 -332.20456) (xy 229.249049 -332.189199) (xy 229.302998 -332.181435)
			(xy 229.33025 -332.180946) (xy 229.356964 -332.181383) (xy 229.409865 -332.188873) (xy 229.461204 -332.203671)
			(xy 229.509975 -332.225488) (xy 229.555226 -332.253897) (xy 229.596069 -332.288342) (xy 229.614222 -332.307946)
			(xy 229.614222 -332.3082) (xy 229.621904 -332.315821) (xy 229.641761 -332.324372) (xy 229.652576 -332.32471)
			(xy 229.74046 -332.323694) (xy 229.760272 -332.314296) (xy 229.767384 -332.305914) (xy 229.785598 -332.285247)
			(xy 229.826945 -332.248848) (xy 229.873099 -332.218775) (xy 229.923098 -332.195653) (xy 229.975904 -332.179965)
			(xy 230.030417 -332.172035) (xy 230.05796 -332.171548) (xy 230.085212 -332.172096) (xy 230.139161 -332.179848)
			(xy 230.191457 -332.195199) (xy 230.241037 -332.217836) (xy 230.28689 -332.2473) (xy 230.328082 -332.282989)
			(xy 230.363776 -332.324178) (xy 230.393244 -332.370028) (xy 230.415887 -332.419605) (xy 230.431244 -332.4719)
			(xy 230.439001 -332.525848) (xy 230.439001 -332.580352) (xy 230.431244 -332.6343) (xy 230.415887 -332.686595)
			(xy 230.393244 -332.736172) (xy 230.363776 -332.782022) (xy 230.328082 -332.823211) (xy 230.28689 -332.8589)
			(xy 230.248986 -332.883256) (xy 236.029498 -332.883256) (xy 236.033569 -332.827634) (xy 236.045695 -332.773197)
			(xy 236.065618 -332.721106) (xy 236.092914 -332.672471) (xy 236.127 -332.628328) (xy 236.167149 -332.589619)
			(xy 236.212507 -332.557168) (xy 236.262107 -332.531667) (xy 236.314891 -332.51366) (xy 236.369734 -332.50353)
			(xy 236.425468 -332.501493) (xy 236.480905 -332.507593) (xy 236.534862 -332.521699) (xy 236.586191 -332.543511)
			(xy 236.633797 -332.572565) (xy 236.676665 -332.60824) (xy 236.713882 -332.649777) (xy 236.744655 -332.69629)
			(xy 236.768327 -332.746787) (xy 236.784395 -332.800194) (xy 236.792515 -332.85537) (xy 236.793024 -332.883256)
			(xy 236.792515 -332.911142) (xy 236.784395 -332.966318) (xy 236.768327 -333.019725) (xy 236.744655 -333.070222)
			(xy 236.713882 -333.116735) (xy 236.676665 -333.158272) (xy 236.633797 -333.193947) (xy 236.586191 -333.223001)
			(xy 236.534862 -333.244813) (xy 236.480905 -333.258919) (xy 236.425468 -333.265019) (xy 236.369734 -333.262982)
			(xy 236.314891 -333.252852) (xy 236.262107 -333.234845) (xy 236.212507 -333.209344) (xy 236.167149 -333.176893)
			(xy 236.127 -333.138184) (xy 236.092914 -333.094041) (xy 236.065618 -333.045406) (xy 236.045695 -332.993315)
			(xy 236.033569 -332.938878) (xy 236.029498 -332.883256) (xy 230.248986 -332.883256) (xy 230.241037 -332.888364)
			(xy 230.191457 -332.911001) (xy 230.139161 -332.926352) (xy 230.085212 -332.934104) (xy 230.05796 -332.934564)
			(xy 230.031246 -332.934117) (xy 229.978346 -332.926628) (xy 229.927007 -332.911832) (xy 229.878236 -332.890017)
			(xy 229.832985 -332.86161) (xy 229.792141 -332.827167) (xy 229.773988 -332.807564) (xy 229.773988 -332.80731)
			(xy 229.766301 -332.799695) (xy 229.746448 -332.79114) (xy 229.735634 -332.7908) (xy 229.64775 -332.791816)
			(xy 229.627938 -332.801214) (xy 229.620826 -332.809596) (xy 229.602609 -332.830261) (xy 229.561262 -332.866659)
			(xy 229.515109 -332.896732) (xy 229.46511 -332.919854) (xy 229.412305 -332.935543) (xy 229.357793 -332.943474)
			(xy 229.33025 -332.943962) (xy 229.302998 -332.943565) (xy 229.249049 -332.935801) (xy 229.196754 -332.92044)
			(xy 229.147177 -332.897793) (xy 229.101327 -332.868322) (xy 229.060138 -332.832626) (xy 229.024448 -332.791433)
			(xy 228.994983 -332.745579) (xy 228.972342 -332.695999) (xy 228.956988 -332.643702) (xy 228.949232 -332.589752)
			(xy 182.032733 -332.589752) (xy 184.482416 -334.00746) (xy 225.00285 -334.00746) (xy 225.006921 -333.951838)
			(xy 225.019047 -333.897401) (xy 225.03897 -333.84531) (xy 225.066266 -333.796675) (xy 225.100352 -333.752532)
			(xy 225.140501 -333.713823) (xy 225.185859 -333.681372) (xy 225.235459 -333.655871) (xy 225.288243 -333.637864)
			(xy 225.343086 -333.627734) (xy 225.39882 -333.625697) (xy 225.454257 -333.631797) (xy 225.508214 -333.645903)
			(xy 225.559543 -333.667715) (xy 225.607149 -333.696769) (xy 225.650017 -333.732444) (xy 225.687234 -333.773981)
			(xy 225.718007 -333.820494) (xy 225.72409 -333.83347) (xy 225.95916 -333.83347) (xy 225.963231 -333.777848)
			(xy 225.975357 -333.723411) (xy 225.99528 -333.67132) (xy 226.022576 -333.622685) (xy 226.056662 -333.578542)
			(xy 226.096811 -333.539833) (xy 226.142169 -333.507382) (xy 226.191769 -333.481881) (xy 226.244553 -333.463874)
			(xy 226.299396 -333.453744) (xy 226.35513 -333.451707) (xy 226.410567 -333.457807) (xy 226.464524 -333.471913)
			(xy 226.515853 -333.493725) (xy 226.563459 -333.522779) (xy 226.606327 -333.558454) (xy 226.643544 -333.599991)
			(xy 226.674317 -333.646504) (xy 226.697989 -333.697001) (xy 226.714057 -333.750408) (xy 226.722177 -333.805584)
			(xy 226.722686 -333.83347) (xy 226.722177 -333.861356) (xy 226.714057 -333.916532) (xy 226.697989 -333.969939)
			(xy 226.674317 -334.020436) (xy 226.643544 -334.066949) (xy 226.606327 -334.108486) (xy 226.563459 -334.144161)
			(xy 226.515853 -334.173215) (xy 226.464524 -334.195027) (xy 226.410567 -334.209133) (xy 226.35513 -334.215233)
			(xy 226.299396 -334.213196) (xy 226.244553 -334.203066) (xy 226.191769 -334.185059) (xy 226.142169 -334.159558)
			(xy 226.096811 -334.127107) (xy 226.056662 -334.088398) (xy 226.022576 -334.044255) (xy 225.99528 -333.99562)
			(xy 225.975357 -333.943529) (xy 225.963231 -333.889092) (xy 225.95916 -333.83347) (xy 225.72409 -333.83347)
			(xy 225.741679 -333.870991) (xy 225.757747 -333.924398) (xy 225.765867 -333.979574) (xy 225.766376 -334.00746)
			(xy 225.765867 -334.035346) (xy 225.757747 -334.090522) (xy 225.741679 -334.143929) (xy 225.718007 -334.194426)
			(xy 225.687234 -334.240939) (xy 225.650017 -334.282476) (xy 225.607149 -334.318151) (xy 225.559543 -334.347205)
			(xy 225.511899 -334.367451) (xy 230.428778 -334.367451) (xy 230.428778 -334.312949) (xy 230.436534 -334.259001)
			(xy 230.451889 -334.206706) (xy 230.474531 -334.157129) (xy 230.503997 -334.111279) (xy 230.539688 -334.070088)
			(xy 230.580879 -334.034397) (xy 230.626729 -334.004931) (xy 230.676306 -333.982289) (xy 230.728601 -333.966934)
			(xy 230.782549 -333.959178) (xy 230.8098 -333.958692) (xy 230.837644 -333.959212) (xy 230.892732 -333.967366)
			(xy 230.919528 -333.974948) (xy 230.933923 -333.97882) (xy 230.963724 -333.978783) (xy 230.992248 -333.970151)
			(xy 231.017068 -333.953656) (xy 231.036074 -333.930703) (xy 231.047651 -333.903242) (xy 231.050812 -333.873609)
			(xy 231.04856 -333.85887) (xy 231.045567 -333.841563) (xy 231.042388 -333.806583) (xy 231.04221 -333.78902)
			(xy 231.042633 -333.761766) (xy 231.050388 -333.707811) (xy 231.065742 -333.65551) (xy 231.088383 -333.605926)
			(xy 231.117851 -333.560069) (xy 231.153544 -333.518872) (xy 231.194737 -333.483174) (xy 231.240591 -333.453702)
			(xy 231.290173 -333.431056) (xy 231.342473 -333.415696) (xy 231.396426 -333.407936) (xy 231.450935 -333.407934)
			(xy 231.504889 -333.415688) (xy 231.557191 -333.431042) (xy 231.606775 -333.453684) (xy 231.652632 -333.483151)
			(xy 231.693829 -333.518845) (xy 231.729526 -333.560038) (xy 231.758998 -333.605892) (xy 231.781644 -333.655474)
			(xy 231.797004 -333.707774) (xy 231.804764 -333.761727) (xy 231.804766 -333.816236) (xy 231.797012 -333.87019)
			(xy 231.781657 -333.922491) (xy 231.759016 -333.972075) (xy 231.729549 -334.017932) (xy 231.693855 -334.059129)
			(xy 231.652662 -334.094827) (xy 231.606808 -334.124298) (xy 231.557226 -334.146945) (xy 231.504926 -334.162304)
			(xy 231.450972 -334.170064) (xy 231.423718 -334.170528) (xy 231.395874 -334.170025) (xy 231.340786 -334.161859)
			(xy 231.31399 -334.154272) (xy 231.299572 -334.150513) (xy 231.269792 -334.150548) (xy 231.241287 -334.159169)
			(xy 231.21648 -334.175645) (xy 231.197478 -334.198575) (xy 231.185896 -334.22601) (xy 231.182718 -334.25562)
			(xy 231.184958 -334.27035) (xy 231.187953 -334.287656) (xy 231.191131 -334.322637) (xy 231.191308 -334.3402)
			(xy 231.190822 -334.367451) (xy 231.183066 -334.421399) (xy 231.167711 -334.473694) (xy 231.145069 -334.523271)
			(xy 231.115603 -334.569121) (xy 231.079912 -334.610312) (xy 231.038721 -334.646003) (xy 230.992871 -334.675469)
			(xy 230.943294 -334.698111) (xy 230.890999 -334.713466) (xy 230.837051 -334.721222) (xy 230.782549 -334.721222)
			(xy 230.728601 -334.713466) (xy 230.676306 -334.698111) (xy 230.626729 -334.675469) (xy 230.580879 -334.646003)
			(xy 230.539688 -334.610312) (xy 230.503997 -334.569121) (xy 230.474531 -334.523271) (xy 230.451889 -334.473694)
			(xy 230.436534 -334.421399) (xy 230.428778 -334.367451) (xy 225.511899 -334.367451) (xy 225.508214 -334.369017)
			(xy 225.454257 -334.383123) (xy 225.39882 -334.389223) (xy 225.343086 -334.387186) (xy 225.288243 -334.377056)
			(xy 225.235459 -334.359049) (xy 225.185859 -334.333548) (xy 225.140501 -334.301097) (xy 225.100352 -334.262388)
			(xy 225.066266 -334.218245) (xy 225.03897 -334.16961) (xy 225.019047 -334.117519) (xy 225.006921 -334.063082)
			(xy 225.00285 -334.00746) (xy 184.482416 -334.00746) (xy 187.005601 -335.467706) (xy 239.44656 -335.467706)
			(xy 239.450631 -335.412084) (xy 239.462757 -335.357647) (xy 239.48268 -335.305556) (xy 239.509976 -335.256921)
			(xy 239.544062 -335.212778) (xy 239.584211 -335.174069) (xy 239.629569 -335.141618) (xy 239.679169 -335.116117)
			(xy 239.731953 -335.09811) (xy 239.786796 -335.08798) (xy 239.84253 -335.085943) (xy 239.897967 -335.092043)
			(xy 239.951924 -335.106149) (xy 240.003253 -335.127961) (xy 240.050859 -335.157015) (xy 240.093727 -335.19269)
			(xy 240.130944 -335.234227) (xy 240.161717 -335.28074) (xy 240.185389 -335.331237) (xy 240.201457 -335.384644)
			(xy 240.209577 -335.43982) (xy 240.210086 -335.467706) (xy 240.210007 -335.472024) (xy 251.205236 -335.472024)
			(xy 251.209307 -335.416402) (xy 251.221433 -335.361965) (xy 251.241356 -335.309874) (xy 251.268652 -335.261239)
			(xy 251.302738 -335.217096) (xy 251.342887 -335.178387) (xy 251.388245 -335.145936) (xy 251.437845 -335.120435)
			(xy 251.490629 -335.102428) (xy 251.545472 -335.092298) (xy 251.601206 -335.090261) (xy 251.656643 -335.096361)
			(xy 251.7106 -335.110467) (xy 251.761929 -335.132279) (xy 251.809535 -335.161333) (xy 251.852403 -335.197008)
			(xy 251.88962 -335.238545) (xy 251.920393 -335.285058) (xy 251.944065 -335.335555) (xy 251.960133 -335.388962)
			(xy 251.968253 -335.444138) (xy 251.968762 -335.472024) (xy 251.968253 -335.49991) (xy 251.960133 -335.555086)
			(xy 251.944065 -335.608493) (xy 251.920393 -335.65899) (xy 251.88962 -335.705503) (xy 251.852403 -335.74704)
			(xy 251.809535 -335.782715) (xy 251.761929 -335.811769) (xy 251.7106 -335.833581) (xy 251.656643 -335.847687)
			(xy 251.601206 -335.853787) (xy 251.545472 -335.85175) (xy 251.490629 -335.84162) (xy 251.437845 -335.823613)
			(xy 251.388245 -335.798112) (xy 251.342887 -335.765661) (xy 251.302738 -335.726952) (xy 251.268652 -335.682809)
			(xy 251.241356 -335.634174) (xy 251.221433 -335.582083) (xy 251.209307 -335.527646) (xy 251.205236 -335.472024)
			(xy 240.210007 -335.472024) (xy 240.209577 -335.495592) (xy 240.201457 -335.550768) (xy 240.185389 -335.604175)
			(xy 240.161717 -335.654672) (xy 240.130944 -335.701185) (xy 240.093727 -335.742722) (xy 240.050859 -335.778397)
			(xy 240.003253 -335.807451) (xy 239.951924 -335.829263) (xy 239.897967 -335.843369) (xy 239.84253 -335.849469)
			(xy 239.786796 -335.847432) (xy 239.731953 -335.837302) (xy 239.679169 -335.819295) (xy 239.629569 -335.793794)
			(xy 239.584211 -335.761343) (xy 239.544062 -335.722634) (xy 239.509976 -335.678491) (xy 239.48268 -335.629856)
			(xy 239.462757 -335.577765) (xy 239.450631 -335.523328) (xy 239.44656 -335.467706) (xy 187.005601 -335.467706)
			(xy 190.11295 -337.266026) (xy 234.403392 -337.266026) (xy 234.403392 -336.402426) (xy 234.403882 -336.372458)
			(xy 234.411705 -336.313036) (xy 234.427218 -336.255143) (xy 234.450154 -336.19977) (xy 234.480121 -336.147864)
			(xy 234.516608 -336.100314) (xy 234.558988 -336.057934) (xy 234.606538 -336.021447) (xy 234.658444 -335.99148)
			(xy 234.713817 -335.968544) (xy 234.77171 -335.953031) (xy 234.831132 -335.945208) (xy 234.891068 -335.945208)
			(xy 234.95049 -335.953031) (xy 235.008383 -335.968544) (xy 235.063756 -335.99148) (xy 235.115662 -336.021447)
			(xy 235.163212 -336.057934) (xy 235.205592 -336.100314) (xy 235.242079 -336.147864) (xy 235.272046 -336.19977)
			(xy 235.294982 -336.255143) (xy 235.310495 -336.313036) (xy 235.318318 -336.372458) (xy 235.318808 -336.402426)
			(xy 235.318808 -336.55889) (xy 240.234214 -336.55889) (xy 240.238285 -336.503268) (xy 240.250411 -336.448831)
			(xy 240.270334 -336.39674) (xy 240.29763 -336.348105) (xy 240.331716 -336.303962) (xy 240.371865 -336.265253)
			(xy 240.417223 -336.232802) (xy 240.466823 -336.207301) (xy 240.519607 -336.189294) (xy 240.57445 -336.179164)
			(xy 240.630184 -336.177127) (xy 240.685621 -336.183227) (xy 240.739578 -336.197333) (xy 240.790907 -336.219145)
			(xy 240.838513 -336.248199) (xy 240.881381 -336.283874) (xy 240.918598 -336.325411) (xy 240.949371 -336.371924)
			(xy 240.973043 -336.422421) (xy 240.989111 -336.475828) (xy 240.997231 -336.531004) (xy 240.99774 -336.55889)
			(xy 240.997231 -336.586776) (xy 240.989111 -336.641952) (xy 240.973043 -336.695359) (xy 240.949371 -336.745856)
			(xy 240.918598 -336.792369) (xy 240.881381 -336.833906) (xy 240.838513 -336.869581) (xy 240.790907 -336.898635)
			(xy 240.739578 -336.920447) (xy 240.685621 -336.934553) (xy 240.630184 -336.940653) (xy 240.57445 -336.938616)
			(xy 240.519607 -336.928486) (xy 240.466823 -336.910479) (xy 240.417223 -336.884978) (xy 240.371865 -336.852527)
			(xy 240.331716 -336.813818) (xy 240.29763 -336.769675) (xy 240.270334 -336.72104) (xy 240.250411 -336.668949)
			(xy 240.238285 -336.614512) (xy 240.234214 -336.55889) (xy 235.318808 -336.55889) (xy 235.318808 -337.070192)
			(xy 251.234194 -337.070192) (xy 251.234658 -337.043878) (xy 251.241894 -336.991749) (xy 251.256214 -336.941107)
			(xy 251.277347 -336.892908) (xy 251.304893 -336.848064) (xy 251.338332 -336.807425) (xy 251.357384 -336.789268)
			(xy 251.364799 -336.781758) (xy 251.373316 -336.762469) (xy 251.373894 -336.75193) (xy 251.373894 -336.677254)
			(xy 251.373351 -336.666706) (xy 251.364826 -336.64741) (xy 251.357384 -336.639916) (xy 251.33834 -336.621749)
			(xy 251.304883 -336.581121) (xy 251.277322 -336.536283) (xy 251.256182 -336.488085) (xy 251.241862 -336.43744)
			(xy 251.234634 -336.385307) (xy 251.234194 -336.358992) (xy 251.23467 -336.33174) (xy 251.242428 -336.277792)
			(xy 251.257784 -336.225497) (xy 251.280426 -336.17592) (xy 251.309894 -336.130069) (xy 251.345586 -336.088879)
			(xy 251.386777 -336.053188) (xy 251.432629 -336.023722) (xy 251.482207 -336.001081) (xy 251.534502 -335.985726)
			(xy 251.58845 -335.97797) (xy 251.615702 -335.977484) (xy 251.642016 -335.977955) (xy 251.694144 -335.98519)
			(xy 251.744786 -335.999509) (xy 251.792985 -336.02064) (xy 251.837829 -336.048186) (xy 251.878469 -336.081623)
			(xy 251.896626 -336.100674) (xy 251.904139 -336.108085) (xy 251.923426 -336.116605) (xy 251.933964 -336.117184)
			(xy 252.00864 -336.117184) (xy 252.019188 -336.116641) (xy 252.038484 -336.108116) (xy 252.045978 -336.100674)
			(xy 252.065798 -336.079886) (xy 252.11057 -336.043911) (xy 252.160228 -336.015051) (xy 252.21365 -335.993958)
			(xy 252.269629 -335.981109) (xy 252.326902 -335.976794) (xy 252.384175 -335.981109) (xy 252.440154 -335.993958)
			(xy 252.493576 -336.015051) (xy 252.543234 -336.043911) (xy 252.588006 -336.079886) (xy 252.607826 -336.100674)
			(xy 252.615339 -336.108085) (xy 252.634626 -336.116605) (xy 252.645164 -336.117184) (xy 252.71984 -336.117184)
			(xy 252.730388 -336.116641) (xy 252.749684 -336.108116) (xy 252.757178 -336.100674) (xy 252.775346 -336.081631)
			(xy 252.815974 -336.048174) (xy 252.860812 -336.020614) (xy 252.90901 -335.999473) (xy 252.959655 -335.985153)
			(xy 253.011787 -335.977925) (xy 253.038102 -335.977484) (xy 253.065353 -335.977976) (xy 253.1193 -335.985732)
			(xy 253.171594 -336.001087) (xy 253.221171 -336.023728) (xy 253.267021 -336.053194) (xy 253.308211 -336.088885)
			(xy 253.343902 -336.130074) (xy 253.373369 -336.175924) (xy 253.39601 -336.2255) (xy 253.411366 -336.277794)
			(xy 253.419124 -336.331741) (xy 253.41961 -336.358992) (xy 253.419134 -336.385306) (xy 253.4119 -336.437434)
			(xy 253.397583 -336.488076) (xy 253.376452 -336.536275) (xy 253.348908 -336.581119) (xy 253.315471 -336.621759)
			(xy 253.29642 -336.639916) (xy 253.289012 -336.647432) (xy 253.280491 -336.666716) (xy 253.27991 -336.677254)
			(xy 253.27991 -336.75193) (xy 253.280461 -336.762477) (xy 253.28898 -336.781773) (xy 253.29642 -336.789268)
			(xy 253.315505 -336.807394) (xy 253.348959 -336.84803) (xy 253.376514 -336.892877) (xy 253.397647 -336.941083)
			(xy 253.411958 -336.991736) (xy 253.419175 -337.043874) (xy 253.41961 -337.070192) (xy 253.419137 -337.097445)
			(xy 253.411381 -337.151395) (xy 253.396026 -337.203693) (xy 253.373385 -337.253273) (xy 253.343918 -337.299126)
			(xy 253.308225 -337.340318) (xy 253.267034 -337.376012) (xy 253.221181 -337.40548) (xy 253.171602 -337.428123)
			(xy 253.119305 -337.443479) (xy 253.065355 -337.451237) (xy 253.038102 -337.4517) (xy 253.011788 -337.451231)
			(xy 252.95966 -337.443997) (xy 252.909017 -337.429678) (xy 252.860818 -337.408546) (xy 252.815974 -337.381)
			(xy 252.775335 -337.347561) (xy 252.757178 -337.32851) (xy 252.749665 -337.321098) (xy 252.730379 -337.312579)
			(xy 252.71984 -337.312) (xy 252.645164 -337.312) (xy 252.634617 -337.31255) (xy 252.615321 -337.321071)
			(xy 252.607826 -337.32851) (xy 252.588006 -337.349298) (xy 252.543234 -337.385273) (xy 252.493576 -337.414133)
			(xy 252.440154 -337.435226) (xy 252.384175 -337.448075) (xy 252.326902 -337.45239) (xy 252.269629 -337.448075)
			(xy 252.21365 -337.435226) (xy 252.160228 -337.414133) (xy 252.11057 -337.385273) (xy 252.065798 -337.349298)
			(xy 252.045978 -337.32851) (xy 252.038465 -337.321098) (xy 252.019179 -337.312579) (xy 252.00864 -337.312)
			(xy 251.933964 -337.312) (xy 251.923417 -337.31255) (xy 251.904121 -337.321071) (xy 251.896626 -337.32851)
			(xy 251.878453 -337.347548) (xy 251.837827 -337.381006) (xy 251.79299 -337.408567) (xy 251.744793 -337.429709)
			(xy 251.694148 -337.44403) (xy 251.642017 -337.451259) (xy 251.615702 -337.4517) (xy 251.588449 -337.451243)
			(xy 251.534497 -337.443486) (xy 251.482199 -337.42813) (xy 251.432618 -337.405487) (xy 251.386765 -337.376018)
			(xy 251.345572 -337.340324) (xy 251.309878 -337.299131) (xy 251.28041 -337.253277) (xy 251.257768 -337.203696)
			(xy 251.242413 -337.151397) (xy 251.234657 -337.097445) (xy 251.234194 -337.070192) (xy 235.318808 -337.070192)
			(xy 235.318808 -337.266026) (xy 235.318318 -337.295994) (xy 235.310495 -337.355416) (xy 235.294982 -337.413309)
			(xy 235.272046 -337.468682) (xy 235.242079 -337.520588) (xy 235.205592 -337.568138) (xy 235.163212 -337.610518)
			(xy 235.115662 -337.647005) (xy 235.063756 -337.676972) (xy 235.008383 -337.699908) (xy 234.95049 -337.715421)
			(xy 234.891068 -337.723244) (xy 234.831132 -337.723244) (xy 234.77171 -337.715421) (xy 234.713817 -337.699908)
			(xy 234.658444 -337.676972) (xy 234.606538 -337.647005) (xy 234.558988 -337.610518) (xy 234.516608 -337.568138)
			(xy 234.480121 -337.520588) (xy 234.450154 -337.468682) (xy 234.427218 -337.413309) (xy 234.411705 -337.355416)
			(xy 234.403882 -337.295994) (xy 234.403392 -337.266026) (xy 190.11295 -337.266026) (xy 192.029588 -338.375244)
			(xy 192.034586 -338.377732) (xy 192.045355 -338.380672) (xy 192.050924 -338.381086) (xy 195.687188 -338.381086)
			(xy 195.69726 -338.381506) (xy 195.715869 -338.389216) (xy 195.723256 -338.396072) (xy 196.170804 -338.84362)
			(xy 201.544174 -338.84362) (xy 201.544663 -338.817307) (xy 201.551895 -338.76518) (xy 201.56621 -338.714538)
			(xy 201.587339 -338.666339) (xy 201.61488 -338.621495) (xy 201.648315 -338.580854) (xy 201.667364 -338.562696)
			(xy 201.674764 -338.555173) (xy 201.683291 -338.535894) (xy 201.683874 -338.525358) (xy 201.683874 -338.450682)
			(xy 201.683322 -338.440135) (xy 201.674804 -338.420839) (xy 201.667364 -338.413344) (xy 201.648281 -338.395216)
			(xy 201.614828 -338.354579) (xy 201.587274 -338.309733) (xy 201.56614 -338.261527) (xy 201.551828 -338.210875)
			(xy 201.544609 -338.158738) (xy 201.544174 -338.13242) (xy 201.54466 -338.105169) (xy 201.552416 -338.051221)
			(xy 201.567771 -337.998926) (xy 201.590413 -337.949349) (xy 201.619879 -337.903499) (xy 201.65557 -337.862308)
			(xy 201.696761 -337.826617) (xy 201.742611 -337.797151) (xy 201.792188 -337.774509) (xy 201.844483 -337.759154)
			(xy 201.898431 -337.751398) (xy 201.952933 -337.751398) (xy 202.006881 -337.759154) (xy 202.059176 -337.774509)
			(xy 202.108753 -337.797151) (xy 202.154603 -337.826617) (xy 202.195794 -337.862308) (xy 202.231485 -337.903499)
			(xy 202.260951 -337.949349) (xy 202.283593 -337.998926) (xy 202.298948 -338.051221) (xy 202.306704 -338.105169)
			(xy 202.30719 -338.13242) (xy 202.306739 -338.158735) (xy 202.299501 -338.210864) (xy 202.285179 -338.261507)
			(xy 202.264044 -338.309706) (xy 202.236495 -338.354549) (xy 202.203053 -338.395188) (xy 202.184 -338.413344)
			(xy 202.176577 -338.420847) (xy 202.168065 -338.440141) (xy 202.16749 -338.450682) (xy 202.16749 -338.525358)
			(xy 202.168031 -338.535906) (xy 202.176558 -338.555202) (xy 202.184 -338.562696) (xy 202.203047 -338.580861)
			(xy 202.236505 -338.621488) (xy 202.264065 -338.666327) (xy 202.285205 -338.714526) (xy 202.299524 -338.765172)
			(xy 202.30675 -338.817304) (xy 202.30719 -338.84362) (xy 202.306704 -338.870871) (xy 202.298948 -338.924819)
			(xy 202.283593 -338.977114) (xy 202.260951 -339.026691) (xy 202.231485 -339.072541) (xy 202.195794 -339.113732)
			(xy 202.154603 -339.149423) (xy 202.108753 -339.178889) (xy 202.059176 -339.201531) (xy 202.006881 -339.216886)
			(xy 201.952933 -339.224642) (xy 201.898431 -339.224642) (xy 201.844483 -339.216886) (xy 201.792188 -339.201531)
			(xy 201.742611 -339.178889) (xy 201.696761 -339.149423) (xy 201.65557 -339.113732) (xy 201.619879 -339.072541)
			(xy 201.590413 -339.026691) (xy 201.567771 -338.977114) (xy 201.552416 -338.924819) (xy 201.54466 -338.870871)
			(xy 201.544174 -338.84362) (xy 196.170804 -338.84362) (xy 197.020942 -339.693758) (xy 266.115798 -339.693758)
			(xy 266.119869 -339.638136) (xy 266.131995 -339.583699) (xy 266.151918 -339.531608) (xy 266.179214 -339.482973)
			(xy 266.2133 -339.43883) (xy 266.253449 -339.400121) (xy 266.298807 -339.36767) (xy 266.348407 -339.342169)
			(xy 266.401191 -339.324162) (xy 266.456034 -339.314032) (xy 266.511768 -339.311995) (xy 266.567205 -339.318095)
			(xy 266.621162 -339.332201) (xy 266.672491 -339.354013) (xy 266.720097 -339.383067) (xy 266.762965 -339.418742)
			(xy 266.800182 -339.460279) (xy 266.830955 -339.506792) (xy 266.854627 -339.557289) (xy 266.870695 -339.610696)
			(xy 266.878815 -339.665872) (xy 266.879324 -339.693758) (xy 266.878815 -339.721644) (xy 266.870695 -339.77682)
			(xy 266.854627 -339.830227) (xy 266.830955 -339.880724) (xy 266.800182 -339.927237) (xy 266.762965 -339.968774)
			(xy 266.720097 -340.004449) (xy 266.672491 -340.033503) (xy 266.621162 -340.055315) (xy 266.567205 -340.069421)
			(xy 266.511768 -340.075521) (xy 266.456034 -340.073484) (xy 266.401191 -340.063354) (xy 266.348407 -340.045347)
			(xy 266.298807 -340.019846) (xy 266.253449 -339.987395) (xy 266.2133 -339.948686) (xy 266.179214 -339.904543)
			(xy 266.151918 -339.855908) (xy 266.131995 -339.803817) (xy 266.119869 -339.74938) (xy 266.115798 -339.693758)
			(xy 197.020942 -339.693758) (xy 198.42353 -341.096346) (xy 198.430377 -341.103744) (xy 198.438106 -341.122343)
			(xy 198.438516 -341.132414) (xy 198.438516 -341.799448) (xy 231.047318 -341.799448) (xy 231.047318 -341.744952)
			(xy 231.055074 -341.691011) (xy 231.070427 -341.638723) (xy 231.093065 -341.589151) (xy 231.122527 -341.543306)
			(xy 231.158213 -341.502121) (xy 231.199398 -341.466433) (xy 231.245242 -341.436969) (xy 231.294813 -341.41433)
			(xy 231.347101 -341.398976) (xy 231.401042 -341.391219) (xy 231.42829 -341.390732) (xy 231.456426 -341.391179)
			(xy 231.51209 -341.399433) (xy 231.565936 -341.415778) (xy 231.616795 -341.439859) (xy 231.663563 -341.471153)
			(xy 231.705224 -341.508981) (xy 231.723438 -341.530432) (xy 231.730819 -341.538715) (xy 231.750723 -341.548461)
			(xy 231.761792 -341.549228) (xy 231.850438 -341.550752) (xy 231.870758 -341.541862) (xy 231.878124 -341.53348)
			(xy 231.896316 -341.513539) (xy 231.937357 -341.478478) (xy 231.982928 -341.449551) (xy 232.032122 -341.427334)
			(xy 232.083955 -341.412271) (xy 232.137393 -341.404662) (xy 232.164382 -341.404194) (xy 232.191636 -341.404652)
			(xy 232.245589 -341.412407) (xy 232.297889 -341.427762) (xy 232.347472 -341.450403) (xy 232.393328 -341.479871)
			(xy 232.434523 -341.515565) (xy 232.470218 -341.556758) (xy 232.499688 -341.602612) (xy 232.522332 -341.652194)
			(xy 232.537689 -341.704493) (xy 232.545447 -341.758446) (xy 232.545447 -341.812954) (xy 232.537689 -341.866907)
			(xy 232.522332 -341.919206) (xy 232.499688 -341.968788) (xy 232.470218 -342.014642) (xy 232.434523 -342.055835)
			(xy 232.429691 -342.060022) (xy 255.91262 -342.060022) (xy 255.91262 -341.196422) (xy 255.91311 -341.166438)
			(xy 255.920938 -341.106982) (xy 255.936459 -341.049057) (xy 255.959408 -340.993653) (xy 255.989392 -340.941719)
			(xy 256.025898 -340.894143) (xy 256.068303 -340.851738) (xy 256.115879 -340.815232) (xy 256.167813 -340.785248)
			(xy 256.223217 -340.762299) (xy 256.281142 -340.746778) (xy 256.340598 -340.73895) (xy 256.400566 -340.73895)
			(xy 256.460022 -340.746778) (xy 256.517947 -340.762299) (xy 256.573351 -340.785248) (xy 256.625285 -340.815232)
			(xy 256.672861 -340.851738) (xy 256.715266 -340.894143) (xy 256.751772 -340.941719) (xy 256.781756 -340.993653)
			(xy 256.804705 -341.049057) (xy 256.820226 -341.106982) (xy 256.828054 -341.166438) (xy 256.828544 -341.196422)
			(xy 256.828544 -342.060022) (xy 256.828054 -342.090006) (xy 256.820226 -342.149462) (xy 256.804705 -342.207387)
			(xy 256.781756 -342.262791) (xy 256.751772 -342.314725) (xy 256.715266 -342.362301) (xy 256.672861 -342.404706)
			(xy 256.625285 -342.441212) (xy 256.573351 -342.471196) (xy 256.517947 -342.494145) (xy 256.460022 -342.509666)
			(xy 256.400566 -342.517494) (xy 256.340598 -342.517494) (xy 256.281142 -342.509666) (xy 256.223217 -342.494145)
			(xy 256.167813 -342.471196) (xy 256.115879 -342.441212) (xy 256.068303 -342.404706) (xy 256.025898 -342.362301)
			(xy 255.989392 -342.314725) (xy 255.959408 -342.262791) (xy 255.936459 -342.207387) (xy 255.920938 -342.149462)
			(xy 255.91311 -342.090006) (xy 255.91262 -342.060022) (xy 232.429691 -342.060022) (xy 232.393328 -342.091529)
			(xy 232.347472 -342.120997) (xy 232.297889 -342.143638) (xy 232.245589 -342.158993) (xy 232.191636 -342.166748)
			(xy 232.164382 -342.16721) (xy 232.136248 -342.166698) (xy 232.080588 -342.158455) (xy 232.026744 -342.142122)
			(xy 231.975885 -342.118053) (xy 231.929115 -342.086771) (xy 231.887451 -342.048955) (xy 231.869234 -342.02751)
			(xy 231.861858 -342.019221) (xy 231.84195 -342.009477) (xy 231.83088 -342.008714) (xy 231.742234 -342.00719)
			(xy 231.721914 -342.01608) (xy 231.714548 -342.024462) (xy 231.696358 -342.044406) (xy 231.655318 -342.079468)
			(xy 231.609747 -342.108397) (xy 231.560553 -342.130614) (xy 231.508719 -342.145676) (xy 231.455279 -342.153282)
			(xy 231.42829 -342.153748) (xy 231.401042 -342.153181) (xy 231.347101 -342.145424) (xy 231.294813 -342.13007)
			(xy 231.245242 -342.107431) (xy 231.199398 -342.077967) (xy 231.158213 -342.042279) (xy 231.122527 -342.001094)
			(xy 231.093065 -341.955249) (xy 231.070427 -341.905677) (xy 231.055074 -341.853389) (xy 231.047318 -341.799448)
			(xy 198.438516 -341.799448) (xy 198.438516 -345.42857) (xy 229.27894 -345.42857) (xy 229.283011 -345.372948)
			(xy 229.295137 -345.318511) (xy 229.31506 -345.26642) (xy 229.342356 -345.217785) (xy 229.376442 -345.173642)
			(xy 229.416591 -345.134933) (xy 229.461949 -345.102482) (xy 229.511549 -345.076981) (xy 229.564333 -345.058974)
			(xy 229.619176 -345.048844) (xy 229.67491 -345.046807) (xy 229.730347 -345.052907) (xy 229.784304 -345.067013)
			(xy 229.835633 -345.088825) (xy 229.883239 -345.117879) (xy 229.926107 -345.153554) (xy 229.963324 -345.195091)
			(xy 229.994097 -345.241604) (xy 230.017769 -345.292101) (xy 230.033837 -345.345508) (xy 230.041957 -345.400684)
			(xy 230.042466 -345.42857) (xy 230.041957 -345.456456) (xy 230.033837 -345.511632) (xy 230.017769 -345.565039)
			(xy 229.994097 -345.615536) (xy 229.963324 -345.662049) (xy 229.926107 -345.703586) (xy 229.883239 -345.739261)
			(xy 229.835633 -345.768315) (xy 229.784304 -345.790127) (xy 229.730347 -345.804233) (xy 229.67491 -345.810333)
			(xy 229.619176 -345.808296) (xy 229.564333 -345.798166) (xy 229.511549 -345.780159) (xy 229.461949 -345.754658)
			(xy 229.416591 -345.722207) (xy 229.376442 -345.683498) (xy 229.342356 -345.639355) (xy 229.31506 -345.59072)
			(xy 229.295137 -345.538629) (xy 229.283011 -345.484192) (xy 229.27894 -345.42857) (xy 198.438516 -345.42857)
			(xy 198.438516 -345.832938) (xy 235.125004 -345.832938) (xy 235.129075 -345.777316) (xy 235.141201 -345.722879)
			(xy 235.161124 -345.670788) (xy 235.18842 -345.622153) (xy 235.222506 -345.57801) (xy 235.262655 -345.539301)
			(xy 235.308013 -345.50685) (xy 235.357613 -345.481349) (xy 235.410397 -345.463342) (xy 235.46524 -345.453212)
			(xy 235.520974 -345.451175) (xy 235.576411 -345.457275) (xy 235.630368 -345.471381) (xy 235.681697 -345.493193)
			(xy 235.729303 -345.522247) (xy 235.772171 -345.557922) (xy 235.809388 -345.599459) (xy 235.840161 -345.645972)
			(xy 235.863833 -345.696469) (xy 235.879901 -345.749876) (xy 235.888021 -345.805052) (xy 235.88853 -345.832938)
			(xy 235.888021 -345.860824) (xy 235.879901 -345.916) (xy 235.87226 -345.941396) (xy 250.769118 -345.941396)
			(xy 250.773189 -345.885774) (xy 250.785315 -345.831337) (xy 250.805238 -345.779246) (xy 250.832534 -345.730611)
			(xy 250.86662 -345.686468) (xy 250.906769 -345.647759) (xy 250.952127 -345.615308) (xy 251.001727 -345.589807)
			(xy 251.054511 -345.5718) (xy 251.109354 -345.56167) (xy 251.165088 -345.559633) (xy 251.220525 -345.565733)
			(xy 251.274482 -345.579839) (xy 251.325811 -345.601651) (xy 251.373417 -345.630705) (xy 251.40125 -345.653868)
			(xy 257.171696 -345.653868) (xy 257.175767 -345.598246) (xy 257.187893 -345.543809) (xy 257.207816 -345.491718)
			(xy 257.235112 -345.443083) (xy 257.269198 -345.39894) (xy 257.309347 -345.360231) (xy 257.354705 -345.32778)
			(xy 257.404305 -345.302279) (xy 257.457089 -345.284272) (xy 257.511932 -345.274142) (xy 257.567666 -345.272105)
			(xy 257.623103 -345.278205) (xy 257.67706 -345.292311) (xy 257.728389 -345.314123) (xy 257.775995 -345.343177)
			(xy 257.818863 -345.378852) (xy 257.85608 -345.420389) (xy 257.886853 -345.466902) (xy 257.910525 -345.517399)
			(xy 257.926593 -345.570806) (xy 257.934713 -345.625982) (xy 257.935222 -345.653868) (xy 257.934713 -345.681754)
			(xy 257.926593 -345.73693) (xy 257.910525 -345.790337) (xy 257.886853 -345.840834) (xy 257.85608 -345.887347)
			(xy 257.818863 -345.928884) (xy 257.775995 -345.964559) (xy 257.728389 -345.993613) (xy 257.67706 -346.015425)
			(xy 257.623103 -346.029531) (xy 257.567666 -346.035631) (xy 257.511932 -346.033594) (xy 257.457089 -346.023464)
			(xy 257.404305 -346.005457) (xy 257.354705 -345.979956) (xy 257.309347 -345.947505) (xy 257.269198 -345.908796)
			(xy 257.235112 -345.864653) (xy 257.207816 -345.816018) (xy 257.187893 -345.763927) (xy 257.175767 -345.70949)
			(xy 257.171696 -345.653868) (xy 251.40125 -345.653868) (xy 251.416285 -345.66638) (xy 251.453502 -345.707917)
			(xy 251.484275 -345.75443) (xy 251.507947 -345.804927) (xy 251.524015 -345.858334) (xy 251.532135 -345.91351)
			(xy 251.532644 -345.941396) (xy 251.532135 -345.969282) (xy 251.524015 -346.024458) (xy 251.507947 -346.077865)
			(xy 251.484275 -346.128362) (xy 251.453502 -346.174875) (xy 251.416285 -346.216412) (xy 251.373417 -346.252087)
			(xy 251.325811 -346.281141) (xy 251.274482 -346.302953) (xy 251.220525 -346.317059) (xy 251.165088 -346.323159)
			(xy 251.109354 -346.321122) (xy 251.054511 -346.310992) (xy 251.001727 -346.292985) (xy 250.952127 -346.267484)
			(xy 250.906769 -346.235033) (xy 250.86662 -346.196324) (xy 250.832534 -346.152181) (xy 250.805238 -346.103546)
			(xy 250.785315 -346.051455) (xy 250.773189 -345.997018) (xy 250.769118 -345.941396) (xy 235.87226 -345.941396)
			(xy 235.863833 -345.969407) (xy 235.840161 -346.019904) (xy 235.809388 -346.066417) (xy 235.772171 -346.107954)
			(xy 235.729303 -346.143629) (xy 235.681697 -346.172683) (xy 235.630368 -346.194495) (xy 235.576411 -346.208601)
			(xy 235.520974 -346.214701) (xy 235.46524 -346.212664) (xy 235.410397 -346.202534) (xy 235.357613 -346.184527)
			(xy 235.308013 -346.159026) (xy 235.262655 -346.126575) (xy 235.222506 -346.087866) (xy 235.18842 -346.043723)
			(xy 235.161124 -345.995088) (xy 235.141201 -345.942997) (xy 235.129075 -345.88856) (xy 235.125004 -345.832938)
			(xy 198.438516 -345.832938) (xy 198.438516 -346.330016) (xy 198.438091 -346.340085) (xy 198.430374 -346.358687)
			(xy 198.42353 -346.366084) (xy 197.92061 -346.869004) (xy 197.913212 -346.875852) (xy 197.894614 -346.883589)
			(xy 197.884542 -346.88399) (xy 196.672708 -346.88399) (xy 196.667831 -346.88409) (xy 196.658245 -346.885887)
			(xy 196.653658 -346.887546) (xy 196.644514 -346.891356) (xy 196.617914 -346.917956) (xy 245.50903 -346.917956)
			(xy 245.50903 -346.83326) (xy 245.517081 -346.748946) (xy 245.53311 -346.66578) (xy 245.556971 -346.584513)
			(xy 245.58845 -346.505883) (xy 245.627261 -346.430602) (xy 245.673051 -346.35935) (xy 245.725407 -346.292774)
			(xy 245.783855 -346.231476) (xy 245.847865 -346.176011) (xy 245.916857 -346.126882) (xy 245.990207 -346.084533)
			(xy 246.06725 -346.049349) (xy 246.147289 -346.021647) (xy 246.229598 -346.001679) (xy 246.313433 -345.989626)
			(xy 246.398034 -345.985596) (xy 246.482635 -345.989626) (xy 246.56647 -346.001679) (xy 246.648779 -346.021647)
			(xy 246.728818 -346.049349) (xy 246.805861 -346.084533) (xy 246.879211 -346.126882) (xy 246.948203 -346.176011)
			(xy 247.012213 -346.231476) (xy 247.070661 -346.292774) (xy 247.123017 -346.35935) (xy 247.168807 -346.430602)
			(xy 247.171556 -346.435934) (xy 259.550914 -346.435934) (xy 259.554985 -346.380312) (xy 259.567111 -346.325875)
			(xy 259.587034 -346.273784) (xy 259.61433 -346.225149) (xy 259.648416 -346.181006) (xy 259.688565 -346.142297)
			(xy 259.733923 -346.109846) (xy 259.783523 -346.084345) (xy 259.836307 -346.066338) (xy 259.89115 -346.056208)
			(xy 259.946884 -346.054171) (xy 260.002321 -346.060271) (xy 260.056278 -346.074377) (xy 260.107607 -346.096189)
			(xy 260.155213 -346.125243) (xy 260.198081 -346.160918) (xy 260.235298 -346.202455) (xy 260.266071 -346.248968)
			(xy 260.289743 -346.299465) (xy 260.305811 -346.352872) (xy 260.313931 -346.408048) (xy 260.31444 -346.435934)
			(xy 260.313931 -346.46382) (xy 260.305811 -346.518996) (xy 260.289743 -346.572403) (xy 260.266071 -346.6229)
			(xy 260.235298 -346.669413) (xy 260.198081 -346.71095) (xy 260.155213 -346.746625) (xy 260.107607 -346.775679)
			(xy 260.056278 -346.797491) (xy 260.002321 -346.811597) (xy 259.946884 -346.817697) (xy 259.89115 -346.81566)
			(xy 259.836307 -346.80553) (xy 259.783523 -346.787523) (xy 259.733923 -346.762022) (xy 259.688565 -346.729571)
			(xy 259.648416 -346.690862) (xy 259.61433 -346.646719) (xy 259.587034 -346.598084) (xy 259.567111 -346.545993)
			(xy 259.554985 -346.491556) (xy 259.550914 -346.435934) (xy 247.171556 -346.435934) (xy 247.207618 -346.505883)
			(xy 247.239097 -346.584513) (xy 247.262958 -346.66578) (xy 247.278987 -346.748946) (xy 247.287038 -346.83326)
			(xy 247.287542 -346.875608) (xy 247.287038 -346.917956) (xy 247.278987 -347.00227) (xy 247.262958 -347.085436)
			(xy 247.239097 -347.166703) (xy 247.207618 -347.245333) (xy 247.168807 -347.320614) (xy 247.123017 -347.391866)
			(xy 247.070661 -347.458442) (xy 247.012213 -347.51974) (xy 246.948203 -347.575205) (xy 246.879211 -347.624334)
			(xy 246.805861 -347.666683) (xy 246.728818 -347.701867) (xy 246.648779 -347.729569) (xy 246.56647 -347.749537)
			(xy 246.482635 -347.76159) (xy 246.398034 -347.765621) (xy 246.313433 -347.76159) (xy 246.229598 -347.749537)
			(xy 246.147289 -347.729569) (xy 246.06725 -347.701867) (xy 245.990207 -347.666683) (xy 245.916857 -347.624334)
			(xy 245.847865 -347.575205) (xy 245.783855 -347.51974) (xy 245.725407 -347.458442) (xy 245.673051 -347.391866)
			(xy 245.627261 -347.320614) (xy 245.58845 -347.245333) (xy 245.556971 -347.166703) (xy 245.53311 -347.085436)
			(xy 245.517081 -347.00227) (xy 245.50903 -346.917956) (xy 196.617914 -346.917956) (xy 195.75907 -347.7768)
			(xy 253.262382 -347.7768) (xy 253.266453 -347.721178) (xy 253.278579 -347.666741) (xy 253.298502 -347.61465)
			(xy 253.325798 -347.566015) (xy 253.359884 -347.521872) (xy 253.400033 -347.483163) (xy 253.445391 -347.450712)
			(xy 253.494991 -347.425211) (xy 253.547775 -347.407204) (xy 253.602618 -347.397074) (xy 253.658352 -347.395037)
			(xy 253.713789 -347.401137) (xy 253.767746 -347.415243) (xy 253.819075 -347.437055) (xy 253.866681 -347.466109)
			(xy 253.909549 -347.501784) (xy 253.946766 -347.543321) (xy 253.977539 -347.589834) (xy 254.001211 -347.640331)
			(xy 254.014376 -347.68409) (xy 255.611882 -347.68409) (xy 255.615953 -347.628468) (xy 255.628079 -347.574031)
			(xy 255.648002 -347.52194) (xy 255.675298 -347.473305) (xy 255.709384 -347.429162) (xy 255.749533 -347.390453)
			(xy 255.794891 -347.358002) (xy 255.844491 -347.332501) (xy 255.897275 -347.314494) (xy 255.952118 -347.304364)
			(xy 256.007852 -347.302327) (xy 256.063289 -347.308427) (xy 256.117246 -347.322533) (xy 256.168575 -347.344345)
			(xy 256.216181 -347.373399) (xy 256.259049 -347.409074) (xy 256.296266 -347.450611) (xy 256.327039 -347.497124)
			(xy 256.350711 -347.547621) (xy 256.366779 -347.601028) (xy 256.374899 -347.656204) (xy 256.375408 -347.68409)
			(xy 256.374899 -347.711976) (xy 256.366779 -347.767152) (xy 256.350711 -347.820559) (xy 256.327039 -347.871056)
			(xy 256.296266 -347.917569) (xy 256.259049 -347.959106) (xy 256.216181 -347.994781) (xy 256.168575 -348.023835)
			(xy 256.117246 -348.045647) (xy 256.063289 -348.059753) (xy 256.007852 -348.065853) (xy 255.952118 -348.063816)
			(xy 255.897275 -348.053686) (xy 255.844491 -348.035679) (xy 255.794891 -348.010178) (xy 255.749533 -347.977727)
			(xy 255.709384 -347.939018) (xy 255.675298 -347.894875) (xy 255.648002 -347.84624) (xy 255.628079 -347.794149)
			(xy 255.615953 -347.739712) (xy 255.611882 -347.68409) (xy 254.014376 -347.68409) (xy 254.017279 -347.693738)
			(xy 254.025399 -347.748914) (xy 254.025908 -347.7768) (xy 254.025399 -347.804686) (xy 254.017279 -347.859862)
			(xy 254.001211 -347.913269) (xy 253.977539 -347.963766) (xy 253.946766 -348.010279) (xy 253.909549 -348.051816)
			(xy 253.866681 -348.087491) (xy 253.819075 -348.116545) (xy 253.767746 -348.138357) (xy 253.713789 -348.152463)
			(xy 253.658352 -348.158563) (xy 253.602618 -348.156526) (xy 253.547775 -348.146396) (xy 253.494991 -348.128389)
			(xy 253.445391 -348.102888) (xy 253.400033 -348.070437) (xy 253.359884 -348.031728) (xy 253.325798 -347.987585)
			(xy 253.298502 -347.93895) (xy 253.278579 -347.886859) (xy 253.266453 -347.832422) (xy 253.262382 -347.7768)
			(xy 195.75907 -347.7768) (xy 195.695062 -347.840808) (xy 195.692355 -347.843658) (xy 195.687761 -347.850036)
			(xy 195.685918 -347.853508) (xy 195.68333 -347.858934) (xy 195.680498 -347.870613) (xy 195.68033 -347.876622)
			(xy 195.68033 -348.475554) (xy 236.142528 -348.475554) (xy 236.146599 -348.419932) (xy 236.158725 -348.365495)
			(xy 236.178648 -348.313404) (xy 236.205944 -348.264769) (xy 236.24003 -348.220626) (xy 236.280179 -348.181917)
			(xy 236.325537 -348.149466) (xy 236.375137 -348.123965) (xy 236.427921 -348.105958) (xy 236.482764 -348.095828)
			(xy 236.538498 -348.093791) (xy 236.593935 -348.099891) (xy 236.647892 -348.113997) (xy 236.699221 -348.135809)
			(xy 236.746827 -348.164863) (xy 236.789695 -348.200538) (xy 236.826912 -348.242075) (xy 236.857685 -348.288588)
			(xy 236.881357 -348.339085) (xy 236.897425 -348.392492) (xy 236.902555 -348.427353) (xy 240.622271 -348.427353)
			(xy 240.622271 -348.372847) (xy 240.630029 -348.318896) (xy 240.645386 -348.266598) (xy 240.668029 -348.217018)
			(xy 240.697499 -348.171166) (xy 240.733194 -348.129974) (xy 240.774388 -348.094282) (xy 240.820243 -348.064816)
			(xy 240.869824 -348.042176) (xy 240.922123 -348.026823) (xy 240.976075 -348.019069) (xy 241.003328 -348.018608)
			(xy 241.032243 -348.019175) (xy 241.089412 -348.027893) (xy 241.14461 -348.045141) (xy 241.196572 -348.070524)
			(xy 241.244107 -348.103459) (xy 241.286126 -348.143192) (xy 241.304318 -348.165674) (xy 241.311914 -348.174492)
			(xy 241.332824 -348.184666) (xy 241.34445 -348.185232) (xy 241.424206 -348.185232) (xy 241.43584 -348.184706)
			(xy 241.456751 -348.17451) (xy 241.464338 -348.165674) (xy 241.482501 -348.143167) (xy 241.524527 -348.103434)
			(xy 241.572068 -348.070499) (xy 241.624035 -348.045115) (xy 241.679237 -348.027863) (xy 241.73641 -348.01914)
			(xy 241.765328 -348.018608) (xy 241.792579 -348.019064) (xy 241.846526 -348.026824) (xy 241.89882 -348.042182)
			(xy 241.948395 -348.064826) (xy 241.994244 -348.094294) (xy 242.035433 -348.129987) (xy 242.071123 -348.171178)
			(xy 242.100588 -348.217029) (xy 242.123228 -348.266607) (xy 242.138582 -348.318901) (xy 242.146338 -348.372849)
			(xy 242.146338 -348.427351) (xy 242.138582 -348.481299) (xy 242.123228 -348.533593) (xy 242.100588 -348.583171)
			(xy 242.071123 -348.629022) (xy 242.035433 -348.670213) (xy 241.994244 -348.705906) (xy 241.948395 -348.735374)
			(xy 241.89882 -348.758018) (xy 241.846526 -348.773376) (xy 241.792579 -348.781136) (xy 241.765328 -348.781624)
			(xy 241.73641 -348.781115) (xy 241.679237 -348.772388) (xy 241.624037 -348.75513) (xy 241.572075 -348.729737)
			(xy 241.524541 -348.69679) (xy 241.482527 -348.657046) (xy 241.464338 -348.634558) (xy 241.456712 -348.625771)
			(xy 241.435825 -348.615578) (xy 241.424206 -348.615) (xy 241.34445 -348.615) (xy 241.332816 -348.615525)
			(xy 241.311907 -348.625724) (xy 241.304318 -348.634558) (xy 241.286106 -348.657024) (xy 241.244092 -348.696762)
			(xy 241.196562 -348.729705) (xy 241.144604 -348.755096) (xy 241.08941 -348.772356) (xy 241.032243 -348.781088)
			(xy 241.003328 -348.781624) (xy 240.976075 -348.781131) (xy 240.922123 -348.773377) (xy 240.869824 -348.758024)
			(xy 240.820243 -348.735384) (xy 240.774388 -348.705918) (xy 240.733194 -348.670226) (xy 240.697499 -348.629034)
			(xy 240.668029 -348.583182) (xy 240.645386 -348.533602) (xy 240.630029 -348.481304) (xy 240.622271 -348.427353)
			(xy 236.902555 -348.427353) (xy 236.905545 -348.447668) (xy 236.906054 -348.475554) (xy 236.905545 -348.50344)
			(xy 236.897425 -348.558616) (xy 236.881357 -348.612023) (xy 236.857685 -348.66252) (xy 236.826912 -348.709033)
			(xy 236.789695 -348.75057) (xy 236.746827 -348.786245) (xy 236.699221 -348.815299) (xy 236.647892 -348.837111)
			(xy 236.593935 -348.851217) (xy 236.538498 -348.857317) (xy 236.482764 -348.85528) (xy 236.427921 -348.84515)
			(xy 236.375137 -348.827143) (xy 236.325537 -348.801642) (xy 236.280179 -348.769191) (xy 236.24003 -348.730482)
			(xy 236.205944 -348.686339) (xy 236.178648 -348.637704) (xy 236.158725 -348.585613) (xy 236.146599 -348.531176)
			(xy 236.142528 -348.475554) (xy 195.68033 -348.475554) (xy 195.68033 -349.302832) (xy 204.379574 -349.302832)
			(xy 204.383645 -349.24721) (xy 204.395771 -349.192773) (xy 204.415694 -349.140682) (xy 204.44299 -349.092047)
			(xy 204.477076 -349.047904) (xy 204.517225 -349.009195) (xy 204.562583 -348.976744) (xy 204.612183 -348.951243)
			(xy 204.664967 -348.933236) (xy 204.71981 -348.923106) (xy 204.775544 -348.921069) (xy 204.830981 -348.927169)
			(xy 204.884938 -348.941275) (xy 204.936267 -348.963087) (xy 204.983873 -348.992141) (xy 205.026741 -349.027816)
			(xy 205.063958 -349.069353) (xy 205.094731 -349.115866) (xy 205.118403 -349.166363) (xy 205.134471 -349.21977)
			(xy 205.134584 -349.220536) (xy 205.395574 -349.220536) (xy 205.399645 -349.164914) (xy 205.411771 -349.110477)
			(xy 205.431694 -349.058386) (xy 205.45899 -349.009751) (xy 205.493076 -348.965608) (xy 205.533225 -348.926899)
			(xy 205.578583 -348.894448) (xy 205.628183 -348.868947) (xy 205.680967 -348.85094) (xy 205.73581 -348.84081)
			(xy 205.791544 -348.838773) (xy 205.846981 -348.844873) (xy 205.900938 -348.858979) (xy 205.952267 -348.880791)
			(xy 205.983722 -348.899988) (xy 248.580146 -348.899988) (xy 248.584217 -348.844366) (xy 248.596343 -348.789929)
			(xy 248.616266 -348.737838) (xy 248.643562 -348.689203) (xy 248.677648 -348.64506) (xy 248.717797 -348.606351)
			(xy 248.763155 -348.5739) (xy 248.812755 -348.548399) (xy 248.865539 -348.530392) (xy 248.920382 -348.520262)
			(xy 248.976116 -348.518225) (xy 249.031553 -348.524325) (xy 249.08551 -348.538431) (xy 249.136839 -348.560243)
			(xy 249.184445 -348.589297) (xy 249.227313 -348.624972) (xy 249.26453 -348.666509) (xy 249.295303 -348.713022)
			(xy 249.318975 -348.763519) (xy 249.335043 -348.816926) (xy 249.338968 -348.8436) (xy 253.262382 -348.8436)
			(xy 253.266453 -348.787978) (xy 253.278579 -348.733541) (xy 253.298502 -348.68145) (xy 253.325798 -348.632815)
			(xy 253.359884 -348.588672) (xy 253.400033 -348.549963) (xy 253.445391 -348.517512) (xy 253.494991 -348.492011)
			(xy 253.547775 -348.474004) (xy 253.602618 -348.463874) (xy 253.658352 -348.461837) (xy 253.713789 -348.467937)
			(xy 253.767746 -348.482043) (xy 253.819075 -348.503855) (xy 253.866681 -348.532909) (xy 253.909549 -348.568584)
			(xy 253.946766 -348.610121) (xy 253.977539 -348.656634) (xy 254.001211 -348.707131) (xy 254.017279 -348.760538)
			(xy 254.025399 -348.815714) (xy 254.025908 -348.8436) (xy 254.025399 -348.871486) (xy 254.017279 -348.926662)
			(xy 254.001211 -348.980069) (xy 253.977539 -349.030566) (xy 253.946766 -349.077079) (xy 253.909549 -349.118616)
			(xy 253.866681 -349.154291) (xy 253.819075 -349.183345) (xy 253.767746 -349.205157) (xy 253.713789 -349.219263)
			(xy 253.658352 -349.225363) (xy 253.602618 -349.223326) (xy 253.547775 -349.213196) (xy 253.494991 -349.195189)
			(xy 253.445391 -349.169688) (xy 253.400033 -349.137237) (xy 253.359884 -349.098528) (xy 253.325798 -349.054385)
			(xy 253.298502 -349.00575) (xy 253.278579 -348.953659) (xy 253.266453 -348.899222) (xy 253.262382 -348.8436)
			(xy 249.338968 -348.8436) (xy 249.343163 -348.872102) (xy 249.343672 -348.899988) (xy 249.343163 -348.927874)
			(xy 249.335043 -348.98305) (xy 249.318975 -349.036457) (xy 249.295303 -349.086954) (xy 249.26453 -349.133467)
			(xy 249.227313 -349.175004) (xy 249.184445 -349.210679) (xy 249.136839 -349.239733) (xy 249.08551 -349.261545)
			(xy 249.031553 -349.275651) (xy 248.976116 -349.281751) (xy 248.920382 -349.279714) (xy 248.865539 -349.269584)
			(xy 248.812755 -349.251577) (xy 248.763155 -349.226076) (xy 248.717797 -349.193625) (xy 248.677648 -349.154916)
			(xy 248.643562 -349.110773) (xy 248.616266 -349.062138) (xy 248.596343 -349.010047) (xy 248.584217 -348.95561)
			(xy 248.580146 -348.899988) (xy 205.983722 -348.899988) (xy 205.999873 -348.909845) (xy 206.042741 -348.94552)
			(xy 206.079958 -348.987057) (xy 206.110731 -349.03357) (xy 206.134403 -349.084067) (xy 206.150471 -349.137474)
			(xy 206.158591 -349.19265) (xy 206.1591 -349.220536) (xy 206.158591 -349.248422) (xy 206.150471 -349.303598)
			(xy 206.134403 -349.357005) (xy 206.110731 -349.407502) (xy 206.079958 -349.454015) (xy 206.062937 -349.473012)
			(xy 236.12678 -349.473012) (xy 236.130851 -349.41739) (xy 236.142977 -349.362953) (xy 236.1629 -349.310862)
			(xy 236.190196 -349.262227) (xy 236.224282 -349.218084) (xy 236.264431 -349.179375) (xy 236.309789 -349.146924)
			(xy 236.359389 -349.121423) (xy 236.412173 -349.103416) (xy 236.467016 -349.093286) (xy 236.52275 -349.091249)
			(xy 236.578187 -349.097349) (xy 236.632144 -349.111455) (xy 236.683473 -349.133267) (xy 236.731079 -349.162321)
			(xy 236.773947 -349.197996) (xy 236.811164 -349.239533) (xy 236.841937 -349.286046) (xy 236.865609 -349.336543)
			(xy 236.881677 -349.38995) (xy 236.887181 -349.42735) (xy 240.762792 -349.42735) (xy 240.762792 -349.37285)
			(xy 240.770548 -349.318905) (xy 240.785902 -349.266613) (xy 240.808542 -349.217039) (xy 240.838006 -349.171191)
			(xy 240.873695 -349.130002) (xy 240.914883 -349.094312) (xy 240.96073 -349.064847) (xy 241.010304 -349.042206)
			(xy 241.062596 -349.02685) (xy 241.11654 -349.019093) (xy 241.14379 -349.018606) (xy 241.172707 -349.019129)
			(xy 241.229878 -349.027857) (xy 241.285077 -349.045114) (xy 241.337038 -349.070505) (xy 241.384572 -349.103447)
			(xy 241.42659 -349.143187) (xy 241.44478 -349.165672) (xy 241.452393 -349.174472) (xy 241.47329 -349.184657)
			(xy 241.484912 -349.18523) (xy 241.564668 -349.18523) (xy 241.5763 -349.184683) (xy 241.597211 -349.174502)
			(xy 241.6048 -349.165672) (xy 241.622984 -349.143183) (xy 241.665006 -349.103449) (xy 241.712543 -349.070512)
			(xy 241.764505 -349.045125) (xy 241.819704 -349.027869) (xy 241.876874 -349.019141) (xy 241.90579 -349.018606)
			(xy 241.933044 -349.01904) (xy 241.986998 -349.026796) (xy 242.039299 -349.042152) (xy 242.088883 -349.064795)
			(xy 242.134739 -349.094264) (xy 242.175934 -349.129959) (xy 242.21163 -349.171153) (xy 242.2411 -349.217009)
			(xy 242.263744 -349.266591) (xy 242.279102 -349.318892) (xy 242.286859 -349.372846) (xy 242.286859 -349.427354)
			(xy 242.279102 -349.481308) (xy 242.263744 -349.533609) (xy 242.2411 -349.583191) (xy 242.21163 -349.629047)
			(xy 242.175934 -349.670241) (xy 242.134739 -349.705936) (xy 242.088883 -349.735405) (xy 242.039299 -349.758048)
			(xy 241.986998 -349.773404) (xy 241.933044 -349.78116) (xy 241.90579 -349.781622) (xy 241.876874 -349.781069)
			(xy 241.819703 -349.772351) (xy 241.764504 -349.755102) (xy 241.712541 -349.729717) (xy 241.665007 -349.696778)
			(xy 241.62299 -349.65704) (xy 241.6048 -349.634556) (xy 241.597191 -349.625752) (xy 241.576291 -349.615568)
			(xy 241.564668 -349.614998) (xy 241.484912 -349.614998) (xy 241.473283 -349.615559) (xy 241.452373 -349.625733)
			(xy 241.44478 -349.634556) (xy 241.426589 -349.65704) (xy 241.384571 -349.696777) (xy 241.337036 -349.729717)
			(xy 241.285075 -349.755106) (xy 241.229876 -349.772362) (xy 241.172706 -349.781088) (xy 241.14379 -349.781622)
			(xy 241.11654 -349.781107) (xy 241.062596 -349.77335) (xy 241.010304 -349.757994) (xy 240.96073 -349.735353)
			(xy 240.914883 -349.705888) (xy 240.873695 -349.670198) (xy 240.838006 -349.629009) (xy 240.808542 -349.583161)
			(xy 240.785902 -349.533587) (xy 240.770548 -349.481295) (xy 240.762792 -349.42735) (xy 236.887181 -349.42735)
			(xy 236.889797 -349.445126) (xy 236.890306 -349.473012) (xy 236.889797 -349.500898) (xy 236.881677 -349.556074)
			(xy 236.865609 -349.609481) (xy 236.841937 -349.659978) (xy 236.811164 -349.706491) (xy 236.773947 -349.748028)
			(xy 236.731079 -349.783703) (xy 236.683473 -349.812757) (xy 236.632144 -349.834569) (xy 236.578187 -349.848675)
			(xy 236.52275 -349.854775) (xy 236.467016 -349.852738) (xy 236.412173 -349.842608) (xy 236.359389 -349.824601)
			(xy 236.309789 -349.7991) (xy 236.264431 -349.766649) (xy 236.224282 -349.72794) (xy 236.190196 -349.683797)
			(xy 236.1629 -349.635162) (xy 236.142977 -349.583071) (xy 236.130851 -349.528634) (xy 236.12678 -349.473012)
			(xy 206.062937 -349.473012) (xy 206.042741 -349.495552) (xy 205.999873 -349.531227) (xy 205.952267 -349.560281)
			(xy 205.900938 -349.582093) (xy 205.846981 -349.596199) (xy 205.791544 -349.602299) (xy 205.73581 -349.600262)
			(xy 205.680967 -349.590132) (xy 205.628183 -349.572125) (xy 205.578583 -349.546624) (xy 205.533225 -349.514173)
			(xy 205.493076 -349.475464) (xy 205.45899 -349.431321) (xy 205.431694 -349.382686) (xy 205.411771 -349.330595)
			(xy 205.399645 -349.276158) (xy 205.395574 -349.220536) (xy 205.134584 -349.220536) (xy 205.142591 -349.274946)
			(xy 205.1431 -349.302832) (xy 205.142591 -349.330718) (xy 205.134471 -349.385894) (xy 205.118403 -349.439301)
			(xy 205.094731 -349.489798) (xy 205.063958 -349.536311) (xy 205.026741 -349.577848) (xy 204.983873 -349.613523)
			(xy 204.936267 -349.642577) (xy 204.884938 -349.664389) (xy 204.830981 -349.678495) (xy 204.775544 -349.684595)
			(xy 204.71981 -349.682558) (xy 204.664967 -349.672428) (xy 204.612183 -349.654421) (xy 204.562583 -349.62892)
			(xy 204.517225 -349.596469) (xy 204.477076 -349.55776) (xy 204.44299 -349.513617) (xy 204.415694 -349.464982)
			(xy 204.395771 -349.412891) (xy 204.383645 -349.358454) (xy 204.379574 -349.302832) (xy 195.68033 -349.302832)
			(xy 195.68033 -349.899986) (xy 248.589544 -349.899986) (xy 248.593615 -349.844364) (xy 248.605741 -349.789927)
			(xy 248.625664 -349.737836) (xy 248.65296 -349.689201) (xy 248.687046 -349.645058) (xy 248.727195 -349.606349)
			(xy 248.772553 -349.573898) (xy 248.822153 -349.548397) (xy 248.874937 -349.53039) (xy 248.92978 -349.52026)
			(xy 248.985514 -349.518223) (xy 249.040951 -349.524323) (xy 249.094908 -349.538429) (xy 249.146237 -349.560241)
			(xy 249.193843 -349.589295) (xy 249.236711 -349.62497) (xy 249.273928 -349.666507) (xy 249.304701 -349.71302)
			(xy 249.328373 -349.763517) (xy 249.344441 -349.816924) (xy 249.350721 -349.8596) (xy 253.435864 -349.8596)
			(xy 253.439935 -349.803978) (xy 253.452061 -349.749541) (xy 253.471984 -349.69745) (xy 253.49928 -349.648815)
			(xy 253.533366 -349.604672) (xy 253.573515 -349.565963) (xy 253.618873 -349.533512) (xy 253.668473 -349.508011)
			(xy 253.721257 -349.490004) (xy 253.7761 -349.479874) (xy 253.831834 -349.477837) (xy 253.887271 -349.483937)
			(xy 253.941228 -349.498043) (xy 253.992557 -349.519855) (xy 254.040163 -349.548909) (xy 254.083031 -349.584584)
			(xy 254.120248 -349.626121) (xy 254.151021 -349.672634) (xy 254.174693 -349.723131) (xy 254.189845 -349.773494)
			(xy 258.543296 -349.773494) (xy 258.547367 -349.717872) (xy 258.559493 -349.663435) (xy 258.579416 -349.611344)
			(xy 258.606712 -349.562709) (xy 258.640798 -349.518566) (xy 258.680947 -349.479857) (xy 258.726305 -349.447406)
			(xy 258.775905 -349.421905) (xy 258.828689 -349.403898) (xy 258.883532 -349.393768) (xy 258.939266 -349.391731)
			(xy 258.994703 -349.397831) (xy 259.04866 -349.411937) (xy 259.099989 -349.433749) (xy 259.147595 -349.462803)
			(xy 259.190463 -349.498478) (xy 259.22768 -349.540015) (xy 259.258453 -349.586528) (xy 259.282125 -349.637025)
			(xy 259.298193 -349.690432) (xy 259.306313 -349.745608) (xy 259.306822 -349.773494) (xy 259.306313 -349.80138)
			(xy 259.298193 -349.856556) (xy 259.282125 -349.909963) (xy 259.258453 -349.96046) (xy 259.22768 -350.006973)
			(xy 259.190463 -350.04851) (xy 259.147595 -350.084185) (xy 259.099989 -350.113239) (xy 259.04866 -350.135051)
			(xy 258.994703 -350.149157) (xy 258.939266 -350.155257) (xy 258.883532 -350.15322) (xy 258.828689 -350.14309)
			(xy 258.775905 -350.125083) (xy 258.726305 -350.099582) (xy 258.680947 -350.067131) (xy 258.640798 -350.028422)
			(xy 258.606712 -349.984279) (xy 258.579416 -349.935644) (xy 258.559493 -349.883553) (xy 258.547367 -349.829116)
			(xy 258.543296 -349.773494) (xy 254.189845 -349.773494) (xy 254.190761 -349.776538) (xy 254.198881 -349.831714)
			(xy 254.19939 -349.8596) (xy 254.198881 -349.887486) (xy 254.190761 -349.942662) (xy 254.174693 -349.996069)
			(xy 254.151021 -350.046566) (xy 254.120248 -350.093079) (xy 254.083031 -350.134616) (xy 254.040163 -350.170291)
			(xy 253.992557 -350.199345) (xy 253.941228 -350.221157) (xy 253.887271 -350.235263) (xy 253.831834 -350.241363)
			(xy 253.7761 -350.239326) (xy 253.721257 -350.229196) (xy 253.668473 -350.211189) (xy 253.618873 -350.185688)
			(xy 253.573515 -350.153237) (xy 253.533366 -350.114528) (xy 253.49928 -350.070385) (xy 253.471984 -350.02175)
			(xy 253.452061 -349.969659) (xy 253.439935 -349.915222) (xy 253.435864 -349.8596) (xy 249.350721 -349.8596)
			(xy 249.352561 -349.8721) (xy 249.35307 -349.899986) (xy 249.352561 -349.927872) (xy 249.344441 -349.983048)
			(xy 249.328373 -350.036455) (xy 249.304701 -350.086952) (xy 249.273928 -350.133465) (xy 249.236711 -350.175002)
			(xy 249.193843 -350.210677) (xy 249.146237 -350.239731) (xy 249.094908 -350.261543) (xy 249.040951 -350.275649)
			(xy 248.985514 -350.281749) (xy 248.92978 -350.279712) (xy 248.874937 -350.269582) (xy 248.822153 -350.251575)
			(xy 248.772553 -350.226074) (xy 248.727195 -350.193623) (xy 248.687046 -350.154914) (xy 248.65296 -350.110771)
			(xy 248.625664 -350.062136) (xy 248.605741 -350.010045) (xy 248.593615 -349.955608) (xy 248.589544 -349.899986)
			(xy 195.68033 -349.899986) (xy 195.68033 -350.712532) (xy 207.046574 -350.712532) (xy 207.050645 -350.65691)
			(xy 207.062771 -350.602473) (xy 207.082694 -350.550382) (xy 207.10999 -350.501747) (xy 207.144076 -350.457604)
			(xy 207.184225 -350.418895) (xy 207.229583 -350.386444) (xy 207.279183 -350.360943) (xy 207.331967 -350.342936)
			(xy 207.38681 -350.332806) (xy 207.442544 -350.330769) (xy 207.497981 -350.336869) (xy 207.551938 -350.350975)
			(xy 207.603267 -350.372787) (xy 207.606005 -350.374458) (xy 236.132368 -350.374458) (xy 236.136439 -350.318836)
			(xy 236.148565 -350.264399) (xy 236.168488 -350.212308) (xy 236.195784 -350.163673) (xy 236.22987 -350.11953)
			(xy 236.270019 -350.080821) (xy 236.315377 -350.04837) (xy 236.364977 -350.022869) (xy 236.417761 -350.004862)
			(xy 236.472604 -349.994732) (xy 236.528338 -349.992695) (xy 236.583775 -349.998795) (xy 236.637732 -350.012901)
			(xy 236.689061 -350.034713) (xy 236.736667 -350.063767) (xy 236.779535 -350.099442) (xy 236.816752 -350.140979)
			(xy 236.847525 -350.187492) (xy 236.871197 -350.237989) (xy 236.887265 -350.291396) (xy 236.895385 -350.346572)
			(xy 236.895894 -350.374458) (xy 236.895385 -350.402344) (xy 236.891705 -350.427353) (xy 240.784067 -350.427353)
			(xy 240.784067 -350.372847) (xy 240.791825 -350.318895) (xy 240.807182 -350.266597) (xy 240.829825 -350.217017)
			(xy 240.859295 -350.171164) (xy 240.89499 -350.129972) (xy 240.936185 -350.094279) (xy 240.98204 -350.064813)
			(xy 241.031621 -350.042173) (xy 241.083921 -350.026819) (xy 241.137873 -350.019066) (xy 241.165126 -350.018604)
			(xy 241.193321 -350.019079) (xy 241.249098 -350.027377) (xy 241.303047 -350.043788) (xy 241.353997 -350.067955)
			(xy 241.400838 -350.099352) (xy 241.442551 -350.137298) (xy 241.460782 -350.158812) (xy 241.46838 -350.167237)
			(xy 241.488824 -350.176999) (xy 241.500152 -350.177608) (xy 241.578892 -350.177608) (xy 241.590208 -350.176941)
			(xy 241.610641 -350.167201) (xy 241.618262 -350.158812) (xy 241.636496 -350.137297) (xy 241.67819 -350.099327)
			(xy 241.725025 -350.067915) (xy 241.775978 -350.043748) (xy 241.829936 -350.027353) (xy 241.885721 -350.019089)
			(xy 241.913918 -350.018604) (xy 241.941169 -350.019067) (xy 241.995117 -350.026826) (xy 242.047411 -350.042183)
			(xy 242.096987 -350.064826) (xy 242.142837 -350.094294) (xy 242.184026 -350.129986) (xy 242.219717 -350.171177)
			(xy 242.249183 -350.217028) (xy 242.271823 -350.266606) (xy 242.287178 -350.318901) (xy 242.294934 -350.372849)
			(xy 242.294934 -350.427351) (xy 242.287178 -350.481299) (xy 242.271823 -350.533594) (xy 242.249183 -350.583172)
			(xy 242.219717 -350.629023) (xy 242.184026 -350.670214) (xy 242.142837 -350.705906) (xy 242.096987 -350.735374)
			(xy 242.047411 -350.758017) (xy 241.995117 -350.773374) (xy 241.941169 -350.781133) (xy 241.913918 -350.78162)
			(xy 241.885724 -350.781105) (xy 241.82995 -350.772814) (xy 241.776001 -350.756411) (xy 241.725052 -350.732251)
			(xy 241.67821 -350.700861) (xy 241.636494 -350.662923) (xy 241.618262 -350.641412) (xy 241.610684 -350.632966)
			(xy 241.590225 -350.623214) (xy 241.578892 -350.622616) (xy 241.500152 -350.622616) (xy 241.488831 -350.623244)
			(xy 241.468398 -350.633011) (xy 241.460782 -350.641412) (xy 241.442585 -350.662958) (xy 241.400882 -350.700926)
			(xy 241.354039 -350.732333) (xy 241.303079 -350.756495) (xy 241.249115 -350.772883) (xy 241.193325 -350.781139)
			(xy 241.165126 -350.78162) (xy 241.137873 -350.781134) (xy 241.083921 -350.773381) (xy 241.031621 -350.758027)
			(xy 240.98204 -350.735387) (xy 240.936185 -350.705921) (xy 240.89499 -350.670228) (xy 240.859295 -350.629036)
			(xy 240.829825 -350.583183) (xy 240.807182 -350.533603) (xy 240.791825 -350.481305) (xy 240.784067 -350.427353)
			(xy 236.891705 -350.427353) (xy 236.887265 -350.45752) (xy 236.871197 -350.510927) (xy 236.847525 -350.561424)
			(xy 236.816752 -350.607937) (xy 236.779535 -350.649474) (xy 236.736667 -350.685149) (xy 236.689061 -350.714203)
			(xy 236.637732 -350.736015) (xy 236.583775 -350.750121) (xy 236.528338 -350.756221) (xy 236.472604 -350.754184)
			(xy 236.417761 -350.744054) (xy 236.364977 -350.726047) (xy 236.315377 -350.700546) (xy 236.270019 -350.668095)
			(xy 236.22987 -350.629386) (xy 236.195784 -350.585243) (xy 236.168488 -350.536608) (xy 236.148565 -350.484517)
			(xy 236.136439 -350.43008) (xy 236.132368 -350.374458) (xy 207.606005 -350.374458) (xy 207.650873 -350.401841)
			(xy 207.693741 -350.437516) (xy 207.730958 -350.479053) (xy 207.761731 -350.525566) (xy 207.785403 -350.576063)
			(xy 207.801471 -350.62947) (xy 207.809591 -350.684646) (xy 207.8101 -350.712532) (xy 207.809591 -350.740418)
			(xy 207.801471 -350.795594) (xy 207.785403 -350.849001) (xy 207.761731 -350.899498) (xy 207.761409 -350.899984)
			(xy 248.573288 -350.899984) (xy 248.577359 -350.844362) (xy 248.589485 -350.789925) (xy 248.609408 -350.737834)
			(xy 248.636704 -350.689199) (xy 248.67079 -350.645056) (xy 248.710939 -350.606347) (xy 248.756297 -350.573896)
			(xy 248.805897 -350.548395) (xy 248.858681 -350.530388) (xy 248.913524 -350.520258) (xy 248.969258 -350.518221)
			(xy 249.024695 -350.524321) (xy 249.078652 -350.538427) (xy 249.129981 -350.560239) (xy 249.177587 -350.589293)
			(xy 249.220455 -350.624968) (xy 249.257672 -350.666505) (xy 249.288445 -350.713018) (xy 249.312117 -350.763515)
			(xy 249.328185 -350.816922) (xy 249.329344 -350.8248) (xy 252.957836 -350.8248) (xy 252.961907 -350.769178)
			(xy 252.974033 -350.714741) (xy 252.993956 -350.66265) (xy 253.021252 -350.614015) (xy 253.055338 -350.569872)
			(xy 253.095487 -350.531163) (xy 253.140845 -350.498712) (xy 253.190445 -350.473211) (xy 253.243229 -350.455204)
			(xy 253.298072 -350.445074) (xy 253.353806 -350.443037) (xy 253.409243 -350.449137) (xy 253.4632 -350.463243)
			(xy 253.514529 -350.485055) (xy 253.562135 -350.514109) (xy 253.605003 -350.549784) (xy 253.64222 -350.591321)
			(xy 253.672993 -350.637834) (xy 253.696665 -350.688331) (xy 253.706926 -350.722438) (xy 255.74828 -350.722438)
			(xy 255.752351 -350.666816) (xy 255.764477 -350.612379) (xy 255.7844 -350.560288) (xy 255.811696 -350.511653)
			(xy 255.845782 -350.46751) (xy 255.885931 -350.428801) (xy 255.931289 -350.39635) (xy 255.980889 -350.370849)
			(xy 256.033673 -350.352842) (xy 256.088516 -350.342712) (xy 256.14425 -350.340675) (xy 256.199687 -350.346775)
			(xy 256.253644 -350.360881) (xy 256.304973 -350.382693) (xy 256.352579 -350.411747) (xy 256.395447 -350.447422)
			(xy 256.432664 -350.488959) (xy 256.463437 -350.535472) (xy 256.487109 -350.585969) (xy 256.503177 -350.639376)
			(xy 256.511297 -350.694552) (xy 256.511806 -350.722438) (xy 256.511297 -350.750324) (xy 256.503177 -350.8055)
			(xy 256.487109 -350.858907) (xy 256.463437 -350.909404) (xy 256.432664 -350.955917) (xy 256.395447 -350.997454)
			(xy 256.352579 -351.033129) (xy 256.304973 -351.062183) (xy 256.253644 -351.083995) (xy 256.199687 -351.098101)
			(xy 256.14425 -351.104201) (xy 256.088516 -351.102164) (xy 256.033673 -351.092034) (xy 255.980889 -351.074027)
			(xy 255.931289 -351.048526) (xy 255.885931 -351.016075) (xy 255.845782 -350.977366) (xy 255.811696 -350.933223)
			(xy 255.7844 -350.884588) (xy 255.764477 -350.832497) (xy 255.752351 -350.77806) (xy 255.74828 -350.722438)
			(xy 253.706926 -350.722438) (xy 253.712733 -350.741738) (xy 253.720853 -350.796914) (xy 253.721362 -350.8248)
			(xy 253.720853 -350.852686) (xy 253.712733 -350.907862) (xy 253.696665 -350.961269) (xy 253.672993 -351.011766)
			(xy 253.64222 -351.058279) (xy 253.605003 -351.099816) (xy 253.562135 -351.135491) (xy 253.514529 -351.164545)
			(xy 253.4632 -351.186357) (xy 253.409243 -351.200463) (xy 253.353806 -351.206563) (xy 253.298072 -351.204526)
			(xy 253.243229 -351.194396) (xy 253.190445 -351.176389) (xy 253.140845 -351.150888) (xy 253.095487 -351.118437)
			(xy 253.055338 -351.079728) (xy 253.021252 -351.035585) (xy 252.993956 -350.98695) (xy 252.974033 -350.934859)
			(xy 252.961907 -350.880422) (xy 252.957836 -350.8248) (xy 249.329344 -350.8248) (xy 249.336305 -350.872098)
			(xy 249.336814 -350.899984) (xy 249.336305 -350.92787) (xy 249.328185 -350.983046) (xy 249.312117 -351.036453)
			(xy 249.288445 -351.08695) (xy 249.257672 -351.133463) (xy 249.220455 -351.175) (xy 249.177587 -351.210675)
			(xy 249.129981 -351.239729) (xy 249.078652 -351.261541) (xy 249.024695 -351.275647) (xy 248.969258 -351.281747)
			(xy 248.913524 -351.27971) (xy 248.858681 -351.26958) (xy 248.805897 -351.251573) (xy 248.756297 -351.226072)
			(xy 248.710939 -351.193621) (xy 248.67079 -351.154912) (xy 248.636704 -351.110769) (xy 248.609408 -351.062134)
			(xy 248.589485 -351.010043) (xy 248.577359 -350.955606) (xy 248.573288 -350.899984) (xy 207.761409 -350.899984)
			(xy 207.730958 -350.946011) (xy 207.693741 -350.987548) (xy 207.650873 -351.023223) (xy 207.603267 -351.052277)
			(xy 207.551938 -351.074089) (xy 207.497981 -351.088195) (xy 207.442544 -351.094295) (xy 207.38681 -351.092258)
			(xy 207.331967 -351.082128) (xy 207.279183 -351.064121) (xy 207.229583 -351.03862) (xy 207.184225 -351.006169)
			(xy 207.144076 -350.96746) (xy 207.10999 -350.923317) (xy 207.082694 -350.874682) (xy 207.062771 -350.822591)
			(xy 207.050645 -350.768154) (xy 207.046574 -350.712532) (xy 195.68033 -350.712532) (xy 195.68033 -351.46361)
			(xy 204.379574 -351.46361) (xy 204.383645 -351.407988) (xy 204.395771 -351.353551) (xy 204.415694 -351.30146)
			(xy 204.44299 -351.252825) (xy 204.477076 -351.208682) (xy 204.517225 -351.169973) (xy 204.562583 -351.137522)
			(xy 204.612183 -351.112021) (xy 204.664967 -351.094014) (xy 204.71981 -351.083884) (xy 204.775544 -351.081847)
			(xy 204.830981 -351.087947) (xy 204.884938 -351.102053) (xy 204.936267 -351.123865) (xy 204.983873 -351.152919)
			(xy 205.026741 -351.188594) (xy 205.063958 -351.230131) (xy 205.094731 -351.276644) (xy 205.118403 -351.327141)
			(xy 205.124996 -351.349056) (xy 233.362752 -351.349056) (xy 233.366823 -351.293434) (xy 233.378949 -351.238997)
			(xy 233.398872 -351.186906) (xy 233.426168 -351.138271) (xy 233.460254 -351.094128) (xy 233.500403 -351.055419)
			(xy 233.545761 -351.022968) (xy 233.595361 -350.997467) (xy 233.648145 -350.97946) (xy 233.702988 -350.96933)
			(xy 233.758722 -350.967293) (xy 233.814159 -350.973393) (xy 233.868116 -350.987499) (xy 233.919445 -351.009311)
			(xy 233.967051 -351.038365) (xy 234.009919 -351.07404) (xy 234.047136 -351.115577) (xy 234.077909 -351.16209)
			(xy 234.101581 -351.212587) (xy 234.117649 -351.265994) (xy 234.125769 -351.32117) (xy 234.126106 -351.339658)
			(xy 236.132368 -351.339658) (xy 236.136439 -351.284036) (xy 236.148565 -351.229599) (xy 236.168488 -351.177508)
			(xy 236.195784 -351.128873) (xy 236.22987 -351.08473) (xy 236.270019 -351.046021) (xy 236.315377 -351.01357)
			(xy 236.364977 -350.988069) (xy 236.417761 -350.970062) (xy 236.472604 -350.959932) (xy 236.528338 -350.957895)
			(xy 236.583775 -350.963995) (xy 236.637732 -350.978101) (xy 236.689061 -350.999913) (xy 236.736667 -351.028967)
			(xy 236.779535 -351.064642) (xy 236.816752 -351.106179) (xy 236.847525 -351.152692) (xy 236.871197 -351.203189)
			(xy 236.887265 -351.256596) (xy 236.895385 -351.311772) (xy 236.895894 -351.339658) (xy 236.895385 -351.367544)
			(xy 236.890592 -351.40011) (xy 241.568476 -351.40011) (xy 241.572547 -351.344488) (xy 241.584673 -351.290051)
			(xy 241.604596 -351.23796) (xy 241.631892 -351.189325) (xy 241.665978 -351.145182) (xy 241.706127 -351.106473)
			(xy 241.751485 -351.074022) (xy 241.801085 -351.048521) (xy 241.853869 -351.030514) (xy 241.908712 -351.020384)
			(xy 241.964446 -351.018347) (xy 242.019883 -351.024447) (xy 242.07384 -351.038553) (xy 242.125169 -351.060365)
			(xy 242.172775 -351.089419) (xy 242.215643 -351.125094) (xy 242.25286 -351.166631) (xy 242.283633 -351.213144)
			(xy 242.307305 -351.263641) (xy 242.323373 -351.317048) (xy 242.331493 -351.372224) (xy 242.332002 -351.40011)
			(xy 242.331493 -351.427996) (xy 242.323373 -351.483172) (xy 242.307305 -351.536579) (xy 242.283633 -351.587076)
			(xy 242.25286 -351.633589) (xy 242.215643 -351.675126) (xy 242.172775 -351.710801) (xy 242.125169 -351.739855)
			(xy 242.07384 -351.761667) (xy 242.019883 -351.775773) (xy 241.964446 -351.781873) (xy 241.908712 -351.779836)
			(xy 241.853869 -351.769706) (xy 241.801085 -351.751699) (xy 241.751485 -351.726198) (xy 241.706127 -351.693747)
			(xy 241.665978 -351.655038) (xy 241.631892 -351.610895) (xy 241.604596 -351.56226) (xy 241.584673 -351.510169)
			(xy 241.572547 -351.455732) (xy 241.568476 -351.40011) (xy 236.890592 -351.40011) (xy 236.887265 -351.42272)
			(xy 236.871197 -351.476127) (xy 236.847525 -351.526624) (xy 236.816752 -351.573137) (xy 236.779535 -351.614674)
			(xy 236.736667 -351.650349) (xy 236.689061 -351.679403) (xy 236.637732 -351.701215) (xy 236.583775 -351.715321)
			(xy 236.528338 -351.721421) (xy 236.472604 -351.719384) (xy 236.417761 -351.709254) (xy 236.364977 -351.691247)
			(xy 236.315377 -351.665746) (xy 236.270019 -351.633295) (xy 236.22987 -351.594586) (xy 236.195784 -351.550443)
			(xy 236.168488 -351.501808) (xy 236.148565 -351.449717) (xy 236.136439 -351.39528) (xy 236.132368 -351.339658)
			(xy 234.126106 -351.339658) (xy 234.126278 -351.349056) (xy 234.125769 -351.376942) (xy 234.117649 -351.432118)
			(xy 234.101581 -351.485525) (xy 234.077909 -351.536022) (xy 234.047136 -351.582535) (xy 234.009919 -351.624072)
			(xy 233.967051 -351.659747) (xy 233.919445 -351.688801) (xy 233.868116 -351.710613) (xy 233.814159 -351.724719)
			(xy 233.758722 -351.730819) (xy 233.702988 -351.728782) (xy 233.648145 -351.718652) (xy 233.595361 -351.700645)
			(xy 233.545761 -351.675144) (xy 233.500403 -351.642693) (xy 233.460254 -351.603984) (xy 233.426168 -351.559841)
			(xy 233.398872 -351.511206) (xy 233.378949 -351.459115) (xy 233.366823 -351.404678) (xy 233.362752 -351.349056)
			(xy 205.124996 -351.349056) (xy 205.134471 -351.380548) (xy 205.142591 -351.435724) (xy 205.1431 -351.46361)
			(xy 205.142591 -351.491496) (xy 205.134471 -351.546672) (xy 205.118403 -351.600079) (xy 205.094731 -351.650576)
			(xy 205.063958 -351.697089) (xy 205.026741 -351.738626) (xy 204.983873 -351.774301) (xy 204.936267 -351.803355)
			(xy 204.884938 -351.825167) (xy 204.830981 -351.839273) (xy 204.775544 -351.845373) (xy 204.71981 -351.843336)
			(xy 204.664967 -351.833206) (xy 204.612183 -351.815199) (xy 204.562583 -351.789698) (xy 204.517225 -351.757247)
			(xy 204.477076 -351.718538) (xy 204.44299 -351.674395) (xy 204.415694 -351.62576) (xy 204.395771 -351.573669)
			(xy 204.383645 -351.519232) (xy 204.379574 -351.46361) (xy 195.68033 -351.46361) (xy 195.68033 -352.307906)
			(xy 233.389422 -352.307906) (xy 233.393493 -352.252284) (xy 233.405619 -352.197847) (xy 233.425542 -352.145756)
			(xy 233.452838 -352.097121) (xy 233.486924 -352.052978) (xy 233.527073 -352.014269) (xy 233.572431 -351.981818)
			(xy 233.622031 -351.956317) (xy 233.674815 -351.93831) (xy 233.729658 -351.92818) (xy 233.785392 -351.926143)
			(xy 233.840829 -351.932243) (xy 233.894786 -351.946349) (xy 233.946115 -351.968161) (xy 233.993721 -351.997215)
			(xy 234.036589 -352.03289) (xy 234.073806 -352.074427) (xy 234.104579 -352.12094) (xy 234.128251 -352.171437)
			(xy 234.144319 -352.224844) (xy 234.152439 -352.28002) (xy 234.152892 -352.304858) (xy 236.132368 -352.304858)
			(xy 236.136439 -352.249236) (xy 236.148565 -352.194799) (xy 236.168488 -352.142708) (xy 236.195784 -352.094073)
			(xy 236.22987 -352.04993) (xy 236.270019 -352.011221) (xy 236.315377 -351.97877) (xy 236.364977 -351.953269)
			(xy 236.417761 -351.935262) (xy 236.472604 -351.925132) (xy 236.528338 -351.923095) (xy 236.583775 -351.929195)
			(xy 236.637732 -351.943301) (xy 236.689061 -351.965113) (xy 236.736667 -351.994167) (xy 236.779535 -352.029842)
			(xy 236.816752 -352.071379) (xy 236.847525 -352.117892) (xy 236.871197 -352.168389) (xy 236.887265 -352.221796)
			(xy 236.895385 -352.276972) (xy 236.895894 -352.304858) (xy 236.895385 -352.332744) (xy 236.887265 -352.38792)
			(xy 236.883598 -352.400108) (xy 241.607846 -352.400108) (xy 241.611917 -352.344486) (xy 241.624043 -352.290049)
			(xy 241.643966 -352.237958) (xy 241.671262 -352.189323) (xy 241.705348 -352.14518) (xy 241.745497 -352.106471)
			(xy 241.790855 -352.07402) (xy 241.840455 -352.048519) (xy 241.893239 -352.030512) (xy 241.948082 -352.020382)
			(xy 242.003816 -352.018345) (xy 242.059253 -352.024445) (xy 242.11321 -352.038551) (xy 242.164539 -352.060363)
			(xy 242.179346 -352.0694) (xy 248.537476 -352.0694) (xy 248.537962 -352.042149) (xy 248.545718 -351.988201)
			(xy 248.561073 -351.935906) (xy 248.583715 -351.886329) (xy 248.613181 -351.840479) (xy 248.648872 -351.799288)
			(xy 248.690063 -351.763597) (xy 248.735913 -351.734131) (xy 248.78549 -351.711489) (xy 248.837785 -351.696134)
			(xy 248.891733 -351.688378) (xy 248.946235 -351.688378) (xy 249.000183 -351.696134) (xy 249.052478 -351.711489)
			(xy 249.102055 -351.734131) (xy 249.147905 -351.763597) (xy 249.189096 -351.799288) (xy 249.224787 -351.840479)
			(xy 249.254253 -351.886329) (xy 249.276895 -351.935906) (xy 249.29225 -351.988201) (xy 249.300006 -352.042149)
			(xy 249.300492 -352.0694) (xy 249.30006 -352.09683) (xy 249.292182 -352.151123) (xy 249.276617 -352.20373)
			(xy 249.253686 -352.253569) (xy 249.223861 -352.299614) (xy 249.187754 -352.340918) (xy 249.146109 -352.376632)
			(xy 249.1232 -352.391726) (xy 249.11084 -352.400294) (xy 249.091263 -352.423097) (xy 249.079171 -352.45061)
			(xy 249.07561 -352.480453) (xy 249.080889 -352.510039) (xy 249.094552 -352.536808) (xy 249.115414 -352.558442)
			(xy 249.12828 -352.566224) (xy 249.153419 -352.580761) (xy 249.199351 -352.616288) (xy 249.239371 -352.658364)
			(xy 249.272556 -352.706016) (xy 249.29814 -352.758145) (xy 249.315532 -352.813548) (xy 249.324332 -352.870946)
			(xy 249.324876 -352.89998) (xy 249.32439 -352.927231) (xy 249.316634 -352.981179) (xy 249.301279 -353.033474)
			(xy 249.278637 -353.083051) (xy 249.249171 -353.128901) (xy 249.21348 -353.170092) (xy 249.172289 -353.205783)
			(xy 249.126439 -353.235249) (xy 249.076862 -353.257891) (xy 249.024567 -353.273246) (xy 248.970619 -353.281002)
			(xy 248.916117 -353.281002) (xy 248.862169 -353.273246) (xy 248.809874 -353.257891) (xy 248.760297 -353.235249)
			(xy 248.714447 -353.205783) (xy 248.673256 -353.170092) (xy 248.637565 -353.128901) (xy 248.608099 -353.083051)
			(xy 248.585457 -353.033474) (xy 248.570102 -352.981179) (xy 248.562346 -352.927231) (xy 248.56186 -352.89998)
			(xy 248.562376 -352.872553) (xy 248.570242 -352.818265) (xy 248.585793 -352.765661) (xy 248.608711 -352.715823)
			(xy 248.638523 -352.669777) (xy 248.674617 -352.62847) (xy 248.716249 -352.592751) (xy 248.739152 -352.577654)
			(xy 248.751525 -352.569107) (xy 248.771093 -352.546296) (xy 248.783177 -352.518779) (xy 248.786733 -352.488937)
			(xy 248.781453 -352.45935) (xy 248.767793 -352.43258) (xy 248.746936 -352.410942) (xy 248.734072 -352.403156)
			(xy 248.708914 -352.388652) (xy 248.662984 -352.353117) (xy 248.622966 -352.311035) (xy 248.589784 -352.263378)
			(xy 248.564204 -352.211244) (xy 248.546815 -352.155837) (xy 248.538019 -352.098436) (xy 248.537476 -352.0694)
			(xy 242.179346 -352.0694) (xy 242.212145 -352.089417) (xy 242.255013 -352.125092) (xy 242.29223 -352.166629)
			(xy 242.323003 -352.213142) (xy 242.346675 -352.263639) (xy 242.362743 -352.317046) (xy 242.370863 -352.372222)
			(xy 242.371372 -352.400108) (xy 242.370863 -352.427994) (xy 242.362743 -352.48317) (xy 242.346675 -352.536577)
			(xy 242.323003 -352.587074) (xy 242.29223 -352.633587) (xy 242.255013 -352.675124) (xy 242.212145 -352.710799)
			(xy 242.164539 -352.739853) (xy 242.11321 -352.761665) (xy 242.059253 -352.775771) (xy 242.003816 -352.781871)
			(xy 241.948082 -352.779834) (xy 241.893239 -352.769704) (xy 241.840455 -352.751697) (xy 241.790855 -352.726196)
			(xy 241.745497 -352.693745) (xy 241.705348 -352.655036) (xy 241.671262 -352.610893) (xy 241.643966 -352.562258)
			(xy 241.624043 -352.510167) (xy 241.611917 -352.45573) (xy 241.607846 -352.400108) (xy 236.883598 -352.400108)
			(xy 236.871197 -352.441327) (xy 236.847525 -352.491824) (xy 236.816752 -352.538337) (xy 236.779535 -352.579874)
			(xy 236.736667 -352.615549) (xy 236.689061 -352.644603) (xy 236.637732 -352.666415) (xy 236.583775 -352.680521)
			(xy 236.528338 -352.686621) (xy 236.472604 -352.684584) (xy 236.417761 -352.674454) (xy 236.364977 -352.656447)
			(xy 236.315377 -352.630946) (xy 236.270019 -352.598495) (xy 236.22987 -352.559786) (xy 236.195784 -352.515643)
			(xy 236.168488 -352.467008) (xy 236.148565 -352.414917) (xy 236.136439 -352.36048) (xy 236.132368 -352.304858)
			(xy 234.152892 -352.304858) (xy 234.152948 -352.307906) (xy 234.152439 -352.335792) (xy 234.144319 -352.390968)
			(xy 234.128251 -352.444375) (xy 234.104579 -352.494872) (xy 234.073806 -352.541385) (xy 234.036589 -352.582922)
			(xy 233.993721 -352.618597) (xy 233.946115 -352.647651) (xy 233.894786 -352.669463) (xy 233.840829 -352.683569)
			(xy 233.785392 -352.689669) (xy 233.729658 -352.687632) (xy 233.674815 -352.677502) (xy 233.622031 -352.659495)
			(xy 233.572431 -352.633994) (xy 233.527073 -352.601543) (xy 233.486924 -352.562834) (xy 233.452838 -352.518691)
			(xy 233.425542 -352.470056) (xy 233.405619 -352.417965) (xy 233.393493 -352.363528) (xy 233.389422 -352.307906)
			(xy 195.68033 -352.307906) (xy 195.68033 -353.270058) (xy 236.132368 -353.270058) (xy 236.136439 -353.214436)
			(xy 236.148565 -353.159999) (xy 236.168488 -353.107908) (xy 236.195784 -353.059273) (xy 236.22987 -353.01513)
			(xy 236.270019 -352.976421) (xy 236.315377 -352.94397) (xy 236.364977 -352.918469) (xy 236.417761 -352.900462)
			(xy 236.472604 -352.890332) (xy 236.528338 -352.888295) (xy 236.583775 -352.894395) (xy 236.637732 -352.908501)
			(xy 236.689061 -352.930313) (xy 236.736667 -352.959367) (xy 236.779535 -352.995042) (xy 236.816752 -353.036579)
			(xy 236.847525 -353.083092) (xy 236.871197 -353.133589) (xy 236.887265 -353.186996) (xy 236.895385 -353.242172)
			(xy 236.895894 -353.270058) (xy 236.895385 -353.297944) (xy 236.887265 -353.35312) (xy 236.873129 -353.400106)
			(xy 241.556538 -353.400106) (xy 241.560609 -353.344484) (xy 241.572735 -353.290047) (xy 241.592658 -353.237956)
			(xy 241.619954 -353.189321) (xy 241.65404 -353.145178) (xy 241.694189 -353.106469) (xy 241.739547 -353.074018)
			(xy 241.789147 -353.048517) (xy 241.841931 -353.03051) (xy 241.896774 -353.02038) (xy 241.952508 -353.018343)
			(xy 242.007945 -353.024443) (xy 242.061902 -353.038549) (xy 242.113231 -353.060361) (xy 242.160837 -353.089415)
			(xy 242.203705 -353.12509) (xy 242.240922 -353.166627) (xy 242.271695 -353.21314) (xy 242.295367 -353.263637)
			(xy 242.311435 -353.317044) (xy 242.319555 -353.37222) (xy 242.320064 -353.400106) (xy 242.319555 -353.427992)
			(xy 242.311435 -353.483168) (xy 242.295367 -353.536575) (xy 242.271695 -353.587072) (xy 242.240922 -353.633585)
			(xy 242.203705 -353.675122) (xy 242.160837 -353.710797) (xy 242.113231 -353.739851) (xy 242.061902 -353.761663)
			(xy 242.007945 -353.775769) (xy 241.952508 -353.781869) (xy 241.896774 -353.779832) (xy 241.841931 -353.769702)
			(xy 241.789147 -353.751695) (xy 241.739547 -353.726194) (xy 241.694189 -353.693743) (xy 241.65404 -353.655034)
			(xy 241.619954 -353.610891) (xy 241.592658 -353.562256) (xy 241.572735 -353.510165) (xy 241.560609 -353.455728)
			(xy 241.556538 -353.400106) (xy 236.873129 -353.400106) (xy 236.871197 -353.406527) (xy 236.847525 -353.457024)
			(xy 236.816752 -353.503537) (xy 236.779535 -353.545074) (xy 236.736667 -353.580749) (xy 236.689061 -353.609803)
			(xy 236.637732 -353.631615) (xy 236.583775 -353.645721) (xy 236.528338 -353.651821) (xy 236.472604 -353.649784)
			(xy 236.417761 -353.639654) (xy 236.364977 -353.621647) (xy 236.315377 -353.596146) (xy 236.270019 -353.563695)
			(xy 236.22987 -353.524986) (xy 236.195784 -353.480843) (xy 236.168488 -353.432208) (xy 236.148565 -353.380117)
			(xy 236.136439 -353.32568) (xy 236.132368 -353.270058) (xy 195.68033 -353.270058) (xy 195.68033 -354.235258)
			(xy 236.132368 -354.235258) (xy 236.136439 -354.179636) (xy 236.148565 -354.125199) (xy 236.168488 -354.073108)
			(xy 236.195784 -354.024473) (xy 236.22987 -353.98033) (xy 236.270019 -353.941621) (xy 236.315377 -353.90917)
			(xy 236.364977 -353.883669) (xy 236.417761 -353.865662) (xy 236.472604 -353.855532) (xy 236.528338 -353.853495)
			(xy 236.583775 -353.859595) (xy 236.637732 -353.873701) (xy 236.689061 -353.895513) (xy 236.696793 -353.900232)
			(xy 248.573288 -353.900232) (xy 248.577359 -353.84461) (xy 248.589485 -353.790173) (xy 248.609408 -353.738082)
			(xy 248.636704 -353.689447) (xy 248.67079 -353.645304) (xy 248.710939 -353.606595) (xy 248.756297 -353.574144)
			(xy 248.805897 -353.548643) (xy 248.858681 -353.530636) (xy 248.913524 -353.520506) (xy 248.969258 -353.518469)
			(xy 249.024695 -353.524569) (xy 249.078652 -353.538675) (xy 249.129981 -353.560487) (xy 249.177587 -353.589541)
			(xy 249.220455 -353.625216) (xy 249.257672 -353.666753) (xy 249.288445 -353.713266) (xy 249.312117 -353.763763)
			(xy 249.328185 -353.81717) (xy 249.336305 -353.872346) (xy 249.336814 -353.900232) (xy 249.336305 -353.928118)
			(xy 249.328185 -353.983294) (xy 249.312117 -354.036701) (xy 249.288445 -354.087198) (xy 249.257672 -354.133711)
			(xy 249.220455 -354.175248) (xy 249.177587 -354.210923) (xy 249.129981 -354.239977) (xy 249.078652 -354.261789)
			(xy 249.024695 -354.275895) (xy 248.969258 -354.281995) (xy 248.913524 -354.279958) (xy 248.858681 -354.269828)
			(xy 248.805897 -354.251821) (xy 248.756297 -354.22632) (xy 248.710939 -354.193869) (xy 248.67079 -354.15516)
			(xy 248.636704 -354.111017) (xy 248.609408 -354.062382) (xy 248.589485 -354.010291) (xy 248.577359 -353.955854)
			(xy 248.573288 -353.900232) (xy 236.696793 -353.900232) (xy 236.736667 -353.924567) (xy 236.779535 -353.960242)
			(xy 236.816752 -354.001779) (xy 236.847525 -354.048292) (xy 236.871197 -354.098789) (xy 236.887265 -354.152196)
			(xy 236.895385 -354.207372) (xy 236.895894 -354.235258) (xy 236.895385 -354.263144) (xy 236.887265 -354.31832)
			(xy 236.871197 -354.371727) (xy 236.857894 -354.400104) (xy 241.526312 -354.400104) (xy 241.530383 -354.344482)
			(xy 241.542509 -354.290045) (xy 241.562432 -354.237954) (xy 241.589728 -354.189319) (xy 241.623814 -354.145176)
			(xy 241.663963 -354.106467) (xy 241.709321 -354.074016) (xy 241.758921 -354.048515) (xy 241.811705 -354.030508)
			(xy 241.866548 -354.020378) (xy 241.922282 -354.018341) (xy 241.977719 -354.024441) (xy 242.031676 -354.038547)
			(xy 242.083005 -354.060359) (xy 242.130611 -354.089413) (xy 242.173479 -354.125088) (xy 242.210696 -354.166625)
			(xy 242.241469 -354.213138) (xy 242.265141 -354.263635) (xy 242.281209 -354.317042) (xy 242.289329 -354.372218)
			(xy 242.289838 -354.400104) (xy 242.289329 -354.42799) (xy 242.281209 -354.483166) (xy 242.265141 -354.536573)
			(xy 242.241469 -354.58707) (xy 242.210696 -354.633583) (xy 242.173479 -354.67512) (xy 242.130611 -354.710795)
			(xy 242.083005 -354.739849) (xy 242.031676 -354.761661) (xy 241.977719 -354.775767) (xy 241.922282 -354.781867)
			(xy 241.866548 -354.77983) (xy 241.811705 -354.7697) (xy 241.758921 -354.751693) (xy 241.709321 -354.726192)
			(xy 241.663963 -354.693741) (xy 241.623814 -354.655032) (xy 241.589728 -354.610889) (xy 241.562432 -354.562254)
			(xy 241.542509 -354.510163) (xy 241.530383 -354.455726) (xy 241.526312 -354.400104) (xy 236.857894 -354.400104)
			(xy 236.847525 -354.422224) (xy 236.816752 -354.468737) (xy 236.779535 -354.510274) (xy 236.736667 -354.545949)
			(xy 236.689061 -354.575003) (xy 236.637732 -354.596815) (xy 236.583775 -354.610921) (xy 236.528338 -354.617021)
			(xy 236.472604 -354.614984) (xy 236.417761 -354.604854) (xy 236.364977 -354.586847) (xy 236.315377 -354.561346)
			(xy 236.270019 -354.528895) (xy 236.22987 -354.490186) (xy 236.195784 -354.446043) (xy 236.168488 -354.397408)
			(xy 236.148565 -354.345317) (xy 236.136439 -354.29088) (xy 236.132368 -354.235258) (xy 195.68033 -354.235258)
			(xy 195.68033 -355.01326) (xy 201.179174 -355.01326) (xy 201.183245 -354.957638) (xy 201.195371 -354.903201)
			(xy 201.215294 -354.85111) (xy 201.24259 -354.802475) (xy 201.276676 -354.758332) (xy 201.316825 -354.719623)
			(xy 201.362183 -354.687172) (xy 201.411783 -354.661671) (xy 201.464567 -354.643664) (xy 201.51941 -354.633534)
			(xy 201.575144 -354.631497) (xy 201.630581 -354.637597) (xy 201.684538 -354.651703) (xy 201.735867 -354.673515)
			(xy 201.783473 -354.702569) (xy 201.826341 -354.738244) (xy 201.863558 -354.779781) (xy 201.894331 -354.826294)
			(xy 201.918003 -354.876791) (xy 201.934071 -354.930198) (xy 201.942191 -354.985374) (xy 201.9427 -355.01326)
			(xy 201.942191 -355.041146) (xy 201.934071 -355.096322) (xy 201.918003 -355.149729) (xy 201.894331 -355.200226)
			(xy 201.894178 -355.200458) (xy 236.132368 -355.200458) (xy 236.136439 -355.144836) (xy 236.148565 -355.090399)
			(xy 236.168488 -355.038308) (xy 236.195784 -354.989673) (xy 236.22987 -354.94553) (xy 236.270019 -354.906821)
			(xy 236.315377 -354.87437) (xy 236.364977 -354.848869) (xy 236.417761 -354.830862) (xy 236.472604 -354.820732)
			(xy 236.528338 -354.818695) (xy 236.583775 -354.824795) (xy 236.637732 -354.838901) (xy 236.689061 -354.860713)
			(xy 236.736667 -354.889767) (xy 236.779535 -354.925442) (xy 236.816752 -354.966979) (xy 236.847525 -355.013492)
			(xy 236.871197 -355.063989) (xy 236.887265 -355.117396) (xy 236.895385 -355.172572) (xy 236.895894 -355.200458)
			(xy 238.265968 -355.200458) (xy 238.270039 -355.144836) (xy 238.282165 -355.090399) (xy 238.302088 -355.038308)
			(xy 238.329384 -354.989673) (xy 238.36347 -354.94553) (xy 238.403619 -354.906821) (xy 238.448977 -354.87437)
			(xy 238.498577 -354.848869) (xy 238.551361 -354.830862) (xy 238.606204 -354.820732) (xy 238.661938 -354.818695)
			(xy 238.717375 -354.824795) (xy 238.771332 -354.838901) (xy 238.822661 -354.860713) (xy 238.870267 -354.889767)
			(xy 238.88284 -354.90023) (xy 248.54992 -354.90023) (xy 248.553991 -354.844608) (xy 248.566117 -354.790171)
			(xy 248.58604 -354.73808) (xy 248.613336 -354.689445) (xy 248.647422 -354.645302) (xy 248.687571 -354.606593)
			(xy 248.732929 -354.574142) (xy 248.782529 -354.548641) (xy 248.835313 -354.530634) (xy 248.890156 -354.520504)
			(xy 248.94589 -354.518467) (xy 249.001327 -354.524567) (xy 249.055284 -354.538673) (xy 249.106613 -354.560485)
			(xy 249.154219 -354.589539) (xy 249.197087 -354.625214) (xy 249.234304 -354.666751) (xy 249.265077 -354.713264)
			(xy 249.288749 -354.763761) (xy 249.304817 -354.817168) (xy 249.312937 -354.872344) (xy 249.313446 -354.90023)
			(xy 249.312937 -354.928116) (xy 249.304817 -354.983292) (xy 249.288749 -355.036699) (xy 249.265077 -355.087196)
			(xy 249.234304 -355.133709) (xy 249.21 -355.160834) (xy 249.921774 -355.160834) (xy 249.925845 -355.105212)
			(xy 249.937971 -355.050775) (xy 249.957894 -354.998684) (xy 249.98519 -354.950049) (xy 250.019276 -354.905906)
			(xy 250.059425 -354.867197) (xy 250.104783 -354.834746) (xy 250.154383 -354.809245) (xy 250.207167 -354.791238)
			(xy 250.26201 -354.781108) (xy 250.317744 -354.779071) (xy 250.373181 -354.785171) (xy 250.427138 -354.799277)
			(xy 250.478467 -354.821089) (xy 250.526073 -354.850143) (xy 250.568941 -354.885818) (xy 250.606158 -354.927355)
			(xy 250.636931 -354.973868) (xy 250.660603 -355.024365) (xy 250.676671 -355.077772) (xy 250.684791 -355.132948)
			(xy 250.6853 -355.160834) (xy 250.684791 -355.18872) (xy 250.676671 -355.243896) (xy 250.660603 -355.297303)
			(xy 250.636931 -355.3478) (xy 250.606158 -355.394313) (xy 250.568941 -355.43585) (xy 250.526073 -355.471525)
			(xy 250.478467 -355.500579) (xy 250.427138 -355.522391) (xy 250.373181 -355.536497) (xy 250.317744 -355.542597)
			(xy 250.26201 -355.54056) (xy 250.207167 -355.53043) (xy 250.154383 -355.512423) (xy 250.104783 -355.486922)
			(xy 250.059425 -355.454471) (xy 250.019276 -355.415762) (xy 249.98519 -355.371619) (xy 249.957894 -355.322984)
			(xy 249.937971 -355.270893) (xy 249.925845 -355.216456) (xy 249.921774 -355.160834) (xy 249.21 -355.160834)
			(xy 249.197087 -355.175246) (xy 249.154219 -355.210921) (xy 249.106613 -355.239975) (xy 249.055284 -355.261787)
			(xy 249.001327 -355.275893) (xy 248.94589 -355.281993) (xy 248.890156 -355.279956) (xy 248.835313 -355.269826)
			(xy 248.782529 -355.251819) (xy 248.732929 -355.226318) (xy 248.687571 -355.193867) (xy 248.647422 -355.155158)
			(xy 248.613336 -355.111015) (xy 248.58604 -355.06238) (xy 248.566117 -355.010289) (xy 248.553991 -354.955852)
			(xy 248.54992 -354.90023) (xy 238.88284 -354.90023) (xy 238.913135 -354.925442) (xy 238.950352 -354.966979)
			(xy 238.981125 -355.013492) (xy 239.004797 -355.063989) (xy 239.020865 -355.117396) (xy 239.028985 -355.172572)
			(xy 239.029494 -355.200458) (xy 239.028985 -355.228344) (xy 239.020865 -355.28352) (xy 239.004797 -355.336927)
			(xy 238.981125 -355.387424) (xy 238.950352 -355.433937) (xy 238.913135 -355.475474) (xy 238.870267 -355.511149)
			(xy 238.822661 -355.540203) (xy 238.771332 -355.562015) (xy 238.717375 -355.576121) (xy 238.661938 -355.582221)
			(xy 238.606204 -355.580184) (xy 238.551361 -355.570054) (xy 238.498577 -355.552047) (xy 238.448977 -355.526546)
			(xy 238.403619 -355.494095) (xy 238.36347 -355.455386) (xy 238.329384 -355.411243) (xy 238.302088 -355.362608)
			(xy 238.282165 -355.310517) (xy 238.270039 -355.25608) (xy 238.265968 -355.200458) (xy 236.895894 -355.200458)
			(xy 236.895385 -355.228344) (xy 236.887265 -355.28352) (xy 236.871197 -355.336927) (xy 236.847525 -355.387424)
			(xy 236.816752 -355.433937) (xy 236.779535 -355.475474) (xy 236.736667 -355.511149) (xy 236.689061 -355.540203)
			(xy 236.637732 -355.562015) (xy 236.583775 -355.576121) (xy 236.528338 -355.582221) (xy 236.472604 -355.580184)
			(xy 236.417761 -355.570054) (xy 236.364977 -355.552047) (xy 236.315377 -355.526546) (xy 236.270019 -355.494095)
			(xy 236.22987 -355.455386) (xy 236.195784 -355.411243) (xy 236.168488 -355.362608) (xy 236.148565 -355.310517)
			(xy 236.136439 -355.25608) (xy 236.132368 -355.200458) (xy 201.894178 -355.200458) (xy 201.863558 -355.246739)
			(xy 201.826341 -355.288276) (xy 201.783473 -355.323951) (xy 201.735867 -355.353005) (xy 201.684538 -355.374817)
			(xy 201.630581 -355.388923) (xy 201.575144 -355.395023) (xy 201.51941 -355.392986) (xy 201.464567 -355.382856)
			(xy 201.411783 -355.364849) (xy 201.362183 -355.339348) (xy 201.316825 -355.306897) (xy 201.276676 -355.268188)
			(xy 201.24259 -355.224045) (xy 201.215294 -355.17541) (xy 201.195371 -355.123319) (xy 201.183245 -355.068882)
			(xy 201.179174 -355.01326) (xy 195.68033 -355.01326) (xy 195.68033 -355.701854) (xy 195.679898 -355.711921)
			(xy 195.672173 -355.730514) (xy 195.665344 -355.737922) (xy 195.381372 -356.021894) (xy 205.409798 -356.021894)
			(xy 205.413869 -355.966272) (xy 205.425995 -355.911835) (xy 205.445918 -355.859744) (xy 205.473214 -355.811109)
			(xy 205.5073 -355.766966) (xy 205.547449 -355.728257) (xy 205.592807 -355.695806) (xy 205.642407 -355.670305)
			(xy 205.695191 -355.652298) (xy 205.750034 -355.642168) (xy 205.805768 -355.640131) (xy 205.861205 -355.646231)
			(xy 205.915162 -355.660337) (xy 205.966491 -355.682149) (xy 206.014097 -355.711203) (xy 206.056965 -355.746878)
			(xy 206.094182 -355.788415) (xy 206.124955 -355.834928) (xy 206.148627 -355.885425) (xy 206.164695 -355.938832)
			(xy 206.172815 -355.994008) (xy 206.173324 -356.021894) (xy 206.172815 -356.04978) (xy 206.164695 -356.104956)
			(xy 206.148627 -356.158363) (xy 206.145207 -356.165658) (xy 236.132368 -356.165658) (xy 236.136439 -356.110036)
			(xy 236.148565 -356.055599) (xy 236.168488 -356.003508) (xy 236.195784 -355.954873) (xy 236.22987 -355.91073)
			(xy 236.270019 -355.872021) (xy 236.315377 -355.83957) (xy 236.364977 -355.814069) (xy 236.417761 -355.796062)
			(xy 236.472604 -355.785932) (xy 236.528338 -355.783895) (xy 236.583775 -355.789995) (xy 236.637732 -355.804101)
			(xy 236.689061 -355.825913) (xy 236.736667 -355.854967) (xy 236.779535 -355.890642) (xy 236.816752 -355.932179)
			(xy 236.847525 -355.978692) (xy 236.871197 -356.029189) (xy 236.887265 -356.082596) (xy 236.895385 -356.137772)
			(xy 236.895894 -356.165658) (xy 238.265968 -356.165658) (xy 238.270039 -356.110036) (xy 238.282165 -356.055599)
			(xy 238.302088 -356.003508) (xy 238.329384 -355.954873) (xy 238.36347 -355.91073) (xy 238.403619 -355.872021)
			(xy 238.448977 -355.83957) (xy 238.498577 -355.814069) (xy 238.551361 -355.796062) (xy 238.606204 -355.785932)
			(xy 238.661938 -355.783895) (xy 238.717375 -355.789995) (xy 238.771332 -355.804101) (xy 238.822661 -355.825913)
			(xy 238.870267 -355.854967) (xy 238.913135 -355.890642) (xy 238.950352 -355.932179) (xy 238.981125 -355.978692)
			(xy 239.004797 -356.029189) (xy 239.008878 -356.042752) (xy 249.589499 -356.042752) (xy 249.589499 -355.988248)
			(xy 249.597257 -355.9343) (xy 249.612613 -355.882004) (xy 249.635256 -355.832427) (xy 249.664725 -355.786577)
			(xy 249.700419 -355.745388) (xy 249.741612 -355.709698) (xy 249.787466 -355.680235) (xy 249.837046 -355.657598)
			(xy 249.889343 -355.642247) (xy 249.943292 -355.634496) (xy 249.970544 -355.634036) (xy 249.99946 -355.634581)
			(xy 250.056631 -355.643302) (xy 250.11183 -355.660554) (xy 250.163792 -355.685941) (xy 250.211326 -355.71888)
			(xy 250.253344 -355.758618) (xy 250.271534 -355.781102) (xy 250.279136 -355.789915) (xy 250.30004 -355.800095)
			(xy 250.311666 -355.80066) (xy 250.391422 -355.80066) (xy 250.403056 -355.800133) (xy 250.423966 -355.789937)
			(xy 250.431554 -355.781102) (xy 250.449771 -355.758641) (xy 250.491786 -355.718904) (xy 250.539315 -355.685963)
			(xy 250.591271 -355.66057) (xy 250.646464 -355.643309) (xy 250.70363 -355.634574) (xy 250.732544 -355.634036)
			(xy 250.759796 -355.634437) (xy 250.813746 -355.642199) (xy 250.866041 -355.65756) (xy 250.915618 -355.680206)
			(xy 250.961469 -355.709677) (xy 251.002658 -355.745373) (xy 251.038349 -355.786567) (xy 251.067815 -355.83242)
			(xy 251.090455 -355.882) (xy 251.10581 -355.934298) (xy 251.113566 -355.988248) (xy 251.113566 -356.042752)
			(xy 251.10581 -356.096702) (xy 251.090455 -356.149) (xy 251.067815 -356.19858) (xy 251.038349 -356.244433)
			(xy 251.002658 -356.285627) (xy 250.961469 -356.321323) (xy 250.915618 -356.350794) (xy 250.866041 -356.37344)
			(xy 250.813746 -356.388801) (xy 250.759796 -356.396563) (xy 250.732544 -356.397052) (xy 250.703627 -356.39652)
			(xy 250.646456 -356.387797) (xy 250.591257 -356.370543) (xy 250.539294 -356.345154) (xy 250.49176 -356.312211)
			(xy 250.449744 -356.272471) (xy 250.431554 -356.249986) (xy 250.423959 -356.241166) (xy 250.403049 -356.23099)
			(xy 250.391422 -356.230428) (xy 250.311666 -356.230428) (xy 250.300032 -356.230952) (xy 250.279122 -356.241151)
			(xy 250.271534 -356.249986) (xy 250.25332 -356.27245) (xy 250.211306 -356.312187) (xy 250.163776 -356.345129)
			(xy 250.111819 -356.370521) (xy 250.056625 -356.387781) (xy 249.999459 -356.396515) (xy 249.970544 -356.397052)
			(xy 249.943292 -356.396504) (xy 249.889343 -356.388753) (xy 249.837046 -356.373402) (xy 249.787466 -356.350765)
			(xy 249.741612 -356.321302) (xy 249.700419 -356.285612) (xy 249.664725 -356.244423) (xy 249.635256 -356.198573)
			(xy 249.612613 -356.148996) (xy 249.597257 -356.0967) (xy 249.589499 -356.042752) (xy 239.008878 -356.042752)
			(xy 239.020865 -356.082596) (xy 239.028985 -356.137772) (xy 239.029494 -356.165658) (xy 239.028985 -356.193544)
			(xy 239.020865 -356.24872) (xy 239.004797 -356.302127) (xy 238.981125 -356.352624) (xy 238.950352 -356.399137)
			(xy 238.913135 -356.440674) (xy 238.870267 -356.476349) (xy 238.822661 -356.505403) (xy 238.771332 -356.527215)
			(xy 238.717375 -356.541321) (xy 238.661938 -356.547421) (xy 238.606204 -356.545384) (xy 238.551361 -356.535254)
			(xy 238.498577 -356.517247) (xy 238.448977 -356.491746) (xy 238.403619 -356.459295) (xy 238.36347 -356.420586)
			(xy 238.329384 -356.376443) (xy 238.302088 -356.327808) (xy 238.282165 -356.275717) (xy 238.270039 -356.22128)
			(xy 238.265968 -356.165658) (xy 236.895894 -356.165658) (xy 236.895385 -356.193544) (xy 236.887265 -356.24872)
			(xy 236.871197 -356.302127) (xy 236.847525 -356.352624) (xy 236.816752 -356.399137) (xy 236.779535 -356.440674)
			(xy 236.736667 -356.476349) (xy 236.689061 -356.505403) (xy 236.637732 -356.527215) (xy 236.583775 -356.541321)
			(xy 236.528338 -356.547421) (xy 236.472604 -356.545384) (xy 236.417761 -356.535254) (xy 236.364977 -356.517247)
			(xy 236.315377 -356.491746) (xy 236.270019 -356.459295) (xy 236.22987 -356.420586) (xy 236.195784 -356.376443)
			(xy 236.168488 -356.327808) (xy 236.148565 -356.275717) (xy 236.136439 -356.22128) (xy 236.132368 -356.165658)
			(xy 206.145207 -356.165658) (xy 206.124955 -356.20886) (xy 206.094182 -356.255373) (xy 206.056965 -356.29691)
			(xy 206.014097 -356.332585) (xy 205.966491 -356.361639) (xy 205.915162 -356.383451) (xy 205.861205 -356.397557)
			(xy 205.805768 -356.403657) (xy 205.750034 -356.40162) (xy 205.695191 -356.39149) (xy 205.642407 -356.373483)
			(xy 205.592807 -356.347982) (xy 205.547449 -356.315531) (xy 205.5073 -356.276822) (xy 205.473214 -356.232679)
			(xy 205.445918 -356.184044) (xy 205.425995 -356.131953) (xy 205.413869 -356.077516) (xy 205.409798 -356.021894)
			(xy 195.381372 -356.021894) (xy 193.326766 -358.0765) (xy 193.3194 -358.083612) (xy 193.312288 -358.10063)
			(xy 193.311526 -358.10825) (xy 193.30679 -358.150201) (xy 193.291067 -358.233153) (xy 193.268325 -358.314462)
			(xy 193.238729 -358.393535) (xy 193.202496 -358.469794) (xy 193.159889 -358.542685) (xy 193.11122 -358.611675)
			(xy 193.056843 -358.676262) (xy 193.0273 -358.70642) (xy 192.870328 -358.863392) (xy 197.77913 -358.863392)
			(xy 197.783201 -358.80777) (xy 197.795327 -358.753333) (xy 197.81525 -358.701242) (xy 197.842546 -358.652607)
			(xy 197.876632 -358.608464) (xy 197.916781 -358.569755) (xy 197.962139 -358.537304) (xy 198.011739 -358.511803)
			(xy 198.064523 -358.493796) (xy 198.119366 -358.483666) (xy 198.1751 -358.481629) (xy 198.230537 -358.487729)
			(xy 198.284494 -358.501835) (xy 198.335823 -358.523647) (xy 198.383429 -358.552701) (xy 198.426297 -358.588376)
			(xy 198.463514 -358.629913) (xy 198.494287 -358.676426) (xy 198.517959 -358.726923) (xy 198.534027 -358.78033)
			(xy 198.542147 -358.835506) (xy 198.542656 -358.863392) (xy 198.542147 -358.891278) (xy 198.534027 -358.946454)
			(xy 198.517959 -358.999861) (xy 198.494287 -359.050358) (xy 198.463514 -359.096871) (xy 198.426297 -359.138408)
			(xy 198.383429 -359.174083) (xy 198.335823 -359.203137) (xy 198.284494 -359.224949) (xy 198.230537 -359.239055)
			(xy 198.1751 -359.245155) (xy 198.119366 -359.243118) (xy 198.064523 -359.232988) (xy 198.011739 -359.214981)
			(xy 197.962139 -359.18948) (xy 197.916781 -359.157029) (xy 197.876632 -359.11832) (xy 197.842546 -359.074177)
			(xy 197.81525 -359.025542) (xy 197.795327 -358.973451) (xy 197.783201 -358.919014) (xy 197.77913 -358.863392)
			(xy 192.870328 -358.863392) (xy 186.615768 -365.117952) (xy 194.110065 -365.117952) (xy 194.110065 -365.063448)
			(xy 194.117822 -365.009498) (xy 194.133178 -364.957201) (xy 194.15582 -364.907622) (xy 194.185287 -364.86177)
			(xy 194.22098 -364.820579) (xy 194.262172 -364.784886) (xy 194.308024 -364.755419) (xy 194.357603 -364.732777)
			(xy 194.4099 -364.717422) (xy 194.46385 -364.709665) (xy 194.491102 -364.709202) (xy 194.517968 -364.709649)
			(xy 194.571169 -364.717189) (xy 194.622786 -364.732119) (xy 194.671797 -364.754143) (xy 194.717233 -364.782827)
			(xy 194.758194 -364.817602) (xy 194.793871 -364.857781) (xy 194.823558 -364.902568) (xy 194.835526 -364.926626)
			(xy 194.842292 -364.939646) (xy 194.861922 -364.961438) (xy 194.886936 -364.976752) (xy 194.915271 -364.984326)
			(xy 194.94459 -364.983533) (xy 194.972474 -364.974441) (xy 194.996625 -364.957798) (xy 195.006214 -364.946692)
			(xy 195.024426 -364.92493) (xy 195.066198 -364.886523) (xy 195.113199 -364.854729) (xy 195.164393 -364.830249)
			(xy 195.218648 -364.813626) (xy 195.274767 -364.805224) (xy 195.30314 -364.804706) (xy 195.33039 -364.805167)
			(xy 195.384336 -364.812928) (xy 195.436628 -364.828287) (xy 195.486202 -364.850931) (xy 195.532049 -364.8804)
			(xy 195.573236 -364.916093) (xy 195.608924 -364.957283) (xy 195.638388 -365.003134) (xy 195.661027 -365.05271)
			(xy 195.676381 -365.105003) (xy 195.684136 -365.15895) (xy 195.684136 -365.21345) (xy 195.676381 -365.267397)
			(xy 195.661027 -365.31969) (xy 195.638388 -365.369266) (xy 195.608924 -365.415117) (xy 195.573236 -365.456307)
			(xy 195.532049 -365.492) (xy 195.486202 -365.521469) (xy 195.436628 -365.544113) (xy 195.384336 -365.559472)
			(xy 195.33039 -365.567233) (xy 195.30314 -365.567722) (xy 195.276276 -365.567226) (xy 195.223077 -365.559693)
			(xy 195.171463 -365.544769) (xy 195.122453 -365.522751) (xy 195.077017 -365.494074) (xy 195.036054 -365.459306)
			(xy 195.000375 -365.419134) (xy 194.970686 -365.374353) (xy 194.958716 -365.350298) (xy 194.951897 -365.337311)
			(xy 194.932271 -365.315537) (xy 194.907268 -365.300233) (xy 194.878948 -365.292662) (xy 194.849644 -365.293446)
			(xy 194.82177 -365.302521) (xy 194.797621 -365.319139) (xy 194.788028 -365.330232) (xy 194.769799 -365.351979)
			(xy 194.72803 -365.390387) (xy 194.681032 -365.422182) (xy 194.629842 -365.446663) (xy 194.57559 -365.463291)
			(xy 194.519473 -365.471698) (xy 194.491102 -365.472218) (xy 194.46385 -365.471735) (xy 194.4099 -365.463978)
			(xy 194.357603 -365.448623) (xy 194.308024 -365.425981) (xy 194.262172 -365.396514) (xy 194.22098 -365.360821)
			(xy 194.185287 -365.31963) (xy 194.15582 -365.273778) (xy 194.133178 -365.224199) (xy 194.117822 -365.171902)
			(xy 194.110065 -365.117952) (xy 186.615768 -365.117952) (xy 185.903616 -365.830104) (xy 192.759074 -365.830104)
			(xy 192.763145 -365.774482) (xy 192.775271 -365.720045) (xy 192.795194 -365.667954) (xy 192.82249 -365.619319)
			(xy 192.856576 -365.575176) (xy 192.896725 -365.536467) (xy 192.942083 -365.504016) (xy 192.991683 -365.478515)
			(xy 193.044467 -365.460508) (xy 193.09931 -365.450378) (xy 193.155044 -365.448341) (xy 193.210481 -365.454441)
			(xy 193.264438 -365.468547) (xy 193.315767 -365.490359) (xy 193.363373 -365.519413) (xy 193.406241 -365.555088)
			(xy 193.443458 -365.596625) (xy 193.474231 -365.643138) (xy 193.497903 -365.693635) (xy 193.513971 -365.747042)
			(xy 193.522091 -365.802218) (xy 193.5226 -365.830104) (xy 193.522091 -365.85799) (xy 193.513971 -365.913166)
			(xy 193.497903 -365.966573) (xy 193.474231 -366.01707) (xy 193.443458 -366.063583) (xy 193.406241 -366.10512)
			(xy 193.363373 -366.140795) (xy 193.315767 -366.169849) (xy 193.264438 -366.191661) (xy 193.210481 -366.205767)
			(xy 193.155044 -366.211867) (xy 193.09931 -366.20983) (xy 193.044467 -366.1997) (xy 192.991683 -366.181693)
			(xy 192.942083 -366.156192) (xy 192.896725 -366.123741) (xy 192.856576 -366.085032) (xy 192.82249 -366.040889)
			(xy 192.795194 -365.992254) (xy 192.775271 -365.940163) (xy 192.763145 -365.885726) (xy 192.759074 -365.830104)
			(xy 185.903616 -365.830104) (xy 185.10377 -366.62995) (xy 185.078041 -366.655096) (xy 191.396872 -366.655096)
			(xy 191.400943 -366.599474) (xy 191.413069 -366.545037) (xy 191.432992 -366.492946) (xy 191.460288 -366.444311)
			(xy 191.494374 -366.400168) (xy 191.534523 -366.361459) (xy 191.579881 -366.329008) (xy 191.629481 -366.303507)
			(xy 191.682265 -366.2855) (xy 191.737108 -366.27537) (xy 191.792842 -366.273333) (xy 191.848279 -366.279433)
			(xy 191.902236 -366.293539) (xy 191.953565 -366.315351) (xy 192.001171 -366.344405) (xy 192.044039 -366.38008)
			(xy 192.081256 -366.421617) (xy 192.112029 -366.46813) (xy 192.135701 -366.518627) (xy 192.151769 -366.572034)
			(xy 192.159889 -366.62721) (xy 192.160398 -366.655096) (xy 192.159889 -366.682982) (xy 192.151769 -366.738158)
			(xy 192.135701 -366.791565) (xy 192.112029 -366.842062) (xy 192.081256 -366.888575) (xy 192.044039 -366.930112)
			(xy 192.001171 -366.965787) (xy 191.953565 -366.994841) (xy 191.902236 -367.016653) (xy 191.848279 -367.030759)
			(xy 191.792842 -367.036859) (xy 191.737108 -367.034822) (xy 191.682265 -367.024692) (xy 191.629481 -367.006685)
			(xy 191.579881 -366.981184) (xy 191.534523 -366.948733) (xy 191.494374 -366.910024) (xy 191.460288 -366.865881)
			(xy 191.432992 -366.817246) (xy 191.413069 -366.765155) (xy 191.400943 -366.710718) (xy 191.396872 -366.655096)
			(xy 185.078041 -366.655096) (xy 185.072475 -366.660536) (xy 185.005344 -366.71668) (xy 184.933516 -366.766674)
			(xy 184.857552 -366.810126) (xy 184.778045 -366.846696) (xy 184.736994 -366.861852) (xy 184.437274 -366.96904)
			(xy 184.430924 -366.973866) (xy 184.425336 -366.97793) (xy 183.911494 -367.491772) (xy 195.59346 -367.491772)
			(xy 195.597531 -367.43615) (xy 195.609657 -367.381713) (xy 195.62958 -367.329622) (xy 195.656876 -367.280987)
			(xy 195.690962 -367.236844) (xy 195.731111 -367.198135) (xy 195.776469 -367.165684) (xy 195.826069 -367.140183)
			(xy 195.878853 -367.122176) (xy 195.933696 -367.112046) (xy 195.98943 -367.110009) (xy 196.044867 -367.116109)
			(xy 196.098824 -367.130215) (xy 196.150153 -367.152027) (xy 196.197759 -367.181081) (xy 196.240627 -367.216756)
			(xy 196.277844 -367.258293) (xy 196.308617 -367.304806) (xy 196.332289 -367.355303) (xy 196.348357 -367.40871)
			(xy 196.356477 -367.463886) (xy 196.356986 -367.491772) (xy 196.356477 -367.519658) (xy 196.348357 -367.574834)
			(xy 196.332289 -367.628241) (xy 196.308617 -367.678738) (xy 196.277844 -367.725251) (xy 196.240627 -367.766788)
			(xy 196.197759 -367.802463) (xy 196.150153 -367.831517) (xy 196.098824 -367.853329) (xy 196.044867 -367.867435)
			(xy 195.98943 -367.873535) (xy 195.933696 -367.871498) (xy 195.878853 -367.861368) (xy 195.826069 -367.843361)
			(xy 195.776469 -367.81786) (xy 195.731111 -367.785409) (xy 195.690962 -367.7467) (xy 195.656876 -367.702557)
			(xy 195.62958 -367.653922) (xy 195.609657 -367.601831) (xy 195.597531 -367.547394) (xy 195.59346 -367.491772)
			(xy 183.911494 -367.491772) (xy 182.263542 -369.139724) (xy 194.89623 -369.139724) (xy 194.900301 -369.084102)
			(xy 194.912427 -369.029665) (xy 194.93235 -368.977574) (xy 194.959646 -368.928939) (xy 194.993732 -368.884796)
			(xy 195.033881 -368.846087) (xy 195.079239 -368.813636) (xy 195.128839 -368.788135) (xy 195.181623 -368.770128)
			(xy 195.236466 -368.759998) (xy 195.2922 -368.757961) (xy 195.347637 -368.764061) (xy 195.401594 -368.778167)
			(xy 195.452923 -368.799979) (xy 195.500529 -368.829033) (xy 195.543397 -368.864708) (xy 195.580614 -368.906245)
			(xy 195.611387 -368.952758) (xy 195.635059 -369.003255) (xy 195.651127 -369.056662) (xy 195.659247 -369.111838)
			(xy 195.659756 -369.139724) (xy 195.659247 -369.16761) (xy 195.651127 -369.222786) (xy 195.635059 -369.276193)
			(xy 195.611387 -369.32669) (xy 195.580614 -369.373203) (xy 195.543397 -369.41474) (xy 195.500529 -369.450415)
			(xy 195.452923 -369.479469) (xy 195.401594 -369.501281) (xy 195.347637 -369.515387) (xy 195.2922 -369.521487)
			(xy 195.236466 -369.51945) (xy 195.181623 -369.50932) (xy 195.128839 -369.491313) (xy 195.079239 -369.465812)
			(xy 195.033881 -369.433361) (xy 194.993732 -369.394652) (xy 194.959646 -369.350509) (xy 194.93235 -369.301874)
			(xy 194.912427 -369.249783) (xy 194.900301 -369.195346) (xy 194.89623 -369.139724) (xy 182.263542 -369.139724)
			(xy 181.115462 -370.287804) (xy 181.110414 -370.292595) (xy 181.0983 -370.299435) (xy 181.091586 -370.301266)
			(xy 181.091332 -370.301266) (xy 181.084474 -370.303044) (xy 181.078886 -370.306092) (xy 181.06771 -370.314474)
			(xy 181.064408 -370.317776) (xy 181.061702 -370.320627) (xy 181.057109 -370.327005) (xy 181.055264 -370.330476)
			(xy 181.052682 -370.335903) (xy 181.049862 -370.347583) (xy 181.049676 -370.35359) (xy 181.049676 -370.529358)
			(xy 189.975488 -370.529358) (xy 189.979559 -370.473736) (xy 189.991685 -370.419299) (xy 190.011608 -370.367208)
			(xy 190.038904 -370.318573) (xy 190.07299 -370.27443) (xy 190.113139 -370.235721) (xy 190.158497 -370.20327)
			(xy 190.208097 -370.177769) (xy 190.260881 -370.159762) (xy 190.315724 -370.149632) (xy 190.371458 -370.147595)
			(xy 190.426895 -370.153695) (xy 190.480852 -370.167801) (xy 190.532181 -370.189613) (xy 190.579787 -370.218667)
			(xy 190.622655 -370.254342) (xy 190.659872 -370.295879) (xy 190.690645 -370.342392) (xy 190.714317 -370.392889)
			(xy 190.730385 -370.446296) (xy 190.738505 -370.501472) (xy 190.739014 -370.529358) (xy 190.738505 -370.557244)
			(xy 190.730385 -370.61242) (xy 190.714317 -370.665827) (xy 190.690645 -370.716324) (xy 190.659872 -370.762837)
			(xy 190.622655 -370.804374) (xy 190.579787 -370.840049) (xy 190.532181 -370.869103) (xy 190.480852 -370.890915)
			(xy 190.426895 -370.905021) (xy 190.371458 -370.911121) (xy 190.315724 -370.909084) (xy 190.260881 -370.898954)
			(xy 190.208097 -370.880947) (xy 190.158497 -370.855446) (xy 190.113139 -370.822995) (xy 190.07299 -370.784286)
			(xy 190.038904 -370.740143) (xy 190.011608 -370.691508) (xy 189.991685 -370.639417) (xy 189.979559 -370.58498)
			(xy 189.975488 -370.529358) (xy 181.049676 -370.529358) (xy 181.049676 -371.718586) (xy 200.353166 -371.718586)
			(xy 200.357237 -371.662964) (xy 200.369363 -371.608527) (xy 200.389286 -371.556436) (xy 200.416582 -371.507801)
			(xy 200.450668 -371.463658) (xy 200.490817 -371.424949) (xy 200.536175 -371.392498) (xy 200.585775 -371.366997)
			(xy 200.638559 -371.34899) (xy 200.693402 -371.33886) (xy 200.749136 -371.336823) (xy 200.804573 -371.342923)
			(xy 200.85853 -371.357029) (xy 200.909859 -371.378841) (xy 200.957465 -371.407895) (xy 201.000333 -371.44357)
			(xy 201.03755 -371.485107) (xy 201.068323 -371.53162) (xy 201.091995 -371.582117) (xy 201.108063 -371.635524)
			(xy 201.116183 -371.6907) (xy 201.116692 -371.718586) (xy 201.116183 -371.746472) (xy 201.108063 -371.801648)
			(xy 201.091995 -371.855055) (xy 201.070358 -371.901212) (xy 201.295252 -371.901212) (xy 201.299323 -371.84559)
			(xy 201.311449 -371.791153) (xy 201.331372 -371.739062) (xy 201.358668 -371.690427) (xy 201.392754 -371.646284)
			(xy 201.432903 -371.607575) (xy 201.478261 -371.575124) (xy 201.527861 -371.549623) (xy 201.580645 -371.531616)
			(xy 201.635488 -371.521486) (xy 201.691222 -371.519449) (xy 201.746659 -371.525549) (xy 201.800616 -371.539655)
			(xy 201.851945 -371.561467) (xy 201.899551 -371.590521) (xy 201.942419 -371.626196) (xy 201.979636 -371.667733)
			(xy 202.010409 -371.714246) (xy 202.034081 -371.764743) (xy 202.050149 -371.81815) (xy 202.058269 -371.873326)
			(xy 202.058778 -371.901212) (xy 202.058269 -371.929098) (xy 202.050149 -371.984274) (xy 202.034081 -372.037681)
			(xy 202.010409 -372.088178) (xy 201.979636 -372.134691) (xy 201.942419 -372.176228) (xy 201.899551 -372.211903)
			(xy 201.851945 -372.240957) (xy 201.800616 -372.262769) (xy 201.746659 -372.276875) (xy 201.691222 -372.282975)
			(xy 201.635488 -372.280938) (xy 201.580645 -372.270808) (xy 201.527861 -372.252801) (xy 201.478261 -372.2273)
			(xy 201.432903 -372.194849) (xy 201.392754 -372.15614) (xy 201.358668 -372.111997) (xy 201.331372 -372.063362)
			(xy 201.311449 -372.011271) (xy 201.299323 -371.956834) (xy 201.295252 -371.901212) (xy 201.070358 -371.901212)
			(xy 201.068323 -371.905552) (xy 201.03755 -371.952065) (xy 201.000333 -371.993602) (xy 200.957465 -372.029277)
			(xy 200.909859 -372.058331) (xy 200.85853 -372.080143) (xy 200.804573 -372.094249) (xy 200.749136 -372.100349)
			(xy 200.693402 -372.098312) (xy 200.638559 -372.088182) (xy 200.585775 -372.070175) (xy 200.536175 -372.044674)
			(xy 200.490817 -372.012223) (xy 200.450668 -371.973514) (xy 200.416582 -371.929371) (xy 200.389286 -371.880736)
			(xy 200.369363 -371.828645) (xy 200.357237 -371.774208) (xy 200.353166 -371.718586) (xy 181.049676 -371.718586)
			(xy 181.049676 -372.842282) (xy 202.077574 -372.842282) (xy 202.07806 -372.815031) (xy 202.085816 -372.761083)
			(xy 202.101171 -372.708788) (xy 202.123813 -372.659211) (xy 202.153279 -372.613361) (xy 202.18897 -372.57217)
			(xy 202.230161 -372.536479) (xy 202.276011 -372.507013) (xy 202.325588 -372.484371) (xy 202.377883 -372.469016)
			(xy 202.431831 -372.46126) (xy 202.486333 -372.46126) (xy 202.540281 -372.469016) (xy 202.592576 -372.484371)
			(xy 202.642153 -372.507013) (xy 202.688003 -372.536479) (xy 202.729194 -372.57217) (xy 202.764885 -372.613361)
			(xy 202.794351 -372.659211) (xy 202.816993 -372.708788) (xy 202.832348 -372.761083) (xy 202.840104 -372.815031)
			(xy 202.84059 -372.842282) (xy 202.840062 -372.870014) (xy 202.832039 -372.924894) (xy 202.816158 -372.978036)
			(xy 202.792755 -373.02832) (xy 202.762321 -373.074688) (xy 202.725498 -373.116164) (xy 202.68306 -373.151875)
			(xy 202.659742 -373.166894) (xy 202.648228 -373.174553) (xy 202.629458 -373.194843) (xy 202.616827 -373.219429)
			(xy 202.611264 -373.246504) (xy 202.613177 -373.274078) (xy 202.622425 -373.300125) (xy 202.638329 -373.322731)
			(xy 202.659721 -373.340235) (xy 202.672188 -373.346218) (xy 202.697276 -373.357729) (xy 202.744091 -373.38697)
			(xy 202.786202 -373.422656) (xy 202.822729 -373.464039) (xy 202.852908 -373.510256) (xy 202.87611 -373.56034)
			(xy 202.891849 -373.613247) (xy 202.899796 -373.667869) (xy 202.90028 -373.695468) (xy 202.899794 -373.722719)
			(xy 202.892038 -373.776667) (xy 202.876683 -373.828962) (xy 202.854041 -373.878539) (xy 202.824575 -373.924389)
			(xy 202.788884 -373.96558) (xy 202.747693 -374.001271) (xy 202.701843 -374.030737) (xy 202.652266 -374.053379)
			(xy 202.599971 -374.068734) (xy 202.546023 -374.07649) (xy 202.491521 -374.07649) (xy 202.437573 -374.068734)
			(xy 202.385278 -374.053379) (xy 202.335701 -374.030737) (xy 202.289851 -374.001271) (xy 202.24866 -373.96558)
			(xy 202.212969 -373.924389) (xy 202.183503 -373.878539) (xy 202.160861 -373.828962) (xy 202.145506 -373.776667)
			(xy 202.13775 -373.722719) (xy 202.137264 -373.695468) (xy 202.137727 -373.667734) (xy 202.145759 -373.612849)
			(xy 202.161649 -373.559705) (xy 202.185063 -373.50942) (xy 202.215507 -373.463052) (xy 202.252341 -373.421579)
			(xy 202.294789 -373.385872) (xy 202.318112 -373.370856) (xy 202.329666 -373.363257) (xy 202.348428 -373.342952)
			(xy 202.36105 -373.318355) (xy 202.366606 -373.291273) (xy 202.364687 -373.263693) (xy 202.355434 -373.237641)
			(xy 202.339527 -373.21503) (xy 202.318134 -373.197519) (xy 202.305666 -373.191532) (xy 202.28061 -373.179956)
			(xy 202.233794 -373.150725) (xy 202.191681 -373.11505) (xy 202.155151 -373.073677) (xy 202.124967 -373.027469)
			(xy 202.101761 -372.977393) (xy 202.086016 -372.924494) (xy 202.078061 -372.869878) (xy 202.077574 -372.842282)
			(xy 181.049676 -372.842282) (xy 181.049676 -374.826022) (xy 202.643738 -374.826022) (xy 202.647809 -374.7704)
			(xy 202.659935 -374.715963) (xy 202.679858 -374.663872) (xy 202.707154 -374.615237) (xy 202.74124 -374.571094)
			(xy 202.781389 -374.532385) (xy 202.826747 -374.499934) (xy 202.876347 -374.474433) (xy 202.929131 -374.456426)
			(xy 202.983974 -374.446296) (xy 203.039708 -374.444259) (xy 203.095145 -374.450359) (xy 203.149102 -374.464465)
			(xy 203.200431 -374.486277) (xy 203.248037 -374.515331) (xy 203.290905 -374.551006) (xy 203.328122 -374.592543)
			(xy 203.358895 -374.639056) (xy 203.382567 -374.689553) (xy 203.398635 -374.74296) (xy 203.406755 -374.798136)
			(xy 203.407264 -374.826022) (xy 203.406755 -374.853908) (xy 203.398635 -374.909084) (xy 203.382567 -374.962491)
			(xy 203.358895 -375.012988) (xy 203.328122 -375.059501) (xy 203.290905 -375.101038) (xy 203.248037 -375.136713)
			(xy 203.200431 -375.165767) (xy 203.149102 -375.187579) (xy 203.095145 -375.201685) (xy 203.039708 -375.207785)
			(xy 202.983974 -375.205748) (xy 202.929131 -375.195618) (xy 202.876347 -375.177611) (xy 202.826747 -375.15211)
			(xy 202.781389 -375.119659) (xy 202.74124 -375.08095) (xy 202.707154 -375.036807) (xy 202.679858 -374.988172)
			(xy 202.659935 -374.936081) (xy 202.647809 -374.881644) (xy 202.643738 -374.826022) (xy 181.049676 -374.826022)
			(xy 181.049676 -377.383802) (xy 181.050692 -377.393454) (xy 181.052319 -377.400699) (xy 181.059156 -377.413871)
			(xy 181.064154 -377.419362) (xy 181.241192 -377.5964) (xy 181.248039 -377.603798) (xy 181.255775 -377.622396)
			(xy 181.256178 -377.632468) (xy 181.256178 -378.766811) (xy 193.48983 -378.766811) (xy 193.48983 -378.633249)
			(xy 193.497894 -378.499931) (xy 193.513994 -378.367343) (xy 193.538069 -378.235969) (xy 193.570032 -378.106288)
			(xy 193.609767 -377.978774) (xy 193.657129 -377.853891) (xy 193.711944 -377.732096) (xy 193.774014 -377.613833)
			(xy 193.84311 -377.499534) (xy 193.918982 -377.389614) (xy 194.001352 -377.284477) (xy 194.08992 -377.184504)
			(xy 194.184362 -377.090062) (xy 194.284335 -377.001494) (xy 194.389472 -376.919124) (xy 194.499392 -376.843252)
			(xy 194.613691 -376.774156) (xy 194.731954 -376.712086) (xy 194.853749 -376.657271) (xy 194.978632 -376.609909)
			(xy 195.106146 -376.570174) (xy 195.235827 -376.538211) (xy 195.367201 -376.514136) (xy 195.499789 -376.498036)
			(xy 195.633107 -376.489972) (xy 195.766669 -376.489972) (xy 195.899987 -376.498036) (xy 196.032575 -376.514136)
			(xy 196.163949 -376.538211) (xy 196.29363 -376.570174) (xy 196.421144 -376.609909) (xy 196.546027 -376.657271)
			(xy 196.667822 -376.712086) (xy 196.786085 -376.774156) (xy 196.900384 -376.843252) (xy 197.010304 -376.919124)
			(xy 197.115441 -377.001494) (xy 197.215414 -377.090062) (xy 197.309856 -377.184504) (xy 197.398424 -377.284477)
			(xy 197.480794 -377.389614) (xy 197.556666 -377.499534) (xy 197.625762 -377.613833) (xy 197.687832 -377.732096)
			(xy 197.742647 -377.853891) (xy 197.790009 -377.978774) (xy 197.829744 -378.106288) (xy 197.861707 -378.235969)
			(xy 197.885782 -378.367343) (xy 197.901882 -378.499931) (xy 197.909946 -378.633249) (xy 197.91045 -378.70003)
			(xy 197.909946 -378.766811) (xy 197.901882 -378.900129) (xy 197.885782 -379.032717) (xy 197.861707 -379.164091)
			(xy 197.829744 -379.293772) (xy 197.790009 -379.421286) (xy 197.742647 -379.546169) (xy 197.687832 -379.667964)
			(xy 197.625762 -379.786227) (xy 197.556666 -379.900526) (xy 197.480794 -380.010446) (xy 197.398424 -380.115583)
			(xy 197.309856 -380.215556) (xy 197.215414 -380.309998) (xy 197.115441 -380.398566) (xy 197.010304 -380.480936)
			(xy 196.900384 -380.556808) (xy 196.786085 -380.625904) (xy 196.667822 -380.687974) (xy 196.546027 -380.742789)
			(xy 196.421144 -380.790151) (xy 196.29363 -380.829886) (xy 196.163949 -380.861849) (xy 196.032575 -380.885924)
			(xy 195.899987 -380.902024) (xy 195.766669 -380.910088) (xy 195.633107 -380.910088) (xy 195.499789 -380.902024)
			(xy 195.367201 -380.885924) (xy 195.235827 -380.861849) (xy 195.106146 -380.829886) (xy 194.978632 -380.790151)
			(xy 194.853749 -380.742789) (xy 194.731954 -380.687974) (xy 194.613691 -380.625904) (xy 194.499392 -380.556808)
			(xy 194.389472 -380.480936) (xy 194.284335 -380.398566) (xy 194.184362 -380.309998) (xy 194.08992 -380.215556)
			(xy 194.001352 -380.115583) (xy 193.918982 -380.010446) (xy 193.84311 -379.900526) (xy 193.774014 -379.786227)
			(xy 193.711944 -379.667964) (xy 193.657129 -379.546169) (xy 193.609767 -379.421286) (xy 193.570032 -379.293772)
			(xy 193.538069 -379.164091) (xy 193.513994 -379.032717) (xy 193.497894 -378.900129) (xy 193.48983 -378.766811)
			(xy 181.256178 -378.766811) (xy 181.256178 -387.124702) (xy 187.712602 -387.124702) (xy 187.716673 -387.06908)
			(xy 187.728799 -387.014643) (xy 187.748722 -386.962552) (xy 187.776018 -386.913917) (xy 187.810104 -386.869774)
			(xy 187.850253 -386.831065) (xy 187.895611 -386.798614) (xy 187.945211 -386.773113) (xy 187.997995 -386.755106)
			(xy 188.052838 -386.744976) (xy 188.108572 -386.742939) (xy 188.164009 -386.749039) (xy 188.217966 -386.763145)
			(xy 188.269295 -386.784957) (xy 188.316901 -386.814011) (xy 188.359769 -386.849686) (xy 188.396986 -386.891223)
			(xy 188.427759 -386.937736) (xy 188.451431 -386.988233) (xy 188.467499 -387.04164) (xy 188.475619 -387.096816)
			(xy 188.476128 -387.124702) (xy 188.475619 -387.152588) (xy 188.467499 -387.207764) (xy 188.451431 -387.261171)
			(xy 188.427759 -387.311668) (xy 188.396986 -387.358181) (xy 188.359769 -387.399718) (xy 188.316901 -387.435393)
			(xy 188.269295 -387.464447) (xy 188.217966 -387.486259) (xy 188.164009 -387.500365) (xy 188.108572 -387.506465)
			(xy 188.052838 -387.504428) (xy 187.997995 -387.494298) (xy 187.945211 -387.476291) (xy 187.895611 -387.45079)
			(xy 187.850253 -387.418339) (xy 187.810104 -387.37963) (xy 187.776018 -387.335487) (xy 187.748722 -387.286852)
			(xy 187.728799 -387.234761) (xy 187.716673 -387.180324) (xy 187.712602 -387.124702) (xy 181.256178 -387.124702)
			(xy 181.256178 -401.322286) (xy 181.255739 -401.332349) (xy 181.248 -401.350928) (xy 181.241192 -401.358354)
			(xy 180.940456 -401.65909) (xy 189.391542 -401.65909) (xy 189.395613 -401.603468) (xy 189.407739 -401.549031)
			(xy 189.427662 -401.49694) (xy 189.454958 -401.448305) (xy 189.489044 -401.404162) (xy 189.529193 -401.365453)
			(xy 189.574551 -401.333002) (xy 189.624151 -401.307501) (xy 189.676935 -401.289494) (xy 189.731778 -401.279364)
			(xy 189.787512 -401.277327) (xy 189.842949 -401.283427) (xy 189.896906 -401.297533) (xy 189.948235 -401.319345)
			(xy 189.995841 -401.348399) (xy 190.038709 -401.384074) (xy 190.075926 -401.425611) (xy 190.106699 -401.472124)
			(xy 190.130371 -401.522621) (xy 190.13215 -401.528534) (xy 191.43548 -401.528534) (xy 191.439551 -401.472912)
			(xy 191.451677 -401.418475) (xy 191.4716 -401.366384) (xy 191.498896 -401.317749) (xy 191.532982 -401.273606)
			(xy 191.573131 -401.234897) (xy 191.618489 -401.202446) (xy 191.668089 -401.176945) (xy 191.720873 -401.158938)
			(xy 191.775716 -401.148808) (xy 191.83145 -401.146771) (xy 191.886887 -401.152871) (xy 191.940844 -401.166977)
			(xy 191.992173 -401.188789) (xy 192.039779 -401.217843) (xy 192.082647 -401.253518) (xy 192.119864 -401.295055)
			(xy 192.150637 -401.341568) (xy 192.174309 -401.392065) (xy 192.190377 -401.445472) (xy 192.198497 -401.500648)
			(xy 192.199006 -401.528534) (xy 192.198497 -401.55642) (xy 192.190377 -401.611596) (xy 192.174309 -401.665003)
			(xy 192.150637 -401.7155) (xy 192.119864 -401.762013) (xy 192.082647 -401.80355) (xy 192.039779 -401.839225)
			(xy 191.992173 -401.868279) (xy 191.940844 -401.890091) (xy 191.886887 -401.904197) (xy 191.83145 -401.910297)
			(xy 191.775716 -401.90826) (xy 191.720873 -401.89813) (xy 191.668089 -401.880123) (xy 191.618489 -401.854622)
			(xy 191.573131 -401.822171) (xy 191.532982 -401.783462) (xy 191.498896 -401.739319) (xy 191.4716 -401.690684)
			(xy 191.451677 -401.638593) (xy 191.439551 -401.584156) (xy 191.43548 -401.528534) (xy 190.13215 -401.528534)
			(xy 190.146439 -401.576028) (xy 190.154559 -401.631204) (xy 190.155068 -401.65909) (xy 190.154559 -401.686976)
			(xy 190.146439 -401.742152) (xy 190.130371 -401.795559) (xy 190.106699 -401.846056) (xy 190.075926 -401.892569)
			(xy 190.038709 -401.934106) (xy 189.995841 -401.969781) (xy 189.948235 -401.998835) (xy 189.896906 -402.020647)
			(xy 189.842949 -402.034753) (xy 189.787512 -402.040853) (xy 189.731778 -402.038816) (xy 189.676935 -402.028686)
			(xy 189.624151 -402.010679) (xy 189.574551 -401.985178) (xy 189.529193 -401.952727) (xy 189.489044 -401.914018)
			(xy 189.454958 -401.869875) (xy 189.427662 -401.82124) (xy 189.407739 -401.769149) (xy 189.395613 -401.714712)
			(xy 189.391542 -401.65909) (xy 180.940456 -401.65909) (xy 180.377084 -402.222462) (xy 198.023478 -402.222462)
			(xy 198.027549 -402.16684) (xy 198.039675 -402.112403) (xy 198.059598 -402.060312) (xy 198.086894 -402.011677)
			(xy 198.12098 -401.967534) (xy 198.161129 -401.928825) (xy 198.206487 -401.896374) (xy 198.256087 -401.870873)
			(xy 198.308871 -401.852866) (xy 198.363714 -401.842736) (xy 198.419448 -401.840699) (xy 198.474885 -401.846799)
			(xy 198.528842 -401.860905) (xy 198.580171 -401.882717) (xy 198.627777 -401.911771) (xy 198.670645 -401.947446)
			(xy 198.707862 -401.988983) (xy 198.738635 -402.035496) (xy 198.762307 -402.085993) (xy 198.778375 -402.1394)
			(xy 198.786495 -402.194576) (xy 198.787004 -402.222462) (xy 198.786495 -402.250348) (xy 198.778375 -402.305524)
			(xy 198.762307 -402.358931) (xy 198.738635 -402.409428) (xy 198.707862 -402.455941) (xy 198.670645 -402.497478)
			(xy 198.627777 -402.533153) (xy 198.580171 -402.562207) (xy 198.528842 -402.584019) (xy 198.474885 -402.598125)
			(xy 198.419448 -402.604225) (xy 198.363714 -402.602188) (xy 198.308871 -402.592058) (xy 198.256087 -402.574051)
			(xy 198.206487 -402.54855) (xy 198.161129 -402.516099) (xy 198.12098 -402.47739) (xy 198.086894 -402.433247)
			(xy 198.059598 -402.384612) (xy 198.039675 -402.332521) (xy 198.027549 -402.278084) (xy 198.023478 -402.222462)
			(xy 180.377084 -402.222462) (xy 180.12918 -402.470366) (xy 180.121607 -402.4789) (xy 180.114119 -402.500422)
			(xy 180.11663 -402.52307) (xy 180.122068 -402.533104) (xy 180.139506 -402.562152) (xy 180.167043 -402.624055)
			(xy 180.185706 -402.689185) (xy 180.195132 -402.756277) (xy 180.195728 -402.790152) (xy 180.195234 -402.821952)
			(xy 180.186938 -402.885009) (xy 180.170481 -402.946443) (xy 180.146146 -403.005203) (xy 180.114349 -403.060284)
			(xy 180.075634 -403.110742) (xy 180.030664 -403.155716) (xy 179.980207 -403.194434) (xy 179.925128 -403.226234)
			(xy 179.866369 -403.250572) (xy 179.804936 -403.267032) (xy 179.74188 -403.275332) (xy 179.71008 -403.2758)
			(xy 179.676205 -403.275209) (xy 179.609113 -403.265782) (xy 179.543984 -403.247115) (xy 179.482086 -403.21957)
			(xy 179.453032 -403.20214) (xy 179.445666 -403.197568) (xy 179.428902 -403.193758) (xy 179.420266 -403.194774)
			(xy 179.411855 -403.196069) (xy 179.396548 -403.20348) (xy 179.390294 -403.209252) (xy 178.608228 -403.991318)
			(xy 190.063626 -403.991318) (xy 190.067697 -403.935696) (xy 190.079823 -403.881259) (xy 190.099746 -403.829168)
			(xy 190.127042 -403.780533) (xy 190.161128 -403.73639) (xy 190.201277 -403.697681) (xy 190.246635 -403.66523)
			(xy 190.296235 -403.639729) (xy 190.349019 -403.621722) (xy 190.403862 -403.611592) (xy 190.459596 -403.609555)
			(xy 190.515033 -403.615655) (xy 190.56899 -403.629761) (xy 190.620319 -403.651573) (xy 190.667925 -403.680627)
			(xy 190.710793 -403.716302) (xy 190.74801 -403.757839) (xy 190.778783 -403.804352) (xy 190.802455 -403.854849)
			(xy 190.818523 -403.908256) (xy 190.826643 -403.963432) (xy 190.827152 -403.991318) (xy 190.826643 -404.019204)
			(xy 190.818523 -404.07438) (xy 190.816996 -404.079456) (xy 192.60769 -404.079456) (xy 192.611761 -404.023834)
			(xy 192.623887 -403.969397) (xy 192.64381 -403.917306) (xy 192.671106 -403.868671) (xy 192.705192 -403.824528)
			(xy 192.745341 -403.785819) (xy 192.790699 -403.753368) (xy 192.840299 -403.727867) (xy 192.893083 -403.70986)
			(xy 192.947926 -403.69973) (xy 193.00366 -403.697693) (xy 193.059097 -403.703793) (xy 193.113054 -403.717899)
			(xy 193.164383 -403.739711) (xy 193.211989 -403.768765) (xy 193.254857 -403.80444) (xy 193.292074 -403.845977)
			(xy 193.322847 -403.89249) (xy 193.329763 -403.907244) (xy 193.55765 -403.907244) (xy 193.561721 -403.851622)
			(xy 193.573847 -403.797185) (xy 193.59377 -403.745094) (xy 193.621066 -403.696459) (xy 193.655152 -403.652316)
			(xy 193.695301 -403.613607) (xy 193.740659 -403.581156) (xy 193.790259 -403.555655) (xy 193.843043 -403.537648)
			(xy 193.897886 -403.527518) (xy 193.95362 -403.525481) (xy 194.009057 -403.531581) (xy 194.063014 -403.545687)
			(xy 194.114343 -403.567499) (xy 194.161949 -403.596553) (xy 194.204817 -403.632228) (xy 194.242034 -403.673765)
			(xy 194.272807 -403.720278) (xy 194.296479 -403.770775) (xy 194.312547 -403.824182) (xy 194.320667 -403.879358)
			(xy 194.321176 -403.907244) (xy 194.320667 -403.93513) (xy 194.312547 -403.990306) (xy 194.296479 -404.043713)
			(xy 194.272807 -404.09421) (xy 194.242034 -404.140723) (xy 194.204817 -404.18226) (xy 194.161949 -404.217935)
			(xy 194.114343 -404.246989) (xy 194.063014 -404.268801) (xy 194.009057 -404.282907) (xy 193.95362 -404.289007)
			(xy 193.897886 -404.28697) (xy 193.843043 -404.27684) (xy 193.790259 -404.258833) (xy 193.740659 -404.233332)
			(xy 193.695301 -404.200881) (xy 193.655152 -404.162172) (xy 193.621066 -404.118029) (xy 193.59377 -404.069394)
			(xy 193.573847 -404.017303) (xy 193.561721 -403.962866) (xy 193.55765 -403.907244) (xy 193.329763 -403.907244)
			(xy 193.346519 -403.942987) (xy 193.362587 -403.996394) (xy 193.370707 -404.05157) (xy 193.371216 -404.079456)
			(xy 193.370707 -404.107342) (xy 193.362587 -404.162518) (xy 193.346519 -404.215925) (xy 193.322847 -404.266422)
			(xy 193.292074 -404.312935) (xy 193.254857 -404.354472) (xy 193.211989 -404.390147) (xy 193.164383 -404.419201)
			(xy 193.113054 -404.441013) (xy 193.059097 -404.455119) (xy 193.00366 -404.461219) (xy 192.947926 -404.459182)
			(xy 192.893083 -404.449052) (xy 192.840299 -404.431045) (xy 192.790699 -404.405544) (xy 192.745341 -404.373093)
			(xy 192.705192 -404.334384) (xy 192.671106 -404.290241) (xy 192.64381 -404.241606) (xy 192.623887 -404.189515)
			(xy 192.611761 -404.135078) (xy 192.60769 -404.079456) (xy 190.816996 -404.079456) (xy 190.802455 -404.127787)
			(xy 190.778783 -404.178284) (xy 190.74801 -404.224797) (xy 190.710793 -404.266334) (xy 190.667925 -404.302009)
			(xy 190.620319 -404.331063) (xy 190.56899 -404.352875) (xy 190.515033 -404.366981) (xy 190.459596 -404.373081)
			(xy 190.403862 -404.371044) (xy 190.349019 -404.360914) (xy 190.296235 -404.342907) (xy 190.246635 -404.317406)
			(xy 190.201277 -404.284955) (xy 190.161128 -404.246246) (xy 190.127042 -404.202103) (xy 190.099746 -404.153468)
			(xy 190.079823 -404.101377) (xy 190.067697 -404.04694) (xy 190.063626 -403.991318) (xy 178.608228 -403.991318)
			(xy 178.485292 -404.114254) (xy 178.477895 -404.121104) (xy 178.459297 -404.128843) (xy 178.449224 -404.12924)
			(xy 178.094132 -404.12924) (xy 178.093116 -404.12924) (xy 178.083238 -404.12991) (xy 178.065081 -404.137758)
			(xy 178.05781 -404.14448) (xy 178.027584 -404.178008) (xy 178.006248 -404.20163) (xy 178.002742 -404.20566)
			(xy 177.997359 -404.214882) (xy 177.99558 -404.219918) (xy 177.992024 -404.231094) (xy 177.99304 -404.241254)
			(xy 177.994208 -404.253412) (xy 177.995476 -404.277808) (xy 177.99558 -404.290022) (xy 177.99506 -404.321819)
			(xy 177.986759 -404.384869) (xy 177.9703 -404.446296) (xy 177.945964 -404.505049) (xy 177.914167 -404.560123)
			(xy 177.875453 -404.610575) (xy 177.830485 -404.655543) (xy 177.780033 -404.694257) (xy 177.724959 -404.726054)
			(xy 177.666206 -404.75039) (xy 177.604779 -404.766849) (xy 177.541729 -404.77515) (xy 177.478135 -404.77515)
			(xy 177.415085 -404.766849) (xy 177.353658 -404.75039) (xy 177.294905 -404.726054) (xy 177.239831 -404.694257)
			(xy 177.189379 -404.655543) (xy 177.144411 -404.610575) (xy 177.105697 -404.560123) (xy 177.0739 -404.505049)
			(xy 177.049564 -404.446296) (xy 177.033105 -404.384869) (xy 177.024804 -404.321819) (xy 177.024284 -404.290022)
			(xy 177.024326 -404.277938) (xy 177.025471 -404.253796) (xy 177.02657 -404.241762) (xy 177.02784 -404.229824)
			(xy 177.023014 -404.217124) (xy 177.019204 -404.20798) (xy 176.99228 -404.178008) (xy 176.962054 -404.14448)
			(xy 176.954803 -404.137729) (xy 176.936634 -404.129879) (xy 176.926748 -404.12924) (xy 175.935132 -404.12924)
			(xy 175.926028 -404.129615) (xy 175.908978 -404.136) (xy 175.901858 -404.141686) (xy 175.887634 -404.153878)
			(xy 175.886618 -404.161498) (xy 175.88484 -404.172928) (xy 175.87942 -404.207062) (xy 175.861515 -404.273819)
			(xy 175.835812 -404.337979) (xy 175.802676 -404.398634) (xy 175.762574 -404.454928) (xy 175.716074 -404.506063)
			(xy 175.663833 -404.551318) (xy 175.60659 -404.590051) (xy 175.545153 -404.621717) (xy 175.480393 -404.645866)
			(xy 175.413224 -404.662158) (xy 175.344596 -404.670362) (xy 175.27548 -404.670362) (xy 175.206852 -404.662158)
			(xy 175.139683 -404.645866) (xy 175.074923 -404.621717) (xy 175.013486 -404.590051) (xy 174.956243 -404.551318)
			(xy 174.904002 -404.506063) (xy 174.857502 -404.454928) (xy 174.8174 -404.398634) (xy 174.784264 -404.337979)
			(xy 174.758561 -404.273819) (xy 174.740656 -404.207062) (xy 174.735236 -404.172928) (xy 174.733458 -404.161498)
			(xy 174.732442 -404.153878) (xy 174.718218 -404.141686) (xy 174.711098 -404.135999) (xy 174.694048 -404.129606)
			(xy 174.684944 -404.12924) (xy 173.69409 -404.12924) (xy 173.693074 -404.12924) (xy 173.683191 -404.1299)
			(xy 173.665019 -404.137733) (xy 173.657768 -404.14448) (xy 173.627542 -404.178008) (xy 173.606968 -404.200868)
			(xy 173.600872 -404.207726) (xy 173.596808 -404.217632) (xy 173.594693 -404.223417) (xy 173.593033 -404.23562)
			(xy 173.593506 -404.241762) (xy 173.594662 -404.253794) (xy 173.595933 -404.277935) (xy 173.596046 -404.290022)
			(xy 173.595537 -404.322076) (xy 173.587116 -404.385627) (xy 173.570411 -404.447519) (xy 173.54571 -404.506677)
			(xy 173.530006 -404.534624) (xy 173.529752 -404.534878) (xy 173.52645 -404.54072) (xy 173.521116 -404.560786)
			(xy 173.519592 -404.57247) (xy 173.519592 -405.308816) (xy 173.521116 -405.3205) (xy 173.526704 -405.340312)
			(xy 173.529498 -405.345138) (xy 173.530768 -405.347678) (xy 173.53153 -405.348948) (xy 173.533054 -405.351742)
			(xy 173.53407 -405.35352) (xy 173.538642 -405.361648) (xy 173.543976 -405.372316) (xy 173.559083 -405.403755)
			(xy 173.581134 -405.469928) (xy 173.587918 -405.504142) (xy 173.593253 -405.536816) (xy 173.596058 -405.60296)
			(xy 173.593506 -405.635968) (xy 173.592236 -405.647144) (xy 173.588134 -405.679122) (xy 173.572558 -405.741683)
			(xy 173.548835 -405.801631) (xy 173.533562 -405.830024) (xy 173.530514 -405.83612) (xy 173.527974 -405.840692)
			(xy 173.52518 -405.847296) (xy 173.523402 -405.850852) (xy 173.52137 -405.858472) (xy 173.519592 -405.865076)
			(xy 173.519592 -406.151334) (xy 173.519091 -406.161489) (xy 173.511312 -406.180252) (xy 173.496949 -406.194614)
			(xy 173.478186 -406.202392) (xy 173.46803 -406.202896) (xy 172.75175 -406.202896) (xy 172.741569 -406.202479)
			(xy 172.722752 -406.194705) (xy 172.708343 -406.180319) (xy 172.700537 -406.161514) (xy 172.700188 -406.151334)
			(xy 172.700188 -405.871172) (xy 172.698664 -405.859488) (xy 172.693076 -405.839676) (xy 172.690282 -405.83485)
			(xy 172.689012 -405.83231) (xy 172.68825 -405.83104) (xy 172.686726 -405.828246) (xy 172.68571 -405.826468)
			(xy 172.681138 -405.81834) (xy 172.675804 -405.807672) (xy 172.663519 -405.782259) (xy 172.644233 -405.729208)
			(xy 172.631219 -405.674281) (xy 172.62465 -405.618217) (xy 172.624242 -405.589994) (xy 172.625004 -405.562308)
			(xy 172.627544 -405.533606) (xy 172.629068 -405.521922) (xy 172.633908 -405.490824) (xy 172.65057 -405.430134)
			(xy 172.674917 -405.372097) (xy 172.690282 -405.34463) (xy 172.693838 -405.338534) (xy 172.69841 -405.321008)
			(xy 172.700188 -405.314404) (xy 172.700188 -404.571454) (xy 172.698664 -404.559262) (xy 172.695362 -404.547578)
			(xy 172.691044 -404.53691) (xy 172.689266 -404.533862) (xy 172.673694 -404.506006) (xy 172.649182 -404.447081)
			(xy 172.6326 -404.385454) (xy 172.624231 -404.322186) (xy 172.623734 -404.290276) (xy 172.623734 -404.290022)
			(xy 172.623821 -404.277744) (xy 172.62509 -404.253221) (xy 172.626274 -404.241) (xy 172.627544 -404.229062)
			(xy 172.619924 -404.208742) (xy 172.61332 -404.201376) (xy 172.592238 -404.178008) (xy 172.562012 -404.14448)
			(xy 172.554758 -404.137736) (xy 172.536589 -404.1299) (xy 172.526706 -404.12924) (xy 171.53509 -404.12924)
			(xy 171.525989 -404.129622) (xy 171.508948 -404.136018) (xy 171.501816 -404.141686) (xy 171.487592 -404.153878)
			(xy 171.486576 -404.161498) (xy 171.484798 -404.172928) (xy 171.479378 -404.207062) (xy 171.461473 -404.273819)
			(xy 171.43577 -404.337979) (xy 171.402634 -404.398634) (xy 171.362532 -404.454928) (xy 171.316032 -404.506063)
			(xy 171.263791 -404.551318) (xy 171.206548 -404.590051) (xy 171.145111 -404.621717) (xy 171.080351 -404.645866)
			(xy 171.013182 -404.662158) (xy 170.944554 -404.670362) (xy 170.875438 -404.670362) (xy 170.80681 -404.662158)
			(xy 170.739641 -404.645866) (xy 170.674881 -404.621717) (xy 170.613444 -404.590051) (xy 170.556201 -404.551318)
			(xy 170.50396 -404.506063) (xy 170.45746 -404.454928) (xy 170.417358 -404.398634) (xy 170.384222 -404.337979)
			(xy 170.358519 -404.273819) (xy 170.340614 -404.207062) (xy 170.335194 -404.172928) (xy 170.333416 -404.161498)
			(xy 170.3324 -404.153878) (xy 170.318176 -404.141686) (xy 170.311054 -404.136005) (xy 170.294004 -404.129626)
			(xy 170.284902 -404.12924) (xy 169.294302 -404.12924) (xy 169.293286 -404.12924) (xy 169.283402 -404.129897)
			(xy 169.265227 -404.137728) (xy 169.25798 -404.14448) (xy 169.227754 -404.178008) (xy 169.20718 -404.200868)
			(xy 169.201084 -404.207726) (xy 169.19702 -404.217632) (xy 169.194905 -404.223417) (xy 169.193244 -404.23562)
			(xy 169.193718 -404.241762) (xy 169.194874 -404.253794) (xy 169.196146 -404.277935) (xy 169.196258 -404.290022)
			(xy 169.195749 -404.322076) (xy 169.187329 -404.385627) (xy 169.170623 -404.44752) (xy 169.145923 -404.506677)
			(xy 169.130218 -404.534624) (xy 169.129964 -404.534878) (xy 169.126662 -404.54072) (xy 169.121328 -404.560786)
			(xy 169.119804 -404.57247) (xy 169.119804 -405.308816) (xy 169.121328 -405.3205) (xy 169.126916 -405.340312)
			(xy 169.12971 -405.345138) (xy 169.13098 -405.347678) (xy 169.131742 -405.348948) (xy 169.133266 -405.351742)
			(xy 169.134282 -405.35352) (xy 169.138854 -405.361648) (xy 169.144188 -405.372316) (xy 169.159297 -405.403754)
			(xy 169.181352 -405.469926) (xy 169.18813 -405.504142) (xy 169.193465 -405.536816) (xy 169.19627 -405.60296)
			(xy 169.193718 -405.635968) (xy 169.192448 -405.647144) (xy 169.188346 -405.679122) (xy 169.172767 -405.741682)
			(xy 169.14904 -405.801628) (xy 169.133774 -405.830024) (xy 169.130726 -405.83612) (xy 169.128186 -405.840692)
			(xy 169.125392 -405.847296) (xy 169.123614 -405.850852) (xy 169.121582 -405.858472) (xy 169.119804 -405.865076)
			(xy 169.119804 -406.151334) (xy 169.119303 -406.16149) (xy 169.111524 -406.180255) (xy 169.097162 -406.19462)
			(xy 169.078398 -406.202402) (xy 169.068242 -406.202896) (xy 168.351962 -406.202896) (xy 168.341807 -406.202395)
			(xy 168.323045 -406.194615) (xy 168.308683 -406.180252) (xy 168.300905 -406.161489) (xy 168.3004 -406.151334)
			(xy 168.3004 -405.871172) (xy 168.298876 -405.859488) (xy 168.293288 -405.839676) (xy 168.290494 -405.83485)
			(xy 168.289224 -405.83231) (xy 168.288462 -405.83104) (xy 168.286938 -405.828246) (xy 168.285922 -405.826468)
			(xy 168.28135 -405.81834) (xy 168.276016 -405.807672) (xy 168.263731 -405.782259) (xy 168.244445 -405.729208)
			(xy 168.23143 -405.674282) (xy 168.224861 -405.618218) (xy 168.224454 -405.589994) (xy 168.225216 -405.562308)
			(xy 168.227756 -405.533606) (xy 168.22928 -405.521922) (xy 168.23412 -405.490824) (xy 168.250779 -405.430132)
			(xy 168.275121 -405.372093) (xy 168.290494 -405.34463) (xy 168.29405 -405.338534) (xy 168.298622 -405.321008)
			(xy 168.3004 -405.314404) (xy 168.3004 -404.571454) (xy 168.298876 -404.559262) (xy 168.295574 -404.547578)
			(xy 168.291256 -404.53691) (xy 168.289478 -404.533862) (xy 168.273905 -404.506006) (xy 168.249393 -404.447081)
			(xy 168.23281 -404.385454) (xy 168.224441 -404.322186) (xy 168.223946 -404.290276) (xy 168.223946 -404.290022)
			(xy 168.224033 -404.277744) (xy 168.225302 -404.253221) (xy 168.226486 -404.241) (xy 168.227756 -404.229062)
			(xy 168.220136 -404.208742) (xy 168.213532 -404.201376) (xy 168.19245 -404.178008) (xy 168.162224 -404.14448)
			(xy 168.154971 -404.137734) (xy 168.136802 -404.129894) (xy 168.126918 -404.12924) (xy 167.135048 -404.12924)
			(xy 167.125943 -404.129613) (xy 167.108889 -404.135993) (xy 167.101774 -404.141686) (xy 167.08755 -404.153878)
			(xy 167.086534 -404.161498) (xy 167.084756 -404.172928) (xy 167.079336 -404.207062) (xy 167.061431 -404.273819)
			(xy 167.035728 -404.337979) (xy 167.002592 -404.398634) (xy 166.96249 -404.454928) (xy 166.91599 -404.506063)
			(xy 166.863749 -404.551318) (xy 166.806506 -404.590051) (xy 166.745069 -404.621717) (xy 166.680309 -404.645866)
			(xy 166.61314 -404.662158) (xy 166.544512 -404.670362) (xy 166.475396 -404.670362) (xy 166.406768 -404.662158)
			(xy 166.339599 -404.645866) (xy 166.274839 -404.621717) (xy 166.213402 -404.590051) (xy 166.156159 -404.551318)
			(xy 166.103918 -404.506063) (xy 166.057418 -404.454928) (xy 166.017316 -404.398634) (xy 165.98418 -404.337979)
			(xy 165.958477 -404.273819) (xy 165.940572 -404.207062) (xy 165.935152 -404.172928) (xy 165.933374 -404.161498)
			(xy 165.932358 -404.153878) (xy 165.918134 -404.141686) (xy 165.91101 -404.136011) (xy 165.89396 -404.129646)
			(xy 165.88486 -404.12924) (xy 164.89426 -404.12924) (xy 164.893244 -404.12924) (xy 164.883363 -404.129905)
			(xy 164.865199 -404.137746) (xy 164.857938 -404.14448) (xy 164.827712 -404.178008) (xy 164.807138 -404.200868)
			(xy 164.801042 -404.207726) (xy 164.796978 -404.217632) (xy 164.794864 -404.223418) (xy 164.793205 -404.23562)
			(xy 164.793676 -404.241762) (xy 164.794832 -404.253794) (xy 164.796104 -404.277935) (xy 164.796216 -404.290022)
			(xy 164.796216 -404.291292) (xy 164.795696 -404.323489) (xy 164.787206 -404.38732) (xy 164.770373 -404.449474)
			(xy 164.745491 -404.508865) (xy 164.729668 -404.53691) (xy 164.726112 -404.543006) (xy 164.721286 -404.560786)
			(xy 164.719508 -404.573994) (xy 164.719508 -405.305514) (xy 164.721286 -405.318722) (xy 164.726112 -405.336502)
			(xy 164.729668 -405.342598) (xy 164.745477 -405.370651) (xy 164.770375 -405.430036) (xy 164.787215 -405.492188)
			(xy 164.795701 -405.556019) (xy 164.796216 -405.588216) (xy 164.796216 -405.595836) (xy 164.795674 -405.628803)
			(xy 164.786786 -405.694136) (xy 164.769166 -405.757672) (xy 164.743135 -405.81825) (xy 164.72662 -405.846788)
			(xy 164.723064 -405.85263) (xy 164.721286 -405.859234) (xy 164.719508 -405.872442) (xy 164.719508 -406.008078)
			(xy 164.719762 -406.008078) (xy 164.719762 -406.151334) (xy 164.719267 -406.161456) (xy 164.711534 -406.180165)
			(xy 164.697249 -406.19451) (xy 164.678573 -406.202323) (xy 164.668454 -406.202896) (xy 163.95192 -406.202896)
			(xy 163.939135 -406.202201) (xy 163.916626 -406.190064) (xy 163.908994 -406.179782) (xy 163.9062 -406.174702)
			(xy 163.90359 -406.169217) (xy 163.900774 -406.157406) (xy 163.900612 -406.151334) (xy 163.900612 -405.873966)
			(xy 163.898834 -405.860758) (xy 163.894008 -405.842978) (xy 163.890452 -405.836882) (xy 163.874646 -405.808828)
			(xy 163.849755 -405.749442) (xy 163.832921 -405.68729) (xy 163.824438 -405.62346) (xy 163.823904 -405.591264)
			(xy 163.823904 -405.588724) (xy 163.824429 -405.556529) (xy 163.83293 -405.492702) (xy 163.849773 -405.430554)
			(xy 163.874664 -405.371169) (xy 163.890452 -405.343106) (xy 163.894008 -405.33701) (xy 163.898834 -405.31923)
			(xy 163.900612 -405.306022) (xy 163.900612 -404.573994) (xy 163.898834 -404.560786) (xy 163.894008 -404.543006)
			(xy 163.890452 -404.53691) (xy 163.874645 -404.508857) (xy 163.84975 -404.449471) (xy 163.832912 -404.387319)
			(xy 163.824426 -404.323488) (xy 163.823904 -404.291292) (xy 163.823904 -404.290022) (xy 163.823983 -404.278382)
			(xy 163.825124 -404.255131) (xy 163.82619 -404.24354) (xy 163.827968 -404.23211) (xy 163.82492 -404.221696)
			(xy 163.823203 -404.216247) (xy 163.817688 -404.206245) (xy 163.813998 -404.201884) (xy 163.792408 -404.178008)
			(xy 163.762182 -404.14448) (xy 163.754932 -404.137725) (xy 163.736764 -404.129865) (xy 163.726876 -404.12924)
			(xy 162.735006 -404.12924) (xy 162.725904 -404.12962) (xy 162.70886 -404.136011) (xy 162.701732 -404.141686)
			(xy 162.687508 -404.153878) (xy 162.686492 -404.161498) (xy 162.684714 -404.172928) (xy 162.679294 -404.207062)
			(xy 162.661389 -404.273819) (xy 162.635686 -404.337979) (xy 162.60255 -404.398634) (xy 162.562448 -404.454928)
			(xy 162.515948 -404.506063) (xy 162.463707 -404.551318) (xy 162.406464 -404.590051) (xy 162.345027 -404.621717)
			(xy 162.280267 -404.645866) (xy 162.213098 -404.662158) (xy 162.14447 -404.670362) (xy 162.075354 -404.670362)
			(xy 162.006726 -404.662158) (xy 161.939557 -404.645866) (xy 161.874797 -404.621717) (xy 161.81336 -404.590051)
			(xy 161.756117 -404.551318) (xy 161.703876 -404.506063) (xy 161.657376 -404.454928) (xy 161.617274 -404.398634)
			(xy 161.584138 -404.337979) (xy 161.558435 -404.273819) (xy 161.54053 -404.207062) (xy 161.53511 -404.172928)
			(xy 161.533332 -404.161498) (xy 161.532316 -404.153878) (xy 161.518092 -404.141686) (xy 161.510971 -404.136003)
			(xy 161.49392 -404.129618) (xy 161.484818 -404.12924) (xy 160.494218 -404.12924) (xy 160.493202 -404.12924)
			(xy 160.483317 -404.129895) (xy 160.465137 -404.137721) (xy 160.457896 -404.14448) (xy 160.42767 -404.178008)
			(xy 160.407096 -404.200868) (xy 160.401 -404.207726) (xy 160.396936 -404.217632) (xy 160.394823 -404.223418)
			(xy 160.393165 -404.23562) (xy 160.393634 -404.241762) (xy 160.39479 -404.253794) (xy 160.396062 -404.277935)
			(xy 160.396174 -404.290022) (xy 160.395665 -404.322076) (xy 160.387245 -404.385628) (xy 160.37054 -404.44752)
			(xy 160.345841 -404.506678) (xy 160.330134 -404.534624) (xy 160.32988 -404.534878) (xy 160.326578 -404.54072)
			(xy 160.321244 -404.560786) (xy 160.31972 -404.57247) (xy 160.31972 -405.308816) (xy 160.321244 -405.3205)
			(xy 160.326832 -405.340312) (xy 160.329626 -405.345138) (xy 160.330896 -405.347678) (xy 160.331658 -405.348948)
			(xy 160.333182 -405.351742) (xy 160.334198 -405.35352) (xy 160.33877 -405.361648) (xy 160.344104 -405.372316)
			(xy 160.359213 -405.403754) (xy 160.381267 -405.469926) (xy 160.388046 -405.504142) (xy 160.393381 -405.536816)
			(xy 160.396186 -405.60296) (xy 160.393634 -405.635968) (xy 160.392364 -405.647144) (xy 160.388262 -405.679122)
			(xy 160.372684 -405.741682) (xy 160.348957 -405.801628) (xy 160.33369 -405.830024) (xy 160.330642 -405.83612)
			(xy 160.328102 -405.840692) (xy 160.325308 -405.847296) (xy 160.32353 -405.850852) (xy 160.321498 -405.858472)
			(xy 160.31972 -405.865076) (xy 160.31972 -406.151334) (xy 160.319288 -406.161498) (xy 160.311495 -406.180274)
			(xy 160.29711 -406.194638) (xy 160.278323 -406.202403) (xy 160.268158 -406.202896) (xy 159.551878 -406.202896)
			(xy 159.541721 -406.202397) (xy 159.522953 -406.19462) (xy 159.508586 -406.180257) (xy 159.500805 -406.161491)
			(xy 159.500316 -406.151334) (xy 159.500316 -405.871172) (xy 159.498792 -405.859488) (xy 159.493204 -405.839676)
			(xy 159.49041 -405.83485) (xy 159.48914 -405.83231) (xy 159.488378 -405.83104) (xy 159.486854 -405.828246)
			(xy 159.485838 -405.826468) (xy 159.481266 -405.81834) (xy 159.475932 -405.807672) (xy 159.463649 -405.782258)
			(xy 159.444366 -405.729207) (xy 159.431353 -405.674281) (xy 159.424786 -405.618217) (xy 159.42437 -405.589994)
			(xy 159.425132 -405.562308) (xy 159.427672 -405.533606) (xy 159.429196 -405.521922) (xy 159.434036 -405.490824)
			(xy 159.450696 -405.430132) (xy 159.475039 -405.372094) (xy 159.49041 -405.34463) (xy 159.493966 -405.338534)
			(xy 159.498538 -405.321008) (xy 159.500316 -405.314404) (xy 159.500316 -404.571454) (xy 159.498792 -404.559262)
			(xy 159.49549 -404.547578) (xy 159.491172 -404.53691) (xy 159.489394 -404.533862) (xy 159.473821 -404.506006)
			(xy 159.449308 -404.447082) (xy 159.432724 -404.385454) (xy 159.424355 -404.322186) (xy 159.423862 -404.290276)
			(xy 159.423862 -404.290022) (xy 159.423949 -404.277744) (xy 159.425218 -404.253221) (xy 159.426402 -404.241)
			(xy 159.427672 -404.229062) (xy 159.420052 -404.208742) (xy 159.413448 -404.201376) (xy 159.392366 -404.178008)
			(xy 159.36214 -404.14448) (xy 159.354888 -404.137731) (xy 159.336719 -404.129886) (xy 159.326834 -404.12924)
			(xy 157.730444 -404.12924) (xy 157.729936 -404.128732) (xy 154.626818 -404.128732) (xy 154.617451 -404.129153)
			(xy 154.59997 -404.135884) (xy 154.586078 -404.148452) (xy 154.577637 -404.165175) (xy 154.576272 -404.174452)
			(xy 154.576272 -406.690068) (xy 161.624264 -406.690068) (xy 161.624842 -406.657339) (xy 161.633695 -406.592481)
			(xy 161.651182 -406.529401) (xy 161.676985 -406.469243) (xy 161.693352 -406.440894) (xy 161.696665 -406.434868)
			(xy 161.700272 -406.421605) (xy 161.700464 -406.414732) (xy 161.700464 -405.665432) (xy 161.700264 -405.658559)
			(xy 161.696662 -405.645296) (xy 161.693352 -405.63927) (xy 161.676979 -405.610925) (xy 161.651178 -405.550764)
			(xy 161.63369 -405.487683) (xy 161.624833 -405.422825) (xy 161.624264 -405.390096) (xy 161.62481 -405.357366)
			(xy 161.633673 -405.292507) (xy 161.651169 -405.229427) (xy 161.676981 -405.169269) (xy 161.693352 -405.140922)
			(xy 161.696655 -405.134892) (xy 161.700269 -405.121632) (xy 161.700464 -405.11476) (xy 161.700464 -404.828756)
			(xy 161.700948 -404.818649) (xy 161.708694 -404.799977) (xy 161.72299 -404.785685) (xy 161.741665 -404.777945)
			(xy 161.751772 -404.777448) (xy 162.468052 -404.777448) (xy 162.478165 -404.777954) (xy 162.496858 -404.785677)
			(xy 162.511172 -404.799965) (xy 162.518928 -404.818644) (xy 162.51936 -404.828756) (xy 162.51936 -405.11476)
			(xy 162.519572 -405.121632) (xy 162.523167 -405.134894) (xy 162.526472 -405.140922) (xy 162.542844 -405.169268)
			(xy 162.568645 -405.229428) (xy 162.586133 -405.292509) (xy 162.594991 -405.357367) (xy 162.59556 -405.390096)
			(xy 162.595007 -405.422826) (xy 162.586146 -405.487684) (xy 162.568652 -405.550764) (xy 162.542842 -405.610922)
			(xy 162.526472 -405.63927) (xy 162.523166 -405.645299) (xy 162.519555 -405.658559) (xy 162.51936 -405.665432)
			(xy 162.51936 -406.414732) (xy 162.519545 -406.421606) (xy 162.523159 -406.434868) (xy 162.526472 -406.440894)
			(xy 162.542833 -406.469246) (xy 162.568636 -406.529404) (xy 162.586127 -406.592483) (xy 162.594989 -406.657339)
			(xy 162.59556 -406.690068) (xy 162.594994 -406.722792) (xy 166.02489 -406.722792) (xy 166.024894 -406.657353)
			(xy 166.033681 -406.592507) (xy 166.051094 -406.529427) (xy 166.076816 -406.469255) (xy 166.09314 -406.440894)
			(xy 166.096452 -406.434868) (xy 166.10006 -406.421605) (xy 166.100252 -406.414732) (xy 166.100252 -405.665432)
			(xy 166.100054 -405.658559) (xy 166.096451 -405.645296) (xy 166.09314 -405.63927) (xy 166.076814 -405.610911)
			(xy 166.051097 -405.550739) (xy 166.033689 -405.48766) (xy 166.024906 -405.422815) (xy 166.024907 -405.357378)
			(xy 166.033691 -405.292533) (xy 166.051099 -405.229454) (xy 166.076817 -405.169283) (xy 166.09314 -405.140922)
			(xy 166.096442 -405.134891) (xy 166.100057 -405.121632) (xy 166.100252 -405.11476) (xy 166.100252 -404.828756)
			(xy 166.100685 -404.818605) (xy 166.108486 -404.799861) (xy 166.122878 -404.785541) (xy 166.141661 -404.777834)
			(xy 166.151814 -404.777448) (xy 166.868094 -404.777448) (xy 166.878221 -404.777932) (xy 166.896944 -404.785659)
			(xy 166.911301 -404.799946) (xy 166.919119 -404.818631) (xy 166.919656 -404.828756) (xy 166.919656 -405.11476)
			(xy 166.919856 -405.121633) (xy 166.923458 -405.134896) (xy 166.926768 -405.140922) (xy 166.943087 -405.169285)
			(xy 166.968804 -405.229456) (xy 166.986212 -405.292534) (xy 166.994996 -405.357378) (xy 166.994997 -405.422815)
			(xy 166.986214 -405.487659) (xy 166.968806 -405.550738) (xy 166.94309 -405.610909) (xy 166.926768 -405.63927)
			(xy 166.923462 -405.645299) (xy 166.919851 -405.658559) (xy 166.919656 -405.665432) (xy 166.919656 -406.414732)
			(xy 166.919829 -406.421607) (xy 166.923449 -406.43487) (xy 166.926768 -406.440894) (xy 166.943063 -406.46927)
			(xy 166.968783 -406.529438) (xy 166.986194 -406.592514) (xy 166.99498 -406.657355) (xy 166.994982 -406.690068)
			(xy 170.424348 -406.690068) (xy 170.424929 -406.657339) (xy 170.433781 -406.592482) (xy 170.451267 -406.529402)
			(xy 170.47707 -406.469243) (xy 170.493436 -406.440894) (xy 170.496748 -406.434868) (xy 170.500356 -406.421605)
			(xy 170.500548 -406.414732) (xy 170.500548 -405.665432) (xy 170.50035 -405.658559) (xy 170.496747 -405.645296)
			(xy 170.493436 -405.63927) (xy 170.477062 -405.610925) (xy 170.451261 -405.550764) (xy 170.433774 -405.487683)
			(xy 170.424917 -405.422825) (xy 170.424348 -405.390096) (xy 170.424897 -405.357366) (xy 170.433759 -405.292507)
			(xy 170.451254 -405.229427) (xy 170.477066 -405.16927) (xy 170.493436 -405.140922) (xy 170.496738 -405.134891)
			(xy 170.500353 -405.121632) (xy 170.500548 -405.11476) (xy 170.500548 -404.828756) (xy 170.501048 -404.818651)
			(xy 170.50879 -404.799982) (xy 170.523082 -404.78569) (xy 170.541751 -404.777948) (xy 170.551856 -404.777448)
			(xy 171.268136 -404.777448) (xy 171.278241 -404.777954) (xy 171.29691 -404.785694) (xy 171.311201 -404.799984)
			(xy 171.318944 -404.818651) (xy 171.319444 -404.828756) (xy 171.319444 -405.11476) (xy 171.319646 -405.121633)
			(xy 171.323247 -405.134896) (xy 171.326556 -405.140922) (xy 171.342926 -405.169269) (xy 171.368728 -405.229429)
			(xy 171.386216 -405.292509) (xy 171.395075 -405.357367) (xy 171.395644 -405.390096) (xy 171.395093 -405.422826)
			(xy 171.386232 -405.487685) (xy 171.368737 -405.550765) (xy 171.342926 -405.610922) (xy 171.326556 -405.63927)
			(xy 171.323256 -405.645302) (xy 171.31964 -405.65856) (xy 171.319444 -405.665432) (xy 171.319444 -406.414732)
			(xy 171.319618 -406.421607) (xy 171.323238 -406.43487) (xy 171.326556 -406.440894) (xy 171.342915 -406.469247)
			(xy 171.368719 -406.529405) (xy 171.386211 -406.592483) (xy 171.395073 -406.657339) (xy 171.395644 -406.690068)
			(xy 171.39508 -406.722792) (xy 174.824976 -406.722792) (xy 174.82498 -406.657353) (xy 174.833767 -406.592507)
			(xy 174.851179 -406.529427) (xy 174.8769 -406.469255) (xy 174.893224 -406.440894) (xy 174.896543 -406.434871)
			(xy 174.900145 -406.421606) (xy 174.900336 -406.414732) (xy 174.900336 -405.665432) (xy 174.900127 -405.65856)
			(xy 174.89653 -405.645297) (xy 174.893224 -405.63927) (xy 174.876899 -405.61091) (xy 174.851182 -405.550739)
			(xy 174.833775 -405.48766) (xy 174.824992 -405.422815) (xy 174.824993 -405.357378) (xy 174.833777 -405.292534)
			(xy 174.851185 -405.229455) (xy 174.876902 -405.169283) (xy 174.893224 -405.140922) (xy 174.896533 -405.134894)
			(xy 174.900142 -405.121633) (xy 174.900336 -405.11476) (xy 174.900336 -404.828756) (xy 174.900686 -404.818594)
			(xy 174.908503 -404.799834) (xy 174.922922 -404.785511) (xy 174.941734 -404.77782) (xy 174.951898 -404.777448)
			(xy 175.668178 -404.777448) (xy 175.678304 -404.777945) (xy 175.697027 -404.785667) (xy 175.711384 -404.79995)
			(xy 175.719202 -404.818632) (xy 175.71974 -404.828756) (xy 175.71974 -405.11476) (xy 175.719942 -405.121633)
			(xy 175.723543 -405.134896) (xy 175.726852 -405.140922) (xy 175.743171 -405.169285) (xy 175.76889 -405.229456)
			(xy 175.786298 -405.292534) (xy 175.795082 -405.357378) (xy 175.795083 -405.422815) (xy 175.7863 -405.487659)
			(xy 175.768892 -405.550738) (xy 175.752113 -405.589994) (xy 177.023784 -405.589994) (xy 177.027775 -405.527827)
			(xy 177.039684 -405.46668) (xy 177.059313 -405.407559) (xy 177.086342 -405.351433) (xy 177.120326 -405.299224)
			(xy 177.160708 -405.251789) (xy 177.206824 -405.209908) (xy 177.257916 -405.174268) (xy 177.313147 -405.145454)
			(xy 177.371609 -405.12394) (xy 177.432343 -405.110078) (xy 177.49435 -405.104096) (xy 177.556613 -405.106092)
			(xy 177.61811 -405.116035) (xy 177.677831 -405.133759) (xy 177.734794 -405.158976) (xy 177.788065 -405.191269)
			(xy 177.83677 -405.230109) (xy 177.880107 -405.274859) (xy 177.917367 -405.324783) (xy 177.947936 -405.379062)
			(xy 177.952403 -405.390096) (xy 179.223932 -405.390096) (xy 179.227923 -405.327929) (xy 179.239832 -405.266782)
			(xy 179.259461 -405.207661) (xy 179.28649 -405.151535) (xy 179.320474 -405.099326) (xy 179.360856 -405.051891)
			(xy 179.406972 -405.01001) (xy 179.458064 -404.97437) (xy 179.513295 -404.945556) (xy 179.571757 -404.924042)
			(xy 179.632491 -404.91018) (xy 179.694498 -404.904198) (xy 179.756761 -404.906194) (xy 179.818258 -404.916137)
			(xy 179.877979 -404.933861) (xy 179.934942 -404.959078) (xy 179.988213 -404.991371) (xy 180.036918 -405.030211)
			(xy 180.080255 -405.074961) (xy 180.117515 -405.124885) (xy 180.148084 -405.179164) (xy 180.154299 -405.194516)
			(xy 198.019922 -405.194516) (xy 198.023993 -405.138894) (xy 198.036119 -405.084457) (xy 198.056042 -405.032366)
			(xy 198.083338 -404.983731) (xy 198.117424 -404.939588) (xy 198.157573 -404.900879) (xy 198.202931 -404.868428)
			(xy 198.252531 -404.842927) (xy 198.305315 -404.82492) (xy 198.360158 -404.81479) (xy 198.415892 -404.812753)
			(xy 198.471329 -404.818853) (xy 198.525286 -404.832959) (xy 198.576615 -404.854771) (xy 198.624221 -404.883825)
			(xy 198.667089 -404.9195) (xy 198.704306 -404.961037) (xy 198.735079 -405.00755) (xy 198.758751 -405.058047)
			(xy 198.774819 -405.111454) (xy 198.782939 -405.16663) (xy 198.783448 -405.194516) (xy 198.782939 -405.222402)
			(xy 198.774819 -405.277578) (xy 198.758751 -405.330985) (xy 198.735079 -405.381482) (xy 198.704306 -405.427995)
			(xy 198.667089 -405.469532) (xy 198.624221 -405.505207) (xy 198.576615 -405.534261) (xy 198.525286 -405.556073)
			(xy 198.471329 -405.570179) (xy 198.415892 -405.576279) (xy 198.360158 -405.574242) (xy 198.305315 -405.564112)
			(xy 198.252531 -405.546105) (xy 198.202931 -405.520604) (xy 198.157573 -405.488153) (xy 198.117424 -405.449444)
			(xy 198.083338 -405.405301) (xy 198.056042 -405.356666) (xy 198.036119 -405.304575) (xy 198.023993 -405.250138)
			(xy 198.019922 -405.194516) (xy 180.154299 -405.194516) (xy 180.171462 -405.236907) (xy 180.187263 -405.297165)
			(xy 180.195229 -405.358948) (xy 180.195728 -405.390096) (xy 180.195229 -405.421244) (xy 180.187263 -405.483027)
			(xy 180.171462 -405.543285) (xy 180.148084 -405.601028) (xy 180.117515 -405.655307) (xy 180.080255 -405.705231)
			(xy 180.036918 -405.749981) (xy 179.988213 -405.788821) (xy 179.934942 -405.821114) (xy 179.877979 -405.846331)
			(xy 179.838782 -405.857964) (xy 187.266832 -405.857964) (xy 187.270903 -405.802342) (xy 187.283029 -405.747905)
			(xy 187.302952 -405.695814) (xy 187.330248 -405.647179) (xy 187.364334 -405.603036) (xy 187.404483 -405.564327)
			(xy 187.449841 -405.531876) (xy 187.499441 -405.506375) (xy 187.552225 -405.488368) (xy 187.607068 -405.478238)
			(xy 187.662802 -405.476201) (xy 187.718239 -405.482301) (xy 187.772196 -405.496407) (xy 187.823525 -405.518219)
			(xy 187.871131 -405.547273) (xy 187.913999 -405.582948) (xy 187.951216 -405.624485) (xy 187.981989 -405.670998)
			(xy 188.005661 -405.721495) (xy 188.021729 -405.774902) (xy 188.029849 -405.830078) (xy 188.030358 -405.857964)
			(xy 188.029849 -405.88585) (xy 188.021729 -405.941026) (xy 188.005661 -405.994433) (xy 187.981989 -406.04493)
			(xy 187.951216 -406.091443) (xy 187.913999 -406.13298) (xy 187.871131 -406.168655) (xy 187.823525 -406.197709)
			(xy 187.772196 -406.219521) (xy 187.718239 -406.233627) (xy 187.662802 -406.239727) (xy 187.607068 -406.23769)
			(xy 187.552225 -406.22756) (xy 187.499441 -406.209553) (xy 187.449841 -406.184052) (xy 187.404483 -406.151601)
			(xy 187.364334 -406.112892) (xy 187.330248 -406.068749) (xy 187.302952 -406.020114) (xy 187.283029 -405.968023)
			(xy 187.270903 -405.913586) (xy 187.266832 -405.857964) (xy 179.838782 -405.857964) (xy 179.818258 -405.864055)
			(xy 179.756761 -405.873998) (xy 179.694498 -405.875994) (xy 179.632491 -405.870012) (xy 179.571757 -405.85615)
			(xy 179.513295 -405.834636) (xy 179.458064 -405.805822) (xy 179.406972 -405.770182) (xy 179.360856 -405.728301)
			(xy 179.320474 -405.680866) (xy 179.28649 -405.628657) (xy 179.259461 -405.572531) (xy 179.239832 -405.51341)
			(xy 179.227923 -405.452263) (xy 179.223932 -405.390096) (xy 177.952403 -405.390096) (xy 177.971314 -405.436805)
			(xy 177.987115 -405.497063) (xy 177.995081 -405.558846) (xy 177.99558 -405.589994) (xy 177.995081 -405.621142)
			(xy 177.987115 -405.682925) (xy 177.971314 -405.743183) (xy 177.947936 -405.800926) (xy 177.917367 -405.855205)
			(xy 177.880107 -405.905129) (xy 177.83677 -405.949879) (xy 177.788065 -405.988719) (xy 177.734794 -406.021012)
			(xy 177.677831 -406.046229) (xy 177.61811 -406.063953) (xy 177.556613 -406.073896) (xy 177.49435 -406.075892)
			(xy 177.432343 -406.06991) (xy 177.371609 -406.056048) (xy 177.313147 -406.034534) (xy 177.257916 -406.00572)
			(xy 177.206824 -405.97008) (xy 177.160708 -405.928199) (xy 177.120326 -405.880764) (xy 177.086342 -405.828555)
			(xy 177.059313 -405.772429) (xy 177.039684 -405.713308) (xy 177.027775 -405.652161) (xy 177.023784 -405.589994)
			(xy 175.752113 -405.589994) (xy 175.743174 -405.610909) (xy 175.726852 -405.63927) (xy 175.723552 -405.645302)
			(xy 175.719936 -405.65856) (xy 175.71974 -405.665432) (xy 175.71974 -406.414732) (xy 175.719915 -406.421607)
			(xy 175.723534 -406.434869) (xy 175.726852 -406.440894) (xy 175.743147 -406.46927) (xy 175.768868 -406.529438)
			(xy 175.786279 -406.592513) (xy 175.795067 -406.657355) (xy 175.795068 -406.690068) (xy 179.223932 -406.690068)
			(xy 179.227923 -406.627901) (xy 179.239832 -406.566754) (xy 179.259461 -406.507633) (xy 179.28649 -406.451507)
			(xy 179.320474 -406.399298) (xy 179.360856 -406.351863) (xy 179.406972 -406.309982) (xy 179.458064 -406.274342)
			(xy 179.513295 -406.245528) (xy 179.571757 -406.224014) (xy 179.632491 -406.210152) (xy 179.694498 -406.20417)
			(xy 179.756761 -406.206166) (xy 179.818258 -406.216109) (xy 179.877979 -406.233833) (xy 179.934942 -406.25905)
			(xy 179.988213 -406.291343) (xy 180.036918 -406.330183) (xy 180.080255 -406.374933) (xy 180.117515 -406.424857)
			(xy 180.148084 -406.479136) (xy 180.161087 -406.511252) (xy 198.765666 -406.511252) (xy 198.769737 -406.45563)
			(xy 198.781863 -406.401193) (xy 198.801786 -406.349102) (xy 198.829082 -406.300467) (xy 198.863168 -406.256324)
			(xy 198.903317 -406.217615) (xy 198.948675 -406.185164) (xy 198.998275 -406.159663) (xy 199.051059 -406.141656)
			(xy 199.105902 -406.131526) (xy 199.161636 -406.129489) (xy 199.217073 -406.135589) (xy 199.27103 -406.149695)
			(xy 199.322359 -406.171507) (xy 199.369965 -406.200561) (xy 199.412833 -406.236236) (xy 199.45005 -406.277773)
			(xy 199.480823 -406.324286) (xy 199.504495 -406.374783) (xy 199.520563 -406.42819) (xy 199.528683 -406.483366)
			(xy 199.529192 -406.511252) (xy 199.528683 -406.539138) (xy 199.520563 -406.594314) (xy 199.504495 -406.647721)
			(xy 199.480823 -406.698218) (xy 199.45005 -406.744731) (xy 199.412833 -406.786268) (xy 199.369965 -406.821943)
			(xy 199.322359 -406.850997) (xy 199.27103 -406.872809) (xy 199.217073 -406.886915) (xy 199.161636 -406.893015)
			(xy 199.105902 -406.890978) (xy 199.051059 -406.880848) (xy 198.998275 -406.862841) (xy 198.948675 -406.83734)
			(xy 198.903317 -406.804889) (xy 198.863168 -406.76618) (xy 198.829082 -406.722037) (xy 198.801786 -406.673402)
			(xy 198.781863 -406.621311) (xy 198.769737 -406.566874) (xy 198.765666 -406.511252) (xy 180.161087 -406.511252)
			(xy 180.171462 -406.536879) (xy 180.187263 -406.597137) (xy 180.195229 -406.65892) (xy 180.195728 -406.690068)
			(xy 180.195229 -406.721216) (xy 180.187263 -406.782999) (xy 180.171462 -406.843257) (xy 180.148084 -406.901)
			(xy 180.117515 -406.955279) (xy 180.088348 -406.99436) (xy 187.04255 -406.99436) (xy 187.046621 -406.938738)
			(xy 187.058747 -406.884301) (xy 187.07867 -406.83221) (xy 187.105966 -406.783575) (xy 187.140052 -406.739432)
			(xy 187.180201 -406.700723) (xy 187.225559 -406.668272) (xy 187.275159 -406.642771) (xy 187.327943 -406.624764)
			(xy 187.382786 -406.614634) (xy 187.43852 -406.612597) (xy 187.493957 -406.618697) (xy 187.547914 -406.632803)
			(xy 187.599243 -406.654615) (xy 187.646849 -406.683669) (xy 187.689717 -406.719344) (xy 187.726934 -406.760881)
			(xy 187.757707 -406.807394) (xy 187.781379 -406.857891) (xy 187.797447 -406.911298) (xy 187.805567 -406.966474)
			(xy 187.806076 -406.99436) (xy 187.805567 -407.022246) (xy 187.797447 -407.077422) (xy 187.781379 -407.130829)
			(xy 187.757707 -407.181326) (xy 187.726934 -407.227839) (xy 187.689717 -407.269376) (xy 187.646849 -407.305051)
			(xy 187.599243 -407.334105) (xy 187.547914 -407.355917) (xy 187.493957 -407.370023) (xy 187.43852 -407.376123)
			(xy 187.382786 -407.374086) (xy 187.327943 -407.363956) (xy 187.275159 -407.345949) (xy 187.225559 -407.320448)
			(xy 187.180201 -407.287997) (xy 187.140052 -407.249288) (xy 187.105966 -407.205145) (xy 187.07867 -407.15651)
			(xy 187.058747 -407.104419) (xy 187.046621 -407.049982) (xy 187.04255 -406.99436) (xy 180.088348 -406.99436)
			(xy 180.080255 -407.005203) (xy 180.036918 -407.049953) (xy 179.988213 -407.088793) (xy 179.934942 -407.121086)
			(xy 179.877979 -407.146303) (xy 179.818258 -407.164027) (xy 179.756761 -407.17397) (xy 179.694498 -407.175966)
			(xy 179.632491 -407.169984) (xy 179.571757 -407.156122) (xy 179.513295 -407.134608) (xy 179.458064 -407.105794)
			(xy 179.406972 -407.070154) (xy 179.360856 -407.028273) (xy 179.320474 -406.980838) (xy 179.28649 -406.928629)
			(xy 179.259461 -406.872503) (xy 179.239832 -406.813382) (xy 179.227923 -406.752235) (xy 179.223932 -406.690068)
			(xy 175.795068 -406.690068) (xy 175.79507 -406.72279) (xy 175.78629 -406.787633) (xy 175.768886 -406.85071)
			(xy 175.743172 -406.910881) (xy 175.726852 -406.939242) (xy 175.723526 -406.945261) (xy 175.719927 -406.958529)
			(xy 175.71974 -406.965404) (xy 175.71974 -407.251408) (xy 175.719286 -407.261558) (xy 175.711495 -407.280302)
			(xy 175.697109 -407.294624) (xy 175.678329 -407.302331) (xy 175.668178 -407.302716) (xy 174.951898 -407.302716)
			(xy 174.941766 -407.302274) (xy 174.923036 -407.294537) (xy 174.908679 -407.280237) (xy 174.900867 -407.261538)
			(xy 174.900336 -407.251408) (xy 174.900336 -406.965404) (xy 174.900138 -406.958531) (xy 174.896533 -406.945269)
			(xy 174.893224 -406.939242) (xy 174.876875 -406.910896) (xy 174.851161 -406.850721) (xy 174.833756 -406.787639)
			(xy 174.824976 -406.722792) (xy 171.39508 -406.722792) (xy 171.39508 -406.722798) (xy 171.386223 -406.787656)
			(xy 171.368732 -406.850736) (xy 171.342925 -406.910894) (xy 171.326556 -406.939242) (xy 171.323231 -406.945262)
			(xy 171.319631 -406.958529) (xy 171.319444 -406.965404) (xy 171.319444 -407.251408) (xy 171.318922 -407.261512)
			(xy 171.31119 -407.280182) (xy 171.296905 -407.294475) (xy 171.278239 -407.302217) (xy 171.268136 -407.302716)
			(xy 170.551856 -407.302716) (xy 170.541746 -407.302251) (xy 170.52307 -407.294502) (xy 170.508778 -407.280199)
			(xy 170.501042 -407.261518) (xy 170.500548 -407.251408) (xy 170.500548 -406.965404) (xy 170.500361 -406.95853)
			(xy 170.49675 -406.945267) (xy 170.493436 -406.939242) (xy 170.477091 -406.910882) (xy 170.451283 -406.850726)
			(xy 170.433788 -406.78765) (xy 170.424921 -406.722796) (xy 170.424348 -406.690068) (xy 166.994982 -406.690068)
			(xy 166.994984 -406.72279) (xy 166.986205 -406.787633) (xy 166.968801 -406.85071) (xy 166.943088 -406.910881)
			(xy 166.926768 -406.939242) (xy 166.923436 -406.945258) (xy 166.919842 -406.958529) (xy 166.919656 -406.965404)
			(xy 166.919656 -407.251408) (xy 166.919186 -407.261556) (xy 166.911398 -407.280297) (xy 166.897017 -407.294618)
			(xy 166.878243 -407.302328) (xy 166.868094 -407.302716) (xy 166.151814 -407.302716) (xy 166.141683 -407.302261)
			(xy 166.122954 -407.294529) (xy 166.108595 -407.280233) (xy 166.100783 -407.261537) (xy 166.100252 -407.251408)
			(xy 166.100252 -406.965404) (xy 166.100064 -406.95853) (xy 166.096454 -406.945267) (xy 166.09314 -406.939242)
			(xy 166.076791 -406.910896) (xy 166.051076 -406.850721) (xy 166.03367 -406.787639) (xy 166.02489 -406.722792)
			(xy 162.594994 -406.722792) (xy 162.594994 -406.722797) (xy 162.586137 -406.787655) (xy 162.568647 -406.850735)
			(xy 162.54284 -406.910894) (xy 162.526472 -406.939242) (xy 162.52314 -406.945258) (xy 162.519546 -406.958529)
			(xy 162.51936 -406.965404) (xy 162.51936 -407.251408) (xy 162.518989 -407.261536) (xy 162.511231 -407.280247)
			(xy 162.4969 -407.294563) (xy 162.47818 -407.3023) (xy 162.468052 -407.302716) (xy 161.751772 -407.302716)
			(xy 161.741663 -407.302238) (xy 161.722988 -407.294494) (xy 161.708694 -407.280196) (xy 161.700958 -407.261517)
			(xy 161.700464 -407.251408) (xy 161.700464 -406.965404) (xy 161.700275 -406.95853) (xy 161.696665 -406.945268)
			(xy 161.693352 -406.939242) (xy 161.677008 -406.910881) (xy 161.6512 -406.850726) (xy 161.633704 -406.78765)
			(xy 161.624837 -406.722796) (xy 161.624264 -406.690068) (xy 154.576272 -406.690068) (xy 154.576272 -407.4414)
			(xy 185.755532 -407.4414) (xy 185.759603 -407.385778) (xy 185.771729 -407.331341) (xy 185.791652 -407.27925)
			(xy 185.818948 -407.230615) (xy 185.853034 -407.186472) (xy 185.893183 -407.147763) (xy 185.938541 -407.115312)
			(xy 185.988141 -407.089811) (xy 186.040925 -407.071804) (xy 186.095768 -407.061674) (xy 186.151502 -407.059637)
			(xy 186.206939 -407.065737) (xy 186.260896 -407.079843) (xy 186.312225 -407.101655) (xy 186.359831 -407.130709)
			(xy 186.402699 -407.166384) (xy 186.439916 -407.207921) (xy 186.470689 -407.254434) (xy 186.494361 -407.304931)
			(xy 186.510429 -407.358338) (xy 186.518549 -407.413514) (xy 186.519058 -407.4414) (xy 186.518549 -407.469286)
			(xy 186.510429 -407.524462) (xy 186.494361 -407.577869) (xy 186.470689 -407.628366) (xy 186.439916 -407.674879)
			(xy 186.402699 -407.716416) (xy 186.359831 -407.752091) (xy 186.312225 -407.781145) (xy 186.260896 -407.802957)
			(xy 186.206939 -407.817063) (xy 186.151502 -407.823163) (xy 186.095768 -407.821126) (xy 186.040925 -407.810996)
			(xy 185.988141 -407.792989) (xy 185.938541 -407.767488) (xy 185.893183 -407.735037) (xy 185.853034 -407.696328)
			(xy 185.818948 -407.652185) (xy 185.791652 -407.60355) (xy 185.771729 -407.551459) (xy 185.759603 -407.497022)
			(xy 185.755532 -407.4414) (xy 154.576272 -407.4414) (xy 154.576272 -409.522889) (xy 159.424957 -409.522889)
			(xy 159.424961 -409.45745) (xy 159.433748 -409.392604) (xy 159.45116 -409.329524) (xy 159.47688 -409.269352)
			(xy 159.493204 -409.24099) (xy 159.496523 -409.234967) (xy 159.500126 -409.221702) (xy 159.500316 -409.214828)
			(xy 159.500316 -408.465528) (xy 159.500112 -408.458656) (xy 159.496512 -408.445393) (xy 159.493204 -408.439366)
			(xy 159.476876 -408.411008) (xy 159.451161 -408.350836) (xy 159.433755 -408.287756) (xy 159.424973 -408.222912)
			(xy 159.424974 -408.157475) (xy 159.433758 -408.09263) (xy 159.451165 -408.029551) (xy 159.476882 -407.96938)
			(xy 159.493204 -407.941018) (xy 159.496513 -407.93499) (xy 159.500122 -407.921729) (xy 159.500316 -407.914856)
			(xy 159.500316 -407.628852) (xy 159.500683 -407.618693) (xy 159.508497 -407.599936) (xy 159.522911 -407.585614)
			(xy 159.541716 -407.577919) (xy 159.551878 -407.577544) (xy 160.268158 -407.577544) (xy 160.278283 -407.578061)
			(xy 160.297003 -407.585776) (xy 160.311361 -407.600053) (xy 160.319181 -407.61873) (xy 160.31972 -407.628852)
			(xy 160.31972 -407.914856) (xy 160.319926 -407.921728) (xy 160.323525 -407.934991) (xy 160.326832 -407.941018)
			(xy 160.343148 -407.969383) (xy 160.368868 -408.029553) (xy 160.386278 -408.092631) (xy 160.395063 -408.157475)
			(xy 160.395064 -408.222911) (xy 160.386281 -408.287756) (xy 160.368873 -408.350834) (xy 160.343155 -408.411005)
			(xy 160.326832 -408.439366) (xy 160.323532 -408.445398) (xy 160.319917 -408.458656) (xy 160.31972 -408.465528)
			(xy 160.31972 -409.214828) (xy 160.319899 -409.221702) (xy 160.323516 -409.234965) (xy 160.326832 -409.24099)
			(xy 160.343125 -409.269368) (xy 160.368847 -409.329535) (xy 160.386259 -409.39261) (xy 160.395047 -409.457452)
			(xy 160.395051 -409.522886) (xy 160.386272 -409.587729) (xy 160.368867 -409.650807) (xy 160.343153 -409.710977)
			(xy 160.326832 -409.739338) (xy 160.323506 -409.745357) (xy 160.319907 -409.758625) (xy 160.31972 -409.7655)
			(xy 160.31972 -410.051504) (xy 160.319282 -410.061656) (xy 160.311489 -410.080404) (xy 160.297098 -410.094727)
			(xy 160.278312 -410.10243) (xy 160.268158 -410.102812) (xy 159.551878 -410.102812) (xy 159.541756 -410.102293)
			(xy 159.523044 -410.094568) (xy 159.508691 -410.080292) (xy 159.500863 -410.061623) (xy 159.500316 -410.051504)
			(xy 159.500316 -409.7655) (xy 159.500122 -409.758627) (xy 159.496515 -409.745364) (xy 159.493204 -409.739338)
			(xy 159.476852 -409.710993) (xy 159.451139 -409.650818) (xy 159.433736 -409.587736) (xy 159.424957 -409.522889)
			(xy 154.576272 -409.522889) (xy 154.576272 -410.589984) (xy 161.624264 -410.589984) (xy 161.62485 -410.557255)
			(xy 161.633701 -410.492398) (xy 161.651185 -410.429318) (xy 161.676987 -410.369159) (xy 161.693352 -410.34081)
			(xy 161.696659 -410.334782) (xy 161.70027 -410.321521) (xy 161.700464 -410.314648) (xy 161.700464 -409.565348)
			(xy 161.700258 -409.558476) (xy 161.69666 -409.545213) (xy 161.693352 -409.539186) (xy 161.676986 -409.510837)
			(xy 161.651183 -409.450678) (xy 161.633693 -409.387598) (xy 161.624834 -409.322741) (xy 161.624264 -409.290012)
			(xy 161.624817 -409.257282) (xy 161.633678 -409.192424) (xy 161.651172 -409.129343) (xy 161.676982 -409.069186)
			(xy 161.693352 -409.040838) (xy 161.696649 -409.034805) (xy 161.700267 -409.021548) (xy 161.700464 -409.014676)
			(xy 161.700464 -408.728672) (xy 161.700961 -408.718566) (xy 161.708701 -408.699894) (xy 161.722994 -408.685601)
			(xy 161.741666 -408.677861) (xy 161.751772 -408.677364) (xy 162.468052 -408.677364) (xy 162.478167 -408.677854)
			(xy 162.496863 -408.68558) (xy 162.511177 -408.699874) (xy 162.518931 -408.718558) (xy 162.51936 -408.728672)
			(xy 162.51936 -409.014676) (xy 162.519566 -409.021548) (xy 162.523165 -409.034811) (xy 162.526472 -409.040838)
			(xy 162.54285 -409.06918) (xy 162.568649 -409.129342) (xy 162.586136 -409.192424) (xy 162.594992 -409.257282)
			(xy 162.59556 -409.290012) (xy 162.594969 -409.322741) (xy 162.58612 -409.387598) (xy 162.568637 -409.450678)
			(xy 162.551703 -409.490164) (xy 163.824412 -409.490164) (xy 163.824982 -409.457435) (xy 163.833837 -409.392577)
			(xy 163.851326 -409.329496) (xy 163.877132 -409.269338) (xy 163.8935 -409.24099) (xy 163.896818 -409.234967)
			(xy 163.900422 -409.221702) (xy 163.900612 -409.214828) (xy 163.900612 -408.465528) (xy 163.900408 -408.458656)
			(xy 163.896808 -408.445393) (xy 163.8935 -408.439366) (xy 163.877121 -408.411024) (xy 163.851322 -408.350862)
			(xy 163.833836 -408.28778) (xy 163.82498 -408.222922) (xy 163.824412 -408.190192) (xy 163.824995 -408.157463)
			(xy 163.833845 -408.092605) (xy 163.851331 -408.029525) (xy 163.877134 -407.969367) (xy 163.8935 -407.941018)
			(xy 163.896808 -407.93499) (xy 163.900418 -407.921729) (xy 163.900612 -407.914856) (xy 163.900612 -407.628852)
			(xy 163.901046 -407.618739) (xy 163.908802 -407.600057) (xy 163.923114 -407.585764) (xy 163.941806 -407.578033)
			(xy 163.95192 -407.577544) (xy 164.6682 -407.577544) (xy 164.678302 -407.578084) (xy 164.696969 -407.585811)
			(xy 164.711262 -407.60009) (xy 164.719007 -407.618751) (xy 164.719508 -407.628852) (xy 164.719508 -407.914856)
			(xy 164.719716 -407.921728) (xy 164.723313 -407.934991) (xy 164.72662 -407.941018) (xy 164.742995 -407.969362)
			(xy 164.768794 -408.029524) (xy 164.786281 -408.092605) (xy 164.795139 -408.157463) (xy 164.795708 -408.190192)
			(xy 164.79516 -408.222922) (xy 164.786299 -408.287781) (xy 164.768804 -408.350861) (xy 164.742991 -408.411019)
			(xy 164.72662 -408.439366) (xy 164.723319 -408.445397) (xy 164.719704 -408.458656) (xy 164.719508 -408.465528)
			(xy 164.719508 -409.214828) (xy 164.719688 -409.221702) (xy 164.723304 -409.234965) (xy 164.72662 -409.24099)
			(xy 164.742984 -409.26934) (xy 164.768785 -409.3295) (xy 164.786276 -409.392579) (xy 164.795137 -409.457435)
			(xy 164.795708 -409.490164) (xy 164.795147 -409.522894) (xy 164.78629 -409.587752) (xy 164.768798 -409.650832)
			(xy 164.742989 -409.71099) (xy 164.72662 -409.739338) (xy 164.723293 -409.745357) (xy 164.719695 -409.758625)
			(xy 164.719508 -409.7655) (xy 164.719508 -410.051504) (xy 164.719018 -410.061612) (xy 164.711281 -410.080289)
			(xy 164.696985 -410.094583) (xy 164.678308 -410.102319) (xy 164.6682 -410.102812) (xy 163.95192 -410.102812)
			(xy 163.9418 -410.102368) (xy 163.923099 -410.094629) (xy 163.908785 -410.080321) (xy 163.901037 -410.061624)
			(xy 163.900612 -410.051504) (xy 163.900612 -409.7655) (xy 163.900419 -409.758627) (xy 163.896811 -409.745364)
			(xy 163.8935 -409.739338) (xy 163.87715 -409.71098) (xy 163.851344 -409.650824) (xy 163.83385 -409.587747)
			(xy 163.824985 -409.522892) (xy 163.824412 -409.490164) (xy 162.551703 -409.490164) (xy 162.542837 -409.510837)
			(xy 162.526472 -409.539186) (xy 162.52316 -409.545212) (xy 162.519553 -409.558475) (xy 162.51936 -409.565348)
			(xy 162.51936 -410.314648) (xy 162.519577 -410.321519) (xy 162.523169 -410.334782) (xy 162.526472 -410.34081)
			(xy 162.542839 -410.369159) (xy 162.568641 -410.429318) (xy 162.58613 -410.492398) (xy 162.59499 -410.557255)
			(xy 162.59556 -410.589984) (xy 162.595001 -410.622705) (xy 166.024899 -410.622705) (xy 166.024901 -410.557267)
			(xy 166.033687 -410.492422) (xy 166.051097 -410.429343) (xy 166.076817 -410.369171) (xy 166.09314 -410.34081)
			(xy 166.096446 -410.334781) (xy 166.100058 -410.321521) (xy 166.100252 -410.314648) (xy 166.100252 -409.565348)
			(xy 166.100048 -409.558476) (xy 166.096449 -409.545213) (xy 166.09314 -409.539186) (xy 166.076828 -409.510819)
			(xy 166.051109 -409.450649) (xy 166.0337 -409.387572) (xy 166.024915 -409.322728) (xy 166.024914 -409.257292)
			(xy 166.033696 -409.192448) (xy 166.051102 -409.12937) (xy 166.076819 -409.069199) (xy 166.09314 -409.040838)
			(xy 166.096437 -409.034804) (xy 166.100054 -409.021548) (xy 166.100252 -409.014676) (xy 166.100252 -408.728672)
			(xy 166.100698 -408.718522) (xy 166.108493 -408.699778) (xy 166.122882 -408.685458) (xy 166.141662 -408.67775)
			(xy 166.151814 -408.677364) (xy 166.868094 -408.677364) (xy 166.878223 -408.677832) (xy 166.896949 -408.685562)
			(xy 166.911306 -408.699855) (xy 166.919121 -408.718545) (xy 166.919656 -408.728672) (xy 166.919656 -409.014676)
			(xy 166.91985 -409.021549) (xy 166.923456 -409.034812) (xy 166.926768 -409.040838) (xy 166.9431 -409.069194)
			(xy 166.968816 -409.129366) (xy 166.986223 -409.192446) (xy 166.995005 -409.257292) (xy 166.995004 -409.322729)
			(xy 166.986219 -409.387574) (xy 166.96881 -409.450653) (xy 166.943091 -409.510825) (xy 166.936148 -409.522888)
			(xy 168.225043 -409.522888) (xy 168.225047 -409.45745) (xy 168.233834 -409.392604) (xy 168.251245 -409.329524)
			(xy 168.276965 -409.269352) (xy 168.293288 -409.24099) (xy 168.296605 -409.234967) (xy 168.30021 -409.221702)
			(xy 168.3004 -409.214828) (xy 168.3004 -408.465528) (xy 168.300197 -408.458656) (xy 168.296596 -408.445393)
			(xy 168.293288 -408.439366) (xy 168.276961 -408.411008) (xy 168.251246 -408.350835) (xy 168.233841 -408.287756)
			(xy 168.225059 -408.222911) (xy 168.22506 -408.157475) (xy 168.233844 -408.09263) (xy 168.251251 -408.029552)
			(xy 168.276967 -407.96938) (xy 168.293288 -407.941018) (xy 168.296595 -407.93499) (xy 168.300206 -407.921729)
			(xy 168.3004 -407.914856) (xy 168.3004 -407.628852) (xy 168.300782 -407.618695) (xy 168.308594 -407.599941)
			(xy 168.323002 -407.58562) (xy 168.341802 -407.577922) (xy 168.351962 -407.577544) (xy 169.068242 -407.577544)
			(xy 169.078372 -407.577992) (xy 169.097095 -407.585735) (xy 169.11145 -407.600032) (xy 169.119267 -407.618724)
			(xy 169.119804 -407.628852) (xy 169.119804 -407.914856) (xy 169.120012 -407.921728) (xy 169.123609 -407.934991)
			(xy 169.126916 -407.941018) (xy 169.143233 -407.969383) (xy 169.168953 -408.029552) (xy 169.186364 -408.09263)
			(xy 169.195149 -408.157475) (xy 169.19515 -408.222912) (xy 169.186367 -408.287756) (xy 169.168958 -408.350835)
			(xy 169.143239 -408.411005) (xy 169.126916 -408.439366) (xy 169.123614 -408.445397) (xy 169.12 -408.458656)
			(xy 169.119804 -408.465528) (xy 169.119804 -409.214828) (xy 169.119985 -409.221702) (xy 169.1236 -409.234965)
			(xy 169.126916 -409.24099) (xy 169.143209 -409.269368) (xy 169.168932 -409.329534) (xy 169.186345 -409.39261)
			(xy 169.195133 -409.457452) (xy 169.195137 -409.522887) (xy 169.186357 -409.58773) (xy 169.168952 -409.650807)
			(xy 169.143237 -409.710977) (xy 169.126916 -409.739338) (xy 169.123589 -409.745357) (xy 169.119991 -409.758625)
			(xy 169.119804 -409.7655) (xy 169.119804 -410.051504) (xy 169.119382 -410.061658) (xy 169.111586 -410.08041)
			(xy 169.097189 -410.094733) (xy 169.078398 -410.102433) (xy 169.068242 -410.102812) (xy 168.351962 -410.102812)
			(xy 168.341839 -410.102306) (xy 168.323127 -410.094575) (xy 168.308774 -410.080296) (xy 168.300947 -410.061624)
			(xy 168.3004 -410.051504) (xy 168.3004 -409.7655) (xy 168.300208 -409.758627) (xy 168.2966 -409.745364)
			(xy 168.293288 -409.739338) (xy 168.276937 -409.710993) (xy 168.251225 -409.650817) (xy 168.233822 -409.587735)
			(xy 168.225043 -409.522888) (xy 166.936148 -409.522888) (xy 166.926768 -409.539186) (xy 166.923456 -409.545212)
			(xy 166.919849 -409.558475) (xy 166.919656 -409.565348) (xy 166.919656 -410.314648) (xy 166.919861 -410.32152)
			(xy 166.923459 -410.334783) (xy 166.926768 -410.34081) (xy 166.943076 -410.369179) (xy 166.968795 -410.429348)
			(xy 166.986204 -410.492425) (xy 166.994989 -410.557269) (xy 166.99499 -410.589984) (xy 170.424348 -410.589984)
			(xy 170.424936 -410.557255) (xy 170.433786 -410.492398) (xy 170.45127 -410.429318) (xy 170.477071 -410.369159)
			(xy 170.493436 -410.34081) (xy 170.496742 -410.334781) (xy 170.500354 -410.321521) (xy 170.500548 -410.314648)
			(xy 170.500548 -409.565348) (xy 170.500344 -409.558476) (xy 170.496745 -409.545212) (xy 170.493436 -409.539186)
			(xy 170.477068 -409.510838) (xy 170.451266 -409.450678) (xy 170.433777 -409.387598) (xy 170.424918 -409.322741)
			(xy 170.424348 -409.290012) (xy 170.424904 -409.257282) (xy 170.433764 -409.192424) (xy 170.451257 -409.129344)
			(xy 170.477066 -409.069186) (xy 170.493436 -409.040838) (xy 170.496732 -409.034804) (xy 170.50035 -409.021548)
			(xy 170.500548 -409.014676) (xy 170.500548 -408.728672) (xy 170.501061 -408.718568) (xy 170.508798 -408.699899)
			(xy 170.523086 -408.685607) (xy 170.541752 -408.677864) (xy 170.551856 -408.677364) (xy 171.268136 -408.677364)
			(xy 171.278243 -408.677855) (xy 171.296915 -408.685598) (xy 171.311207 -408.699892) (xy 171.318947 -408.718565)
			(xy 171.319444 -408.728672) (xy 171.319444 -409.014676) (xy 171.31964 -409.021549) (xy 171.323245 -409.034812)
			(xy 171.326556 -409.040838) (xy 171.342932 -409.069181) (xy 171.368733 -409.129343) (xy 171.386219 -409.192424)
			(xy 171.395076 -409.257282) (xy 171.395644 -409.290012) (xy 171.395056 -409.322741) (xy 171.386206 -409.387598)
			(xy 171.368722 -409.450678) (xy 171.342921 -409.510837) (xy 171.335964 -409.522889) (xy 172.624819 -409.522889)
			(xy 172.624823 -409.457449) (xy 172.633612 -409.392602) (xy 172.651026 -409.329522) (xy 172.67675 -409.269351)
			(xy 172.693076 -409.24099) (xy 172.696393 -409.234966) (xy 172.699998 -409.221702) (xy 172.700188 -409.214828)
			(xy 172.700188 -408.465528) (xy 172.699987 -408.458655) (xy 172.696385 -408.445393) (xy 172.693076 -408.439366)
			(xy 172.676746 -408.411009) (xy 172.651027 -408.350837) (xy 172.633618 -408.287758) (xy 172.624835 -408.222912)
			(xy 172.624836 -408.157474) (xy 172.633621 -408.092629) (xy 172.651031 -408.02955) (xy 172.676752 -407.969379)
			(xy 172.693076 -407.941018) (xy 172.696383 -407.934989) (xy 172.699994 -407.921729) (xy 172.700188 -407.914856)
			(xy 172.700188 -407.628852) (xy 172.700582 -407.618696) (xy 172.708391 -407.599945) (xy 172.722796 -407.585624)
			(xy 172.741592 -407.577924) (xy 172.75175 -407.577544) (xy 173.46803 -407.577544) (xy 173.478159 -407.578002)
			(xy 173.496882 -407.58574) (xy 173.511237 -407.600035) (xy 173.519055 -407.618725) (xy 173.519592 -407.628852)
			(xy 173.519592 -407.914856) (xy 173.519802 -407.921728) (xy 173.523398 -407.934991) (xy 173.526704 -407.941018)
			(xy 173.543018 -407.969383) (xy 173.568734 -408.029554) (xy 173.586141 -408.092632) (xy 173.594925 -408.157475)
			(xy 173.594925 -408.190192) (xy 177.023784 -408.190192) (xy 177.027775 -408.128025) (xy 177.039684 -408.066878)
			(xy 177.059313 -408.007757) (xy 177.086342 -407.951631) (xy 177.120326 -407.899422) (xy 177.160708 -407.851987)
			(xy 177.206824 -407.810106) (xy 177.257916 -407.774466) (xy 177.313147 -407.745652) (xy 177.371609 -407.724138)
			(xy 177.432343 -407.710276) (xy 177.49435 -407.704294) (xy 177.556613 -407.70629) (xy 177.61811 -407.716233)
			(xy 177.677831 -407.733957) (xy 177.734794 -407.759174) (xy 177.788065 -407.791467) (xy 177.83677 -407.830307)
			(xy 177.880107 -407.875057) (xy 177.917367 -407.924981) (xy 177.947936 -407.97926) (xy 177.971314 -408.037003)
			(xy 177.987115 -408.097261) (xy 177.995081 -408.159044) (xy 177.99558 -408.190192) (xy 177.995081 -408.22134)
			(xy 177.987115 -408.283123) (xy 177.971314 -408.343381) (xy 177.947936 -408.401124) (xy 177.917367 -408.455403)
			(xy 177.880107 -408.505327) (xy 177.83677 -408.550077) (xy 177.788065 -408.588917) (xy 177.782527 -408.592274)
			(xy 190.042798 -408.592274) (xy 190.046869 -408.536652) (xy 190.058995 -408.482215) (xy 190.078918 -408.430124)
			(xy 190.106214 -408.381489) (xy 190.1403 -408.337346) (xy 190.180449 -408.298637) (xy 190.225807 -408.266186)
			(xy 190.275407 -408.240685) (xy 190.328191 -408.222678) (xy 190.383034 -408.212548) (xy 190.438768 -408.210511)
			(xy 190.494205 -408.216611) (xy 190.548162 -408.230717) (xy 190.599491 -408.252529) (xy 190.647097 -408.281583)
			(xy 190.689965 -408.317258) (xy 190.727182 -408.358795) (xy 190.757955 -408.405308) (xy 190.781627 -408.455805)
			(xy 190.797695 -408.509212) (xy 190.805815 -408.564388) (xy 190.806324 -408.592274) (xy 190.805815 -408.62016)
			(xy 190.797695 -408.675336) (xy 190.781627 -408.728743) (xy 190.757955 -408.77924) (xy 190.727182 -408.825753)
			(xy 190.689965 -408.86729) (xy 190.647097 -408.902965) (xy 190.599491 -408.932019) (xy 190.548162 -408.953831)
			(xy 190.520426 -408.961082) (xy 194.781676 -408.961082) (xy 194.785747 -408.90546) (xy 194.797873 -408.851023)
			(xy 194.817796 -408.798932) (xy 194.845092 -408.750297) (xy 194.879178 -408.706154) (xy 194.919327 -408.667445)
			(xy 194.964685 -408.634994) (xy 195.014285 -408.609493) (xy 195.067069 -408.591486) (xy 195.121912 -408.581356)
			(xy 195.177646 -408.579319) (xy 195.233083 -408.585419) (xy 195.28704 -408.599525) (xy 195.338369 -408.621337)
			(xy 195.385975 -408.650391) (xy 195.42327 -408.681428) (xy 196.990968 -408.681428) (xy 196.995039 -408.625806)
			(xy 197.007165 -408.571369) (xy 197.027088 -408.519278) (xy 197.054384 -408.470643) (xy 197.08847 -408.4265)
			(xy 197.128619 -408.387791) (xy 197.173977 -408.35534) (xy 197.223577 -408.329839) (xy 197.276361 -408.311832)
			(xy 197.331204 -408.301702) (xy 197.386938 -408.299665) (xy 197.442375 -408.305765) (xy 197.496332 -408.319871)
			(xy 197.547661 -408.341683) (xy 197.595267 -408.370737) (xy 197.638135 -408.406412) (xy 197.675352 -408.447949)
			(xy 197.706125 -408.494462) (xy 197.729797 -408.544959) (xy 197.745865 -408.598366) (xy 197.753985 -408.653542)
			(xy 197.754494 -408.681428) (xy 197.753985 -408.709314) (xy 197.745865 -408.76449) (xy 197.729797 -408.817897)
			(xy 197.706125 -408.868394) (xy 197.675352 -408.914907) (xy 197.638135 -408.956444) (xy 197.595267 -408.992119)
			(xy 197.547661 -409.021173) (xy 197.496332 -409.042985) (xy 197.442375 -409.057091) (xy 197.386938 -409.063191)
			(xy 197.331204 -409.061154) (xy 197.276361 -409.051024) (xy 197.223577 -409.033017) (xy 197.173977 -409.007516)
			(xy 197.128619 -408.975065) (xy 197.08847 -408.936356) (xy 197.054384 -408.892213) (xy 197.027088 -408.843578)
			(xy 197.007165 -408.791487) (xy 196.995039 -408.73705) (xy 196.990968 -408.681428) (xy 195.42327 -408.681428)
			(xy 195.428843 -408.686066) (xy 195.46606 -408.727603) (xy 195.496833 -408.774116) (xy 195.520505 -408.824613)
			(xy 195.536573 -408.87802) (xy 195.544693 -408.933196) (xy 195.545202 -408.961082) (xy 195.544693 -408.988968)
			(xy 195.536573 -409.044144) (xy 195.520505 -409.097551) (xy 195.496833 -409.148048) (xy 195.46606 -409.194561)
			(xy 195.428843 -409.236098) (xy 195.385975 -409.271773) (xy 195.338369 -409.300827) (xy 195.28704 -409.322639)
			(xy 195.233083 -409.336745) (xy 195.177646 -409.342845) (xy 195.121912 -409.340808) (xy 195.067069 -409.330678)
			(xy 195.014285 -409.312671) (xy 194.964685 -409.28717) (xy 194.919327 -409.254719) (xy 194.879178 -409.21601)
			(xy 194.845092 -409.171867) (xy 194.817796 -409.123232) (xy 194.797873 -409.071141) (xy 194.785747 -409.016704)
			(xy 194.781676 -408.961082) (xy 190.520426 -408.961082) (xy 190.494205 -408.967937) (xy 190.438768 -408.974037)
			(xy 190.383034 -408.972) (xy 190.328191 -408.96187) (xy 190.275407 -408.943863) (xy 190.225807 -408.918362)
			(xy 190.180449 -408.885911) (xy 190.1403 -408.847202) (xy 190.106214 -408.803059) (xy 190.078918 -408.754424)
			(xy 190.058995 -408.702333) (xy 190.046869 -408.647896) (xy 190.042798 -408.592274) (xy 177.782527 -408.592274)
			(xy 177.734794 -408.62121) (xy 177.677831 -408.646427) (xy 177.61811 -408.664151) (xy 177.556613 -408.674094)
			(xy 177.49435 -408.67609) (xy 177.432343 -408.670108) (xy 177.371609 -408.656246) (xy 177.313147 -408.634732)
			(xy 177.257916 -408.605918) (xy 177.206824 -408.570278) (xy 177.160708 -408.528397) (xy 177.120326 -408.480962)
			(xy 177.086342 -408.428753) (xy 177.059313 -408.372627) (xy 177.039684 -408.313506) (xy 177.027775 -408.252359)
			(xy 177.023784 -408.190192) (xy 173.594925 -408.190192) (xy 173.594926 -408.222911) (xy 173.586144 -408.287755)
			(xy 173.568739 -408.350833) (xy 173.543024 -408.411004) (xy 173.526704 -408.439366) (xy 173.523402 -408.445397)
			(xy 173.519788 -408.458656) (xy 173.519592 -408.465528) (xy 173.519592 -409.214828) (xy 173.519774 -409.221702)
			(xy 173.523389 -409.234965) (xy 173.526704 -409.24099) (xy 173.542994 -409.269369) (xy 173.568713 -409.329536)
			(xy 173.586122 -409.392611) (xy 173.594909 -409.457452) (xy 173.594913 -409.522886) (xy 173.586135 -409.587728)
			(xy 173.568733 -409.650805) (xy 173.543022 -409.710976) (xy 173.526704 -409.739338) (xy 173.523376 -409.745356)
			(xy 173.519779 -409.758625) (xy 173.519592 -409.7655) (xy 173.519592 -410.051504) (xy 173.519181 -410.061659)
			(xy 173.511383 -410.080413) (xy 173.496983 -410.094737) (xy 173.478187 -410.102435) (xy 173.46803 -410.102812)
			(xy 172.75175 -410.102812) (xy 172.741633 -410.102234) (xy 172.722923 -410.094532) (xy 172.708567 -410.080274)
			(xy 172.700736 -410.061618) (xy 172.700188 -410.051504) (xy 172.700188 -409.7655) (xy 172.699997 -409.758627)
			(xy 172.696388 -409.745364) (xy 172.693076 -409.739338) (xy 172.676722 -409.710994) (xy 172.651005 -409.650819)
			(xy 172.633599 -409.587737) (xy 172.624819 -409.522889) (xy 171.335964 -409.522889) (xy 171.326556 -409.539186)
			(xy 171.323251 -409.545215) (xy 171.319638 -409.558475) (xy 171.319444 -409.565348) (xy 171.319444 -410.314648)
			(xy 171.31965 -410.32152) (xy 171.323248 -410.334783) (xy 171.326556 -410.34081) (xy 171.342921 -410.369159)
			(xy 171.368724 -410.429319) (xy 171.386214 -410.492398) (xy 171.395074 -410.557255) (xy 171.395644 -410.589984)
			(xy 171.395088 -410.622705) (xy 174.824985 -410.622705) (xy 174.824987 -410.557267) (xy 174.833773 -410.492422)
			(xy 174.851182 -410.429343) (xy 174.876901 -410.369171) (xy 174.893224 -410.34081) (xy 174.896537 -410.334785)
			(xy 174.900143 -410.321521) (xy 174.900336 -410.314648) (xy 174.900336 -409.565348) (xy 174.900121 -409.558476)
			(xy 174.896528 -409.545214) (xy 174.893224 -409.539186) (xy 174.876912 -409.510819) (xy 174.851195 -409.450649)
			(xy 174.833786 -409.387572) (xy 174.825001 -409.322728) (xy 174.825 -409.257292) (xy 174.833782 -409.192449)
			(xy 174.851188 -409.12937) (xy 174.876903 -409.069199) (xy 174.893224 -409.040838) (xy 174.896527 -409.034808)
			(xy 174.90014 -409.021548) (xy 174.900336 -409.014676) (xy 174.900336 -408.728672) (xy 174.900699 -408.718512)
			(xy 174.908511 -408.699752) (xy 174.922926 -408.685428) (xy 174.941735 -408.677736) (xy 174.951898 -408.677364)
			(xy 175.668178 -408.677364) (xy 175.678306 -408.677845) (xy 175.697032 -408.68557) (xy 175.711389 -408.699859)
			(xy 175.719205 -408.718546) (xy 175.71974 -408.728672) (xy 175.71974 -409.014676) (xy 175.719936 -409.021549)
			(xy 175.723541 -409.034812) (xy 175.726852 -409.040838) (xy 175.743185 -409.069194) (xy 175.768902 -409.129366)
			(xy 175.786309 -409.192446) (xy 175.795092 -409.257291) (xy 175.79509 -409.322729) (xy 175.786305 -409.387574)
			(xy 175.768895 -409.450654) (xy 175.752007 -409.490164) (xy 177.023784 -409.490164) (xy 177.027775 -409.427997)
			(xy 177.039684 -409.36685) (xy 177.059313 -409.307729) (xy 177.086342 -409.251603) (xy 177.120326 -409.199394)
			(xy 177.160708 -409.151959) (xy 177.206824 -409.110078) (xy 177.257916 -409.074438) (xy 177.313147 -409.045624)
			(xy 177.371609 -409.02411) (xy 177.432343 -409.010248) (xy 177.49435 -409.004266) (xy 177.556613 -409.006262)
			(xy 177.61811 -409.016205) (xy 177.677831 -409.033929) (xy 177.734794 -409.059146) (xy 177.788065 -409.091439)
			(xy 177.83677 -409.130279) (xy 177.880107 -409.175029) (xy 177.917367 -409.224953) (xy 177.947936 -409.279232)
			(xy 177.9523 -409.290012) (xy 179.223932 -409.290012) (xy 179.227923 -409.227845) (xy 179.239832 -409.166698)
			(xy 179.259461 -409.107577) (xy 179.28649 -409.051451) (xy 179.320474 -408.999242) (xy 179.360856 -408.951807)
			(xy 179.406972 -408.909926) (xy 179.458064 -408.874286) (xy 179.513295 -408.845472) (xy 179.571757 -408.823958)
			(xy 179.632491 -408.810096) (xy 179.694498 -408.804114) (xy 179.756761 -408.80611) (xy 179.818258 -408.816053)
			(xy 179.877979 -408.833777) (xy 179.934942 -408.858994) (xy 179.988213 -408.891287) (xy 180.036918 -408.930127)
			(xy 180.080255 -408.974877) (xy 180.117515 -409.024801) (xy 180.148084 -409.07908) (xy 180.171462 -409.136823)
			(xy 180.187263 -409.197081) (xy 180.195229 -409.258864) (xy 180.195728 -409.290012) (xy 180.195229 -409.32116)
			(xy 180.187263 -409.382943) (xy 180.177397 -409.420568) (xy 186.579 -409.420568) (xy 186.583071 -409.364946)
			(xy 186.595197 -409.310509) (xy 186.61512 -409.258418) (xy 186.642416 -409.209783) (xy 186.676502 -409.16564)
			(xy 186.716651 -409.126931) (xy 186.762009 -409.09448) (xy 186.811609 -409.068979) (xy 186.864393 -409.050972)
			(xy 186.919236 -409.040842) (xy 186.97497 -409.038805) (xy 187.030407 -409.044905) (xy 187.084364 -409.059011)
			(xy 187.135693 -409.080823) (xy 187.183299 -409.109877) (xy 187.226167 -409.145552) (xy 187.263384 -409.187089)
			(xy 187.294157 -409.233602) (xy 187.317829 -409.284099) (xy 187.333897 -409.337506) (xy 187.342017 -409.392682)
			(xy 187.342526 -409.420568) (xy 187.342017 -409.448454) (xy 187.333897 -409.50363) (xy 187.317829 -409.557037)
			(xy 187.294157 -409.607534) (xy 187.263384 -409.654047) (xy 187.226167 -409.695584) (xy 187.183299 -409.731259)
			(xy 187.135693 -409.760313) (xy 187.084364 -409.782125) (xy 187.030407 -409.796231) (xy 186.97497 -409.802331)
			(xy 186.919236 -409.800294) (xy 186.864393 -409.790164) (xy 186.811609 -409.772157) (xy 186.762009 -409.746656)
			(xy 186.716651 -409.714205) (xy 186.676502 -409.675496) (xy 186.642416 -409.631353) (xy 186.61512 -409.582718)
			(xy 186.595197 -409.530627) (xy 186.583071 -409.47619) (xy 186.579 -409.420568) (xy 180.177397 -409.420568)
			(xy 180.171462 -409.443201) (xy 180.148084 -409.500944) (xy 180.117515 -409.555223) (xy 180.080255 -409.605147)
			(xy 180.036918 -409.649897) (xy 179.988213 -409.688737) (xy 179.934942 -409.72103) (xy 179.877979 -409.746247)
			(xy 179.818258 -409.763971) (xy 179.756761 -409.773914) (xy 179.694498 -409.77591) (xy 179.632491 -409.769928)
			(xy 179.571757 -409.756066) (xy 179.513295 -409.734552) (xy 179.458064 -409.705738) (xy 179.406972 -409.670098)
			(xy 179.360856 -409.628217) (xy 179.320474 -409.580782) (xy 179.28649 -409.528573) (xy 179.259461 -409.472447)
			(xy 179.239832 -409.413326) (xy 179.227923 -409.352179) (xy 179.223932 -409.290012) (xy 177.9523 -409.290012)
			(xy 177.971314 -409.336975) (xy 177.987115 -409.397233) (xy 177.995081 -409.459016) (xy 177.99558 -409.490164)
			(xy 177.995081 -409.521312) (xy 177.987115 -409.583095) (xy 177.971314 -409.643353) (xy 177.947936 -409.701096)
			(xy 177.917367 -409.755375) (xy 177.880107 -409.805299) (xy 177.83677 -409.850049) (xy 177.788065 -409.888889)
			(xy 177.774985 -409.896818) (xy 191.732914 -409.896818) (xy 191.736985 -409.841196) (xy 191.749111 -409.786759)
			(xy 191.769034 -409.734668) (xy 191.79633 -409.686033) (xy 191.830416 -409.64189) (xy 191.870565 -409.603181)
			(xy 191.915923 -409.57073) (xy 191.965523 -409.545229) (xy 192.018307 -409.527222) (xy 192.07315 -409.517092)
			(xy 192.128884 -409.515055) (xy 192.184321 -409.521155) (xy 192.238278 -409.535261) (xy 192.289607 -409.557073)
			(xy 192.337213 -409.586127) (xy 192.380081 -409.621802) (xy 192.417298 -409.663339) (xy 192.448071 -409.709852)
			(xy 192.471743 -409.760349) (xy 192.487811 -409.813756) (xy 192.495931 -409.868932) (xy 192.49644 -409.896818)
			(xy 192.495931 -409.924704) (xy 192.487811 -409.97988) (xy 192.471743 -410.033287) (xy 192.448071 -410.083784)
			(xy 192.417298 -410.130297) (xy 192.380081 -410.171834) (xy 192.337213 -410.207509) (xy 192.289607 -410.236563)
			(xy 192.238278 -410.258375) (xy 192.184321 -410.272481) (xy 192.128884 -410.278581) (xy 192.07315 -410.276544)
			(xy 192.018307 -410.266414) (xy 191.965523 -410.248407) (xy 191.915923 -410.222906) (xy 191.870565 -410.190455)
			(xy 191.830416 -410.151746) (xy 191.79633 -410.107603) (xy 191.769034 -410.058968) (xy 191.749111 -410.006877)
			(xy 191.736985 -409.95244) (xy 191.732914 -409.896818) (xy 177.774985 -409.896818) (xy 177.734794 -409.921182)
			(xy 177.677831 -409.946399) (xy 177.61811 -409.964123) (xy 177.556613 -409.974066) (xy 177.49435 -409.976062)
			(xy 177.432343 -409.97008) (xy 177.371609 -409.956218) (xy 177.313147 -409.934704) (xy 177.257916 -409.90589)
			(xy 177.206824 -409.87025) (xy 177.160708 -409.828369) (xy 177.120326 -409.780934) (xy 177.086342 -409.728725)
			(xy 177.059313 -409.672599) (xy 177.039684 -409.613478) (xy 177.027775 -409.552331) (xy 177.023784 -409.490164)
			(xy 175.752007 -409.490164) (xy 175.743175 -409.510825) (xy 175.726852 -409.539186) (xy 175.723546 -409.545215)
			(xy 175.719934 -409.558475) (xy 175.71974 -409.565348) (xy 175.71974 -410.314648) (xy 175.719947 -410.32152)
			(xy 175.723544 -410.334783) (xy 175.726852 -410.34081) (xy 175.743161 -410.369179) (xy 175.76888 -410.429348)
			(xy 175.78629 -410.492425) (xy 175.795076 -410.557268) (xy 175.795076 -410.589984) (xy 179.223932 -410.589984)
			(xy 179.227923 -410.527817) (xy 179.239832 -410.46667) (xy 179.259461 -410.407549) (xy 179.28649 -410.351423)
			(xy 179.320474 -410.299214) (xy 179.360856 -410.251779) (xy 179.406972 -410.209898) (xy 179.458064 -410.174258)
			(xy 179.513295 -410.145444) (xy 179.571757 -410.12393) (xy 179.632491 -410.110068) (xy 179.694498 -410.104086)
			(xy 179.756761 -410.106082) (xy 179.818258 -410.116025) (xy 179.877979 -410.133749) (xy 179.934942 -410.158966)
			(xy 179.988213 -410.191259) (xy 180.036918 -410.230099) (xy 180.080255 -410.274849) (xy 180.117515 -410.324773)
			(xy 180.148084 -410.379052) (xy 180.171462 -410.436795) (xy 180.187263 -410.497053) (xy 180.195229 -410.558836)
			(xy 180.195728 -410.589984) (xy 180.195229 -410.621132) (xy 180.187263 -410.682915) (xy 180.171462 -410.743173)
			(xy 180.148084 -410.800916) (xy 180.117515 -410.855195) (xy 180.080255 -410.905119) (xy 180.036918 -410.949869)
			(xy 179.988213 -410.988709) (xy 179.934942 -411.021002) (xy 179.896455 -411.03804) (xy 185.614054 -411.03804)
			(xy 185.618125 -410.982418) (xy 185.630251 -410.927981) (xy 185.650174 -410.87589) (xy 185.67747 -410.827255)
			(xy 185.711556 -410.783112) (xy 185.751705 -410.744403) (xy 185.797063 -410.711952) (xy 185.846663 -410.686451)
			(xy 185.899447 -410.668444) (xy 185.95429 -410.658314) (xy 186.010024 -410.656277) (xy 186.065461 -410.662377)
			(xy 186.119418 -410.676483) (xy 186.170747 -410.698295) (xy 186.218353 -410.727349) (xy 186.261221 -410.763024)
			(xy 186.298438 -410.804561) (xy 186.329211 -410.851074) (xy 186.351249 -410.898086) (xy 188.828678 -410.898086)
			(xy 188.832749 -410.842464) (xy 188.844875 -410.788027) (xy 188.864798 -410.735936) (xy 188.892094 -410.687301)
			(xy 188.92618 -410.643158) (xy 188.966329 -410.604449) (xy 189.011687 -410.571998) (xy 189.061287 -410.546497)
			(xy 189.114071 -410.52849) (xy 189.168914 -410.51836) (xy 189.224648 -410.516323) (xy 189.280085 -410.522423)
			(xy 189.334042 -410.536529) (xy 189.385371 -410.558341) (xy 189.432977 -410.587395) (xy 189.475845 -410.62307)
			(xy 189.513062 -410.664607) (xy 189.534439 -410.696918) (xy 195.549264 -410.696918) (xy 195.553335 -410.641296)
			(xy 195.565461 -410.586859) (xy 195.585384 -410.534768) (xy 195.61268 -410.486133) (xy 195.646766 -410.44199)
			(xy 195.686915 -410.403281) (xy 195.732273 -410.37083) (xy 195.781873 -410.345329) (xy 195.834657 -410.327322)
			(xy 195.8895 -410.317192) (xy 195.945234 -410.315155) (xy 196.000671 -410.321255) (xy 196.054628 -410.335361)
			(xy 196.105957 -410.357173) (xy 196.153563 -410.386227) (xy 196.196431 -410.421902) (xy 196.233648 -410.463439)
			(xy 196.264421 -410.509952) (xy 196.288093 -410.560449) (xy 196.304161 -410.613856) (xy 196.312281 -410.669032)
			(xy 196.31279 -410.696918) (xy 196.312281 -410.724804) (xy 196.304161 -410.77998) (xy 196.288093 -410.833387)
			(xy 196.264421 -410.883884) (xy 196.233648 -410.930397) (xy 196.196431 -410.971934) (xy 196.153563 -411.007609)
			(xy 196.105957 -411.036663) (xy 196.054628 -411.058475) (xy 196.000671 -411.072581) (xy 195.945234 -411.078681)
			(xy 195.8895 -411.076644) (xy 195.834657 -411.066514) (xy 195.781873 -411.048507) (xy 195.732273 -411.023006)
			(xy 195.686915 -410.990555) (xy 195.646766 -410.951846) (xy 195.61268 -410.907703) (xy 195.585384 -410.859068)
			(xy 195.565461 -410.806977) (xy 195.553335 -410.75254) (xy 195.549264 -410.696918) (xy 189.534439 -410.696918)
			(xy 189.543835 -410.71112) (xy 189.567507 -410.761617) (xy 189.583575 -410.815024) (xy 189.591695 -410.8702)
			(xy 189.592204 -410.898086) (xy 189.591695 -410.925972) (xy 189.583575 -410.981148) (xy 189.567507 -411.034555)
			(xy 189.543835 -411.085052) (xy 189.513062 -411.131565) (xy 189.475845 -411.173102) (xy 189.432977 -411.208777)
			(xy 189.385371 -411.237831) (xy 189.334042 -411.259643) (xy 189.280085 -411.273749) (xy 189.224648 -411.279849)
			(xy 189.168914 -411.277812) (xy 189.114071 -411.267682) (xy 189.061287 -411.249675) (xy 189.011687 -411.224174)
			(xy 188.966329 -411.191723) (xy 188.92618 -411.153014) (xy 188.892094 -411.108871) (xy 188.864798 -411.060236)
			(xy 188.844875 -411.008145) (xy 188.832749 -410.953708) (xy 188.828678 -410.898086) (xy 186.351249 -410.898086)
			(xy 186.352883 -410.901571) (xy 186.368951 -410.954978) (xy 186.377071 -411.010154) (xy 186.37758 -411.03804)
			(xy 186.377071 -411.065926) (xy 186.368951 -411.121102) (xy 186.352883 -411.174509) (xy 186.329211 -411.225006)
			(xy 186.298438 -411.271519) (xy 186.261221 -411.313056) (xy 186.253817 -411.319218) (xy 193.336416 -411.319218)
			(xy 193.340487 -411.263596) (xy 193.352613 -411.209159) (xy 193.372536 -411.157068) (xy 193.399832 -411.108433)
			(xy 193.433918 -411.06429) (xy 193.474067 -411.025581) (xy 193.519425 -410.99313) (xy 193.569025 -410.967629)
			(xy 193.621809 -410.949622) (xy 193.676652 -410.939492) (xy 193.732386 -410.937455) (xy 193.787823 -410.943555)
			(xy 193.84178 -410.957661) (xy 193.893109 -410.979473) (xy 193.940715 -411.008527) (xy 193.983583 -411.044202)
			(xy 194.0208 -411.085739) (xy 194.051573 -411.132252) (xy 194.075245 -411.182749) (xy 194.091313 -411.236156)
			(xy 194.099433 -411.291332) (xy 194.099942 -411.319218) (xy 194.099812 -411.32633) (xy 197.241412 -411.32633)
			(xy 197.245483 -411.270708) (xy 197.257609 -411.216271) (xy 197.277532 -411.16418) (xy 197.304828 -411.115545)
			(xy 197.338914 -411.071402) (xy 197.379063 -411.032693) (xy 197.424421 -411.000242) (xy 197.474021 -410.974741)
			(xy 197.526805 -410.956734) (xy 197.581648 -410.946604) (xy 197.637382 -410.944567) (xy 197.692819 -410.950667)
			(xy 197.746776 -410.964773) (xy 197.798105 -410.986585) (xy 197.845711 -411.015639) (xy 197.888579 -411.051314)
			(xy 197.925796 -411.092851) (xy 197.956569 -411.139364) (xy 197.980241 -411.189861) (xy 197.996309 -411.243268)
			(xy 198.004429 -411.298444) (xy 198.004938 -411.32633) (xy 198.004429 -411.354216) (xy 197.996309 -411.409392)
			(xy 197.980241 -411.462799) (xy 197.956569 -411.513296) (xy 197.925796 -411.559809) (xy 197.888579 -411.601346)
			(xy 197.845711 -411.637021) (xy 197.798105 -411.666075) (xy 197.746776 -411.687887) (xy 197.692819 -411.701993)
			(xy 197.637382 -411.708093) (xy 197.581648 -411.706056) (xy 197.526805 -411.695926) (xy 197.474021 -411.677919)
			(xy 197.424421 -411.652418) (xy 197.379063 -411.619967) (xy 197.338914 -411.581258) (xy 197.304828 -411.537115)
			(xy 197.277532 -411.48848) (xy 197.257609 -411.436389) (xy 197.245483 -411.381952) (xy 197.241412 -411.32633)
			(xy 194.099812 -411.32633) (xy 194.099433 -411.347104) (xy 194.091313 -411.40228) (xy 194.075245 -411.455687)
			(xy 194.051573 -411.506184) (xy 194.0208 -411.552697) (xy 193.983583 -411.594234) (xy 193.940715 -411.629909)
			(xy 193.893109 -411.658963) (xy 193.84178 -411.680775) (xy 193.787823 -411.694881) (xy 193.732386 -411.700981)
			(xy 193.676652 -411.698944) (xy 193.621809 -411.688814) (xy 193.569025 -411.670807) (xy 193.519425 -411.645306)
			(xy 193.474067 -411.612855) (xy 193.433918 -411.574146) (xy 193.399832 -411.530003) (xy 193.372536 -411.481368)
			(xy 193.352613 -411.429277) (xy 193.340487 -411.37484) (xy 193.336416 -411.319218) (xy 186.253817 -411.319218)
			(xy 186.218353 -411.348731) (xy 186.170747 -411.377785) (xy 186.119418 -411.399597) (xy 186.065461 -411.413703)
			(xy 186.010024 -411.419803) (xy 185.95429 -411.417766) (xy 185.899447 -411.407636) (xy 185.846663 -411.389629)
			(xy 185.797063 -411.364128) (xy 185.751705 -411.331677) (xy 185.711556 -411.292968) (xy 185.67747 -411.248825)
			(xy 185.650174 -411.20019) (xy 185.630251 -411.148099) (xy 185.618125 -411.093662) (xy 185.614054 -411.03804)
			(xy 179.896455 -411.03804) (xy 179.877979 -411.046219) (xy 179.818258 -411.063943) (xy 179.756761 -411.073886)
			(xy 179.694498 -411.075882) (xy 179.632491 -411.0699) (xy 179.571757 -411.056038) (xy 179.513295 -411.034524)
			(xy 179.458064 -411.00571) (xy 179.406972 -410.97007) (xy 179.360856 -410.928189) (xy 179.320474 -410.880754)
			(xy 179.28649 -410.828545) (xy 179.259461 -410.772419) (xy 179.239832 -410.713298) (xy 179.227923 -410.652151)
			(xy 179.223932 -410.589984) (xy 175.795076 -410.589984) (xy 175.795077 -410.622704) (xy 175.786296 -410.687548)
			(xy 175.768889 -410.750626) (xy 175.743173 -410.810797) (xy 175.726852 -410.839158) (xy 175.723556 -410.845192)
			(xy 175.719938 -410.858448) (xy 175.71974 -410.86532) (xy 175.71974 -411.151324) (xy 175.719299 -411.161475)
			(xy 175.711503 -411.18022) (xy 175.697113 -411.194541) (xy 175.678331 -411.202247) (xy 175.668178 -411.202632)
			(xy 174.951898 -411.202632) (xy 174.941768 -411.202174) (xy 174.923041 -411.194441) (xy 174.908684 -411.180145)
			(xy 174.90087 -411.161452) (xy 174.900336 -411.151324) (xy 174.900336 -410.86532) (xy 174.900132 -410.858448)
			(xy 174.896531 -410.845185) (xy 174.893224 -410.839158) (xy 174.876889 -410.810804) (xy 174.851173 -410.750631)
			(xy 174.833767 -410.687551) (xy 174.824985 -410.622705) (xy 171.395088 -410.622705) (xy 171.395088 -410.622714)
			(xy 171.386228 -410.687572) (xy 171.368735 -410.750652) (xy 171.342926 -410.81081) (xy 171.326556 -410.839158)
			(xy 171.323261 -410.845192) (xy 171.319642 -410.858448) (xy 171.319444 -410.86532) (xy 171.319444 -411.151324)
			(xy 171.318936 -411.161429) (xy 171.311198 -411.180099) (xy 171.296909 -411.194392) (xy 171.278241 -411.202133)
			(xy 171.268136 -411.202632) (xy 170.551856 -411.202632) (xy 170.541748 -411.202152) (xy 170.523075 -411.194405)
			(xy 170.508783 -411.180108) (xy 170.501044 -411.161432) (xy 170.500548 -411.151324) (xy 170.500548 -410.86532)
			(xy 170.500355 -410.858447) (xy 170.496748 -410.845184) (xy 170.493436 -410.839158) (xy 170.477057 -410.810816)
			(xy 170.451258 -410.750654) (xy 170.433772 -410.687572) (xy 170.424916 -410.622714) (xy 170.424348 -410.589984)
			(xy 166.99499 -410.589984) (xy 166.994991 -410.622704) (xy 166.98621 -410.687548) (xy 166.968804 -410.750626)
			(xy 166.943089 -410.810797) (xy 166.926768 -410.839158) (xy 166.923466 -410.845189) (xy 166.919853 -410.858448)
			(xy 166.919656 -410.86532) (xy 166.919656 -411.151324) (xy 166.919199 -411.161473) (xy 166.911406 -411.180215)
			(xy 166.897021 -411.194535) (xy 166.878245 -411.202244) (xy 166.868094 -411.202632) (xy 166.151814 -411.202632)
			(xy 166.141685 -411.202161) (xy 166.122959 -411.194433) (xy 166.108601 -411.180141) (xy 166.100786 -411.161451)
			(xy 166.100252 -411.151324) (xy 166.100252 -410.86532) (xy 166.100058 -410.858447) (xy 166.096452 -410.845184)
			(xy 166.09314 -410.839158) (xy 166.076804 -410.810804) (xy 166.051088 -410.750631) (xy 166.033681 -410.687551)
			(xy 166.024899 -410.622705) (xy 162.595001 -410.622705) (xy 162.595001 -410.622714) (xy 162.586142 -410.687572)
			(xy 162.56865 -410.750652) (xy 162.542841 -410.81081) (xy 162.526472 -410.839158) (xy 162.52317 -410.845189)
			(xy 162.519557 -410.858448) (xy 162.51936 -410.86532) (xy 162.51936 -411.151324) (xy 162.519003 -411.161453)
			(xy 162.511239 -411.180165) (xy 162.496904 -411.19448) (xy 162.478182 -411.202217) (xy 162.468052 -411.202632)
			(xy 161.751772 -411.202632) (xy 161.741665 -411.202139) (xy 161.722993 -411.194398) (xy 161.7087 -411.180104)
			(xy 161.700961 -411.161431) (xy 161.700464 -411.151324) (xy 161.700464 -410.86532) (xy 161.700269 -410.858447)
			(xy 161.696663 -410.845184) (xy 161.693352 -410.839158) (xy 161.676975 -410.810815) (xy 161.651175 -410.750654)
			(xy 161.633688 -410.687572) (xy 161.624832 -410.622714) (xy 161.624264 -410.589984) (xy 154.576272 -410.589984)
			(xy 154.576272 -412.090108) (xy 159.42387 -412.090108) (xy 159.427861 -412.027941) (xy 159.43977 -411.966794)
			(xy 159.459399 -411.907673) (xy 159.486428 -411.851547) (xy 159.520412 -411.799338) (xy 159.560794 -411.751903)
			(xy 159.60691 -411.710022) (xy 159.658002 -411.674382) (xy 159.713233 -411.645568) (xy 159.771695 -411.624054)
			(xy 159.832429 -411.610192) (xy 159.894436 -411.60421) (xy 159.956699 -411.606206) (xy 160.018196 -411.616149)
			(xy 160.077917 -411.633873) (xy 160.13488 -411.65909) (xy 160.188151 -411.691383) (xy 160.236856 -411.730223)
			(xy 160.280193 -411.774973) (xy 160.317453 -411.824897) (xy 160.348022 -411.879176) (xy 160.3714 -411.936919)
			(xy 160.387201 -411.997177) (xy 160.395167 -412.05896) (xy 160.395666 -412.090108) (xy 163.823912 -412.090108)
			(xy 163.827903 -412.027941) (xy 163.839812 -411.966794) (xy 163.859441 -411.907673) (xy 163.88647 -411.851547)
			(xy 163.920454 -411.799338) (xy 163.960836 -411.751903) (xy 164.006952 -411.710022) (xy 164.058044 -411.674382)
			(xy 164.113275 -411.645568) (xy 164.171737 -411.624054) (xy 164.232471 -411.610192) (xy 164.294478 -411.60421)
			(xy 164.356741 -411.606206) (xy 164.418238 -411.616149) (xy 164.477959 -411.633873) (xy 164.534922 -411.65909)
			(xy 164.588193 -411.691383) (xy 164.636898 -411.730223) (xy 164.680235 -411.774973) (xy 164.717495 -411.824897)
			(xy 164.748064 -411.879176) (xy 164.771442 -411.936919) (xy 164.787243 -411.997177) (xy 164.795209 -412.05896)
			(xy 164.795708 -412.090108) (xy 168.223954 -412.090108) (xy 168.227945 -412.027941) (xy 168.239854 -411.966794)
			(xy 168.259483 -411.907673) (xy 168.286512 -411.851547) (xy 168.320496 -411.799338) (xy 168.360878 -411.751903)
			(xy 168.406994 -411.710022) (xy 168.458086 -411.674382) (xy 168.513317 -411.645568) (xy 168.571779 -411.624054)
			(xy 168.632513 -411.610192) (xy 168.69452 -411.60421) (xy 168.756783 -411.606206) (xy 168.81828 -411.616149)
			(xy 168.878001 -411.633873) (xy 168.934964 -411.65909) (xy 168.988235 -411.691383) (xy 169.03694 -411.730223)
			(xy 169.080277 -411.774973) (xy 169.117537 -411.824897) (xy 169.148106 -411.879176) (xy 169.171484 -411.936919)
			(xy 169.187285 -411.997177) (xy 169.195251 -412.05896) (xy 169.19575 -412.090108) (xy 172.623742 -412.090108)
			(xy 172.627733 -412.027941) (xy 172.639642 -411.966794) (xy 172.659271 -411.907673) (xy 172.6863 -411.851547)
			(xy 172.720284 -411.799338) (xy 172.760666 -411.751903) (xy 172.806782 -411.710022) (xy 172.857874 -411.674382)
			(xy 172.913105 -411.645568) (xy 172.971567 -411.624054) (xy 173.032301 -411.610192) (xy 173.094308 -411.60421)
			(xy 173.156571 -411.606206) (xy 173.218068 -411.616149) (xy 173.277789 -411.633873) (xy 173.334752 -411.65909)
			(xy 173.388023 -411.691383) (xy 173.436728 -411.730223) (xy 173.480065 -411.774973) (xy 173.517325 -411.824897)
			(xy 173.547894 -411.879176) (xy 173.571272 -411.936919) (xy 173.587073 -411.997177) (xy 173.595039 -412.05896)
			(xy 173.595538 -412.090108) (xy 177.023784 -412.090108) (xy 177.027775 -412.027941) (xy 177.039684 -411.966794)
			(xy 177.059313 -411.907673) (xy 177.086342 -411.851547) (xy 177.120326 -411.799338) (xy 177.160708 -411.751903)
			(xy 177.206824 -411.710022) (xy 177.257916 -411.674382) (xy 177.313147 -411.645568) (xy 177.371609 -411.624054)
			(xy 177.432343 -411.610192) (xy 177.49435 -411.60421) (xy 177.556613 -411.606206) (xy 177.61811 -411.616149)
			(xy 177.677831 -411.633873) (xy 177.734794 -411.65909) (xy 177.788065 -411.691383) (xy 177.83677 -411.730223)
			(xy 177.880107 -411.774973) (xy 177.917367 -411.824897) (xy 177.947936 -411.879176) (xy 177.971314 -411.936919)
			(xy 177.985708 -411.99181) (xy 188.011052 -411.99181) (xy 188.015123 -411.936188) (xy 188.027249 -411.881751)
			(xy 188.047172 -411.82966) (xy 188.074468 -411.781025) (xy 188.108554 -411.736882) (xy 188.148703 -411.698173)
			(xy 188.194061 -411.665722) (xy 188.243661 -411.640221) (xy 188.296445 -411.622214) (xy 188.351288 -411.612084)
			(xy 188.407022 -411.610047) (xy 188.462459 -411.616147) (xy 188.516416 -411.630253) (xy 188.567745 -411.652065)
			(xy 188.615351 -411.681119) (xy 188.658219 -411.716794) (xy 188.695436 -411.758331) (xy 188.726209 -411.804844)
			(xy 188.749881 -411.855341) (xy 188.765949 -411.908748) (xy 188.774069 -411.963924) (xy 188.774578 -411.99181)
			(xy 188.774069 -412.019696) (xy 188.765949 -412.074872) (xy 188.749881 -412.128279) (xy 188.726209 -412.178776)
			(xy 188.695436 -412.225289) (xy 188.658219 -412.266826) (xy 188.615351 -412.302501) (xy 188.567745 -412.331555)
			(xy 188.516416 -412.353367) (xy 188.462459 -412.367473) (xy 188.407022 -412.373573) (xy 188.351288 -412.371536)
			(xy 188.296445 -412.361406) (xy 188.243661 -412.343399) (xy 188.194061 -412.317898) (xy 188.148703 -412.285447)
			(xy 188.108554 -412.246738) (xy 188.074468 -412.202595) (xy 188.047172 -412.15396) (xy 188.027249 -412.101869)
			(xy 188.015123 -412.047432) (xy 188.011052 -411.99181) (xy 177.985708 -411.99181) (xy 177.987115 -411.997177)
			(xy 177.995081 -412.05896) (xy 177.99558 -412.090108) (xy 177.995081 -412.121256) (xy 177.987115 -412.183039)
			(xy 177.971314 -412.243297) (xy 177.947936 -412.30104) (xy 177.917367 -412.355319) (xy 177.880107 -412.405243)
			(xy 177.83677 -412.449993) (xy 177.788065 -412.488833) (xy 177.734794 -412.521126) (xy 177.677831 -412.546343)
			(xy 177.61811 -412.564067) (xy 177.556613 -412.57401) (xy 177.49435 -412.576006) (xy 177.432343 -412.570024)
			(xy 177.371609 -412.556162) (xy 177.313147 -412.534648) (xy 177.257916 -412.505834) (xy 177.206824 -412.470194)
			(xy 177.160708 -412.428313) (xy 177.120326 -412.380878) (xy 177.086342 -412.328669) (xy 177.059313 -412.272543)
			(xy 177.039684 -412.213422) (xy 177.027775 -412.152275) (xy 177.023784 -412.090108) (xy 173.595538 -412.090108)
			(xy 173.595039 -412.121256) (xy 173.587073 -412.183039) (xy 173.571272 -412.243297) (xy 173.547894 -412.30104)
			(xy 173.517325 -412.355319) (xy 173.480065 -412.405243) (xy 173.436728 -412.449993) (xy 173.388023 -412.488833)
			(xy 173.334752 -412.521126) (xy 173.277789 -412.546343) (xy 173.218068 -412.564067) (xy 173.156571 -412.57401)
			(xy 173.094308 -412.576006) (xy 173.032301 -412.570024) (xy 172.971567 -412.556162) (xy 172.913105 -412.534648)
			(xy 172.857874 -412.505834) (xy 172.806782 -412.470194) (xy 172.760666 -412.428313) (xy 172.720284 -412.380878)
			(xy 172.6863 -412.328669) (xy 172.659271 -412.272543) (xy 172.639642 -412.213422) (xy 172.627733 -412.152275)
			(xy 172.623742 -412.090108) (xy 169.19575 -412.090108) (xy 169.195251 -412.121256) (xy 169.187285 -412.183039)
			(xy 169.171484 -412.243297) (xy 169.148106 -412.30104) (xy 169.117537 -412.355319) (xy 169.080277 -412.405243)
			(xy 169.03694 -412.449993) (xy 168.988235 -412.488833) (xy 168.934964 -412.521126) (xy 168.878001 -412.546343)
			(xy 168.81828 -412.564067) (xy 168.756783 -412.57401) (xy 168.69452 -412.576006) (xy 168.632513 -412.570024)
			(xy 168.571779 -412.556162) (xy 168.513317 -412.534648) (xy 168.458086 -412.505834) (xy 168.406994 -412.470194)
			(xy 168.360878 -412.428313) (xy 168.320496 -412.380878) (xy 168.286512 -412.328669) (xy 168.259483 -412.272543)
			(xy 168.239854 -412.213422) (xy 168.227945 -412.152275) (xy 168.223954 -412.090108) (xy 164.795708 -412.090108)
			(xy 164.795209 -412.121256) (xy 164.787243 -412.183039) (xy 164.771442 -412.243297) (xy 164.748064 -412.30104)
			(xy 164.717495 -412.355319) (xy 164.680235 -412.405243) (xy 164.636898 -412.449993) (xy 164.588193 -412.488833)
			(xy 164.534922 -412.521126) (xy 164.477959 -412.546343) (xy 164.418238 -412.564067) (xy 164.356741 -412.57401)
			(xy 164.294478 -412.576006) (xy 164.232471 -412.570024) (xy 164.171737 -412.556162) (xy 164.113275 -412.534648)
			(xy 164.058044 -412.505834) (xy 164.006952 -412.470194) (xy 163.960836 -412.428313) (xy 163.920454 -412.380878)
			(xy 163.88647 -412.328669) (xy 163.859441 -412.272543) (xy 163.839812 -412.213422) (xy 163.827903 -412.152275)
			(xy 163.823912 -412.090108) (xy 160.395666 -412.090108) (xy 160.395167 -412.121256) (xy 160.387201 -412.183039)
			(xy 160.3714 -412.243297) (xy 160.348022 -412.30104) (xy 160.317453 -412.355319) (xy 160.280193 -412.405243)
			(xy 160.236856 -412.449993) (xy 160.188151 -412.488833) (xy 160.13488 -412.521126) (xy 160.077917 -412.546343)
			(xy 160.018196 -412.564067) (xy 159.956699 -412.57401) (xy 159.894436 -412.576006) (xy 159.832429 -412.570024)
			(xy 159.771695 -412.556162) (xy 159.713233 -412.534648) (xy 159.658002 -412.505834) (xy 159.60691 -412.470194)
			(xy 159.560794 -412.428313) (xy 159.520412 -412.380878) (xy 159.486428 -412.328669) (xy 159.459399 -412.272543)
			(xy 159.43977 -412.213422) (xy 159.427861 -412.152275) (xy 159.42387 -412.090108) (xy 154.576272 -412.090108)
			(xy 154.576272 -412.79191) (xy 184.936382 -412.79191) (xy 184.940453 -412.736288) (xy 184.952579 -412.681851)
			(xy 184.972502 -412.62976) (xy 184.999798 -412.581125) (xy 185.033884 -412.536982) (xy 185.074033 -412.498273)
			(xy 185.119391 -412.465822) (xy 185.168991 -412.440321) (xy 185.221775 -412.422314) (xy 185.276618 -412.412184)
			(xy 185.332352 -412.410147) (xy 185.387789 -412.416247) (xy 185.441746 -412.430353) (xy 185.493075 -412.452165)
			(xy 185.540681 -412.481219) (xy 185.583549 -412.516894) (xy 185.620766 -412.558431) (xy 185.651539 -412.604944)
			(xy 185.675211 -412.655441) (xy 185.691279 -412.708848) (xy 185.699399 -412.764024) (xy 185.699908 -412.79191)
			(xy 185.699399 -412.819796) (xy 185.691279 -412.874972) (xy 185.675211 -412.928379) (xy 185.651539 -412.978876)
			(xy 185.620766 -413.025389) (xy 185.583549 -413.066926) (xy 185.540681 -413.102601) (xy 185.493075 -413.131655)
			(xy 185.441746 -413.153467) (xy 185.387789 -413.167573) (xy 185.332352 -413.173673) (xy 185.276618 -413.171636)
			(xy 185.221775 -413.161506) (xy 185.168991 -413.143499) (xy 185.119391 -413.117998) (xy 185.074033 -413.085547)
			(xy 185.033884 -413.046838) (xy 184.999798 -413.002695) (xy 184.972502 -412.95406) (xy 184.952579 -412.901969)
			(xy 184.940453 -412.847532) (xy 184.936382 -412.79191) (xy 154.576272 -412.79191) (xy 154.576272 -413.479234)
			(xy 188.424056 -413.479234) (xy 188.428127 -413.423612) (xy 188.440253 -413.369175) (xy 188.460176 -413.317084)
			(xy 188.487472 -413.268449) (xy 188.521558 -413.224306) (xy 188.561707 -413.185597) (xy 188.607065 -413.153146)
			(xy 188.656665 -413.127645) (xy 188.709449 -413.109638) (xy 188.764292 -413.099508) (xy 188.820026 -413.097471)
			(xy 188.875463 -413.103571) (xy 188.92942 -413.117677) (xy 188.980749 -413.139489) (xy 189.028355 -413.168543)
			(xy 189.071223 -413.204218) (xy 189.10844 -413.245755) (xy 189.139213 -413.292268) (xy 189.162885 -413.342765)
			(xy 189.169325 -413.364172) (xy 197.320914 -413.364172) (xy 197.324985 -413.30855) (xy 197.337111 -413.254113)
			(xy 197.357034 -413.202022) (xy 197.38433 -413.153387) (xy 197.418416 -413.109244) (xy 197.458565 -413.070535)
			(xy 197.503923 -413.038084) (xy 197.553523 -413.012583) (xy 197.606307 -412.994576) (xy 197.66115 -412.984446)
			(xy 197.716884 -412.982409) (xy 197.772321 -412.988509) (xy 197.826278 -413.002615) (xy 197.877607 -413.024427)
			(xy 197.925213 -413.053481) (xy 197.968081 -413.089156) (xy 198.005298 -413.130693) (xy 198.036071 -413.177206)
			(xy 198.059743 -413.227703) (xy 198.075811 -413.28111) (xy 198.083931 -413.336286) (xy 198.08444 -413.364172)
			(xy 198.083931 -413.392058) (xy 198.075811 -413.447234) (xy 198.059743 -413.500641) (xy 198.036071 -413.551138)
			(xy 198.005298 -413.597651) (xy 197.968081 -413.639188) (xy 197.925213 -413.674863) (xy 197.877607 -413.703917)
			(xy 197.826278 -413.725729) (xy 197.772321 -413.739835) (xy 197.716884 -413.745935) (xy 197.66115 -413.743898)
			(xy 197.606307 -413.733768) (xy 197.553523 -413.715761) (xy 197.503923 -413.69026) (xy 197.458565 -413.657809)
			(xy 197.418416 -413.6191) (xy 197.38433 -413.574957) (xy 197.357034 -413.526322) (xy 197.337111 -413.474231)
			(xy 197.324985 -413.419794) (xy 197.320914 -413.364172) (xy 189.169325 -413.364172) (xy 189.178953 -413.396172)
			(xy 189.187073 -413.451348) (xy 189.187582 -413.479234) (xy 189.187073 -413.50712) (xy 189.178953 -413.562296)
			(xy 189.162885 -413.615703) (xy 189.139213 -413.6662) (xy 189.10844 -413.712713) (xy 189.071223 -413.75425)
			(xy 189.028355 -413.789925) (xy 188.980749 -413.818979) (xy 188.92942 -413.840791) (xy 188.875463 -413.854897)
			(xy 188.820026 -413.860997) (xy 188.764292 -413.85896) (xy 188.709449 -413.84883) (xy 188.656665 -413.830823)
			(xy 188.607065 -413.805322) (xy 188.561707 -413.772871) (xy 188.521558 -413.734162) (xy 188.487472 -413.690019)
			(xy 188.460176 -413.641384) (xy 188.440253 -413.589293) (xy 188.428127 -413.534856) (xy 188.424056 -413.479234)
			(xy 154.576272 -413.479234) (xy 154.576272 -415.15919) (xy 187.152532 -415.15919) (xy 187.156603 -415.103568)
			(xy 187.168729 -415.049131) (xy 187.188652 -414.99704) (xy 187.215948 -414.948405) (xy 187.250034 -414.904262)
			(xy 187.290183 -414.865553) (xy 187.335541 -414.833102) (xy 187.385141 -414.807601) (xy 187.437925 -414.789594)
			(xy 187.492768 -414.779464) (xy 187.548502 -414.777427) (xy 187.603939 -414.783527) (xy 187.657896 -414.797633)
			(xy 187.709225 -414.819445) (xy 187.756831 -414.848499) (xy 187.799699 -414.884174) (xy 187.836916 -414.925711)
			(xy 187.867689 -414.972224) (xy 187.891361 -415.022721) (xy 187.907429 -415.076128) (xy 187.915549 -415.131304)
			(xy 187.916058 -415.15919) (xy 187.915549 -415.187076) (xy 187.907429 -415.242252) (xy 187.891361 -415.295659)
			(xy 187.867689 -415.346156) (xy 187.836916 -415.392669) (xy 187.799699 -415.434206) (xy 187.756831 -415.469881)
			(xy 187.709225 -415.498935) (xy 187.657896 -415.520747) (xy 187.603939 -415.534853) (xy 187.548502 -415.540953)
			(xy 187.492768 -415.538916) (xy 187.437925 -415.528786) (xy 187.385141 -415.510779) (xy 187.335541 -415.485278)
			(xy 187.290183 -415.452827) (xy 187.250034 -415.414118) (xy 187.215948 -415.369975) (xy 187.188652 -415.32134)
			(xy 187.168729 -415.269249) (xy 187.156603 -415.214812) (xy 187.152532 -415.15919) (xy 154.576272 -415.15919)
			(xy 154.576272 -415.949638) (xy 154.577624 -415.958919) (xy 154.586066 -415.975649) (xy 154.599961 -415.988223)
			(xy 154.617448 -415.994958) (xy 154.626818 -415.995358) (xy 201.242422 -415.995358) (xy 201.250804 -415.994596)
			(xy 201.258408 -415.993081) (xy 201.272241 -415.986093) (xy 201.277982 -415.98088) (xy 201.462894 -415.795968)
			(xy 201.470289 -415.789113) (xy 201.488888 -415.781366) (xy 201.498962 -415.780982) (xy 274.103592 -415.780982)
			(xy 274.113663 -415.781403) (xy 274.132272 -415.789113) (xy 274.13966 -415.795968) (xy 274.741132 -416.39744)
			(xy 274.746633 -416.402424) (xy 274.7598 -416.409261) (xy 274.76704 -416.410902) (xy 274.776692 -416.411918)
		)
		(stroke
			(width 0)
			(type solid)
		)
		(fill yes)
		(layer "In11.Cu")
		(net "GND")
	)
	(gr_poly
		(pts
			(xy 268.350238 -285.6992) (xy 268.358928 -285.698848) (xy 268.375292 -285.692999) (xy 268.382242 -285.68777)
			(xy 268.4028 -285.671749) (xy 268.448242 -285.646229) (xy 268.497355 -285.628793) (xy 268.548716 -285.619947)
			(xy 268.600832 -285.619947) (xy 268.652193 -285.628793) (xy 268.701306 -285.646229) (xy 268.746748 -285.671749)
			(xy 268.767306 -285.68777) (xy 268.774269 -285.692974) (xy 268.790626 -285.698819) (xy 268.79931 -285.6992)
			(xy 269.300198 -285.6992) (xy 269.30889 -285.698855) (xy 269.325263 -285.693015) (xy 269.332202 -285.68777)
			(xy 269.35276 -285.671749) (xy 269.398202 -285.646229) (xy 269.447315 -285.628793) (xy 269.498676 -285.619947)
			(xy 269.550792 -285.619947) (xy 269.602153 -285.628793) (xy 269.651266 -285.646229) (xy 269.696708 -285.671749)
			(xy 269.717266 -285.68777) (xy 269.724231 -285.692965) (xy 269.740589 -285.698792) (xy 269.74927 -285.6992)
			(xy 270.250412 -285.6992) (xy 270.259103 -285.698853) (xy 270.275473 -285.693009) (xy 270.282416 -285.68777)
			(xy 270.302974 -285.671749) (xy 270.348416 -285.646229) (xy 270.397529 -285.628793) (xy 270.44889 -285.619947)
			(xy 270.501006 -285.619947) (xy 270.552367 -285.628793) (xy 270.60148 -285.646229) (xy 270.646922 -285.671749)
			(xy 270.66748 -285.68777) (xy 270.674441 -285.692977) (xy 270.690799 -285.698831) (xy 270.699484 -285.6992)
			(xy 271.200372 -285.6992) (xy 271.209066 -285.698859) (xy 271.225444 -285.693026) (xy 271.232376 -285.68777)
			(xy 271.252934 -285.671749) (xy 271.298376 -285.646229) (xy 271.347489 -285.628793) (xy 271.39885 -285.619947)
			(xy 271.450966 -285.619947) (xy 271.502327 -285.628793) (xy 271.55144 -285.646229) (xy 271.596882 -285.671749)
			(xy 271.61744 -285.68777) (xy 271.624404 -285.692968) (xy 271.640762 -285.698803) (xy 271.649444 -285.6992)
			(xy 272.150332 -285.6992) (xy 272.159022 -285.698849) (xy 272.175388 -285.693001) (xy 272.182336 -285.68777)
			(xy 272.202894 -285.671749) (xy 272.248336 -285.646229) (xy 272.297449 -285.628793) (xy 272.34881 -285.619947)
			(xy 272.400926 -285.619947) (xy 272.452287 -285.628793) (xy 272.5014 -285.646229) (xy 272.546842 -285.671749)
			(xy 272.5674 -285.68777) (xy 272.574362 -285.692974) (xy 272.59072 -285.698822) (xy 272.599404 -285.6992)
			(xy 273.100292 -285.6992) (xy 273.108985 -285.698856) (xy 273.125358 -285.693018) (xy 273.132296 -285.68777)
			(xy 273.152854 -285.671749) (xy 273.198296 -285.646229) (xy 273.247409 -285.628793) (xy 273.29877 -285.619947)
			(xy 273.350886 -285.619947) (xy 273.402247 -285.628793) (xy 273.45136 -285.646229) (xy 273.496802 -285.671749)
			(xy 273.51736 -285.68777) (xy 273.524325 -285.692966) (xy 273.540683 -285.698794) (xy 273.549364 -285.6992)
			(xy 275.010118 -285.6992) (xy 275.01831 -285.698888) (xy 275.033853 -285.693701) (xy 275.040598 -285.68904)
			(xy 275.046186 -285.684214) (xy 275.277326 -285.453074) (xy 275.283892 -285.445823) (xy 275.291477 -285.427811)
			(xy 275.291802 -285.408269) (xy 275.288756 -285.398972) (xy 275.255228 -285.312104) (xy 275.253704 -285.308548)
			(xy 275.250733 -285.302788) (xy 275.242372 -285.292889) (xy 275.237194 -285.28899) (xy 275.231606 -285.284926)
			(xy 275.218144 -285.280354) (xy 275.21027 -285.279846) (xy 275.184467 -285.27808) (xy 275.13396 -285.266963)
			(xy 275.086049 -285.247492) (xy 275.042105 -285.220225) (xy 275.003386 -285.185942) (xy 274.970999 -285.145623)
			(xy 274.945871 -285.100422) (xy 274.928721 -285.051632) (xy 274.920039 -285.00065) (xy 274.91944 -284.974792)
			(xy 274.919887 -284.950801) (xy 274.927395 -284.903409) (xy 274.942225 -284.857775) (xy 274.964011 -284.815024)
			(xy 274.992218 -284.776207) (xy 275.02615 -284.742281) (xy 275.064972 -284.714082) (xy 275.107727 -284.692303)
			(xy 275.153363 -284.677482) (xy 275.200757 -284.669982) (xy 275.224748 -284.669484) (xy 275.252798 -284.670109)
			(xy 275.307955 -284.680351) (xy 275.360305 -284.700516) (xy 275.384514 -284.714696) (xy 275.390455 -284.718099)
			(xy 275.403585 -284.721961) (xy 275.410422 -284.722316) (xy 275.42363 -284.72257) (xy 275.513292 -284.672278)
			(xy 275.520934 -284.667558) (xy 275.53257 -284.65389) (xy 275.5388 -284.637056) (xy 275.5392 -284.628082)
			(xy 275.5392 -284.371542) (xy 275.538847 -284.362561) (xy 275.532626 -284.34571) (xy 275.520943 -284.332066)
			(xy 275.513292 -284.327346) (xy 275.435822 -284.283912) (xy 275.43125 -284.281626) (xy 275.430742 -284.281626)
			(xy 275.421087 -284.278054) (xy 275.400519 -284.278054) (xy 275.390864 -284.281626) (xy 275.384514 -284.284928)
			(xy 275.360283 -284.299064) (xy 275.307935 -284.319212) (xy 275.252793 -284.32949) (xy 275.224748 -284.33014)
			(xy 275.199485 -284.329651) (xy 275.149647 -284.321342) (xy 275.101857 -284.304942) (xy 275.057418 -284.280899)
			(xy 275.017544 -284.249869) (xy 274.983321 -284.212699) (xy 274.955683 -284.170402) (xy 274.935385 -284.124133)
			(xy 274.922981 -284.075153) (xy 274.918808 -284.0248) (xy 274.922981 -283.974447) (xy 274.935385 -283.925467)
			(xy 274.955683 -283.879198) (xy 274.983321 -283.836901) (xy 275.017544 -283.799731) (xy 275.057418 -283.768701)
			(xy 275.101857 -283.744658) (xy 275.149647 -283.728258) (xy 275.199485 -283.719949) (xy 275.224748 -283.719524)
			(xy 275.252798 -283.72015) (xy 275.307954 -283.730393) (xy 275.360302 -283.75056) (xy 275.384514 -283.764736)
			(xy 275.390454 -283.768143) (xy 275.403584 -283.772009) (xy 275.410422 -283.772356) (xy 275.42363 -283.77261)
			(xy 275.513292 -283.722318) (xy 275.520938 -283.7176) (xy 275.532586 -283.703934) (xy 275.538829 -283.687098)
			(xy 275.5392 -283.678122) (xy 275.5392 -283.421582) (xy 275.538853 -283.412597) (xy 275.532641 -283.395736)
			(xy 275.520961 -283.382081) (xy 275.513292 -283.377386) (xy 275.435822 -283.333952) (xy 275.43125 -283.331666)
			(xy 275.430742 -283.331666) (xy 275.421087 -283.328094) (xy 275.400519 -283.328094) (xy 275.390864 -283.331666)
			(xy 275.384514 -283.334968) (xy 275.360282 -283.349102) (xy 275.307934 -283.369248) (xy 275.252793 -283.379525)
			(xy 275.224748 -283.38018) (xy 275.19949 -283.379691) (xy 275.149662 -283.371384) (xy 275.101881 -283.354987)
			(xy 275.057451 -283.330949) (xy 275.017584 -283.299925) (xy 274.983368 -283.262762) (xy 274.955736 -283.220473)
			(xy 274.935442 -283.174213) (xy 274.92304 -283.125243) (xy 274.918868 -283.0749) (xy 274.92304 -283.024557)
			(xy 274.935442 -282.975587) (xy 274.955736 -282.929327) (xy 274.983368 -282.887038) (xy 275.017584 -282.849875)
			(xy 275.057451 -282.818851) (xy 275.101881 -282.794813) (xy 275.149662 -282.778416) (xy 275.19949 -282.770109)
			(xy 275.224748 -282.769564) (xy 275.252798 -282.770189) (xy 275.307955 -282.78043) (xy 275.360306 -282.800594)
			(xy 275.384514 -282.814776) (xy 275.390454 -282.81818) (xy 275.403585 -282.822044) (xy 275.410422 -282.822396)
			(xy 275.42363 -282.82265) (xy 275.513292 -282.772358) (xy 275.520931 -282.767637) (xy 275.532563 -282.753969)
			(xy 275.538787 -282.737135) (xy 275.5392 -282.728162) (xy 275.5392 -282.471622) (xy 275.53886 -282.462633)
			(xy 275.532657 -282.445762) (xy 275.520979 -282.432096) (xy 275.513292 -282.427426) (xy 275.435822 -282.383992)
			(xy 275.43125 -282.381706) (xy 275.430742 -282.381706) (xy 275.421087 -282.378134) (xy 275.400519 -282.378134)
			(xy 275.390864 -282.381706) (xy 275.384514 -282.385008) (xy 275.360283 -282.399145) (xy 275.307935 -282.419295)
			(xy 275.252793 -282.429573) (xy 275.224748 -282.43022) (xy 275.199487 -282.429731) (xy 275.149652 -282.421422)
			(xy 275.101865 -282.405024) (xy 275.057429 -282.380982) (xy 275.017557 -282.349954) (xy 274.983336 -282.312786)
			(xy 274.955701 -282.270492) (xy 274.935404 -282.224226) (xy 274.923001 -282.17525) (xy 274.918828 -282.1249)
			(xy 274.923001 -282.07455) (xy 274.935404 -282.025574) (xy 274.955701 -281.979308) (xy 274.983336 -281.937014)
			(xy 275.017557 -281.899846) (xy 275.057429 -281.868818) (xy 275.101865 -281.844776) (xy 275.149652 -281.828378)
			(xy 275.199487 -281.820069) (xy 275.224748 -281.819604) (xy 275.252798 -281.82023) (xy 275.307954 -281.830472)
			(xy 275.360303 -281.850638) (xy 275.384514 -281.864816) (xy 275.390455 -281.868218) (xy 275.403585 -281.872079)
			(xy 275.410422 -281.872436) (xy 275.42363 -281.87269) (xy 275.513292 -281.822398) (xy 275.520936 -281.817679)
			(xy 275.532578 -281.804012) (xy 275.538814 -281.787177) (xy 275.5392 -281.778202) (xy 275.5392 -281.521662)
			(xy 275.53885 -281.512679) (xy 275.532634 -281.495823) (xy 275.520952 -281.482174) (xy 275.513292 -281.477466)
			(xy 275.435822 -281.434032) (xy 275.43125 -281.431746) (xy 275.430742 -281.431746) (xy 275.421087 -281.428174)
			(xy 275.400519 -281.428174) (xy 275.390864 -281.431746) (xy 275.384514 -281.435048) (xy 275.360283 -281.449183)
			(xy 275.307935 -281.46933) (xy 275.252793 -281.479607) (xy 275.224748 -281.48026) (xy 275.199492 -281.479771)
			(xy 275.149667 -281.471464) (xy 275.101889 -281.455069) (xy 275.057462 -281.431032) (xy 275.017598 -281.40001)
			(xy 274.983384 -281.36285) (xy 274.955754 -281.320564) (xy 274.935461 -281.274307) (xy 274.92306 -281.22534)
			(xy 274.918888 -281.175) (xy 274.92306 -281.12466) (xy 274.935461 -281.075693) (xy 274.955754 -281.029436)
			(xy 274.983384 -280.98715) (xy 275.017598 -280.94999) (xy 275.057462 -280.918968) (xy 275.101889 -280.894931)
			(xy 275.149667 -280.878536) (xy 275.199492 -280.870229) (xy 275.224748 -280.869644) (xy 275.252798 -280.87027)
			(xy 275.307953 -280.880513) (xy 275.360301 -280.900682) (xy 275.384514 -280.914856) (xy 275.390454 -280.918261)
			(xy 275.403584 -280.922126) (xy 275.410422 -280.922476) (xy 275.42363 -280.92273) (xy 275.513292 -280.872438)
			(xy 275.52094 -280.867721) (xy 275.532593 -280.854056) (xy 275.538842 -280.83722) (xy 275.5392 -280.828242)
			(xy 275.5392 -280.571448) (xy 275.538848 -280.562466) (xy 275.532628 -280.545614) (xy 275.520946 -280.531969)
			(xy 275.513292 -280.527252) (xy 275.435822 -280.483818) (xy 275.43125 -280.481532) (xy 275.430742 -280.481532)
			(xy 275.421087 -280.47796) (xy 275.400519 -280.47796) (xy 275.390864 -280.481532) (xy 275.384514 -280.484834)
			(xy 275.360283 -280.49897) (xy 275.307935 -280.519118) (xy 275.252793 -280.529395) (xy 275.224748 -280.530046)
			(xy 275.199485 -280.529557) (xy 275.149646 -280.521248) (xy 275.101855 -280.504847) (xy 275.057415 -280.480804)
			(xy 275.01754 -280.449774) (xy 274.983316 -280.412602) (xy 274.955678 -280.370305) (xy 274.93538 -280.324034)
			(xy 274.922975 -280.275054) (xy 274.918802 -280.2247) (xy 274.922975 -280.174346) (xy 274.93538 -280.125365)
			(xy 274.955678 -280.079095) (xy 274.983316 -280.036798) (xy 275.01754 -279.999626) (xy 275.057415 -279.968596)
			(xy 275.101855 -279.944553) (xy 275.149646 -279.928152) (xy 275.199485 -279.919843) (xy 275.224748 -279.91943)
			(xy 275.252798 -279.920056) (xy 275.307954 -279.930299) (xy 275.360302 -279.950467) (xy 275.384514 -279.964642)
			(xy 275.390454 -279.968048) (xy 275.403584 -279.971914) (xy 275.410422 -279.972262) (xy 275.42363 -279.972516)
			(xy 275.513292 -279.922224) (xy 275.520939 -279.917506) (xy 275.532588 -279.903841) (xy 275.538833 -279.887005)
			(xy 275.5392 -279.878028) (xy 275.5392 -279.621488) (xy 275.538854 -279.612502) (xy 275.532644 -279.59564)
			(xy 275.520964 -279.581983) (xy 275.513292 -279.577292) (xy 275.435822 -279.533858) (xy 275.43125 -279.531572)
			(xy 275.430742 -279.531572) (xy 275.421087 -279.528) (xy 275.400519 -279.528) (xy 275.390864 -279.531572)
			(xy 275.384514 -279.534874) (xy 275.360282 -279.549008) (xy 275.307934 -279.569153) (xy 275.252793 -279.57943)
			(xy 275.224748 -279.580086) (xy 275.199489 -279.579597) (xy 275.14966 -279.571289) (xy 275.101879 -279.554893)
			(xy 275.057448 -279.530854) (xy 275.01758 -279.499829) (xy 274.983363 -279.462666) (xy 274.955731 -279.420376)
			(xy 274.935436 -279.374115) (xy 274.923034 -279.325144) (xy 274.918862 -279.2748) (xy 274.923034 -279.224456)
			(xy 274.935436 -279.175485) (xy 274.955731 -279.129224) (xy 274.983363 -279.086934) (xy 275.01758 -279.049771)
			(xy 275.057448 -279.018746) (xy 275.101879 -278.994707) (xy 275.14966 -278.978311) (xy 275.199489 -278.970003)
			(xy 275.224748 -278.96947) (xy 275.225256 -278.96947) (xy 275.248932 -278.969941) (xy 275.29571 -278.977294)
			(xy 275.340796 -278.991769) (xy 275.362162 -279.001982) (xy 275.362416 -279.001982) (xy 275.369565 -279.005257)
			(xy 275.385086 -279.007717) (xy 275.392896 -279.006808) (xy 275.40077 -279.005538) (xy 275.414994 -278.998426)
			(xy 275.420836 -278.992584) (xy 275.427517 -278.985174) (xy 275.435109 -278.966745) (xy 275.4351 -278.946813)
			(xy 275.427494 -278.92839) (xy 275.420836 -278.920956) (xy 275.392134 -278.892254) (xy 275.357592 -278.856817)
			(xy 275.295117 -278.780065) (xy 275.240765 -278.697362) (xy 275.217382 -278.653748) (xy 275.211635 -278.643949)
			(xy 275.193567 -278.630231) (xy 275.182584 -278.627332) (xy 275.182076 -278.627332) (xy 275.17979 -278.626824)
			(xy 275.155968 -278.622817) (xy 275.109905 -278.608273) (xy 275.066707 -278.586657) (xy 275.027453 -278.558506)
			(xy 274.993122 -278.524525) (xy 274.964572 -278.485561) (xy 274.942515 -278.442586) (xy 274.927502 -278.396674)
			(xy 274.919907 -278.34897) (xy 274.91944 -278.324818) (xy 274.919875 -278.301258) (xy 274.927108 -278.254697)
			(xy 274.941405 -278.209799) (xy 274.962428 -278.167628) (xy 274.989676 -278.129187) (xy 275.022505 -278.095385)
			(xy 275.060135 -278.067026) (xy 275.08073 -278.055578) (xy 275.086826 -278.052276) (xy 275.096732 -278.042878)
			(xy 275.100288 -278.037036) (xy 275.103336 -278.031194) (xy 275.105226 -278.026394) (xy 275.107274 -278.016285)
			(xy 275.1074 -278.011128) (xy 275.1074 -277.688548) (xy 275.107307 -277.683387) (xy 275.10526 -277.673272)
			(xy 275.103336 -277.668482) (xy 275.100288 -277.66264) (xy 275.096732 -277.656798) (xy 275.086826 -277.6474)
			(xy 275.08073 -277.644098) (xy 275.058593 -277.631689) (xy 275.018419 -277.600688) (xy 274.983924 -277.563471)
			(xy 274.956057 -277.521062) (xy 274.935587 -277.474629) (xy 274.923076 -277.42545) (xy 274.91887 -277.37488)
			(xy 274.923083 -277.32431) (xy 274.9356 -277.275133) (xy 274.956076 -277.228703) (xy 274.983948 -277.186298)
			(xy 275.018448 -277.149085) (xy 275.058626 -277.118089) (xy 275.08073 -277.105618) (xy 275.086826 -277.102316)
			(xy 275.096732 -277.092918) (xy 275.100288 -277.087076) (xy 275.103336 -277.081234) (xy 275.10523 -277.076435)
			(xy 275.107286 -277.066326) (xy 275.1074 -277.061168) (xy 275.1074 -276.738588) (xy 275.107311 -276.733426)
			(xy 275.105272 -276.723308) (xy 275.103336 -276.718522) (xy 275.100288 -276.71268) (xy 275.096732 -276.706838)
			(xy 275.086826 -276.69744) (xy 275.08073 -276.694138) (xy 275.05859 -276.681729) (xy 275.018409 -276.650727)
			(xy 274.983907 -276.613507) (xy 274.956035 -276.571095) (xy 274.93556 -276.524658) (xy 274.923045 -276.475475)
			(xy 274.918834 -276.424899) (xy 274.923045 -276.374323) (xy 274.93556 -276.32514) (xy 274.956036 -276.278703)
			(xy 274.983909 -276.236291) (xy 275.01841 -276.199072) (xy 275.058591 -276.16807) (xy 275.08073 -276.155658)
			(xy 275.086826 -276.152356) (xy 275.096732 -276.142958) (xy 275.100288 -276.137116) (xy 275.103336 -276.131274)
			(xy 275.105225 -276.126474) (xy 275.107268 -276.116365) (xy 275.1074 -276.111208) (xy 275.1074 -275.788628)
			(xy 275.107305 -275.783468) (xy 275.105254 -275.773354) (xy 275.103336 -275.768562) (xy 275.100288 -275.76272)
			(xy 275.096732 -275.756878) (xy 275.086826 -275.74748) (xy 275.08073 -275.744178) (xy 275.058587 -275.731769)
			(xy 275.018399 -275.700766) (xy 274.983891 -275.663544) (xy 274.956013 -275.621129) (xy 274.935533 -275.574688)
			(xy 274.923013 -275.525499) (xy 274.918799 -275.474918) (xy 274.923007 -275.424336) (xy 274.935521 -275.375146)
			(xy 274.955996 -275.328703) (xy 274.983869 -275.286284) (xy 275.018373 -275.249058) (xy 275.058556 -275.21805)
			(xy 275.08073 -275.205698) (xy 275.086826 -275.202396) (xy 275.096732 -275.192998) (xy 275.100288 -275.187156)
			(xy 275.103336 -275.181314) (xy 275.105228 -275.176515) (xy 275.10728 -275.166405) (xy 275.1074 -275.161248)
			(xy 275.1074 -274.838668) (xy 275.107309 -274.833507) (xy 275.105266 -274.82339) (xy 275.103336 -274.818602)
			(xy 275.100288 -274.81276) (xy 275.096732 -274.806918) (xy 275.086826 -274.79752) (xy 275.08073 -274.794218)
			(xy 275.058592 -274.781809) (xy 275.018414 -274.750808) (xy 274.983916 -274.713589) (xy 274.956046 -274.671179)
			(xy 274.935573 -274.624744) (xy 274.92306 -274.575563) (xy 274.918852 -274.52499) (xy 274.923064 -274.474417)
			(xy 274.93558 -274.425237) (xy 274.956056 -274.378803) (xy 274.983928 -274.336394) (xy 275.018429 -274.299178)
			(xy 275.058609 -274.268179) (xy 275.08073 -274.255738) (xy 275.086826 -274.252436) (xy 275.096732 -274.243038)
			(xy 275.100288 -274.237196) (xy 275.103336 -274.231354) (xy 275.105223 -274.226554) (xy 275.107263 -274.216444)
			(xy 275.1074 -274.211288) (xy 275.1074 -273.888454) (xy 275.107307 -273.883293) (xy 275.105262 -273.873177)
			(xy 275.103336 -273.868388) (xy 275.100288 -273.862546) (xy 275.096732 -273.856704) (xy 275.086826 -273.847306)
			(xy 275.08073 -273.844004) (xy 275.058593 -273.831595) (xy 275.018417 -273.800594) (xy 274.983921 -273.763376)
			(xy 274.956054 -273.720967) (xy 274.935583 -273.674533) (xy 274.923071 -273.625354) (xy 274.918864 -273.574783)
			(xy 274.923077 -273.524212) (xy 274.935594 -273.475034) (xy 274.95607 -273.428603) (xy 274.983942 -273.386197)
			(xy 275.018442 -273.348983) (xy 275.058621 -273.317986) (xy 275.08073 -273.305524) (xy 275.086826 -273.302222)
			(xy 275.096732 -273.292824) (xy 275.100288 -273.286982) (xy 275.103336 -273.28114) (xy 275.105231 -273.276341)
			(xy 275.107287 -273.266232) (xy 275.1074 -273.261074) (xy 275.1074 -272.938494) (xy 275.107301 -272.933334)
			(xy 275.105244 -272.923223) (xy 275.103336 -272.918428) (xy 275.100288 -272.912586) (xy 275.096732 -272.906744)
			(xy 275.086826 -272.897346) (xy 275.08073 -272.894044) (xy 275.058589 -272.881635) (xy 275.018407 -272.850633)
			(xy 274.983905 -272.813413) (xy 274.956032 -272.771) (xy 274.935556 -272.724563) (xy 274.92304 -272.675379)
			(xy 274.918829 -272.624802) (xy 274.923039 -272.574225) (xy 274.935554 -272.525041) (xy 274.95603 -272.478603)
			(xy 274.983903 -272.43619) (xy 275.018405 -272.39897) (xy 275.058586 -272.367967) (xy 275.08073 -272.355564)
			(xy 275.086826 -272.352262) (xy 275.096732 -272.342864) (xy 275.100288 -272.337022) (xy 275.103336 -272.33118)
			(xy 275.105225 -272.32638) (xy 275.10727 -272.316271) (xy 275.1074 -272.311114) (xy 275.1074 -271.769078)
			(xy 275.104098 -271.760188) (xy 275.08784 -271.716929) (xy 275.062459 -271.628062) (xy 275.045401 -271.53723)
			(xy 275.036812 -271.44521) (xy 275.03628 -271.399) (xy 275.03628 -270.838422) (xy 275.035518 -270.830294)
			(xy 274.217384 -265.90117) (xy 274.21542 -265.892031) (xy 274.205945 -265.875936) (xy 274.191356 -265.864274)
			(xy 274.182586 -265.861038) (xy 274.157112 -265.852547) (xy 274.108654 -265.829414) (xy 274.06392 -265.799713)
			(xy 274.023794 -265.764031) (xy 273.98907 -265.723074) (xy 273.960433 -265.677652) (xy 273.93845 -265.628662)
			(xy 273.923556 -265.577072) (xy 273.916044 -265.523904) (xy 273.915632 -265.497056) (xy 273.916208 -265.467264)
			(xy 273.925477 -265.408405) (xy 273.943782 -265.351702) (xy 273.970679 -265.298534) (xy 274.005513 -265.250193)
			(xy 274.047438 -265.207854) (xy 274.07108 -265.189716) (xy 274.078382 -265.183839) (xy 274.088503 -265.168081)
			(xy 274.092294 -265.149741) (xy 274.091146 -265.14044) (xy 274.024344 -264.737342) (xy 274.02409 -264.735818)
			(xy 274.019196 -264.709904) (xy 274.011826 -264.65768) (xy 274.009358 -264.631424) (xy 273.952716 -263.996424)
			(xy 273.952028 -263.990226) (xy 273.948033 -263.978415) (xy 273.944842 -263.973056) (xy 273.94154 -263.967976)
			(xy 273.932396 -263.959594) (xy 273.927316 -263.9568) (xy 273.90207 -263.942286) (xy 273.855906 -263.906795)
			(xy 273.815671 -263.8647) (xy 273.782299 -263.816981) (xy 273.756566 -263.764745) (xy 273.73907 -263.709205)
			(xy 273.730216 -263.651651) (xy 273.729704 -263.622536) (xy 273.730224 -263.594209) (xy 273.738605 -263.538178)
			(xy 273.755175 -263.484002) (xy 273.779568 -263.432868) (xy 273.811249 -263.3859) (xy 273.849523 -263.34413)
			(xy 273.871182 -263.325864) (xy 273.876008 -263.3218) (xy 273.88312 -263.312402) (xy 273.88566 -263.30656)
			(xy 273.887438 -263.301988) (xy 273.888923 -263.297052) (xy 273.890076 -263.28681) (xy 273.889724 -263.281668)
			(xy 273.807428 -262.355838) (xy 273.806785 -262.350362) (xy 273.803459 -262.339853) (xy 273.800824 -262.33501)
			(xy 273.79803 -262.330184) (xy 273.79041 -262.321802) (xy 273.786092 -262.319008) (xy 273.764768 -262.303646)
			(xy 273.726143 -262.268008) (xy 273.692769 -262.22741) (xy 273.665279 -262.182619) (xy 273.644191 -262.134481)
			(xy 273.629903 -262.083906) (xy 273.622686 -262.031849) (xy 273.622262 -262.005572) (xy 273.622368 -261.993664)
			(xy 273.623896 -261.969898) (xy 273.62531 -261.958074) (xy 273.62531 -261.957566) (xy 273.625989 -261.948705)
			(xy 273.621988 -261.931402) (xy 273.612353 -261.916484) (xy 273.605498 -261.91083) (xy 273.534886 -261.857744)
			(xy 273.529326 -261.853845) (xy 273.516713 -261.848823) (xy 273.509994 -261.847838) (xy 273.496532 -261.846314)
			(xy 273.484086 -261.851902) (xy 273.460097 -261.861838) (xy 273.410101 -261.875851) (xy 273.358663 -261.882938)
			(xy 273.332702 -261.883398) (xy 273.33194 -261.883398) (xy 273.304686 -261.882937) (xy 273.250732 -261.875185)
			(xy 273.198431 -261.859833) (xy 273.148847 -261.837193) (xy 273.10299 -261.807727) (xy 273.061794 -261.772035)
			(xy 273.026097 -261.730842) (xy 272.996626 -261.684988) (xy 272.973981 -261.635407) (xy 272.958623 -261.583107)
			(xy 272.950865 -261.529154) (xy 272.950865 -261.474646) (xy 272.958623 -261.420693) (xy 272.973981 -261.368393)
			(xy 272.996626 -261.318812) (xy 273.026097 -261.272958) (xy 273.061794 -261.231765) (xy 273.10299 -261.196073)
			(xy 273.148847 -261.166607) (xy 273.198431 -261.143967) (xy 273.250732 -261.128615) (xy 273.304686 -261.120863)
			(xy 273.33194 -261.120382) (xy 273.332194 -261.120382) (xy 273.359521 -261.120875) (xy 273.413612 -261.128712)
			(xy 273.466036 -261.144169) (xy 273.515725 -261.166933) (xy 273.53895 -261.181342) (xy 273.5453 -261.185406)
			(xy 273.558762 -261.18947) (xy 273.565874 -261.189724) (xy 273.572825 -261.189485) (xy 273.586218 -261.185751)
			(xy 273.59229 -261.182358) (xy 273.670522 -261.135368) (xy 273.673062 -261.133844) (xy 273.680269 -261.128497)
			(xy 273.690669 -261.113886) (xy 273.695364 -261.096578) (xy 273.694906 -261.087616) (xy 273.694906 -261.087362)
			(xy 273.392138 -257.671316) (xy 273.391236 -257.664398) (xy 273.386215 -257.651389) (xy 273.382232 -257.645662)
			(xy 273.378422 -257.640074) (xy 273.3675 -257.631692) (xy 273.36115 -257.629152) (xy 273.337658 -257.61897)
			(xy 273.293402 -257.59322) (xy 273.252986 -257.561787) (xy 273.217134 -257.525232) (xy 273.18649 -257.484214)
			(xy 273.161604 -257.439467) (xy 273.151854 -257.415792) (xy 273.151854 -257.415284) (xy 273.1516 -257.415284)
			(xy 273.149026 -257.409275) (xy 273.141306 -257.398731) (xy 273.13636 -257.394456) (xy 273.13128 -257.390392)
			(xy 273.12493 -257.387598) (xy 273.111722 -257.383788) (xy 273.024346 -257.371342) (xy 273.015486 -257.37039)
			(xy 272.998046 -257.374003) (xy 272.982897 -257.383368) (xy 272.977102 -257.390138) (xy 272.976848 -257.390392)
			(xy 272.958673 -257.412985) (xy 272.916643 -257.452927) (xy 272.869048 -257.486042) (xy 272.816985 -257.511565)
			(xy 272.761658 -257.528907) (xy 272.704341 -257.537668) (xy 272.67535 -257.53822) (xy 272.647582 -257.537716)
			(xy 272.592633 -257.529657) (xy 272.539433 -257.513716) (xy 272.489107 -257.49023) (xy 272.442718 -257.459696)
			(xy 272.401246 -257.422758) (xy 272.382996 -257.401822) (xy 272.376138 -257.393694) (xy 272.367248 -257.389122)
			(xy 272.363868 -257.387449) (xy 272.356724 -257.385031) (xy 272.353024 -257.384296) (xy 272.346928 -257.383534)
			(xy 272.27403 -257.378962) (xy 272.26641 -257.378962) (xy 272.258036 -257.380076) (xy 272.242612 -257.386942)
			(xy 272.236184 -257.392424) (xy 272.214935 -257.411317) (xy 272.167886 -257.443244) (xy 272.116619 -257.46783)
			(xy 272.062269 -257.484531) (xy 272.006041 -257.492976) (xy 271.977612 -257.493516) (xy 271.950358 -257.493053)
			(xy 271.896405 -257.485298) (xy 271.844104 -257.469942) (xy 271.794522 -257.4473) (xy 271.748666 -257.417832)
			(xy 271.707471 -257.382137) (xy 271.671775 -257.340944) (xy 271.642306 -257.295089) (xy 271.619662 -257.245507)
			(xy 271.604305 -257.193207) (xy 271.596547 -257.139254) (xy 271.596547 -257.084746) (xy 271.604305 -257.030793)
			(xy 271.619662 -256.978493) (xy 271.642306 -256.928911) (xy 271.671775 -256.883056) (xy 271.707471 -256.841863)
			(xy 271.748666 -256.806168) (xy 271.794522 -256.7767) (xy 271.844104 -256.754058) (xy 271.896405 -256.738702)
			(xy 271.950358 -256.730947) (xy 271.977612 -256.7305) (xy 272.005381 -256.731002) (xy 272.060332 -256.739056)
			(xy 272.113535 -256.754994) (xy 272.163864 -256.778478) (xy 272.210257 -256.809011) (xy 272.251731 -256.845948)
			(xy 272.269966 -256.866898) (xy 272.276824 -256.875026) (xy 272.285714 -256.879598) (xy 272.289094 -256.881273)
			(xy 272.296237 -256.883696) (xy 272.299938 -256.884424) (xy 272.306034 -256.885186) (xy 272.378932 -256.889758)
			(xy 272.386552 -256.889758) (xy 272.394923 -256.888636) (xy 272.410335 -256.881758) (xy 272.416778 -256.876296)
			(xy 272.438026 -256.857399) (xy 272.485073 -256.825467) (xy 272.53634 -256.800874) (xy 272.590691 -256.784167)
			(xy 272.64692 -256.775716) (xy 272.67535 -256.775204) (xy 272.703923 -256.775708) (xy 272.760431 -256.78422)
			(xy 272.815039 -256.801061) (xy 272.866527 -256.825854) (xy 272.913743 -256.858046) (xy 272.955632 -256.896917)
			(xy 272.991258 -256.941599) (xy 273.019825 -256.991092) (xy 273.030696 -257.01752) (xy 273.030696 -257.018028)
			(xy 273.03095 -257.018028) (xy 273.033523 -257.024038) (xy 273.041239 -257.034586) (xy 273.04619 -257.038856)
			(xy 273.05127 -257.04292) (xy 273.05762 -257.045714) (xy 273.070828 -257.049524) (xy 273.158204 -257.06197)
			(xy 273.167068 -257.06293) (xy 273.18452 -257.059331) (xy 273.199684 -257.049975) (xy 273.205448 -257.043174)
			(xy 273.205702 -257.04292) (xy 273.226195 -257.017516) (xy 273.274345 -256.973458) (xy 273.30146 -256.95529)
			(xy 273.307048 -256.951734) (xy 273.316192 -256.941574) (xy 273.31924 -256.935224) (xy 273.322144 -256.928905)
			(xy 273.324723 -256.915243) (xy 273.32432 -256.9083) (xy 273.265646 -256.243074) (xy 273.265138 -256.240026)
			(xy 273.06016 -254.89535) (xy 273.059003 -254.883375) (xy 273.066551 -254.860568) (xy 273.074638 -254.851662)
			(xy 273.106134 -254.820166) (xy 273.111323 -254.814485) (xy 273.118293 -254.800778) (xy 273.11985 -254.793242)
			(xy 273.11985 -254.792734) (xy 273.120612 -254.784606) (xy 273.120612 -254.613664) (xy 273.120358 -254.609092)
			(xy 273.05508 -253.871476) (xy 273.053354 -253.859611) (xy 273.04063 -253.839328) (xy 273.030696 -253.832614)
			(xy 272.993612 -253.810262) (xy 272.99285 -253.810008) (xy 272.983204 -253.805023) (xy 272.961615 -253.8029)
			(xy 272.951194 -253.805944) (xy 272.947892 -253.807468) (xy 272.924145 -253.817121) (xy 272.874717 -253.8307)
			(xy 272.823916 -253.83755) (xy 272.798286 -253.837948) (xy 272.793714 -253.837948) (xy 272.766678 -253.837151)
			(xy 272.713229 -253.828869) (xy 272.661486 -253.813119) (xy 272.612486 -253.79022) (xy 272.567212 -253.760628)
			(xy 272.526572 -253.724939) (xy 272.49138 -253.683867) (xy 272.462342 -253.638235) (xy 272.440041 -253.58896)
			(xy 272.424923 -253.537029) (xy 272.417292 -253.483484) (xy 272.416778 -253.45644) (xy 272.417238 -253.429185)
			(xy 272.42499 -253.375229) (xy 272.440343 -253.322925) (xy 272.462983 -253.273339) (xy 272.49245 -253.22748)
			(xy 272.528143 -253.186281) (xy 272.569337 -253.150582) (xy 272.615192 -253.121109) (xy 272.664775 -253.098462)
			(xy 272.717076 -253.083102) (xy 272.771031 -253.075342) (xy 272.798286 -253.074932) (xy 272.819944 -253.075263)
			(xy 272.862974 -253.080227) (xy 272.884138 -253.084838) (xy 272.89633 -253.087632) (xy 272.90776 -253.084838)
			(xy 272.913482 -253.083226) (xy 272.924003 -253.0777) (xy 272.928588 -253.073916) (xy 272.960846 -253.045976)
			(xy 272.964402 -253.042674) (xy 272.971529 -253.034455) (xy 272.978633 -253.013917) (xy 272.978118 -253.00305)
			(xy 272.848324 -251.540264) (xy 272.846546 -251.539756) (xy 272.801842 -251.54001) (xy 272.798286 -251.54001)
			(xy 272.771035 -251.539523) (xy 272.717089 -251.531765) (xy 272.664796 -251.516409) (xy 272.61522 -251.493767)
			(xy 272.569371 -251.4643) (xy 272.528183 -251.428609) (xy 272.492493 -251.387419) (xy 272.463027 -251.341569)
			(xy 272.440387 -251.291993) (xy 272.425032 -251.239699) (xy 272.417276 -251.185753) (xy 272.416778 -251.158502)
			(xy 272.416856 -251.145764) (xy 272.41851 -251.120343) (xy 272.42008 -251.107702) (xy 272.424373 -251.079645)
			(xy 272.440176 -251.025133) (xy 272.463879 -250.973562) (xy 272.494959 -250.92607) (xy 272.532729 -250.883706)
			(xy 272.576358 -250.847403) (xy 272.624883 -250.817962) (xy 272.677232 -250.796033) (xy 272.732253 -250.7821)
			(xy 272.76044 -250.778772) (xy 272.767044 -250.77801) (xy 272.780252 -250.7742) (xy 272.114264 -243.26469)
			(xy 272.113101 -243.255956) (xy 272.105704 -243.239976) (xy 272.099786 -243.233448) (xy 267.533628 -238.66729)
			(xy 267.524484 -238.663734) (xy 267.519917 -238.66198) (xy 267.510324 -238.660065) (xy 267.505434 -238.659924)
			(xy 262.232648 -238.659924) (xy 262.222581 -238.659492) (xy 262.203988 -238.651767) (xy 262.19658 -238.644938)
			(xy 262.17499 -238.623348) (xy 262.167578 -238.616664) (xy 262.149145 -238.609067) (xy 262.129207 -238.609067)
			(xy 262.110774 -238.616664) (xy 262.103362 -238.623348) (xy 262.1026 -238.62411) (xy 262.084565 -238.642214)
			(xy 262.044493 -238.673922) (xy 262.000543 -238.699994) (xy 261.953506 -238.719962) (xy 261.904222 -238.733469)
			(xy 261.853576 -238.740271) (xy 261.828026 -238.740696) (xy 261.800772 -238.740234) (xy 261.746819 -238.73248)
			(xy 261.694519 -238.717126) (xy 261.644936 -238.694485) (xy 261.599081 -238.665018) (xy 261.557886 -238.629324)
			(xy 261.522191 -238.588131) (xy 261.492721 -238.542276) (xy 261.470078 -238.492694) (xy 261.454723 -238.440395)
			(xy 261.446967 -238.386442) (xy 261.446518 -238.359188) (xy 261.446995 -238.332654) (xy 261.454382 -238.280101)
			(xy 261.468971 -238.229077) (xy 261.49048 -238.180562) (xy 261.518497 -238.135492) (xy 261.535164 -238.11484)
			(xy 261.535672 -238.114332) (xy 261.541514 -238.106966) (xy 261.544308 -238.09833) (xy 261.545669 -238.093888)
			(xy 261.546942 -238.084687) (xy 261.546848 -238.080042) (xy 261.5438 -238.011208) (xy 261.543043 -238.001763)
			(xy 261.535478 -237.984404) (xy 261.529068 -237.977426) (xy 259.765292 -236.21365) (xy 259.758454 -236.206248)
			(xy 259.750739 -236.18765) (xy 259.750306 -236.177582) (xy 259.750306 -233.569764) (xy 259.749544 -233.561382)
			(xy 259.748727 -233.557471) (xy 259.746042 -233.549947) (xy 259.74421 -233.546396) (xy 259.73659 -233.535728)
			(xy 259.715 -233.512868) (xy 259.687314 -233.483404) (xy 259.680456 -233.477816) (xy 259.674538 -233.474062)
			(xy 259.661275 -233.469548) (xy 259.654294 -233.468926) (xy 259.653532 -233.468926) (xy 259.62612 -233.466822)
			(xy 259.572274 -233.455732) (xy 259.520576 -233.437031) (xy 259.472096 -233.411106) (xy 259.427836 -233.378495)
			(xy 259.388713 -233.33987) (xy 259.355537 -233.296033) (xy 259.328993 -233.247889) (xy 259.30963 -233.196435)
			(xy 259.29785 -233.142736) (xy 259.293896 -233.087902) (xy 259.297849 -233.033067) (xy 259.309629 -232.979368)
			(xy 259.328991 -232.927914) (xy 259.355535 -232.87977) (xy 259.388711 -232.835932) (xy 259.427834 -232.797307)
			(xy 259.472093 -232.764695) (xy 259.520573 -232.73877) (xy 259.572271 -232.720069) (xy 259.626117 -232.708978)
			(xy 259.653532 -232.706926) (xy 259.654294 -232.706926) (xy 259.661286 -232.706356) (xy 259.674561 -232.701839)
			(xy 259.680456 -232.698036) (xy 259.687314 -232.692448) (xy 259.715 -232.662984) (xy 259.73659 -232.640124)
			(xy 259.74421 -232.629456) (xy 259.746059 -232.625913) (xy 259.74874 -232.618385) (xy 259.749544 -232.61447)
			(xy 259.750306 -232.606088) (xy 259.750306 -227.766626) (xy 259.750052 -227.761292) (xy 259.748362 -227.749919)
			(xy 259.736309 -227.730366) (xy 259.726938 -227.7237) (xy 259.72643 -227.723446) (xy 259.653278 -227.677726)
			(xy 259.645863 -227.673531) (xy 259.629242 -227.66984) (xy 259.612328 -227.6718) (xy 259.60451 -227.675186)
			(xy 259.604256 -227.675186) (xy 259.578159 -227.687271) (xy 259.523242 -227.704342) (xy 259.466386 -227.712992)
			(xy 259.437632 -227.71354) (xy 259.410375 -227.713079) (xy 259.356416 -227.705325) (xy 259.30411 -227.689971)
			(xy 259.254522 -227.667328) (xy 259.208661 -227.637859) (xy 259.167461 -227.602162) (xy 259.131761 -227.560965)
			(xy 259.102287 -227.515106) (xy 259.07964 -227.46552) (xy 259.064281 -227.413215) (xy 259.056523 -227.359257)
			(xy 259.056523 -227.304743) (xy 259.064281 -227.250785) (xy 259.07964 -227.19848) (xy 259.102287 -227.148894)
			(xy 259.131761 -227.103035) (xy 259.167461 -227.061838) (xy 259.208661 -227.026141) (xy 259.254522 -226.996672)
			(xy 259.30411 -226.974029) (xy 259.356416 -226.958675) (xy 259.410375 -226.950921) (xy 259.437632 -226.950524)
			(xy 259.466389 -226.951044) (xy 259.52325 -226.959684) (xy 259.578164 -226.976776) (xy 259.604256 -226.988878)
			(xy 259.60451 -226.988878) (xy 259.612318 -226.992301) (xy 259.629243 -226.994271) (xy 259.645872 -226.990561)
			(xy 259.653278 -226.986338) (xy 259.72643 -226.940618) (xy 259.726938 -226.940364) (xy 259.736225 -226.933623)
			(xy 259.748231 -226.914102) (xy 259.750052 -226.902772) (xy 259.750306 -226.897438) (xy 259.750306 -222.177864)
			(xy 259.749976 -222.169259) (xy 259.744272 -222.153021) (xy 259.73913 -222.146114) (xy 259.738622 -222.145606)
			(xy 259.735574 -222.14205) (xy 259.142484 -221.54896) (xy 259.13334 -221.545404) (xy 259.128773 -221.543646)
			(xy 259.119181 -221.541721) (xy 259.11429 -221.541594) (xy 255.554734 -221.541594) (xy 255.548867 -221.541748)
			(xy 255.537448 -221.544448) (xy 255.532128 -221.546928) (xy 255.51257 -221.556834) (xy 255.503172 -221.56293)
			(xy 255.499108 -221.566232) (xy 255.495552 -221.57055) (xy 255.477351 -221.592583) (xy 255.435477 -221.631472)
			(xy 255.388271 -221.663681) (xy 255.336789 -221.68849) (xy 255.282184 -221.705344) (xy 255.225676 -221.713867)
			(xy 255.168528 -221.713867) (xy 255.11202 -221.705344) (xy 255.057415 -221.68849) (xy 255.005933 -221.663681)
			(xy 254.958727 -221.631472) (xy 254.916853 -221.592583) (xy 254.898652 -221.57055) (xy 254.895096 -221.566232)
			(xy 254.891032 -221.56293) (xy 254.881634 -221.556834) (xy 254.862076 -221.546928) (xy 254.856751 -221.544464)
			(xy 254.845335 -221.541766) (xy 254.83947 -221.541594) (xy 248.487184 -221.541594) (xy 248.478577 -221.541921)
			(xy 248.462336 -221.54762) (xy 248.455434 -221.55277) (xy 248.454926 -221.553278) (xy 248.45137 -221.556326)
			(xy 247.35409 -222.653606) (xy 248.510806 -222.653606) (xy 248.511292 -222.626355) (xy 248.519048 -222.572407)
			(xy 248.534403 -222.520112) (xy 248.557045 -222.470535) (xy 248.586511 -222.424685) (xy 248.622202 -222.383494)
			(xy 248.663393 -222.347803) (xy 248.709243 -222.318337) (xy 248.75882 -222.295695) (xy 248.811115 -222.28034)
			(xy 248.865063 -222.272584) (xy 248.919565 -222.272584) (xy 248.973513 -222.28034) (xy 249.025808 -222.295695)
			(xy 249.075385 -222.318337) (xy 249.121235 -222.347803) (xy 249.162426 -222.383494) (xy 249.198117 -222.424685)
			(xy 249.227583 -222.470535) (xy 249.250225 -222.520112) (xy 249.26558 -222.572407) (xy 249.273336 -222.626355)
			(xy 249.273822 -222.653606) (xy 249.273822 -222.65386) (xy 249.273181 -222.685576) (xy 249.262688 -222.748133)
			(xy 249.241969 -222.808085) (xy 249.22734 -222.836232) (xy 249.222514 -222.844868) (xy 249.221498 -222.854266)
			(xy 249.221014 -222.858913) (xy 249.221521 -222.868242) (xy 249.222514 -222.872808) (xy 249.239786 -222.939864)
			(xy 249.241047 -222.944472) (xy 249.245002 -222.953167) (xy 249.24766 -222.957136) (xy 249.253502 -222.96501)
			(xy 249.261376 -222.97009) (xy 249.283949 -222.98526) (xy 249.324977 -223.020961) (xy 249.36052 -223.062126)
			(xy 249.36144 -223.063562) (xy 250.628656 -223.063562) (xy 250.632727 -223.00794) (xy 250.644853 -222.953503)
			(xy 250.664776 -222.901412) (xy 250.692072 -222.852777) (xy 250.726158 -222.808634) (xy 250.766307 -222.769925)
			(xy 250.811665 -222.737474) (xy 250.861265 -222.711973) (xy 250.914049 -222.693966) (xy 250.968892 -222.683836)
			(xy 251.024626 -222.681799) (xy 251.080063 -222.687899) (xy 251.13402 -222.702005) (xy 251.185349 -222.723817)
			(xy 251.232955 -222.752871) (xy 251.275823 -222.788546) (xy 251.31304 -222.830083) (xy 251.343813 -222.876596)
			(xy 251.367485 -222.927093) (xy 251.382255 -222.976186) (xy 255.04267 -222.976186) (xy 255.043224 -222.94727)
			(xy 255.051942 -222.890099) (xy 255.069191 -222.8349) (xy 255.094576 -222.782938) (xy 255.127515 -222.735403)
			(xy 255.167252 -222.693386) (xy 255.189736 -222.675196) (xy 255.198501 -222.667638) (xy 255.208681 -222.646876)
			(xy 255.209294 -222.635318) (xy 255.209294 -222.555054) (xy 255.208694 -222.54349) (xy 255.198521 -222.522718)
			(xy 255.189736 -222.515176) (xy 255.167249 -222.496989) (xy 255.127512 -222.45497) (xy 255.094572 -222.407434)
			(xy 255.069184 -222.355472) (xy 255.05193 -222.300273) (xy 255.043203 -222.243102) (xy 255.04267 -222.214186)
			(xy 255.043156 -222.186935) (xy 255.050912 -222.132987) (xy 255.066267 -222.080692) (xy 255.088909 -222.031115)
			(xy 255.118375 -221.985265) (xy 255.154066 -221.944074) (xy 255.195257 -221.908383) (xy 255.241107 -221.878917)
			(xy 255.290684 -221.856275) (xy 255.342979 -221.84092) (xy 255.396927 -221.833164) (xy 255.451429 -221.833164)
			(xy 255.505377 -221.84092) (xy 255.557672 -221.856275) (xy 255.607249 -221.878917) (xy 255.653099 -221.908383)
			(xy 255.69429 -221.944074) (xy 255.729981 -221.985265) (xy 255.759447 -222.031115) (xy 255.782089 -222.080692)
			(xy 255.797444 -222.132987) (xy 255.8052 -222.186935) (xy 255.805686 -222.214186) (xy 255.805163 -222.243103)
			(xy 255.796436 -222.300274) (xy 255.779179 -222.355473) (xy 255.753788 -222.407435) (xy 255.720845 -222.454969)
			(xy 255.681105 -222.496986) (xy 255.65862 -222.515176) (xy 255.64986 -222.522739) (xy 255.639679 -222.543498)
			(xy 255.639062 -222.555054) (xy 255.639062 -222.635318) (xy 255.639601 -222.646891) (xy 255.649816 -222.667662)
			(xy 255.65862 -222.675196) (xy 255.681106 -222.693384) (xy 255.72084 -222.735405) (xy 255.753778 -222.782941)
			(xy 255.779166 -222.834903) (xy 255.796422 -222.8901) (xy 255.805151 -222.94727) (xy 255.805686 -222.976186)
			(xy 255.8052 -223.003437) (xy 255.797444 -223.057385) (xy 255.782089 -223.10968) (xy 255.759447 -223.159257)
			(xy 255.729981 -223.205107) (xy 255.69429 -223.246298) (xy 255.653099 -223.281989) (xy 255.607249 -223.311455)
			(xy 255.557672 -223.334097) (xy 255.505377 -223.349452) (xy 255.451429 -223.357208) (xy 255.396927 -223.357208)
			(xy 255.342979 -223.349452) (xy 255.290684 -223.334097) (xy 255.241107 -223.311455) (xy 255.195257 -223.281989)
			(xy 255.154066 -223.246298) (xy 255.118375 -223.205107) (xy 255.088909 -223.159257) (xy 255.066267 -223.10968)
			(xy 255.050912 -223.057385) (xy 255.043156 -223.003437) (xy 255.04267 -222.976186) (xy 251.382255 -222.976186)
			(xy 251.383553 -222.9805) (xy 251.391673 -223.035676) (xy 251.392182 -223.063562) (xy 251.391673 -223.091448)
			(xy 251.383553 -223.146624) (xy 251.367485 -223.200031) (xy 251.343813 -223.250528) (xy 251.31304 -223.297041)
			(xy 251.275823 -223.338578) (xy 251.232955 -223.374253) (xy 251.185349 -223.403307) (xy 251.13402 -223.425119)
			(xy 251.080063 -223.439225) (xy 251.024626 -223.445325) (xy 250.968892 -223.443288) (xy 250.914049 -223.433158)
			(xy 250.861265 -223.415151) (xy 250.811665 -223.38965) (xy 250.766307 -223.357199) (xy 250.726158 -223.31849)
			(xy 250.692072 -223.274347) (xy 250.664776 -223.225712) (xy 250.644853 -223.173621) (xy 250.632727 -223.119184)
			(xy 250.628656 -223.063562) (xy 249.36144 -223.063562) (xy 249.389858 -223.10792) (xy 249.412396 -223.157415)
			(xy 249.427679 -223.20961) (xy 249.435395 -223.263445) (xy 249.435874 -223.290638) (xy 249.435388 -223.317889)
			(xy 249.427632 -223.371837) (xy 249.412277 -223.424132) (xy 249.389635 -223.473709) (xy 249.360169 -223.519559)
			(xy 249.324478 -223.56075) (xy 249.283287 -223.596441) (xy 249.237437 -223.625907) (xy 249.18786 -223.648549)
			(xy 249.135565 -223.663904) (xy 249.081617 -223.67166) (xy 249.027115 -223.67166) (xy 248.973167 -223.663904)
			(xy 248.920872 -223.648549) (xy 248.871295 -223.625907) (xy 248.825445 -223.596441) (xy 248.784254 -223.56075)
			(xy 248.748563 -223.519559) (xy 248.719097 -223.473709) (xy 248.696455 -223.424132) (xy 248.6811 -223.371837)
			(xy 248.673344 -223.317889) (xy 248.672858 -223.290638) (xy 248.672858 -223.290384) (xy 248.673468 -223.258667)
			(xy 248.683972 -223.196108) (xy 248.704704 -223.136157) (xy 248.71934 -223.108012) (xy 248.724166 -223.099376)
			(xy 248.725182 -223.089978) (xy 248.725679 -223.085332) (xy 248.725163 -223.076002) (xy 248.724166 -223.071436)
			(xy 248.706894 -223.00438) (xy 248.705648 -222.999767) (xy 248.701683 -222.991075) (xy 248.69902 -222.987108)
			(xy 248.693178 -222.979234) (xy 248.685304 -222.974154) (xy 248.6627 -222.959027) (xy 248.621674 -222.923318)
			(xy 248.586134 -222.882146) (xy 248.5568 -222.836345) (xy 248.534267 -222.786842) (xy 248.51899 -222.734642)
			(xy 248.511281 -222.680801) (xy 248.510806 -222.653606) (xy 247.35409 -222.653606) (xy 246.568214 -223.439482)
			(xy 246.564658 -223.448626) (xy 246.562908 -223.453194) (xy 246.560997 -223.462786) (xy 246.560848 -223.467676)
			(xy 246.560848 -225.623882) (xy 250.583698 -225.623882) (xy 250.587769 -225.56826) (xy 250.599895 -225.513823)
			(xy 250.619818 -225.461732) (xy 250.647114 -225.413097) (xy 250.6812 -225.368954) (xy 250.721349 -225.330245)
			(xy 250.766707 -225.297794) (xy 250.816307 -225.272293) (xy 250.869091 -225.254286) (xy 250.923934 -225.244156)
			(xy 250.979668 -225.242119) (xy 251.035105 -225.248219) (xy 251.089062 -225.262325) (xy 251.140391 -225.284137)
			(xy 251.187997 -225.313191) (xy 251.230865 -225.348866) (xy 251.268082 -225.390403) (xy 251.298855 -225.436916)
			(xy 251.322527 -225.487413) (xy 251.338595 -225.54082) (xy 251.346715 -225.595996) (xy 251.347224 -225.623882)
			(xy 251.346715 -225.651768) (xy 251.338595 -225.706944) (xy 251.338562 -225.707053) (xy 252.38274 -225.707053)
			(xy 252.38274 -225.652547) (xy 252.390497 -225.598595) (xy 252.405852 -225.546297) (xy 252.428494 -225.496716)
			(xy 252.457962 -225.450862) (xy 252.493655 -225.409668) (xy 252.534847 -225.373973) (xy 252.5807 -225.344503)
			(xy 252.63028 -225.321859) (xy 252.682578 -225.3065) (xy 252.736529 -225.298741) (xy 252.763782 -225.298254)
			(xy 252.793288 -225.298796) (xy 252.851593 -225.307899) (xy 252.907804 -225.325862) (xy 252.960584 -225.352256)
			(xy 253.008677 -225.386453) (xy 253.050939 -225.427639) (xy 253.06909 -225.450908) (xy 253.078104 -225.462225)
			(xy 253.101178 -225.479659) (xy 253.128218 -225.489916) (xy 253.157049 -225.49217) (xy 253.185355 -225.486239)
			(xy 253.210857 -225.472601) (xy 253.231505 -225.452353) (xy 253.239016 -225.439986) (xy 253.253643 -225.415103)
			(xy 253.289177 -225.369623) (xy 253.331157 -225.330014) (xy 253.378625 -225.297181) (xy 253.430496 -225.271873)
			(xy 253.485589 -225.254669) (xy 253.542644 -225.245959) (xy 253.571502 -225.245422) (xy 253.598755 -225.245848)
			(xy 253.652707 -225.253605) (xy 253.705006 -225.268962) (xy 253.754587 -225.291605) (xy 253.80044 -225.321074)
			(xy 253.841634 -225.356768) (xy 253.877328 -225.397961) (xy 253.906796 -225.443815) (xy 253.929439 -225.493396)
			(xy 253.944795 -225.545695) (xy 253.952552 -225.599647) (xy 253.952552 -225.654153) (xy 253.944795 -225.708105)
			(xy 253.929439 -225.760404) (xy 253.906796 -225.809985) (xy 253.877328 -225.855839) (xy 253.841634 -225.897032)
			(xy 253.80044 -225.932726) (xy 253.754587 -225.962195) (xy 253.705006 -225.984838) (xy 253.652707 -226.000195)
			(xy 253.598755 -226.007952) (xy 253.571502 -226.008438) (xy 253.541995 -226.007859) (xy 253.48368 -225.998797)
			(xy 253.427458 -225.980859) (xy 253.374671 -225.954473) (xy 253.32658 -225.920269) (xy 253.284333 -225.879064)
			(xy 253.266194 -225.855784) (xy 253.257198 -225.844452) (xy 253.23412 -225.827018) (xy 253.207076 -225.816764)
			(xy 253.178241 -225.814513) (xy 253.149933 -225.820446) (xy 253.124429 -225.834087) (xy 253.103779 -225.854338)
			(xy 253.096268 -225.866706) (xy 253.081649 -225.891594) (xy 253.046114 -225.937075) (xy 253.004133 -225.976684)
			(xy 252.956664 -226.009516) (xy 252.904791 -226.034823) (xy 252.849697 -226.052027) (xy 252.79264 -226.060734)
			(xy 252.763782 -226.06127) (xy 252.736529 -226.060859) (xy 252.682578 -226.0531) (xy 252.63028 -226.037741)
			(xy 252.5807 -226.015097) (xy 252.534847 -225.985627) (xy 252.493655 -225.949932) (xy 252.457962 -225.908738)
			(xy 252.428494 -225.862884) (xy 252.405852 -225.813303) (xy 252.390497 -225.761005) (xy 252.38274 -225.707053)
			(xy 251.338562 -225.707053) (xy 251.322527 -225.760351) (xy 251.298855 -225.810848) (xy 251.268082 -225.857361)
			(xy 251.230865 -225.898898) (xy 251.187997 -225.934573) (xy 251.140391 -225.963627) (xy 251.089062 -225.985439)
			(xy 251.035105 -225.999545) (xy 250.979668 -226.005645) (xy 250.923934 -226.003608) (xy 250.869091 -225.993478)
			(xy 250.816307 -225.975471) (xy 250.766707 -225.94997) (xy 250.721349 -225.917519) (xy 250.6812 -225.87881)
			(xy 250.647114 -225.834667) (xy 250.619818 -225.786032) (xy 250.599895 -225.733941) (xy 250.587769 -225.679504)
			(xy 250.583698 -225.623882) (xy 246.560848 -225.623882) (xy 246.560848 -227.965) (xy 248.081036 -227.965)
			(xy 248.085107 -227.909378) (xy 248.097233 -227.854941) (xy 248.117156 -227.80285) (xy 248.144452 -227.754215)
			(xy 248.178538 -227.710072) (xy 248.218687 -227.671363) (xy 248.264045 -227.638912) (xy 248.313645 -227.613411)
			(xy 248.366429 -227.595404) (xy 248.421272 -227.585274) (xy 248.477006 -227.583237) (xy 248.532443 -227.589337)
			(xy 248.5864 -227.603443) (xy 248.637729 -227.625255) (xy 248.685335 -227.654309) (xy 248.728203 -227.689984)
			(xy 248.76542 -227.731521) (xy 248.786016 -227.762651) (xy 250.517662 -227.762651) (xy 250.517662 -227.708149)
			(xy 250.525417 -227.654203) (xy 250.540771 -227.601909) (xy 250.56341 -227.552333) (xy 250.592874 -227.506482)
			(xy 250.628563 -227.465291) (xy 250.66975 -227.429598) (xy 250.715597 -227.40013) (xy 250.765172 -227.377485)
			(xy 250.817464 -227.362126) (xy 250.871409 -227.354365) (xy 250.89866 -227.353876) (xy 250.925455 -227.354304)
			(xy 250.978516 -227.361811) (xy 251.030005 -227.376669) (xy 251.078908 -227.398586) (xy 251.124264 -227.427129)
			(xy 251.165179 -227.461739) (xy 251.200849 -227.501733) (xy 251.230572 -227.546324) (xy 251.242576 -227.570284)
			(xy 251.246894 -227.579174) (xy 251.25426 -227.585778) (xy 251.258013 -227.588932) (xy 251.26645 -227.59392)
			(xy 251.271024 -227.595684) (xy 251.338334 -227.620068) (xy 251.34772 -227.62293) (xy 251.36731 -227.622153)
			(xy 251.376434 -227.618544) (xy 251.376942 -227.618544) (xy 251.402023 -227.607494) (xy 251.454566 -227.59191)
			(xy 251.508798 -227.584001) (xy 251.5362 -227.583492) (xy 251.563451 -227.583978) (xy 251.617399 -227.591734)
			(xy 251.669694 -227.607089) (xy 251.719271 -227.629731) (xy 251.765121 -227.659197) (xy 251.806312 -227.694888)
			(xy 251.842003 -227.736079) (xy 251.871469 -227.781929) (xy 251.894111 -227.831506) (xy 251.909466 -227.883801)
			(xy 251.917222 -227.937749) (xy 251.917222 -227.992251) (xy 251.909466 -228.046199) (xy 251.894111 -228.098494)
			(xy 251.871469 -228.148071) (xy 251.842003 -228.193921) (xy 251.806312 -228.235112) (xy 251.765121 -228.270803)
			(xy 251.719271 -228.300269) (xy 251.669694 -228.322911) (xy 251.617399 -228.338266) (xy 251.563451 -228.346022)
			(xy 251.5362 -228.346508) (xy 251.509406 -228.346038) (xy 251.456347 -228.338539) (xy 251.404858 -228.323688)
			(xy 251.355955 -228.301778) (xy 251.310599 -228.27324) (xy 251.269683 -228.238636) (xy 251.234012 -228.198646)
			(xy 251.204289 -228.154058) (xy 251.192284 -228.1301) (xy 251.187966 -228.12121) (xy 251.1806 -228.114606)
			(xy 251.176854 -228.111443) (xy 251.168412 -228.10646) (xy 251.163836 -228.1047) (xy 251.096526 -228.080316)
			(xy 251.087145 -228.077432) (xy 251.067551 -228.078224) (xy 251.058426 -228.08184) (xy 251.057918 -228.08184)
			(xy 251.032831 -228.092875) (xy 250.980291 -228.108463) (xy 250.926061 -228.116379) (xy 250.89866 -228.116892)
			(xy 250.871409 -228.116435) (xy 250.817464 -228.108674) (xy 250.765172 -228.093315) (xy 250.715597 -228.07067)
			(xy 250.66975 -228.041202) (xy 250.628563 -228.005509) (xy 250.592874 -227.964318) (xy 250.56341 -227.918467)
			(xy 250.540771 -227.868891) (xy 250.525417 -227.816597) (xy 250.517662 -227.762651) (xy 248.786016 -227.762651)
			(xy 248.796193 -227.778034) (xy 248.819865 -227.828531) (xy 248.835933 -227.881938) (xy 248.844053 -227.937114)
			(xy 248.844562 -227.965) (xy 248.844053 -227.992886) (xy 248.835933 -228.048062) (xy 248.819865 -228.101469)
			(xy 248.796193 -228.151966) (xy 248.76542 -228.198479) (xy 248.728203 -228.240016) (xy 248.685335 -228.275691)
			(xy 248.637729 -228.304745) (xy 248.5864 -228.326557) (xy 248.532443 -228.340663) (xy 248.477006 -228.346763)
			(xy 248.421272 -228.344726) (xy 248.366429 -228.334596) (xy 248.313645 -228.316589) (xy 248.264045 -228.291088)
			(xy 248.218687 -228.258637) (xy 248.178538 -228.219928) (xy 248.144452 -228.175785) (xy 248.117156 -228.12715)
			(xy 248.097233 -228.075059) (xy 248.085107 -228.020622) (xy 248.081036 -227.965) (xy 246.560848 -227.965)
			(xy 246.560848 -228.538278) (xy 249.24588 -228.538278) (xy 249.249951 -228.482656) (xy 249.262077 -228.428219)
			(xy 249.282 -228.376128) (xy 249.309296 -228.327493) (xy 249.343382 -228.28335) (xy 249.383531 -228.244641)
			(xy 249.428889 -228.21219) (xy 249.478489 -228.186689) (xy 249.531273 -228.168682) (xy 249.586116 -228.158552)
			(xy 249.64185 -228.156515) (xy 249.697287 -228.162615) (xy 249.751244 -228.176721) (xy 249.802573 -228.198533)
			(xy 249.850179 -228.227587) (xy 249.893047 -228.263262) (xy 249.930264 -228.304799) (xy 249.961037 -228.351312)
			(xy 249.984709 -228.401809) (xy 250.000777 -228.455216) (xy 250.008897 -228.510392) (xy 250.009406 -228.538278)
			(xy 250.008897 -228.566164) (xy 250.000777 -228.62134) (xy 249.984709 -228.674747) (xy 249.961037 -228.725244)
			(xy 249.930264 -228.771757) (xy 249.893047 -228.813294) (xy 249.850179 -228.848969) (xy 249.802573 -228.878023)
			(xy 249.751244 -228.899835) (xy 249.697287 -228.913941) (xy 249.64185 -228.920041) (xy 249.586116 -228.918004)
			(xy 249.531273 -228.907874) (xy 249.478489 -228.889867) (xy 249.428889 -228.864366) (xy 249.383531 -228.831915)
			(xy 249.343382 -228.793206) (xy 249.309296 -228.749063) (xy 249.282 -228.700428) (xy 249.262077 -228.648337)
			(xy 249.249951 -228.5939) (xy 249.24588 -228.538278) (xy 246.560848 -228.538278) (xy 246.560848 -230.381302)
			(xy 246.561893 -230.390521) (xy 246.569712 -230.407328) (xy 246.576088 -230.414068) (xy 246.62765 -230.464614)
			(xy 246.631382 -230.468133) (xy 246.639958 -230.473757) (xy 246.644668 -230.47579) (xy 246.653812 -230.479346)
			(xy 246.663972 -230.479346) (xy 246.669814 -230.479092) (xy 246.671338 -230.479092) (xy 246.699595 -230.479632)
			(xy 246.755534 -230.487695) (xy 246.80978 -230.503554) (xy 246.812969 -230.505) (xy 248.410474 -230.505)
			(xy 248.414545 -230.449378) (xy 248.426671 -230.394941) (xy 248.446594 -230.34285) (xy 248.47389 -230.294215)
			(xy 248.507976 -230.250072) (xy 248.548125 -230.211363) (xy 248.593483 -230.178912) (xy 248.643083 -230.153411)
			(xy 248.695867 -230.135404) (xy 248.75071 -230.125274) (xy 248.806444 -230.123237) (xy 248.861881 -230.129337)
			(xy 248.915838 -230.143443) (xy 248.967167 -230.165255) (xy 249.014773 -230.194309) (xy 249.057641 -230.229984)
			(xy 249.094858 -230.271521) (xy 249.125631 -230.318034) (xy 249.140923 -230.350655) (xy 254.363145 -230.350655)
			(xy 254.363145 -230.296145) (xy 254.370903 -230.242191) (xy 254.38626 -230.18989) (xy 254.408905 -230.140308)
			(xy 254.438375 -230.094452) (xy 254.474072 -230.053258) (xy 254.515268 -230.017563) (xy 254.561125 -229.988095)
			(xy 254.610709 -229.965453) (xy 254.663011 -229.950098) (xy 254.716965 -229.942344) (xy 254.74422 -229.941882)
			(xy 254.775203 -229.942506) (xy 254.836342 -229.952595) (xy 254.865886 -229.961948) (xy 254.86614 -229.961948)
			(xy 254.873853 -229.964163) (xy 254.88989 -229.964297) (xy 254.897636 -229.962202) (xy 254.908558 -229.957376)
			(xy 254.974598 -229.917498) (xy 254.974852 -229.917244) (xy 254.979548 -229.914235) (xy 254.98763 -229.906554)
			(xy 254.990854 -229.902004) (xy 254.996696 -229.893368) (xy 254.998474 -229.882192) (xy 255.003294 -229.855794)
			(xy 255.019457 -229.804624) (xy 255.04263 -229.756223) (xy 255.072355 -229.711545) (xy 255.108047 -229.671473)
			(xy 255.149001 -229.636798) (xy 255.194409 -229.608202) (xy 255.243376 -229.58625) (xy 255.294936 -229.571375)
			(xy 255.348071 -229.563871) (xy 255.374902 -229.563422) (xy 255.402155 -229.563848) (xy 255.456107 -229.571605)
			(xy 255.508406 -229.586962) (xy 255.557987 -229.609605) (xy 255.60384 -229.639074) (xy 255.645034 -229.674768)
			(xy 255.680728 -229.715961) (xy 255.710196 -229.761815) (xy 255.732839 -229.811396) (xy 255.748195 -229.863695)
			(xy 255.755952 -229.917647) (xy 255.755952 -229.972153) (xy 255.748195 -230.026105) (xy 255.732839 -230.078404)
			(xy 255.710196 -230.127985) (xy 255.680728 -230.173839) (xy 255.645034 -230.215032) (xy 255.60384 -230.250726)
			(xy 255.557987 -230.280195) (xy 255.508406 -230.302838) (xy 255.456107 -230.318195) (xy 255.402155 -230.325952)
			(xy 255.374902 -230.326438) (xy 255.34392 -230.325808) (xy 255.28278 -230.315723) (xy 255.253236 -230.306372)
			(xy 255.252982 -230.306372) (xy 255.245267 -230.304167) (xy 255.229232 -230.304026) (xy 255.221486 -230.306118)
			(xy 255.210564 -230.310944) (xy 255.144524 -230.350822) (xy 255.14427 -230.351076) (xy 255.139561 -230.354066)
			(xy 255.131487 -230.36176) (xy 255.128268 -230.366316) (xy 255.122426 -230.374952) (xy 255.120648 -230.386128)
			(xy 255.115822 -230.412524) (xy 255.099658 -230.463693) (xy 255.076484 -230.512093) (xy 255.046759 -230.556769)
			(xy 255.011068 -230.59684) (xy 254.970115 -230.631516) (xy 254.924708 -230.660112) (xy 254.875743 -230.682065)
			(xy 254.824184 -230.696941) (xy 254.771051 -230.704448) (xy 254.74422 -230.704898) (xy 254.716965 -230.704456)
			(xy 254.663011 -230.696702) (xy 254.610709 -230.681347) (xy 254.561125 -230.658705) (xy 254.515268 -230.629237)
			(xy 254.474072 -230.593542) (xy 254.438375 -230.552348) (xy 254.408905 -230.506492) (xy 254.38626 -230.45691)
			(xy 254.370903 -230.404609) (xy 254.363145 -230.350655) (xy 249.140923 -230.350655) (xy 249.149303 -230.368531)
			(xy 249.165371 -230.421938) (xy 249.173491 -230.477114) (xy 249.174 -230.505) (xy 249.173491 -230.532886)
			(xy 249.165371 -230.588062) (xy 249.149303 -230.641469) (xy 249.125631 -230.691966) (xy 249.094858 -230.738479)
			(xy 249.057641 -230.780016) (xy 249.014773 -230.815691) (xy 248.967167 -230.844745) (xy 248.915838 -230.866557)
			(xy 248.861881 -230.880663) (xy 248.806444 -230.886763) (xy 248.75071 -230.884726) (xy 248.695867 -230.874596)
			(xy 248.643083 -230.856589) (xy 248.593483 -230.831088) (xy 248.548125 -230.798637) (xy 248.507976 -230.759928)
			(xy 248.47389 -230.715785) (xy 248.446594 -230.66715) (xy 248.426671 -230.615059) (xy 248.414545 -230.560622)
			(xy 248.410474 -230.505) (xy 246.812969 -230.505) (xy 246.861251 -230.526895) (xy 246.908923 -230.557252)
			(xy 246.951844 -230.594019) (xy 246.98916 -230.636465) (xy 247.020127 -230.683743) (xy 247.044127 -230.73491)
			(xy 247.052846 -230.761794) (xy 247.056148 -230.77297) (xy 247.063768 -230.781352) (xy 247.067879 -230.785594)
			(xy 247.077634 -230.792251) (xy 247.083072 -230.79456) (xy 247.15724 -230.823262) (xy 247.162546 -230.825196)
			(xy 247.173693 -230.826995) (xy 247.179338 -230.826818) (xy 247.191022 -230.825802) (xy 247.200928 -230.81996)
			(xy 247.222877 -230.807651) (xy 247.269319 -230.788271) (xy 247.317904 -230.77516) (xy 247.36779 -230.768543)
			(xy 247.392952 -230.768144) (xy 247.420211 -230.768604) (xy 247.474174 -230.776356) (xy 247.526484 -230.79171)
			(xy 247.576076 -230.814353) (xy 247.621941 -230.843823) (xy 247.663145 -230.879521) (xy 247.698848 -230.92072)
			(xy 247.728324 -230.966582) (xy 247.750973 -231.016171) (xy 247.766334 -231.06848) (xy 247.774093 -231.122442)
			(xy 247.774093 -231.13873) (xy 249.244864 -231.13873) (xy 249.248935 -231.083108) (xy 249.261061 -231.028671)
			(xy 249.280984 -230.97658) (xy 249.30828 -230.927945) (xy 249.342366 -230.883802) (xy 249.382515 -230.845093)
			(xy 249.427873 -230.812642) (xy 249.477473 -230.787141) (xy 249.530257 -230.769134) (xy 249.5851 -230.759004)
			(xy 249.640834 -230.756967) (xy 249.696271 -230.763067) (xy 249.750228 -230.777173) (xy 249.801557 -230.798985)
			(xy 249.849163 -230.828039) (xy 249.892031 -230.863714) (xy 249.929248 -230.905251) (xy 249.960021 -230.951764)
			(xy 249.983693 -231.002261) (xy 249.999761 -231.055668) (xy 250.007881 -231.110844) (xy 250.00839 -231.13873)
			(xy 250.007881 -231.166616) (xy 249.999761 -231.221792) (xy 249.983693 -231.275199) (xy 249.965509 -231.31399)
			(xy 256.87985 -231.31399) (xy 256.883921 -231.258368) (xy 256.896047 -231.203931) (xy 256.91597 -231.15184)
			(xy 256.943266 -231.103205) (xy 256.977352 -231.059062) (xy 257.017501 -231.020353) (xy 257.062859 -230.987902)
			(xy 257.112459 -230.962401) (xy 257.165243 -230.944394) (xy 257.220086 -230.934264) (xy 257.27582 -230.932227)
			(xy 257.331257 -230.938327) (xy 257.385214 -230.952433) (xy 257.436543 -230.974245) (xy 257.484149 -231.003299)
			(xy 257.527017 -231.038974) (xy 257.564234 -231.080511) (xy 257.595007 -231.127024) (xy 257.618679 -231.177521)
			(xy 257.634747 -231.230928) (xy 257.642867 -231.286104) (xy 257.643376 -231.31399) (xy 257.642867 -231.341876)
			(xy 257.634747 -231.397052) (xy 257.618679 -231.450459) (xy 257.595007 -231.500956) (xy 257.564234 -231.547469)
			(xy 257.527017 -231.589006) (xy 257.484149 -231.624681) (xy 257.436543 -231.653735) (xy 257.385214 -231.675547)
			(xy 257.331257 -231.689653) (xy 257.27582 -231.695753) (xy 257.220086 -231.693716) (xy 257.165243 -231.683586)
			(xy 257.112459 -231.665579) (xy 257.062859 -231.640078) (xy 257.017501 -231.607627) (xy 256.977352 -231.568918)
			(xy 256.943266 -231.524775) (xy 256.91597 -231.47614) (xy 256.896047 -231.424049) (xy 256.883921 -231.369612)
			(xy 256.87985 -231.31399) (xy 249.965509 -231.31399) (xy 249.960021 -231.325696) (xy 249.929248 -231.372209)
			(xy 249.892031 -231.413746) (xy 249.849163 -231.449421) (xy 249.801557 -231.478475) (xy 249.750228 -231.500287)
			(xy 249.696271 -231.514393) (xy 249.640834 -231.520493) (xy 249.5851 -231.518456) (xy 249.530257 -231.508326)
			(xy 249.477473 -231.490319) (xy 249.427873 -231.464818) (xy 249.382515 -231.432367) (xy 249.342366 -231.393658)
			(xy 249.30828 -231.349515) (xy 249.280984 -231.30088) (xy 249.261061 -231.248789) (xy 249.248935 -231.194352)
			(xy 249.244864 -231.13873) (xy 247.774093 -231.13873) (xy 247.774093 -231.176958) (xy 247.766334 -231.23092)
			(xy 247.750973 -231.283229) (xy 247.728324 -231.332818) (xy 247.698848 -231.37868) (xy 247.663145 -231.419879)
			(xy 247.621941 -231.455577) (xy 247.576076 -231.485047) (xy 247.526484 -231.50769) (xy 247.474174 -231.523044)
			(xy 247.420211 -231.530796) (xy 247.392952 -231.53116) (xy 247.3644 -231.530623) (xy 247.307933 -231.522108)
			(xy 247.253366 -231.505274) (xy 247.201916 -231.480498) (xy 247.154731 -231.448333) (xy 247.112866 -231.409496)
			(xy 247.077255 -231.364856) (xy 247.062498 -231.340406) (xy 247.058688 -231.333802) (xy 247.049544 -231.324658)
			(xy 247.043448 -231.321356) (xy 247.038008 -231.318542) (xy 247.026196 -231.31532) (xy 247.02008 -231.315006)
			(xy 246.97309 -231.316022) (xy 246.928386 -231.316784) (xy 246.921528 -231.317546) (xy 246.92102 -231.317546)
			(xy 246.916266 -231.318433) (xy 246.907185 -231.321752) (xy 246.902986 -231.32415) (xy 246.897144 -231.327706)
			(xy 246.888 -231.337612) (xy 246.884698 -231.343962) (xy 246.870155 -231.370458) (xy 246.834313 -231.419123)
			(xy 246.79155 -231.461834) (xy 246.742841 -231.497616) (xy 246.689298 -231.525653) (xy 246.632143 -231.545305)
			(xy 246.602504 -231.551226) (xy 246.593773 -231.553178) (xy 246.578305 -231.56214) (xy 246.572278 -231.568752)
			(xy 246.566944 -231.57561) (xy 246.563896 -231.583484) (xy 246.562453 -231.587785) (xy 246.560929 -231.596728)
			(xy 246.560848 -231.601264) (xy 246.560848 -232.4608) (xy 246.560423 -232.470869) (xy 246.552703 -232.489469)
			(xy 246.545862 -232.496868) (xy 245.97868 -233.06405) (xy 258.296408 -233.06405) (xy 258.300479 -233.008428)
			(xy 258.312605 -232.953991) (xy 258.332528 -232.9019) (xy 258.359824 -232.853265) (xy 258.39391 -232.809122)
			(xy 258.434059 -232.770413) (xy 258.479417 -232.737962) (xy 258.529017 -232.712461) (xy 258.581801 -232.694454)
			(xy 258.636644 -232.684324) (xy 258.692378 -232.682287) (xy 258.747815 -232.688387) (xy 258.801772 -232.702493)
			(xy 258.853101 -232.724305) (xy 258.900707 -232.753359) (xy 258.943575 -232.789034) (xy 258.980792 -232.830571)
			(xy 259.011565 -232.877084) (xy 259.035237 -232.927581) (xy 259.051305 -232.980988) (xy 259.059425 -233.036164)
			(xy 259.059934 -233.06405) (xy 259.059425 -233.091936) (xy 259.051305 -233.147112) (xy 259.035237 -233.200519)
			(xy 259.011565 -233.251016) (xy 258.980792 -233.297529) (xy 258.943575 -233.339066) (xy 258.900707 -233.374741)
			(xy 258.853101 -233.403795) (xy 258.801772 -233.425607) (xy 258.747815 -233.439713) (xy 258.692378 -233.445813)
			(xy 258.636644 -233.443776) (xy 258.581801 -233.433646) (xy 258.529017 -233.415639) (xy 258.479417 -233.390138)
			(xy 258.434059 -233.357687) (xy 258.39391 -233.318978) (xy 258.359824 -233.274835) (xy 258.332528 -233.2262)
			(xy 258.312605 -233.174109) (xy 258.300479 -233.119672) (xy 258.296408 -233.06405) (xy 245.97868 -233.06405)
			(xy 245.270274 -233.772456) (xy 250.902976 -233.772456) (xy 250.907047 -233.716834) (xy 250.919173 -233.662397)
			(xy 250.939096 -233.610306) (xy 250.966392 -233.561671) (xy 251.000478 -233.517528) (xy 251.040627 -233.478819)
			(xy 251.085985 -233.446368) (xy 251.135585 -233.420867) (xy 251.188369 -233.40286) (xy 251.243212 -233.39273)
			(xy 251.298946 -233.390693) (xy 251.354383 -233.396793) (xy 251.40834 -233.410899) (xy 251.459669 -233.432711)
			(xy 251.507275 -233.461765) (xy 251.550143 -233.49744) (xy 251.58736 -233.538977) (xy 251.618133 -233.58549)
			(xy 251.641805 -233.635987) (xy 251.657873 -233.689394) (xy 251.665993 -233.74457) (xy 251.666502 -233.772456)
			(xy 251.665993 -233.800342) (xy 251.657873 -233.855518) (xy 251.641805 -233.908925) (xy 251.618133 -233.959422)
			(xy 251.58736 -234.005935) (xy 251.550143 -234.047472) (xy 251.507275 -234.083147) (xy 251.459669 -234.112201)
			(xy 251.40834 -234.134013) (xy 251.354383 -234.148119) (xy 251.298946 -234.154219) (xy 251.243212 -234.152182)
			(xy 251.188369 -234.142052) (xy 251.135585 -234.124045) (xy 251.085985 -234.098544) (xy 251.040627 -234.066093)
			(xy 251.000478 -234.027384) (xy 250.966392 -233.983241) (xy 250.939096 -233.934606) (xy 250.919173 -233.882515)
			(xy 250.907047 -233.828078) (xy 250.902976 -233.772456) (xy 245.270274 -233.772456) (xy 244.348 -234.69473)
			(xy 254.876044 -234.69473) (xy 254.880115 -234.639108) (xy 254.892241 -234.584671) (xy 254.912164 -234.53258)
			(xy 254.93946 -234.483945) (xy 254.973546 -234.439802) (xy 255.013695 -234.401093) (xy 255.059053 -234.368642)
			(xy 255.108653 -234.343141) (xy 255.161437 -234.325134) (xy 255.21628 -234.315004) (xy 255.272014 -234.312967)
			(xy 255.327451 -234.319067) (xy 255.381408 -234.333173) (xy 255.432737 -234.354985) (xy 255.480343 -234.384039)
			(xy 255.523211 -234.419714) (xy 255.560428 -234.461251) (xy 255.591201 -234.507764) (xy 255.614873 -234.558261)
			(xy 255.630941 -234.611668) (xy 255.639061 -234.666844) (xy 255.63957 -234.69473) (xy 255.639514 -234.697778)
			(xy 255.887472 -234.697778) (xy 255.891543 -234.642156) (xy 255.903669 -234.587719) (xy 255.923592 -234.535628)
			(xy 255.950888 -234.486993) (xy 255.984974 -234.44285) (xy 256.025123 -234.404141) (xy 256.070481 -234.37169)
			(xy 256.120081 -234.346189) (xy 256.172865 -234.328182) (xy 256.227708 -234.318052) (xy 256.283442 -234.316015)
			(xy 256.338879 -234.322115) (xy 256.392836 -234.336221) (xy 256.444165 -234.358033) (xy 256.491771 -234.387087)
			(xy 256.534639 -234.422762) (xy 256.571856 -234.464299) (xy 256.602629 -234.510812) (xy 256.626301 -234.561309)
			(xy 256.642369 -234.614716) (xy 256.650489 -234.669892) (xy 256.650998 -234.697778) (xy 256.650489 -234.725664)
			(xy 256.642369 -234.78084) (xy 256.626301 -234.834247) (xy 256.602629 -234.884744) (xy 256.571856 -234.931257)
			(xy 256.534639 -234.972794) (xy 256.491771 -235.008469) (xy 256.444165 -235.037523) (xy 256.392836 -235.059335)
			(xy 256.338879 -235.073441) (xy 256.283442 -235.079541) (xy 256.227708 -235.077504) (xy 256.172865 -235.067374)
			(xy 256.120081 -235.049367) (xy 256.070481 -235.023866) (xy 256.025123 -234.991415) (xy 255.984974 -234.952706)
			(xy 255.950888 -234.908563) (xy 255.923592 -234.859928) (xy 255.903669 -234.807837) (xy 255.891543 -234.7534)
			(xy 255.887472 -234.697778) (xy 255.639514 -234.697778) (xy 255.639061 -234.722616) (xy 255.630941 -234.777792)
			(xy 255.614873 -234.831199) (xy 255.591201 -234.881696) (xy 255.560428 -234.928209) (xy 255.523211 -234.969746)
			(xy 255.480343 -235.005421) (xy 255.432737 -235.034475) (xy 255.381408 -235.056287) (xy 255.327451 -235.070393)
			(xy 255.272014 -235.076493) (xy 255.21628 -235.074456) (xy 255.161437 -235.064326) (xy 255.108653 -235.046319)
			(xy 255.059053 -235.020818) (xy 255.013695 -234.988367) (xy 254.973546 -234.949658) (xy 254.93946 -234.905515)
			(xy 254.912164 -234.85688) (xy 254.892241 -234.804789) (xy 254.880115 -234.750352) (xy 254.876044 -234.69473)
			(xy 244.348 -234.69473) (xy 244.304058 -234.738672) (xy 244.296659 -234.745515) (xy 244.27806 -234.753239)
			(xy 244.26799 -234.753658) (xy 216.123774 -234.753658) (xy 216.121996 -234.753658) (xy 216.11353 -234.754273)
			(xy 216.0977 -234.760374) (xy 216.091008 -234.765596) (xy 216.091008 -234.76585) (xy 216.084541 -234.771731)
			(xy 216.075706 -234.786798) (xy 216.073736 -234.795314) (xy 216.073736 -234.795568) (xy 216.068343 -234.823073)
			(xy 216.050562 -234.876228) (xy 216.025197 -234.92621) (xy 215.992792 -234.971942) (xy 215.954046 -235.012443)
			(xy 215.909791 -235.046839) (xy 215.860981 -235.07439) (xy 215.808664 -235.094505) (xy 215.753969 -235.106749)
			(xy 215.69807 -235.11086) (xy 215.642171 -235.106749) (xy 215.587476 -235.094505) (xy 215.535159 -235.07439)
			(xy 215.486349 -235.046839) (xy 215.442094 -235.012443) (xy 215.403348 -234.971942) (xy 215.370943 -234.92621)
			(xy 215.345578 -234.876228) (xy 215.327797 -234.823073) (xy 215.322404 -234.795568) (xy 215.322404 -234.795314)
			(xy 215.320432 -234.786798) (xy 215.311602 -234.771727) (xy 215.305132 -234.76585) (xy 215.305132 -234.765596)
			(xy 215.29844 -234.760377) (xy 215.282608 -234.754293) (xy 215.274144 -234.753658) (xy 210.02371 -234.753658)
			(xy 210.015515 -234.753965) (xy 209.999965 -234.759141) (xy 209.99323 -234.763818) (xy 209.987642 -234.768644)
			(xy 209.095848 -235.660438) (xy 209.091022 -235.666026) (xy 209.086357 -235.672768) (xy 209.081181 -235.688313)
			(xy 209.080862 -235.696506) (xy 209.080862 -235.737654) (xy 231.425494 -235.737654) (xy 231.429565 -235.682032)
			(xy 231.441691 -235.627595) (xy 231.461614 -235.575504) (xy 231.48891 -235.526869) (xy 231.522996 -235.482726)
			(xy 231.563145 -235.444017) (xy 231.608503 -235.411566) (xy 231.658103 -235.386065) (xy 231.710887 -235.368058)
			(xy 231.76573 -235.357928) (xy 231.821464 -235.355891) (xy 231.876901 -235.361991) (xy 231.930858 -235.376097)
			(xy 231.982187 -235.397909) (xy 232.029793 -235.426963) (xy 232.072661 -235.462638) (xy 232.109878 -235.504175)
			(xy 232.140651 -235.550688) (xy 232.164323 -235.601185) (xy 232.180391 -235.654592) (xy 232.188511 -235.709768)
			(xy 232.18902 -235.737654) (xy 232.441494 -235.737654) (xy 232.445565 -235.682032) (xy 232.457691 -235.627595)
			(xy 232.477614 -235.575504) (xy 232.50491 -235.526869) (xy 232.538996 -235.482726) (xy 232.579145 -235.444017)
			(xy 232.624503 -235.411566) (xy 232.674103 -235.386065) (xy 232.726887 -235.368058) (xy 232.78173 -235.357928)
			(xy 232.837464 -235.355891) (xy 232.892901 -235.361991) (xy 232.946858 -235.376097) (xy 232.998187 -235.397909)
			(xy 233.045793 -235.426963) (xy 233.088661 -235.462638) (xy 233.125878 -235.504175) (xy 233.156651 -235.550688)
			(xy 233.180323 -235.601185) (xy 233.196391 -235.654592) (xy 233.204511 -235.709768) (xy 233.20502 -235.737654)
			(xy 233.457494 -235.737654) (xy 233.461565 -235.682032) (xy 233.473691 -235.627595) (xy 233.493614 -235.575504)
			(xy 233.52091 -235.526869) (xy 233.554996 -235.482726) (xy 233.595145 -235.444017) (xy 233.640503 -235.411566)
			(xy 233.690103 -235.386065) (xy 233.742887 -235.368058) (xy 233.79773 -235.357928) (xy 233.853464 -235.355891)
			(xy 233.908901 -235.361991) (xy 233.962858 -235.376097) (xy 234.014187 -235.397909) (xy 234.061793 -235.426963)
			(xy 234.104661 -235.462638) (xy 234.141878 -235.504175) (xy 234.172651 -235.550688) (xy 234.196323 -235.601185)
			(xy 234.212391 -235.654592) (xy 234.220511 -235.709768) (xy 234.22102 -235.737654) (xy 234.473494 -235.737654)
			(xy 234.477565 -235.682032) (xy 234.489691 -235.627595) (xy 234.509614 -235.575504) (xy 234.53691 -235.526869)
			(xy 234.570996 -235.482726) (xy 234.611145 -235.444017) (xy 234.656503 -235.411566) (xy 234.706103 -235.386065)
			(xy 234.758887 -235.368058) (xy 234.81373 -235.357928) (xy 234.869464 -235.355891) (xy 234.924901 -235.361991)
			(xy 234.978858 -235.376097) (xy 235.030187 -235.397909) (xy 235.077793 -235.426963) (xy 235.120661 -235.462638)
			(xy 235.157878 -235.504175) (xy 235.188651 -235.550688) (xy 235.212323 -235.601185) (xy 235.228391 -235.654592)
			(xy 235.236511 -235.709768) (xy 235.23702 -235.737654) (xy 235.489494 -235.737654) (xy 235.493565 -235.682032)
			(xy 235.505691 -235.627595) (xy 235.525614 -235.575504) (xy 235.55291 -235.526869) (xy 235.586996 -235.482726)
			(xy 235.627145 -235.444017) (xy 235.672503 -235.411566) (xy 235.722103 -235.386065) (xy 235.774887 -235.368058)
			(xy 235.82973 -235.357928) (xy 235.885464 -235.355891) (xy 235.940901 -235.361991) (xy 235.994858 -235.376097)
			(xy 236.046187 -235.397909) (xy 236.093793 -235.426963) (xy 236.136661 -235.462638) (xy 236.173878 -235.504175)
			(xy 236.204651 -235.550688) (xy 236.228323 -235.601185) (xy 236.244391 -235.654592) (xy 236.252511 -235.709768)
			(xy 236.25302 -235.737654) (xy 236.505494 -235.737654) (xy 236.509565 -235.682032) (xy 236.521691 -235.627595)
			(xy 236.541614 -235.575504) (xy 236.56891 -235.526869) (xy 236.602996 -235.482726) (xy 236.643145 -235.444017)
			(xy 236.688503 -235.411566) (xy 236.738103 -235.386065) (xy 236.790887 -235.368058) (xy 236.84573 -235.357928)
			(xy 236.901464 -235.355891) (xy 236.956901 -235.361991) (xy 237.010858 -235.376097) (xy 237.062187 -235.397909)
			(xy 237.109793 -235.426963) (xy 237.152661 -235.462638) (xy 237.189878 -235.504175) (xy 237.220651 -235.550688)
			(xy 237.244323 -235.601185) (xy 237.260391 -235.654592) (xy 237.268511 -235.709768) (xy 237.26902 -235.737654)
			(xy 237.521494 -235.737654) (xy 237.525565 -235.682032) (xy 237.537691 -235.627595) (xy 237.557614 -235.575504)
			(xy 237.58491 -235.526869) (xy 237.618996 -235.482726) (xy 237.659145 -235.444017) (xy 237.704503 -235.411566)
			(xy 237.754103 -235.386065) (xy 237.806887 -235.368058) (xy 237.86173 -235.357928) (xy 237.917464 -235.355891)
			(xy 237.972901 -235.361991) (xy 238.026858 -235.376097) (xy 238.078187 -235.397909) (xy 238.125793 -235.426963)
			(xy 238.168661 -235.462638) (xy 238.205878 -235.504175) (xy 238.236651 -235.550688) (xy 238.260323 -235.601185)
			(xy 238.276391 -235.654592) (xy 238.284511 -235.709768) (xy 238.28502 -235.737654) (xy 238.50422 -235.737654)
			(xy 238.508291 -235.682032) (xy 238.520417 -235.627595) (xy 238.54034 -235.575504) (xy 238.567636 -235.526869)
			(xy 238.601722 -235.482726) (xy 238.641871 -235.444017) (xy 238.687229 -235.411566) (xy 238.736829 -235.386065)
			(xy 238.789613 -235.368058) (xy 238.844456 -235.357928) (xy 238.90019 -235.355891) (xy 238.955627 -235.361991)
			(xy 239.009584 -235.376097) (xy 239.060913 -235.397909) (xy 239.108519 -235.426963) (xy 239.151387 -235.462638)
			(xy 239.188604 -235.504175) (xy 239.219377 -235.550688) (xy 239.243049 -235.601185) (xy 239.259117 -235.654592)
			(xy 239.267237 -235.709768) (xy 239.267746 -235.737654) (xy 239.553494 -235.737654) (xy 239.557565 -235.682032)
			(xy 239.569691 -235.627595) (xy 239.589614 -235.575504) (xy 239.61691 -235.526869) (xy 239.650996 -235.482726)
			(xy 239.691145 -235.444017) (xy 239.736503 -235.411566) (xy 239.786103 -235.386065) (xy 239.838887 -235.368058)
			(xy 239.89373 -235.357928) (xy 239.949464 -235.355891) (xy 240.004901 -235.361991) (xy 240.058858 -235.376097)
			(xy 240.110187 -235.397909) (xy 240.157793 -235.426963) (xy 240.200661 -235.462638) (xy 240.237878 -235.504175)
			(xy 240.268651 -235.550688) (xy 240.292323 -235.601185) (xy 240.299222 -235.624116) (xy 241.062 -235.624116)
			(xy 241.066071 -235.568494) (xy 241.078197 -235.514057) (xy 241.09812 -235.461966) (xy 241.125416 -235.413331)
			(xy 241.159502 -235.369188) (xy 241.199651 -235.330479) (xy 241.245009 -235.298028) (xy 241.294609 -235.272527)
			(xy 241.347393 -235.25452) (xy 241.402236 -235.24439) (xy 241.45797 -235.242353) (xy 241.513407 -235.248453)
			(xy 241.567364 -235.262559) (xy 241.618693 -235.284371) (xy 241.666299 -235.313425) (xy 241.709167 -235.3491)
			(xy 241.746384 -235.390637) (xy 241.777157 -235.43715) (xy 241.800829 -235.487647) (xy 241.816897 -235.541054)
			(xy 241.825017 -235.59623) (xy 241.825526 -235.624116) (xy 242.078 -235.624116) (xy 242.082071 -235.568494)
			(xy 242.094197 -235.514057) (xy 242.11412 -235.461966) (xy 242.141416 -235.413331) (xy 242.175502 -235.369188)
			(xy 242.215651 -235.330479) (xy 242.261009 -235.298028) (xy 242.310609 -235.272527) (xy 242.363393 -235.25452)
			(xy 242.418236 -235.24439) (xy 242.47397 -235.242353) (xy 242.529407 -235.248453) (xy 242.583364 -235.262559)
			(xy 242.634693 -235.284371) (xy 242.682299 -235.313425) (xy 242.725167 -235.3491) (xy 242.762384 -235.390637)
			(xy 242.793157 -235.43715) (xy 242.816829 -235.487647) (xy 242.832897 -235.541054) (xy 242.841017 -235.59623)
			(xy 242.841526 -235.624116) (xy 242.841029 -235.651353) (xy 243.094971 -235.651353) (xy 243.094971 -235.596847)
			(xy 243.102728 -235.542897) (xy 243.118085 -235.4906) (xy 243.140728 -235.441021) (xy 243.170196 -235.395169)
			(xy 243.20589 -235.353977) (xy 243.247083 -235.318285) (xy 243.292937 -235.288819) (xy 243.342517 -235.266178)
			(xy 243.394815 -235.250825) (xy 243.448765 -235.24307) (xy 243.476018 -235.242608) (xy 243.503622 -235.243135)
			(xy 243.558254 -235.251082) (xy 243.61117 -235.266821) (xy 243.661265 -235.290025) (xy 243.707491 -235.320208)
			(xy 243.748883 -235.356739) (xy 243.767102 -235.377482) (xy 243.774468 -235.386118) (xy 243.78412 -235.39069)
			(xy 243.788353 -235.39254) (xy 243.7973 -235.39484) (xy 243.8019 -235.395262) (xy 243.805964 -235.395516)
			(xy 243.884196 -235.395008) (xy 243.889711 -235.394817) (xy 243.900474 -235.392388) (xy 243.905532 -235.390182)
			(xy 243.905786 -235.390182) (xy 243.91051 -235.38786) (xy 243.91896 -235.381586) (xy 243.92255 -235.377736)
			(xy 243.922804 -235.377228) (xy 243.922804 -235.376974) (xy 243.941049 -235.355937) (xy 243.982537 -235.318797)
			(xy 244.028987 -235.288089) (xy 244.079411 -235.264465) (xy 244.132735 -235.24843) (xy 244.187825 -235.240323)
			(xy 244.215666 -235.239814) (xy 244.243541 -235.240341) (xy 244.298697 -235.248443) (xy 244.352086 -235.264493)
			(xy 244.402566 -235.28815) (xy 244.449062 -235.318908) (xy 244.490581 -235.356111) (xy 244.508782 -235.377228)
			(xy 244.509036 -235.377482) (xy 244.516225 -235.385197) (xy 244.535115 -235.394517) (xy 244.545612 -235.395516)
			(xy 244.620288 -235.399072) (xy 244.631718 -235.39831) (xy 244.639182 -235.396712) (xy 244.652755 -235.389744)
			(xy 244.658388 -235.384594) (xy 244.658642 -235.38434) (xy 244.680218 -235.363778) (xy 244.728559 -235.328919)
			(xy 244.781733 -235.302005) (xy 244.838448 -235.283691) (xy 244.897321 -235.274423) (xy 244.92712 -235.27385)
			(xy 244.954367 -235.274422) (xy 245.008307 -235.282179) (xy 245.060593 -235.297535) (xy 245.110163 -235.320174)
			(xy 245.156005 -235.349638) (xy 245.197189 -235.385326) (xy 245.232874 -235.426511) (xy 245.262335 -235.472355)
			(xy 245.284972 -235.521925) (xy 245.300325 -235.574213) (xy 245.30808 -235.628153) (xy 245.30808 -235.682647)
			(xy 245.300325 -235.736587) (xy 245.284972 -235.788875) (xy 245.262335 -235.838445) (xy 245.232874 -235.884289)
			(xy 245.197189 -235.925474) (xy 245.156005 -235.961162) (xy 245.110163 -235.990626) (xy 245.060593 -236.013265)
			(xy 245.008307 -236.028621) (xy 244.954367 -236.036378) (xy 244.92712 -236.036866) (xy 244.899245 -236.036356)
			(xy 244.844087 -236.028252) (xy 244.790698 -236.012199) (xy 244.740217 -235.988539) (xy 244.693722 -235.957778)
			(xy 244.652204 -235.920571) (xy 244.634004 -235.899452) (xy 244.63375 -235.899198) (xy 244.626554 -235.89149)
			(xy 244.60767 -235.882163) (xy 244.597174 -235.881164) (xy 244.522498 -235.877608) (xy 244.511068 -235.87837)
			(xy 244.503597 -235.879945) (xy 244.490027 -235.886928) (xy 244.484398 -235.892086) (xy 244.484144 -235.89234)
			(xy 244.462571 -235.912906) (xy 244.41423 -235.947764) (xy 244.361054 -235.974678) (xy 244.304339 -235.992991)
			(xy 244.245465 -236.002258) (xy 244.215666 -236.00283) (xy 244.188061 -236.002336) (xy 244.133426 -235.994385)
			(xy 244.080508 -235.978641) (xy 244.030414 -235.955431) (xy 243.984189 -235.925241) (xy 243.942799 -235.888702)
			(xy 243.924582 -235.867956) (xy 243.917216 -235.85932) (xy 243.907564 -235.854748) (xy 243.903334 -235.852891)
			(xy 243.894385 -235.850596) (xy 243.889784 -235.850176) (xy 243.88572 -235.849922) (xy 243.807488 -235.85043)
			(xy 243.801972 -235.850613) (xy 243.79121 -235.853047) (xy 243.786152 -235.855256) (xy 243.785898 -235.855256)
			(xy 243.78118 -235.85759) (xy 243.772726 -235.863855) (xy 243.769134 -235.867702) (xy 243.76888 -235.86821)
			(xy 243.76888 -235.868464) (xy 243.750652 -235.889517) (xy 243.70916 -235.926654) (xy 243.662706 -235.957359)
			(xy 243.612279 -235.980979) (xy 243.558952 -235.997012) (xy 243.50386 -236.005116) (xy 243.476018 -236.005624)
			(xy 243.448765 -236.00513) (xy 243.394815 -235.997375) (xy 243.342517 -235.982022) (xy 243.292937 -235.959381)
			(xy 243.247083 -235.929915) (xy 243.20589 -235.894223) (xy 243.170196 -235.853031) (xy 243.140728 -235.807179)
			(xy 243.118085 -235.7576) (xy 243.102728 -235.705303) (xy 243.094971 -235.651353) (xy 242.841029 -235.651353)
			(xy 242.841017 -235.652002) (xy 242.832897 -235.707178) (xy 242.816829 -235.760585) (xy 242.793157 -235.811082)
			(xy 242.762384 -235.857595) (xy 242.725167 -235.899132) (xy 242.682299 -235.934807) (xy 242.634693 -235.963861)
			(xy 242.583364 -235.985673) (xy 242.529407 -235.999779) (xy 242.47397 -236.005879) (xy 242.418236 -236.003842)
			(xy 242.363393 -235.993712) (xy 242.310609 -235.975705) (xy 242.261009 -235.950204) (xy 242.215651 -235.917753)
			(xy 242.175502 -235.879044) (xy 242.141416 -235.834901) (xy 242.11412 -235.786266) (xy 242.094197 -235.734175)
			(xy 242.082071 -235.679738) (xy 242.078 -235.624116) (xy 241.825526 -235.624116) (xy 241.825017 -235.652002)
			(xy 241.816897 -235.707178) (xy 241.800829 -235.760585) (xy 241.777157 -235.811082) (xy 241.746384 -235.857595)
			(xy 241.709167 -235.899132) (xy 241.666299 -235.934807) (xy 241.618693 -235.963861) (xy 241.567364 -235.985673)
			(xy 241.513407 -235.999779) (xy 241.45797 -236.005879) (xy 241.402236 -236.003842) (xy 241.347393 -235.993712)
			(xy 241.294609 -235.975705) (xy 241.245009 -235.950204) (xy 241.199651 -235.917753) (xy 241.159502 -235.879044)
			(xy 241.125416 -235.834901) (xy 241.09812 -235.786266) (xy 241.078197 -235.734175) (xy 241.066071 -235.679738)
			(xy 241.062 -235.624116) (xy 240.299222 -235.624116) (xy 240.308391 -235.654592) (xy 240.316511 -235.709768)
			(xy 240.31702 -235.737654) (xy 240.316511 -235.76554) (xy 240.308391 -235.820716) (xy 240.292323 -235.874123)
			(xy 240.268651 -235.92462) (xy 240.237878 -235.971133) (xy 240.200661 -236.01267) (xy 240.157793 -236.048345)
			(xy 240.110187 -236.077399) (xy 240.058858 -236.099211) (xy 240.004901 -236.113317) (xy 239.949464 -236.119417)
			(xy 239.89373 -236.11738) (xy 239.838887 -236.10725) (xy 239.786103 -236.089243) (xy 239.736503 -236.063742)
			(xy 239.691145 -236.031291) (xy 239.650996 -235.992582) (xy 239.61691 -235.948439) (xy 239.589614 -235.899804)
			(xy 239.569691 -235.847713) (xy 239.557565 -235.793276) (xy 239.553494 -235.737654) (xy 239.267746 -235.737654)
			(xy 239.267237 -235.76554) (xy 239.259117 -235.820716) (xy 239.243049 -235.874123) (xy 239.219377 -235.92462)
			(xy 239.188604 -235.971133) (xy 239.151387 -236.01267) (xy 239.108519 -236.048345) (xy 239.060913 -236.077399)
			(xy 239.009584 -236.099211) (xy 238.955627 -236.113317) (xy 238.90019 -236.119417) (xy 238.844456 -236.11738)
			(xy 238.789613 -236.10725) (xy 238.736829 -236.089243) (xy 238.687229 -236.063742) (xy 238.641871 -236.031291)
			(xy 238.601722 -235.992582) (xy 238.567636 -235.948439) (xy 238.54034 -235.899804) (xy 238.520417 -235.847713)
			(xy 238.508291 -235.793276) (xy 238.50422 -235.737654) (xy 238.28502 -235.737654) (xy 238.284511 -235.76554)
			(xy 238.276391 -235.820716) (xy 238.260323 -235.874123) (xy 238.236651 -235.92462) (xy 238.205878 -235.971133)
			(xy 238.168661 -236.01267) (xy 238.125793 -236.048345) (xy 238.078187 -236.077399) (xy 238.026858 -236.099211)
			(xy 237.972901 -236.113317) (xy 237.917464 -236.119417) (xy 237.86173 -236.11738) (xy 237.806887 -236.10725)
			(xy 237.754103 -236.089243) (xy 237.704503 -236.063742) (xy 237.659145 -236.031291) (xy 237.618996 -235.992582)
			(xy 237.58491 -235.948439) (xy 237.557614 -235.899804) (xy 237.537691 -235.847713) (xy 237.525565 -235.793276)
			(xy 237.521494 -235.737654) (xy 237.26902 -235.737654) (xy 237.268511 -235.76554) (xy 237.260391 -235.820716)
			(xy 237.244323 -235.874123) (xy 237.220651 -235.92462) (xy 237.189878 -235.971133) (xy 237.152661 -236.01267)
			(xy 237.109793 -236.048345) (xy 237.062187 -236.077399) (xy 237.010858 -236.099211) (xy 236.956901 -236.113317)
			(xy 236.901464 -236.119417) (xy 236.84573 -236.11738) (xy 236.790887 -236.10725) (xy 236.738103 -236.089243)
			(xy 236.688503 -236.063742) (xy 236.643145 -236.031291) (xy 236.602996 -235.992582) (xy 236.56891 -235.948439)
			(xy 236.541614 -235.899804) (xy 236.521691 -235.847713) (xy 236.509565 -235.793276) (xy 236.505494 -235.737654)
			(xy 236.25302 -235.737654) (xy 236.252511 -235.76554) (xy 236.244391 -235.820716) (xy 236.228323 -235.874123)
			(xy 236.204651 -235.92462) (xy 236.173878 -235.971133) (xy 236.136661 -236.01267) (xy 236.093793 -236.048345)
			(xy 236.046187 -236.077399) (xy 235.994858 -236.099211) (xy 235.940901 -236.113317) (xy 235.885464 -236.119417)
			(xy 235.82973 -236.11738) (xy 235.774887 -236.10725) (xy 235.722103 -236.089243) (xy 235.672503 -236.063742)
			(xy 235.627145 -236.031291) (xy 235.586996 -235.992582) (xy 235.55291 -235.948439) (xy 235.525614 -235.899804)
			(xy 235.505691 -235.847713) (xy 235.493565 -235.793276) (xy 235.489494 -235.737654) (xy 235.23702 -235.737654)
			(xy 235.236511 -235.76554) (xy 235.228391 -235.820716) (xy 235.212323 -235.874123) (xy 235.188651 -235.92462)
			(xy 235.157878 -235.971133) (xy 235.120661 -236.01267) (xy 235.077793 -236.048345) (xy 235.030187 -236.077399)
			(xy 234.978858 -236.099211) (xy 234.924901 -236.113317) (xy 234.869464 -236.119417) (xy 234.81373 -236.11738)
			(xy 234.758887 -236.10725) (xy 234.706103 -236.089243) (xy 234.656503 -236.063742) (xy 234.611145 -236.031291)
			(xy 234.570996 -235.992582) (xy 234.53691 -235.948439) (xy 234.509614 -235.899804) (xy 234.489691 -235.847713)
			(xy 234.477565 -235.793276) (xy 234.473494 -235.737654) (xy 234.22102 -235.737654) (xy 234.220511 -235.76554)
			(xy 234.212391 -235.820716) (xy 234.196323 -235.874123) (xy 234.172651 -235.92462) (xy 234.141878 -235.971133)
			(xy 234.104661 -236.01267) (xy 234.061793 -236.048345) (xy 234.014187 -236.077399) (xy 233.962858 -236.099211)
			(xy 233.908901 -236.113317) (xy 233.853464 -236.119417) (xy 233.79773 -236.11738) (xy 233.742887 -236.10725)
			(xy 233.690103 -236.089243) (xy 233.640503 -236.063742) (xy 233.595145 -236.031291) (xy 233.554996 -235.992582)
			(xy 233.52091 -235.948439) (xy 233.493614 -235.899804) (xy 233.473691 -235.847713) (xy 233.461565 -235.793276)
			(xy 233.457494 -235.737654) (xy 233.20502 -235.737654) (xy 233.204511 -235.76554) (xy 233.196391 -235.820716)
			(xy 233.180323 -235.874123) (xy 233.156651 -235.92462) (xy 233.125878 -235.971133) (xy 233.088661 -236.01267)
			(xy 233.045793 -236.048345) (xy 232.998187 -236.077399) (xy 232.946858 -236.099211) (xy 232.892901 -236.113317)
			(xy 232.837464 -236.119417) (xy 232.78173 -236.11738) (xy 232.726887 -236.10725) (xy 232.674103 -236.089243)
			(xy 232.624503 -236.063742) (xy 232.579145 -236.031291) (xy 232.538996 -235.992582) (xy 232.50491 -235.948439)
			(xy 232.477614 -235.899804) (xy 232.457691 -235.847713) (xy 232.445565 -235.793276) (xy 232.441494 -235.737654)
			(xy 232.18902 -235.737654) (xy 232.188511 -235.76554) (xy 232.180391 -235.820716) (xy 232.164323 -235.874123)
			(xy 232.140651 -235.92462) (xy 232.109878 -235.971133) (xy 232.072661 -236.01267) (xy 232.029793 -236.048345)
			(xy 231.982187 -236.077399) (xy 231.930858 -236.099211) (xy 231.876901 -236.113317) (xy 231.821464 -236.119417)
			(xy 231.76573 -236.11738) (xy 231.710887 -236.10725) (xy 231.658103 -236.089243) (xy 231.608503 -236.063742)
			(xy 231.563145 -236.031291) (xy 231.522996 -235.992582) (xy 231.48891 -235.948439) (xy 231.461614 -235.899804)
			(xy 231.441691 -235.847713) (xy 231.429565 -235.793276) (xy 231.425494 -235.737654) (xy 209.080862 -235.737654)
			(xy 209.080862 -237.438557) (xy 216.288515 -237.438557) (xy 216.288515 -237.384043) (xy 216.296273 -237.330085)
			(xy 216.311632 -237.27778) (xy 216.334278 -237.228193) (xy 216.363751 -237.182334) (xy 216.399451 -237.141137)
			(xy 216.44065 -237.105439) (xy 216.486511 -237.075969) (xy 216.536099 -237.053325) (xy 216.588405 -237.037969)
			(xy 216.642363 -237.030214) (xy 216.66962 -237.029752) (xy 216.697861 -237.030262) (xy 216.753727 -237.038579)
			(xy 216.807756 -237.055044) (xy 216.858766 -237.079295) (xy 216.905642 -237.110804) (xy 216.94736 -237.148881)
			(xy 216.983007 -237.192693) (xy 217.011803 -237.241282) (xy 217.022934 -237.267242) (xy 217.027252 -237.27791)
			(xy 217.035888 -237.28553) (xy 217.040082 -237.289151) (xy 217.049698 -237.294651) (xy 217.054938 -237.296452)
			(xy 217.14206 -237.322868) (xy 217.153744 -237.320836) (xy 217.159107 -237.319792) (xy 217.16923 -237.315688)
			(xy 217.17381 -237.312708) (xy 217.174318 -237.312454) (xy 217.198237 -237.296709) (xy 217.249777 -237.271757)
			(xy 217.304467 -237.254789) (xy 217.361079 -237.246187) (xy 217.38971 -237.245652) (xy 217.390218 -237.245652)
			(xy 217.414763 -237.246052) (xy 217.463443 -237.252387) (xy 217.510909 -237.264912) (xy 217.556377 -237.28342)
			(xy 217.577924 -237.295182) (xy 217.583593 -237.298136) (xy 217.595924 -237.301484) (xy 217.602308 -237.301786)
			(xy 217.606169 -237.301795) (xy 217.613822 -237.300769) (xy 217.617548 -237.299754) (xy 217.621104 -237.298484)
			(xy 217.694256 -237.270544) (xy 217.705178 -237.264702) (xy 217.712798 -237.258352) (xy 217.720418 -237.250478)
			(xy 217.723974 -237.23981) (xy 217.732959 -237.215129) (xy 217.756753 -237.168303) (xy 217.786743 -237.125183)
			(xy 217.822363 -237.086583) (xy 217.86294 -237.053232) (xy 217.907707 -237.02576) (xy 217.955818 -237.004688)
			(xy 218.006365 -236.990412) (xy 218.058392 -236.983203) (xy 218.084654 -236.982762) (xy 218.111907 -236.983282)
			(xy 218.165859 -236.991033) (xy 218.218158 -237.006384) (xy 218.26774 -237.029022) (xy 218.313595 -237.058487)
			(xy 218.35479 -237.094177) (xy 218.390486 -237.135368) (xy 218.419956 -237.18122) (xy 218.4426 -237.230799)
			(xy 218.457957 -237.283096) (xy 218.465715 -237.337047) (xy 218.465715 -237.391553) (xy 218.457957 -237.445504)
			(xy 218.4426 -237.497801) (xy 218.419956 -237.54738) (xy 218.390486 -237.593232) (xy 218.35479 -237.634423)
			(xy 218.313595 -237.670113) (xy 218.26774 -237.699578) (xy 218.218158 -237.722216) (xy 218.17596 -237.734602)
			(xy 219.860876 -237.734602) (xy 219.861343 -237.707737) (xy 219.868855 -237.654536) (xy 219.88376 -237.602916)
			(xy 219.905762 -237.553898) (xy 219.934425 -237.508453) (xy 219.969182 -237.467481) (xy 220.009346 -237.431792)
			(xy 220.054121 -237.402093) (xy 220.102621 -237.378972) (xy 220.153886 -237.362887) (xy 220.206901 -237.354155)
			(xy 220.233748 -237.353094) (xy 220.248745 -237.352203) (xy 220.277268 -237.342814) (xy 220.301829 -237.325539)
			(xy 220.320309 -237.301871) (xy 220.331111 -237.273854) (xy 220.333304 -237.243906) (xy 220.330522 -237.229142)
			(xy 220.326124 -237.208467) (xy 220.321419 -237.166458) (xy 220.321124 -237.145322) (xy 220.321124 -237.14456)
			(xy 220.32161 -237.117309) (xy 220.329366 -237.063361) (xy 220.344721 -237.011066) (xy 220.367363 -236.961489)
			(xy 220.396829 -236.915639) (xy 220.43252 -236.874448) (xy 220.473711 -236.838757) (xy 220.519561 -236.809291)
			(xy 220.569138 -236.786649) (xy 220.621433 -236.771294) (xy 220.675381 -236.763538) (xy 220.729883 -236.763538)
			(xy 220.783831 -236.771294) (xy 220.836126 -236.786649) (xy 220.885703 -236.809291) (xy 220.931553 -236.838757)
			(xy 220.972744 -236.874448) (xy 221.008435 -236.915639) (xy 221.037901 -236.961489) (xy 221.060543 -237.011066)
			(xy 221.075898 -237.063361) (xy 221.083654 -237.117309) (xy 221.08414 -237.14456) (xy 221.083715 -237.171426)
			(xy 221.076195 -237.224628) (xy 221.061283 -237.276248) (xy 221.039275 -237.325265) (xy 221.010607 -237.370709)
			(xy 220.975846 -237.41168) (xy 220.954592 -237.430564) (xy 221.137986 -237.430564) (xy 221.142057 -237.374942)
			(xy 221.154183 -237.320505) (xy 221.174106 -237.268414) (xy 221.201402 -237.219779) (xy 221.235488 -237.175636)
			(xy 221.275637 -237.136927) (xy 221.320995 -237.104476) (xy 221.370595 -237.078975) (xy 221.423379 -237.060968)
			(xy 221.478222 -237.050838) (xy 221.533956 -237.048801) (xy 221.589393 -237.054901) (xy 221.64335 -237.069007)
			(xy 221.694679 -237.090819) (xy 221.712816 -237.101888) (xy 223.839784 -237.101888) (xy 223.843855 -237.046266)
			(xy 223.855981 -236.991829) (xy 223.875904 -236.939738) (xy 223.9032 -236.891103) (xy 223.937286 -236.84696)
			(xy 223.977435 -236.808251) (xy 224.022793 -236.7758) (xy 224.072393 -236.750299) (xy 224.125177 -236.732292)
			(xy 224.18002 -236.722162) (xy 224.235754 -236.720125) (xy 224.291191 -236.726225) (xy 224.345148 -236.740331)
			(xy 224.389053 -236.758988) (xy 258.093208 -236.758988) (xy 258.097279 -236.703366) (xy 258.109405 -236.648929)
			(xy 258.129328 -236.596838) (xy 258.156624 -236.548203) (xy 258.19071 -236.50406) (xy 258.230859 -236.465351)
			(xy 258.276217 -236.4329) (xy 258.325817 -236.407399) (xy 258.378601 -236.389392) (xy 258.433444 -236.379262)
			(xy 258.489178 -236.377225) (xy 258.544615 -236.383325) (xy 258.598572 -236.397431) (xy 258.649901 -236.419243)
			(xy 258.697507 -236.448297) (xy 258.740375 -236.483972) (xy 258.777592 -236.525509) (xy 258.808365 -236.572022)
			(xy 258.832037 -236.622519) (xy 258.848105 -236.675926) (xy 258.856225 -236.731102) (xy 258.856734 -236.758988)
			(xy 258.856225 -236.786874) (xy 258.848105 -236.84205) (xy 258.832037 -236.895457) (xy 258.808365 -236.945954)
			(xy 258.777592 -236.992467) (xy 258.740375 -237.034004) (xy 258.697507 -237.069679) (xy 258.649901 -237.098733)
			(xy 258.598572 -237.120545) (xy 258.544615 -237.134651) (xy 258.489178 -237.140751) (xy 258.433444 -237.138714)
			(xy 258.378601 -237.128584) (xy 258.325817 -237.110577) (xy 258.276217 -237.085076) (xy 258.230859 -237.052625)
			(xy 258.19071 -237.013916) (xy 258.156624 -236.969773) (xy 258.129328 -236.921138) (xy 258.109405 -236.869047)
			(xy 258.097279 -236.81461) (xy 258.093208 -236.758988) (xy 224.389053 -236.758988) (xy 224.396477 -236.762143)
			(xy 224.444083 -236.791197) (xy 224.486951 -236.826872) (xy 224.524168 -236.868409) (xy 224.554941 -236.914922)
			(xy 224.578613 -236.965419) (xy 224.594681 -237.018826) (xy 224.602801 -237.074002) (xy 224.60331 -237.101888)
			(xy 224.602801 -237.129774) (xy 224.594681 -237.18495) (xy 224.578613 -237.238357) (xy 224.554941 -237.288854)
			(xy 224.524168 -237.335367) (xy 224.515567 -237.344966) (xy 246.576594 -237.344966) (xy 246.580665 -237.289344)
			(xy 246.592791 -237.234907) (xy 246.612714 -237.182816) (xy 246.64001 -237.134181) (xy 246.674096 -237.090038)
			(xy 246.714245 -237.051329) (xy 246.759603 -237.018878) (xy 246.809203 -236.993377) (xy 246.861987 -236.97537)
			(xy 246.91683 -236.96524) (xy 246.972564 -236.963203) (xy 247.028001 -236.969303) (xy 247.081958 -236.983409)
			(xy 247.133287 -237.005221) (xy 247.180893 -237.034275) (xy 247.223761 -237.06995) (xy 247.260978 -237.111487)
			(xy 247.291751 -237.158) (xy 247.307121 -237.190788) (xy 255.299208 -237.190788) (xy 255.303279 -237.135166)
			(xy 255.315405 -237.080729) (xy 255.335328 -237.028638) (xy 255.362624 -236.980003) (xy 255.39671 -236.93586)
			(xy 255.436859 -236.897151) (xy 255.482217 -236.8647) (xy 255.531817 -236.839199) (xy 255.584601 -236.821192)
			(xy 255.639444 -236.811062) (xy 255.695178 -236.809025) (xy 255.750615 -236.815125) (xy 255.804572 -236.829231)
			(xy 255.855901 -236.851043) (xy 255.903507 -236.880097) (xy 255.946375 -236.915772) (xy 255.983592 -236.957309)
			(xy 256.014365 -237.003822) (xy 256.038037 -237.054319) (xy 256.054105 -237.107726) (xy 256.062225 -237.162902)
			(xy 256.062734 -237.190788) (xy 256.188208 -237.190788) (xy 256.192279 -237.135166) (xy 256.204405 -237.080729)
			(xy 256.224328 -237.028638) (xy 256.251624 -236.980003) (xy 256.28571 -236.93586) (xy 256.325859 -236.897151)
			(xy 256.371217 -236.8647) (xy 256.420817 -236.839199) (xy 256.473601 -236.821192) (xy 256.528444 -236.811062)
			(xy 256.584178 -236.809025) (xy 256.639615 -236.815125) (xy 256.693572 -236.829231) (xy 256.744901 -236.851043)
			(xy 256.792507 -236.880097) (xy 256.835375 -236.915772) (xy 256.872592 -236.957309) (xy 256.903365 -237.003822)
			(xy 256.927037 -237.054319) (xy 256.943105 -237.107726) (xy 256.951225 -237.162902) (xy 256.951734 -237.190788)
			(xy 256.951225 -237.218674) (xy 256.943105 -237.27385) (xy 256.927037 -237.327257) (xy 256.903365 -237.377754)
			(xy 256.872592 -237.424267) (xy 256.835375 -237.465804) (xy 256.792507 -237.501479) (xy 256.744901 -237.530533)
			(xy 256.693572 -237.552345) (xy 256.639615 -237.566451) (xy 256.584178 -237.572551) (xy 256.528444 -237.570514)
			(xy 256.473601 -237.560384) (xy 256.420817 -237.542377) (xy 256.371217 -237.516876) (xy 256.325859 -237.484425)
			(xy 256.28571 -237.445716) (xy 256.251624 -237.401573) (xy 256.224328 -237.352938) (xy 256.204405 -237.300847)
			(xy 256.192279 -237.24641) (xy 256.188208 -237.190788) (xy 256.062734 -237.190788) (xy 256.062225 -237.218674)
			(xy 256.054105 -237.27385) (xy 256.038037 -237.327257) (xy 256.014365 -237.377754) (xy 255.983592 -237.424267)
			(xy 255.946375 -237.465804) (xy 255.903507 -237.501479) (xy 255.855901 -237.530533) (xy 255.804572 -237.552345)
			(xy 255.750615 -237.566451) (xy 255.695178 -237.572551) (xy 255.639444 -237.570514) (xy 255.584601 -237.560384)
			(xy 255.531817 -237.542377) (xy 255.482217 -237.516876) (xy 255.436859 -237.484425) (xy 255.39671 -237.445716)
			(xy 255.362624 -237.401573) (xy 255.335328 -237.352938) (xy 255.315405 -237.300847) (xy 255.303279 -237.24641)
			(xy 255.299208 -237.190788) (xy 247.307121 -237.190788) (xy 247.315423 -237.208497) (xy 247.331491 -237.261904)
			(xy 247.339611 -237.31708) (xy 247.34012 -237.344966) (xy 247.339611 -237.372852) (xy 247.331491 -237.428028)
			(xy 247.315423 -237.481435) (xy 247.291751 -237.531932) (xy 247.260978 -237.578445) (xy 247.223761 -237.619982)
			(xy 247.180893 -237.655657) (xy 247.133287 -237.684711) (xy 247.081958 -237.706523) (xy 247.028001 -237.720629)
			(xy 246.972564 -237.726729) (xy 246.91683 -237.724692) (xy 246.861987 -237.714562) (xy 246.809203 -237.696555)
			(xy 246.759603 -237.671054) (xy 246.714245 -237.638603) (xy 246.674096 -237.599894) (xy 246.64001 -237.555751)
			(xy 246.612714 -237.507116) (xy 246.592791 -237.455025) (xy 246.580665 -237.400588) (xy 246.576594 -237.344966)
			(xy 224.515567 -237.344966) (xy 224.486951 -237.376904) (xy 224.444083 -237.412579) (xy 224.396477 -237.441633)
			(xy 224.345148 -237.463445) (xy 224.291191 -237.477551) (xy 224.235754 -237.483651) (xy 224.18002 -237.481614)
			(xy 224.125177 -237.471484) (xy 224.072393 -237.453477) (xy 224.022793 -237.427976) (xy 223.977435 -237.395525)
			(xy 223.937286 -237.356816) (xy 223.9032 -237.312673) (xy 223.875904 -237.264038) (xy 223.855981 -237.211947)
			(xy 223.843855 -237.15751) (xy 223.839784 -237.101888) (xy 221.712816 -237.101888) (xy 221.742285 -237.119873)
			(xy 221.785153 -237.155548) (xy 221.82237 -237.197085) (xy 221.853143 -237.243598) (xy 221.876815 -237.294095)
			(xy 221.892883 -237.347502) (xy 221.901003 -237.402678) (xy 221.901512 -237.430564) (xy 221.901003 -237.45845)
			(xy 221.892883 -237.513626) (xy 221.876815 -237.567033) (xy 221.853143 -237.61753) (xy 221.82237 -237.664043)
			(xy 221.785153 -237.70558) (xy 221.742285 -237.741255) (xy 221.694679 -237.770309) (xy 221.656173 -237.786672)
			(xy 241.391184 -237.786672) (xy 241.395255 -237.73105) (xy 241.407381 -237.676613) (xy 241.427304 -237.624522)
			(xy 241.4546 -237.575887) (xy 241.488686 -237.531744) (xy 241.528835 -237.493035) (xy 241.574193 -237.460584)
			(xy 241.623793 -237.435083) (xy 241.676577 -237.417076) (xy 241.73142 -237.406946) (xy 241.787154 -237.404909)
			(xy 241.842591 -237.411009) (xy 241.896548 -237.425115) (xy 241.947877 -237.446927) (xy 241.995483 -237.475981)
			(xy 242.038351 -237.511656) (xy 242.075568 -237.553193) (xy 242.106341 -237.599706) (xy 242.130013 -237.650203)
			(xy 242.146081 -237.70361) (xy 242.154201 -237.758786) (xy 242.15471 -237.786672) (xy 242.154201 -237.814558)
			(xy 242.149707 -237.845092) (xy 242.755672 -237.845092) (xy 242.759743 -237.78947) (xy 242.771869 -237.735033)
			(xy 242.791792 -237.682942) (xy 242.819088 -237.634307) (xy 242.853174 -237.590164) (xy 242.893323 -237.551455)
			(xy 242.938681 -237.519004) (xy 242.988281 -237.493503) (xy 243.041065 -237.475496) (xy 243.095908 -237.465366)
			(xy 243.151642 -237.463329) (xy 243.207079 -237.469429) (xy 243.261036 -237.483535) (xy 243.312365 -237.505347)
			(xy 243.359971 -237.534401) (xy 243.402839 -237.570076) (xy 243.440056 -237.611613) (xy 243.470829 -237.658126)
			(xy 243.494501 -237.708623) (xy 243.510569 -237.76203) (xy 243.516476 -237.802166) (xy 244.049548 -237.802166)
			(xy 244.053619 -237.746544) (xy 244.065745 -237.692107) (xy 244.085668 -237.640016) (xy 244.112964 -237.591381)
			(xy 244.14705 -237.547238) (xy 244.187199 -237.508529) (xy 244.232557 -237.476078) (xy 244.282157 -237.450577)
			(xy 244.334941 -237.43257) (xy 244.389784 -237.42244) (xy 244.445518 -237.420403) (xy 244.500955 -237.426503)
			(xy 244.554912 -237.440609) (xy 244.606241 -237.462421) (xy 244.653847 -237.491475) (xy 244.696715 -237.52715)
			(xy 244.733932 -237.568687) (xy 244.764705 -237.6152) (xy 244.788377 -237.665697) (xy 244.804445 -237.719104)
			(xy 244.812565 -237.77428) (xy 244.813074 -237.802166) (xy 244.812565 -237.830052) (xy 244.804445 -237.885228)
			(xy 244.788377 -237.938635) (xy 244.764705 -237.989132) (xy 244.733932 -238.035645) (xy 244.696715 -238.077182)
			(xy 244.653847 -238.112857) (xy 244.606241 -238.141911) (xy 244.554912 -238.163723) (xy 244.500955 -238.177829)
			(xy 244.468056 -238.181449) (xy 245.619788 -238.181449) (xy 245.619788 -238.126951) (xy 245.627544 -238.073006)
			(xy 245.642898 -238.020715) (xy 245.665536 -237.97114) (xy 245.695 -237.925292) (xy 245.730688 -237.884104)
			(xy 245.771874 -237.848413) (xy 245.817721 -237.818947) (xy 245.867294 -237.796305) (xy 245.919585 -237.780949)
			(xy 245.973529 -237.77319) (xy 246.000778 -237.772702) (xy 246.027118 -237.773097) (xy 246.079298 -237.780329)
			(xy 246.129986 -237.794673) (xy 246.178218 -237.815856) (xy 246.223077 -237.843474) (xy 246.263708 -237.877003)
			(xy 246.299339 -237.915804) (xy 246.329292 -237.959139) (xy 246.352996 -238.006183) (xy 246.370001 -238.056042)
			(xy 246.375428 -238.08182) (xy 246.378564 -238.095855) (xy 246.391627 -238.121464) (xy 246.41132 -238.142408)
			(xy 246.436077 -238.157021) (xy 246.46393 -238.164141) (xy 246.492663 -238.163202) (xy 246.519991 -238.154278)
			(xy 246.532146 -238.14659) (xy 246.555962 -238.13105) (xy 246.607238 -238.106461) (xy 246.661598 -238.089763)
			(xy 246.717835 -238.081325) (xy 246.746268 -238.080804) (xy 246.746522 -238.080804) (xy 246.773773 -238.081267)
			(xy 246.82772 -238.089027) (xy 246.880014 -238.104384) (xy 246.92959 -238.127027) (xy 246.975439 -238.156495)
			(xy 247.016628 -238.192188) (xy 247.052318 -238.233379) (xy 247.081783 -238.279229) (xy 247.104424 -238.328807)
			(xy 247.105886 -238.333788) (xy 257.356608 -238.333788) (xy 257.360679 -238.278166) (xy 257.372805 -238.223729)
			(xy 257.392728 -238.171638) (xy 257.420024 -238.123003) (xy 257.45411 -238.07886) (xy 257.494259 -238.040151)
			(xy 257.539617 -238.0077) (xy 257.589217 -237.982199) (xy 257.642001 -237.964192) (xy 257.696844 -237.954062)
			(xy 257.752578 -237.952025) (xy 257.808015 -237.958125) (xy 257.861972 -237.972231) (xy 257.913301 -237.994043)
			(xy 257.960907 -238.023097) (xy 258.003775 -238.058772) (xy 258.040992 -238.100309) (xy 258.071765 -238.146822)
			(xy 258.095437 -238.197319) (xy 258.105928 -238.232188) (xy 258.575808 -238.232188) (xy 258.579879 -238.176566)
			(xy 258.592005 -238.122129) (xy 258.611928 -238.070038) (xy 258.639224 -238.021403) (xy 258.67331 -237.97726)
			(xy 258.713459 -237.938551) (xy 258.758817 -237.9061) (xy 258.808417 -237.880599) (xy 258.861201 -237.862592)
			(xy 258.916044 -237.852462) (xy 258.971778 -237.850425) (xy 259.027215 -237.856525) (xy 259.081172 -237.870631)
			(xy 259.132501 -237.892443) (xy 259.180107 -237.921497) (xy 259.222975 -237.957172) (xy 259.260192 -237.998709)
			(xy 259.290965 -238.045222) (xy 259.314637 -238.095719) (xy 259.330705 -238.149126) (xy 259.338825 -238.204302)
			(xy 259.339334 -238.232188) (xy 259.541008 -238.232188) (xy 259.545079 -238.176566) (xy 259.557205 -238.122129)
			(xy 259.577128 -238.070038) (xy 259.604424 -238.021403) (xy 259.63851 -237.97726) (xy 259.678659 -237.938551)
			(xy 259.724017 -237.9061) (xy 259.773617 -237.880599) (xy 259.826401 -237.862592) (xy 259.881244 -237.852462)
			(xy 259.936978 -237.850425) (xy 259.992415 -237.856525) (xy 260.046372 -237.870631) (xy 260.097701 -237.892443)
			(xy 260.145307 -237.921497) (xy 260.188175 -237.957172) (xy 260.225392 -237.998709) (xy 260.256165 -238.045222)
			(xy 260.279837 -238.095719) (xy 260.295905 -238.149126) (xy 260.304025 -238.204302) (xy 260.304534 -238.232188)
			(xy 260.304025 -238.260074) (xy 260.295905 -238.31525) (xy 260.290328 -238.333788) (xy 260.557008 -238.333788)
			(xy 260.561079 -238.278166) (xy 260.573205 -238.223729) (xy 260.593128 -238.171638) (xy 260.620424 -238.123003)
			(xy 260.65451 -238.07886) (xy 260.694659 -238.040151) (xy 260.740017 -238.0077) (xy 260.789617 -237.982199)
			(xy 260.842401 -237.964192) (xy 260.897244 -237.954062) (xy 260.952978 -237.952025) (xy 261.008415 -237.958125)
			(xy 261.062372 -237.972231) (xy 261.113701 -237.994043) (xy 261.161307 -238.023097) (xy 261.204175 -238.058772)
			(xy 261.241392 -238.100309) (xy 261.272165 -238.146822) (xy 261.295837 -238.197319) (xy 261.311905 -238.250726)
			(xy 261.320025 -238.305902) (xy 261.320534 -238.333788) (xy 261.320025 -238.361674) (xy 261.311905 -238.41685)
			(xy 261.295837 -238.470257) (xy 261.272165 -238.520754) (xy 261.241392 -238.567267) (xy 261.204175 -238.608804)
			(xy 261.161307 -238.644479) (xy 261.113701 -238.673533) (xy 261.062372 -238.695345) (xy 261.008415 -238.709451)
			(xy 260.952978 -238.715551) (xy 260.897244 -238.713514) (xy 260.842401 -238.703384) (xy 260.789617 -238.685377)
			(xy 260.740017 -238.659876) (xy 260.694659 -238.627425) (xy 260.65451 -238.588716) (xy 260.620424 -238.544573)
			(xy 260.593128 -238.495938) (xy 260.573205 -238.443847) (xy 260.561079 -238.38941) (xy 260.557008 -238.333788)
			(xy 260.290328 -238.333788) (xy 260.279837 -238.368657) (xy 260.256165 -238.419154) (xy 260.225392 -238.465667)
			(xy 260.188175 -238.507204) (xy 260.145307 -238.542879) (xy 260.097701 -238.571933) (xy 260.046372 -238.593745)
			(xy 259.992415 -238.607851) (xy 259.936978 -238.613951) (xy 259.881244 -238.611914) (xy 259.826401 -238.601784)
			(xy 259.773617 -238.583777) (xy 259.724017 -238.558276) (xy 259.678659 -238.525825) (xy 259.63851 -238.487116)
			(xy 259.604424 -238.442973) (xy 259.577128 -238.394338) (xy 259.557205 -238.342247) (xy 259.545079 -238.28781)
			(xy 259.541008 -238.232188) (xy 259.339334 -238.232188) (xy 259.338825 -238.260074) (xy 259.330705 -238.31525)
			(xy 259.314637 -238.368657) (xy 259.290965 -238.419154) (xy 259.260192 -238.465667) (xy 259.222975 -238.507204)
			(xy 259.180107 -238.542879) (xy 259.132501 -238.571933) (xy 259.081172 -238.593745) (xy 259.027215 -238.607851)
			(xy 258.971778 -238.613951) (xy 258.916044 -238.611914) (xy 258.861201 -238.601784) (xy 258.808417 -238.583777)
			(xy 258.758817 -238.558276) (xy 258.713459 -238.525825) (xy 258.67331 -238.487116) (xy 258.639224 -238.442973)
			(xy 258.611928 -238.394338) (xy 258.592005 -238.342247) (xy 258.579879 -238.28781) (xy 258.575808 -238.232188)
			(xy 258.105928 -238.232188) (xy 258.111505 -238.250726) (xy 258.119625 -238.305902) (xy 258.120134 -238.333788)
			(xy 258.119625 -238.361674) (xy 258.111505 -238.41685) (xy 258.095437 -238.470257) (xy 258.071765 -238.520754)
			(xy 258.040992 -238.567267) (xy 258.003775 -238.608804) (xy 257.960907 -238.644479) (xy 257.913301 -238.673533)
			(xy 257.861972 -238.695345) (xy 257.808015 -238.709451) (xy 257.752578 -238.715551) (xy 257.696844 -238.713514)
			(xy 257.642001 -238.703384) (xy 257.589217 -238.685377) (xy 257.539617 -238.659876) (xy 257.494259 -238.627425)
			(xy 257.45411 -238.588716) (xy 257.420024 -238.544573) (xy 257.392728 -238.495938) (xy 257.372805 -238.443847)
			(xy 257.360679 -238.38941) (xy 257.356608 -238.333788) (xy 247.105886 -238.333788) (xy 247.119778 -238.381101)
			(xy 247.127534 -238.435049) (xy 247.127534 -238.489551) (xy 247.119778 -238.543499) (xy 247.104424 -238.595793)
			(xy 247.081783 -238.645371) (xy 247.052318 -238.691221) (xy 247.016628 -238.732412) (xy 246.975439 -238.768105)
			(xy 246.92959 -238.797573) (xy 246.880014 -238.820216) (xy 246.82772 -238.835573) (xy 246.773773 -238.843333)
			(xy 246.746522 -238.84382) (xy 246.720183 -238.843408) (xy 246.668005 -238.836176) (xy 246.617318 -238.821833)
			(xy 246.569086 -238.800651) (xy 246.524229 -238.773035) (xy 246.483598 -238.739508) (xy 246.447966 -238.70071)
			(xy 246.418013 -238.657377) (xy 246.394307 -238.610335) (xy 246.3773 -238.560479) (xy 246.371872 -238.534702)
			(xy 246.368725 -238.520669) (xy 246.355666 -238.495058) (xy 246.335976 -238.474113) (xy 246.31122 -238.459498)
			(xy 246.283368 -238.452377) (xy 246.254635 -238.453317) (xy 246.227308 -238.462242) (xy 246.215154 -238.469932)
			(xy 246.191339 -238.485474) (xy 246.140063 -238.510062) (xy 246.085703 -238.52676) (xy 246.029465 -238.535197)
			(xy 246.001032 -238.535718) (xy 246.000778 -238.535718) (xy 245.973529 -238.53521) (xy 245.919585 -238.527451)
			(xy 245.867294 -238.512095) (xy 245.817721 -238.489453) (xy 245.771875 -238.459987) (xy 245.730688 -238.424296)
			(xy 245.695 -238.383108) (xy 245.665536 -238.33726) (xy 245.642898 -238.287685) (xy 245.627544 -238.235394)
			(xy 245.619788 -238.181449) (xy 244.468056 -238.181449) (xy 244.445518 -238.183929) (xy 244.389784 -238.181892)
			(xy 244.334941 -238.171762) (xy 244.282157 -238.153755) (xy 244.232557 -238.128254) (xy 244.187199 -238.095803)
			(xy 244.14705 -238.057094) (xy 244.112964 -238.012951) (xy 244.085668 -237.964316) (xy 244.065745 -237.912225)
			(xy 244.053619 -237.857788) (xy 244.049548 -237.802166) (xy 243.516476 -237.802166) (xy 243.518689 -237.817206)
			(xy 243.519198 -237.845092) (xy 243.518689 -237.872978) (xy 243.510569 -237.928154) (xy 243.494501 -237.981561)
			(xy 243.470829 -238.032058) (xy 243.440056 -238.078571) (xy 243.402839 -238.120108) (xy 243.359971 -238.155783)
			(xy 243.312365 -238.184837) (xy 243.261036 -238.206649) (xy 243.207079 -238.220755) (xy 243.151642 -238.226855)
			(xy 243.095908 -238.224818) (xy 243.041065 -238.214688) (xy 242.988281 -238.196681) (xy 242.938681 -238.17118)
			(xy 242.893323 -238.138729) (xy 242.853174 -238.10002) (xy 242.819088 -238.055877) (xy 242.791792 -238.007242)
			(xy 242.771869 -237.955151) (xy 242.759743 -237.900714) (xy 242.755672 -237.845092) (xy 242.149707 -237.845092)
			(xy 242.146081 -237.869734) (xy 242.130013 -237.923141) (xy 242.106341 -237.973638) (xy 242.075568 -238.020151)
			(xy 242.038351 -238.061688) (xy 241.995483 -238.097363) (xy 241.947877 -238.126417) (xy 241.896548 -238.148229)
			(xy 241.842591 -238.162335) (xy 241.787154 -238.168435) (xy 241.73142 -238.166398) (xy 241.676577 -238.156268)
			(xy 241.623793 -238.138261) (xy 241.574193 -238.11276) (xy 241.528835 -238.080309) (xy 241.488686 -238.0416)
			(xy 241.4546 -237.997457) (xy 241.427304 -237.948822) (xy 241.407381 -237.896731) (xy 241.395255 -237.842294)
			(xy 241.391184 -237.786672) (xy 221.656173 -237.786672) (xy 221.64335 -237.792121) (xy 221.589393 -237.806227)
			(xy 221.533956 -237.812327) (xy 221.478222 -237.81029) (xy 221.423379 -237.80016) (xy 221.370595 -237.782153)
			(xy 221.320995 -237.756652) (xy 221.275637 -237.724201) (xy 221.235488 -237.685492) (xy 221.201402 -237.641349)
			(xy 221.174106 -237.592714) (xy 221.154183 -237.540623) (xy 221.142057 -237.486186) (xy 221.137986 -237.430564)
			(xy 220.954592 -237.430564) (xy 220.935679 -237.447368) (xy 220.890901 -237.477066) (xy 220.842399 -237.500187)
			(xy 220.791133 -237.516273) (xy 220.738116 -237.525006) (xy 220.711268 -237.526068) (xy 220.696271 -237.526936)
			(xy 220.667756 -237.536342) (xy 220.643201 -237.553625) (xy 220.624726 -237.577294) (xy 220.613921 -237.60531)
			(xy 220.611719 -237.635256) (xy 220.614494 -237.65002) (xy 220.618886 -237.670696) (xy 220.623595 -237.712704)
			(xy 220.623892 -237.73384) (xy 220.623892 -237.734602) (xy 220.623406 -237.761853) (xy 220.61565 -237.815801)
			(xy 220.600295 -237.868096) (xy 220.577653 -237.917673) (xy 220.548187 -237.963523) (xy 220.512496 -238.004714)
			(xy 220.471305 -238.040405) (xy 220.425455 -238.069871) (xy 220.375878 -238.092513) (xy 220.323583 -238.107868)
			(xy 220.269635 -238.115624) (xy 220.215133 -238.115624) (xy 220.161185 -238.107868) (xy 220.10889 -238.092513)
			(xy 220.059313 -238.069871) (xy 220.013463 -238.040405) (xy 219.972272 -238.004714) (xy 219.936581 -237.963523)
			(xy 219.907115 -237.917673) (xy 219.884473 -237.868096) (xy 219.869118 -237.815801) (xy 219.861362 -237.761853)
			(xy 219.860876 -237.734602) (xy 218.17596 -237.734602) (xy 218.165859 -237.737567) (xy 218.111907 -237.745318)
			(xy 218.084654 -237.745778) (xy 218.060109 -237.745386) (xy 218.011429 -237.739048) (xy 217.963963 -237.72652)
			(xy 217.918495 -237.708011) (xy 217.896948 -237.696248) (xy 217.891283 -237.693287) (xy 217.878949 -237.689943)
			(xy 217.872564 -237.689644) (xy 217.868703 -237.689654) (xy 217.861051 -237.690668) (xy 217.857324 -237.691676)
			(xy 217.853768 -237.692946) (xy 217.780616 -237.720886) (xy 217.769694 -237.726728) (xy 217.762074 -237.733078)
			(xy 217.754454 -237.740952) (xy 217.750898 -237.75162) (xy 217.741954 -237.776317) (xy 217.718155 -237.823143)
			(xy 217.688159 -237.866263) (xy 217.652533 -237.904863) (xy 217.611951 -237.938212) (xy 217.567179 -237.965681)
			(xy 217.519063 -237.986751) (xy 217.468512 -238.001024) (xy 217.416482 -238.008229) (xy 217.390218 -238.008668)
			(xy 217.361979 -238.008113) (xy 217.306115 -237.999802) (xy 217.252088 -237.983344) (xy 217.201079 -237.959098)
			(xy 217.154202 -237.927596) (xy 217.112484 -237.889526) (xy 217.076835 -237.845719) (xy 217.048036 -237.797135)
			(xy 217.036904 -237.771178) (xy 217.032586 -237.76051) (xy 217.02395 -237.75289) (xy 217.019748 -237.74928)
			(xy 217.010138 -237.743773) (xy 217.0049 -237.741968) (xy 216.917778 -237.715552) (xy 216.906094 -237.717584)
			(xy 216.900733 -237.718637) (xy 216.890609 -237.722735) (xy 216.886028 -237.725712) (xy 216.88552 -237.725966)
			(xy 216.861619 -237.74174) (xy 216.810073 -237.766685) (xy 216.755377 -237.783644) (xy 216.69876 -237.792238)
			(xy 216.670128 -237.792768) (xy 216.66962 -237.792768) (xy 216.642363 -237.792386) (xy 216.588405 -237.784631)
			(xy 216.536099 -237.769275) (xy 216.486511 -237.746631) (xy 216.44065 -237.717161) (xy 216.399451 -237.681463)
			(xy 216.363751 -237.640266) (xy 216.334278 -237.594407) (xy 216.311632 -237.54482) (xy 216.296273 -237.492515)
			(xy 216.288515 -237.438557) (xy 209.080862 -237.438557) (xy 209.080862 -238.24184) (xy 209.081116 -238.246666)
			(xy 209.082514 -238.256688) (xy 209.092083 -238.274499) (xy 209.099658 -238.28121) (xy 209.105246 -238.28502)
			(xy 209.178906 -238.330232) (xy 209.186433 -238.334415) (xy 209.203268 -238.337995) (xy 209.22034 -238.335822)
			(xy 209.228182 -238.332264) (xy 209.228436 -238.332264) (xy 209.255353 -238.319255) (xy 209.312223 -238.300831)
			(xy 209.371267 -238.291479) (xy 209.401156 -238.290862) (xy 209.428413 -238.291322) (xy 209.482373 -238.299074)
			(xy 209.53468 -238.314428) (xy 209.58427 -238.33707) (xy 209.630132 -238.366539) (xy 209.671334 -238.402235)
			(xy 209.707035 -238.443432) (xy 209.736509 -238.489291) (xy 209.759157 -238.538878) (xy 209.774516 -238.591184)
			(xy 209.782275 -238.645143) (xy 209.782275 -238.654082) (xy 210.3407 -238.654082) (xy 210.344771 -238.59846)
			(xy 210.356897 -238.544023) (xy 210.37682 -238.491932) (xy 210.404116 -238.443297) (xy 210.438202 -238.399154)
			(xy 210.478351 -238.360445) (xy 210.523709 -238.327994) (xy 210.573309 -238.302493) (xy 210.626093 -238.284486)
			(xy 210.680936 -238.274356) (xy 210.73667 -238.272319) (xy 210.792107 -238.278419) (xy 210.846064 -238.292525)
			(xy 210.897393 -238.314337) (xy 210.944999 -238.343391) (xy 210.987867 -238.379066) (xy 211.025084 -238.420603)
			(xy 211.055857 -238.467116) (xy 211.079529 -238.517613) (xy 211.095597 -238.57102) (xy 211.103717 -238.626196)
			(xy 211.104226 -238.654082) (xy 211.103746 -238.680353) (xy 211.374444 -238.680353) (xy 211.374444 -238.625847)
			(xy 211.382201 -238.571896) (xy 211.397556 -238.519598) (xy 211.420198 -238.470018) (xy 211.449665 -238.424164)
			(xy 211.485358 -238.382971) (xy 211.52655 -238.347276) (xy 211.572402 -238.317807) (xy 211.621981 -238.295162)
			(xy 211.674279 -238.279804) (xy 211.728229 -238.272045) (xy 211.755482 -238.271558) (xy 211.783662 -238.272089)
			(xy 211.839409 -238.280384) (xy 211.893331 -238.296781) (xy 211.944258 -238.320925) (xy 211.991083 -238.352291)
			(xy 212.012276 -238.370872) (xy 212.019134 -238.377222) (xy 212.028024 -238.380778) (xy 212.032436 -238.382328)
			(xy 212.041637 -238.383994) (xy 212.046312 -238.38408) (xy 212.114892 -238.38408) (xy 212.119568 -238.383995)
			(xy 212.128771 -238.382337) (xy 212.13318 -238.380778) (xy 212.14207 -238.377222) (xy 212.148928 -238.370872)
			(xy 212.170123 -238.352291) (xy 212.21694 -238.320907) (xy 212.267865 -238.296751) (xy 212.32179 -238.280351)
			(xy 212.37754 -238.272062) (xy 212.405722 -238.271558) (xy 212.433884 -238.272086) (xy 212.489596 -238.280364)
			(xy 212.543488 -238.296736) (xy 212.594389 -238.320848) (xy 212.641197 -238.352176) (xy 212.682894 -238.390041)
			(xy 212.701124 -238.411512) (xy 212.708478 -238.419696) (xy 212.728245 -238.429309) (xy 212.739224 -238.430054)
			(xy 212.815424 -238.43234) (xy 212.819077 -238.432412) (xy 212.826344 -238.431646) (xy 212.829902 -238.430816)
			(xy 212.836998 -238.428653) (xy 212.849646 -238.420916) (xy 212.854794 -238.415576) (xy 212.854794 -238.415322)
			(xy 212.872974 -238.396078) (xy 212.913705 -238.362262) (xy 212.958721 -238.334404) (xy 213.007157 -238.313038)
			(xy 213.058082 -238.298576) (xy 213.110518 -238.291295) (xy 213.136988 -238.290862) (xy 213.164239 -238.291384)
			(xy 213.218187 -238.299139) (xy 213.270482 -238.314493) (xy 213.32006 -238.337133) (xy 213.365911 -238.366599)
			(xy 213.407102 -238.402289) (xy 213.442794 -238.443479) (xy 213.472261 -238.489329) (xy 213.494903 -238.538906)
			(xy 213.510258 -238.591201) (xy 213.518015 -238.645149) (xy 213.518015 -238.699651) (xy 213.510258 -238.753599)
			(xy 213.494903 -238.805894) (xy 213.472261 -238.855471) (xy 213.442794 -238.901321) (xy 213.407102 -238.942511)
			(xy 213.365911 -238.978201) (xy 213.32006 -239.007667) (xy 213.270482 -239.030307) (xy 213.218187 -239.045661)
			(xy 213.215801 -239.046004) (xy 222.244156 -239.046004) (xy 222.248227 -238.990382) (xy 222.260353 -238.935945)
			(xy 222.280276 -238.883854) (xy 222.307572 -238.835219) (xy 222.341658 -238.791076) (xy 222.381807 -238.752367)
			(xy 222.427165 -238.719916) (xy 222.476765 -238.694415) (xy 222.529549 -238.676408) (xy 222.584392 -238.666278)
			(xy 222.640126 -238.664241) (xy 222.695563 -238.670341) (xy 222.74952 -238.684447) (xy 222.800849 -238.706259)
			(xy 222.848455 -238.735313) (xy 222.891323 -238.770988) (xy 222.92854 -238.812525) (xy 222.959313 -238.859038)
			(xy 222.982985 -238.909535) (xy 222.999053 -238.962942) (xy 223.007173 -239.018118) (xy 223.007682 -239.046004)
			(xy 226.0252 -239.046004) (xy 226.029271 -238.990382) (xy 226.041397 -238.935945) (xy 226.06132 -238.883854)
			(xy 226.088616 -238.835219) (xy 226.122702 -238.791076) (xy 226.162851 -238.752367) (xy 226.208209 -238.719916)
			(xy 226.257809 -238.694415) (xy 226.310593 -238.676408) (xy 226.365436 -238.666278) (xy 226.42117 -238.664241)
			(xy 226.476607 -238.670341) (xy 226.530564 -238.684447) (xy 226.581893 -238.706259) (xy 226.629499 -238.735313)
			(xy 226.672367 -238.770988) (xy 226.709584 -238.812525) (xy 226.740357 -238.859038) (xy 226.764029 -238.909535)
			(xy 226.780097 -238.962942) (xy 226.783686 -238.98733) (xy 228.467664 -238.98733) (xy 228.471735 -238.931708)
			(xy 228.483861 -238.877271) (xy 228.503784 -238.82518) (xy 228.53108 -238.776545) (xy 228.565166 -238.732402)
			(xy 228.605315 -238.693693) (xy 228.650673 -238.661242) (xy 228.700273 -238.635741) (xy 228.753057 -238.617734)
			(xy 228.8079 -238.607604) (xy 228.863634 -238.605567) (xy 228.919071 -238.611667) (xy 228.973028 -238.625773)
			(xy 229.024357 -238.647585) (xy 229.071963 -238.676639) (xy 229.114831 -238.712314) (xy 229.152048 -238.753851)
			(xy 229.182821 -238.800364) (xy 229.206493 -238.850861) (xy 229.222561 -238.904268) (xy 229.230681 -238.959444)
			(xy 229.23119 -238.98733) (xy 229.230681 -239.015216) (xy 229.222561 -239.070392) (xy 229.206493 -239.123799)
			(xy 229.182821 -239.174296) (xy 229.152048 -239.220809) (xy 229.114831 -239.262346) (xy 229.071963 -239.298021)
			(xy 229.024357 -239.327075) (xy 228.973028 -239.348887) (xy 228.919071 -239.362993) (xy 228.863634 -239.369093)
			(xy 228.8079 -239.367056) (xy 228.753057 -239.356926) (xy 228.700273 -239.338919) (xy 228.650673 -239.313418)
			(xy 228.605315 -239.280967) (xy 228.565166 -239.242258) (xy 228.53108 -239.198115) (xy 228.503784 -239.14948)
			(xy 228.483861 -239.097389) (xy 228.471735 -239.042952) (xy 228.467664 -238.98733) (xy 226.783686 -238.98733)
			(xy 226.788217 -239.018118) (xy 226.788726 -239.046004) (xy 226.788217 -239.07389) (xy 226.780097 -239.129066)
			(xy 226.764029 -239.182473) (xy 226.740357 -239.23297) (xy 226.709584 -239.279483) (xy 226.672367 -239.32102)
			(xy 226.629499 -239.356695) (xy 226.581893 -239.385749) (xy 226.530564 -239.407561) (xy 226.476607 -239.421667)
			(xy 226.42117 -239.427767) (xy 226.365436 -239.42573) (xy 226.310593 -239.4156) (xy 226.257809 -239.397593)
			(xy 226.208209 -239.372092) (xy 226.162851 -239.339641) (xy 226.122702 -239.300932) (xy 226.088616 -239.256789)
			(xy 226.06132 -239.208154) (xy 226.041397 -239.156063) (xy 226.029271 -239.101626) (xy 226.0252 -239.046004)
			(xy 223.007682 -239.046004) (xy 223.007173 -239.07389) (xy 222.999053 -239.129066) (xy 222.982985 -239.182473)
			(xy 222.959313 -239.23297) (xy 222.92854 -239.279483) (xy 222.891323 -239.32102) (xy 222.848455 -239.356695)
			(xy 222.800849 -239.385749) (xy 222.74952 -239.407561) (xy 222.695563 -239.421667) (xy 222.640126 -239.427767)
			(xy 222.584392 -239.42573) (xy 222.529549 -239.4156) (xy 222.476765 -239.397593) (xy 222.427165 -239.372092)
			(xy 222.381807 -239.339641) (xy 222.341658 -239.300932) (xy 222.307572 -239.256789) (xy 222.280276 -239.208154)
			(xy 222.260353 -239.156063) (xy 222.248227 -239.101626) (xy 222.244156 -239.046004) (xy 213.215801 -239.046004)
			(xy 213.164239 -239.053416) (xy 213.136988 -239.053878) (xy 213.108825 -239.053365) (xy 213.053111 -239.045088)
			(xy 212.999218 -239.028714) (xy 212.948316 -239.004599) (xy 212.90151 -238.973267) (xy 212.859815 -238.935397)
			(xy 212.841586 -238.913924) (xy 212.834221 -238.90575) (xy 212.814463 -238.896131) (xy 212.803486 -238.895382)
			(xy 212.727286 -238.893096) (xy 212.723633 -238.893028) (xy 212.716367 -238.893792) (xy 212.712808 -238.89462)
			(xy 212.705707 -238.896768) (xy 212.693063 -238.904517) (xy 212.687916 -238.90986) (xy 212.687916 -238.910114)
			(xy 212.669768 -238.92939) (xy 212.629031 -238.963205) (xy 212.584009 -238.991061) (xy 212.535566 -239.012421)
			(xy 212.484635 -239.026876) (xy 212.432194 -239.034147) (xy 212.405722 -239.034574) (xy 212.377542 -239.034033)
			(xy 212.321797 -239.025739) (xy 212.267875 -239.009344) (xy 212.216948 -238.985202) (xy 212.170122 -238.953839)
			(xy 212.148928 -238.93526) (xy 212.14207 -238.92891) (xy 212.13318 -238.925354) (xy 212.128767 -238.923806)
			(xy 212.119567 -238.922138) (xy 212.114892 -238.922052) (xy 212.046312 -238.922052) (xy 212.041636 -238.922136)
			(xy 212.032433 -238.923795) (xy 212.028024 -238.925354) (xy 212.019134 -238.92891) (xy 212.012276 -238.93526)
			(xy 211.991084 -238.953844) (xy 211.944265 -238.985227) (xy 211.89334 -239.009381) (xy 211.839415 -239.025781)
			(xy 211.783664 -239.03407) (xy 211.755482 -239.034574) (xy 211.728229 -239.034155) (xy 211.674279 -239.026396)
			(xy 211.621981 -239.011038) (xy 211.572402 -238.988393) (xy 211.52655 -238.958924) (xy 211.485358 -238.923229)
			(xy 211.449665 -238.882036) (xy 211.420198 -238.836182) (xy 211.397556 -238.786602) (xy 211.382201 -238.734304)
			(xy 211.374444 -238.680353) (xy 211.103746 -238.680353) (xy 211.103717 -238.681968) (xy 211.095597 -238.737144)
			(xy 211.079529 -238.790551) (xy 211.055857 -238.841048) (xy 211.025084 -238.887561) (xy 210.987867 -238.929098)
			(xy 210.944999 -238.964773) (xy 210.897393 -238.993827) (xy 210.846064 -239.015639) (xy 210.792107 -239.029745)
			(xy 210.73667 -239.035845) (xy 210.680936 -239.033808) (xy 210.626093 -239.023678) (xy 210.573309 -239.005671)
			(xy 210.523709 -238.98017) (xy 210.478351 -238.947719) (xy 210.438202 -238.90901) (xy 210.404116 -238.864867)
			(xy 210.37682 -238.816232) (xy 210.356897 -238.764141) (xy 210.344771 -238.709704) (xy 210.3407 -238.654082)
			(xy 209.782275 -238.654082) (xy 209.782275 -238.699657) (xy 209.774516 -238.753616) (xy 209.759157 -238.805922)
			(xy 209.736509 -238.855509) (xy 209.707035 -238.901368) (xy 209.671334 -238.942565) (xy 209.630132 -238.978261)
			(xy 209.58427 -239.00773) (xy 209.53468 -239.030372) (xy 209.482373 -239.045726) (xy 209.428413 -239.053478)
			(xy 209.401156 -239.053878) (xy 209.371305 -239.053284) (xy 209.31234 -239.043937) (xy 209.255558 -239.025495)
			(xy 209.22869 -239.012476) (xy 209.228182 -239.012476) (xy 209.220342 -239.008908) (xy 209.203269 -239.006716)
			(xy 209.186437 -239.010325) (xy 209.178906 -239.014508) (xy 209.105246 -239.05972) (xy 209.099658 -239.06353)
			(xy 209.092093 -239.070248) (xy 209.082528 -239.088057) (xy 209.081116 -239.098074) (xy 209.080862 -239.1029)
			(xy 209.080862 -240.034151) (xy 231.103164 -240.034151) (xy 231.103164 -239.979649) (xy 231.11092 -239.925702)
			(xy 231.126274 -239.873408) (xy 231.148914 -239.823831) (xy 231.178378 -239.77798) (xy 231.214068 -239.736789)
			(xy 231.255256 -239.701096) (xy 231.301104 -239.671628) (xy 231.35068 -239.648984) (xy 231.402973 -239.633626)
			(xy 231.456919 -239.625866) (xy 231.48417 -239.625378) (xy 231.511347 -239.625861) (xy 231.565148 -239.633589)
			(xy 231.617307 -239.648878) (xy 231.666767 -239.671419) (xy 231.712525 -239.700754) (xy 231.753653 -239.736289)
			(xy 231.789319 -239.777305) (xy 231.804464 -239.799876) (xy 231.804718 -239.80013) (xy 231.811049 -239.80885)
			(xy 231.829191 -239.820437) (xy 231.83977 -239.822482) (xy 231.915716 -239.833404) (xy 231.920029 -239.833934)
			(xy 231.928714 -239.833679) (xy 231.932988 -239.832896) (xy 231.937052 -239.83188) (xy 231.94772 -239.828832)
			(xy 231.955848 -239.82172) (xy 231.956356 -239.82172) (xy 231.977208 -239.804392) (xy 232.022876 -239.775174)
			(xy 232.072223 -239.752718) (xy 232.124252 -239.737478) (xy 232.177915 -239.72976) (xy 232.205022 -239.729264)
			(xy 232.23227 -239.729808) (xy 232.286212 -239.737566) (xy 232.3385 -239.752922) (xy 232.38807 -239.775563)
			(xy 232.433915 -239.805027) (xy 232.475099 -239.840716) (xy 232.510786 -239.881903) (xy 232.540248 -239.927749)
			(xy 232.562886 -239.977321) (xy 232.578238 -240.02961) (xy 232.585994 -240.083552) (xy 232.585994 -240.138048)
			(xy 232.578238 -240.19199) (xy 232.562886 -240.244279) (xy 232.540248 -240.293851) (xy 232.510786 -240.339697)
			(xy 232.475099 -240.380884) (xy 232.433915 -240.416573) (xy 232.38807 -240.446037) (xy 232.3385 -240.468678)
			(xy 232.286212 -240.484034) (xy 232.23227 -240.491792) (xy 232.205022 -240.49228) (xy 232.177844 -240.491822)
			(xy 232.124041 -240.484092) (xy 232.07188 -240.4688) (xy 232.02242 -240.446256) (xy 231.976662 -240.416916)
			(xy 231.935535 -240.381376) (xy 231.899871 -240.340355) (xy 231.884728 -240.317782) (xy 231.884474 -240.317528)
			(xy 231.878156 -240.308797) (xy 231.860004 -240.297218) (xy 231.849422 -240.295176) (xy 231.773476 -240.284254)
			(xy 231.769163 -240.283721) (xy 231.760478 -240.283978) (xy 231.756204 -240.284762) (xy 231.75214 -240.285778)
			(xy 231.741472 -240.288826) (xy 231.733344 -240.295938) (xy 231.732836 -240.295938) (xy 231.711994 -240.313278)
			(xy 231.666322 -240.342493) (xy 231.616973 -240.364945) (xy 231.564942 -240.380183) (xy 231.511278 -240.387898)
			(xy 231.48417 -240.388394) (xy 231.456919 -240.387934) (xy 231.402973 -240.380174) (xy 231.35068 -240.364816)
			(xy 231.301104 -240.342172) (xy 231.255256 -240.312704) (xy 231.214068 -240.277011) (xy 231.178378 -240.23582)
			(xy 231.148914 -240.189969) (xy 231.126274 -240.140392) (xy 231.11092 -240.088098) (xy 231.103164 -240.034151)
			(xy 209.080862 -240.034151) (xy 209.080862 -241.128296) (xy 209.979004 -241.128296) (xy 209.983075 -241.072674)
			(xy 209.995201 -241.018237) (xy 210.015124 -240.966146) (xy 210.04242 -240.917511) (xy 210.076506 -240.873368)
			(xy 210.116655 -240.834659) (xy 210.162013 -240.802208) (xy 210.211613 -240.776707) (xy 210.264397 -240.7587)
			(xy 210.31924 -240.74857) (xy 210.374974 -240.746533) (xy 210.430411 -240.752633) (xy 210.484368 -240.766739)
			(xy 210.535697 -240.788551) (xy 210.583303 -240.817605) (xy 210.626171 -240.85328) (xy 210.663388 -240.894817)
			(xy 210.694161 -240.94133) (xy 210.717833 -240.991827) (xy 210.733901 -241.045234) (xy 210.741954 -241.099953)
			(xy 211.374448 -241.099953) (xy 211.374448 -241.045447) (xy 211.382204 -240.991497) (xy 211.39756 -240.9392)
			(xy 211.420201 -240.88962) (xy 211.449668 -240.843767) (xy 211.485361 -240.802574) (xy 211.526552 -240.766879)
			(xy 211.572404 -240.73741) (xy 211.621983 -240.714766) (xy 211.674279 -240.699408) (xy 211.728229 -240.691649)
			(xy 211.755482 -240.691162) (xy 211.783662 -240.691692) (xy 211.839409 -240.699987) (xy 211.893331 -240.716384)
			(xy 211.944258 -240.740529) (xy 211.991083 -240.771895) (xy 212.012276 -240.790476) (xy 212.019134 -240.796826)
			(xy 212.028024 -240.800382) (xy 212.032436 -240.801932) (xy 212.041637 -240.803598) (xy 212.046312 -240.803684)
			(xy 212.114892 -240.803684) (xy 212.119568 -240.803599) (xy 212.128771 -240.801941) (xy 212.13318 -240.800382)
			(xy 212.14207 -240.796826) (xy 212.148928 -240.790476) (xy 212.170123 -240.771895) (xy 212.21694 -240.740511)
			(xy 212.267865 -240.716356) (xy 212.32179 -240.699955) (xy 212.37754 -240.691666) (xy 212.405722 -240.691162)
			(xy 212.43297 -240.69171) (xy 212.486911 -240.699468) (xy 212.539199 -240.714824) (xy 212.58877 -240.737465)
			(xy 212.634614 -240.766929) (xy 212.675798 -240.802618) (xy 212.711484 -240.843804) (xy 212.740946 -240.88965)
			(xy 212.763584 -240.939222) (xy 212.778937 -240.99151) (xy 212.786692 -241.045452) (xy 212.786692 -241.083084)
			(xy 213.703406 -241.083084) (xy 213.707477 -241.027462) (xy 213.719603 -240.973025) (xy 213.739526 -240.920934)
			(xy 213.766822 -240.872299) (xy 213.800908 -240.828156) (xy 213.841057 -240.789447) (xy 213.886415 -240.756996)
			(xy 213.936015 -240.731495) (xy 213.988799 -240.713488) (xy 214.043642 -240.703358) (xy 214.099376 -240.701321)
			(xy 214.154813 -240.707421) (xy 214.20877 -240.721527) (xy 214.260099 -240.743339) (xy 214.307705 -240.772393)
			(xy 214.350573 -240.808068) (xy 214.38779 -240.849605) (xy 214.418563 -240.896118) (xy 214.442235 -240.946615)
			(xy 214.458303 -241.000022) (xy 214.466423 -241.055198) (xy 214.466932 -241.083084) (xy 214.466423 -241.11097)
			(xy 214.458303 -241.166146) (xy 214.457819 -241.167756) (xy 219.887443 -241.167756) (xy 219.887443 -241.113244)
			(xy 219.895201 -241.059287) (xy 219.91056 -241.006984) (xy 219.933207 -240.957399) (xy 219.96268 -240.911543)
			(xy 219.99838 -240.870347) (xy 220.039579 -240.834653) (xy 220.08544 -240.805185) (xy 220.135027 -240.782544)
			(xy 220.187332 -240.767192) (xy 220.24129 -240.75944) (xy 220.268546 -240.75898) (xy 220.297705 -240.759516)
			(xy 220.355343 -240.768385) (xy 220.410961 -240.785924) (xy 220.46326 -240.811725) (xy 220.511022 -240.845186)
			(xy 220.553134 -240.885528) (xy 220.571314 -240.908332) (xy 220.581175 -240.920286) (xy 220.606522 -240.93809)
			(xy 220.636034 -240.947496) (xy 220.667008 -240.947643) (xy 220.696607 -240.938517) (xy 220.722121 -240.920954)
			(xy 220.732096 -240.909094) (xy 220.750288 -240.886611) (xy 220.792308 -240.846876) (xy 220.839842 -240.813937)
			(xy 220.891803 -240.788549) (xy 220.947001 -240.771292) (xy 221.00417 -240.762563) (xy 221.033086 -240.762028)
			(xy 221.060342 -240.762418) (xy 221.1143 -240.770174) (xy 221.166604 -240.78553) (xy 221.216191 -240.808174)
			(xy 221.26205 -240.837645) (xy 221.303248 -240.873342) (xy 221.338947 -240.914539) (xy 221.368419 -240.960397)
			(xy 221.391065 -241.009983) (xy 221.396371 -241.028055) (xy 254.817543 -241.028055) (xy 254.817543 -240.973545)
			(xy 254.825301 -240.91959) (xy 254.840659 -240.867288) (xy 254.863304 -240.817705) (xy 254.892775 -240.771849)
			(xy 254.928473 -240.730654) (xy 254.96967 -240.69496) (xy 255.015528 -240.665491) (xy 255.065113 -240.64285)
			(xy 255.117416 -240.627495) (xy 255.171371 -240.619741) (xy 255.198626 -240.61928) (xy 255.22587 -240.619763)
			(xy 255.279802 -240.627523) (xy 255.33208 -240.64288) (xy 255.38164 -240.665523) (xy 255.427473 -240.694989)
			(xy 255.468644 -240.73068) (xy 255.504315 -240.771867) (xy 255.519428 -240.79454) (xy 255.525951 -240.803574)
			(xy 255.544783 -240.815434) (xy 255.55575 -240.8174) (xy 255.556258 -240.8174) (xy 255.5621 -240.817908)
			(xy 255.647952 -240.817908) (xy 255.653794 -240.8174) (xy 255.654302 -240.8174) (xy 255.665285 -240.815477)
			(xy 255.684131 -240.803606) (xy 255.690624 -240.79454) (xy 255.705721 -240.771855) (xy 255.741391 -240.730661)
			(xy 255.782563 -240.694966) (xy 255.828397 -240.665496) (xy 255.877961 -240.642852) (xy 255.930244 -240.627497)
			(xy 255.98418 -240.619742) (xy 256.011426 -240.61928) (xy 256.037403 -240.61969) (xy 256.088876 -240.626737)
			(xy 256.138914 -240.64071) (xy 256.186591 -240.661351) (xy 256.231022 -240.688277) (xy 256.271384 -240.720988)
			(xy 256.306929 -240.758879) (xy 256.322322 -240.779808) (xy 256.3241 -240.78184) (xy 256.3241 -240.782348)
			(xy 256.328984 -240.787951) (xy 256.341235 -240.79635) (xy 256.34823 -240.798858) (xy 256.352003 -240.799975)
			(xy 256.359789 -240.801119) (xy 256.363724 -240.801144) (xy 256.446528 -240.801144) (xy 256.450461 -240.801086)
			(xy 256.458241 -240.799941) (xy 256.462022 -240.798858) (xy 256.469021 -240.796352) (xy 256.481285 -240.787966)
			(xy 256.486152 -240.782348) (xy 256.486152 -240.78184) (xy 256.48793 -240.779808) (xy 256.503344 -240.758898)
			(xy 256.538896 -240.721023) (xy 256.57926 -240.688323) (xy 256.623687 -240.661404) (xy 256.671358 -240.640764)
			(xy 256.721388 -240.626784) (xy 256.772853 -240.619724) (xy 256.798826 -240.61928) (xy 256.826075 -240.619792)
			(xy 256.880018 -240.627551) (xy 256.932308 -240.642908) (xy 256.981881 -240.66555) (xy 257.027726 -240.695016)
			(xy 257.068912 -240.730706) (xy 257.1046 -240.771895) (xy 257.134062 -240.817742) (xy 257.156701 -240.867316)
			(xy 257.172054 -240.919607) (xy 257.17981 -240.973551) (xy 257.17981 -241.028049) (xy 257.172054 -241.081993)
			(xy 257.156701 -241.134284) (xy 257.134062 -241.183858) (xy 257.1046 -241.229705) (xy 257.068912 -241.270894)
			(xy 257.058187 -241.280188) (xy 261.547608 -241.280188) (xy 261.551679 -241.224566) (xy 261.563805 -241.170129)
			(xy 261.583728 -241.118038) (xy 261.611024 -241.069403) (xy 261.64511 -241.02526) (xy 261.685259 -240.986551)
			(xy 261.730617 -240.9541) (xy 261.780217 -240.928599) (xy 261.833001 -240.910592) (xy 261.887844 -240.900462)
			(xy 261.943578 -240.898425) (xy 261.999015 -240.904525) (xy 262.052972 -240.918631) (xy 262.104301 -240.940443)
			(xy 262.151907 -240.969497) (xy 262.194775 -241.005172) (xy 262.231992 -241.046709) (xy 262.262765 -241.093222)
			(xy 262.286437 -241.143719) (xy 262.302505 -241.197126) (xy 262.310625 -241.252302) (xy 262.311134 -241.280188)
			(xy 262.310625 -241.308074) (xy 262.302505 -241.36325) (xy 262.286437 -241.416657) (xy 262.262765 -241.467154)
			(xy 262.231992 -241.513667) (xy 262.194775 -241.555204) (xy 262.151907 -241.590879) (xy 262.104301 -241.619933)
			(xy 262.052972 -241.641745) (xy 261.999015 -241.655851) (xy 261.943578 -241.661951) (xy 261.887844 -241.659914)
			(xy 261.833001 -241.649784) (xy 261.780217 -241.631777) (xy 261.730617 -241.606276) (xy 261.685259 -241.573825)
			(xy 261.64511 -241.535116) (xy 261.611024 -241.490973) (xy 261.583728 -241.442338) (xy 261.563805 -241.390247)
			(xy 261.551679 -241.33581) (xy 261.547608 -241.280188) (xy 257.058187 -241.280188) (xy 257.027726 -241.306584)
			(xy 256.981881 -241.33605) (xy 256.932308 -241.358692) (xy 256.880018 -241.374049) (xy 256.826075 -241.381808)
			(xy 256.798826 -241.382296) (xy 256.772852 -241.381815) (xy 256.721383 -241.374777) (xy 256.671348 -241.360813)
			(xy 256.623672 -241.340183) (xy 256.57924 -241.313269) (xy 256.538876 -241.28057) (xy 256.503326 -241.242691)
			(xy 256.48793 -241.221768) (xy 256.486152 -241.219736) (xy 256.486152 -241.219228) (xy 256.481285 -241.213609)
			(xy 256.469022 -241.20522) (xy 256.462022 -241.202718) (xy 256.458246 -241.201612) (xy 256.450463 -241.200461)
			(xy 256.446528 -241.200432) (xy 256.363724 -241.200432) (xy 256.359791 -241.20048) (xy 256.35201 -241.201632)
			(xy 256.34823 -241.202718) (xy 256.341228 -241.205214) (xy 256.328965 -241.213607) (xy 256.3241 -241.219228)
			(xy 256.3241 -241.219736) (xy 256.322322 -241.221768) (xy 256.30693 -241.242695) (xy 256.271375 -241.280571)
			(xy 256.231008 -241.31327) (xy 256.186577 -241.340188) (xy 256.138903 -241.360825) (xy 256.088869 -241.3748)
			(xy 256.037401 -241.381855) (xy 256.011426 -241.382296) (xy 255.984181 -241.381861) (xy 255.930246 -241.374094)
			(xy 255.877966 -241.358729) (xy 255.828405 -241.336079) (xy 255.782574 -241.306605) (xy 255.741404 -241.270907)
			(xy 255.705735 -241.229712) (xy 255.690624 -241.207036) (xy 255.684127 -241.19798) (xy 255.665276 -241.186132)
			(xy 255.654302 -241.184176) (xy 255.653794 -241.184176) (xy 255.647952 -241.183668) (xy 255.5621 -241.183668)
			(xy 255.556258 -241.184176) (xy 255.55575 -241.184176) (xy 255.544763 -241.186084) (xy 255.52592 -241.197967)
			(xy 255.519428 -241.207036) (xy 255.504289 -241.229691) (xy 255.468627 -241.270887) (xy 255.427463 -241.306585)
			(xy 255.381635 -241.336059) (xy 255.332078 -241.358707) (xy 255.279801 -241.374069) (xy 255.22587 -241.381831)
			(xy 255.198626 -241.382296) (xy 255.171371 -241.381859) (xy 255.117416 -241.374105) (xy 255.065113 -241.35875)
			(xy 255.015528 -241.336109) (xy 254.96967 -241.30664) (xy 254.928473 -241.270946) (xy 254.892775 -241.229751)
			(xy 254.863304 -241.183895) (xy 254.840659 -241.134312) (xy 254.825301 -241.08201) (xy 254.817543 -241.028055)
			(xy 221.396371 -241.028055) (xy 221.406423 -241.062287) (xy 221.414181 -241.116244) (xy 221.414181 -241.170756)
			(xy 221.406423 -241.224713) (xy 221.391065 -241.277017) (xy 221.368419 -241.326603) (xy 221.338947 -241.372461)
			(xy 221.303248 -241.413658) (xy 221.26205 -241.449355) (xy 221.216191 -241.478826) (xy 221.166604 -241.50147)
			(xy 221.1143 -241.516826) (xy 221.060342 -241.524582) (xy 221.033086 -241.525044) (xy 221.003929 -241.524476)
			(xy 220.946292 -241.515612) (xy 220.890676 -241.498079) (xy 220.838377 -241.472284) (xy 220.790613 -241.438829)
			(xy 220.748499 -241.398493) (xy 220.730318 -241.375692) (xy 220.720422 -241.363768) (xy 220.695086 -241.345959)
			(xy 220.665583 -241.336548) (xy 220.634615 -241.336395) (xy 220.60502 -241.345515) (xy 220.579509 -241.363073)
			(xy 220.569536 -241.37493) (xy 220.551332 -241.397402) (xy 220.509314 -241.437137) (xy 220.461782 -241.470076)
			(xy 220.409823 -241.495466) (xy 220.354628 -241.512726) (xy 220.297461 -241.521459) (xy 220.268546 -241.521996)
			(xy 220.24129 -241.52156) (xy 220.187332 -241.513808) (xy 220.135027 -241.498456) (xy 220.08544 -241.475815)
			(xy 220.039579 -241.446347) (xy 219.99838 -241.410653) (xy 219.96268 -241.369457) (xy 219.933207 -241.323601)
			(xy 219.91056 -241.274016) (xy 219.895201 -241.221713) (xy 219.887443 -241.167756) (xy 214.457819 -241.167756)
			(xy 214.442235 -241.219553) (xy 214.418563 -241.27005) (xy 214.38779 -241.316563) (xy 214.350573 -241.3581)
			(xy 214.307705 -241.393775) (xy 214.260099 -241.422829) (xy 214.20877 -241.444641) (xy 214.154813 -241.458747)
			(xy 214.099376 -241.464847) (xy 214.043642 -241.46281) (xy 213.988799 -241.45268) (xy 213.936015 -241.434673)
			(xy 213.886415 -241.409172) (xy 213.841057 -241.376721) (xy 213.800908 -241.338012) (xy 213.766822 -241.293869)
			(xy 213.739526 -241.245234) (xy 213.719603 -241.193143) (xy 213.707477 -241.138706) (xy 213.703406 -241.083084)
			(xy 212.786692 -241.083084) (xy 212.786692 -241.099948) (xy 212.778937 -241.15389) (xy 212.763584 -241.206178)
			(xy 212.740946 -241.25575) (xy 212.711484 -241.301596) (xy 212.675798 -241.342782) (xy 212.634614 -241.378471)
			(xy 212.58877 -241.407935) (xy 212.539199 -241.430576) (xy 212.486911 -241.445932) (xy 212.43297 -241.45369)
			(xy 212.405722 -241.454178) (xy 212.377543 -241.453635) (xy 212.321797 -241.445342) (xy 212.267875 -241.428947)
			(xy 212.216948 -241.404806) (xy 212.170122 -241.373443) (xy 212.148928 -241.354864) (xy 212.14207 -241.348514)
			(xy 212.13318 -241.344958) (xy 212.128767 -241.34341) (xy 212.119567 -241.341742) (xy 212.114892 -241.341656)
			(xy 212.046312 -241.341656) (xy 212.041636 -241.34174) (xy 212.032433 -241.343399) (xy 212.028024 -241.344958)
			(xy 212.019134 -241.348514) (xy 212.012276 -241.354864) (xy 211.991085 -241.373449) (xy 211.944266 -241.404832)
			(xy 211.89334 -241.428985) (xy 211.839415 -241.445385) (xy 211.783664 -241.453674) (xy 211.755482 -241.454178)
			(xy 211.728229 -241.453751) (xy 211.674279 -241.445992) (xy 211.621983 -241.430634) (xy 211.572404 -241.40799)
			(xy 211.526552 -241.378521) (xy 211.485361 -241.342826) (xy 211.449668 -241.301633) (xy 211.420201 -241.25578)
			(xy 211.39756 -241.2062) (xy 211.382204 -241.153903) (xy 211.374448 -241.099953) (xy 210.741954 -241.099953)
			(xy 210.742021 -241.10041) (xy 210.74253 -241.128296) (xy 210.742021 -241.156182) (xy 210.733901 -241.211358)
			(xy 210.717833 -241.264765) (xy 210.694161 -241.315262) (xy 210.663388 -241.361775) (xy 210.626171 -241.403312)
			(xy 210.583303 -241.438987) (xy 210.535697 -241.468041) (xy 210.484368 -241.489853) (xy 210.430411 -241.503959)
			(xy 210.374974 -241.510059) (xy 210.31924 -241.508022) (xy 210.264397 -241.497892) (xy 210.211613 -241.479885)
			(xy 210.162013 -241.454384) (xy 210.116655 -241.421933) (xy 210.076506 -241.383224) (xy 210.04242 -241.339081)
			(xy 210.015124 -241.290446) (xy 209.995201 -241.238355) (xy 209.983075 -241.183918) (xy 209.979004 -241.128296)
			(xy 209.080862 -241.128296) (xy 209.080862 -241.601851) (xy 215.287352 -241.601851) (xy 215.287352 -241.547349)
			(xy 215.295107 -241.493402) (xy 215.310461 -241.441107) (xy 215.3331 -241.39153) (xy 215.362564 -241.345679)
			(xy 215.398253 -241.304487) (xy 215.43944 -241.268793) (xy 215.485288 -241.239323) (xy 215.534862 -241.216678)
			(xy 215.587155 -241.201318) (xy 215.641101 -241.193555) (xy 215.668352 -241.193066) (xy 215.694016 -241.193504)
			(xy 215.744881 -241.200373) (xy 215.794364 -241.214007) (xy 215.841569 -241.234159) (xy 215.885642 -241.260465)
			(xy 215.925786 -241.292448) (xy 215.961275 -241.32953) (xy 215.976708 -241.350038) (xy 215.983058 -241.358928)
			(xy 215.99271 -241.364262) (xy 215.997403 -241.366735) (xy 216.007514 -241.369941) (xy 216.012776 -241.370612)
			(xy 216.088468 -241.377978) (xy 216.09685 -241.377978) (xy 216.105586 -241.377014) (xy 216.12169 -241.370002)
			(xy 216.128346 -241.364262) (xy 216.149674 -241.345046) (xy 216.197003 -241.31256) (xy 216.248664 -241.28753)
			(xy 216.303491 -241.27052) (xy 216.360247 -241.261914) (xy 216.38895 -241.261392) (xy 216.416205 -241.261852)
			(xy 216.470162 -241.269603) (xy 216.522465 -241.284955) (xy 216.572052 -241.307594) (xy 216.617911 -241.337061)
			(xy 216.65911 -241.372755) (xy 216.694809 -241.413949) (xy 216.724282 -241.459804) (xy 216.746928 -241.509388)
			(xy 216.762286 -241.56169) (xy 216.770045 -241.615645) (xy 216.770045 -241.670155) (xy 216.769758 -241.672148)
			(xy 229.17381 -241.672148) (xy 229.17381 -241.617652) (xy 229.181566 -241.56371) (xy 229.196919 -241.511421)
			(xy 229.219557 -241.461849) (xy 229.249019 -241.416003) (xy 229.284706 -241.374816) (xy 229.325891 -241.339128)
			(xy 229.371736 -241.309664) (xy 229.421307 -241.287024) (xy 229.473596 -241.271669) (xy 229.527538 -241.263911)
			(xy 229.554786 -241.263424) (xy 229.582598 -241.263907) (xy 229.637634 -241.271983) (xy 229.690913 -241.287966)
			(xy 229.741306 -241.311518) (xy 229.787744 -241.342137) (xy 229.829244 -241.379177) (xy 229.864924 -241.42185)
			(xy 229.879906 -241.445288) (xy 229.887772 -241.457109) (xy 229.908709 -241.476269) (xy 229.934111 -241.488926)
			(xy 229.962016 -241.494101) (xy 229.990267 -241.491395) (xy 230.016681 -241.481016) (xy 230.039219 -241.463768)
			(xy 230.048054 -241.452654) (xy 230.066166 -241.429085) (xy 230.108493 -241.387352) (xy 230.15678 -241.352689)
			(xy 230.209858 -241.325934) (xy 230.266443 -241.307734) (xy 230.325166 -241.298529) (xy 230.354886 -241.297968)
			(xy 230.382138 -241.298478) (xy 230.436087 -241.306233) (xy 230.488383 -241.321587) (xy 230.537962 -241.344227)
			(xy 230.583814 -241.373693) (xy 230.625006 -241.409384) (xy 230.660699 -241.450575) (xy 230.690166 -241.496426)
			(xy 230.712808 -241.546004) (xy 230.728164 -241.598299) (xy 230.734886 -241.645053) (xy 233.645432 -241.645053)
			(xy 233.645432 -241.590547) (xy 233.653188 -241.536597) (xy 233.668543 -241.4843) (xy 233.691183 -241.434719)
			(xy 233.720649 -241.388865) (xy 233.75634 -241.347671) (xy 233.79753 -241.311976) (xy 233.843381 -241.282505)
			(xy 233.892958 -241.259858) (xy 233.945254 -241.244497) (xy 233.999204 -241.236735) (xy 234.026456 -241.236246)
			(xy 234.052655 -241.236651) (xy 234.104559 -241.243822) (xy 234.154992 -241.258034) (xy 234.203003 -241.279021)
			(xy 234.247688 -241.306385) (xy 234.288202 -241.339612) (xy 234.323784 -241.378076) (xy 234.33913 -241.399314)
			(xy 234.347533 -241.410538) (xy 234.369231 -241.428276) (xy 234.394934 -241.439448) (xy 234.422707 -241.443211)
			(xy 234.450456 -241.439281) (xy 234.476092 -241.427956) (xy 234.497683 -241.410087) (xy 234.506008 -241.398806)
			(xy 234.52133 -241.377407) (xy 234.556962 -241.33867) (xy 234.597578 -241.305197) (xy 234.64241 -241.277623)
			(xy 234.690605 -241.256471) (xy 234.741249 -241.242142) (xy 234.793382 -241.234909) (xy 234.819698 -241.234468)
			(xy 234.846949 -241.234979) (xy 234.900897 -241.242735) (xy 234.953192 -241.25809) (xy 235.002769 -241.280731)
			(xy 235.04862 -241.310197) (xy 235.08981 -241.345889) (xy 235.125501 -241.387079) (xy 235.154968 -241.432929)
			(xy 235.177609 -241.482506) (xy 235.192964 -241.534801) (xy 235.20029 -241.58575) (xy 235.38764 -241.58575)
			(xy 235.391711 -241.530128) (xy 235.403837 -241.475691) (xy 235.42376 -241.4236) (xy 235.451056 -241.374965)
			(xy 235.485142 -241.330822) (xy 235.525291 -241.292113) (xy 235.570649 -241.259662) (xy 235.620249 -241.234161)
			(xy 235.673033 -241.216154) (xy 235.727876 -241.206024) (xy 235.78361 -241.203987) (xy 235.839047 -241.210087)
			(xy 235.893004 -241.224193) (xy 235.944333 -241.246005) (xy 235.991939 -241.275059) (xy 236.034807 -241.310734)
			(xy 236.072024 -241.352271) (xy 236.102797 -241.398784) (xy 236.126469 -241.449281) (xy 236.142537 -241.502688)
			(xy 236.150657 -241.557864) (xy 236.151166 -241.58575) (xy 236.150657 -241.613636) (xy 236.142537 -241.668812)
			(xy 236.140093 -241.676936) (xy 237.456216 -241.676936) (xy 237.460287 -241.621314) (xy 237.472413 -241.566877)
			(xy 237.492336 -241.514786) (xy 237.519632 -241.466151) (xy 237.553718 -241.422008) (xy 237.593867 -241.383299)
			(xy 237.639225 -241.350848) (xy 237.688825 -241.325347) (xy 237.741609 -241.30734) (xy 237.796452 -241.29721)
			(xy 237.852186 -241.295173) (xy 237.907623 -241.301273) (xy 237.96158 -241.315379) (xy 238.012909 -241.337191)
			(xy 238.060515 -241.366245) (xy 238.103383 -241.40192) (xy 238.1406 -241.443457) (xy 238.171373 -241.48997)
			(xy 238.195045 -241.540467) (xy 238.211113 -241.593874) (xy 238.219233 -241.64905) (xy 238.219742 -241.676936)
			(xy 238.219233 -241.704822) (xy 238.214029 -241.740182) (xy 238.559846 -241.740182) (xy 238.563917 -241.68456)
			(xy 238.576043 -241.630123) (xy 238.595966 -241.578032) (xy 238.623262 -241.529397) (xy 238.657348 -241.485254)
			(xy 238.697497 -241.446545) (xy 238.742855 -241.414094) (xy 238.792455 -241.388593) (xy 238.845239 -241.370586)
			(xy 238.900082 -241.360456) (xy 238.955816 -241.358419) (xy 239.011253 -241.364519) (xy 239.06521 -241.378625)
			(xy 239.116539 -241.400437) (xy 239.164145 -241.429491) (xy 239.207013 -241.465166) (xy 239.24423 -241.506703)
			(xy 239.275003 -241.553216) (xy 239.296684 -241.599466) (xy 239.994184 -241.599466) (xy 239.998255 -241.543844)
			(xy 240.010381 -241.489407) (xy 240.030304 -241.437316) (xy 240.0576 -241.388681) (xy 240.091686 -241.344538)
			(xy 240.131835 -241.305829) (xy 240.177193 -241.273378) (xy 240.226793 -241.247877) (xy 240.279577 -241.22987)
			(xy 240.33442 -241.21974) (xy 240.390154 -241.217703) (xy 240.445591 -241.223803) (xy 240.499548 -241.237909)
			(xy 240.550877 -241.259721) (xy 240.598483 -241.288775) (xy 240.641351 -241.32445) (xy 240.678568 -241.365987)
			(xy 240.709341 -241.4125) (xy 240.733013 -241.462997) (xy 240.749081 -241.516404) (xy 240.757201 -241.57158)
			(xy 240.75771 -241.599466) (xy 240.757201 -241.627352) (xy 240.749081 -241.682528) (xy 240.74786 -241.686588)
			(xy 258.423408 -241.686588) (xy 258.427479 -241.630966) (xy 258.439605 -241.576529) (xy 258.459528 -241.524438)
			(xy 258.486824 -241.475803) (xy 258.52091 -241.43166) (xy 258.561059 -241.392951) (xy 258.606417 -241.3605)
			(xy 258.656017 -241.334999) (xy 258.708801 -241.316992) (xy 258.763644 -241.306862) (xy 258.819378 -241.304825)
			(xy 258.874815 -241.310925) (xy 258.928772 -241.325031) (xy 258.980101 -241.346843) (xy 259.027707 -241.375897)
			(xy 259.070575 -241.411572) (xy 259.107792 -241.453109) (xy 259.138565 -241.499622) (xy 259.162237 -241.550119)
			(xy 259.178305 -241.603526) (xy 259.186425 -241.658702) (xy 259.186934 -241.686588) (xy 259.591808 -241.686588)
			(xy 259.595879 -241.630966) (xy 259.608005 -241.576529) (xy 259.627928 -241.524438) (xy 259.655224 -241.475803)
			(xy 259.68931 -241.43166) (xy 259.729459 -241.392951) (xy 259.774817 -241.3605) (xy 259.824417 -241.334999)
			(xy 259.877201 -241.316992) (xy 259.932044 -241.306862) (xy 259.987778 -241.304825) (xy 260.043215 -241.310925)
			(xy 260.097172 -241.325031) (xy 260.148501 -241.346843) (xy 260.196107 -241.375897) (xy 260.238975 -241.411572)
			(xy 260.276192 -241.453109) (xy 260.306965 -241.499622) (xy 260.330637 -241.550119) (xy 260.346705 -241.603526)
			(xy 260.354825 -241.658702) (xy 260.355334 -241.686588) (xy 260.354825 -241.714474) (xy 260.346705 -241.76965)
			(xy 260.330637 -241.823057) (xy 260.306965 -241.873554) (xy 260.276192 -241.920067) (xy 260.238975 -241.961604)
			(xy 260.196107 -241.997279) (xy 260.148501 -242.026333) (xy 260.097172 -242.048145) (xy 260.043215 -242.062251)
			(xy 259.987778 -242.068351) (xy 259.932044 -242.066314) (xy 259.877201 -242.056184) (xy 259.824417 -242.038177)
			(xy 259.774817 -242.012676) (xy 259.729459 -241.980225) (xy 259.68931 -241.941516) (xy 259.655224 -241.897373)
			(xy 259.627928 -241.848738) (xy 259.608005 -241.796647) (xy 259.595879 -241.74221) (xy 259.591808 -241.686588)
			(xy 259.186934 -241.686588) (xy 259.186425 -241.714474) (xy 259.178305 -241.76965) (xy 259.162237 -241.823057)
			(xy 259.138565 -241.873554) (xy 259.107792 -241.920067) (xy 259.070575 -241.961604) (xy 259.027707 -241.997279)
			(xy 258.980101 -242.026333) (xy 258.928772 -242.048145) (xy 258.874815 -242.062251) (xy 258.819378 -242.068351)
			(xy 258.763644 -242.066314) (xy 258.708801 -242.056184) (xy 258.656017 -242.038177) (xy 258.606417 -242.012676)
			(xy 258.561059 -241.980225) (xy 258.52091 -241.941516) (xy 258.486824 -241.897373) (xy 258.459528 -241.848738)
			(xy 258.439605 -241.796647) (xy 258.427479 -241.74221) (xy 258.423408 -241.686588) (xy 240.74786 -241.686588)
			(xy 240.733013 -241.735935) (xy 240.709341 -241.786432) (xy 240.678568 -241.832945) (xy 240.641351 -241.874482)
			(xy 240.598483 -241.910157) (xy 240.550877 -241.939211) (xy 240.499548 -241.961023) (xy 240.445591 -241.975129)
			(xy 240.390154 -241.981229) (xy 240.33442 -241.979192) (xy 240.279577 -241.969062) (xy 240.226793 -241.951055)
			(xy 240.177193 -241.925554) (xy 240.131835 -241.893103) (xy 240.091686 -241.854394) (xy 240.0576 -241.810251)
			(xy 240.030304 -241.761616) (xy 240.010381 -241.709525) (xy 239.998255 -241.655088) (xy 239.994184 -241.599466)
			(xy 239.296684 -241.599466) (xy 239.298675 -241.603713) (xy 239.314743 -241.65712) (xy 239.322863 -241.712296)
			(xy 239.323372 -241.740182) (xy 239.322863 -241.768068) (xy 239.314743 -241.823244) (xy 239.298675 -241.876651)
			(xy 239.275003 -241.927148) (xy 239.24423 -241.973661) (xy 239.207013 -242.015198) (xy 239.164145 -242.050873)
			(xy 239.116539 -242.079927) (xy 239.06521 -242.101739) (xy 239.011253 -242.115845) (xy 238.955816 -242.121945)
			(xy 238.900082 -242.119908) (xy 238.845239 -242.109778) (xy 238.792455 -242.091771) (xy 238.742855 -242.06627)
			(xy 238.697497 -242.033819) (xy 238.657348 -241.99511) (xy 238.623262 -241.950967) (xy 238.595966 -241.902332)
			(xy 238.576043 -241.850241) (xy 238.563917 -241.795804) (xy 238.559846 -241.740182) (xy 238.214029 -241.740182)
			(xy 238.211113 -241.759998) (xy 238.195045 -241.813405) (xy 238.171373 -241.863902) (xy 238.1406 -241.910415)
			(xy 238.103383 -241.951952) (xy 238.060515 -241.987627) (xy 238.012909 -242.016681) (xy 237.96158 -242.038493)
			(xy 237.907623 -242.052599) (xy 237.852186 -242.058699) (xy 237.796452 -242.056662) (xy 237.741609 -242.046532)
			(xy 237.688825 -242.028525) (xy 237.639225 -242.003024) (xy 237.593867 -241.970573) (xy 237.553718 -241.931864)
			(xy 237.519632 -241.887721) (xy 237.492336 -241.839086) (xy 237.472413 -241.786995) (xy 237.460287 -241.732558)
			(xy 237.456216 -241.676936) (xy 236.140093 -241.676936) (xy 236.126469 -241.722219) (xy 236.102797 -241.772716)
			(xy 236.072024 -241.819229) (xy 236.034807 -241.860766) (xy 235.991939 -241.896441) (xy 235.944333 -241.925495)
			(xy 235.893004 -241.947307) (xy 235.839047 -241.961413) (xy 235.78361 -241.967513) (xy 235.727876 -241.965476)
			(xy 235.673033 -241.955346) (xy 235.620249 -241.937339) (xy 235.570649 -241.911838) (xy 235.525291 -241.879387)
			(xy 235.485142 -241.840678) (xy 235.451056 -241.796535) (xy 235.42376 -241.7479) (xy 235.403837 -241.695809)
			(xy 235.391711 -241.641372) (xy 235.38764 -241.58575) (xy 235.20029 -241.58575) (xy 235.200721 -241.588749)
			(xy 235.200721 -241.643251) (xy 235.192964 -241.697199) (xy 235.177609 -241.749494) (xy 235.154968 -241.799071)
			(xy 235.125501 -241.844921) (xy 235.08981 -241.886111) (xy 235.04862 -241.921803) (xy 235.002769 -241.951269)
			(xy 234.953192 -241.97391) (xy 234.900897 -241.989265) (xy 234.846949 -241.997021) (xy 234.819698 -241.997484)
			(xy 234.793501 -241.997026) (xy 234.7416 -241.989863) (xy 234.691168 -241.975659) (xy 234.643158 -241.954681)
			(xy 234.598473 -241.927325) (xy 234.557956 -241.894106) (xy 234.522372 -241.855651) (xy 234.507024 -241.834416)
			(xy 234.498673 -241.823154) (xy 234.476959 -241.805426) (xy 234.451246 -241.794266) (xy 234.423467 -241.790512)
			(xy 234.395713 -241.794447) (xy 234.370073 -241.805775) (xy 234.348476 -241.823643) (xy 234.340146 -241.834924)
			(xy 234.324769 -241.856282) (xy 234.289149 -241.895024) (xy 234.248543 -241.928502) (xy 234.203721 -241.956082)
			(xy 234.155534 -241.977241) (xy 234.104897 -241.991577) (xy 234.05277 -241.998817) (xy 234.026456 -241.999262)
			(xy 233.999204 -241.998865) (xy 233.945254 -241.991103) (xy 233.892958 -241.975742) (xy 233.843381 -241.953095)
			(xy 233.79753 -241.923624) (xy 233.75634 -241.887929) (xy 233.720649 -241.846735) (xy 233.691183 -241.800881)
			(xy 233.668543 -241.7513) (xy 233.653188 -241.699003) (xy 233.645432 -241.645053) (xy 230.734886 -241.645053)
			(xy 230.735921 -241.652248) (xy 230.735921 -241.706752) (xy 230.728164 -241.760701) (xy 230.712808 -241.812996)
			(xy 230.690166 -241.862574) (xy 230.660699 -241.908425) (xy 230.625006 -241.949616) (xy 230.583814 -241.985307)
			(xy 230.537962 -242.014773) (xy 230.488383 -242.037413) (xy 230.436087 -242.052767) (xy 230.382138 -242.060522)
			(xy 230.354886 -242.060984) (xy 230.327076 -242.060441) (xy 230.272043 -242.052375) (xy 230.218766 -242.036402)
			(xy 230.168373 -242.012861) (xy 230.121934 -241.98225) (xy 230.080432 -241.94522) (xy 230.044749 -241.902554)
			(xy 230.029766 -241.87912) (xy 230.021936 -241.867272) (xy 230.000992 -241.84811) (xy 229.975582 -241.835453)
			(xy 229.94767 -241.830281) (xy 229.919412 -241.832992) (xy 229.892993 -241.843378) (xy 229.870453 -241.860636)
			(xy 229.861618 -241.871754) (xy 229.843465 -241.895291) (xy 229.801147 -241.937024) (xy 229.752868 -241.971691)
			(xy 229.699798 -241.998452) (xy 229.643221 -242.01666) (xy 229.584504 -242.025874) (xy 229.554786 -242.02644)
			(xy 229.527538 -242.025889) (xy 229.473596 -242.018131) (xy 229.421307 -242.002776) (xy 229.371736 -241.980136)
			(xy 229.325891 -241.950672) (xy 229.284706 -241.914984) (xy 229.249019 -241.873797) (xy 229.219557 -241.827951)
			(xy 229.196919 -241.778379) (xy 229.181566 -241.72609) (xy 229.17381 -241.672148) (xy 216.769758 -241.672148)
			(xy 216.762286 -241.72411) (xy 216.746928 -241.776412) (xy 216.724282 -241.825996) (xy 216.694809 -241.871851)
			(xy 216.65911 -241.913045) (xy 216.617911 -241.948739) (xy 216.572052 -241.978206) (xy 216.522465 -242.000845)
			(xy 216.470162 -242.016197) (xy 216.416205 -242.023948) (xy 216.38895 -242.024408) (xy 216.363286 -242.023979)
			(xy 216.31242 -242.017109) (xy 216.262937 -242.003474) (xy 216.215731 -241.983321) (xy 216.171658 -241.957014)
			(xy 216.131514 -241.925029) (xy 216.096027 -241.887945) (xy 216.080594 -241.867436) (xy 216.074244 -241.858546)
			(xy 216.064592 -241.853212) (xy 216.059899 -241.850738) (xy 216.049788 -241.847533) (xy 216.044526 -241.846862)
			(xy 215.968834 -241.839496) (xy 215.960452 -241.839496) (xy 215.951717 -241.840467) (xy 215.935613 -241.847475)
			(xy 215.928956 -241.853212) (xy 215.907624 -241.872423) (xy 215.860296 -241.90491) (xy 215.808637 -241.929942)
			(xy 215.75381 -241.946954) (xy 215.697054 -241.95556) (xy 215.668352 -241.956082) (xy 215.641101 -241.955645)
			(xy 215.587155 -241.947882) (xy 215.534862 -241.932522) (xy 215.485288 -241.909877) (xy 215.43944 -241.880407)
			(xy 215.398253 -241.844713) (xy 215.362564 -241.803521) (xy 215.3331 -241.75767) (xy 215.310461 -241.708093)
			(xy 215.295107 -241.655798) (xy 215.287352 -241.601851) (xy 209.080862 -241.601851) (xy 209.080862 -241.877088)
			(xy 209.081169 -241.885283) (xy 209.086345 -241.900833) (xy 209.091022 -241.907568) (xy 209.095848 -241.913156)
			(xy 209.458052 -242.27536) (xy 209.458814 -242.283488) (xy 209.458814 -242.283996) (xy 209.460411 -242.291517)
			(xy 209.467382 -242.305211) (xy 209.47253 -242.31092) (xy 209.826098 -242.664488) (xy 254.886458 -242.664488)
			(xy 254.890529 -242.608866) (xy 254.902655 -242.554429) (xy 254.922578 -242.502338) (xy 254.949874 -242.453703)
			(xy 254.98396 -242.40956) (xy 255.024109 -242.370851) (xy 255.069467 -242.3384) (xy 255.119067 -242.312899)
			(xy 255.171851 -242.294892) (xy 255.226694 -242.284762) (xy 255.282428 -242.282725) (xy 255.337865 -242.288825)
			(xy 255.391822 -242.302931) (xy 255.443151 -242.324743) (xy 255.490757 -242.353797) (xy 255.513096 -242.372388)
			(xy 256.721608 -242.372388) (xy 256.725679 -242.316766) (xy 256.737805 -242.262329) (xy 256.757728 -242.210238)
			(xy 256.785024 -242.161603) (xy 256.81911 -242.11746) (xy 256.859259 -242.078751) (xy 256.904617 -242.0463)
			(xy 256.954217 -242.020799) (xy 257.007001 -242.002792) (xy 257.061844 -241.992662) (xy 257.117578 -241.990625)
			(xy 257.173015 -241.996725) (xy 257.226972 -242.010831) (xy 257.278301 -242.032643) (xy 257.325907 -242.061697)
			(xy 257.368775 -242.097372) (xy 257.405992 -242.138909) (xy 257.436765 -242.185422) (xy 257.460437 -242.235919)
			(xy 257.476505 -242.289326) (xy 257.480206 -242.314476) (xy 262.093962 -242.314476) (xy 262.098033 -242.258854)
			(xy 262.110159 -242.204417) (xy 262.130082 -242.152326) (xy 262.157378 -242.103691) (xy 262.191464 -242.059548)
			(xy 262.231613 -242.020839) (xy 262.276971 -241.988388) (xy 262.326571 -241.962887) (xy 262.379355 -241.94488)
			(xy 262.434198 -241.93475) (xy 262.489932 -241.932713) (xy 262.545369 -241.938813) (xy 262.599326 -241.952919)
			(xy 262.650655 -241.974731) (xy 262.698261 -242.003785) (xy 262.741129 -242.03946) (xy 262.778346 -242.080997)
			(xy 262.809119 -242.12751) (xy 262.832791 -242.178007) (xy 262.848859 -242.231414) (xy 262.856979 -242.28659)
			(xy 262.857488 -242.314476) (xy 262.856979 -242.342362) (xy 262.848859 -242.397538) (xy 262.832791 -242.450945)
			(xy 262.809119 -242.501442) (xy 262.778346 -242.547955) (xy 262.741129 -242.589492) (xy 262.698261 -242.625167)
			(xy 262.650655 -242.654221) (xy 262.599326 -242.676033) (xy 262.545369 -242.690139) (xy 262.489932 -242.696239)
			(xy 262.434198 -242.694202) (xy 262.379355 -242.684072) (xy 262.326571 -242.666065) (xy 262.276971 -242.640564)
			(xy 262.231613 -242.608113) (xy 262.191464 -242.569404) (xy 262.157378 -242.525261) (xy 262.130082 -242.476626)
			(xy 262.110159 -242.424535) (xy 262.098033 -242.370098) (xy 262.093962 -242.314476) (xy 257.480206 -242.314476)
			(xy 257.484625 -242.344502) (xy 257.485134 -242.372388) (xy 257.484625 -242.400274) (xy 257.476505 -242.45545)
			(xy 257.460437 -242.508857) (xy 257.436765 -242.559354) (xy 257.405992 -242.605867) (xy 257.368775 -242.647404)
			(xy 257.325907 -242.683079) (xy 257.278301 -242.712133) (xy 257.226972 -242.733945) (xy 257.173015 -242.748051)
			(xy 257.117578 -242.754151) (xy 257.061844 -242.752114) (xy 257.007001 -242.741984) (xy 256.954217 -242.723977)
			(xy 256.904617 -242.698476) (xy 256.859259 -242.666025) (xy 256.81911 -242.627316) (xy 256.785024 -242.583173)
			(xy 256.757728 -242.534538) (xy 256.737805 -242.482447) (xy 256.725679 -242.42801) (xy 256.721608 -242.372388)
			(xy 255.513096 -242.372388) (xy 255.533625 -242.389472) (xy 255.570842 -242.431009) (xy 255.601615 -242.477522)
			(xy 255.625287 -242.528019) (xy 255.641355 -242.581426) (xy 255.649475 -242.636602) (xy 255.649984 -242.664488)
			(xy 255.649475 -242.692374) (xy 255.641355 -242.74755) (xy 255.625287 -242.800957) (xy 255.601615 -242.851454)
			(xy 255.570842 -242.897967) (xy 255.533625 -242.939504) (xy 255.490757 -242.975179) (xy 255.443151 -243.004233)
			(xy 255.391822 -243.026045) (xy 255.337865 -243.040151) (xy 255.282428 -243.046251) (xy 255.226694 -243.044214)
			(xy 255.171851 -243.034084) (xy 255.119067 -243.016077) (xy 255.069467 -242.990576) (xy 255.024109 -242.958125)
			(xy 254.98396 -242.919416) (xy 254.949874 -242.875273) (xy 254.922578 -242.826638) (xy 254.902655 -242.774547)
			(xy 254.890529 -242.72011) (xy 254.886458 -242.664488) (xy 209.826098 -242.664488) (xy 210.002882 -242.841272)
			(xy 210.008562 -242.846464) (xy 210.022268 -242.853442) (xy 210.029806 -242.854988) (xy 210.030314 -242.854988)
			(xy 210.038442 -242.85575) (xy 244.710966 -242.85575) (xy 244.72103 -242.856187) (xy 244.739612 -242.863923)
			(xy 244.747034 -242.870736) (xy 245.416982 -243.540788) (xy 260.658608 -243.540788) (xy 260.662679 -243.485166)
			(xy 260.674805 -243.430729) (xy 260.694728 -243.378638) (xy 260.722024 -243.330003) (xy 260.75611 -243.28586)
			(xy 260.796259 -243.247151) (xy 260.841617 -243.2147) (xy 260.891217 -243.189199) (xy 260.944001 -243.171192)
			(xy 260.998844 -243.161062) (xy 261.054578 -243.159025) (xy 261.110015 -243.165125) (xy 261.163972 -243.179231)
			(xy 261.215301 -243.201043) (xy 261.262907 -243.230097) (xy 261.305775 -243.265772) (xy 261.342992 -243.307309)
			(xy 261.373765 -243.353822) (xy 261.397437 -243.404319) (xy 261.413505 -243.457726) (xy 261.421625 -243.512902)
			(xy 261.422134 -243.540788) (xy 261.421625 -243.568674) (xy 261.413505 -243.62385) (xy 261.397437 -243.677257)
			(xy 261.373765 -243.727754) (xy 261.342992 -243.774267) (xy 261.305775 -243.815804) (xy 261.262907 -243.851479)
			(xy 261.215301 -243.880533) (xy 261.163972 -243.902345) (xy 261.110015 -243.916451) (xy 261.054578 -243.922551)
			(xy 260.998844 -243.920514) (xy 260.944001 -243.910384) (xy 260.891217 -243.892377) (xy 260.841617 -243.866876)
			(xy 260.796259 -243.834425) (xy 260.75611 -243.795716) (xy 260.722024 -243.751573) (xy 260.694728 -243.702938)
			(xy 260.674805 -243.650847) (xy 260.662679 -243.59641) (xy 260.658608 -243.540788) (xy 245.416982 -243.540788)
			(xy 246.379746 -244.503702) (xy 246.386598 -244.511098) (xy 246.39434 -244.529697) (xy 246.394732 -244.53977)
			(xy 246.394732 -246.01551) (xy 249.35764 -246.01551) (xy 249.361711 -245.959888) (xy 249.373837 -245.905451)
			(xy 249.39376 -245.85336) (xy 249.421056 -245.804725) (xy 249.455142 -245.760582) (xy 249.495291 -245.721873)
			(xy 249.540649 -245.689422) (xy 249.590249 -245.663921) (xy 249.643033 -245.645914) (xy 249.697876 -245.635784)
			(xy 249.75361 -245.633747) (xy 249.809047 -245.639847) (xy 249.863004 -245.653953) (xy 249.914333 -245.675765)
			(xy 249.961939 -245.704819) (xy 250.004807 -245.740494) (xy 250.042024 -245.782031) (xy 250.072797 -245.828544)
			(xy 250.096469 -245.879041) (xy 250.112537 -245.932448) (xy 250.120657 -245.987624) (xy 250.121166 -246.01551)
			(xy 250.120657 -246.043396) (xy 250.112537 -246.098572) (xy 250.096469 -246.151979) (xy 250.072797 -246.202476)
			(xy 250.042024 -246.248989) (xy 250.004807 -246.290526) (xy 249.961939 -246.326201) (xy 249.914333 -246.355255)
			(xy 249.863004 -246.377067) (xy 249.809047 -246.391173) (xy 249.75361 -246.397273) (xy 249.697876 -246.395236)
			(xy 249.643033 -246.385106) (xy 249.590249 -246.367099) (xy 249.540649 -246.341598) (xy 249.495291 -246.309147)
			(xy 249.455142 -246.270438) (xy 249.421056 -246.226295) (xy 249.39376 -246.17766) (xy 249.373837 -246.125569)
			(xy 249.361711 -246.071132) (xy 249.35764 -246.01551) (xy 246.394732 -246.01551) (xy 246.394732 -249.005598)
			(xy 255.19837 -249.005598) (xy 255.202441 -248.949976) (xy 255.214567 -248.895539) (xy 255.23449 -248.843448)
			(xy 255.261786 -248.794813) (xy 255.295872 -248.75067) (xy 255.336021 -248.711961) (xy 255.381379 -248.67951)
			(xy 255.430979 -248.654009) (xy 255.483763 -248.636002) (xy 255.538606 -248.625872) (xy 255.59434 -248.623835)
			(xy 255.649777 -248.629935) (xy 255.703734 -248.644041) (xy 255.755063 -248.665853) (xy 255.802669 -248.694907)
			(xy 255.845537 -248.730582) (xy 255.882754 -248.772119) (xy 255.913527 -248.818632) (xy 255.937199 -248.869129)
			(xy 255.953267 -248.922536) (xy 255.961387 -248.977712) (xy 255.961896 -249.005598) (xy 255.961387 -249.033484)
			(xy 255.961043 -249.035824) (xy 259.186678 -249.035824) (xy 259.190749 -248.980202) (xy 259.202875 -248.925765)
			(xy 259.222798 -248.873674) (xy 259.250094 -248.825039) (xy 259.28418 -248.780896) (xy 259.324329 -248.742187)
			(xy 259.369687 -248.709736) (xy 259.419287 -248.684235) (xy 259.472071 -248.666228) (xy 259.526914 -248.656098)
			(xy 259.582648 -248.654061) (xy 259.638085 -248.660161) (xy 259.692042 -248.674267) (xy 259.743371 -248.696079)
			(xy 259.790977 -248.725133) (xy 259.833845 -248.760808) (xy 259.871062 -248.802345) (xy 259.901835 -248.848858)
			(xy 259.925507 -248.899355) (xy 259.941575 -248.952762) (xy 259.949695 -249.007938) (xy 259.950204 -249.035824)
			(xy 259.949695 -249.06371) (xy 259.941575 -249.118886) (xy 259.925507 -249.172293) (xy 259.901835 -249.22279)
			(xy 259.871062 -249.269303) (xy 259.833845 -249.31084) (xy 259.790977 -249.346515) (xy 259.743371 -249.375569)
			(xy 259.692042 -249.397381) (xy 259.638085 -249.411487) (xy 259.582648 -249.417587) (xy 259.526914 -249.41555)
			(xy 259.472071 -249.40542) (xy 259.419287 -249.387413) (xy 259.369687 -249.361912) (xy 259.324329 -249.329461)
			(xy 259.28418 -249.290752) (xy 259.250094 -249.246609) (xy 259.222798 -249.197974) (xy 259.202875 -249.145883)
			(xy 259.190749 -249.091446) (xy 259.186678 -249.035824) (xy 255.961043 -249.035824) (xy 255.953267 -249.08866)
			(xy 255.937199 -249.142067) (xy 255.913527 -249.192564) (xy 255.882754 -249.239077) (xy 255.845537 -249.280614)
			(xy 255.802669 -249.316289) (xy 255.755063 -249.345343) (xy 255.703734 -249.367155) (xy 255.649777 -249.381261)
			(xy 255.59434 -249.387361) (xy 255.538606 -249.385324) (xy 255.483763 -249.375194) (xy 255.430979 -249.357187)
			(xy 255.381379 -249.331686) (xy 255.336021 -249.299235) (xy 255.295872 -249.260526) (xy 255.261786 -249.216383)
			(xy 255.23449 -249.167748) (xy 255.214567 -249.115657) (xy 255.202441 -249.06122) (xy 255.19837 -249.005598)
			(xy 246.394732 -249.005598) (xy 246.394732 -251.173996) (xy 256.047238 -251.173996) (xy 256.051309 -251.118374)
			(xy 256.063435 -251.063937) (xy 256.083358 -251.011846) (xy 256.110654 -250.963211) (xy 256.14474 -250.919068)
			(xy 256.184889 -250.880359) (xy 256.230247 -250.847908) (xy 256.279847 -250.822407) (xy 256.332631 -250.8044)
			(xy 256.387474 -250.79427) (xy 256.443208 -250.792233) (xy 256.498645 -250.798333) (xy 256.552602 -250.812439)
			(xy 256.603931 -250.834251) (xy 256.651537 -250.863305) (xy 256.694405 -250.89898) (xy 256.731622 -250.940517)
			(xy 256.762395 -250.98703) (xy 256.786067 -251.037527) (xy 256.802135 -251.090934) (xy 256.810255 -251.14611)
			(xy 256.810481 -251.158502) (xy 257.176268 -251.158502) (xy 257.180339 -251.10288) (xy 257.192465 -251.048443)
			(xy 257.212388 -250.996352) (xy 257.239684 -250.947717) (xy 257.27377 -250.903574) (xy 257.313919 -250.864865)
			(xy 257.359277 -250.832414) (xy 257.408877 -250.806913) (xy 257.461661 -250.788906) (xy 257.516504 -250.778776)
			(xy 257.572238 -250.776739) (xy 257.627675 -250.782839) (xy 257.681632 -250.796945) (xy 257.732961 -250.818757)
			(xy 257.780567 -250.847811) (xy 257.823435 -250.883486) (xy 257.860652 -250.925023) (xy 257.891425 -250.971536)
			(xy 257.915097 -251.022033) (xy 257.931165 -251.07544) (xy 257.939285 -251.130616) (xy 257.939794 -251.158502)
			(xy 258.192268 -251.158502) (xy 258.196339 -251.10288) (xy 258.208465 -251.048443) (xy 258.228388 -250.996352)
			(xy 258.255684 -250.947717) (xy 258.28977 -250.903574) (xy 258.329919 -250.864865) (xy 258.375277 -250.832414)
			(xy 258.424877 -250.806913) (xy 258.477661 -250.788906) (xy 258.532504 -250.778776) (xy 258.588238 -250.776739)
			(xy 258.643675 -250.782839) (xy 258.697632 -250.796945) (xy 258.748961 -250.818757) (xy 258.796567 -250.847811)
			(xy 258.839435 -250.883486) (xy 258.876652 -250.925023) (xy 258.907425 -250.971536) (xy 258.931097 -251.022033)
			(xy 258.947165 -251.07544) (xy 258.955285 -251.130616) (xy 258.955794 -251.158502) (xy 259.208268 -251.158502)
			(xy 259.212339 -251.10288) (xy 259.224465 -251.048443) (xy 259.244388 -250.996352) (xy 259.271684 -250.947717)
			(xy 259.30577 -250.903574) (xy 259.345919 -250.864865) (xy 259.391277 -250.832414) (xy 259.440877 -250.806913)
			(xy 259.493661 -250.788906) (xy 259.548504 -250.778776) (xy 259.604238 -250.776739) (xy 259.659675 -250.782839)
			(xy 259.713632 -250.796945) (xy 259.764961 -250.818757) (xy 259.812567 -250.847811) (xy 259.855435 -250.883486)
			(xy 259.892652 -250.925023) (xy 259.923425 -250.971536) (xy 259.947097 -251.022033) (xy 259.963165 -251.07544)
			(xy 259.971285 -251.130616) (xy 259.971794 -251.158502) (xy 260.224268 -251.158502) (xy 260.228339 -251.10288)
			(xy 260.240465 -251.048443) (xy 260.260388 -250.996352) (xy 260.287684 -250.947717) (xy 260.32177 -250.903574)
			(xy 260.361919 -250.864865) (xy 260.407277 -250.832414) (xy 260.456877 -250.806913) (xy 260.509661 -250.788906)
			(xy 260.564504 -250.778776) (xy 260.620238 -250.776739) (xy 260.675675 -250.782839) (xy 260.729632 -250.796945)
			(xy 260.780961 -250.818757) (xy 260.828567 -250.847811) (xy 260.871435 -250.883486) (xy 260.908652 -250.925023)
			(xy 260.939425 -250.971536) (xy 260.963097 -251.022033) (xy 260.979165 -251.07544) (xy 260.987285 -251.130616)
			(xy 260.987794 -251.158502) (xy 261.240268 -251.158502) (xy 261.244339 -251.10288) (xy 261.256465 -251.048443)
			(xy 261.276388 -250.996352) (xy 261.303684 -250.947717) (xy 261.33777 -250.903574) (xy 261.377919 -250.864865)
			(xy 261.423277 -250.832414) (xy 261.472877 -250.806913) (xy 261.525661 -250.788906) (xy 261.580504 -250.778776)
			(xy 261.636238 -250.776739) (xy 261.691675 -250.782839) (xy 261.745632 -250.796945) (xy 261.796961 -250.818757)
			(xy 261.844567 -250.847811) (xy 261.887435 -250.883486) (xy 261.924652 -250.925023) (xy 261.955425 -250.971536)
			(xy 261.979097 -251.022033) (xy 261.995165 -251.07544) (xy 262.003285 -251.130616) (xy 262.003794 -251.158502)
			(xy 262.256268 -251.158502) (xy 262.260339 -251.10288) (xy 262.272465 -251.048443) (xy 262.292388 -250.996352)
			(xy 262.319684 -250.947717) (xy 262.35377 -250.903574) (xy 262.393919 -250.864865) (xy 262.439277 -250.832414)
			(xy 262.488877 -250.806913) (xy 262.541661 -250.788906) (xy 262.596504 -250.778776) (xy 262.652238 -250.776739)
			(xy 262.707675 -250.782839) (xy 262.761632 -250.796945) (xy 262.812961 -250.818757) (xy 262.860567 -250.847811)
			(xy 262.903435 -250.883486) (xy 262.940652 -250.925023) (xy 262.971425 -250.971536) (xy 262.995097 -251.022033)
			(xy 263.011165 -251.07544) (xy 263.019285 -251.130616) (xy 263.019794 -251.158502) (xy 263.272268 -251.158502)
			(xy 263.276339 -251.10288) (xy 263.288465 -251.048443) (xy 263.308388 -250.996352) (xy 263.335684 -250.947717)
			(xy 263.36977 -250.903574) (xy 263.409919 -250.864865) (xy 263.455277 -250.832414) (xy 263.504877 -250.806913)
			(xy 263.557661 -250.788906) (xy 263.612504 -250.778776) (xy 263.668238 -250.776739) (xy 263.723675 -250.782839)
			(xy 263.777632 -250.796945) (xy 263.828961 -250.818757) (xy 263.876567 -250.847811) (xy 263.919435 -250.883486)
			(xy 263.956652 -250.925023) (xy 263.987425 -250.971536) (xy 264.011097 -251.022033) (xy 264.027165 -251.07544)
			(xy 264.035285 -251.130616) (xy 264.035794 -251.158502) (xy 264.288268 -251.158502) (xy 264.292339 -251.10288)
			(xy 264.304465 -251.048443) (xy 264.324388 -250.996352) (xy 264.351684 -250.947717) (xy 264.38577 -250.903574)
			(xy 264.425919 -250.864865) (xy 264.471277 -250.832414) (xy 264.520877 -250.806913) (xy 264.573661 -250.788906)
			(xy 264.628504 -250.778776) (xy 264.684238 -250.776739) (xy 264.739675 -250.782839) (xy 264.793632 -250.796945)
			(xy 264.844961 -250.818757) (xy 264.892567 -250.847811) (xy 264.935435 -250.883486) (xy 264.972652 -250.925023)
			(xy 265.003425 -250.971536) (xy 265.027097 -251.022033) (xy 265.043165 -251.07544) (xy 265.051285 -251.130616)
			(xy 265.051794 -251.158502) (xy 265.304268 -251.158502) (xy 265.308339 -251.10288) (xy 265.320465 -251.048443)
			(xy 265.340388 -250.996352) (xy 265.367684 -250.947717) (xy 265.40177 -250.903574) (xy 265.441919 -250.864865)
			(xy 265.487277 -250.832414) (xy 265.536877 -250.806913) (xy 265.589661 -250.788906) (xy 265.644504 -250.778776)
			(xy 265.700238 -250.776739) (xy 265.755675 -250.782839) (xy 265.809632 -250.796945) (xy 265.860961 -250.818757)
			(xy 265.908567 -250.847811) (xy 265.951435 -250.883486) (xy 265.988652 -250.925023) (xy 266.019425 -250.971536)
			(xy 266.043097 -251.022033) (xy 266.059165 -251.07544) (xy 266.067285 -251.130616) (xy 266.067794 -251.158502)
			(xy 266.320268 -251.158502) (xy 266.324339 -251.10288) (xy 266.336465 -251.048443) (xy 266.356388 -250.996352)
			(xy 266.383684 -250.947717) (xy 266.41777 -250.903574) (xy 266.457919 -250.864865) (xy 266.503277 -250.832414)
			(xy 266.552877 -250.806913) (xy 266.605661 -250.788906) (xy 266.660504 -250.778776) (xy 266.716238 -250.776739)
			(xy 266.771675 -250.782839) (xy 266.825632 -250.796945) (xy 266.876961 -250.818757) (xy 266.924567 -250.847811)
			(xy 266.967435 -250.883486) (xy 267.004652 -250.925023) (xy 267.035425 -250.971536) (xy 267.059097 -251.022033)
			(xy 267.075165 -251.07544) (xy 267.083285 -251.130616) (xy 267.083794 -251.158502) (xy 267.336268 -251.158502)
			(xy 267.340339 -251.10288) (xy 267.352465 -251.048443) (xy 267.372388 -250.996352) (xy 267.399684 -250.947717)
			(xy 267.43377 -250.903574) (xy 267.473919 -250.864865) (xy 267.519277 -250.832414) (xy 267.568877 -250.806913)
			(xy 267.621661 -250.788906) (xy 267.676504 -250.778776) (xy 267.732238 -250.776739) (xy 267.787675 -250.782839)
			(xy 267.841632 -250.796945) (xy 267.892961 -250.818757) (xy 267.940567 -250.847811) (xy 267.983435 -250.883486)
			(xy 268.020652 -250.925023) (xy 268.051425 -250.971536) (xy 268.075097 -251.022033) (xy 268.091165 -251.07544)
			(xy 268.099285 -251.130616) (xy 268.099794 -251.158502) (xy 268.352268 -251.158502) (xy 268.356339 -251.10288)
			(xy 268.368465 -251.048443) (xy 268.388388 -250.996352) (xy 268.415684 -250.947717) (xy 268.44977 -250.903574)
			(xy 268.489919 -250.864865) (xy 268.535277 -250.832414) (xy 268.584877 -250.806913) (xy 268.637661 -250.788906)
			(xy 268.692504 -250.778776) (xy 268.748238 -250.776739) (xy 268.803675 -250.782839) (xy 268.857632 -250.796945)
			(xy 268.908961 -250.818757) (xy 268.956567 -250.847811) (xy 268.999435 -250.883486) (xy 269.036652 -250.925023)
			(xy 269.067425 -250.971536) (xy 269.091097 -251.022033) (xy 269.107165 -251.07544) (xy 269.115285 -251.130616)
			(xy 269.115794 -251.158502) (xy 269.368268 -251.158502) (xy 269.372339 -251.10288) (xy 269.384465 -251.048443)
			(xy 269.404388 -250.996352) (xy 269.431684 -250.947717) (xy 269.46577 -250.903574) (xy 269.505919 -250.864865)
			(xy 269.551277 -250.832414) (xy 269.600877 -250.806913) (xy 269.653661 -250.788906) (xy 269.708504 -250.778776)
			(xy 269.764238 -250.776739) (xy 269.819675 -250.782839) (xy 269.873632 -250.796945) (xy 269.924961 -250.818757)
			(xy 269.972567 -250.847811) (xy 270.015435 -250.883486) (xy 270.052652 -250.925023) (xy 270.083425 -250.971536)
			(xy 270.107097 -251.022033) (xy 270.123165 -251.07544) (xy 270.131285 -251.130616) (xy 270.131609 -251.148342)
			(xy 270.337024 -251.148342) (xy 270.341095 -251.09272) (xy 270.353221 -251.038283) (xy 270.373144 -250.986192)
			(xy 270.40044 -250.937557) (xy 270.434526 -250.893414) (xy 270.474675 -250.854705) (xy 270.520033 -250.822254)
			(xy 270.569633 -250.796753) (xy 270.622417 -250.778746) (xy 270.67726 -250.768616) (xy 270.732994 -250.766579)
			(xy 270.788431 -250.772679) (xy 270.842388 -250.786785) (xy 270.893717 -250.808597) (xy 270.941323 -250.837651)
			(xy 270.984191 -250.873326) (xy 271.021408 -250.914863) (xy 271.052181 -250.961376) (xy 271.075853 -251.011873)
			(xy 271.091921 -251.06528) (xy 271.100041 -251.120456) (xy 271.10055 -251.148342) (xy 271.100041 -251.176228)
			(xy 271.091921 -251.231404) (xy 271.075853 -251.284811) (xy 271.052181 -251.335308) (xy 271.021408 -251.381821)
			(xy 270.984191 -251.423358) (xy 270.941323 -251.459033) (xy 270.893717 -251.488087) (xy 270.842388 -251.509899)
			(xy 270.788431 -251.524005) (xy 270.732994 -251.530105) (xy 270.67726 -251.528068) (xy 270.622417 -251.517938)
			(xy 270.569633 -251.499931) (xy 270.520033 -251.47443) (xy 270.474675 -251.441979) (xy 270.434526 -251.40327)
			(xy 270.40044 -251.359127) (xy 270.373144 -251.310492) (xy 270.353221 -251.258401) (xy 270.341095 -251.203964)
			(xy 270.337024 -251.148342) (xy 270.131609 -251.148342) (xy 270.131794 -251.158502) (xy 270.131285 -251.186388)
			(xy 270.123165 -251.241564) (xy 270.107097 -251.294971) (xy 270.083425 -251.345468) (xy 270.052652 -251.391981)
			(xy 270.015435 -251.433518) (xy 269.972567 -251.469193) (xy 269.924961 -251.498247) (xy 269.873632 -251.520059)
			(xy 269.819675 -251.534165) (xy 269.764238 -251.540265) (xy 269.708504 -251.538228) (xy 269.653661 -251.528098)
			(xy 269.600877 -251.510091) (xy 269.551277 -251.48459) (xy 269.505919 -251.452139) (xy 269.46577 -251.41343)
			(xy 269.431684 -251.369287) (xy 269.404388 -251.320652) (xy 269.384465 -251.268561) (xy 269.372339 -251.214124)
			(xy 269.368268 -251.158502) (xy 269.115794 -251.158502) (xy 269.115285 -251.186388) (xy 269.107165 -251.241564)
			(xy 269.091097 -251.294971) (xy 269.067425 -251.345468) (xy 269.036652 -251.391981) (xy 268.999435 -251.433518)
			(xy 268.956567 -251.469193) (xy 268.908961 -251.498247) (xy 268.857632 -251.520059) (xy 268.803675 -251.534165)
			(xy 268.748238 -251.540265) (xy 268.692504 -251.538228) (xy 268.637661 -251.528098) (xy 268.584877 -251.510091)
			(xy 268.535277 -251.48459) (xy 268.489919 -251.452139) (xy 268.44977 -251.41343) (xy 268.415684 -251.369287)
			(xy 268.388388 -251.320652) (xy 268.368465 -251.268561) (xy 268.356339 -251.214124) (xy 268.352268 -251.158502)
			(xy 268.099794 -251.158502) (xy 268.099285 -251.186388) (xy 268.091165 -251.241564) (xy 268.075097 -251.294971)
			(xy 268.051425 -251.345468) (xy 268.020652 -251.391981) (xy 267.983435 -251.433518) (xy 267.940567 -251.469193)
			(xy 267.892961 -251.498247) (xy 267.841632 -251.520059) (xy 267.787675 -251.534165) (xy 267.732238 -251.540265)
			(xy 267.676504 -251.538228) (xy 267.621661 -251.528098) (xy 267.568877 -251.510091) (xy 267.519277 -251.48459)
			(xy 267.473919 -251.452139) (xy 267.43377 -251.41343) (xy 267.399684 -251.369287) (xy 267.372388 -251.320652)
			(xy 267.352465 -251.268561) (xy 267.340339 -251.214124) (xy 267.336268 -251.158502) (xy 267.083794 -251.158502)
			(xy 267.083285 -251.186388) (xy 267.075165 -251.241564) (xy 267.059097 -251.294971) (xy 267.035425 -251.345468)
			(xy 267.004652 -251.391981) (xy 266.967435 -251.433518) (xy 266.924567 -251.469193) (xy 266.876961 -251.498247)
			(xy 266.825632 -251.520059) (xy 266.771675 -251.534165) (xy 266.716238 -251.540265) (xy 266.660504 -251.538228)
			(xy 266.605661 -251.528098) (xy 266.552877 -251.510091) (xy 266.503277 -251.48459) (xy 266.457919 -251.452139)
			(xy 266.41777 -251.41343) (xy 266.383684 -251.369287) (xy 266.356388 -251.320652) (xy 266.336465 -251.268561)
			(xy 266.324339 -251.214124) (xy 266.320268 -251.158502) (xy 266.067794 -251.158502) (xy 266.067285 -251.186388)
			(xy 266.059165 -251.241564) (xy 266.043097 -251.294971) (xy 266.019425 -251.345468) (xy 265.988652 -251.391981)
			(xy 265.951435 -251.433518) (xy 265.908567 -251.469193) (xy 265.860961 -251.498247) (xy 265.809632 -251.520059)
			(xy 265.755675 -251.534165) (xy 265.700238 -251.540265) (xy 265.644504 -251.538228) (xy 265.589661 -251.528098)
			(xy 265.536877 -251.510091) (xy 265.487277 -251.48459) (xy 265.441919 -251.452139) (xy 265.40177 -251.41343)
			(xy 265.367684 -251.369287) (xy 265.340388 -251.320652) (xy 265.320465 -251.268561) (xy 265.308339 -251.214124)
			(xy 265.304268 -251.158502) (xy 265.051794 -251.158502) (xy 265.051285 -251.186388) (xy 265.043165 -251.241564)
			(xy 265.027097 -251.294971) (xy 265.003425 -251.345468) (xy 264.972652 -251.391981) (xy 264.935435 -251.433518)
			(xy 264.892567 -251.469193) (xy 264.844961 -251.498247) (xy 264.793632 -251.520059) (xy 264.739675 -251.534165)
			(xy 264.684238 -251.540265) (xy 264.628504 -251.538228) (xy 264.573661 -251.528098) (xy 264.520877 -251.510091)
			(xy 264.471277 -251.48459) (xy 264.425919 -251.452139) (xy 264.38577 -251.41343) (xy 264.351684 -251.369287)
			(xy 264.324388 -251.320652) (xy 264.304465 -251.268561) (xy 264.292339 -251.214124) (xy 264.288268 -251.158502)
			(xy 264.035794 -251.158502) (xy 264.035285 -251.186388) (xy 264.027165 -251.241564) (xy 264.011097 -251.294971)
			(xy 263.987425 -251.345468) (xy 263.956652 -251.391981) (xy 263.919435 -251.433518) (xy 263.876567 -251.469193)
			(xy 263.828961 -251.498247) (xy 263.777632 -251.520059) (xy 263.723675 -251.534165) (xy 263.668238 -251.540265)
			(xy 263.612504 -251.538228) (xy 263.557661 -251.528098) (xy 263.504877 -251.510091) (xy 263.455277 -251.48459)
			(xy 263.409919 -251.452139) (xy 263.36977 -251.41343) (xy 263.335684 -251.369287) (xy 263.308388 -251.320652)
			(xy 263.288465 -251.268561) (xy 263.276339 -251.214124) (xy 263.272268 -251.158502) (xy 263.019794 -251.158502)
			(xy 263.019285 -251.186388) (xy 263.011165 -251.241564) (xy 262.995097 -251.294971) (xy 262.971425 -251.345468)
			(xy 262.940652 -251.391981) (xy 262.903435 -251.433518) (xy 262.860567 -251.469193) (xy 262.812961 -251.498247)
			(xy 262.761632 -251.520059) (xy 262.707675 -251.534165) (xy 262.652238 -251.540265) (xy 262.596504 -251.538228)
			(xy 262.541661 -251.528098) (xy 262.488877 -251.510091) (xy 262.439277 -251.48459) (xy 262.393919 -251.452139)
			(xy 262.35377 -251.41343) (xy 262.319684 -251.369287) (xy 262.292388 -251.320652) (xy 262.272465 -251.268561)
			(xy 262.260339 -251.214124) (xy 262.256268 -251.158502) (xy 262.003794 -251.158502) (xy 262.003285 -251.186388)
			(xy 261.995165 -251.241564) (xy 261.979097 -251.294971) (xy 261.955425 -251.345468) (xy 261.924652 -251.391981)
			(xy 261.887435 -251.433518) (xy 261.844567 -251.469193) (xy 261.796961 -251.498247) (xy 261.745632 -251.520059)
			(xy 261.691675 -251.534165) (xy 261.636238 -251.540265) (xy 261.580504 -251.538228) (xy 261.525661 -251.528098)
			(xy 261.472877 -251.510091) (xy 261.423277 -251.48459) (xy 261.377919 -251.452139) (xy 261.33777 -251.41343)
			(xy 261.303684 -251.369287) (xy 261.276388 -251.320652) (xy 261.256465 -251.268561) (xy 261.244339 -251.214124)
			(xy 261.240268 -251.158502) (xy 260.987794 -251.158502) (xy 260.987285 -251.186388) (xy 260.979165 -251.241564)
			(xy 260.963097 -251.294971) (xy 260.939425 -251.345468) (xy 260.908652 -251.391981) (xy 260.871435 -251.433518)
			(xy 260.828567 -251.469193) (xy 260.780961 -251.498247) (xy 260.729632 -251.520059) (xy 260.675675 -251.534165)
			(xy 260.620238 -251.540265) (xy 260.564504 -251.538228) (xy 260.509661 -251.528098) (xy 260.456877 -251.510091)
			(xy 260.407277 -251.48459) (xy 260.361919 -251.452139) (xy 260.32177 -251.41343) (xy 260.287684 -251.369287)
			(xy 260.260388 -251.320652) (xy 260.240465 -251.268561) (xy 260.228339 -251.214124) (xy 260.224268 -251.158502)
			(xy 259.971794 -251.158502) (xy 259.971285 -251.186388) (xy 259.963165 -251.241564) (xy 259.947097 -251.294971)
			(xy 259.923425 -251.345468) (xy 259.892652 -251.391981) (xy 259.855435 -251.433518) (xy 259.812567 -251.469193)
			(xy 259.764961 -251.498247) (xy 259.713632 -251.520059) (xy 259.659675 -251.534165) (xy 259.604238 -251.540265)
			(xy 259.548504 -251.538228) (xy 259.493661 -251.528098) (xy 259.440877 -251.510091) (xy 259.391277 -251.48459)
			(xy 259.345919 -251.452139) (xy 259.30577 -251.41343) (xy 259.271684 -251.369287) (xy 259.244388 -251.320652)
			(xy 259.224465 -251.268561) (xy 259.212339 -251.214124) (xy 259.208268 -251.158502) (xy 258.955794 -251.158502)
			(xy 258.955285 -251.186388) (xy 258.947165 -251.241564) (xy 258.931097 -251.294971) (xy 258.907425 -251.345468)
			(xy 258.876652 -251.391981) (xy 258.839435 -251.433518) (xy 258.796567 -251.469193) (xy 258.748961 -251.498247)
			(xy 258.697632 -251.520059) (xy 258.643675 -251.534165) (xy 258.588238 -251.540265) (xy 258.532504 -251.538228)
			(xy 258.477661 -251.528098) (xy 258.424877 -251.510091) (xy 258.375277 -251.48459) (xy 258.329919 -251.452139)
			(xy 258.28977 -251.41343) (xy 258.255684 -251.369287) (xy 258.228388 -251.320652) (xy 258.208465 -251.268561)
			(xy 258.196339 -251.214124) (xy 258.192268 -251.158502) (xy 257.939794 -251.158502) (xy 257.939285 -251.186388)
			(xy 257.931165 -251.241564) (xy 257.915097 -251.294971) (xy 257.891425 -251.345468) (xy 257.860652 -251.391981)
			(xy 257.823435 -251.433518) (xy 257.780567 -251.469193) (xy 257.732961 -251.498247) (xy 257.681632 -251.520059)
			(xy 257.627675 -251.534165) (xy 257.572238 -251.540265) (xy 257.516504 -251.538228) (xy 257.461661 -251.528098)
			(xy 257.408877 -251.510091) (xy 257.359277 -251.48459) (xy 257.313919 -251.452139) (xy 257.27377 -251.41343)
			(xy 257.239684 -251.369287) (xy 257.212388 -251.320652) (xy 257.192465 -251.268561) (xy 257.180339 -251.214124)
			(xy 257.176268 -251.158502) (xy 256.810481 -251.158502) (xy 256.810764 -251.173996) (xy 256.810255 -251.201882)
			(xy 256.802135 -251.257058) (xy 256.786067 -251.310465) (xy 256.762395 -251.360962) (xy 256.731622 -251.407475)
			(xy 256.694405 -251.449012) (xy 256.651537 -251.484687) (xy 256.603931 -251.513741) (xy 256.552602 -251.535553)
			(xy 256.498645 -251.549659) (xy 256.443208 -251.555759) (xy 256.387474 -251.553722) (xy 256.332631 -251.543592)
			(xy 256.279847 -251.525585) (xy 256.230247 -251.500084) (xy 256.184889 -251.467633) (xy 256.14474 -251.428924)
			(xy 256.110654 -251.384781) (xy 256.083358 -251.336146) (xy 256.063435 -251.284055) (xy 256.051309 -251.229618)
			(xy 256.047238 -251.173996) (xy 246.394732 -251.173996) (xy 246.394732 -251.813568) (xy 246.394986 -251.817632)
			(xy 246.394986 -251.81814) (xy 246.39639 -251.828324) (xy 246.406089 -251.846431) (xy 246.422063 -251.859345)
			(xy 246.431816 -251.86259) (xy 246.43207 -251.86259) (xy 246.458555 -251.870396) (xy 246.509113 -251.892585)
			(xy 246.555944 -251.921831) (xy 246.598071 -251.957522) (xy 246.634613 -251.998912) (xy 246.664808 -252.045138)
			(xy 246.688023 -252.095233) (xy 246.703775 -252.148152) (xy 246.711735 -252.202789) (xy 246.711735 -252.258002)
			(xy 246.703777 -252.312639) (xy 246.688027 -252.365558) (xy 246.664812 -252.415654) (xy 246.634619 -252.46188)
			(xy 246.598078 -252.503271) (xy 246.555952 -252.538963) (xy 246.509121 -252.56821) (xy 246.458564 -252.590401)
			(xy 246.43207 -252.598174) (xy 246.431816 -252.598174) (xy 246.422036 -252.601387) (xy 246.405998 -252.61426)
			(xy 246.396344 -252.632419) (xy 246.394986 -252.642624) (xy 246.394986 -252.643132) (xy 246.394732 -252.647196)
			(xy 246.394732 -253.5174) (xy 256.160268 -253.5174) (xy 256.164339 -253.461778) (xy 256.176465 -253.407341)
			(xy 256.196388 -253.35525) (xy 256.223684 -253.306615) (xy 256.25777 -253.262472) (xy 256.297919 -253.223763)
			(xy 256.343277 -253.191312) (xy 256.392877 -253.165811) (xy 256.445661 -253.147804) (xy 256.500504 -253.137674)
			(xy 256.556238 -253.135637) (xy 256.611675 -253.141737) (xy 256.665632 -253.155843) (xy 256.716961 -253.177655)
			(xy 256.764567 -253.206709) (xy 256.807435 -253.242384) (xy 256.844652 -253.283921) (xy 256.875425 -253.330434)
			(xy 256.899097 -253.380931) (xy 256.915165 -253.434338) (xy 256.918418 -253.45644) (xy 257.176268 -253.45644)
			(xy 257.180339 -253.400818) (xy 257.192465 -253.346381) (xy 257.212388 -253.29429) (xy 257.239684 -253.245655)
			(xy 257.27377 -253.201512) (xy 257.313919 -253.162803) (xy 257.359277 -253.130352) (xy 257.408877 -253.104851)
			(xy 257.461661 -253.086844) (xy 257.516504 -253.076714) (xy 257.572238 -253.074677) (xy 257.627675 -253.080777)
			(xy 257.681632 -253.094883) (xy 257.732961 -253.116695) (xy 257.780567 -253.145749) (xy 257.823435 -253.181424)
			(xy 257.860652 -253.222961) (xy 257.891425 -253.269474) (xy 257.915097 -253.319971) (xy 257.931165 -253.373378)
			(xy 257.939285 -253.428554) (xy 257.939794 -253.45644) (xy 258.192268 -253.45644) (xy 258.196339 -253.400818)
			(xy 258.208465 -253.346381) (xy 258.228388 -253.29429) (xy 258.255684 -253.245655) (xy 258.28977 -253.201512)
			(xy 258.329919 -253.162803) (xy 258.375277 -253.130352) (xy 258.424877 -253.104851) (xy 258.477661 -253.086844)
			(xy 258.532504 -253.076714) (xy 258.588238 -253.074677) (xy 258.643675 -253.080777) (xy 258.697632 -253.094883)
			(xy 258.748961 -253.116695) (xy 258.796567 -253.145749) (xy 258.839435 -253.181424) (xy 258.876652 -253.222961)
			(xy 258.907425 -253.269474) (xy 258.931097 -253.319971) (xy 258.947165 -253.373378) (xy 258.955285 -253.428554)
			(xy 258.955794 -253.45644) (xy 259.208268 -253.45644) (xy 259.212339 -253.400818) (xy 259.224465 -253.346381)
			(xy 259.244388 -253.29429) (xy 259.271684 -253.245655) (xy 259.30577 -253.201512) (xy 259.345919 -253.162803)
			(xy 259.391277 -253.130352) (xy 259.440877 -253.104851) (xy 259.493661 -253.086844) (xy 259.548504 -253.076714)
			(xy 259.604238 -253.074677) (xy 259.659675 -253.080777) (xy 259.713632 -253.094883) (xy 259.764961 -253.116695)
			(xy 259.812567 -253.145749) (xy 259.855435 -253.181424) (xy 259.892652 -253.222961) (xy 259.923425 -253.269474)
			(xy 259.947097 -253.319971) (xy 259.963165 -253.373378) (xy 259.971285 -253.428554) (xy 259.971794 -253.45644)
			(xy 260.224268 -253.45644) (xy 260.228339 -253.400818) (xy 260.240465 -253.346381) (xy 260.260388 -253.29429)
			(xy 260.287684 -253.245655) (xy 260.32177 -253.201512) (xy 260.361919 -253.162803) (xy 260.407277 -253.130352)
			(xy 260.456877 -253.104851) (xy 260.509661 -253.086844) (xy 260.564504 -253.076714) (xy 260.620238 -253.074677)
			(xy 260.675675 -253.080777) (xy 260.729632 -253.094883) (xy 260.780961 -253.116695) (xy 260.828567 -253.145749)
			(xy 260.871435 -253.181424) (xy 260.908652 -253.222961) (xy 260.939425 -253.269474) (xy 260.963097 -253.319971)
			(xy 260.979165 -253.373378) (xy 260.987285 -253.428554) (xy 260.987794 -253.45644) (xy 261.240268 -253.45644)
			(xy 261.244339 -253.400818) (xy 261.256465 -253.346381) (xy 261.276388 -253.29429) (xy 261.303684 -253.245655)
			(xy 261.33777 -253.201512) (xy 261.377919 -253.162803) (xy 261.423277 -253.130352) (xy 261.472877 -253.104851)
			(xy 261.525661 -253.086844) (xy 261.580504 -253.076714) (xy 261.636238 -253.074677) (xy 261.691675 -253.080777)
			(xy 261.745632 -253.094883) (xy 261.796961 -253.116695) (xy 261.844567 -253.145749) (xy 261.887435 -253.181424)
			(xy 261.924652 -253.222961) (xy 261.955425 -253.269474) (xy 261.979097 -253.319971) (xy 261.995165 -253.373378)
			(xy 262.003285 -253.428554) (xy 262.003794 -253.45644) (xy 262.256268 -253.45644) (xy 262.260339 -253.400818)
			(xy 262.272465 -253.346381) (xy 262.292388 -253.29429) (xy 262.319684 -253.245655) (xy 262.35377 -253.201512)
			(xy 262.393919 -253.162803) (xy 262.439277 -253.130352) (xy 262.488877 -253.104851) (xy 262.541661 -253.086844)
			(xy 262.596504 -253.076714) (xy 262.652238 -253.074677) (xy 262.707675 -253.080777) (xy 262.761632 -253.094883)
			(xy 262.812961 -253.116695) (xy 262.860567 -253.145749) (xy 262.903435 -253.181424) (xy 262.940652 -253.222961)
			(xy 262.971425 -253.269474) (xy 262.995097 -253.319971) (xy 263.011165 -253.373378) (xy 263.019285 -253.428554)
			(xy 263.019794 -253.45644) (xy 263.272268 -253.45644) (xy 263.276339 -253.400818) (xy 263.288465 -253.346381)
			(xy 263.308388 -253.29429) (xy 263.335684 -253.245655) (xy 263.36977 -253.201512) (xy 263.409919 -253.162803)
			(xy 263.455277 -253.130352) (xy 263.504877 -253.104851) (xy 263.557661 -253.086844) (xy 263.612504 -253.076714)
			(xy 263.668238 -253.074677) (xy 263.723675 -253.080777) (xy 263.777632 -253.094883) (xy 263.828961 -253.116695)
			(xy 263.876567 -253.145749) (xy 263.919435 -253.181424) (xy 263.956652 -253.222961) (xy 263.987425 -253.269474)
			(xy 264.011097 -253.319971) (xy 264.027165 -253.373378) (xy 264.035285 -253.428554) (xy 264.035794 -253.45644)
			(xy 264.288268 -253.45644) (xy 264.292339 -253.400818) (xy 264.304465 -253.346381) (xy 264.324388 -253.29429)
			(xy 264.351684 -253.245655) (xy 264.38577 -253.201512) (xy 264.425919 -253.162803) (xy 264.471277 -253.130352)
			(xy 264.520877 -253.104851) (xy 264.573661 -253.086844) (xy 264.628504 -253.076714) (xy 264.684238 -253.074677)
			(xy 264.739675 -253.080777) (xy 264.793632 -253.094883) (xy 264.844961 -253.116695) (xy 264.892567 -253.145749)
			(xy 264.935435 -253.181424) (xy 264.972652 -253.222961) (xy 265.003425 -253.269474) (xy 265.027097 -253.319971)
			(xy 265.043165 -253.373378) (xy 265.051285 -253.428554) (xy 265.051794 -253.45644) (xy 265.304268 -253.45644)
			(xy 265.308339 -253.400818) (xy 265.320465 -253.346381) (xy 265.340388 -253.29429) (xy 265.367684 -253.245655)
			(xy 265.40177 -253.201512) (xy 265.441919 -253.162803) (xy 265.487277 -253.130352) (xy 265.536877 -253.104851)
			(xy 265.589661 -253.086844) (xy 265.644504 -253.076714) (xy 265.700238 -253.074677) (xy 265.755675 -253.080777)
			(xy 265.809632 -253.094883) (xy 265.860961 -253.116695) (xy 265.908567 -253.145749) (xy 265.951435 -253.181424)
			(xy 265.988652 -253.222961) (xy 266.019425 -253.269474) (xy 266.043097 -253.319971) (xy 266.059165 -253.373378)
			(xy 266.067285 -253.428554) (xy 266.067794 -253.45644) (xy 266.320268 -253.45644) (xy 266.324339 -253.400818)
			(xy 266.336465 -253.346381) (xy 266.356388 -253.29429) (xy 266.383684 -253.245655) (xy 266.41777 -253.201512)
			(xy 266.457919 -253.162803) (xy 266.503277 -253.130352) (xy 266.552877 -253.104851) (xy 266.605661 -253.086844)
			(xy 266.660504 -253.076714) (xy 266.716238 -253.074677) (xy 266.771675 -253.080777) (xy 266.825632 -253.094883)
			(xy 266.876961 -253.116695) (xy 266.924567 -253.145749) (xy 266.967435 -253.181424) (xy 267.004652 -253.222961)
			(xy 267.035425 -253.269474) (xy 267.059097 -253.319971) (xy 267.075165 -253.373378) (xy 267.083285 -253.428554)
			(xy 267.083794 -253.45644) (xy 267.336268 -253.45644) (xy 267.340339 -253.400818) (xy 267.352465 -253.346381)
			(xy 267.372388 -253.29429) (xy 267.399684 -253.245655) (xy 267.43377 -253.201512) (xy 267.473919 -253.162803)
			(xy 267.519277 -253.130352) (xy 267.568877 -253.104851) (xy 267.621661 -253.086844) (xy 267.676504 -253.076714)
			(xy 267.732238 -253.074677) (xy 267.787675 -253.080777) (xy 267.841632 -253.094883) (xy 267.892961 -253.116695)
			(xy 267.940567 -253.145749) (xy 267.983435 -253.181424) (xy 268.020652 -253.222961) (xy 268.051425 -253.269474)
			(xy 268.075097 -253.319971) (xy 268.091165 -253.373378) (xy 268.099285 -253.428554) (xy 268.099794 -253.45644)
			(xy 268.352268 -253.45644) (xy 268.356339 -253.400818) (xy 268.368465 -253.346381) (xy 268.388388 -253.29429)
			(xy 268.415684 -253.245655) (xy 268.44977 -253.201512) (xy 268.489919 -253.162803) (xy 268.535277 -253.130352)
			(xy 268.584877 -253.104851) (xy 268.637661 -253.086844) (xy 268.692504 -253.076714) (xy 268.748238 -253.074677)
			(xy 268.803675 -253.080777) (xy 268.857632 -253.094883) (xy 268.908961 -253.116695) (xy 268.956567 -253.145749)
			(xy 268.999435 -253.181424) (xy 269.036652 -253.222961) (xy 269.067425 -253.269474) (xy 269.091097 -253.319971)
			(xy 269.107165 -253.373378) (xy 269.115285 -253.428554) (xy 269.115794 -253.45644) (xy 269.368268 -253.45644)
			(xy 269.372339 -253.400818) (xy 269.384465 -253.346381) (xy 269.404388 -253.29429) (xy 269.431684 -253.245655)
			(xy 269.46577 -253.201512) (xy 269.505919 -253.162803) (xy 269.551277 -253.130352) (xy 269.600877 -253.104851)
			(xy 269.653661 -253.086844) (xy 269.708504 -253.076714) (xy 269.764238 -253.074677) (xy 269.819675 -253.080777)
			(xy 269.873632 -253.094883) (xy 269.924961 -253.116695) (xy 269.972567 -253.145749) (xy 270.015435 -253.181424)
			(xy 270.052652 -253.222961) (xy 270.083425 -253.269474) (xy 270.107097 -253.319971) (xy 270.123165 -253.373378)
			(xy 270.131285 -253.428554) (xy 270.131794 -253.45644) (xy 270.384268 -253.45644) (xy 270.388339 -253.400818)
			(xy 270.400465 -253.346381) (xy 270.420388 -253.29429) (xy 270.447684 -253.245655) (xy 270.48177 -253.201512)
			(xy 270.521919 -253.162803) (xy 270.567277 -253.130352) (xy 270.616877 -253.104851) (xy 270.669661 -253.086844)
			(xy 270.724504 -253.076714) (xy 270.780238 -253.074677) (xy 270.835675 -253.080777) (xy 270.889632 -253.094883)
			(xy 270.940961 -253.116695) (xy 270.988567 -253.145749) (xy 271.031435 -253.181424) (xy 271.068652 -253.222961)
			(xy 271.099425 -253.269474) (xy 271.123097 -253.319971) (xy 271.139165 -253.373378) (xy 271.147285 -253.428554)
			(xy 271.147794 -253.45644) (xy 271.400268 -253.45644) (xy 271.404339 -253.400818) (xy 271.416465 -253.346381)
			(xy 271.436388 -253.29429) (xy 271.463684 -253.245655) (xy 271.49777 -253.201512) (xy 271.537919 -253.162803)
			(xy 271.583277 -253.130352) (xy 271.632877 -253.104851) (xy 271.685661 -253.086844) (xy 271.740504 -253.076714)
			(xy 271.796238 -253.074677) (xy 271.851675 -253.080777) (xy 271.905632 -253.094883) (xy 271.956961 -253.116695)
			(xy 272.004567 -253.145749) (xy 272.047435 -253.181424) (xy 272.084652 -253.222961) (xy 272.115425 -253.269474)
			(xy 272.139097 -253.319971) (xy 272.155165 -253.373378) (xy 272.163285 -253.428554) (xy 272.163794 -253.45644)
			(xy 272.163285 -253.484326) (xy 272.155165 -253.539502) (xy 272.139097 -253.592909) (xy 272.115425 -253.643406)
			(xy 272.084652 -253.689919) (xy 272.047435 -253.731456) (xy 272.004567 -253.767131) (xy 271.956961 -253.796185)
			(xy 271.905632 -253.817997) (xy 271.851675 -253.832103) (xy 271.796238 -253.838203) (xy 271.740504 -253.836166)
			(xy 271.685661 -253.826036) (xy 271.632877 -253.808029) (xy 271.583277 -253.782528) (xy 271.537919 -253.750077)
			(xy 271.49777 -253.711368) (xy 271.463684 -253.667225) (xy 271.436388 -253.61859) (xy 271.416465 -253.566499)
			(xy 271.404339 -253.512062) (xy 271.400268 -253.45644) (xy 271.147794 -253.45644) (xy 271.147285 -253.484326)
			(xy 271.139165 -253.539502) (xy 271.123097 -253.592909) (xy 271.099425 -253.643406) (xy 271.068652 -253.689919)
			(xy 271.031435 -253.731456) (xy 270.988567 -253.767131) (xy 270.940961 -253.796185) (xy 270.889632 -253.817997)
			(xy 270.835675 -253.832103) (xy 270.780238 -253.838203) (xy 270.724504 -253.836166) (xy 270.669661 -253.826036)
			(xy 270.616877 -253.808029) (xy 270.567277 -253.782528) (xy 270.521919 -253.750077) (xy 270.48177 -253.711368)
			(xy 270.447684 -253.667225) (xy 270.420388 -253.61859) (xy 270.400465 -253.566499) (xy 270.388339 -253.512062)
			(xy 270.384268 -253.45644) (xy 270.131794 -253.45644) (xy 270.131285 -253.484326) (xy 270.123165 -253.539502)
			(xy 270.107097 -253.592909) (xy 270.083425 -253.643406) (xy 270.052652 -253.689919) (xy 270.015435 -253.731456)
			(xy 269.972567 -253.767131) (xy 269.924961 -253.796185) (xy 269.873632 -253.817997) (xy 269.819675 -253.832103)
			(xy 269.764238 -253.838203) (xy 269.708504 -253.836166) (xy 269.653661 -253.826036) (xy 269.600877 -253.808029)
			(xy 269.551277 -253.782528) (xy 269.505919 -253.750077) (xy 269.46577 -253.711368) (xy 269.431684 -253.667225)
			(xy 269.404388 -253.61859) (xy 269.384465 -253.566499) (xy 269.372339 -253.512062) (xy 269.368268 -253.45644)
			(xy 269.115794 -253.45644) (xy 269.115285 -253.484326) (xy 269.107165 -253.539502) (xy 269.091097 -253.592909)
			(xy 269.067425 -253.643406) (xy 269.036652 -253.689919) (xy 268.999435 -253.731456) (xy 268.956567 -253.767131)
			(xy 268.908961 -253.796185) (xy 268.857632 -253.817997) (xy 268.803675 -253.832103) (xy 268.748238 -253.838203)
			(xy 268.692504 -253.836166) (xy 268.637661 -253.826036) (xy 268.584877 -253.808029) (xy 268.535277 -253.782528)
			(xy 268.489919 -253.750077) (xy 268.44977 -253.711368) (xy 268.415684 -253.667225) (xy 268.388388 -253.61859)
			(xy 268.368465 -253.566499) (xy 268.356339 -253.512062) (xy 268.352268 -253.45644) (xy 268.099794 -253.45644)
			(xy 268.099285 -253.484326) (xy 268.091165 -253.539502) (xy 268.075097 -253.592909) (xy 268.051425 -253.643406)
			(xy 268.020652 -253.689919) (xy 267.983435 -253.731456) (xy 267.940567 -253.767131) (xy 267.892961 -253.796185)
			(xy 267.841632 -253.817997) (xy 267.787675 -253.832103) (xy 267.732238 -253.838203) (xy 267.676504 -253.836166)
			(xy 267.621661 -253.826036) (xy 267.568877 -253.808029) (xy 267.519277 -253.782528) (xy 267.473919 -253.750077)
			(xy 267.43377 -253.711368) (xy 267.399684 -253.667225) (xy 267.372388 -253.61859) (xy 267.352465 -253.566499)
			(xy 267.340339 -253.512062) (xy 267.336268 -253.45644) (xy 267.083794 -253.45644) (xy 267.083285 -253.484326)
			(xy 267.075165 -253.539502) (xy 267.059097 -253.592909) (xy 267.035425 -253.643406) (xy 267.004652 -253.689919)
			(xy 266.967435 -253.731456) (xy 266.924567 -253.767131) (xy 266.876961 -253.796185) (xy 266.825632 -253.817997)
			(xy 266.771675 -253.832103) (xy 266.716238 -253.838203) (xy 266.660504 -253.836166) (xy 266.605661 -253.826036)
			(xy 266.552877 -253.808029) (xy 266.503277 -253.782528) (xy 266.457919 -253.750077) (xy 266.41777 -253.711368)
			(xy 266.383684 -253.667225) (xy 266.356388 -253.61859) (xy 266.336465 -253.566499) (xy 266.324339 -253.512062)
			(xy 266.320268 -253.45644) (xy 266.067794 -253.45644) (xy 266.067285 -253.484326) (xy 266.059165 -253.539502)
			(xy 266.043097 -253.592909) (xy 266.019425 -253.643406) (xy 265.988652 -253.689919) (xy 265.951435 -253.731456)
			(xy 265.908567 -253.767131) (xy 265.860961 -253.796185) (xy 265.809632 -253.817997) (xy 265.755675 -253.832103)
			(xy 265.700238 -253.838203) (xy 265.644504 -253.836166) (xy 265.589661 -253.826036) (xy 265.536877 -253.808029)
			(xy 265.487277 -253.782528) (xy 265.441919 -253.750077) (xy 265.40177 -253.711368) (xy 265.367684 -253.667225)
			(xy 265.340388 -253.61859) (xy 265.320465 -253.566499) (xy 265.308339 -253.512062) (xy 265.304268 -253.45644)
			(xy 265.051794 -253.45644) (xy 265.051285 -253.484326) (xy 265.043165 -253.539502) (xy 265.027097 -253.592909)
			(xy 265.003425 -253.643406) (xy 264.972652 -253.689919) (xy 264.935435 -253.731456) (xy 264.892567 -253.767131)
			(xy 264.844961 -253.796185) (xy 264.793632 -253.817997) (xy 264.739675 -253.832103) (xy 264.684238 -253.838203)
			(xy 264.628504 -253.836166) (xy 264.573661 -253.826036) (xy 264.520877 -253.808029) (xy 264.471277 -253.782528)
			(xy 264.425919 -253.750077) (xy 264.38577 -253.711368) (xy 264.351684 -253.667225) (xy 264.324388 -253.61859)
			(xy 264.304465 -253.566499) (xy 264.292339 -253.512062) (xy 264.288268 -253.45644) (xy 264.035794 -253.45644)
			(xy 264.035285 -253.484326) (xy 264.027165 -253.539502) (xy 264.011097 -253.592909) (xy 263.987425 -253.643406)
			(xy 263.956652 -253.689919) (xy 263.919435 -253.731456) (xy 263.876567 -253.767131) (xy 263.828961 -253.796185)
			(xy 263.777632 -253.817997) (xy 263.723675 -253.832103) (xy 263.668238 -253.838203) (xy 263.612504 -253.836166)
			(xy 263.557661 -253.826036) (xy 263.504877 -253.808029) (xy 263.455277 -253.782528) (xy 263.409919 -253.750077)
			(xy 263.36977 -253.711368) (xy 263.335684 -253.667225) (xy 263.308388 -253.61859) (xy 263.288465 -253.566499)
			(xy 263.276339 -253.512062) (xy 263.272268 -253.45644) (xy 263.019794 -253.45644) (xy 263.019285 -253.484326)
			(xy 263.011165 -253.539502) (xy 262.995097 -253.592909) (xy 262.971425 -253.643406) (xy 262.940652 -253.689919)
			(xy 262.903435 -253.731456) (xy 262.860567 -253.767131) (xy 262.812961 -253.796185) (xy 262.761632 -253.817997)
			(xy 262.707675 -253.832103) (xy 262.652238 -253.838203) (xy 262.596504 -253.836166) (xy 262.541661 -253.826036)
			(xy 262.488877 -253.808029) (xy 262.439277 -253.782528) (xy 262.393919 -253.750077) (xy 262.35377 -253.711368)
			(xy 262.319684 -253.667225) (xy 262.292388 -253.61859) (xy 262.272465 -253.566499) (xy 262.260339 -253.512062)
			(xy 262.256268 -253.45644) (xy 262.003794 -253.45644) (xy 262.003285 -253.484326) (xy 261.995165 -253.539502)
			(xy 261.979097 -253.592909) (xy 261.955425 -253.643406) (xy 261.924652 -253.689919) (xy 261.887435 -253.731456)
			(xy 261.844567 -253.767131) (xy 261.796961 -253.796185) (xy 261.745632 -253.817997) (xy 261.691675 -253.832103)
			(xy 261.636238 -253.838203) (xy 261.580504 -253.836166) (xy 261.525661 -253.826036) (xy 261.472877 -253.808029)
			(xy 261.423277 -253.782528) (xy 261.377919 -253.750077) (xy 261.33777 -253.711368) (xy 261.303684 -253.667225)
			(xy 261.276388 -253.61859) (xy 261.256465 -253.566499) (xy 261.244339 -253.512062) (xy 261.240268 -253.45644)
			(xy 260.987794 -253.45644) (xy 260.987285 -253.484326) (xy 260.979165 -253.539502) (xy 260.963097 -253.592909)
			(xy 260.939425 -253.643406) (xy 260.908652 -253.689919) (xy 260.871435 -253.731456) (xy 260.828567 -253.767131)
			(xy 260.780961 -253.796185) (xy 260.729632 -253.817997) (xy 260.675675 -253.832103) (xy 260.620238 -253.838203)
			(xy 260.564504 -253.836166) (xy 260.509661 -253.826036) (xy 260.456877 -253.808029) (xy 260.407277 -253.782528)
			(xy 260.361919 -253.750077) (xy 260.32177 -253.711368) (xy 260.287684 -253.667225) (xy 260.260388 -253.61859)
			(xy 260.240465 -253.566499) (xy 260.228339 -253.512062) (xy 260.224268 -253.45644) (xy 259.971794 -253.45644)
			(xy 259.971285 -253.484326) (xy 259.963165 -253.539502) (xy 259.947097 -253.592909) (xy 259.923425 -253.643406)
			(xy 259.892652 -253.689919) (xy 259.855435 -253.731456) (xy 259.812567 -253.767131) (xy 259.764961 -253.796185)
			(xy 259.713632 -253.817997) (xy 259.659675 -253.832103) (xy 259.604238 -253.838203) (xy 259.548504 -253.836166)
			(xy 259.493661 -253.826036) (xy 259.440877 -253.808029) (xy 259.391277 -253.782528) (xy 259.345919 -253.750077)
			(xy 259.30577 -253.711368) (xy 259.271684 -253.667225) (xy 259.244388 -253.61859) (xy 259.224465 -253.566499)
			(xy 259.212339 -253.512062) (xy 259.208268 -253.45644) (xy 258.955794 -253.45644) (xy 258.955285 -253.484326)
			(xy 258.947165 -253.539502) (xy 258.931097 -253.592909) (xy 258.907425 -253.643406) (xy 258.876652 -253.689919)
			(xy 258.839435 -253.731456) (xy 258.796567 -253.767131) (xy 258.748961 -253.796185) (xy 258.697632 -253.817997)
			(xy 258.643675 -253.832103) (xy 258.588238 -253.838203) (xy 258.532504 -253.836166) (xy 258.477661 -253.826036)
			(xy 258.424877 -253.808029) (xy 258.375277 -253.782528) (xy 258.329919 -253.750077) (xy 258.28977 -253.711368)
			(xy 258.255684 -253.667225) (xy 258.228388 -253.61859) (xy 258.208465 -253.566499) (xy 258.196339 -253.512062)
			(xy 258.192268 -253.45644) (xy 257.939794 -253.45644) (xy 257.939285 -253.484326) (xy 257.931165 -253.539502)
			(xy 257.915097 -253.592909) (xy 257.891425 -253.643406) (xy 257.860652 -253.689919) (xy 257.823435 -253.731456)
			(xy 257.780567 -253.767131) (xy 257.732961 -253.796185) (xy 257.681632 -253.817997) (xy 257.627675 -253.832103)
			(xy 257.572238 -253.838203) (xy 257.516504 -253.836166) (xy 257.461661 -253.826036) (xy 257.408877 -253.808029)
			(xy 257.359277 -253.782528) (xy 257.313919 -253.750077) (xy 257.27377 -253.711368) (xy 257.239684 -253.667225)
			(xy 257.212388 -253.61859) (xy 257.192465 -253.566499) (xy 257.180339 -253.512062) (xy 257.176268 -253.45644)
			(xy 256.918418 -253.45644) (xy 256.923285 -253.489514) (xy 256.923794 -253.5174) (xy 256.923285 -253.545286)
			(xy 256.915165 -253.600462) (xy 256.899097 -253.653869) (xy 256.875425 -253.704366) (xy 256.844652 -253.750879)
			(xy 256.807435 -253.792416) (xy 256.764567 -253.828091) (xy 256.716961 -253.857145) (xy 256.665632 -253.878957)
			(xy 256.611675 -253.893063) (xy 256.556238 -253.899163) (xy 256.500504 -253.897126) (xy 256.445661 -253.886996)
			(xy 256.392877 -253.868989) (xy 256.343277 -253.843488) (xy 256.297919 -253.811037) (xy 256.25777 -253.772328)
			(xy 256.223684 -253.728185) (xy 256.196388 -253.67955) (xy 256.176465 -253.627459) (xy 256.164339 -253.573022)
			(xy 256.160268 -253.5174) (xy 246.394732 -253.5174) (xy 246.394732 -254.687832) (xy 246.395047 -254.696023)
			(xy 246.400239 -254.711562) (xy 246.404892 -254.718312) (xy 246.409718 -254.7239) (xy 247.596406 -255.910588)
			(xy 254.076452 -255.910588) (xy 254.080523 -255.854966) (xy 254.092649 -255.800529) (xy 254.112572 -255.748438)
			(xy 254.139868 -255.699803) (xy 254.173954 -255.65566) (xy 254.214103 -255.616951) (xy 254.259461 -255.5845)
			(xy 254.309061 -255.558999) (xy 254.361845 -255.540992) (xy 254.416688 -255.530862) (xy 254.472422 -255.528825)
			(xy 254.527859 -255.534925) (xy 254.581816 -255.549031) (xy 254.633145 -255.570843) (xy 254.680751 -255.599897)
			(xy 254.723619 -255.635572) (xy 254.760836 -255.677109) (xy 254.771645 -255.693446) (xy 254.965518 -255.693446)
			(xy 254.965518 -255.638954) (xy 254.973273 -255.585016) (xy 254.988624 -255.53273) (xy 255.011259 -255.483161)
			(xy 255.040718 -255.437318) (xy 255.076401 -255.396133) (xy 255.117581 -255.360446) (xy 255.163421 -255.330981)
			(xy 255.212987 -255.30834) (xy 255.265271 -255.292982) (xy 255.319208 -255.285221) (xy 255.346454 -255.284732)
			(xy 255.375406 -255.285311) (xy 255.432644 -255.294062) (xy 255.487905 -255.311355) (xy 255.539922 -255.336794)
			(xy 255.587501 -255.369795) (xy 255.629551 -255.409601) (xy 255.665109 -255.455301) (xy 255.679702 -255.480312)
			(xy 255.687514 -255.493171) (xy 255.709168 -255.514037) (xy 255.735961 -255.527688) (xy 255.76557 -255.53294)
			(xy 255.795424 -255.529337) (xy 255.822933 -255.517192) (xy 255.84571 -255.497559) (xy 255.8542 -255.485138)
			(xy 255.86928 -255.462141) (xy 255.904987 -255.420317) (xy 255.946327 -255.384051) (xy 255.992445 -255.354095)
			(xy 256.042385 -255.33107) (xy 256.095113 -255.31545) (xy 256.149538 -255.307562) (xy 256.177034 -255.307084)
			(xy 256.204283 -255.307588) (xy 256.258226 -255.315348) (xy 256.310516 -255.330706) (xy 256.360087 -255.353349)
			(xy 256.405933 -255.382815) (xy 256.447118 -255.418506) (xy 256.482805 -255.459695) (xy 256.512268 -255.505542)
			(xy 256.534906 -255.555116) (xy 256.550259 -255.607407) (xy 256.558014 -255.661351) (xy 256.558014 -255.715849)
			(xy 256.550259 -255.769793) (xy 256.534906 -255.822084) (xy 256.512268 -255.871658) (xy 256.482805 -255.917505)
			(xy 256.447118 -255.958694) (xy 256.405933 -255.994385) (xy 256.360087 -256.023851) (xy 256.310516 -256.046494)
			(xy 256.258226 -256.061852) (xy 256.204283 -256.069612) (xy 256.177034 -256.0701) (xy 256.14808 -256.069566)
			(xy 256.090838 -256.060811) (xy 256.035574 -256.043513) (xy 255.983556 -256.018067) (xy 255.935978 -255.985059)
			(xy 255.893929 -255.945243) (xy 255.858376 -255.899535) (xy 255.843786 -255.87452) (xy 255.835988 -255.861655)
			(xy 255.814326 -255.840802) (xy 255.787531 -255.82716) (xy 255.757924 -255.821913) (xy 255.728073 -255.825516)
			(xy 255.700564 -255.837655) (xy 255.677783 -255.857279) (xy 255.669288 -255.869694) (xy 255.654227 -255.892704)
			(xy 255.618516 -255.934526) (xy 255.577171 -255.97079) (xy 255.53105 -256.000744) (xy 255.481107 -256.023767)
			(xy 255.428377 -256.039384) (xy 255.373951 -256.047271) (xy 255.346454 -256.047748) (xy 255.319208 -256.047179)
			(xy 255.265271 -256.039418) (xy 255.212987 -256.02406) (xy 255.163421 -256.001419) (xy 255.117581 -255.971954)
			(xy 255.076401 -255.936267) (xy 255.040718 -255.895082) (xy 255.011259 -255.849239) (xy 254.988624 -255.79967)
			(xy 254.973273 -255.747384) (xy 254.965518 -255.693446) (xy 254.771645 -255.693446) (xy 254.791609 -255.723622)
			(xy 254.815281 -255.774119) (xy 254.831349 -255.827526) (xy 254.839469 -255.882702) (xy 254.839978 -255.910588)
			(xy 254.839469 -255.938474) (xy 254.831349 -255.99365) (xy 254.815281 -256.047057) (xy 254.791609 -256.097554)
			(xy 254.760836 -256.144067) (xy 254.723619 -256.185604) (xy 254.680751 -256.221279) (xy 254.633145 -256.250333)
			(xy 254.581816 -256.272145) (xy 254.527859 -256.286251) (xy 254.472422 -256.292351) (xy 254.416688 -256.290314)
			(xy 254.361845 -256.280184) (xy 254.309061 -256.262177) (xy 254.259461 -256.236676) (xy 254.214103 -256.204225)
			(xy 254.173954 -256.165516) (xy 254.139868 -256.121373) (xy 254.112572 -256.072738) (xy 254.092649 -256.020647)
			(xy 254.080523 -255.96621) (xy 254.076452 -255.910588) (xy 247.596406 -255.910588) (xy 248.165471 -256.479653)
			(xy 257.479248 -256.479653) (xy 257.479248 -256.425147) (xy 257.487005 -256.371196) (xy 257.502361 -256.318897)
			(xy 257.525003 -256.269317) (xy 257.554471 -256.223463) (xy 257.590164 -256.18227) (xy 257.631357 -256.146576)
			(xy 257.67721 -256.117107) (xy 257.72679 -256.094463) (xy 257.779088 -256.079106) (xy 257.833039 -256.071348)
			(xy 257.860292 -256.070862) (xy 257.886607 -256.071315) (xy 257.938737 -256.07855) (xy 257.98938 -256.092871)
			(xy 258.03758 -256.114006) (xy 258.082423 -256.141555) (xy 258.123061 -256.174998) (xy 258.141216 -256.194052)
			(xy 258.148736 -256.201455) (xy 258.168017 -256.20998) (xy 258.178554 -256.210562) (xy 258.25323 -256.210562)
			(xy 258.263778 -256.21002) (xy 258.283075 -256.201495) (xy 258.290568 -256.194052) (xy 258.308688 -256.174961)
			(xy 258.349326 -256.141509) (xy 258.394175 -256.113956) (xy 258.442382 -256.092824) (xy 258.493035 -256.078514)
			(xy 258.545174 -256.071297) (xy 258.571492 -256.070862) (xy 258.598743 -256.071385) (xy 258.652691 -256.07914)
			(xy 258.704985 -256.094494) (xy 258.713862 -256.098548) (xy 260.081774 -256.098548) (xy 260.085845 -256.042926)
			(xy 260.097971 -255.988489) (xy 260.117894 -255.936398) (xy 260.14519 -255.887763) (xy 260.179276 -255.84362)
			(xy 260.219425 -255.804911) (xy 260.264783 -255.77246) (xy 260.314383 -255.746959) (xy 260.367167 -255.728952)
			(xy 260.42201 -255.718822) (xy 260.477744 -255.716785) (xy 260.533181 -255.722885) (xy 260.587138 -255.736991)
			(xy 260.638467 -255.758803) (xy 260.686073 -255.787857) (xy 260.728941 -255.823532) (xy 260.766158 -255.865069)
			(xy 260.796931 -255.911582) (xy 260.820603 -255.962079) (xy 260.836671 -256.015486) (xy 260.844791 -256.070662)
			(xy 260.8453 -256.098548) (xy 260.844791 -256.126434) (xy 260.836671 -256.18161) (xy 260.820603 -256.235017)
			(xy 260.796931 -256.285514) (xy 260.766158 -256.332027) (xy 260.728941 -256.373564) (xy 260.726115 -256.375916)
			(xy 260.969504 -256.375916) (xy 260.973575 -256.320294) (xy 260.985701 -256.265857) (xy 261.005624 -256.213766)
			(xy 261.03292 -256.165131) (xy 261.067006 -256.120988) (xy 261.107155 -256.082279) (xy 261.152513 -256.049828)
			(xy 261.202113 -256.024327) (xy 261.254897 -256.00632) (xy 261.30974 -255.99619) (xy 261.365474 -255.994153)
			(xy 261.420911 -256.000253) (xy 261.474868 -256.014359) (xy 261.526197 -256.036171) (xy 261.573803 -256.065225)
			(xy 261.616671 -256.1009) (xy 261.653888 -256.142437) (xy 261.684661 -256.18895) (xy 261.708333 -256.239447)
			(xy 261.724401 -256.292854) (xy 261.732521 -256.34803) (xy 261.73303 -256.375916) (xy 262.44499 -256.375916)
			(xy 262.449061 -256.320294) (xy 262.461187 -256.265857) (xy 262.48111 -256.213766) (xy 262.508406 -256.165131)
			(xy 262.542492 -256.120988) (xy 262.582641 -256.082279) (xy 262.627999 -256.049828) (xy 262.677599 -256.024327)
			(xy 262.730383 -256.00632) (xy 262.785226 -255.99619) (xy 262.84096 -255.994153) (xy 262.896397 -256.000253)
			(xy 262.950354 -256.014359) (xy 263.001683 -256.036171) (xy 263.049289 -256.065225) (xy 263.092157 -256.1009)
			(xy 263.129374 -256.142437) (xy 263.160147 -256.18895) (xy 263.183819 -256.239447) (xy 263.199887 -256.292854)
			(xy 263.208007 -256.34803) (xy 263.208516 -256.375916) (xy 263.33399 -256.375916) (xy 263.338061 -256.320294)
			(xy 263.350187 -256.265857) (xy 263.37011 -256.213766) (xy 263.397406 -256.165131) (xy 263.431492 -256.120988)
			(xy 263.471641 -256.082279) (xy 263.516999 -256.049828) (xy 263.566599 -256.024327) (xy 263.619383 -256.00632)
			(xy 263.674226 -255.99619) (xy 263.72996 -255.994153) (xy 263.785397 -256.000253) (xy 263.839354 -256.014359)
			(xy 263.890683 -256.036171) (xy 263.938289 -256.065225) (xy 263.981157 -256.1009) (xy 264.018374 -256.142437)
			(xy 264.049147 -256.18895) (xy 264.072819 -256.239447) (xy 264.088887 -256.292854) (xy 264.097007 -256.34803)
			(xy 264.097516 -256.375916) (xy 264.097007 -256.403802) (xy 264.088887 -256.458978) (xy 264.072819 -256.512385)
			(xy 264.049147 -256.562882) (xy 264.018374 -256.609395) (xy 263.981157 -256.650932) (xy 263.938289 -256.686607)
			(xy 263.890683 -256.715661) (xy 263.839354 -256.737473) (xy 263.785397 -256.751579) (xy 263.72996 -256.757679)
			(xy 263.674226 -256.755642) (xy 263.619383 -256.745512) (xy 263.566599 -256.727505) (xy 263.516999 -256.702004)
			(xy 263.471641 -256.669553) (xy 263.431492 -256.630844) (xy 263.397406 -256.586701) (xy 263.37011 -256.538066)
			(xy 263.350187 -256.485975) (xy 263.338061 -256.431538) (xy 263.33399 -256.375916) (xy 263.208516 -256.375916)
			(xy 263.208007 -256.403802) (xy 263.199887 -256.458978) (xy 263.183819 -256.512385) (xy 263.160147 -256.562882)
			(xy 263.129374 -256.609395) (xy 263.092157 -256.650932) (xy 263.049289 -256.686607) (xy 263.001683 -256.715661)
			(xy 262.950354 -256.737473) (xy 262.896397 -256.751579) (xy 262.84096 -256.757679) (xy 262.785226 -256.755642)
			(xy 262.730383 -256.745512) (xy 262.677599 -256.727505) (xy 262.627999 -256.702004) (xy 262.582641 -256.669553)
			(xy 262.542492 -256.630844) (xy 262.508406 -256.586701) (xy 262.48111 -256.538066) (xy 262.461187 -256.485975)
			(xy 262.449061 -256.431538) (xy 262.44499 -256.375916) (xy 261.73303 -256.375916) (xy 261.732521 -256.403802)
			(xy 261.724401 -256.458978) (xy 261.708333 -256.512385) (xy 261.684661 -256.562882) (xy 261.653888 -256.609395)
			(xy 261.616671 -256.650932) (xy 261.573803 -256.686607) (xy 261.526197 -256.715661) (xy 261.474868 -256.737473)
			(xy 261.420911 -256.751579) (xy 261.365474 -256.757679) (xy 261.30974 -256.755642) (xy 261.254897 -256.745512)
			(xy 261.202113 -256.727505) (xy 261.152513 -256.702004) (xy 261.107155 -256.669553) (xy 261.067006 -256.630844)
			(xy 261.03292 -256.586701) (xy 261.005624 -256.538066) (xy 260.985701 -256.485975) (xy 260.973575 -256.431538)
			(xy 260.969504 -256.375916) (xy 260.726115 -256.375916) (xy 260.686073 -256.409239) (xy 260.638467 -256.438293)
			(xy 260.587138 -256.460105) (xy 260.533181 -256.474211) (xy 260.477744 -256.480311) (xy 260.42201 -256.478274)
			(xy 260.367167 -256.468144) (xy 260.314383 -256.450137) (xy 260.264783 -256.424636) (xy 260.219425 -256.392185)
			(xy 260.179276 -256.353476) (xy 260.14519 -256.309333) (xy 260.117894 -256.260698) (xy 260.097971 -256.208607)
			(xy 260.085845 -256.15417) (xy 260.081774 -256.098548) (xy 258.713862 -256.098548) (xy 258.754563 -256.117135)
			(xy 258.800413 -256.1466) (xy 258.841603 -256.182291) (xy 258.877295 -256.22348) (xy 258.906762 -256.26933)
			(xy 258.929403 -256.318907) (xy 258.944758 -256.371202) (xy 258.952515 -256.425149) (xy 258.952515 -256.479651)
			(xy 258.944758 -256.533598) (xy 258.929403 -256.585893) (xy 258.906762 -256.63547) (xy 258.877295 -256.68132)
			(xy 258.841603 -256.722509) (xy 258.800413 -256.7582) (xy 258.754563 -256.787665) (xy 258.704985 -256.810306)
			(xy 258.652691 -256.82566) (xy 258.598743 -256.833415) (xy 258.571492 -256.833878) (xy 258.545178 -256.833423)
			(xy 258.493048 -256.826187) (xy 258.442405 -256.811866) (xy 258.394206 -256.790731) (xy 258.349363 -256.763182)
			(xy 258.308724 -256.729741) (xy 258.290568 -256.710688) (xy 258.283062 -256.703268) (xy 258.26377 -256.694755)
			(xy 258.25323 -256.694178) (xy 258.178554 -256.694178) (xy 258.168007 -256.694729) (xy 258.148712 -256.70325)
			(xy 258.141216 -256.710688) (xy 258.123043 -256.729727) (xy 258.082418 -256.763186) (xy 258.037581 -256.790747)
			(xy 257.989383 -256.811889) (xy 257.938739 -256.826209) (xy 257.886607 -256.833438) (xy 257.860292 -256.833878)
			(xy 257.833039 -256.833452) (xy 257.779088 -256.825694) (xy 257.72679 -256.810337) (xy 257.67721 -256.787693)
			(xy 257.631357 -256.758224) (xy 257.590164 -256.72253) (xy 257.554471 -256.681337) (xy 257.525003 -256.635483)
			(xy 257.502361 -256.585903) (xy 257.487005 -256.533604) (xy 257.479248 -256.479653) (xy 248.165471 -256.479653)
			(xy 248.673366 -256.987548) (xy 260.081774 -256.987548) (xy 260.085845 -256.931926) (xy 260.097971 -256.877489)
			(xy 260.117894 -256.825398) (xy 260.14519 -256.776763) (xy 260.179276 -256.73262) (xy 260.219425 -256.693911)
			(xy 260.264783 -256.66146) (xy 260.314383 -256.635959) (xy 260.367167 -256.617952) (xy 260.42201 -256.607822)
			(xy 260.477744 -256.605785) (xy 260.533181 -256.611885) (xy 260.587138 -256.625991) (xy 260.638467 -256.647803)
			(xy 260.686073 -256.676857) (xy 260.728941 -256.712532) (xy 260.766158 -256.754069) (xy 260.796931 -256.800582)
			(xy 260.820603 -256.851079) (xy 260.836671 -256.904486) (xy 260.844791 -256.959662) (xy 260.8453 -256.987548)
			(xy 260.844791 -257.015434) (xy 260.836671 -257.07061) (xy 260.820603 -257.124017) (xy 260.814087 -257.137916)
			(xy 266.496038 -257.137916) (xy 266.496612 -257.108535) (xy 266.505639 -257.050471) (xy 266.523466 -256.994479)
			(xy 266.549671 -256.941884) (xy 266.583634 -256.893931) (xy 266.624551 -256.851756) (xy 266.647676 -256.833624)
			(xy 266.656604 -256.826149) (xy 266.66706 -256.805371) (xy 266.667742 -256.793746) (xy 266.669012 -256.70764)
			(xy 266.666472 -256.696464) (xy 266.664186 -256.691384) (xy 266.661573 -256.686204) (xy 266.654389 -256.677099)
			(xy 266.649962 -256.67335) (xy 266.6281 -256.65516) (xy 266.589562 -256.613337) (xy 266.557658 -256.566258)
			(xy 266.533094 -256.514965) (xy 266.516413 -256.460595) (xy 266.507986 -256.404352) (xy 266.507468 -256.375916)
			(xy 266.507954 -256.348665) (xy 266.51571 -256.294717) (xy 266.531065 -256.242422) (xy 266.553707 -256.192845)
			(xy 266.583173 -256.146995) (xy 266.618864 -256.105804) (xy 266.660055 -256.070113) (xy 266.705905 -256.040647)
			(xy 266.755482 -256.018005) (xy 266.807777 -256.00265) (xy 266.861725 -255.994894) (xy 266.916227 -255.994894)
			(xy 266.970175 -256.00265) (xy 267.02247 -256.018005) (xy 267.072047 -256.040647) (xy 267.117897 -256.070113)
			(xy 267.159088 -256.105804) (xy 267.194779 -256.146995) (xy 267.224245 -256.192845) (xy 267.246887 -256.242422)
			(xy 267.262242 -256.294717) (xy 267.269998 -256.348665) (xy 267.270484 -256.375916) (xy 267.269964 -256.405299)
			(xy 267.26093 -256.463367) (xy 267.243095 -256.519362) (xy 267.216879 -256.571957) (xy 267.182905 -256.619908)
			(xy 267.141976 -256.662079) (xy 267.118846 -256.680208) (xy 267.109907 -256.687673) (xy 267.099456 -256.708459)
			(xy 267.09878 -256.720086) (xy 267.09751 -256.806192) (xy 267.10005 -256.817368) (xy 267.102336 -256.822448)
			(xy 267.104937 -256.827634) (xy 267.11213 -256.836735) (xy 267.11656 -256.840482) (xy 267.138373 -256.858728)
			(xy 267.176918 -256.900537) (xy 267.20883 -256.947604) (xy 267.233403 -256.998886) (xy 267.250093 -257.053247)
			(xy 267.258531 -257.109483) (xy 267.259054 -257.137916) (xy 267.892528 -257.137916) (xy 267.896599 -257.082294)
			(xy 267.908725 -257.027857) (xy 267.928648 -256.975766) (xy 267.955944 -256.927131) (xy 267.99003 -256.882988)
			(xy 268.030179 -256.844279) (xy 268.075537 -256.811828) (xy 268.125137 -256.786327) (xy 268.177921 -256.76832)
			(xy 268.232764 -256.75819) (xy 268.288498 -256.756153) (xy 268.343935 -256.762253) (xy 268.397892 -256.776359)
			(xy 268.449221 -256.798171) (xy 268.496827 -256.827225) (xy 268.539695 -256.8629) (xy 268.576912 -256.904437)
			(xy 268.607685 -256.95095) (xy 268.631357 -257.001447) (xy 268.647425 -257.054854) (xy 268.655545 -257.11003)
			(xy 268.656054 -257.137916) (xy 268.778988 -257.137916) (xy 268.783059 -257.082294) (xy 268.795185 -257.027857)
			(xy 268.815108 -256.975766) (xy 268.842404 -256.927131) (xy 268.87649 -256.882988) (xy 268.916639 -256.844279)
			(xy 268.961997 -256.811828) (xy 269.011597 -256.786327) (xy 269.064381 -256.76832) (xy 269.119224 -256.75819)
			(xy 269.174958 -256.756153) (xy 269.230395 -256.762253) (xy 269.284352 -256.776359) (xy 269.335681 -256.798171)
			(xy 269.383287 -256.827225) (xy 269.426155 -256.8629) (xy 269.463372 -256.904437) (xy 269.494145 -256.95095)
			(xy 269.517817 -257.001447) (xy 269.533885 -257.054854) (xy 269.542005 -257.11003) (xy 269.542514 -257.137916)
			(xy 269.542005 -257.165802) (xy 269.533885 -257.220978) (xy 269.517817 -257.274385) (xy 269.494145 -257.324882)
			(xy 269.463372 -257.371395) (xy 269.426155 -257.412932) (xy 269.383287 -257.448607) (xy 269.335681 -257.477661)
			(xy 269.284352 -257.499473) (xy 269.230395 -257.513579) (xy 269.174958 -257.519679) (xy 269.119224 -257.517642)
			(xy 269.064381 -257.507512) (xy 269.011597 -257.489505) (xy 268.961997 -257.464004) (xy 268.916639 -257.431553)
			(xy 268.87649 -257.392844) (xy 268.842404 -257.348701) (xy 268.815108 -257.300066) (xy 268.795185 -257.247975)
			(xy 268.783059 -257.193538) (xy 268.778988 -257.137916) (xy 268.656054 -257.137916) (xy 268.655545 -257.165802)
			(xy 268.647425 -257.220978) (xy 268.631357 -257.274385) (xy 268.607685 -257.324882) (xy 268.576912 -257.371395)
			(xy 268.539695 -257.412932) (xy 268.496827 -257.448607) (xy 268.449221 -257.477661) (xy 268.397892 -257.499473)
			(xy 268.343935 -257.513579) (xy 268.288498 -257.519679) (xy 268.232764 -257.517642) (xy 268.177921 -257.507512)
			(xy 268.125137 -257.489505) (xy 268.075537 -257.464004) (xy 268.030179 -257.431553) (xy 267.99003 -257.392844)
			(xy 267.955944 -257.348701) (xy 267.928648 -257.300066) (xy 267.908725 -257.247975) (xy 267.896599 -257.193538)
			(xy 267.892528 -257.137916) (xy 267.259054 -257.137916) (xy 267.258568 -257.165167) (xy 267.250812 -257.219115)
			(xy 267.235457 -257.27141) (xy 267.212815 -257.320987) (xy 267.183349 -257.366837) (xy 267.147658 -257.408028)
			(xy 267.106467 -257.443719) (xy 267.060617 -257.473185) (xy 267.01104 -257.495827) (xy 266.958745 -257.511182)
			(xy 266.904797 -257.518938) (xy 266.850295 -257.518938) (xy 266.796347 -257.511182) (xy 266.744052 -257.495827)
			(xy 266.694475 -257.473185) (xy 266.648625 -257.443719) (xy 266.607434 -257.408028) (xy 266.571743 -257.366837)
			(xy 266.542277 -257.320987) (xy 266.519635 -257.27141) (xy 266.50428 -257.219115) (xy 266.496524 -257.165167)
			(xy 266.496038 -257.137916) (xy 260.814087 -257.137916) (xy 260.796931 -257.174514) (xy 260.766158 -257.221027)
			(xy 260.728941 -257.262564) (xy 260.686073 -257.298239) (xy 260.638467 -257.327293) (xy 260.587138 -257.349105)
			(xy 260.533181 -257.363211) (xy 260.477744 -257.369311) (xy 260.42201 -257.367274) (xy 260.367167 -257.357144)
			(xy 260.314383 -257.339137) (xy 260.264783 -257.313636) (xy 260.219425 -257.281185) (xy 260.179276 -257.242476)
			(xy 260.14519 -257.198333) (xy 260.117894 -257.149698) (xy 260.097971 -257.097607) (xy 260.085845 -257.04317)
			(xy 260.081774 -256.987548) (xy 248.673366 -256.987548) (xy 250.55322 -258.867402) (xy 250.561341 -258.874778)
			(xy 250.581879 -258.882431) (xy 250.592844 -258.882134) (xy 250.669552 -258.876546) (xy 250.675001 -258.876016)
			(xy 250.685506 -258.872943) (xy 250.69038 -258.87045) (xy 250.700032 -258.865116) (xy 250.706636 -258.856226)
			(xy 250.724755 -258.832826) (xy 250.766983 -258.791365) (xy 250.79071 -258.773676) (xy 250.799799 -258.766542)
			(xy 250.810919 -258.746312) (xy 250.812046 -258.734814) (xy 250.812046 -258.649978) (xy 250.811349 -258.637819)
			(xy 250.800203 -258.616206) (xy 250.79071 -258.608576) (xy 250.76993 -258.593156) (xy 250.732328 -258.557607)
			(xy 250.699879 -258.5173) (xy 250.673179 -258.472975) (xy 250.652718 -258.425447) (xy 250.638872 -258.375588)
			(xy 250.631896 -258.324315) (xy 250.631452 -258.298442) (xy 250.631958 -258.270644) (xy 250.640028 -258.215638)
			(xy 250.65599 -258.162384) (xy 250.679506 -258.112007) (xy 250.710079 -258.065573) (xy 250.747062 -258.024063)
			(xy 250.789674 -257.988356) (xy 250.813062 -257.973322) (xy 250.818396 -257.970274) (xy 250.827032 -257.961638)
			(xy 250.83008 -257.956558) (xy 250.833033 -257.951344) (xy 250.836638 -257.939919) (xy 250.837192 -257.933952)
			(xy 250.843288 -257.851656) (xy 250.843288 -257.845306) (xy 250.842241 -257.834779) (xy 250.832803 -257.815872)
			(xy 250.825 -257.80873) (xy 250.803877 -257.790532) (xy 250.766662 -257.749017) (xy 250.735892 -257.702523)
			(xy 250.712224 -257.652042) (xy 250.696164 -257.598652) (xy 250.688054 -257.543491) (xy 250.687586 -257.515614)
			(xy 250.688072 -257.488363) (xy 250.695828 -257.434415) (xy 250.711183 -257.38212) (xy 250.733825 -257.332543)
			(xy 250.763291 -257.286693) (xy 250.798982 -257.245502) (xy 250.840173 -257.209811) (xy 250.886023 -257.180345)
			(xy 250.9356 -257.157703) (xy 250.987895 -257.142348) (xy 251.041843 -257.134592) (xy 251.096345 -257.134592)
			(xy 251.150293 -257.142348) (xy 251.202588 -257.157703) (xy 251.252165 -257.180345) (xy 251.298015 -257.209811)
			(xy 251.339206 -257.245502) (xy 251.374897 -257.286693) (xy 251.404363 -257.332543) (xy 251.427005 -257.38212)
			(xy 251.44236 -257.434415) (xy 251.448082 -257.474212) (xy 254.171702 -257.474212) (xy 254.175773 -257.41859)
			(xy 254.187899 -257.364153) (xy 254.207822 -257.312062) (xy 254.235118 -257.263427) (xy 254.269204 -257.219284)
			(xy 254.309353 -257.180575) (xy 254.354711 -257.148124) (xy 254.404311 -257.122623) (xy 254.457095 -257.104616)
			(xy 254.511938 -257.094486) (xy 254.567672 -257.092449) (xy 254.623109 -257.098549) (xy 254.677066 -257.112655)
			(xy 254.728395 -257.134467) (xy 254.776001 -257.163521) (xy 254.818869 -257.199196) (xy 254.856086 -257.240733)
			(xy 254.886859 -257.287246) (xy 254.910531 -257.337743) (xy 254.926599 -257.39115) (xy 254.934719 -257.446326)
			(xy 254.935228 -257.474212) (xy 254.934719 -257.502098) (xy 254.926599 -257.557274) (xy 254.910531 -257.610681)
			(xy 254.886859 -257.661178) (xy 254.856086 -257.707691) (xy 254.818869 -257.749228) (xy 254.776001 -257.784903)
			(xy 254.728395 -257.813957) (xy 254.677066 -257.835769) (xy 254.623109 -257.849875) (xy 254.567672 -257.855975)
			(xy 254.511938 -257.853938) (xy 254.457095 -257.843808) (xy 254.404311 -257.825801) (xy 254.354711 -257.8003)
			(xy 254.309353 -257.767849) (xy 254.269204 -257.72914) (xy 254.235118 -257.684997) (xy 254.207822 -257.636362)
			(xy 254.187899 -257.584271) (xy 254.175773 -257.529834) (xy 254.171702 -257.474212) (xy 251.448082 -257.474212)
			(xy 251.450116 -257.488363) (xy 251.450602 -257.515614) (xy 251.4501 -257.543414) (xy 251.442036 -257.598425)
			(xy 251.42608 -257.651686) (xy 251.402569 -257.70207) (xy 251.372001 -257.748512) (xy 251.335021 -257.790031)
			(xy 251.292412 -257.825749) (xy 251.268992 -257.840734) (xy 251.263658 -257.843782) (xy 251.255022 -257.852418)
			(xy 251.251974 -257.857498) (xy 251.249029 -257.862715) (xy 251.24544 -257.874141) (xy 251.244862 -257.880104)
			(xy 251.238766 -257.9624) (xy 251.238766 -257.96875) (xy 251.239822 -257.979273) (xy 251.249267 -257.99817)
			(xy 251.257054 -258.005326) (xy 251.278177 -258.023525) (xy 251.315392 -258.06504) (xy 251.346162 -258.111534)
			(xy 251.369832 -258.162015) (xy 251.385508 -258.214114) (xy 256.61061 -258.214114) (xy 256.614681 -258.158492)
			(xy 256.626807 -258.104055) (xy 256.64673 -258.051964) (xy 256.674026 -258.003329) (xy 256.708112 -257.959186)
			(xy 256.748261 -257.920477) (xy 256.793619 -257.888026) (xy 256.843219 -257.862525) (xy 256.896003 -257.844518)
			(xy 256.950846 -257.834388) (xy 257.00658 -257.832351) (xy 257.062017 -257.838451) (xy 257.115974 -257.852557)
			(xy 257.167303 -257.874369) (xy 257.214909 -257.903423) (xy 257.257777 -257.939098) (xy 257.294994 -257.980635)
			(xy 257.325767 -258.027148) (xy 257.349439 -258.077645) (xy 257.365507 -258.131052) (xy 257.373627 -258.186228)
			(xy 257.374136 -258.214114) (xy 257.373627 -258.242) (xy 257.368909 -258.274058) (xy 260.969504 -258.274058)
			(xy 260.973575 -258.218436) (xy 260.985701 -258.163999) (xy 261.005624 -258.111908) (xy 261.03292 -258.063273)
			(xy 261.067006 -258.01913) (xy 261.107155 -257.980421) (xy 261.152513 -257.94797) (xy 261.202113 -257.922469)
			(xy 261.254897 -257.904462) (xy 261.30974 -257.894332) (xy 261.365474 -257.892295) (xy 261.420911 -257.898395)
			(xy 261.474868 -257.912501) (xy 261.526197 -257.934313) (xy 261.573803 -257.963367) (xy 261.616671 -257.999042)
			(xy 261.653888 -258.040579) (xy 261.684661 -258.087092) (xy 261.708333 -258.137589) (xy 261.724401 -258.190996)
			(xy 261.732521 -258.246172) (xy 261.73303 -258.274058) (xy 262.454642 -258.274058) (xy 262.458713 -258.218436)
			(xy 262.470839 -258.163999) (xy 262.490762 -258.111908) (xy 262.518058 -258.063273) (xy 262.552144 -258.01913)
			(xy 262.592293 -257.980421) (xy 262.637651 -257.94797) (xy 262.687251 -257.922469) (xy 262.740035 -257.904462)
			(xy 262.794878 -257.894332) (xy 262.850612 -257.892295) (xy 262.906049 -257.898395) (xy 262.960006 -257.912501)
			(xy 263.011335 -257.934313) (xy 263.058941 -257.963367) (xy 263.101809 -257.999042) (xy 263.139026 -258.040579)
			(xy 263.169799 -258.087092) (xy 263.193471 -258.137589) (xy 263.209539 -258.190996) (xy 263.217659 -258.246172)
			(xy 263.218168 -258.274058) (xy 263.217659 -258.301944) (xy 263.209539 -258.35712) (xy 263.193471 -258.410527)
			(xy 263.169799 -258.461024) (xy 263.139026 -258.507537) (xy 263.101809 -258.549074) (xy 263.058941 -258.584749)
			(xy 263.011335 -258.613803) (xy 262.960006 -258.635615) (xy 262.906049 -258.649721) (xy 262.850612 -258.655821)
			(xy 262.794878 -258.653784) (xy 262.740035 -258.643654) (xy 262.687251 -258.625647) (xy 262.637651 -258.600146)
			(xy 262.592293 -258.567695) (xy 262.552144 -258.528986) (xy 262.518058 -258.484843) (xy 262.490762 -258.436208)
			(xy 262.470839 -258.384117) (xy 262.458713 -258.32968) (xy 262.454642 -258.274058) (xy 261.73303 -258.274058)
			(xy 261.732521 -258.301944) (xy 261.724401 -258.35712) (xy 261.708333 -258.410527) (xy 261.684661 -258.461024)
			(xy 261.653888 -258.507537) (xy 261.616671 -258.549074) (xy 261.573803 -258.584749) (xy 261.526197 -258.613803)
			(xy 261.474868 -258.635615) (xy 261.420911 -258.649721) (xy 261.365474 -258.655821) (xy 261.30974 -258.653784)
			(xy 261.254897 -258.643654) (xy 261.202113 -258.625647) (xy 261.152513 -258.600146) (xy 261.107155 -258.567695)
			(xy 261.067006 -258.528986) (xy 261.03292 -258.484843) (xy 261.005624 -258.436208) (xy 260.985701 -258.384117)
			(xy 260.973575 -258.32968) (xy 260.969504 -258.274058) (xy 257.368909 -258.274058) (xy 257.365507 -258.297176)
			(xy 257.349439 -258.350583) (xy 257.325767 -258.40108) (xy 257.294994 -258.447593) (xy 257.257777 -258.48913)
			(xy 257.214909 -258.524805) (xy 257.167303 -258.553859) (xy 257.115974 -258.575671) (xy 257.062017 -258.589777)
			(xy 257.00658 -258.595877) (xy 256.950846 -258.59384) (xy 256.896003 -258.58371) (xy 256.843219 -258.565703)
			(xy 256.793619 -258.540202) (xy 256.748261 -258.507751) (xy 256.708112 -258.469042) (xy 256.674026 -258.424899)
			(xy 256.64673 -258.376264) (xy 256.626807 -258.324173) (xy 256.614681 -258.269736) (xy 256.61061 -258.214114)
			(xy 251.385508 -258.214114) (xy 251.385896 -258.215405) (xy 251.394012 -258.270565) (xy 251.394468 -258.298442)
			(xy 251.394034 -258.324313) (xy 251.387038 -258.375581) (xy 251.37318 -258.425434) (xy 251.352713 -258.472957)
			(xy 251.326014 -258.517279) (xy 251.293571 -258.557588) (xy 251.25598 -258.593145) (xy 251.23521 -258.608576)
			(xy 251.225705 -258.616193) (xy 251.21457 -258.637816) (xy 251.213874 -258.649978) (xy 251.213874 -258.6736)
			(xy 253.541782 -258.6736) (xy 253.545853 -258.617978) (xy 253.557979 -258.563541) (xy 253.577902 -258.51145)
			(xy 253.605198 -258.462815) (xy 253.639284 -258.418672) (xy 253.679433 -258.379963) (xy 253.724791 -258.347512)
			(xy 253.774391 -258.322011) (xy 253.827175 -258.304004) (xy 253.882018 -258.293874) (xy 253.937752 -258.291837)
			(xy 253.993189 -258.297937) (xy 254.047146 -258.312043) (xy 254.098475 -258.333855) (xy 254.146081 -258.362909)
			(xy 254.188949 -258.398584) (xy 254.226166 -258.440121) (xy 254.256939 -258.486634) (xy 254.280611 -258.537131)
			(xy 254.296679 -258.590538) (xy 254.304799 -258.645714) (xy 254.304877 -258.649978) (xy 255.126234 -258.649978)
			(xy 255.130305 -258.594356) (xy 255.142431 -258.539919) (xy 255.162354 -258.487828) (xy 255.18965 -258.439193)
			(xy 255.223736 -258.39505) (xy 255.263885 -258.356341) (xy 255.309243 -258.32389) (xy 255.358843 -258.298389)
			(xy 255.411627 -258.280382) (xy 255.46647 -258.270252) (xy 255.522204 -258.268215) (xy 255.577641 -258.274315)
			(xy 255.631598 -258.288421) (xy 255.682927 -258.310233) (xy 255.730533 -258.339287) (xy 255.773401 -258.374962)
			(xy 255.810618 -258.416499) (xy 255.841391 -258.463012) (xy 255.865063 -258.513509) (xy 255.881131 -258.566916)
			(xy 255.889251 -258.622092) (xy 255.88976 -258.649978) (xy 255.889251 -258.677864) (xy 255.881131 -258.73304)
			(xy 255.865063 -258.786447) (xy 255.841391 -258.836944) (xy 255.810618 -258.883457) (xy 255.773401 -258.924994)
			(xy 255.730533 -258.960669) (xy 255.682927 -258.989723) (xy 255.631598 -259.011535) (xy 255.577641 -259.025641)
			(xy 255.522204 -259.031741) (xy 255.46647 -259.029704) (xy 255.411627 -259.019574) (xy 255.358843 -259.001567)
			(xy 255.309243 -258.976066) (xy 255.263885 -258.943615) (xy 255.223736 -258.904906) (xy 255.18965 -258.860763)
			(xy 255.162354 -258.812128) (xy 255.142431 -258.760037) (xy 255.130305 -258.7056) (xy 255.126234 -258.649978)
			(xy 254.304877 -258.649978) (xy 254.305308 -258.6736) (xy 254.304799 -258.701486) (xy 254.296679 -258.756662)
			(xy 254.280611 -258.810069) (xy 254.256939 -258.860566) (xy 254.226166 -258.907079) (xy 254.188949 -258.948616)
			(xy 254.146081 -258.984291) (xy 254.098475 -259.013345) (xy 254.047146 -259.035157) (xy 253.993189 -259.049263)
			(xy 253.937752 -259.055363) (xy 253.882018 -259.053326) (xy 253.827175 -259.043196) (xy 253.774391 -259.025189)
			(xy 253.724791 -258.999688) (xy 253.679433 -258.967237) (xy 253.639284 -258.928528) (xy 253.605198 -258.884385)
			(xy 253.577902 -258.83575) (xy 253.557979 -258.783659) (xy 253.545853 -258.729222) (xy 253.541782 -258.6736)
			(xy 251.213874 -258.6736) (xy 251.213874 -258.732274) (xy 251.214562 -258.744437) (xy 251.225699 -258.766065)
			(xy 251.23521 -258.773676) (xy 251.255991 -258.789096) (xy 251.293596 -258.824644) (xy 251.326048 -258.864951)
			(xy 251.352752 -258.909275) (xy 251.373218 -258.956803) (xy 251.387069 -259.006662) (xy 251.394051 -259.057936)
			(xy 251.394468 -259.08381) (xy 251.393907 -259.113453) (xy 251.38474 -259.172027) (xy 251.366629 -259.228479)
			(xy 251.340009 -259.281454) (xy 251.305519 -259.329676) (xy 251.26399 -259.371986) (xy 251.240544 -259.390134)
			(xy 251.23624 -259.393478) (xy 251.229066 -259.401681) (xy 251.22632 -259.40639) (xy 251.220986 -259.416042)
			(xy 251.214636 -259.503926) (xy 251.214333 -259.514898) (xy 251.221957 -259.535456) (xy 251.229368 -259.54355)
			(xy 251.262134 -259.576316) (xy 262.44499 -259.576316) (xy 262.449061 -259.520694) (xy 262.461187 -259.466257)
			(xy 262.48111 -259.414166) (xy 262.508406 -259.365531) (xy 262.542492 -259.321388) (xy 262.582641 -259.282679)
			(xy 262.627999 -259.250228) (xy 262.677599 -259.224727) (xy 262.730383 -259.20672) (xy 262.785226 -259.19659)
			(xy 262.84096 -259.194553) (xy 262.896397 -259.200653) (xy 262.950354 -259.214759) (xy 263.001683 -259.236571)
			(xy 263.049289 -259.265625) (xy 263.092157 -259.3013) (xy 263.129374 -259.342837) (xy 263.160147 -259.38935)
			(xy 263.183819 -259.439847) (xy 263.199887 -259.493254) (xy 263.208007 -259.54843) (xy 263.208516 -259.576316)
			(xy 263.33399 -259.576316) (xy 263.338061 -259.520694) (xy 263.350187 -259.466257) (xy 263.37011 -259.414166)
			(xy 263.397406 -259.365531) (xy 263.431492 -259.321388) (xy 263.471641 -259.282679) (xy 263.516999 -259.250228)
			(xy 263.566599 -259.224727) (xy 263.619383 -259.20672) (xy 263.674226 -259.19659) (xy 263.72996 -259.194553)
			(xy 263.785397 -259.200653) (xy 263.839354 -259.214759) (xy 263.890683 -259.236571) (xy 263.938289 -259.265625)
			(xy 263.981157 -259.3013) (xy 264.018374 -259.342837) (xy 264.049147 -259.38935) (xy 264.072819 -259.439847)
			(xy 264.088887 -259.493254) (xy 264.097007 -259.54843) (xy 264.097516 -259.576316) (xy 264.097007 -259.604202)
			(xy 264.088887 -259.659378) (xy 264.072819 -259.712785) (xy 264.049147 -259.763282) (xy 264.018374 -259.809795)
			(xy 263.981157 -259.851332) (xy 263.938289 -259.887007) (xy 263.890683 -259.916061) (xy 263.839354 -259.937873)
			(xy 263.785397 -259.951979) (xy 263.72996 -259.958079) (xy 263.674226 -259.956042) (xy 263.619383 -259.945912)
			(xy 263.566599 -259.927905) (xy 263.516999 -259.902404) (xy 263.471641 -259.869953) (xy 263.431492 -259.831244)
			(xy 263.397406 -259.787101) (xy 263.37011 -259.738466) (xy 263.350187 -259.686375) (xy 263.338061 -259.631938)
			(xy 263.33399 -259.576316) (xy 263.208516 -259.576316) (xy 263.208007 -259.604202) (xy 263.199887 -259.659378)
			(xy 263.183819 -259.712785) (xy 263.160147 -259.763282) (xy 263.129374 -259.809795) (xy 263.092157 -259.851332)
			(xy 263.049289 -259.887007) (xy 263.001683 -259.916061) (xy 262.950354 -259.937873) (xy 262.896397 -259.951979)
			(xy 262.84096 -259.958079) (xy 262.785226 -259.956042) (xy 262.730383 -259.945912) (xy 262.677599 -259.927905)
			(xy 262.627999 -259.902404) (xy 262.582641 -259.869953) (xy 262.542492 -259.831244) (xy 262.508406 -259.787101)
			(xy 262.48111 -259.738466) (xy 262.461187 -259.686375) (xy 262.449061 -259.631938) (xy 262.44499 -259.576316)
			(xy 251.262134 -259.576316) (xy 251.713492 -260.027674) (xy 254.29159 -260.027674) (xy 254.295661 -259.972052)
			(xy 254.307787 -259.917615) (xy 254.32771 -259.865524) (xy 254.355006 -259.816889) (xy 254.389092 -259.772746)
			(xy 254.429241 -259.734037) (xy 254.474599 -259.701586) (xy 254.524199 -259.676085) (xy 254.576983 -259.658078)
			(xy 254.631826 -259.647948) (xy 254.68756 -259.645911) (xy 254.742997 -259.652011) (xy 254.796954 -259.666117)
			(xy 254.848283 -259.687929) (xy 254.895889 -259.716983) (xy 254.938757 -259.752658) (xy 254.975974 -259.794195)
			(xy 255.006747 -259.840708) (xy 255.030419 -259.891205) (xy 255.046487 -259.944612) (xy 255.054607 -259.999788)
			(xy 255.055116 -260.027674) (xy 255.054607 -260.05556) (xy 255.052394 -260.0706) (xy 255.842768 -260.0706)
			(xy 255.846839 -260.014978) (xy 255.858965 -259.960541) (xy 255.878888 -259.90845) (xy 255.906184 -259.859815)
			(xy 255.94027 -259.815672) (xy 255.980419 -259.776963) (xy 256.025777 -259.744512) (xy 256.075377 -259.719011)
			(xy 256.128161 -259.701004) (xy 256.183004 -259.690874) (xy 256.238738 -259.688837) (xy 256.294175 -259.694937)
			(xy 256.348132 -259.709043) (xy 256.399461 -259.730855) (xy 256.447067 -259.759909) (xy 256.489935 -259.795584)
			(xy 256.527152 -259.837121) (xy 256.557925 -259.883634) (xy 256.581597 -259.934131) (xy 256.597665 -259.987538)
			(xy 256.605785 -260.042714) (xy 256.606294 -260.0706) (xy 256.605785 -260.098486) (xy 256.597665 -260.153662)
			(xy 256.581597 -260.207069) (xy 256.557925 -260.257566) (xy 256.527152 -260.304079) (xy 256.489935 -260.345616)
			(xy 256.447067 -260.381291) (xy 256.399461 -260.410345) (xy 256.348132 -260.432157) (xy 256.294175 -260.446263)
			(xy 256.238738 -260.452363) (xy 256.183004 -260.450326) (xy 256.128161 -260.440196) (xy 256.075377 -260.422189)
			(xy 256.025777 -260.396688) (xy 255.980419 -260.364237) (xy 255.94027 -260.325528) (xy 255.906184 -260.281385)
			(xy 255.878888 -260.23275) (xy 255.858965 -260.180659) (xy 255.846839 -260.126222) (xy 255.842768 -260.0706)
			(xy 255.052394 -260.0706) (xy 255.046487 -260.110736) (xy 255.030419 -260.164143) (xy 255.006747 -260.21464)
			(xy 254.975974 -260.261153) (xy 254.938757 -260.30269) (xy 254.895889 -260.338365) (xy 254.848283 -260.367419)
			(xy 254.796954 -260.389231) (xy 254.742997 -260.403337) (xy 254.68756 -260.409437) (xy 254.631826 -260.4074)
			(xy 254.576983 -260.39727) (xy 254.524199 -260.379263) (xy 254.474599 -260.353762) (xy 254.429241 -260.321311)
			(xy 254.389092 -260.282602) (xy 254.355006 -260.238459) (xy 254.32771 -260.189824) (xy 254.307787 -260.137733)
			(xy 254.295661 -260.083296) (xy 254.29159 -260.027674) (xy 251.713492 -260.027674) (xy 253.503773 -261.817955)
			(xy 257.719243 -261.817955) (xy 257.719243 -261.763445) (xy 257.727001 -261.709491) (xy 257.742358 -261.657189)
			(xy 257.765003 -261.607606) (xy 257.794474 -261.56175) (xy 257.830171 -261.520556) (xy 257.871368 -261.484861)
			(xy 257.917225 -261.455393) (xy 257.96681 -261.432751) (xy 258.019112 -261.417396) (xy 258.073067 -261.409641)
			(xy 258.100322 -261.40918) (xy 258.129238 -261.409724) (xy 258.18641 -261.418444) (xy 258.241609 -261.435694)
			(xy 258.293572 -261.461081) (xy 258.341106 -261.494022) (xy 258.383122 -261.533761) (xy 258.401312 -261.556246)
			(xy 258.408865 -261.565016) (xy 258.429631 -261.575193) (xy 258.44119 -261.575804) (xy 258.521454 -261.575804)
			(xy 258.533018 -261.575206) (xy 258.55379 -261.565031) (xy 258.561332 -261.556246) (xy 258.579491 -261.533736)
			(xy 258.621519 -261.494005) (xy 258.669061 -261.461071) (xy 258.721029 -261.435687) (xy 258.776231 -261.418436)
			(xy 258.833404 -261.409712) (xy 258.862322 -261.40918) (xy 258.887647 -261.409583) (xy 258.93785 -261.416303)
			(xy 258.986722 -261.429608) (xy 259.033403 -261.449263) (xy 259.077073 -261.474924) (xy 259.097272 -261.490206)
			(xy 259.097526 -261.49046) (xy 259.104353 -261.495268) (xy 259.120169 -261.500584) (xy 259.128514 -261.500874)
			(xy 259.128768 -261.500874) (xy 259.13879 -261.500453) (xy 259.157312 -261.492789) (xy 259.171486 -261.478617)
			(xy 259.179152 -261.460096) (xy 259.179568 -261.450074) (xy 259.179568 -261.444486) (xy 259.180008 -261.415365)
			(xy 259.187606 -261.357621) (xy 259.202683 -261.301365) (xy 259.224981 -261.24756) (xy 259.254116 -261.19713)
			(xy 259.289591 -261.150938) (xy 259.30987 -261.130034) (xy 259.950966 -260.488684) (xy 259.957443 -260.481598)
			(xy 259.96501 -260.46397) (xy 259.965698 -260.454394) (xy 259.967984 -260.385052) (xy 259.967476 -260.375908)
			(xy 259.966174 -260.368686) (xy 259.959974 -260.355391) (xy 259.955284 -260.349746) (xy 259.95503 -260.349492)
			(xy 259.937075 -260.328473) (xy 259.906804 -260.282219) (xy 259.883529 -260.232078) (xy 259.867737 -260.179103)
			(xy 259.859761 -260.124402) (xy 259.859272 -260.096762) (xy 259.859758 -260.069511) (xy 259.867514 -260.015563)
			(xy 259.882869 -259.963268) (xy 259.905511 -259.913691) (xy 259.934977 -259.867841) (xy 259.970668 -259.82665)
			(xy 260.011859 -259.790959) (xy 260.057709 -259.761493) (xy 260.107286 -259.738851) (xy 260.159581 -259.723496)
			(xy 260.213529 -259.71574) (xy 260.268031 -259.71574) (xy 260.321979 -259.723496) (xy 260.374274 -259.738851)
			(xy 260.423851 -259.761493) (xy 260.469701 -259.790959) (xy 260.510892 -259.82665) (xy 260.546583 -259.867841)
			(xy 260.576049 -259.913691) (xy 260.598691 -259.963268) (xy 260.614046 -260.015563) (xy 260.621802 -260.069511)
			(xy 260.622288 -260.096762) (xy 260.622151 -260.110529) (xy 260.620114 -260.137988) (xy 260.618224 -260.151626)
			(xy 260.6167 -260.162548) (xy 260.619748 -260.172962) (xy 260.621416 -260.178179) (xy 260.62668 -260.187783)
			(xy 260.630162 -260.192012) (xy 260.680454 -260.250178) (xy 260.680708 -260.250432) (xy 260.681724 -260.251448)
			(xy 260.688787 -260.25837) (xy 260.70668 -260.266744) (xy 260.716522 -260.267704) (xy 266.20851 -260.267704)
			(xy 266.236945 -260.26819) (xy 266.293343 -260.275524) (xy 266.34835 -260.28997) (xy 266.37488 -260.300216)
			(xy 266.375134 -260.300216) (xy 266.385216 -260.303663) (xy 266.406483 -260.302877) (xy 266.416282 -260.298692)
			(xy 266.484354 -260.265418) (xy 266.487402 -260.263894) (xy 266.495643 -260.258616) (xy 266.50767 -260.243204)
			(xy 266.51077 -260.233922) (xy 266.51077 -260.233668) (xy 266.519792 -260.204202) (xy 266.546034 -260.148448)
			(xy 266.580888 -260.09763) (xy 266.623449 -260.053068) (xy 266.647676 -260.034024) (xy 266.656604 -260.026549)
			(xy 266.66706 -260.005771) (xy 266.667742 -259.994146) (xy 266.669012 -259.90804) (xy 266.666472 -259.896864)
			(xy 266.664186 -259.891784) (xy 266.661573 -259.886604) (xy 266.654389 -259.877499) (xy 266.649962 -259.87375)
			(xy 266.6281 -259.85556) (xy 266.589562 -259.813737) (xy 266.557658 -259.766658) (xy 266.533094 -259.715365)
			(xy 266.516413 -259.660995) (xy 266.507986 -259.604752) (xy 266.507468 -259.576316) (xy 266.507954 -259.549065)
			(xy 266.51571 -259.495117) (xy 266.531065 -259.442822) (xy 266.553707 -259.393245) (xy 266.583173 -259.347395)
			(xy 266.618864 -259.306204) (xy 266.660055 -259.270513) (xy 266.705905 -259.241047) (xy 266.755482 -259.218405)
			(xy 266.807777 -259.20305) (xy 266.861725 -259.195294) (xy 266.916227 -259.195294) (xy 266.970175 -259.20305)
			(xy 267.02247 -259.218405) (xy 267.072047 -259.241047) (xy 267.117897 -259.270513) (xy 267.159088 -259.306204)
			(xy 267.194779 -259.347395) (xy 267.224245 -259.393245) (xy 267.246887 -259.442822) (xy 267.262242 -259.495117)
			(xy 267.269998 -259.549065) (xy 267.270484 -259.576316) (xy 267.269964 -259.605699) (xy 267.26093 -259.663767)
			(xy 267.243095 -259.719762) (xy 267.216879 -259.772357) (xy 267.182905 -259.820308) (xy 267.141976 -259.862479)
			(xy 267.118846 -259.880608) (xy 267.109907 -259.888073) (xy 267.099456 -259.908859) (xy 267.09878 -259.920486)
			(xy 267.09751 -260.006592) (xy 267.10005 -260.017768) (xy 267.102336 -260.022848) (xy 267.104937 -260.028034)
			(xy 267.11213 -260.037135) (xy 267.11656 -260.040882) (xy 267.138373 -260.059128) (xy 267.176918 -260.100937)
			(xy 267.20883 -260.148004) (xy 267.233403 -260.199286) (xy 267.250093 -260.253647) (xy 267.258531 -260.309883)
			(xy 267.259054 -260.338316) (xy 267.892528 -260.338316) (xy 267.896599 -260.282694) (xy 267.908725 -260.228257)
			(xy 267.928648 -260.176166) (xy 267.955944 -260.127531) (xy 267.99003 -260.083388) (xy 268.030179 -260.044679)
			(xy 268.075537 -260.012228) (xy 268.125137 -259.986727) (xy 268.177921 -259.96872) (xy 268.232764 -259.95859)
			(xy 268.288498 -259.956553) (xy 268.343935 -259.962653) (xy 268.397892 -259.976759) (xy 268.449221 -259.998571)
			(xy 268.496827 -260.027625) (xy 268.539695 -260.0633) (xy 268.576912 -260.104837) (xy 268.607685 -260.15135)
			(xy 268.631357 -260.201847) (xy 268.647425 -260.255254) (xy 268.655545 -260.31043) (xy 268.656054 -260.338316)
			(xy 268.778988 -260.338316) (xy 268.783059 -260.282694) (xy 268.795185 -260.228257) (xy 268.815108 -260.176166)
			(xy 268.842404 -260.127531) (xy 268.87649 -260.083388) (xy 268.916639 -260.044679) (xy 268.961997 -260.012228)
			(xy 269.011597 -259.986727) (xy 269.064381 -259.96872) (xy 269.119224 -259.95859) (xy 269.174958 -259.956553)
			(xy 269.230395 -259.962653) (xy 269.284352 -259.976759) (xy 269.335681 -259.998571) (xy 269.383287 -260.027625)
			(xy 269.426155 -260.0633) (xy 269.463372 -260.104837) (xy 269.494145 -260.15135) (xy 269.517817 -260.201847)
			(xy 269.533885 -260.255254) (xy 269.542005 -260.31043) (xy 269.542514 -260.338316) (xy 269.542005 -260.366202)
			(xy 269.533885 -260.421378) (xy 269.517817 -260.474785) (xy 269.494145 -260.525282) (xy 269.463372 -260.571795)
			(xy 269.426155 -260.613332) (xy 269.383287 -260.649007) (xy 269.335681 -260.678061) (xy 269.284352 -260.699873)
			(xy 269.230395 -260.713979) (xy 269.174958 -260.720079) (xy 269.119224 -260.718042) (xy 269.064381 -260.707912)
			(xy 269.011597 -260.689905) (xy 268.961997 -260.664404) (xy 268.916639 -260.631953) (xy 268.87649 -260.593244)
			(xy 268.842404 -260.549101) (xy 268.815108 -260.500466) (xy 268.795185 -260.448375) (xy 268.783059 -260.393938)
			(xy 268.778988 -260.338316) (xy 268.656054 -260.338316) (xy 268.655545 -260.366202) (xy 268.647425 -260.421378)
			(xy 268.631357 -260.474785) (xy 268.607685 -260.525282) (xy 268.576912 -260.571795) (xy 268.539695 -260.613332)
			(xy 268.496827 -260.649007) (xy 268.449221 -260.678061) (xy 268.397892 -260.699873) (xy 268.343935 -260.713979)
			(xy 268.288498 -260.720079) (xy 268.232764 -260.718042) (xy 268.177921 -260.707912) (xy 268.125137 -260.689905)
			(xy 268.075537 -260.664404) (xy 268.030179 -260.631953) (xy 267.99003 -260.593244) (xy 267.955944 -260.549101)
			(xy 267.928648 -260.500466) (xy 267.908725 -260.448375) (xy 267.896599 -260.393938) (xy 267.892528 -260.338316)
			(xy 267.259054 -260.338316) (xy 267.258538 -260.366766) (xy 267.250111 -260.423038) (xy 267.233416 -260.477433)
			(xy 267.208825 -260.528744) (xy 267.176883 -260.575831) (xy 267.138299 -260.61765) (xy 267.09393 -260.653271)
			(xy 267.044761 -260.681905) (xy 267.018516 -260.6929) (xy 267.018262 -260.6929) (xy 267.006737 -260.698231)
			(xy 266.990478 -260.717696) (xy 266.987274 -260.729984) (xy 266.970256 -260.812788) (xy 266.968333 -260.825309)
			(xy 266.975537 -260.849564) (xy 266.983972 -260.859016) (xy 269.502439 -263.37768) (xy 270.148048 -263.37768)
			(xy 270.152119 -263.322058) (xy 270.164245 -263.267621) (xy 270.184168 -263.21553) (xy 270.211464 -263.166895)
			(xy 270.24555 -263.122752) (xy 270.285699 -263.084043) (xy 270.331057 -263.051592) (xy 270.380657 -263.026091)
			(xy 270.433441 -263.008084) (xy 270.488284 -262.997954) (xy 270.544018 -262.995917) (xy 270.599455 -263.002017)
			(xy 270.653412 -263.016123) (xy 270.704741 -263.037935) (xy 270.752347 -263.066989) (xy 270.795215 -263.102664)
			(xy 270.832432 -263.144201) (xy 270.863205 -263.190714) (xy 270.886877 -263.241211) (xy 270.902945 -263.294618)
			(xy 270.911065 -263.349794) (xy 270.911574 -263.37768) (xy 270.911065 -263.405566) (xy 270.902945 -263.460742)
			(xy 270.886877 -263.514149) (xy 270.863205 -263.564646) (xy 270.832432 -263.611159) (xy 270.795215 -263.652696)
			(xy 270.752347 -263.688371) (xy 270.704741 -263.717425) (xy 270.653412 -263.739237) (xy 270.599455 -263.753343)
			(xy 270.544018 -263.759443) (xy 270.488284 -263.757406) (xy 270.433441 -263.747276) (xy 270.380657 -263.729269)
			(xy 270.331057 -263.703768) (xy 270.285699 -263.671317) (xy 270.24555 -263.632608) (xy 270.211464 -263.588465)
			(xy 270.184168 -263.53983) (xy 270.164245 -263.487739) (xy 270.152119 -263.433302) (xy 270.148048 -263.37768)
			(xy 269.502439 -263.37768) (xy 270.228314 -264.103612) (xy 270.248578 -264.124529) (xy 270.284042 -264.170724)
			(xy 270.313172 -264.221153) (xy 270.335468 -264.274954) (xy 270.34326 -264.304018) (xy 270.618964 -264.304018)
			(xy 270.623035 -264.248396) (xy 270.635161 -264.193959) (xy 270.655084 -264.141868) (xy 270.68238 -264.093233)
			(xy 270.716466 -264.04909) (xy 270.756615 -264.010381) (xy 270.801973 -263.97793) (xy 270.851573 -263.952429)
			(xy 270.904357 -263.934422) (xy 270.9592 -263.924292) (xy 271.014934 -263.922255) (xy 271.070371 -263.928355)
			(xy 271.124328 -263.942461) (xy 271.175657 -263.964273) (xy 271.223263 -263.993327) (xy 271.266131 -264.029002)
			(xy 271.303348 -264.070539) (xy 271.334121 -264.117052) (xy 271.357793 -264.167549) (xy 271.373861 -264.220956)
			(xy 271.381981 -264.276132) (xy 271.38249 -264.304018) (xy 271.381981 -264.331904) (xy 271.373861 -264.38708)
			(xy 271.357793 -264.440487) (xy 271.334121 -264.490984) (xy 271.329262 -264.498328) (xy 273.06854 -264.498328)
			(xy 273.072611 -264.442706) (xy 273.084737 -264.388269) (xy 273.10466 -264.336178) (xy 273.131956 -264.287543)
			(xy 273.166042 -264.2434) (xy 273.206191 -264.204691) (xy 273.251549 -264.17224) (xy 273.301149 -264.146739)
			(xy 273.353933 -264.128732) (xy 273.408776 -264.118602) (xy 273.46451 -264.116565) (xy 273.519947 -264.122665)
			(xy 273.573904 -264.136771) (xy 273.625233 -264.158583) (xy 273.672839 -264.187637) (xy 273.715707 -264.223312)
			(xy 273.752924 -264.264849) (xy 273.783697 -264.311362) (xy 273.807369 -264.361859) (xy 273.823437 -264.415266)
			(xy 273.831557 -264.470442) (xy 273.832066 -264.498328) (xy 273.831557 -264.526214) (xy 273.823437 -264.58139)
			(xy 273.807369 -264.634797) (xy 273.783697 -264.685294) (xy 273.752924 -264.731807) (xy 273.715707 -264.773344)
			(xy 273.672839 -264.809019) (xy 273.625233 -264.838073) (xy 273.573904 -264.859885) (xy 273.519947 -264.873991)
			(xy 273.46451 -264.880091) (xy 273.408776 -264.878054) (xy 273.353933 -264.867924) (xy 273.301149 -264.849917)
			(xy 273.251549 -264.824416) (xy 273.206191 -264.791965) (xy 273.166042 -264.753256) (xy 273.131956 -264.709113)
			(xy 273.10466 -264.660478) (xy 273.084737 -264.608387) (xy 273.072611 -264.55395) (xy 273.06854 -264.498328)
			(xy 271.329262 -264.498328) (xy 271.303348 -264.537497) (xy 271.266131 -264.579034) (xy 271.223263 -264.614709)
			(xy 271.175657 -264.643763) (xy 271.124328 -264.665575) (xy 271.070371 -264.679681) (xy 271.014934 -264.685781)
			(xy 270.9592 -264.683744) (xy 270.904357 -264.673614) (xy 270.851573 -264.655607) (xy 270.801973 -264.630106)
			(xy 270.756615 -264.597655) (xy 270.716466 -264.558946) (xy 270.68238 -264.514803) (xy 270.655084 -264.466168)
			(xy 270.635161 -264.414077) (xy 270.623035 -264.35964) (xy 270.618964 -264.304018) (xy 270.34326 -264.304018)
			(xy 270.350549 -264.331206) (xy 270.358158 -264.388945) (xy 270.358616 -264.418064) (xy 270.358616 -266.012422)
			(xy 273.142454 -266.012422) (xy 273.146525 -265.9568) (xy 273.158651 -265.902363) (xy 273.178574 -265.850272)
			(xy 273.20587 -265.801637) (xy 273.239956 -265.757494) (xy 273.280105 -265.718785) (xy 273.325463 -265.686334)
			(xy 273.375063 -265.660833) (xy 273.427847 -265.642826) (xy 273.48269 -265.632696) (xy 273.538424 -265.630659)
			(xy 273.593861 -265.636759) (xy 273.647818 -265.650865) (xy 273.699147 -265.672677) (xy 273.746753 -265.701731)
			(xy 273.789621 -265.737406) (xy 273.826838 -265.778943) (xy 273.857611 -265.825456) (xy 273.881283 -265.875953)
			(xy 273.897351 -265.92936) (xy 273.905471 -265.984536) (xy 273.90598 -266.012422) (xy 273.905471 -266.040308)
			(xy 273.897351 -266.095484) (xy 273.881283 -266.148891) (xy 273.857611 -266.199388) (xy 273.826838 -266.245901)
			(xy 273.789621 -266.287438) (xy 273.746753 -266.323113) (xy 273.699147 -266.352167) (xy 273.647818 -266.373979)
			(xy 273.593861 -266.388085) (xy 273.538424 -266.394185) (xy 273.48269 -266.392148) (xy 273.427847 -266.382018)
			(xy 273.375063 -266.364011) (xy 273.325463 -266.33851) (xy 273.280105 -266.306059) (xy 273.239956 -266.26735)
			(xy 273.20587 -266.223207) (xy 273.178574 -266.174572) (xy 273.158651 -266.122481) (xy 273.146525 -266.068044)
			(xy 273.142454 -266.012422) (xy 270.358616 -266.012422) (xy 270.358616 -266.632436) (xy 270.358906 -266.640631)
			(xy 270.364101 -266.656178) (xy 270.368776 -266.662916) (xy 270.373602 -266.668504) (xy 270.606266 -266.901168)
			(xy 270.626566 -266.922051) (xy 270.658298 -266.963398) (xy 270.855946 -266.963398) (xy 270.860017 -266.907776)
			(xy 270.872143 -266.853339) (xy 270.892066 -266.801248) (xy 270.919362 -266.752613) (xy 270.953448 -266.70847)
			(xy 270.993597 -266.669761) (xy 271.038955 -266.63731) (xy 271.088555 -266.611809) (xy 271.141339 -266.593802)
			(xy 271.196182 -266.583672) (xy 271.251916 -266.581635) (xy 271.307353 -266.587735) (xy 271.36131 -266.601841)
			(xy 271.412639 -266.623653) (xy 271.460245 -266.652707) (xy 271.503113 -266.688382) (xy 271.54033 -266.729919)
			(xy 271.571103 -266.776432) (xy 271.594775 -266.826929) (xy 271.595026 -266.827762) (xy 271.740374 -266.827762)
			(xy 271.744445 -266.77214) (xy 271.756571 -266.717703) (xy 271.776494 -266.665612) (xy 271.80379 -266.616977)
			(xy 271.837876 -266.572834) (xy 271.878025 -266.534125) (xy 271.923383 -266.501674) (xy 271.972983 -266.476173)
			(xy 272.025767 -266.458166) (xy 272.08061 -266.448036) (xy 272.136344 -266.445999) (xy 272.191781 -266.452099)
			(xy 272.245738 -266.466205) (xy 272.297067 -266.488017) (xy 272.344673 -266.517071) (xy 272.387541 -266.552746)
			(xy 272.424758 -266.594283) (xy 272.455531 -266.640796) (xy 272.479203 -266.691293) (xy 272.495271 -266.7447)
			(xy 272.503391 -266.799876) (xy 272.5039 -266.827762) (xy 272.503391 -266.855648) (xy 272.495271 -266.910824)
			(xy 272.479203 -266.964231) (xy 272.455531 -267.014728) (xy 272.424758 -267.061241) (xy 272.387541 -267.102778)
			(xy 272.344673 -267.138453) (xy 272.297067 -267.167507) (xy 272.245738 -267.189319) (xy 272.191781 -267.203425)
			(xy 272.136344 -267.209525) (xy 272.08061 -267.207488) (xy 272.025767 -267.197358) (xy 271.972983 -267.179351)
			(xy 271.923383 -267.15385) (xy 271.878025 -267.121399) (xy 271.837876 -267.08269) (xy 271.80379 -267.038547)
			(xy 271.776494 -266.989912) (xy 271.756571 -266.937821) (xy 271.744445 -266.883384) (xy 271.740374 -266.827762)
			(xy 271.595026 -266.827762) (xy 271.610843 -266.880336) (xy 271.618963 -266.935512) (xy 271.619472 -266.963398)
			(xy 271.618963 -266.991284) (xy 271.610843 -267.04646) (xy 271.594775 -267.099867) (xy 271.571103 -267.150364)
			(xy 271.54033 -267.196877) (xy 271.503113 -267.238414) (xy 271.460245 -267.274089) (xy 271.412639 -267.303143)
			(xy 271.36131 -267.324955) (xy 271.307353 -267.339061) (xy 271.251916 -267.345161) (xy 271.196182 -267.343124)
			(xy 271.141339 -267.332994) (xy 271.088555 -267.314987) (xy 271.038955 -267.289486) (xy 270.993597 -267.257035)
			(xy 270.953448 -267.218326) (xy 270.919362 -267.174183) (xy 270.892066 -267.125548) (xy 270.872143 -267.073457)
			(xy 270.860017 -267.01902) (xy 270.855946 -266.963398) (xy 270.658298 -266.963398) (xy 270.662025 -266.968254)
			(xy 270.691148 -267.018691) (xy 270.713438 -267.072499) (xy 270.728512 -267.128756) (xy 270.736113 -267.186499)
			(xy 270.736568 -267.21562) (xy 270.736568 -268.766658) (xy 271.815721 -268.766658) (xy 271.815721 -268.712146)
			(xy 271.823479 -268.658189) (xy 271.838837 -268.605885) (xy 271.861482 -268.556299) (xy 271.890954 -268.510441)
			(xy 271.926652 -268.469244) (xy 271.96785 -268.433547) (xy 272.01371 -268.404076) (xy 272.063296 -268.381432)
			(xy 272.1156 -268.366076) (xy 272.169558 -268.35832) (xy 272.196814 -268.357858) (xy 272.222265 -268.358291)
			(xy 272.272712 -268.365091) (xy 272.321805 -268.378542) (xy 272.345404 -268.388084) (xy 272.358518 -268.393175)
			(xy 272.386414 -268.396718) (xy 272.414218 -268.392512) (xy 272.439817 -268.380875) (xy 272.461267 -268.362692)
			(xy 272.476939 -268.339344) (xy 272.485642 -268.312605) (xy 272.486715 -268.284505) (xy 272.483834 -268.270736)
			(xy 272.478981 -268.24896) (xy 272.473764 -268.204651) (xy 272.47342 -268.182344) (xy 272.473808 -268.155088)
			(xy 272.48156 -268.101129) (xy 272.496912 -268.048823) (xy 272.519551 -267.999234) (xy 272.549018 -267.953372)
			(xy 272.584712 -267.91217) (xy 272.625906 -267.876468) (xy 272.671761 -267.846991) (xy 272.721345 -267.824341)
			(xy 272.773648 -267.808977) (xy 272.827605 -267.801214) (xy 272.882118 -267.801208) (xy 272.936076 -267.808961)
			(xy 272.988382 -267.824314) (xy 273.037971 -267.846954) (xy 273.083832 -267.876421) (xy 273.125033 -267.912116)
			(xy 273.160735 -267.95331) (xy 273.190211 -267.999166) (xy 273.212861 -268.04875) (xy 273.228224 -268.101053)
			(xy 273.235987 -268.15501) (xy 273.235991 -268.209523) (xy 273.228238 -268.263481) (xy 273.212885 -268.315787)
			(xy 273.190243 -268.365375) (xy 273.160775 -268.411237) (xy 273.125081 -268.452437) (xy 273.083886 -268.488139)
			(xy 273.038029 -268.517614) (xy 272.988445 -268.540263) (xy 272.936141 -268.555625) (xy 272.882184 -268.563387)
			(xy 272.854928 -268.563852) (xy 272.829477 -268.563405) (xy 272.779031 -268.55661) (xy 272.729937 -268.543165)
			(xy 272.706338 -268.533626) (xy 272.693217 -268.528571) (xy 272.665332 -268.525047) (xy 272.637544 -268.529263)
			(xy 272.611959 -268.540898) (xy 272.590519 -268.559071) (xy 272.574848 -268.582403) (xy 272.566135 -268.609124)
			(xy 272.565041 -268.637209) (xy 272.567908 -268.650974) (xy 272.572763 -268.672749) (xy 272.577979 -268.717059)
			(xy 272.578322 -268.739366) (xy 272.577881 -268.766622) (xy 272.570128 -268.82058) (xy 272.554775 -268.872885)
			(xy 272.532133 -268.922473) (xy 272.502665 -268.968334) (xy 272.46697 -269.009534) (xy 272.425775 -269.045234)
			(xy 272.379919 -269.074708) (xy 272.330334 -269.097356) (xy 272.278031 -269.112717) (xy 272.224074 -269.120478)
			(xy 272.169562 -269.12048) (xy 272.115604 -269.112725) (xy 272.0633 -269.097369) (xy 272.013713 -269.074726)
			(xy 271.967854 -269.045256) (xy 271.926655 -269.009559) (xy 271.890956 -268.968362) (xy 271.861484 -268.922505)
			(xy 271.838838 -268.872919) (xy 271.823479 -268.820615) (xy 271.815721 -268.766658) (xy 270.736568 -268.766658)
			(xy 270.736568 -268.907006) (xy 270.73688 -268.915199) (xy 270.742061 -268.930745) (xy 270.746728 -268.937486)
			(xy 270.751554 -268.943074) (xy 273.275552 -271.467072) (xy 273.295856 -271.487964) (xy 273.331372 -271.534145)
			(xy 273.360549 -271.58457) (xy 273.382888 -271.638376) (xy 273.398004 -271.694639) (xy 273.405639 -271.752395)
			(xy 273.406108 -271.781524) (xy 273.405654 -271.810661) (xy 273.398045 -271.868435) (xy 273.38296 -271.924722)
			(xy 273.360658 -271.978559) (xy 273.331519 -272.029024) (xy 273.296043 -272.075255) (xy 273.254837 -272.116459)
			(xy 273.208604 -272.151933) (xy 273.158138 -272.181068) (xy 273.1043 -272.203368) (xy 273.048012 -272.21845)
			(xy 272.990237 -272.226056) (xy 272.9611 -272.226532) (xy 272.931976 -272.226) (xy 272.874231 -272.218348)
			(xy 272.817979 -272.203227) (xy 272.764181 -272.180896) (xy 272.713756 -272.151736) (xy 272.667566 -272.116246)
			(xy 272.646648 -272.095976) (xy 269.977362 -269.42669) (xy 269.957095 -269.405776) (xy 269.921632 -269.35958)
			(xy 269.892503 -269.30915) (xy 269.870207 -269.255348) (xy 269.855127 -269.199096) (xy 269.847518 -269.141357)
			(xy 269.84706 -269.112238) (xy 269.84706 -267.947394) (xy 269.846575 -267.938935) (xy 269.840693 -267.923054)
			(xy 269.829969 -267.909947) (xy 269.82293 -267.90523) (xy 269.81785 -267.902436) (xy 269.734284 -267.86332)
			(xy 269.727505 -267.860406) (xy 269.712919 -267.858214) (xy 269.705582 -267.859002) (xy 269.698724 -267.860018)
			(xy 269.68577 -267.86586) (xy 269.680182 -267.870432) (xy 269.659484 -267.887194) (xy 269.614307 -267.915401)
			(xy 269.565645 -267.93705) (xy 269.514445 -267.95172) (xy 269.461702 -267.959124) (xy 269.435072 -267.959586)
			(xy 269.407819 -267.959148) (xy 269.353868 -267.951387) (xy 269.301571 -267.936027) (xy 269.251993 -267.913381)
			(xy 269.206141 -267.88391) (xy 269.164951 -267.848214) (xy 269.12926 -267.807019) (xy 269.099795 -267.761163)
			(xy 269.077155 -267.711582) (xy 269.061802 -267.659283) (xy 269.054048 -267.605331) (xy 269.053564 -267.578078)
			(xy 269.054078 -267.550369) (xy 269.062103 -267.495536) (xy 269.07798 -267.442442) (xy 269.101377 -267.392205)
			(xy 269.131798 -267.345885) (xy 269.14983 -267.32484) (xy 269.150084 -267.324586) (xy 269.157317 -267.315367)
			(xy 269.163279 -267.292735) (xy 269.161514 -267.281152) (xy 269.145512 -267.201396) (xy 269.144188 -267.195691)
			(xy 269.139307 -267.185048) (xy 269.13586 -267.180314) (xy 269.132558 -267.175742) (xy 269.12316 -267.168376)
			(xy 269.11808 -267.165836) (xy 269.094169 -267.153815) (xy 269.049672 -267.124079) (xy 269.00977 -267.088414)
			(xy 268.975245 -267.047522) (xy 268.946775 -267.002205) (xy 268.924919 -266.953353) (xy 268.910107 -266.901926)
			(xy 268.90263 -266.848933) (xy 268.90218 -266.822174) (xy 268.902654 -266.794923) (xy 268.910413 -266.740975)
			(xy 268.925771 -266.688681) (xy 268.948414 -266.639104) (xy 268.977882 -266.593255) (xy 269.013575 -266.552065)
			(xy 269.054766 -266.516374) (xy 269.100617 -266.486908) (xy 269.150194 -266.464266) (xy 269.202489 -266.44891)
			(xy 269.256437 -266.441153) (xy 269.283688 -266.440666) (xy 269.300286 -266.440863) (xy 269.333353 -266.443788)
			(xy 269.349728 -266.446508) (xy 269.360783 -266.447867) (xy 269.382263 -266.442072) (xy 269.39113 -266.435332)
			(xy 269.45082 -266.385548) (xy 269.459202 -266.376658) (xy 269.463606 -266.370228) (xy 269.468638 -266.355483)
			(xy 269.469108 -266.347702) (xy 269.469108 -264.623296) (xy 269.468854 -264.617454) (xy 269.467514 -264.608962)
			(xy 269.459982 -264.593519) (xy 269.454122 -264.587228) (xy 269.08506 -264.21842) (xy 269.077915 -264.211931)
			(xy 269.060193 -264.204327) (xy 269.040916 -264.203808) (xy 269.03172 -264.206736) (xy 268.945106 -264.238486)
			(xy 268.94173 -264.2398) (xy 268.935357 -264.243243) (xy 268.932406 -264.245344) (xy 268.926564 -264.249662)
			(xy 268.922246 -264.255504) (xy 268.918112 -264.261309) (xy 268.912961 -264.274592) (xy 268.912086 -264.281666)
			(xy 268.912086 -264.28192) (xy 268.909162 -264.310174) (xy 268.896131 -264.365457) (xy 268.875048 -264.418198)
			(xy 268.846379 -264.46723) (xy 268.810758 -264.51147) (xy 268.768973 -264.54994) (xy 268.721945 -264.581791)
			(xy 268.670716 -264.606318) (xy 268.616417 -264.622979) (xy 268.560247 -264.631407) (xy 268.531848 -264.631932)
			(xy 268.504597 -264.6314) (xy 268.45065 -264.62365) (xy 268.398355 -264.608302) (xy 268.348777 -264.585666)
			(xy 268.302925 -264.556206) (xy 268.261732 -264.520519) (xy 268.226038 -264.479333) (xy 268.196568 -264.433487)
			(xy 268.173924 -264.383912) (xy 268.158565 -264.33162) (xy 268.150805 -264.277674) (xy 268.15034 -264.250424)
			(xy 268.150808 -264.222019) (xy 268.159229 -264.165838) (xy 268.175887 -264.111526) (xy 268.200414 -264.060285)
			(xy 268.232269 -264.013247) (xy 268.270747 -263.971453) (xy 268.314996 -263.935827) (xy 268.364039 -263.907156)
			(xy 268.416792 -263.886074) (xy 268.472087 -263.873048) (xy 268.500352 -263.870186) (xy 268.507718 -263.869424)
			(xy 268.520926 -263.864598) (xy 268.526768 -263.86028) (xy 268.532455 -263.855707) (xy 268.541091 -263.843949)
			(xy 268.543786 -263.837166) (xy 268.575536 -263.750552) (xy 268.578472 -263.741358) (xy 268.577944 -263.722078)
			(xy 268.570353 -263.704347) (xy 268.563852 -263.697212) (xy 266.039346 -261.172706) (xy 266.033758 -261.16788)
			(xy 266.027022 -261.163205) (xy 266.011472 -261.158026) (xy 266.003278 -261.15772) (xy 263.268968 -261.15772)
			(xy 263.265158 -261.157974) (xy 263.26465 -261.157974) (xy 263.252844 -261.159584) (xy 263.232572 -261.172053)
			(xy 263.225788 -261.18185) (xy 263.180576 -261.255002) (xy 263.176305 -261.262535) (xy 263.172629 -261.279449)
			(xy 263.174751 -261.296627) (xy 263.17829 -261.304532) (xy 263.190814 -261.331049) (xy 263.208565 -261.386939)
			(xy 263.217577 -261.444884) (xy 263.218168 -261.474204) (xy 263.218168 -261.474458) (xy 263.217682 -261.501709)
			(xy 263.209926 -261.555657) (xy 263.194571 -261.607952) (xy 263.171929 -261.657529) (xy 263.142463 -261.703379)
			(xy 263.106772 -261.74457) (xy 263.065581 -261.780261) (xy 263.019731 -261.809727) (xy 262.970154 -261.832369)
			(xy 262.917859 -261.847724) (xy 262.863911 -261.85548) (xy 262.809409 -261.85548) (xy 262.755461 -261.847724)
			(xy 262.703166 -261.832369) (xy 262.653589 -261.809727) (xy 262.607739 -261.780261) (xy 262.566548 -261.74457)
			(xy 262.530857 -261.703379) (xy 262.501391 -261.657529) (xy 262.478749 -261.607952) (xy 262.463394 -261.555657)
			(xy 262.455638 -261.501709) (xy 262.455152 -261.474458) (xy 262.455152 -261.474204) (xy 262.455705 -261.444879)
			(xy 262.464686 -261.386921) (xy 262.48245 -261.331027) (xy 262.49503 -261.304532) (xy 262.498624 -261.296642)
			(xy 262.500784 -261.27945) (xy 262.497045 -261.262531) (xy 262.492744 -261.255002) (xy 262.447532 -261.18185)
			(xy 262.44072 -261.172082) (xy 262.420463 -261.159623) (xy 262.40867 -261.157974) (xy 262.408162 -261.157974)
			(xy 262.404352 -261.15772) (xy 261.78383 -261.15772) (xy 261.78002 -261.157974) (xy 261.779512 -261.157974)
			(xy 261.767701 -261.159563) (xy 261.747431 -261.172047) (xy 261.74065 -261.18185) (xy 261.695438 -261.255002)
			(xy 261.691167 -261.262535) (xy 261.687494 -261.279449) (xy 261.689614 -261.296627) (xy 261.693152 -261.304532)
			(xy 261.7057 -261.33104) (xy 261.723454 -261.386933) (xy 261.732467 -261.444882) (xy 261.73303 -261.474204)
			(xy 261.73303 -261.474458) (xy 261.732544 -261.501709) (xy 261.724788 -261.555657) (xy 261.709433 -261.607952)
			(xy 261.686791 -261.657529) (xy 261.657325 -261.703379) (xy 261.621634 -261.74457) (xy 261.580443 -261.780261)
			(xy 261.534593 -261.809727) (xy 261.485016 -261.832369) (xy 261.432721 -261.847724) (xy 261.378773 -261.85548)
			(xy 261.324271 -261.85548) (xy 261.270323 -261.847724) (xy 261.218028 -261.832369) (xy 261.168451 -261.809727)
			(xy 261.122601 -261.780261) (xy 261.08141 -261.74457) (xy 261.045719 -261.703379) (xy 261.016253 -261.657529)
			(xy 260.993611 -261.607952) (xy 260.978256 -261.555657) (xy 260.9705 -261.501709) (xy 260.970014 -261.474458)
			(xy 260.970014 -261.474204) (xy 260.970561 -261.444879) (xy 260.979543 -261.386921) (xy 260.99731 -261.331026)
			(xy 261.009892 -261.304532) (xy 261.01349 -261.296643) (xy 261.015652 -261.27945) (xy 261.01191 -261.26253)
			(xy 261.007606 -261.255002) (xy 260.962394 -261.18185) (xy 260.9556 -261.172067) (xy 260.935329 -261.159616)
			(xy 260.923532 -261.157974) (xy 260.923024 -261.157974) (xy 260.919214 -261.15772) (xy 260.561328 -261.15772)
			(xy 260.553135 -261.158038) (xy 260.537589 -261.163214) (xy 260.530848 -261.16788) (xy 260.52526 -261.172706)
			(xy 260.444488 -261.253478) (xy 260.438453 -261.259959) (xy 260.430928 -261.275979) (xy 260.429337 -261.293606)
			(xy 260.43128 -261.302246) (xy 260.453378 -261.387082) (xy 260.456426 -261.395464) (xy 260.461583 -261.405274)
			(xy 260.478429 -261.419634) (xy 260.488938 -261.42315) (xy 260.515316 -261.431063) (xy 260.565668 -261.453364)
			(xy 260.612293 -261.482669) (xy 260.654222 -261.51837) (xy 260.690587 -261.559725) (xy 260.720631 -261.605877)
			(xy 260.743732 -261.655867) (xy 260.75941 -261.708658) (xy 260.767339 -261.763153) (xy 260.76783 -261.790688)
			(xy 260.767311 -261.817938) (xy 260.759556 -261.871883) (xy 260.744204 -261.924176) (xy 260.721566 -261.973752)
			(xy 260.692103 -262.019601) (xy 260.656415 -262.060791) (xy 260.615228 -262.096482) (xy 260.569382 -262.125949)
			(xy 260.519808 -262.148592) (xy 260.467517 -262.163949) (xy 260.413572 -262.171708) (xy 260.386322 -262.172196)
			(xy 260.356738 -262.171622) (xy 260.29828 -262.162491) (xy 260.241933 -262.144443) (xy 260.189047 -262.117911)
			(xy 260.140893 -262.083533) (xy 260.119368 -262.06323) (xy 260.119114 -262.062976) (xy 260.111196 -262.056057)
			(xy 260.091527 -262.048696) (xy 260.081014 -262.048752) (xy 260.006084 -262.052816) (xy 259.992876 -262.055356)
			(xy 259.98604 -262.057871) (xy 259.974049 -262.066129) (xy 259.969254 -262.071612) (xy 259.951085 -262.093194)
			(xy 259.910223 -262.132091) (xy 259.864774 -262.165514) (xy 259.815467 -262.192928) (xy 259.763092 -262.213893)
			(xy 259.708488 -262.228073) (xy 259.652529 -262.23524) (xy 259.624322 -262.235696) (xy 259.596112 -262.235241)
			(xy 259.540146 -262.228096) (xy 259.485533 -262.213931) (xy 259.43315 -262.192973) (xy 259.383838 -262.165558)
			(xy 259.338389 -262.132128) (xy 259.297533 -262.093218) (xy 259.27939 -262.071612) (xy 259.274629 -262.066092)
			(xy 259.262623 -262.057836) (xy 259.255768 -262.055356) (xy 259.24256 -262.052816) (xy 259.16763 -262.048752)
			(xy 259.157118 -262.048705) (xy 259.137444 -262.056056) (xy 259.12953 -262.062976) (xy 259.129276 -262.06323)
			(xy 259.107744 -262.083526) (xy 259.059592 -262.117909) (xy 259.006709 -262.144445) (xy 258.950363 -262.162499)
			(xy 258.891906 -262.171637) (xy 258.862322 -262.172196) (xy 258.833406 -262.171663) (xy 258.776235 -262.162937)
			(xy 258.721036 -262.145682) (xy 258.669075 -262.120294) (xy 258.62154 -262.087353) (xy 258.579523 -262.047614)
			(xy 258.561332 -262.02513) (xy 258.553764 -262.016375) (xy 258.533009 -262.006191) (xy 258.521454 -262.005572)
			(xy 258.44119 -262.005572) (xy 258.429617 -262.006112) (xy 258.408845 -262.016325) (xy 258.401312 -262.02513)
			(xy 258.383122 -262.047614) (xy 258.341101 -262.087348) (xy 258.293566 -262.120286) (xy 258.241604 -262.145674)
			(xy 258.186407 -262.16293) (xy 258.129238 -262.17166) (xy 258.100322 -262.172196) (xy 258.073067 -262.171759)
			(xy 258.019112 -262.164004) (xy 257.96681 -262.148649) (xy 257.917225 -262.126007) (xy 257.871368 -262.096539)
			(xy 257.830171 -262.060844) (xy 257.794474 -262.01965) (xy 257.765003 -261.973794) (xy 257.742358 -261.924211)
			(xy 257.727001 -261.871909) (xy 257.719243 -261.817955) (xy 253.503773 -261.817955) (xy 254.59817 -262.912352)
			(xy 257.3688 -262.912352) (xy 257.372871 -262.85673) (xy 257.384997 -262.802293) (xy 257.40492 -262.750202)
			(xy 257.432216 -262.701567) (xy 257.466302 -262.657424) (xy 257.506451 -262.618715) (xy 257.551809 -262.586264)
			(xy 257.601409 -262.560763) (xy 257.654193 -262.542756) (xy 257.709036 -262.532626) (xy 257.76477 -262.530589)
			(xy 257.820207 -262.536689) (xy 257.874164 -262.550795) (xy 257.925493 -262.572607) (xy 257.973099 -262.601661)
			(xy 258.015967 -262.637336) (xy 258.053184 -262.678873) (xy 258.083957 -262.725386) (xy 258.107629 -262.775883)
			(xy 258.123697 -262.82929) (xy 258.131817 -262.884466) (xy 258.132326 -262.912352) (xy 258.132205 -262.918956)
			(xy 259.356858 -262.918956) (xy 259.360929 -262.863334) (xy 259.373055 -262.808897) (xy 259.392978 -262.756806)
			(xy 259.420274 -262.708171) (xy 259.45436 -262.664028) (xy 259.494509 -262.625319) (xy 259.539867 -262.592868)
			(xy 259.589467 -262.567367) (xy 259.642251 -262.54936) (xy 259.697094 -262.53923) (xy 259.752828 -262.537193)
			(xy 259.808265 -262.543293) (xy 259.862222 -262.557399) (xy 259.913551 -262.579211) (xy 259.961157 -262.608265)
			(xy 260.004025 -262.64394) (xy 260.041242 -262.685477) (xy 260.072015 -262.73199) (xy 260.095687 -262.782487)
			(xy 260.111755 -262.835894) (xy 260.119875 -262.89107) (xy 260.120384 -262.918956) (xy 260.119875 -262.946842)
			(xy 260.111755 -263.002018) (xy 260.107925 -263.014747) (xy 264.681514 -263.014747) (xy 264.681514 -262.960253)
			(xy 264.689269 -262.906314) (xy 264.704621 -262.854027) (xy 264.727257 -262.804457) (xy 264.756717 -262.758613)
			(xy 264.792401 -262.717428) (xy 264.833583 -262.68174) (xy 264.879424 -262.652275) (xy 264.928991 -262.629634)
			(xy 264.981277 -262.614277) (xy 265.035215 -262.606517) (xy 265.062462 -262.606028) (xy 265.093475 -262.606629)
			(xy 265.154687 -262.616652) (xy 265.213472 -262.636442) (xy 265.268284 -262.665477) (xy 265.293348 -262.683752)
			(xy 265.304384 -262.691639) (xy 265.329499 -262.701857) (xy 265.35642 -262.705089) (xy 265.38324 -262.701108)
			(xy 265.40806 -262.690194) (xy 265.429124 -262.673122) (xy 265.44494 -262.651098) (xy 265.450066 -262.63854)
			(xy 265.460733 -262.611673) (xy 265.48898 -262.56124) (xy 265.524513 -262.515646) (xy 265.566518 -262.475936)
			(xy 265.614034 -262.443018) (xy 265.665973 -262.417646) (xy 265.721145 -262.400401) (xy 265.778288 -262.391678)
			(xy 265.80719 -262.391144) (xy 265.83444 -262.391703) (xy 265.888385 -262.399457) (xy 265.940678 -262.414811)
			(xy 265.990253 -262.43745) (xy 266.036101 -262.466914) (xy 266.07729 -262.502603) (xy 266.11298 -262.543791)
			(xy 266.142446 -262.589638) (xy 266.165086 -262.639213) (xy 266.18044 -262.691505) (xy 266.188197 -262.74545)
			(xy 266.188197 -262.79995) (xy 266.18044 -262.853895) (xy 266.165086 -262.906187) (xy 266.142446 -262.955762)
			(xy 266.11298 -263.001609) (xy 266.07729 -263.042797) (xy 266.036101 -263.078486) (xy 265.990253 -263.10795)
			(xy 265.940678 -263.130589) (xy 265.888385 -263.145943) (xy 265.83444 -263.153697) (xy 265.80719 -263.15416)
			(xy 265.776175 -263.153587) (xy 265.714963 -263.143555) (xy 265.656177 -263.123758) (xy 265.601367 -263.094715)
			(xy 265.576304 -263.076436) (xy 265.565304 -263.068497) (xy 265.540178 -263.058286) (xy 265.513248 -263.055062)
			(xy 265.486422 -263.059052) (xy 265.461597 -263.069974) (xy 265.44053 -263.087055) (xy 265.424713 -263.109086)
			(xy 265.419586 -263.121648) (xy 265.408953 -263.14853) (xy 265.380703 -263.198965) (xy 265.345166 -263.24456)
			(xy 265.303156 -263.28427) (xy 265.255634 -263.317187) (xy 265.20369 -263.342556) (xy 265.148513 -263.359796)
			(xy 265.091366 -263.368513) (xy 265.062462 -263.369044) (xy 265.035215 -263.368483) (xy 264.981277 -263.360723)
			(xy 264.928991 -263.345366) (xy 264.879424 -263.322725) (xy 264.833583 -263.29326) (xy 264.792401 -263.257572)
			(xy 264.756717 -263.216387) (xy 264.727257 -263.170543) (xy 264.704621 -263.120973) (xy 264.689269 -263.068686)
			(xy 264.681514 -263.014747) (xy 260.107925 -263.014747) (xy 260.095687 -263.055425) (xy 260.072015 -263.105922)
			(xy 260.041242 -263.152435) (xy 260.004025 -263.193972) (xy 259.961157 -263.229647) (xy 259.913551 -263.258701)
			(xy 259.862222 -263.280513) (xy 259.808265 -263.294619) (xy 259.752828 -263.300719) (xy 259.697094 -263.298682)
			(xy 259.642251 -263.288552) (xy 259.589467 -263.270545) (xy 259.539867 -263.245044) (xy 259.494509 -263.212593)
			(xy 259.45436 -263.173884) (xy 259.420274 -263.129741) (xy 259.392978 -263.081106) (xy 259.373055 -263.029015)
			(xy 259.360929 -262.974578) (xy 259.356858 -262.918956) (xy 258.132205 -262.918956) (xy 258.131817 -262.940238)
			(xy 258.123697 -262.995414) (xy 258.107629 -263.048821) (xy 258.083957 -263.099318) (xy 258.053184 -263.145831)
			(xy 258.015967 -263.187368) (xy 257.973099 -263.223043) (xy 257.925493 -263.252097) (xy 257.874164 -263.273909)
			(xy 257.820207 -263.288015) (xy 257.76477 -263.294115) (xy 257.709036 -263.292078) (xy 257.654193 -263.281948)
			(xy 257.601409 -263.263941) (xy 257.551809 -263.23844) (xy 257.506451 -263.205989) (xy 257.466302 -263.16728)
			(xy 257.432216 -263.123137) (xy 257.40492 -263.074502) (xy 257.384997 -263.022411) (xy 257.372871 -262.967974)
			(xy 257.3688 -262.912352) (xy 254.59817 -262.912352) (xy 258.847082 -267.161264) (xy 258.853998 -267.167537)
			(xy 258.871063 -267.17508) (xy 258.880356 -267.175996) (xy 258.889246 -267.176504) (xy 258.906518 -267.17117)
			(xy 258.914138 -267.165074) (xy 258.992205 -267.104353) (xy 259.152664 -266.988692) (xy 259.317799 -266.879809)
			(xy 259.487323 -266.777896) (xy 259.660942 -266.683127) (xy 259.838356 -266.595667) (xy 260.019256 -266.515669)
			(xy 260.20333 -266.443269) (xy 260.390258 -266.378595) (xy 260.579716 -266.321759) (xy 260.771376 -266.272857)
			(xy 260.964905 -266.231977) (xy 261.159968 -266.199188) (xy 261.356227 -266.174546) (xy 261.553342 -266.158096)
			(xy 261.75097 -266.149865) (xy 261.84987 -266.149328) (xy 261.94806 -266.149828) (xy 262.144274 -266.157942)
			(xy 262.339984 -266.174158) (xy 262.534857 -266.198448) (xy 262.72856 -266.23077) (xy 262.920762 -266.271069)
			(xy 263.111134 -266.319277) (xy 263.299351 -266.37531) (xy 263.485092 -266.439074) (xy 263.668039 -266.510459)
			(xy 263.84788 -266.589344) (xy 264.024307 -266.675593) (xy 264.197019 -266.769059) (xy 264.365722 -266.869582)
			(xy 264.530126 -266.976992) (xy 264.689951 -267.091104) (xy 264.844923 -267.211723) (xy 264.994779 -267.338643)
			(xy 265.139262 -267.471647) (xy 265.278125 -267.610509) (xy 265.411131 -267.754991) (xy 265.538052 -267.904845)
			(xy 265.658672 -268.059817) (xy 265.772786 -268.219641) (xy 265.880196 -268.384044) (xy 265.980721 -268.552746)
			(xy 266.074189 -268.725457) (xy 266.160439 -268.901884) (xy 266.239325 -269.081724) (xy 266.310712 -269.264671)
			(xy 266.374477 -269.450411) (xy 266.430512 -269.638628) (xy 266.478722 -269.829) (xy 266.519023 -270.021201)
			(xy 266.551346 -270.214903) (xy 266.575638 -270.409776) (xy 266.591855 -270.605486) (xy 266.599971 -270.8017)
			(xy 266.600432 -270.89989) (xy 266.599931 -270.997499) (xy 266.591899 -271.192551) (xy 266.575861 -271.387109)
			(xy 266.551845 -271.580843) (xy 266.51989 -271.773427) (xy 266.48005 -271.964536) (xy 266.432393 -272.153848)
			(xy 266.376999 -272.341041) (xy 266.313962 -272.525801) (xy 266.275575 -272.624804) (xy 270.169144 -272.624804)
			(xy 270.173104 -272.57575) (xy 270.184881 -272.527966) (xy 270.204172 -272.48269) (xy 270.230475 -272.441094)
			(xy 270.26311 -272.404257) (xy 270.301231 -272.373132) (xy 270.343852 -272.348525) (xy 270.389868 -272.331073)
			(xy 270.438087 -272.321229) (xy 270.487262 -272.319248) (xy 270.536117 -272.32518) (xy 270.583388 -272.338872)
			(xy 270.62785 -272.35997) (xy 270.668353 -272.387926) (xy 270.703846 -272.422018) (xy 270.733411 -272.461362)
			(xy 270.756282 -272.504939) (xy 270.771866 -272.55162) (xy 270.779761 -272.600197) (xy 270.780256 -272.624804)
			(xy 271.119104 -272.624804) (xy 271.123064 -272.57575) (xy 271.134841 -272.527966) (xy 271.154132 -272.48269)
			(xy 271.180435 -272.441094) (xy 271.21307 -272.404257) (xy 271.251191 -272.373132) (xy 271.293812 -272.348525)
			(xy 271.339828 -272.331073) (xy 271.388047 -272.321229) (xy 271.437222 -272.319248) (xy 271.486077 -272.32518)
			(xy 271.533348 -272.338872) (xy 271.57781 -272.35997) (xy 271.618313 -272.387926) (xy 271.653806 -272.422018)
			(xy 271.683371 -272.461362) (xy 271.706242 -272.504939) (xy 271.721826 -272.55162) (xy 271.729721 -272.600197)
			(xy 271.730216 -272.624804) (xy 272.069064 -272.624804) (xy 272.073024 -272.57575) (xy 272.084801 -272.527966)
			(xy 272.104092 -272.48269) (xy 272.130395 -272.441094) (xy 272.16303 -272.404257) (xy 272.201151 -272.373132)
			(xy 272.243772 -272.348525) (xy 272.289788 -272.331073) (xy 272.338007 -272.321229) (xy 272.387182 -272.319248)
			(xy 272.436037 -272.32518) (xy 272.483308 -272.338872) (xy 272.52777 -272.35997) (xy 272.568273 -272.387926)
			(xy 272.603766 -272.422018) (xy 272.633331 -272.461362) (xy 272.656202 -272.504939) (xy 272.671786 -272.55162)
			(xy 272.679681 -272.600197) (xy 272.680176 -272.624804) (xy 273.019024 -272.624804) (xy 273.022984 -272.57575)
			(xy 273.034761 -272.527966) (xy 273.054052 -272.48269) (xy 273.080355 -272.441094) (xy 273.11299 -272.404257)
			(xy 273.151111 -272.373132) (xy 273.193732 -272.348525) (xy 273.239748 -272.331073) (xy 273.287967 -272.321229)
			(xy 273.337142 -272.319248) (xy 273.385997 -272.32518) (xy 273.433268 -272.338872) (xy 273.47773 -272.35997)
			(xy 273.518233 -272.387926) (xy 273.553726 -272.422018) (xy 273.583291 -272.461362) (xy 273.606162 -272.504939)
			(xy 273.621746 -272.55162) (xy 273.629641 -272.600197) (xy 273.630136 -272.624804) (xy 273.968984 -272.624804)
			(xy 273.972944 -272.57575) (xy 273.984721 -272.527966) (xy 274.004012 -272.48269) (xy 274.030315 -272.441094)
			(xy 274.06295 -272.404257) (xy 274.101071 -272.373132) (xy 274.143692 -272.348525) (xy 274.189708 -272.331073)
			(xy 274.237927 -272.321229) (xy 274.287102 -272.319248) (xy 274.335957 -272.32518) (xy 274.383228 -272.338872)
			(xy 274.42769 -272.35997) (xy 274.468193 -272.387926) (xy 274.503686 -272.422018) (xy 274.533251 -272.461362)
			(xy 274.556122 -272.504939) (xy 274.571706 -272.55162) (xy 274.579601 -272.600197) (xy 274.580096 -272.624804)
			(xy 274.579601 -272.649411) (xy 274.571706 -272.697988) (xy 274.556122 -272.744669) (xy 274.533251 -272.788246)
			(xy 274.503686 -272.82759) (xy 274.468193 -272.861682) (xy 274.42769 -272.889638) (xy 274.383228 -272.910736)
			(xy 274.335957 -272.924428) (xy 274.287102 -272.93036) (xy 274.237927 -272.928379) (xy 274.189708 -272.918535)
			(xy 274.143692 -272.901083) (xy 274.101071 -272.876476) (xy 274.06295 -272.845351) (xy 274.030315 -272.808514)
			(xy 274.004012 -272.766918) (xy 273.984721 -272.721642) (xy 273.972944 -272.673858) (xy 273.968984 -272.624804)
			(xy 273.630136 -272.624804) (xy 273.629641 -272.649411) (xy 273.621746 -272.697988) (xy 273.606162 -272.744669)
			(xy 273.583291 -272.788246) (xy 273.553726 -272.82759) (xy 273.518233 -272.861682) (xy 273.47773 -272.889638)
			(xy 273.433268 -272.910736) (xy 273.385997 -272.924428) (xy 273.337142 -272.93036) (xy 273.287967 -272.928379)
			(xy 273.239748 -272.918535) (xy 273.193732 -272.901083) (xy 273.151111 -272.876476) (xy 273.11299 -272.845351)
			(xy 273.080355 -272.808514) (xy 273.054052 -272.766918) (xy 273.034761 -272.721642) (xy 273.022984 -272.673858)
			(xy 273.019024 -272.624804) (xy 272.680176 -272.624804) (xy 272.679681 -272.649411) (xy 272.671786 -272.697988)
			(xy 272.656202 -272.744669) (xy 272.633331 -272.788246) (xy 272.603766 -272.82759) (xy 272.568273 -272.861682)
			(xy 272.52777 -272.889638) (xy 272.483308 -272.910736) (xy 272.436037 -272.924428) (xy 272.387182 -272.93036)
			(xy 272.338007 -272.928379) (xy 272.289788 -272.918535) (xy 272.243772 -272.901083) (xy 272.201151 -272.876476)
			(xy 272.16303 -272.845351) (xy 272.130395 -272.808514) (xy 272.104092 -272.766918) (xy 272.084801 -272.721642)
			(xy 272.073024 -272.673858) (xy 272.069064 -272.624804) (xy 271.730216 -272.624804) (xy 271.729721 -272.649411)
			(xy 271.721826 -272.697988) (xy 271.706242 -272.744669) (xy 271.683371 -272.788246) (xy 271.653806 -272.82759)
			(xy 271.618313 -272.861682) (xy 271.57781 -272.889638) (xy 271.533348 -272.910736) (xy 271.486077 -272.924428)
			(xy 271.437222 -272.93036) (xy 271.388047 -272.928379) (xy 271.339828 -272.918535) (xy 271.293812 -272.901083)
			(xy 271.251191 -272.876476) (xy 271.21307 -272.845351) (xy 271.180435 -272.808514) (xy 271.154132 -272.766918)
			(xy 271.134841 -272.721642) (xy 271.123064 -272.673858) (xy 271.119104 -272.624804) (xy 270.780256 -272.624804)
			(xy 270.779761 -272.649411) (xy 270.771866 -272.697988) (xy 270.756282 -272.744669) (xy 270.733411 -272.788246)
			(xy 270.703846 -272.82759) (xy 270.668353 -272.861682) (xy 270.62785 -272.889638) (xy 270.583388 -272.910736)
			(xy 270.536117 -272.924428) (xy 270.487262 -272.93036) (xy 270.438087 -272.928379) (xy 270.389868 -272.918535)
			(xy 270.343852 -272.901083) (xy 270.301231 -272.876476) (xy 270.26311 -272.845351) (xy 270.230475 -272.808514)
			(xy 270.204172 -272.766918) (xy 270.184881 -272.721642) (xy 270.173104 -272.673858) (xy 270.169144 -272.624804)
			(xy 266.275575 -272.624804) (xy 266.243388 -272.707815) (xy 266.165396 -272.886776) (xy 266.080118 -273.062383)
			(xy 265.987699 -273.234338) (xy 265.888293 -273.40235) (xy 265.782069 -273.566138) (xy 265.775957 -273.574764)
			(xy 269.21893 -273.574764) (xy 269.22289 -273.52571) (xy 269.234667 -273.477926) (xy 269.253958 -273.43265)
			(xy 269.280261 -273.391054) (xy 269.312896 -273.354217) (xy 269.351017 -273.323092) (xy 269.393638 -273.298485)
			(xy 269.439654 -273.281033) (xy 269.487873 -273.271189) (xy 269.537048 -273.269208) (xy 269.585903 -273.27514)
			(xy 269.633174 -273.288832) (xy 269.677636 -273.30993) (xy 269.718139 -273.337886) (xy 269.753632 -273.371978)
			(xy 269.783197 -273.411322) (xy 269.806068 -273.454899) (xy 269.821652 -273.50158) (xy 269.829547 -273.550157)
			(xy 269.830042 -273.574764) (xy 270.16889 -273.574764) (xy 270.17285 -273.52571) (xy 270.184627 -273.477926)
			(xy 270.203918 -273.43265) (xy 270.230221 -273.391054) (xy 270.262856 -273.354217) (xy 270.300977 -273.323092)
			(xy 270.343598 -273.298485) (xy 270.389614 -273.281033) (xy 270.437833 -273.271189) (xy 270.487008 -273.269208)
			(xy 270.535863 -273.27514) (xy 270.583134 -273.288832) (xy 270.627596 -273.30993) (xy 270.668099 -273.337886)
			(xy 270.703592 -273.371978) (xy 270.733157 -273.411322) (xy 270.756028 -273.454899) (xy 270.771612 -273.50158)
			(xy 270.779507 -273.550157) (xy 270.780002 -273.574764) (xy 271.119104 -273.574764) (xy 271.123064 -273.52571)
			(xy 271.134841 -273.477926) (xy 271.154132 -273.43265) (xy 271.180435 -273.391054) (xy 271.21307 -273.354217)
			(xy 271.251191 -273.323092) (xy 271.293812 -273.298485) (xy 271.339828 -273.281033) (xy 271.388047 -273.271189)
			(xy 271.437222 -273.269208) (xy 271.486077 -273.27514) (xy 271.533348 -273.288832) (xy 271.57781 -273.30993)
			(xy 271.618313 -273.337886) (xy 271.653806 -273.371978) (xy 271.683371 -273.411322) (xy 271.706242 -273.454899)
			(xy 271.721826 -273.50158) (xy 271.729721 -273.550157) (xy 271.730216 -273.574764) (xy 272.069064 -273.574764)
			(xy 272.073024 -273.52571) (xy 272.084801 -273.477926) (xy 272.104092 -273.43265) (xy 272.130395 -273.391054)
			(xy 272.16303 -273.354217) (xy 272.201151 -273.323092) (xy 272.243772 -273.298485) (xy 272.289788 -273.281033)
			(xy 272.338007 -273.271189) (xy 272.387182 -273.269208) (xy 272.436037 -273.27514) (xy 272.483308 -273.288832)
			(xy 272.52777 -273.30993) (xy 272.568273 -273.337886) (xy 272.603766 -273.371978) (xy 272.633331 -273.411322)
			(xy 272.656202 -273.454899) (xy 272.671786 -273.50158) (xy 272.679681 -273.550157) (xy 272.680176 -273.574764)
			(xy 273.019024 -273.574764) (xy 273.022984 -273.52571) (xy 273.034761 -273.477926) (xy 273.054052 -273.43265)
			(xy 273.080355 -273.391054) (xy 273.11299 -273.354217) (xy 273.151111 -273.323092) (xy 273.193732 -273.298485)
			(xy 273.239748 -273.281033) (xy 273.287967 -273.271189) (xy 273.337142 -273.269208) (xy 273.385997 -273.27514)
			(xy 273.433268 -273.288832) (xy 273.47773 -273.30993) (xy 273.518233 -273.337886) (xy 273.553726 -273.371978)
			(xy 273.583291 -273.411322) (xy 273.606162 -273.454899) (xy 273.621746 -273.50158) (xy 273.629641 -273.550157)
			(xy 273.630136 -273.574764) (xy 273.968984 -273.574764) (xy 273.972944 -273.52571) (xy 273.984721 -273.477926)
			(xy 274.004012 -273.43265) (xy 274.030315 -273.391054) (xy 274.06295 -273.354217) (xy 274.101071 -273.323092)
			(xy 274.143692 -273.298485) (xy 274.189708 -273.281033) (xy 274.237927 -273.271189) (xy 274.287102 -273.269208)
			(xy 274.335957 -273.27514) (xy 274.383228 -273.288832) (xy 274.42769 -273.30993) (xy 274.468193 -273.337886)
			(xy 274.503686 -273.371978) (xy 274.533251 -273.411322) (xy 274.556122 -273.454899) (xy 274.571706 -273.50158)
			(xy 274.579601 -273.550157) (xy 274.580096 -273.574764) (xy 274.579601 -273.599371) (xy 274.571706 -273.647948)
			(xy 274.556122 -273.694629) (xy 274.533251 -273.738206) (xy 274.503686 -273.77755) (xy 274.468193 -273.811642)
			(xy 274.42769 -273.839598) (xy 274.383228 -273.860696) (xy 274.335957 -273.874388) (xy 274.287102 -273.88032)
			(xy 274.237927 -273.878339) (xy 274.189708 -273.868495) (xy 274.143692 -273.851043) (xy 274.101071 -273.826436)
			(xy 274.06295 -273.795311) (xy 274.030315 -273.758474) (xy 274.004012 -273.716878) (xy 273.984721 -273.671602)
			(xy 273.972944 -273.623818) (xy 273.968984 -273.574764) (xy 273.630136 -273.574764) (xy 273.629641 -273.599371)
			(xy 273.621746 -273.647948) (xy 273.606162 -273.694629) (xy 273.583291 -273.738206) (xy 273.553726 -273.77755)
			(xy 273.518233 -273.811642) (xy 273.47773 -273.839598) (xy 273.433268 -273.860696) (xy 273.385997 -273.874388)
			(xy 273.337142 -273.88032) (xy 273.287967 -273.878339) (xy 273.239748 -273.868495) (xy 273.193732 -273.851043)
			(xy 273.151111 -273.826436) (xy 273.11299 -273.795311) (xy 273.080355 -273.758474) (xy 273.054052 -273.716878)
			(xy 273.034761 -273.671602) (xy 273.022984 -273.623818) (xy 273.019024 -273.574764) (xy 272.680176 -273.574764)
			(xy 272.679681 -273.599371) (xy 272.671786 -273.647948) (xy 272.656202 -273.694629) (xy 272.633331 -273.738206)
			(xy 272.603766 -273.77755) (xy 272.568273 -273.811642) (xy 272.52777 -273.839598) (xy 272.483308 -273.860696)
			(xy 272.436037 -273.874388) (xy 272.387182 -273.88032) (xy 272.338007 -273.878339) (xy 272.289788 -273.868495)
			(xy 272.243772 -273.851043) (xy 272.201151 -273.826436) (xy 272.16303 -273.795311) (xy 272.130395 -273.758474)
			(xy 272.104092 -273.716878) (xy 272.084801 -273.671602) (xy 272.073024 -273.623818) (xy 272.069064 -273.574764)
			(xy 271.730216 -273.574764) (xy 271.729721 -273.599371) (xy 271.721826 -273.647948) (xy 271.706242 -273.694629)
			(xy 271.683371 -273.738206) (xy 271.653806 -273.77755) (xy 271.618313 -273.811642) (xy 271.57781 -273.839598)
			(xy 271.533348 -273.860696) (xy 271.486077 -273.874388) (xy 271.437222 -273.88032) (xy 271.388047 -273.878339)
			(xy 271.339828 -273.868495) (xy 271.293812 -273.851043) (xy 271.251191 -273.826436) (xy 271.21307 -273.795311)
			(xy 271.180435 -273.758474) (xy 271.154132 -273.716878) (xy 271.134841 -273.671602) (xy 271.123064 -273.623818)
			(xy 271.119104 -273.574764) (xy 270.780002 -273.574764) (xy 270.779507 -273.599371) (xy 270.771612 -273.647948)
			(xy 270.756028 -273.694629) (xy 270.733157 -273.738206) (xy 270.703592 -273.77755) (xy 270.668099 -273.811642)
			(xy 270.627596 -273.839598) (xy 270.583134 -273.860696) (xy 270.535863 -273.874388) (xy 270.487008 -273.88032)
			(xy 270.437833 -273.878339) (xy 270.389614 -273.868495) (xy 270.343598 -273.851043) (xy 270.300977 -273.826436)
			(xy 270.262856 -273.795311) (xy 270.230221 -273.758474) (xy 270.203918 -273.716878) (xy 270.184627 -273.671602)
			(xy 270.17285 -273.623818) (xy 270.16889 -273.574764) (xy 269.830042 -273.574764) (xy 269.829547 -273.599371)
			(xy 269.821652 -273.647948) (xy 269.806068 -273.694629) (xy 269.783197 -273.738206) (xy 269.753632 -273.77755)
			(xy 269.718139 -273.811642) (xy 269.677636 -273.839598) (xy 269.633174 -273.860696) (xy 269.585903 -273.874388)
			(xy 269.537048 -273.88032) (xy 269.487873 -273.878339) (xy 269.439654 -273.868495) (xy 269.393638 -273.851043)
			(xy 269.351017 -273.826436) (xy 269.312896 -273.795311) (xy 269.280261 -273.758474) (xy 269.253958 -273.716878)
			(xy 269.234667 -273.671602) (xy 269.22289 -273.623818) (xy 269.21893 -273.574764) (xy 265.775957 -273.574764)
			(xy 265.669206 -273.725423) (xy 265.549895 -273.879938) (xy 265.424337 -274.029421) (xy 265.292744 -274.173619)
			(xy 265.155339 -274.31229) (xy 265.012352 -274.445199) (xy 264.919417 -274.524724) (xy 269.21893 -274.524724)
			(xy 269.22289 -274.47567) (xy 269.234667 -274.427886) (xy 269.253958 -274.38261) (xy 269.280261 -274.341014)
			(xy 269.312896 -274.304177) (xy 269.351017 -274.273052) (xy 269.393638 -274.248445) (xy 269.439654 -274.230993)
			(xy 269.487873 -274.221149) (xy 269.537048 -274.219168) (xy 269.585903 -274.2251) (xy 269.633174 -274.238792)
			(xy 269.677636 -274.25989) (xy 269.718139 -274.287846) (xy 269.753632 -274.321938) (xy 269.783197 -274.361282)
			(xy 269.806068 -274.404859) (xy 269.821652 -274.45154) (xy 269.829547 -274.500117) (xy 269.830042 -274.524724)
			(xy 269.830037 -274.524978) (xy 270.169144 -274.524978) (xy 270.173104 -274.475924) (xy 270.184881 -274.42814)
			(xy 270.204172 -274.382864) (xy 270.230475 -274.341268) (xy 270.26311 -274.304431) (xy 270.301231 -274.273306)
			(xy 270.343852 -274.248699) (xy 270.389868 -274.231247) (xy 270.438087 -274.221403) (xy 270.487262 -274.219422)
			(xy 270.536117 -274.225354) (xy 270.583388 -274.239046) (xy 270.62785 -274.260144) (xy 270.668353 -274.2881)
			(xy 270.703846 -274.322192) (xy 270.733411 -274.361536) (xy 270.756282 -274.405113) (xy 270.771866 -274.451794)
			(xy 270.779761 -274.500371) (xy 270.780256 -274.524978) (xy 271.119104 -274.524978) (xy 271.123064 -274.475924)
			(xy 271.134841 -274.42814) (xy 271.154132 -274.382864) (xy 271.180435 -274.341268) (xy 271.21307 -274.304431)
			(xy 271.251191 -274.273306) (xy 271.293812 -274.248699) (xy 271.339828 -274.231247) (xy 271.388047 -274.221403)
			(xy 271.437222 -274.219422) (xy 271.486077 -274.225354) (xy 271.533348 -274.239046) (xy 271.57781 -274.260144)
			(xy 271.618313 -274.2881) (xy 271.653806 -274.322192) (xy 271.683371 -274.361536) (xy 271.706242 -274.405113)
			(xy 271.721826 -274.451794) (xy 271.729721 -274.500371) (xy 271.730216 -274.524978) (xy 272.069064 -274.524978)
			(xy 272.073024 -274.475924) (xy 272.084801 -274.42814) (xy 272.104092 -274.382864) (xy 272.130395 -274.341268)
			(xy 272.16303 -274.304431) (xy 272.201151 -274.273306) (xy 272.243772 -274.248699) (xy 272.289788 -274.231247)
			(xy 272.338007 -274.221403) (xy 272.387182 -274.219422) (xy 272.436037 -274.225354) (xy 272.483308 -274.239046)
			(xy 272.52777 -274.260144) (xy 272.568273 -274.2881) (xy 272.603766 -274.322192) (xy 272.633331 -274.361536)
			(xy 272.656202 -274.405113) (xy 272.671786 -274.451794) (xy 272.679681 -274.500371) (xy 272.680176 -274.524978)
			(xy 273.019024 -274.524978) (xy 273.022984 -274.475924) (xy 273.034761 -274.42814) (xy 273.054052 -274.382864)
			(xy 273.080355 -274.341268) (xy 273.11299 -274.304431) (xy 273.151111 -274.273306) (xy 273.193732 -274.248699)
			(xy 273.239748 -274.231247) (xy 273.287967 -274.221403) (xy 273.337142 -274.219422) (xy 273.385997 -274.225354)
			(xy 273.433268 -274.239046) (xy 273.47773 -274.260144) (xy 273.518233 -274.2881) (xy 273.553726 -274.322192)
			(xy 273.583291 -274.361536) (xy 273.606162 -274.405113) (xy 273.621746 -274.451794) (xy 273.629641 -274.500371)
			(xy 273.630136 -274.524978) (xy 273.968984 -274.524978) (xy 273.972944 -274.475924) (xy 273.984721 -274.42814)
			(xy 274.004012 -274.382864) (xy 274.030315 -274.341268) (xy 274.06295 -274.304431) (xy 274.101071 -274.273306)
			(xy 274.143692 -274.248699) (xy 274.189708 -274.231247) (xy 274.237927 -274.221403) (xy 274.287102 -274.219422)
			(xy 274.335957 -274.225354) (xy 274.383228 -274.239046) (xy 274.42769 -274.260144) (xy 274.468193 -274.2881)
			(xy 274.503686 -274.322192) (xy 274.533251 -274.361536) (xy 274.556122 -274.405113) (xy 274.571706 -274.451794)
			(xy 274.579601 -274.500371) (xy 274.580096 -274.524978) (xy 274.579601 -274.549585) (xy 274.571706 -274.598162)
			(xy 274.556122 -274.644843) (xy 274.533251 -274.68842) (xy 274.503686 -274.727764) (xy 274.468193 -274.761856)
			(xy 274.42769 -274.789812) (xy 274.383228 -274.81091) (xy 274.335957 -274.824602) (xy 274.287102 -274.830534)
			(xy 274.237927 -274.828553) (xy 274.189708 -274.818709) (xy 274.143692 -274.801257) (xy 274.101071 -274.77665)
			(xy 274.06295 -274.745525) (xy 274.030315 -274.708688) (xy 274.004012 -274.667092) (xy 273.984721 -274.621816)
			(xy 273.972944 -274.574032) (xy 273.968984 -274.524978) (xy 273.630136 -274.524978) (xy 273.629641 -274.549585)
			(xy 273.621746 -274.598162) (xy 273.606162 -274.644843) (xy 273.583291 -274.68842) (xy 273.553726 -274.727764)
			(xy 273.518233 -274.761856) (xy 273.47773 -274.789812) (xy 273.433268 -274.81091) (xy 273.385997 -274.824602)
			(xy 273.337142 -274.830534) (xy 273.287967 -274.828553) (xy 273.239748 -274.818709) (xy 273.193732 -274.801257)
			(xy 273.151111 -274.77665) (xy 273.11299 -274.745525) (xy 273.080355 -274.708688) (xy 273.054052 -274.667092)
			(xy 273.034761 -274.621816) (xy 273.022984 -274.574032) (xy 273.019024 -274.524978) (xy 272.680176 -274.524978)
			(xy 272.679681 -274.549585) (xy 272.671786 -274.598162) (xy 272.656202 -274.644843) (xy 272.633331 -274.68842)
			(xy 272.603766 -274.727764) (xy 272.568273 -274.761856) (xy 272.52777 -274.789812) (xy 272.483308 -274.81091)
			(xy 272.436037 -274.824602) (xy 272.387182 -274.830534) (xy 272.338007 -274.828553) (xy 272.289788 -274.818709)
			(xy 272.243772 -274.801257) (xy 272.201151 -274.77665) (xy 272.16303 -274.745525) (xy 272.130395 -274.708688)
			(xy 272.104092 -274.667092) (xy 272.084801 -274.621816) (xy 272.073024 -274.574032) (xy 272.069064 -274.524978)
			(xy 271.730216 -274.524978) (xy 271.729721 -274.549585) (xy 271.721826 -274.598162) (xy 271.706242 -274.644843)
			(xy 271.683371 -274.68842) (xy 271.653806 -274.727764) (xy 271.618313 -274.761856) (xy 271.57781 -274.789812)
			(xy 271.533348 -274.81091) (xy 271.486077 -274.824602) (xy 271.437222 -274.830534) (xy 271.388047 -274.828553)
			(xy 271.339828 -274.818709) (xy 271.293812 -274.801257) (xy 271.251191 -274.77665) (xy 271.21307 -274.745525)
			(xy 271.180435 -274.708688) (xy 271.154132 -274.667092) (xy 271.134841 -274.621816) (xy 271.123064 -274.574032)
			(xy 271.119104 -274.524978) (xy 270.780256 -274.524978) (xy 270.779761 -274.549585) (xy 270.771866 -274.598162)
			(xy 270.756282 -274.644843) (xy 270.733411 -274.68842) (xy 270.703846 -274.727764) (xy 270.668353 -274.761856)
			(xy 270.62785 -274.789812) (xy 270.583388 -274.81091) (xy 270.536117 -274.824602) (xy 270.487262 -274.830534)
			(xy 270.438087 -274.828553) (xy 270.389868 -274.818709) (xy 270.343852 -274.801257) (xy 270.301231 -274.77665)
			(xy 270.26311 -274.745525) (xy 270.230475 -274.708688) (xy 270.204172 -274.667092) (xy 270.184881 -274.621816)
			(xy 270.173104 -274.574032) (xy 270.169144 -274.524978) (xy 269.830037 -274.524978) (xy 269.829547 -274.549331)
			(xy 269.821652 -274.597908) (xy 269.806068 -274.644589) (xy 269.783197 -274.688166) (xy 269.753632 -274.72751)
			(xy 269.718139 -274.761602) (xy 269.677636 -274.789558) (xy 269.633174 -274.810656) (xy 269.585903 -274.824348)
			(xy 269.537048 -274.83028) (xy 269.487873 -274.828299) (xy 269.439654 -274.818455) (xy 269.393638 -274.801003)
			(xy 269.351017 -274.776396) (xy 269.312896 -274.745271) (xy 269.280261 -274.708434) (xy 269.253958 -274.666838)
			(xy 269.234667 -274.621562) (xy 269.22289 -274.573778) (xy 269.21893 -274.524724) (xy 264.919417 -274.524724)
			(xy 264.864027 -274.572122) (xy 264.710612 -274.692844) (xy 264.552368 -274.807162) (xy 264.389561 -274.914883)
			(xy 264.222466 -275.015825) (xy 264.051366 -275.109817) (xy 263.876549 -275.1967) (xy 263.69831 -275.276329)
			(xy 263.607804 -275.312886) (xy 263.600184 -275.316696) (xy 263.592934 -275.321518) (xy 263.581961 -275.335023)
			(xy 263.57616 -275.351429) (xy 263.5758 -275.36013) (xy 263.5758 -275.474938) (xy 268.26897 -275.474938)
			(xy 268.27293 -275.425884) (xy 268.284707 -275.3781) (xy 268.303998 -275.332824) (xy 268.330301 -275.291228)
			(xy 268.362936 -275.254391) (xy 268.401057 -275.223266) (xy 268.443678 -275.198659) (xy 268.489694 -275.181207)
			(xy 268.537913 -275.171363) (xy 268.587088 -275.169382) (xy 268.635943 -275.175314) (xy 268.683214 -275.189006)
			(xy 268.727676 -275.210104) (xy 268.768179 -275.23806) (xy 268.803672 -275.272152) (xy 268.833237 -275.311496)
			(xy 268.856108 -275.355073) (xy 268.871692 -275.401754) (xy 268.879587 -275.450331) (xy 268.880082 -275.474938)
			(xy 269.21893 -275.474938) (xy 269.22289 -275.425884) (xy 269.234667 -275.3781) (xy 269.253958 -275.332824)
			(xy 269.280261 -275.291228) (xy 269.312896 -275.254391) (xy 269.351017 -275.223266) (xy 269.393638 -275.198659)
			(xy 269.439654 -275.181207) (xy 269.487873 -275.171363) (xy 269.537048 -275.169382) (xy 269.585903 -275.175314)
			(xy 269.633174 -275.189006) (xy 269.677636 -275.210104) (xy 269.718139 -275.23806) (xy 269.753632 -275.272152)
			(xy 269.783197 -275.311496) (xy 269.806068 -275.355073) (xy 269.821652 -275.401754) (xy 269.829547 -275.450331)
			(xy 269.830042 -275.474938) (xy 270.169144 -275.474938) (xy 270.173104 -275.425884) (xy 270.184881 -275.3781)
			(xy 270.204172 -275.332824) (xy 270.230475 -275.291228) (xy 270.26311 -275.254391) (xy 270.301231 -275.223266)
			(xy 270.343852 -275.198659) (xy 270.389868 -275.181207) (xy 270.438087 -275.171363) (xy 270.487262 -275.169382)
			(xy 270.536117 -275.175314) (xy 270.583388 -275.189006) (xy 270.62785 -275.210104) (xy 270.668353 -275.23806)
			(xy 270.703846 -275.272152) (xy 270.733411 -275.311496) (xy 270.756282 -275.355073) (xy 270.771866 -275.401754)
			(xy 270.779761 -275.450331) (xy 270.780256 -275.474938) (xy 271.119104 -275.474938) (xy 271.123064 -275.425884)
			(xy 271.134841 -275.3781) (xy 271.154132 -275.332824) (xy 271.180435 -275.291228) (xy 271.21307 -275.254391)
			(xy 271.251191 -275.223266) (xy 271.293812 -275.198659) (xy 271.339828 -275.181207) (xy 271.388047 -275.171363)
			(xy 271.437222 -275.169382) (xy 271.486077 -275.175314) (xy 271.533348 -275.189006) (xy 271.57781 -275.210104)
			(xy 271.618313 -275.23806) (xy 271.653806 -275.272152) (xy 271.683371 -275.311496) (xy 271.706242 -275.355073)
			(xy 271.721826 -275.401754) (xy 271.729721 -275.450331) (xy 271.730216 -275.474938) (xy 272.069064 -275.474938)
			(xy 272.073024 -275.425884) (xy 272.084801 -275.3781) (xy 272.104092 -275.332824) (xy 272.130395 -275.291228)
			(xy 272.16303 -275.254391) (xy 272.201151 -275.223266) (xy 272.243772 -275.198659) (xy 272.289788 -275.181207)
			(xy 272.338007 -275.171363) (xy 272.387182 -275.169382) (xy 272.436037 -275.175314) (xy 272.483308 -275.189006)
			(xy 272.52777 -275.210104) (xy 272.568273 -275.23806) (xy 272.603766 -275.272152) (xy 272.633331 -275.311496)
			(xy 272.656202 -275.355073) (xy 272.671786 -275.401754) (xy 272.679681 -275.450331) (xy 272.680176 -275.474938)
			(xy 273.019024 -275.474938) (xy 273.022984 -275.425884) (xy 273.034761 -275.3781) (xy 273.054052 -275.332824)
			(xy 273.080355 -275.291228) (xy 273.11299 -275.254391) (xy 273.151111 -275.223266) (xy 273.193732 -275.198659)
			(xy 273.239748 -275.181207) (xy 273.287967 -275.171363) (xy 273.337142 -275.169382) (xy 273.385997 -275.175314)
			(xy 273.433268 -275.189006) (xy 273.47773 -275.210104) (xy 273.518233 -275.23806) (xy 273.553726 -275.272152)
			(xy 273.583291 -275.311496) (xy 273.606162 -275.355073) (xy 273.621746 -275.401754) (xy 273.629641 -275.450331)
			(xy 273.630136 -275.474938) (xy 273.968984 -275.474938) (xy 273.972944 -275.425884) (xy 273.984721 -275.3781)
			(xy 274.004012 -275.332824) (xy 274.030315 -275.291228) (xy 274.06295 -275.254391) (xy 274.101071 -275.223266)
			(xy 274.143692 -275.198659) (xy 274.189708 -275.181207) (xy 274.237927 -275.171363) (xy 274.287102 -275.169382)
			(xy 274.335957 -275.175314) (xy 274.383228 -275.189006) (xy 274.42769 -275.210104) (xy 274.468193 -275.23806)
			(xy 274.503686 -275.272152) (xy 274.533251 -275.311496) (xy 274.556122 -275.355073) (xy 274.571706 -275.401754)
			(xy 274.579601 -275.450331) (xy 274.580096 -275.474938) (xy 274.579601 -275.499545) (xy 274.571706 -275.548122)
			(xy 274.556122 -275.594803) (xy 274.533251 -275.63838) (xy 274.503686 -275.677724) (xy 274.468193 -275.711816)
			(xy 274.42769 -275.739772) (xy 274.383228 -275.76087) (xy 274.335957 -275.774562) (xy 274.287102 -275.780494)
			(xy 274.237927 -275.778513) (xy 274.189708 -275.768669) (xy 274.143692 -275.751217) (xy 274.101071 -275.72661)
			(xy 274.06295 -275.695485) (xy 274.030315 -275.658648) (xy 274.004012 -275.617052) (xy 273.984721 -275.571776)
			(xy 273.972944 -275.523992) (xy 273.968984 -275.474938) (xy 273.630136 -275.474938) (xy 273.629641 -275.499545)
			(xy 273.621746 -275.548122) (xy 273.606162 -275.594803) (xy 273.583291 -275.63838) (xy 273.553726 -275.677724)
			(xy 273.518233 -275.711816) (xy 273.47773 -275.739772) (xy 273.433268 -275.76087) (xy 273.385997 -275.774562)
			(xy 273.337142 -275.780494) (xy 273.287967 -275.778513) (xy 273.239748 -275.768669) (xy 273.193732 -275.751217)
			(xy 273.151111 -275.72661) (xy 273.11299 -275.695485) (xy 273.080355 -275.658648) (xy 273.054052 -275.617052)
			(xy 273.034761 -275.571776) (xy 273.022984 -275.523992) (xy 273.019024 -275.474938) (xy 272.680176 -275.474938)
			(xy 272.679681 -275.499545) (xy 272.671786 -275.548122) (xy 272.656202 -275.594803) (xy 272.633331 -275.63838)
			(xy 272.603766 -275.677724) (xy 272.568273 -275.711816) (xy 272.52777 -275.739772) (xy 272.483308 -275.76087)
			(xy 272.436037 -275.774562) (xy 272.387182 -275.780494) (xy 272.338007 -275.778513) (xy 272.289788 -275.768669)
			(xy 272.243772 -275.751217) (xy 272.201151 -275.72661) (xy 272.16303 -275.695485) (xy 272.130395 -275.658648)
			(xy 272.104092 -275.617052) (xy 272.084801 -275.571776) (xy 272.073024 -275.523992) (xy 272.069064 -275.474938)
			(xy 271.730216 -275.474938) (xy 271.729721 -275.499545) (xy 271.721826 -275.548122) (xy 271.706242 -275.594803)
			(xy 271.683371 -275.63838) (xy 271.653806 -275.677724) (xy 271.618313 -275.711816) (xy 271.57781 -275.739772)
			(xy 271.533348 -275.76087) (xy 271.486077 -275.774562) (xy 271.437222 -275.780494) (xy 271.388047 -275.778513)
			(xy 271.339828 -275.768669) (xy 271.293812 -275.751217) (xy 271.251191 -275.72661) (xy 271.21307 -275.695485)
			(xy 271.180435 -275.658648) (xy 271.154132 -275.617052) (xy 271.134841 -275.571776) (xy 271.123064 -275.523992)
			(xy 271.119104 -275.474938) (xy 270.780256 -275.474938) (xy 270.779761 -275.499545) (xy 270.771866 -275.548122)
			(xy 270.756282 -275.594803) (xy 270.733411 -275.63838) (xy 270.703846 -275.677724) (xy 270.668353 -275.711816)
			(xy 270.62785 -275.739772) (xy 270.583388 -275.76087) (xy 270.536117 -275.774562) (xy 270.487262 -275.780494)
			(xy 270.438087 -275.778513) (xy 270.389868 -275.768669) (xy 270.343852 -275.751217) (xy 270.301231 -275.72661)
			(xy 270.26311 -275.695485) (xy 270.230475 -275.658648) (xy 270.204172 -275.617052) (xy 270.184881 -275.571776)
			(xy 270.173104 -275.523992) (xy 270.169144 -275.474938) (xy 269.830042 -275.474938) (xy 269.829547 -275.499545)
			(xy 269.821652 -275.548122) (xy 269.806068 -275.594803) (xy 269.783197 -275.63838) (xy 269.753632 -275.677724)
			(xy 269.718139 -275.711816) (xy 269.677636 -275.739772) (xy 269.633174 -275.76087) (xy 269.585903 -275.774562)
			(xy 269.537048 -275.780494) (xy 269.487873 -275.778513) (xy 269.439654 -275.768669) (xy 269.393638 -275.751217)
			(xy 269.351017 -275.72661) (xy 269.312896 -275.695485) (xy 269.280261 -275.658648) (xy 269.253958 -275.617052)
			(xy 269.234667 -275.571776) (xy 269.22289 -275.523992) (xy 269.21893 -275.474938) (xy 268.880082 -275.474938)
			(xy 268.879587 -275.499545) (xy 268.871692 -275.548122) (xy 268.856108 -275.594803) (xy 268.833237 -275.63838)
			(xy 268.803672 -275.677724) (xy 268.768179 -275.711816) (xy 268.727676 -275.739772) (xy 268.683214 -275.76087)
			(xy 268.635943 -275.774562) (xy 268.587088 -275.780494) (xy 268.537913 -275.778513) (xy 268.489694 -275.768669)
			(xy 268.443678 -275.751217) (xy 268.401057 -275.72661) (xy 268.362936 -275.695485) (xy 268.330301 -275.658648)
			(xy 268.303998 -275.617052) (xy 268.284707 -275.571776) (xy 268.27293 -275.523992) (xy 268.26897 -275.474938)
			(xy 263.5758 -275.474938) (xy 263.5758 -276.424898) (xy 268.26897 -276.424898) (xy 268.27293 -276.375844)
			(xy 268.284707 -276.32806) (xy 268.303998 -276.282784) (xy 268.330301 -276.241188) (xy 268.362936 -276.204351)
			(xy 268.401057 -276.173226) (xy 268.443678 -276.148619) (xy 268.489694 -276.131167) (xy 268.537913 -276.121323)
			(xy 268.587088 -276.119342) (xy 268.635943 -276.125274) (xy 268.683214 -276.138966) (xy 268.727676 -276.160064)
			(xy 268.768179 -276.18802) (xy 268.803672 -276.222112) (xy 268.833237 -276.261456) (xy 268.856108 -276.305033)
			(xy 268.871692 -276.351714) (xy 268.879587 -276.400291) (xy 268.880082 -276.424898) (xy 269.21893 -276.424898)
			(xy 269.22289 -276.375844) (xy 269.234667 -276.32806) (xy 269.253958 -276.282784) (xy 269.280261 -276.241188)
			(xy 269.312896 -276.204351) (xy 269.351017 -276.173226) (xy 269.393638 -276.148619) (xy 269.439654 -276.131167)
			(xy 269.487873 -276.121323) (xy 269.537048 -276.119342) (xy 269.585903 -276.125274) (xy 269.633174 -276.138966)
			(xy 269.677636 -276.160064) (xy 269.718139 -276.18802) (xy 269.753632 -276.222112) (xy 269.783197 -276.261456)
			(xy 269.806068 -276.305033) (xy 269.821652 -276.351714) (xy 269.829547 -276.400291) (xy 269.830042 -276.424898)
			(xy 270.169144 -276.424898) (xy 270.173104 -276.375844) (xy 270.184881 -276.32806) (xy 270.204172 -276.282784)
			(xy 270.230475 -276.241188) (xy 270.26311 -276.204351) (xy 270.301231 -276.173226) (xy 270.343852 -276.148619)
			(xy 270.389868 -276.131167) (xy 270.438087 -276.121323) (xy 270.487262 -276.119342) (xy 270.536117 -276.125274)
			(xy 270.583388 -276.138966) (xy 270.62785 -276.160064) (xy 270.668353 -276.18802) (xy 270.703846 -276.222112)
			(xy 270.733411 -276.261456) (xy 270.756282 -276.305033) (xy 270.771866 -276.351714) (xy 270.779761 -276.400291)
			(xy 270.780256 -276.424898) (xy 271.119104 -276.424898) (xy 271.123064 -276.375844) (xy 271.134841 -276.32806)
			(xy 271.154132 -276.282784) (xy 271.180435 -276.241188) (xy 271.21307 -276.204351) (xy 271.251191 -276.173226)
			(xy 271.293812 -276.148619) (xy 271.339828 -276.131167) (xy 271.388047 -276.121323) (xy 271.437222 -276.119342)
			(xy 271.486077 -276.125274) (xy 271.533348 -276.138966) (xy 271.57781 -276.160064) (xy 271.618313 -276.18802)
			(xy 271.653806 -276.222112) (xy 271.683371 -276.261456) (xy 271.706242 -276.305033) (xy 271.721826 -276.351714)
			(xy 271.729721 -276.400291) (xy 271.730216 -276.424898) (xy 272.069064 -276.424898) (xy 272.073024 -276.375844)
			(xy 272.084801 -276.32806) (xy 272.104092 -276.282784) (xy 272.130395 -276.241188) (xy 272.16303 -276.204351)
			(xy 272.201151 -276.173226) (xy 272.243772 -276.148619) (xy 272.289788 -276.131167) (xy 272.338007 -276.121323)
			(xy 272.387182 -276.119342) (xy 272.436037 -276.125274) (xy 272.483308 -276.138966) (xy 272.52777 -276.160064)
			(xy 272.568273 -276.18802) (xy 272.603766 -276.222112) (xy 272.633331 -276.261456) (xy 272.656202 -276.305033)
			(xy 272.671786 -276.351714) (xy 272.679681 -276.400291) (xy 272.680176 -276.424898) (xy 273.019024 -276.424898)
			(xy 273.022984 -276.375844) (xy 273.034761 -276.32806) (xy 273.054052 -276.282784) (xy 273.080355 -276.241188)
			(xy 273.11299 -276.204351) (xy 273.151111 -276.173226) (xy 273.193732 -276.148619) (xy 273.239748 -276.131167)
			(xy 273.287967 -276.121323) (xy 273.337142 -276.119342) (xy 273.385997 -276.125274) (xy 273.433268 -276.138966)
			(xy 273.47773 -276.160064) (xy 273.518233 -276.18802) (xy 273.553726 -276.222112) (xy 273.583291 -276.261456)
			(xy 273.606162 -276.305033) (xy 273.621746 -276.351714) (xy 273.629641 -276.400291) (xy 273.630136 -276.424898)
			(xy 273.968984 -276.424898) (xy 273.972944 -276.375844) (xy 273.984721 -276.32806) (xy 274.004012 -276.282784)
			(xy 274.030315 -276.241188) (xy 274.06295 -276.204351) (xy 274.101071 -276.173226) (xy 274.143692 -276.148619)
			(xy 274.189708 -276.131167) (xy 274.237927 -276.121323) (xy 274.287102 -276.119342) (xy 274.335957 -276.125274)
			(xy 274.383228 -276.138966) (xy 274.42769 -276.160064) (xy 274.468193 -276.18802) (xy 274.503686 -276.222112)
			(xy 274.533251 -276.261456) (xy 274.556122 -276.305033) (xy 274.571706 -276.351714) (xy 274.579601 -276.400291)
			(xy 274.580096 -276.424898) (xy 274.579601 -276.449505) (xy 274.571706 -276.498082) (xy 274.556122 -276.544763)
			(xy 274.533251 -276.58834) (xy 274.503686 -276.627684) (xy 274.468193 -276.661776) (xy 274.42769 -276.689732)
			(xy 274.383228 -276.71083) (xy 274.335957 -276.724522) (xy 274.287102 -276.730454) (xy 274.237927 -276.728473)
			(xy 274.189708 -276.718629) (xy 274.143692 -276.701177) (xy 274.101071 -276.67657) (xy 274.06295 -276.645445)
			(xy 274.030315 -276.608608) (xy 274.004012 -276.567012) (xy 273.984721 -276.521736) (xy 273.972944 -276.473952)
			(xy 273.968984 -276.424898) (xy 273.630136 -276.424898) (xy 273.629641 -276.449505) (xy 273.621746 -276.498082)
			(xy 273.606162 -276.544763) (xy 273.583291 -276.58834) (xy 273.553726 -276.627684) (xy 273.518233 -276.661776)
			(xy 273.47773 -276.689732) (xy 273.433268 -276.71083) (xy 273.385997 -276.724522) (xy 273.337142 -276.730454)
			(xy 273.287967 -276.728473) (xy 273.239748 -276.718629) (xy 273.193732 -276.701177) (xy 273.151111 -276.67657)
			(xy 273.11299 -276.645445) (xy 273.080355 -276.608608) (xy 273.054052 -276.567012) (xy 273.034761 -276.521736)
			(xy 273.022984 -276.473952) (xy 273.019024 -276.424898) (xy 272.680176 -276.424898) (xy 272.679681 -276.449505)
			(xy 272.671786 -276.498082) (xy 272.656202 -276.544763) (xy 272.633331 -276.58834) (xy 272.603766 -276.627684)
			(xy 272.568273 -276.661776) (xy 272.52777 -276.689732) (xy 272.483308 -276.71083) (xy 272.436037 -276.724522)
			(xy 272.387182 -276.730454) (xy 272.338007 -276.728473) (xy 272.289788 -276.718629) (xy 272.243772 -276.701177)
			(xy 272.201151 -276.67657) (xy 272.16303 -276.645445) (xy 272.130395 -276.608608) (xy 272.104092 -276.567012)
			(xy 272.084801 -276.521736) (xy 272.073024 -276.473952) (xy 272.069064 -276.424898) (xy 271.730216 -276.424898)
			(xy 271.729721 -276.449505) (xy 271.721826 -276.498082) (xy 271.706242 -276.544763) (xy 271.683371 -276.58834)
			(xy 271.653806 -276.627684) (xy 271.618313 -276.661776) (xy 271.57781 -276.689732) (xy 271.533348 -276.71083)
			(xy 271.486077 -276.724522) (xy 271.437222 -276.730454) (xy 271.388047 -276.728473) (xy 271.339828 -276.718629)
			(xy 271.293812 -276.701177) (xy 271.251191 -276.67657) (xy 271.21307 -276.645445) (xy 271.180435 -276.608608)
			(xy 271.154132 -276.567012) (xy 271.134841 -276.521736) (xy 271.123064 -276.473952) (xy 271.119104 -276.424898)
			(xy 270.780256 -276.424898) (xy 270.779761 -276.449505) (xy 270.771866 -276.498082) (xy 270.756282 -276.544763)
			(xy 270.733411 -276.58834) (xy 270.703846 -276.627684) (xy 270.668353 -276.661776) (xy 270.62785 -276.689732)
			(xy 270.583388 -276.71083) (xy 270.536117 -276.724522) (xy 270.487262 -276.730454) (xy 270.438087 -276.728473)
			(xy 270.389868 -276.718629) (xy 270.343852 -276.701177) (xy 270.301231 -276.67657) (xy 270.26311 -276.645445)
			(xy 270.230475 -276.608608) (xy 270.204172 -276.567012) (xy 270.184881 -276.521736) (xy 270.173104 -276.473952)
			(xy 270.169144 -276.424898) (xy 269.830042 -276.424898) (xy 269.829547 -276.449505) (xy 269.821652 -276.498082)
			(xy 269.806068 -276.544763) (xy 269.783197 -276.58834) (xy 269.753632 -276.627684) (xy 269.718139 -276.661776)
			(xy 269.677636 -276.689732) (xy 269.633174 -276.71083) (xy 269.585903 -276.724522) (xy 269.537048 -276.730454)
			(xy 269.487873 -276.728473) (xy 269.439654 -276.718629) (xy 269.393638 -276.701177) (xy 269.351017 -276.67657)
			(xy 269.312896 -276.645445) (xy 269.280261 -276.608608) (xy 269.253958 -276.567012) (xy 269.234667 -276.521736)
			(xy 269.22289 -276.473952) (xy 269.21893 -276.424898) (xy 268.880082 -276.424898) (xy 268.879587 -276.449505)
			(xy 268.871692 -276.498082) (xy 268.856108 -276.544763) (xy 268.833237 -276.58834) (xy 268.803672 -276.627684)
			(xy 268.768179 -276.661776) (xy 268.727676 -276.689732) (xy 268.683214 -276.71083) (xy 268.635943 -276.724522)
			(xy 268.587088 -276.730454) (xy 268.537913 -276.728473) (xy 268.489694 -276.718629) (xy 268.443678 -276.701177)
			(xy 268.401057 -276.67657) (xy 268.362936 -276.645445) (xy 268.330301 -276.608608) (xy 268.303998 -276.567012)
			(xy 268.284707 -276.521736) (xy 268.27293 -276.473952) (xy 268.26897 -276.424898) (xy 263.5758 -276.424898)
			(xy 263.5758 -277.374858) (xy 268.26897 -277.374858) (xy 268.27293 -277.325804) (xy 268.284707 -277.27802)
			(xy 268.303998 -277.232744) (xy 268.330301 -277.191148) (xy 268.362936 -277.154311) (xy 268.401057 -277.123186)
			(xy 268.443678 -277.098579) (xy 268.489694 -277.081127) (xy 268.537913 -277.071283) (xy 268.587088 -277.069302)
			(xy 268.635943 -277.075234) (xy 268.683214 -277.088926) (xy 268.727676 -277.110024) (xy 268.768179 -277.13798)
			(xy 268.803672 -277.172072) (xy 268.833237 -277.211416) (xy 268.856108 -277.254993) (xy 268.871692 -277.301674)
			(xy 268.879587 -277.350251) (xy 268.880082 -277.374858) (xy 269.21893 -277.374858) (xy 269.22289 -277.325804)
			(xy 269.234667 -277.27802) (xy 269.253958 -277.232744) (xy 269.280261 -277.191148) (xy 269.312896 -277.154311)
			(xy 269.351017 -277.123186) (xy 269.393638 -277.098579) (xy 269.439654 -277.081127) (xy 269.487873 -277.071283)
			(xy 269.537048 -277.069302) (xy 269.585903 -277.075234) (xy 269.633174 -277.088926) (xy 269.677636 -277.110024)
			(xy 269.718139 -277.13798) (xy 269.753632 -277.172072) (xy 269.783197 -277.211416) (xy 269.806068 -277.254993)
			(xy 269.821652 -277.301674) (xy 269.829547 -277.350251) (xy 269.830042 -277.374858) (xy 270.169144 -277.374858)
			(xy 270.173104 -277.325804) (xy 270.184881 -277.27802) (xy 270.204172 -277.232744) (xy 270.230475 -277.191148)
			(xy 270.26311 -277.154311) (xy 270.301231 -277.123186) (xy 270.343852 -277.098579) (xy 270.389868 -277.081127)
			(xy 270.438087 -277.071283) (xy 270.487262 -277.069302) (xy 270.536117 -277.075234) (xy 270.583388 -277.088926)
			(xy 270.62785 -277.110024) (xy 270.668353 -277.13798) (xy 270.703846 -277.172072) (xy 270.733411 -277.211416)
			(xy 270.756282 -277.254993) (xy 270.771866 -277.301674) (xy 270.779761 -277.350251) (xy 270.780256 -277.374858)
			(xy 271.119104 -277.374858) (xy 271.123064 -277.325804) (xy 271.134841 -277.27802) (xy 271.154132 -277.232744)
			(xy 271.180435 -277.191148) (xy 271.21307 -277.154311) (xy 271.251191 -277.123186) (xy 271.293812 -277.098579)
			(xy 271.339828 -277.081127) (xy 271.388047 -277.071283) (xy 271.437222 -277.069302) (xy 271.486077 -277.075234)
			(xy 271.533348 -277.088926) (xy 271.57781 -277.110024) (xy 271.618313 -277.13798) (xy 271.653806 -277.172072)
			(xy 271.683371 -277.211416) (xy 271.706242 -277.254993) (xy 271.721826 -277.301674) (xy 271.729721 -277.350251)
			(xy 271.730216 -277.374858) (xy 272.069064 -277.374858) (xy 272.073024 -277.325804) (xy 272.084801 -277.27802)
			(xy 272.104092 -277.232744) (xy 272.130395 -277.191148) (xy 272.16303 -277.154311) (xy 272.201151 -277.123186)
			(xy 272.243772 -277.098579) (xy 272.289788 -277.081127) (xy 272.338007 -277.071283) (xy 272.387182 -277.069302)
			(xy 272.436037 -277.075234) (xy 272.483308 -277.088926) (xy 272.52777 -277.110024) (xy 272.568273 -277.13798)
			(xy 272.603766 -277.172072) (xy 272.633331 -277.211416) (xy 272.656202 -277.254993) (xy 272.671786 -277.301674)
			(xy 272.679681 -277.350251) (xy 272.680176 -277.374858) (xy 273.019024 -277.374858) (xy 273.022984 -277.325804)
			(xy 273.034761 -277.27802) (xy 273.054052 -277.232744) (xy 273.080355 -277.191148) (xy 273.11299 -277.154311)
			(xy 273.151111 -277.123186) (xy 273.193732 -277.098579) (xy 273.239748 -277.081127) (xy 273.287967 -277.071283)
			(xy 273.337142 -277.069302) (xy 273.385997 -277.075234) (xy 273.433268 -277.088926) (xy 273.47773 -277.110024)
			(xy 273.518233 -277.13798) (xy 273.553726 -277.172072) (xy 273.583291 -277.211416) (xy 273.606162 -277.254993)
			(xy 273.621746 -277.301674) (xy 273.629641 -277.350251) (xy 273.630136 -277.374858) (xy 273.968984 -277.374858)
			(xy 273.972944 -277.325804) (xy 273.984721 -277.27802) (xy 274.004012 -277.232744) (xy 274.030315 -277.191148)
			(xy 274.06295 -277.154311) (xy 274.101071 -277.123186) (xy 274.143692 -277.098579) (xy 274.189708 -277.081127)
			(xy 274.237927 -277.071283) (xy 274.287102 -277.069302) (xy 274.335957 -277.075234) (xy 274.383228 -277.088926)
			(xy 274.42769 -277.110024) (xy 274.468193 -277.13798) (xy 274.503686 -277.172072) (xy 274.533251 -277.211416)
			(xy 274.556122 -277.254993) (xy 274.571706 -277.301674) (xy 274.579601 -277.350251) (xy 274.580096 -277.374858)
			(xy 274.579601 -277.399465) (xy 274.571706 -277.448042) (xy 274.556122 -277.494723) (xy 274.533251 -277.5383)
			(xy 274.503686 -277.577644) (xy 274.468193 -277.611736) (xy 274.42769 -277.639692) (xy 274.383228 -277.66079)
			(xy 274.335957 -277.674482) (xy 274.287102 -277.680414) (xy 274.237927 -277.678433) (xy 274.189708 -277.668589)
			(xy 274.143692 -277.651137) (xy 274.101071 -277.62653) (xy 274.06295 -277.595405) (xy 274.030315 -277.558568)
			(xy 274.004012 -277.516972) (xy 273.984721 -277.471696) (xy 273.972944 -277.423912) (xy 273.968984 -277.374858)
			(xy 273.630136 -277.374858) (xy 273.629641 -277.399465) (xy 273.621746 -277.448042) (xy 273.606162 -277.494723)
			(xy 273.583291 -277.5383) (xy 273.553726 -277.577644) (xy 273.518233 -277.611736) (xy 273.47773 -277.639692)
			(xy 273.433268 -277.66079) (xy 273.385997 -277.674482) (xy 273.337142 -277.680414) (xy 273.287967 -277.678433)
			(xy 273.239748 -277.668589) (xy 273.193732 -277.651137) (xy 273.151111 -277.62653) (xy 273.11299 -277.595405)
			(xy 273.080355 -277.558568) (xy 273.054052 -277.516972) (xy 273.034761 -277.471696) (xy 273.022984 -277.423912)
			(xy 273.019024 -277.374858) (xy 272.680176 -277.374858) (xy 272.679681 -277.399465) (xy 272.671786 -277.448042)
			(xy 272.656202 -277.494723) (xy 272.633331 -277.5383) (xy 272.603766 -277.577644) (xy 272.568273 -277.611736)
			(xy 272.52777 -277.639692) (xy 272.483308 -277.66079) (xy 272.436037 -277.674482) (xy 272.387182 -277.680414)
			(xy 272.338007 -277.678433) (xy 272.289788 -277.668589) (xy 272.243772 -277.651137) (xy 272.201151 -277.62653)
			(xy 272.16303 -277.595405) (xy 272.130395 -277.558568) (xy 272.104092 -277.516972) (xy 272.084801 -277.471696)
			(xy 272.073024 -277.423912) (xy 272.069064 -277.374858) (xy 271.730216 -277.374858) (xy 271.729721 -277.399465)
			(xy 271.721826 -277.448042) (xy 271.706242 -277.494723) (xy 271.683371 -277.5383) (xy 271.653806 -277.577644)
			(xy 271.618313 -277.611736) (xy 271.57781 -277.639692) (xy 271.533348 -277.66079) (xy 271.486077 -277.674482)
			(xy 271.437222 -277.680414) (xy 271.388047 -277.678433) (xy 271.339828 -277.668589) (xy 271.293812 -277.651137)
			(xy 271.251191 -277.62653) (xy 271.21307 -277.595405) (xy 271.180435 -277.558568) (xy 271.154132 -277.516972)
			(xy 271.134841 -277.471696) (xy 271.123064 -277.423912) (xy 271.119104 -277.374858) (xy 270.780256 -277.374858)
			(xy 270.779761 -277.399465) (xy 270.771866 -277.448042) (xy 270.756282 -277.494723) (xy 270.733411 -277.5383)
			(xy 270.703846 -277.577644) (xy 270.668353 -277.611736) (xy 270.62785 -277.639692) (xy 270.583388 -277.66079)
			(xy 270.536117 -277.674482) (xy 270.487262 -277.680414) (xy 270.438087 -277.678433) (xy 270.389868 -277.668589)
			(xy 270.343852 -277.651137) (xy 270.301231 -277.62653) (xy 270.26311 -277.595405) (xy 270.230475 -277.558568)
			(xy 270.204172 -277.516972) (xy 270.184881 -277.471696) (xy 270.173104 -277.423912) (xy 270.169144 -277.374858)
			(xy 269.830042 -277.374858) (xy 269.829547 -277.399465) (xy 269.821652 -277.448042) (xy 269.806068 -277.494723)
			(xy 269.783197 -277.5383) (xy 269.753632 -277.577644) (xy 269.718139 -277.611736) (xy 269.677636 -277.639692)
			(xy 269.633174 -277.66079) (xy 269.585903 -277.674482) (xy 269.537048 -277.680414) (xy 269.487873 -277.678433)
			(xy 269.439654 -277.668589) (xy 269.393638 -277.651137) (xy 269.351017 -277.62653) (xy 269.312896 -277.595405)
			(xy 269.280261 -277.558568) (xy 269.253958 -277.516972) (xy 269.234667 -277.471696) (xy 269.22289 -277.423912)
			(xy 269.21893 -277.374858) (xy 268.880082 -277.374858) (xy 268.879587 -277.399465) (xy 268.871692 -277.448042)
			(xy 268.856108 -277.494723) (xy 268.833237 -277.5383) (xy 268.803672 -277.577644) (xy 268.768179 -277.611736)
			(xy 268.727676 -277.639692) (xy 268.683214 -277.66079) (xy 268.635943 -277.674482) (xy 268.587088 -277.680414)
			(xy 268.537913 -277.678433) (xy 268.489694 -277.668589) (xy 268.443678 -277.651137) (xy 268.401057 -277.62653)
			(xy 268.362936 -277.595405) (xy 268.330301 -277.558568) (xy 268.303998 -277.516972) (xy 268.284707 -277.471696)
			(xy 268.27293 -277.423912) (xy 268.26897 -277.374858) (xy 263.5758 -277.374858) (xy 263.5758 -278.324818)
			(xy 268.26897 -278.324818) (xy 268.27293 -278.275764) (xy 268.284707 -278.22798) (xy 268.303998 -278.182704)
			(xy 268.330301 -278.141108) (xy 268.362936 -278.104271) (xy 268.401057 -278.073146) (xy 268.443678 -278.048539)
			(xy 268.489694 -278.031087) (xy 268.537913 -278.021243) (xy 268.587088 -278.019262) (xy 268.635943 -278.025194)
			(xy 268.683214 -278.038886) (xy 268.727676 -278.059984) (xy 268.768179 -278.08794) (xy 268.803672 -278.122032)
			(xy 268.833237 -278.161376) (xy 268.856108 -278.204953) (xy 268.871692 -278.251634) (xy 268.879587 -278.300211)
			(xy 268.880082 -278.324818) (xy 269.21893 -278.324818) (xy 269.22289 -278.275764) (xy 269.234667 -278.22798)
			(xy 269.253958 -278.182704) (xy 269.280261 -278.141108) (xy 269.312896 -278.104271) (xy 269.351017 -278.073146)
			(xy 269.393638 -278.048539) (xy 269.439654 -278.031087) (xy 269.487873 -278.021243) (xy 269.537048 -278.019262)
			(xy 269.585903 -278.025194) (xy 269.633174 -278.038886) (xy 269.677636 -278.059984) (xy 269.718139 -278.08794)
			(xy 269.753632 -278.122032) (xy 269.783197 -278.161376) (xy 269.806068 -278.204953) (xy 269.821652 -278.251634)
			(xy 269.829547 -278.300211) (xy 269.830042 -278.324818) (xy 270.169144 -278.324818) (xy 270.173104 -278.275764)
			(xy 270.184881 -278.22798) (xy 270.204172 -278.182704) (xy 270.230475 -278.141108) (xy 270.26311 -278.104271)
			(xy 270.301231 -278.073146) (xy 270.343852 -278.048539) (xy 270.389868 -278.031087) (xy 270.438087 -278.021243)
			(xy 270.487262 -278.019262) (xy 270.536117 -278.025194) (xy 270.583388 -278.038886) (xy 270.62785 -278.059984)
			(xy 270.668353 -278.08794) (xy 270.703846 -278.122032) (xy 270.733411 -278.161376) (xy 270.756282 -278.204953)
			(xy 270.771866 -278.251634) (xy 270.779761 -278.300211) (xy 270.780256 -278.324818) (xy 271.119104 -278.324818)
			(xy 271.123064 -278.275764) (xy 271.134841 -278.22798) (xy 271.154132 -278.182704) (xy 271.180435 -278.141108)
			(xy 271.21307 -278.104271) (xy 271.251191 -278.073146) (xy 271.293812 -278.048539) (xy 271.339828 -278.031087)
			(xy 271.388047 -278.021243) (xy 271.437222 -278.019262) (xy 271.486077 -278.025194) (xy 271.533348 -278.038886)
			(xy 271.57781 -278.059984) (xy 271.618313 -278.08794) (xy 271.653806 -278.122032) (xy 271.683371 -278.161376)
			(xy 271.706242 -278.204953) (xy 271.721826 -278.251634) (xy 271.729721 -278.300211) (xy 271.730216 -278.324818)
			(xy 272.069064 -278.324818) (xy 272.073024 -278.275764) (xy 272.084801 -278.22798) (xy 272.104092 -278.182704)
			(xy 272.130395 -278.141108) (xy 272.16303 -278.104271) (xy 272.201151 -278.073146) (xy 272.243772 -278.048539)
			(xy 272.289788 -278.031087) (xy 272.338007 -278.021243) (xy 272.387182 -278.019262) (xy 272.436037 -278.025194)
			(xy 272.483308 -278.038886) (xy 272.52777 -278.059984) (xy 272.568273 -278.08794) (xy 272.603766 -278.122032)
			(xy 272.633331 -278.161376) (xy 272.656202 -278.204953) (xy 272.671786 -278.251634) (xy 272.679681 -278.300211)
			(xy 272.680176 -278.324818) (xy 273.019024 -278.324818) (xy 273.022984 -278.275764) (xy 273.034761 -278.22798)
			(xy 273.054052 -278.182704) (xy 273.080355 -278.141108) (xy 273.11299 -278.104271) (xy 273.151111 -278.073146)
			(xy 273.193732 -278.048539) (xy 273.239748 -278.031087) (xy 273.287967 -278.021243) (xy 273.337142 -278.019262)
			(xy 273.385997 -278.025194) (xy 273.433268 -278.038886) (xy 273.47773 -278.059984) (xy 273.518233 -278.08794)
			(xy 273.553726 -278.122032) (xy 273.583291 -278.161376) (xy 273.606162 -278.204953) (xy 273.621746 -278.251634)
			(xy 273.629641 -278.300211) (xy 273.630136 -278.324818) (xy 273.968984 -278.324818) (xy 273.972944 -278.275764)
			(xy 273.984721 -278.22798) (xy 274.004012 -278.182704) (xy 274.030315 -278.141108) (xy 274.06295 -278.104271)
			(xy 274.101071 -278.073146) (xy 274.143692 -278.048539) (xy 274.189708 -278.031087) (xy 274.237927 -278.021243)
			(xy 274.287102 -278.019262) (xy 274.335957 -278.025194) (xy 274.383228 -278.038886) (xy 274.42769 -278.059984)
			(xy 274.468193 -278.08794) (xy 274.503686 -278.122032) (xy 274.533251 -278.161376) (xy 274.556122 -278.204953)
			(xy 274.571706 -278.251634) (xy 274.579601 -278.300211) (xy 274.580096 -278.324818) (xy 274.579601 -278.349425)
			(xy 274.571706 -278.398002) (xy 274.556122 -278.444683) (xy 274.533251 -278.48826) (xy 274.503686 -278.527604)
			(xy 274.468193 -278.561696) (xy 274.42769 -278.589652) (xy 274.383228 -278.61075) (xy 274.335957 -278.624442)
			(xy 274.287102 -278.630374) (xy 274.237927 -278.628393) (xy 274.189708 -278.618549) (xy 274.143692 -278.601097)
			(xy 274.101071 -278.57649) (xy 274.06295 -278.545365) (xy 274.030315 -278.508528) (xy 274.004012 -278.466932)
			(xy 273.984721 -278.421656) (xy 273.972944 -278.373872) (xy 273.968984 -278.324818) (xy 273.630136 -278.324818)
			(xy 273.629641 -278.349425) (xy 273.621746 -278.398002) (xy 273.606162 -278.444683) (xy 273.583291 -278.48826)
			(xy 273.553726 -278.527604) (xy 273.518233 -278.561696) (xy 273.47773 -278.589652) (xy 273.433268 -278.61075)
			(xy 273.385997 -278.624442) (xy 273.337142 -278.630374) (xy 273.287967 -278.628393) (xy 273.239748 -278.618549)
			(xy 273.193732 -278.601097) (xy 273.151111 -278.57649) (xy 273.11299 -278.545365) (xy 273.080355 -278.508528)
			(xy 273.054052 -278.466932) (xy 273.034761 -278.421656) (xy 273.022984 -278.373872) (xy 273.019024 -278.324818)
			(xy 272.680176 -278.324818) (xy 272.679681 -278.349425) (xy 272.671786 -278.398002) (xy 272.656202 -278.444683)
			(xy 272.633331 -278.48826) (xy 272.603766 -278.527604) (xy 272.568273 -278.561696) (xy 272.52777 -278.589652)
			(xy 272.483308 -278.61075) (xy 272.436037 -278.624442) (xy 272.387182 -278.630374) (xy 272.338007 -278.628393)
			(xy 272.289788 -278.618549) (xy 272.243772 -278.601097) (xy 272.201151 -278.57649) (xy 272.16303 -278.545365)
			(xy 272.130395 -278.508528) (xy 272.104092 -278.466932) (xy 272.084801 -278.421656) (xy 272.073024 -278.373872)
			(xy 272.069064 -278.324818) (xy 271.730216 -278.324818) (xy 271.729721 -278.349425) (xy 271.721826 -278.398002)
			(xy 271.706242 -278.444683) (xy 271.683371 -278.48826) (xy 271.653806 -278.527604) (xy 271.618313 -278.561696)
			(xy 271.57781 -278.589652) (xy 271.533348 -278.61075) (xy 271.486077 -278.624442) (xy 271.437222 -278.630374)
			(xy 271.388047 -278.628393) (xy 271.339828 -278.618549) (xy 271.293812 -278.601097) (xy 271.251191 -278.57649)
			(xy 271.21307 -278.545365) (xy 271.180435 -278.508528) (xy 271.154132 -278.466932) (xy 271.134841 -278.421656)
			(xy 271.123064 -278.373872) (xy 271.119104 -278.324818) (xy 270.780256 -278.324818) (xy 270.779761 -278.349425)
			(xy 270.771866 -278.398002) (xy 270.756282 -278.444683) (xy 270.733411 -278.48826) (xy 270.703846 -278.527604)
			(xy 270.668353 -278.561696) (xy 270.62785 -278.589652) (xy 270.583388 -278.61075) (xy 270.536117 -278.624442)
			(xy 270.487262 -278.630374) (xy 270.438087 -278.628393) (xy 270.389868 -278.618549) (xy 270.343852 -278.601097)
			(xy 270.301231 -278.57649) (xy 270.26311 -278.545365) (xy 270.230475 -278.508528) (xy 270.204172 -278.466932)
			(xy 270.184881 -278.421656) (xy 270.173104 -278.373872) (xy 270.169144 -278.324818) (xy 269.830042 -278.324818)
			(xy 269.829547 -278.349425) (xy 269.821652 -278.398002) (xy 269.806068 -278.444683) (xy 269.783197 -278.48826)
			(xy 269.753632 -278.527604) (xy 269.718139 -278.561696) (xy 269.677636 -278.589652) (xy 269.633174 -278.61075)
			(xy 269.585903 -278.624442) (xy 269.537048 -278.630374) (xy 269.487873 -278.628393) (xy 269.439654 -278.618549)
			(xy 269.393638 -278.601097) (xy 269.351017 -278.57649) (xy 269.312896 -278.545365) (xy 269.280261 -278.508528)
			(xy 269.253958 -278.466932) (xy 269.234667 -278.421656) (xy 269.22289 -278.373872) (xy 269.21893 -278.324818)
			(xy 268.880082 -278.324818) (xy 268.879587 -278.349425) (xy 268.871692 -278.398002) (xy 268.856108 -278.444683)
			(xy 268.833237 -278.48826) (xy 268.803672 -278.527604) (xy 268.768179 -278.561696) (xy 268.727676 -278.589652)
			(xy 268.683214 -278.61075) (xy 268.635943 -278.624442) (xy 268.587088 -278.630374) (xy 268.537913 -278.628393)
			(xy 268.489694 -278.618549) (xy 268.443678 -278.601097) (xy 268.401057 -278.57649) (xy 268.362936 -278.545365)
			(xy 268.330301 -278.508528) (xy 268.303998 -278.466932) (xy 268.284707 -278.421656) (xy 268.27293 -278.373872)
			(xy 268.26897 -278.324818) (xy 263.5758 -278.324818) (xy 263.5758 -279.274778) (xy 268.26897 -279.274778)
			(xy 268.27293 -279.225724) (xy 268.284707 -279.17794) (xy 268.303998 -279.132664) (xy 268.330301 -279.091068)
			(xy 268.362936 -279.054231) (xy 268.401057 -279.023106) (xy 268.443678 -278.998499) (xy 268.489694 -278.981047)
			(xy 268.537913 -278.971203) (xy 268.587088 -278.969222) (xy 268.635943 -278.975154) (xy 268.683214 -278.988846)
			(xy 268.727676 -279.009944) (xy 268.768179 -279.0379) (xy 268.803672 -279.071992) (xy 268.833237 -279.111336)
			(xy 268.856108 -279.154913) (xy 268.871692 -279.201594) (xy 268.879587 -279.250171) (xy 268.880082 -279.274778)
			(xy 269.21893 -279.274778) (xy 269.22289 -279.225724) (xy 269.234667 -279.17794) (xy 269.253958 -279.132664)
			(xy 269.280261 -279.091068) (xy 269.312896 -279.054231) (xy 269.351017 -279.023106) (xy 269.393638 -278.998499)
			(xy 269.439654 -278.981047) (xy 269.487873 -278.971203) (xy 269.537048 -278.969222) (xy 269.585903 -278.975154)
			(xy 269.633174 -278.988846) (xy 269.677636 -279.009944) (xy 269.718139 -279.0379) (xy 269.753632 -279.071992)
			(xy 269.783197 -279.111336) (xy 269.806068 -279.154913) (xy 269.821652 -279.201594) (xy 269.829547 -279.250171)
			(xy 269.830042 -279.274778) (xy 270.169144 -279.274778) (xy 270.173104 -279.225724) (xy 270.184881 -279.17794)
			(xy 270.204172 -279.132664) (xy 270.230475 -279.091068) (xy 270.26311 -279.054231) (xy 270.301231 -279.023106)
			(xy 270.343852 -278.998499) (xy 270.389868 -278.981047) (xy 270.438087 -278.971203) (xy 270.487262 -278.969222)
			(xy 270.536117 -278.975154) (xy 270.583388 -278.988846) (xy 270.62785 -279.009944) (xy 270.668353 -279.0379)
			(xy 270.703846 -279.071992) (xy 270.733411 -279.111336) (xy 270.756282 -279.154913) (xy 270.771866 -279.201594)
			(xy 270.779761 -279.250171) (xy 270.780256 -279.274778) (xy 271.119104 -279.274778) (xy 271.123064 -279.225724)
			(xy 271.134841 -279.17794) (xy 271.154132 -279.132664) (xy 271.180435 -279.091068) (xy 271.21307 -279.054231)
			(xy 271.251191 -279.023106) (xy 271.293812 -278.998499) (xy 271.339828 -278.981047) (xy 271.388047 -278.971203)
			(xy 271.437222 -278.969222) (xy 271.486077 -278.975154) (xy 271.533348 -278.988846) (xy 271.57781 -279.009944)
			(xy 271.618313 -279.0379) (xy 271.653806 -279.071992) (xy 271.683371 -279.111336) (xy 271.706242 -279.154913)
			(xy 271.721826 -279.201594) (xy 271.729721 -279.250171) (xy 271.730216 -279.274778) (xy 272.069064 -279.274778)
			(xy 272.073024 -279.225724) (xy 272.084801 -279.17794) (xy 272.104092 -279.132664) (xy 272.130395 -279.091068)
			(xy 272.16303 -279.054231) (xy 272.201151 -279.023106) (xy 272.243772 -278.998499) (xy 272.289788 -278.981047)
			(xy 272.338007 -278.971203) (xy 272.387182 -278.969222) (xy 272.436037 -278.975154) (xy 272.483308 -278.988846)
			(xy 272.52777 -279.009944) (xy 272.568273 -279.0379) (xy 272.603766 -279.071992) (xy 272.633331 -279.111336)
			(xy 272.656202 -279.154913) (xy 272.671786 -279.201594) (xy 272.679681 -279.250171) (xy 272.680176 -279.274778)
			(xy 273.019024 -279.274778) (xy 273.022984 -279.225724) (xy 273.034761 -279.17794) (xy 273.054052 -279.132664)
			(xy 273.080355 -279.091068) (xy 273.11299 -279.054231) (xy 273.151111 -279.023106) (xy 273.193732 -278.998499)
			(xy 273.239748 -278.981047) (xy 273.287967 -278.971203) (xy 273.337142 -278.969222) (xy 273.385997 -278.975154)
			(xy 273.433268 -278.988846) (xy 273.47773 -279.009944) (xy 273.518233 -279.0379) (xy 273.553726 -279.071992)
			(xy 273.583291 -279.111336) (xy 273.606162 -279.154913) (xy 273.621746 -279.201594) (xy 273.629641 -279.250171)
			(xy 273.630136 -279.274778) (xy 273.968984 -279.274778) (xy 273.972944 -279.225724) (xy 273.984721 -279.17794)
			(xy 274.004012 -279.132664) (xy 274.030315 -279.091068) (xy 274.06295 -279.054231) (xy 274.101071 -279.023106)
			(xy 274.143692 -278.998499) (xy 274.189708 -278.981047) (xy 274.237927 -278.971203) (xy 274.287102 -278.969222)
			(xy 274.335957 -278.975154) (xy 274.383228 -278.988846) (xy 274.42769 -279.009944) (xy 274.468193 -279.0379)
			(xy 274.503686 -279.071992) (xy 274.533251 -279.111336) (xy 274.556122 -279.154913) (xy 274.571706 -279.201594)
			(xy 274.579601 -279.250171) (xy 274.580096 -279.274778) (xy 274.579601 -279.299385) (xy 274.571706 -279.347962)
			(xy 274.556122 -279.394643) (xy 274.533251 -279.43822) (xy 274.503686 -279.477564) (xy 274.468193 -279.511656)
			(xy 274.42769 -279.539612) (xy 274.383228 -279.56071) (xy 274.335957 -279.574402) (xy 274.287102 -279.580334)
			(xy 274.237927 -279.578353) (xy 274.189708 -279.568509) (xy 274.143692 -279.551057) (xy 274.101071 -279.52645)
			(xy 274.06295 -279.495325) (xy 274.030315 -279.458488) (xy 274.004012 -279.416892) (xy 273.984721 -279.371616)
			(xy 273.972944 -279.323832) (xy 273.968984 -279.274778) (xy 273.630136 -279.274778) (xy 273.629641 -279.299385)
			(xy 273.621746 -279.347962) (xy 273.606162 -279.394643) (xy 273.583291 -279.43822) (xy 273.553726 -279.477564)
			(xy 273.518233 -279.511656) (xy 273.47773 -279.539612) (xy 273.433268 -279.56071) (xy 273.385997 -279.574402)
			(xy 273.337142 -279.580334) (xy 273.287967 -279.578353) (xy 273.239748 -279.568509) (xy 273.193732 -279.551057)
			(xy 273.151111 -279.52645) (xy 273.11299 -279.495325) (xy 273.080355 -279.458488) (xy 273.054052 -279.416892)
			(xy 273.034761 -279.371616) (xy 273.022984 -279.323832) (xy 273.019024 -279.274778) (xy 272.680176 -279.274778)
			(xy 272.679681 -279.299385) (xy 272.671786 -279.347962) (xy 272.656202 -279.394643) (xy 272.633331 -279.43822)
			(xy 272.603766 -279.477564) (xy 272.568273 -279.511656) (xy 272.52777 -279.539612) (xy 272.483308 -279.56071)
			(xy 272.436037 -279.574402) (xy 272.387182 -279.580334) (xy 272.338007 -279.578353) (xy 272.289788 -279.568509)
			(xy 272.243772 -279.551057) (xy 272.201151 -279.52645) (xy 272.16303 -279.495325) (xy 272.130395 -279.458488)
			(xy 272.104092 -279.416892) (xy 272.084801 -279.371616) (xy 272.073024 -279.323832) (xy 272.069064 -279.274778)
			(xy 271.730216 -279.274778) (xy 271.729721 -279.299385) (xy 271.721826 -279.347962) (xy 271.706242 -279.394643)
			(xy 271.683371 -279.43822) (xy 271.653806 -279.477564) (xy 271.618313 -279.511656) (xy 271.57781 -279.539612)
			(xy 271.533348 -279.56071) (xy 271.486077 -279.574402) (xy 271.437222 -279.580334) (xy 271.388047 -279.578353)
			(xy 271.339828 -279.568509) (xy 271.293812 -279.551057) (xy 271.251191 -279.52645) (xy 271.21307 -279.495325)
			(xy 271.180435 -279.458488) (xy 271.154132 -279.416892) (xy 271.134841 -279.371616) (xy 271.123064 -279.323832)
			(xy 271.119104 -279.274778) (xy 270.780256 -279.274778) (xy 270.779761 -279.299385) (xy 270.771866 -279.347962)
			(xy 270.756282 -279.394643) (xy 270.733411 -279.43822) (xy 270.703846 -279.477564) (xy 270.668353 -279.511656)
			(xy 270.62785 -279.539612) (xy 270.583388 -279.56071) (xy 270.536117 -279.574402) (xy 270.487262 -279.580334)
			(xy 270.438087 -279.578353) (xy 270.389868 -279.568509) (xy 270.343852 -279.551057) (xy 270.301231 -279.52645)
			(xy 270.26311 -279.495325) (xy 270.230475 -279.458488) (xy 270.204172 -279.416892) (xy 270.184881 -279.371616)
			(xy 270.173104 -279.323832) (xy 270.169144 -279.274778) (xy 269.830042 -279.274778) (xy 269.829547 -279.299385)
			(xy 269.821652 -279.347962) (xy 269.806068 -279.394643) (xy 269.783197 -279.43822) (xy 269.753632 -279.477564)
			(xy 269.718139 -279.511656) (xy 269.677636 -279.539612) (xy 269.633174 -279.56071) (xy 269.585903 -279.574402)
			(xy 269.537048 -279.580334) (xy 269.487873 -279.578353) (xy 269.439654 -279.568509) (xy 269.393638 -279.551057)
			(xy 269.351017 -279.52645) (xy 269.312896 -279.495325) (xy 269.280261 -279.458488) (xy 269.253958 -279.416892)
			(xy 269.234667 -279.371616) (xy 269.22289 -279.323832) (xy 269.21893 -279.274778) (xy 268.880082 -279.274778)
			(xy 268.879587 -279.299385) (xy 268.871692 -279.347962) (xy 268.856108 -279.394643) (xy 268.833237 -279.43822)
			(xy 268.803672 -279.477564) (xy 268.768179 -279.511656) (xy 268.727676 -279.539612) (xy 268.683214 -279.56071)
			(xy 268.635943 -279.574402) (xy 268.587088 -279.580334) (xy 268.537913 -279.578353) (xy 268.489694 -279.568509)
			(xy 268.443678 -279.551057) (xy 268.401057 -279.52645) (xy 268.362936 -279.495325) (xy 268.330301 -279.458488)
			(xy 268.303998 -279.416892) (xy 268.284707 -279.371616) (xy 268.27293 -279.323832) (xy 268.26897 -279.274778)
			(xy 263.5758 -279.274778) (xy 263.5758 -279.519888) (xy 263.576142 -279.528876) (xy 263.582347 -279.545745)
			(xy 263.594026 -279.559408) (xy 263.601708 -279.564084) (xy 263.679178 -279.607518) (xy 263.689338 -279.611836)
			(xy 263.693188 -279.612881) (xy 263.701098 -279.613909) (xy 263.705086 -279.613868) (xy 263.719056 -279.613614)
			(xy 263.73074 -279.606248) (xy 263.753374 -279.592817) (xy 263.801553 -279.571635) (xy 263.852191 -279.557291)
			(xy 263.904323 -279.55006) (xy 263.930638 -279.549606) (xy 263.930892 -279.549606) (xy 263.958145 -279.550069)
			(xy 264.012096 -279.557825) (xy 264.064394 -279.57318) (xy 264.113974 -279.595823) (xy 264.159827 -279.625291)
			(xy 264.20102 -279.660985) (xy 264.236713 -279.702178) (xy 264.26618 -279.748031) (xy 264.288822 -279.797612)
			(xy 264.304176 -279.84991) (xy 264.311932 -279.903861) (xy 264.3124 -279.931114) (xy 264.311836 -279.960493)
			(xy 264.302786 -280.018552) (xy 264.284947 -280.074539) (xy 264.258741 -280.127131) (xy 264.224787 -280.175088)
			(xy 264.183887 -280.217276) (xy 264.174369 -280.224738) (xy 268.26897 -280.224738) (xy 268.27293 -280.175684)
			(xy 268.284707 -280.1279) (xy 268.303998 -280.082624) (xy 268.330301 -280.041028) (xy 268.362936 -280.004191)
			(xy 268.401057 -279.973066) (xy 268.443678 -279.948459) (xy 268.489694 -279.931007) (xy 268.537913 -279.921163)
			(xy 268.587088 -279.919182) (xy 268.635943 -279.925114) (xy 268.683214 -279.938806) (xy 268.727676 -279.959904)
			(xy 268.768179 -279.98786) (xy 268.803672 -280.021952) (xy 268.833237 -280.061296) (xy 268.856108 -280.104873)
			(xy 268.871692 -280.151554) (xy 268.879587 -280.200131) (xy 268.880082 -280.224738) (xy 269.21893 -280.224738)
			(xy 269.22289 -280.175684) (xy 269.234667 -280.1279) (xy 269.253958 -280.082624) (xy 269.280261 -280.041028)
			(xy 269.312896 -280.004191) (xy 269.351017 -279.973066) (xy 269.393638 -279.948459) (xy 269.439654 -279.931007)
			(xy 269.487873 -279.921163) (xy 269.537048 -279.919182) (xy 269.585903 -279.925114) (xy 269.633174 -279.938806)
			(xy 269.677636 -279.959904) (xy 269.718139 -279.98786) (xy 269.753632 -280.021952) (xy 269.783197 -280.061296)
			(xy 269.806068 -280.104873) (xy 269.821652 -280.151554) (xy 269.829547 -280.200131) (xy 269.830042 -280.224738)
			(xy 270.169144 -280.224738) (xy 270.173104 -280.175684) (xy 270.184881 -280.1279) (xy 270.204172 -280.082624)
			(xy 270.230475 -280.041028) (xy 270.26311 -280.004191) (xy 270.301231 -279.973066) (xy 270.343852 -279.948459)
			(xy 270.389868 -279.931007) (xy 270.438087 -279.921163) (xy 270.487262 -279.919182) (xy 270.536117 -279.925114)
			(xy 270.583388 -279.938806) (xy 270.62785 -279.959904) (xy 270.668353 -279.98786) (xy 270.703846 -280.021952)
			(xy 270.733411 -280.061296) (xy 270.756282 -280.104873) (xy 270.771866 -280.151554) (xy 270.779761 -280.200131)
			(xy 270.780256 -280.224738) (xy 271.119104 -280.224738) (xy 271.123064 -280.175684) (xy 271.134841 -280.1279)
			(xy 271.154132 -280.082624) (xy 271.180435 -280.041028) (xy 271.21307 -280.004191) (xy 271.251191 -279.973066)
			(xy 271.293812 -279.948459) (xy 271.339828 -279.931007) (xy 271.388047 -279.921163) (xy 271.437222 -279.919182)
			(xy 271.486077 -279.925114) (xy 271.533348 -279.938806) (xy 271.57781 -279.959904) (xy 271.618313 -279.98786)
			(xy 271.653806 -280.021952) (xy 271.683371 -280.061296) (xy 271.706242 -280.104873) (xy 271.721826 -280.151554)
			(xy 271.729721 -280.200131) (xy 271.730216 -280.224738) (xy 272.069064 -280.224738) (xy 272.073024 -280.175684)
			(xy 272.084801 -280.1279) (xy 272.104092 -280.082624) (xy 272.130395 -280.041028) (xy 272.16303 -280.004191)
			(xy 272.201151 -279.973066) (xy 272.243772 -279.948459) (xy 272.289788 -279.931007) (xy 272.338007 -279.921163)
			(xy 272.387182 -279.919182) (xy 272.436037 -279.925114) (xy 272.483308 -279.938806) (xy 272.52777 -279.959904)
			(xy 272.568273 -279.98786) (xy 272.603766 -280.021952) (xy 272.633331 -280.061296) (xy 272.656202 -280.104873)
			(xy 272.671786 -280.151554) (xy 272.679681 -280.200131) (xy 272.680176 -280.224738) (xy 273.019024 -280.224738)
			(xy 273.022984 -280.175684) (xy 273.034761 -280.1279) (xy 273.054052 -280.082624) (xy 273.080355 -280.041028)
			(xy 273.11299 -280.004191) (xy 273.151111 -279.973066) (xy 273.193732 -279.948459) (xy 273.239748 -279.931007)
			(xy 273.287967 -279.921163) (xy 273.337142 -279.919182) (xy 273.385997 -279.925114) (xy 273.433268 -279.938806)
			(xy 273.47773 -279.959904) (xy 273.518233 -279.98786) (xy 273.553726 -280.021952) (xy 273.583291 -280.061296)
			(xy 273.606162 -280.104873) (xy 273.621746 -280.151554) (xy 273.629641 -280.200131) (xy 273.630136 -280.224738)
			(xy 273.968984 -280.224738) (xy 273.972944 -280.175684) (xy 273.984721 -280.1279) (xy 274.004012 -280.082624)
			(xy 274.030315 -280.041028) (xy 274.06295 -280.004191) (xy 274.101071 -279.973066) (xy 274.143692 -279.948459)
			(xy 274.189708 -279.931007) (xy 274.237927 -279.921163) (xy 274.287102 -279.919182) (xy 274.335957 -279.925114)
			(xy 274.383228 -279.938806) (xy 274.42769 -279.959904) (xy 274.468193 -279.98786) (xy 274.503686 -280.021952)
			(xy 274.533251 -280.061296) (xy 274.556122 -280.104873) (xy 274.571706 -280.151554) (xy 274.579601 -280.200131)
			(xy 274.580096 -280.224738) (xy 274.579601 -280.249345) (xy 274.571706 -280.297922) (xy 274.556122 -280.344603)
			(xy 274.533251 -280.38818) (xy 274.503686 -280.427524) (xy 274.468193 -280.461616) (xy 274.42769 -280.489572)
			(xy 274.383228 -280.51067) (xy 274.335957 -280.524362) (xy 274.287102 -280.530294) (xy 274.237927 -280.528313)
			(xy 274.189708 -280.518469) (xy 274.143692 -280.501017) (xy 274.101071 -280.47641) (xy 274.06295 -280.445285)
			(xy 274.030315 -280.408448) (xy 274.004012 -280.366852) (xy 273.984721 -280.321576) (xy 273.972944 -280.273792)
			(xy 273.968984 -280.224738) (xy 273.630136 -280.224738) (xy 273.629641 -280.249345) (xy 273.621746 -280.297922)
			(xy 273.606162 -280.344603) (xy 273.583291 -280.38818) (xy 273.553726 -280.427524) (xy 273.518233 -280.461616)
			(xy 273.47773 -280.489572) (xy 273.433268 -280.51067) (xy 273.385997 -280.524362) (xy 273.337142 -280.530294)
			(xy 273.287967 -280.528313) (xy 273.239748 -280.518469) (xy 273.193732 -280.501017) (xy 273.151111 -280.47641)
			(xy 273.11299 -280.445285) (xy 273.080355 -280.408448) (xy 273.054052 -280.366852) (xy 273.034761 -280.321576)
			(xy 273.022984 -280.273792) (xy 273.019024 -280.224738) (xy 272.680176 -280.224738) (xy 272.679681 -280.249345)
			(xy 272.671786 -280.297922) (xy 272.656202 -280.344603) (xy 272.633331 -280.38818) (xy 272.603766 -280.427524)
			(xy 272.568273 -280.461616) (xy 272.52777 -280.489572) (xy 272.483308 -280.51067) (xy 272.436037 -280.524362)
			(xy 272.387182 -280.530294) (xy 272.338007 -280.528313) (xy 272.289788 -280.518469) (xy 272.243772 -280.501017)
			(xy 272.201151 -280.47641) (xy 272.16303 -280.445285) (xy 272.130395 -280.408448) (xy 272.104092 -280.366852)
			(xy 272.084801 -280.321576) (xy 272.073024 -280.273792) (xy 272.069064 -280.224738) (xy 271.730216 -280.224738)
			(xy 271.729721 -280.249345) (xy 271.721826 -280.297922) (xy 271.706242 -280.344603) (xy 271.683371 -280.38818)
			(xy 271.653806 -280.427524) (xy 271.618313 -280.461616) (xy 271.57781 -280.489572) (xy 271.533348 -280.51067)
			(xy 271.486077 -280.524362) (xy 271.437222 -280.530294) (xy 271.388047 -280.528313) (xy 271.339828 -280.518469)
			(xy 271.293812 -280.501017) (xy 271.251191 -280.47641) (xy 271.21307 -280.445285) (xy 271.180435 -280.408448)
			(xy 271.154132 -280.366852) (xy 271.134841 -280.321576) (xy 271.123064 -280.273792) (xy 271.119104 -280.224738)
			(xy 270.780256 -280.224738) (xy 270.779761 -280.249345) (xy 270.771866 -280.297922) (xy 270.756282 -280.344603)
			(xy 270.733411 -280.38818) (xy 270.703846 -280.427524) (xy 270.668353 -280.461616) (xy 270.62785 -280.489572)
			(xy 270.583388 -280.51067) (xy 270.536117 -280.524362) (xy 270.487262 -280.530294) (xy 270.438087 -280.528313)
			(xy 270.389868 -280.518469) (xy 270.343852 -280.501017) (xy 270.301231 -280.47641) (xy 270.26311 -280.445285)
			(xy 270.230475 -280.408448) (xy 270.204172 -280.366852) (xy 270.184881 -280.321576) (xy 270.173104 -280.273792)
			(xy 270.169144 -280.224738) (xy 269.830042 -280.224738) (xy 269.829547 -280.249345) (xy 269.821652 -280.297922)
			(xy 269.806068 -280.344603) (xy 269.783197 -280.38818) (xy 269.753632 -280.427524) (xy 269.718139 -280.461616)
			(xy 269.677636 -280.489572) (xy 269.633174 -280.51067) (xy 269.585903 -280.524362) (xy 269.537048 -280.530294)
			(xy 269.487873 -280.528313) (xy 269.439654 -280.518469) (xy 269.393638 -280.501017) (xy 269.351017 -280.47641)
			(xy 269.312896 -280.445285) (xy 269.280261 -280.408448) (xy 269.253958 -280.366852) (xy 269.234667 -280.321576)
			(xy 269.22289 -280.273792) (xy 269.21893 -280.224738) (xy 268.880082 -280.224738) (xy 268.879587 -280.249345)
			(xy 268.871692 -280.297922) (xy 268.856108 -280.344603) (xy 268.833237 -280.38818) (xy 268.803672 -280.427524)
			(xy 268.768179 -280.461616) (xy 268.727676 -280.489572) (xy 268.683214 -280.51067) (xy 268.635943 -280.524362)
			(xy 268.587088 -280.530294) (xy 268.537913 -280.528313) (xy 268.489694 -280.518469) (xy 268.443678 -280.501017)
			(xy 268.401057 -280.47641) (xy 268.362936 -280.445285) (xy 268.330301 -280.408448) (xy 268.303998 -280.366852)
			(xy 268.284707 -280.321576) (xy 268.27293 -280.273792) (xy 268.26897 -280.224738) (xy 264.174369 -280.224738)
			(xy 264.160762 -280.235406) (xy 264.160508 -280.235406) (xy 264.156045 -280.239018) (xy 264.148732 -280.247866)
			(xy 264.14603 -280.252932) (xy 264.143236 -280.258266) (xy 264.140696 -280.269188) (xy 264.13968 -280.355548)
			(xy 264.139752 -280.361323) (xy 264.142196 -280.372606) (xy 264.144506 -280.3779) (xy 264.146792 -280.38298)
			(xy 264.153904 -280.39187) (xy 264.158476 -280.39568) (xy 264.1803 -280.413911) (xy 264.218829 -280.455733)
			(xy 264.25073 -280.502806) (xy 264.275297 -280.554089) (xy 264.291988 -280.608448) (xy 264.300433 -280.664682)
			(xy 264.30097 -280.693114) (xy 264.934444 -280.693114) (xy 264.938515 -280.637492) (xy 264.950641 -280.583055)
			(xy 264.970564 -280.530964) (xy 264.99786 -280.482329) (xy 265.031946 -280.438186) (xy 265.072095 -280.399477)
			(xy 265.117453 -280.367026) (xy 265.167053 -280.341525) (xy 265.219837 -280.323518) (xy 265.27468 -280.313388)
			(xy 265.330414 -280.311351) (xy 265.385851 -280.317451) (xy 265.439808 -280.331557) (xy 265.491137 -280.353369)
			(xy 265.538743 -280.382423) (xy 265.581611 -280.418098) (xy 265.618828 -280.459635) (xy 265.649601 -280.506148)
			(xy 265.673273 -280.556645) (xy 265.689341 -280.610052) (xy 265.697461 -280.665228) (xy 265.69797 -280.693114)
			(xy 265.820904 -280.693114) (xy 265.824975 -280.637492) (xy 265.837101 -280.583055) (xy 265.857024 -280.530964)
			(xy 265.88432 -280.482329) (xy 265.918406 -280.438186) (xy 265.958555 -280.399477) (xy 266.003913 -280.367026)
			(xy 266.053513 -280.341525) (xy 266.106297 -280.323518) (xy 266.16114 -280.313388) (xy 266.216874 -280.311351)
			(xy 266.272311 -280.317451) (xy 266.326268 -280.331557) (xy 266.377597 -280.353369) (xy 266.425203 -280.382423)
			(xy 266.468071 -280.418098) (xy 266.505288 -280.459635) (xy 266.536061 -280.506148) (xy 266.559733 -280.556645)
			(xy 266.575801 -280.610052) (xy 266.583921 -280.665228) (xy 266.58443 -280.693114) (xy 266.583921 -280.721)
			(xy 266.575801 -280.776176) (xy 266.559733 -280.829583) (xy 266.536061 -280.88008) (xy 266.505288 -280.926593)
			(xy 266.468071 -280.96813) (xy 266.425203 -281.003805) (xy 266.377597 -281.032859) (xy 266.326268 -281.054671)
			(xy 266.272311 -281.068777) (xy 266.216874 -281.074877) (xy 266.16114 -281.07284) (xy 266.106297 -281.06271)
			(xy 266.053513 -281.044703) (xy 266.003913 -281.019202) (xy 265.958555 -280.986751) (xy 265.918406 -280.948042)
			(xy 265.88432 -280.903899) (xy 265.857024 -280.855264) (xy 265.837101 -280.803173) (xy 265.824975 -280.748736)
			(xy 265.820904 -280.693114) (xy 265.69797 -280.693114) (xy 265.697461 -280.721) (xy 265.689341 -280.776176)
			(xy 265.673273 -280.829583) (xy 265.649601 -280.88008) (xy 265.618828 -280.926593) (xy 265.581611 -280.96813)
			(xy 265.538743 -281.003805) (xy 265.491137 -281.032859) (xy 265.439808 -281.054671) (xy 265.385851 -281.068777)
			(xy 265.330414 -281.074877) (xy 265.27468 -281.07284) (xy 265.219837 -281.06271) (xy 265.167053 -281.044703)
			(xy 265.117453 -281.019202) (xy 265.072095 -280.986751) (xy 265.031946 -280.948042) (xy 264.99786 -280.903899)
			(xy 264.970564 -280.855264) (xy 264.950641 -280.803173) (xy 264.938515 -280.748736) (xy 264.934444 -280.693114)
			(xy 264.30097 -280.693114) (xy 264.300506 -280.720365) (xy 264.292747 -280.774313) (xy 264.277389 -280.826607)
			(xy 264.254745 -280.876183) (xy 264.225276 -280.922031) (xy 264.189582 -280.963219) (xy 264.148389 -280.998908)
			(xy 264.102537 -281.02837) (xy 264.052958 -281.051007) (xy 264.000662 -281.066358) (xy 263.946713 -281.074109)
			(xy 263.919462 -281.074622) (xy 263.919208 -281.074622) (xy 263.894188 -281.074234) (xy 263.844578 -281.067696)
			(xy 263.796251 -281.054719) (xy 263.75004 -281.035526) (xy 263.7282 -281.023314) (xy 263.720326 -281.019155)
			(xy 263.7028 -281.016061) (xy 263.685274 -281.019155) (xy 263.6774 -281.023314) (xy 263.601454 -281.067002)
			(xy 263.595358 -281.070812) (xy 263.586482 -281.078451) (xy 263.576278 -281.099498) (xy 263.5758 -281.111198)
			(xy 263.5758 -281.174952) (xy 268.26897 -281.174952) (xy 268.27293 -281.125898) (xy 268.284707 -281.078114)
			(xy 268.303998 -281.032838) (xy 268.330301 -280.991242) (xy 268.362936 -280.954405) (xy 268.401057 -280.92328)
			(xy 268.443678 -280.898673) (xy 268.489694 -280.881221) (xy 268.537913 -280.871377) (xy 268.587088 -280.869396)
			(xy 268.635943 -280.875328) (xy 268.683214 -280.88902) (xy 268.727676 -280.910118) (xy 268.768179 -280.938074)
			(xy 268.803672 -280.972166) (xy 268.833237 -281.01151) (xy 268.856108 -281.055087) (xy 268.871692 -281.101768)
			(xy 268.879587 -281.150345) (xy 268.880082 -281.174952) (xy 269.21893 -281.174952) (xy 269.22289 -281.125898)
			(xy 269.234667 -281.078114) (xy 269.253958 -281.032838) (xy 269.280261 -280.991242) (xy 269.312896 -280.954405)
			(xy 269.351017 -280.92328) (xy 269.393638 -280.898673) (xy 269.439654 -280.881221) (xy 269.487873 -280.871377)
			(xy 269.537048 -280.869396) (xy 269.585903 -280.875328) (xy 269.633174 -280.88902) (xy 269.677636 -280.910118)
			(xy 269.718139 -280.938074) (xy 269.753632 -280.972166) (xy 269.783197 -281.01151) (xy 269.806068 -281.055087)
			(xy 269.821652 -281.101768) (xy 269.829547 -281.150345) (xy 269.830042 -281.174952) (xy 270.169144 -281.174952)
			(xy 270.173104 -281.125898) (xy 270.184881 -281.078114) (xy 270.204172 -281.032838) (xy 270.230475 -280.991242)
			(xy 270.26311 -280.954405) (xy 270.301231 -280.92328) (xy 270.343852 -280.898673) (xy 270.389868 -280.881221)
			(xy 270.438087 -280.871377) (xy 270.487262 -280.869396) (xy 270.536117 -280.875328) (xy 270.583388 -280.88902)
			(xy 270.62785 -280.910118) (xy 270.668353 -280.938074) (xy 270.703846 -280.972166) (xy 270.733411 -281.01151)
			(xy 270.756282 -281.055087) (xy 270.771866 -281.101768) (xy 270.779761 -281.150345) (xy 270.780256 -281.174952)
			(xy 271.119104 -281.174952) (xy 271.123064 -281.125898) (xy 271.134841 -281.078114) (xy 271.154132 -281.032838)
			(xy 271.180435 -280.991242) (xy 271.21307 -280.954405) (xy 271.251191 -280.92328) (xy 271.293812 -280.898673)
			(xy 271.339828 -280.881221) (xy 271.388047 -280.871377) (xy 271.437222 -280.869396) (xy 271.486077 -280.875328)
			(xy 271.533348 -280.88902) (xy 271.57781 -280.910118) (xy 271.618313 -280.938074) (xy 271.653806 -280.972166)
			(xy 271.683371 -281.01151) (xy 271.706242 -281.055087) (xy 271.721826 -281.101768) (xy 271.729721 -281.150345)
			(xy 271.730216 -281.174952) (xy 272.069064 -281.174952) (xy 272.073024 -281.125898) (xy 272.084801 -281.078114)
			(xy 272.104092 -281.032838) (xy 272.130395 -280.991242) (xy 272.16303 -280.954405) (xy 272.201151 -280.92328)
			(xy 272.243772 -280.898673) (xy 272.289788 -280.881221) (xy 272.338007 -280.871377) (xy 272.387182 -280.869396)
			(xy 272.436037 -280.875328) (xy 272.483308 -280.88902) (xy 272.52777 -280.910118) (xy 272.568273 -280.938074)
			(xy 272.603766 -280.972166) (xy 272.633331 -281.01151) (xy 272.656202 -281.055087) (xy 272.671786 -281.101768)
			(xy 272.679681 -281.150345) (xy 272.680176 -281.174952) (xy 273.019024 -281.174952) (xy 273.022984 -281.125898)
			(xy 273.034761 -281.078114) (xy 273.054052 -281.032838) (xy 273.080355 -280.991242) (xy 273.11299 -280.954405)
			(xy 273.151111 -280.92328) (xy 273.193732 -280.898673) (xy 273.239748 -280.881221) (xy 273.287967 -280.871377)
			(xy 273.337142 -280.869396) (xy 273.385997 -280.875328) (xy 273.433268 -280.88902) (xy 273.47773 -280.910118)
			(xy 273.518233 -280.938074) (xy 273.553726 -280.972166) (xy 273.583291 -281.01151) (xy 273.606162 -281.055087)
			(xy 273.621746 -281.101768) (xy 273.629641 -281.150345) (xy 273.630136 -281.174952) (xy 273.968984 -281.174952)
			(xy 273.972944 -281.125898) (xy 273.984721 -281.078114) (xy 274.004012 -281.032838) (xy 274.030315 -280.991242)
			(xy 274.06295 -280.954405) (xy 274.101071 -280.92328) (xy 274.143692 -280.898673) (xy 274.189708 -280.881221)
			(xy 274.237927 -280.871377) (xy 274.287102 -280.869396) (xy 274.335957 -280.875328) (xy 274.383228 -280.88902)
			(xy 274.42769 -280.910118) (xy 274.468193 -280.938074) (xy 274.503686 -280.972166) (xy 274.533251 -281.01151)
			(xy 274.556122 -281.055087) (xy 274.571706 -281.101768) (xy 274.579601 -281.150345) (xy 274.580096 -281.174952)
			(xy 274.579601 -281.199559) (xy 274.571706 -281.248136) (xy 274.556122 -281.294817) (xy 274.533251 -281.338394)
			(xy 274.503686 -281.377738) (xy 274.468193 -281.41183) (xy 274.42769 -281.439786) (xy 274.383228 -281.460884)
			(xy 274.335957 -281.474576) (xy 274.287102 -281.480508) (xy 274.237927 -281.478527) (xy 274.189708 -281.468683)
			(xy 274.143692 -281.451231) (xy 274.101071 -281.426624) (xy 274.06295 -281.395499) (xy 274.030315 -281.358662)
			(xy 274.004012 -281.317066) (xy 273.984721 -281.27179) (xy 273.972944 -281.224006) (xy 273.968984 -281.174952)
			(xy 273.630136 -281.174952) (xy 273.629641 -281.199559) (xy 273.621746 -281.248136) (xy 273.606162 -281.294817)
			(xy 273.583291 -281.338394) (xy 273.553726 -281.377738) (xy 273.518233 -281.41183) (xy 273.47773 -281.439786)
			(xy 273.433268 -281.460884) (xy 273.385997 -281.474576) (xy 273.337142 -281.480508) (xy 273.287967 -281.478527)
			(xy 273.239748 -281.468683) (xy 273.193732 -281.451231) (xy 273.151111 -281.426624) (xy 273.11299 -281.395499)
			(xy 273.080355 -281.358662) (xy 273.054052 -281.317066) (xy 273.034761 -281.27179) (xy 273.022984 -281.224006)
			(xy 273.019024 -281.174952) (xy 272.680176 -281.174952) (xy 272.679681 -281.199559) (xy 272.671786 -281.248136)
			(xy 272.656202 -281.294817) (xy 272.633331 -281.338394) (xy 272.603766 -281.377738) (xy 272.568273 -281.41183)
			(xy 272.52777 -281.439786) (xy 272.483308 -281.460884) (xy 272.436037 -281.474576) (xy 272.387182 -281.480508)
			(xy 272.338007 -281.478527) (xy 272.289788 -281.468683) (xy 272.243772 -281.451231) (xy 272.201151 -281.426624)
			(xy 272.16303 -281.395499) (xy 272.130395 -281.358662) (xy 272.104092 -281.317066) (xy 272.084801 -281.27179)
			(xy 272.073024 -281.224006) (xy 272.069064 -281.174952) (xy 271.730216 -281.174952) (xy 271.729721 -281.199559)
			(xy 271.721826 -281.248136) (xy 271.706242 -281.294817) (xy 271.683371 -281.338394) (xy 271.653806 -281.377738)
			(xy 271.618313 -281.41183) (xy 271.57781 -281.439786) (xy 271.533348 -281.460884) (xy 271.486077 -281.474576)
			(xy 271.437222 -281.480508) (xy 271.388047 -281.478527) (xy 271.339828 -281.468683) (xy 271.293812 -281.451231)
			(xy 271.251191 -281.426624) (xy 271.21307 -281.395499) (xy 271.180435 -281.358662) (xy 271.154132 -281.317066)
			(xy 271.134841 -281.27179) (xy 271.123064 -281.224006) (xy 271.119104 -281.174952) (xy 270.780256 -281.174952)
			(xy 270.779761 -281.199559) (xy 270.771866 -281.248136) (xy 270.756282 -281.294817) (xy 270.733411 -281.338394)
			(xy 270.703846 -281.377738) (xy 270.668353 -281.41183) (xy 270.62785 -281.439786) (xy 270.583388 -281.460884)
			(xy 270.536117 -281.474576) (xy 270.487262 -281.480508) (xy 270.438087 -281.478527) (xy 270.389868 -281.468683)
			(xy 270.343852 -281.451231) (xy 270.301231 -281.426624) (xy 270.26311 -281.395499) (xy 270.230475 -281.358662)
			(xy 270.204172 -281.317066) (xy 270.184881 -281.27179) (xy 270.173104 -281.224006) (xy 270.169144 -281.174952)
			(xy 269.830042 -281.174952) (xy 269.829547 -281.199559) (xy 269.821652 -281.248136) (xy 269.806068 -281.294817)
			(xy 269.783197 -281.338394) (xy 269.753632 -281.377738) (xy 269.718139 -281.41183) (xy 269.677636 -281.439786)
			(xy 269.633174 -281.460884) (xy 269.585903 -281.474576) (xy 269.537048 -281.480508) (xy 269.487873 -281.478527)
			(xy 269.439654 -281.468683) (xy 269.393638 -281.451231) (xy 269.351017 -281.426624) (xy 269.312896 -281.395499)
			(xy 269.280261 -281.358662) (xy 269.253958 -281.317066) (xy 269.234667 -281.27179) (xy 269.22289 -281.224006)
			(xy 269.21893 -281.174952) (xy 268.880082 -281.174952) (xy 268.879587 -281.199559) (xy 268.871692 -281.248136)
			(xy 268.856108 -281.294817) (xy 268.833237 -281.338394) (xy 268.803672 -281.377738) (xy 268.768179 -281.41183)
			(xy 268.727676 -281.439786) (xy 268.683214 -281.460884) (xy 268.635943 -281.474576) (xy 268.587088 -281.480508)
			(xy 268.537913 -281.478527) (xy 268.489694 -281.468683) (xy 268.443678 -281.451231) (xy 268.401057 -281.426624)
			(xy 268.362936 -281.395499) (xy 268.330301 -281.358662) (xy 268.303998 -281.317066) (xy 268.284707 -281.27179)
			(xy 268.27293 -281.224006) (xy 268.26897 -281.174952) (xy 263.5758 -281.174952) (xy 263.5758 -282.124912)
			(xy 268.26897 -282.124912) (xy 268.27293 -282.075858) (xy 268.284707 -282.028074) (xy 268.303998 -281.982798)
			(xy 268.330301 -281.941202) (xy 268.362936 -281.904365) (xy 268.401057 -281.87324) (xy 268.443678 -281.848633)
			(xy 268.489694 -281.831181) (xy 268.537913 -281.821337) (xy 268.587088 -281.819356) (xy 268.635943 -281.825288)
			(xy 268.683214 -281.83898) (xy 268.727676 -281.860078) (xy 268.768179 -281.888034) (xy 268.803672 -281.922126)
			(xy 268.833237 -281.96147) (xy 268.856108 -282.005047) (xy 268.871692 -282.051728) (xy 268.879587 -282.100305)
			(xy 268.880082 -282.124912) (xy 269.21893 -282.124912) (xy 269.22289 -282.075858) (xy 269.234667 -282.028074)
			(xy 269.253958 -281.982798) (xy 269.280261 -281.941202) (xy 269.312896 -281.904365) (xy 269.351017 -281.87324)
			(xy 269.393638 -281.848633) (xy 269.439654 -281.831181) (xy 269.487873 -281.821337) (xy 269.537048 -281.819356)
			(xy 269.585903 -281.825288) (xy 269.633174 -281.83898) (xy 269.677636 -281.860078) (xy 269.718139 -281.888034)
			(xy 269.753632 -281.922126) (xy 269.783197 -281.96147) (xy 269.806068 -282.005047) (xy 269.821652 -282.051728)
			(xy 269.829547 -282.100305) (xy 269.830042 -282.124912) (xy 270.169144 -282.124912) (xy 270.173104 -282.075858)
			(xy 270.184881 -282.028074) (xy 270.204172 -281.982798) (xy 270.230475 -281.941202) (xy 270.26311 -281.904365)
			(xy 270.301231 -281.87324) (xy 270.343852 -281.848633) (xy 270.389868 -281.831181) (xy 270.438087 -281.821337)
			(xy 270.487262 -281.819356) (xy 270.536117 -281.825288) (xy 270.583388 -281.83898) (xy 270.62785 -281.860078)
			(xy 270.668353 -281.888034) (xy 270.703846 -281.922126) (xy 270.733411 -281.96147) (xy 270.756282 -282.005047)
			(xy 270.771866 -282.051728) (xy 270.779761 -282.100305) (xy 270.780256 -282.124912) (xy 271.119104 -282.124912)
			(xy 271.123064 -282.075858) (xy 271.134841 -282.028074) (xy 271.154132 -281.982798) (xy 271.180435 -281.941202)
			(xy 271.21307 -281.904365) (xy 271.251191 -281.87324) (xy 271.293812 -281.848633) (xy 271.339828 -281.831181)
			(xy 271.388047 -281.821337) (xy 271.437222 -281.819356) (xy 271.486077 -281.825288) (xy 271.533348 -281.83898)
			(xy 271.57781 -281.860078) (xy 271.618313 -281.888034) (xy 271.653806 -281.922126) (xy 271.683371 -281.96147)
			(xy 271.706242 -282.005047) (xy 271.721826 -282.051728) (xy 271.729721 -282.100305) (xy 271.730216 -282.124912)
			(xy 272.069064 -282.124912) (xy 272.073024 -282.075858) (xy 272.084801 -282.028074) (xy 272.104092 -281.982798)
			(xy 272.130395 -281.941202) (xy 272.16303 -281.904365) (xy 272.201151 -281.87324) (xy 272.243772 -281.848633)
			(xy 272.289788 -281.831181) (xy 272.338007 -281.821337) (xy 272.387182 -281.819356) (xy 272.436037 -281.825288)
			(xy 272.483308 -281.83898) (xy 272.52777 -281.860078) (xy 272.568273 -281.888034) (xy 272.603766 -281.922126)
			(xy 272.633331 -281.96147) (xy 272.656202 -282.005047) (xy 272.671786 -282.051728) (xy 272.679681 -282.100305)
			(xy 272.680176 -282.124912) (xy 273.019024 -282.124912) (xy 273.022984 -282.075858) (xy 273.034761 -282.028074)
			(xy 273.054052 -281.982798) (xy 273.080355 -281.941202) (xy 273.11299 -281.904365) (xy 273.151111 -281.87324)
			(xy 273.193732 -281.848633) (xy 273.239748 -281.831181) (xy 273.287967 -281.821337) (xy 273.337142 -281.819356)
			(xy 273.385997 -281.825288) (xy 273.433268 -281.83898) (xy 273.47773 -281.860078) (xy 273.518233 -281.888034)
			(xy 273.553726 -281.922126) (xy 273.583291 -281.96147) (xy 273.606162 -282.005047) (xy 273.621746 -282.051728)
			(xy 273.629641 -282.100305) (xy 273.630136 -282.124912) (xy 273.968984 -282.124912) (xy 273.972944 -282.075858)
			(xy 273.984721 -282.028074) (xy 274.004012 -281.982798) (xy 274.030315 -281.941202) (xy 274.06295 -281.904365)
			(xy 274.101071 -281.87324) (xy 274.143692 -281.848633) (xy 274.189708 -281.831181) (xy 274.237927 -281.821337)
			(xy 274.287102 -281.819356) (xy 274.335957 -281.825288) (xy 274.383228 -281.83898) (xy 274.42769 -281.860078)
			(xy 274.468193 -281.888034) (xy 274.503686 -281.922126) (xy 274.533251 -281.96147) (xy 274.556122 -282.005047)
			(xy 274.571706 -282.051728) (xy 274.579601 -282.100305) (xy 274.580096 -282.124912) (xy 274.579601 -282.149519)
			(xy 274.571706 -282.198096) (xy 274.556122 -282.244777) (xy 274.533251 -282.288354) (xy 274.503686 -282.327698)
			(xy 274.468193 -282.36179) (xy 274.42769 -282.389746) (xy 274.383228 -282.410844) (xy 274.335957 -282.424536)
			(xy 274.287102 -282.430468) (xy 274.237927 -282.428487) (xy 274.189708 -282.418643) (xy 274.143692 -282.401191)
			(xy 274.101071 -282.376584) (xy 274.06295 -282.345459) (xy 274.030315 -282.308622) (xy 274.004012 -282.267026)
			(xy 273.984721 -282.22175) (xy 273.972944 -282.173966) (xy 273.968984 -282.124912) (xy 273.630136 -282.124912)
			(xy 273.629641 -282.149519) (xy 273.621746 -282.198096) (xy 273.606162 -282.244777) (xy 273.583291 -282.288354)
			(xy 273.553726 -282.327698) (xy 273.518233 -282.36179) (xy 273.47773 -282.389746) (xy 273.433268 -282.410844)
			(xy 273.385997 -282.424536) (xy 273.337142 -282.430468) (xy 273.287967 -282.428487) (xy 273.239748 -282.418643)
			(xy 273.193732 -282.401191) (xy 273.151111 -282.376584) (xy 273.11299 -282.345459) (xy 273.080355 -282.308622)
			(xy 273.054052 -282.267026) (xy 273.034761 -282.22175) (xy 273.022984 -282.173966) (xy 273.019024 -282.124912)
			(xy 272.680176 -282.124912) (xy 272.679681 -282.149519) (xy 272.671786 -282.198096) (xy 272.656202 -282.244777)
			(xy 272.633331 -282.288354) (xy 272.603766 -282.327698) (xy 272.568273 -282.36179) (xy 272.52777 -282.389746)
			(xy 272.483308 -282.410844) (xy 272.436037 -282.424536) (xy 272.387182 -282.430468) (xy 272.338007 -282.428487)
			(xy 272.289788 -282.418643) (xy 272.243772 -282.401191) (xy 272.201151 -282.376584) (xy 272.16303 -282.345459)
			(xy 272.130395 -282.308622) (xy 272.104092 -282.267026) (xy 272.084801 -282.22175) (xy 272.073024 -282.173966)
			(xy 272.069064 -282.124912) (xy 271.730216 -282.124912) (xy 271.729721 -282.149519) (xy 271.721826 -282.198096)
			(xy 271.706242 -282.244777) (xy 271.683371 -282.288354) (xy 271.653806 -282.327698) (xy 271.618313 -282.36179)
			(xy 271.57781 -282.389746) (xy 271.533348 -282.410844) (xy 271.486077 -282.424536) (xy 271.437222 -282.430468)
			(xy 271.388047 -282.428487) (xy 271.339828 -282.418643) (xy 271.293812 -282.401191) (xy 271.251191 -282.376584)
			(xy 271.21307 -282.345459) (xy 271.180435 -282.308622) (xy 271.154132 -282.267026) (xy 271.134841 -282.22175)
			(xy 271.123064 -282.173966) (xy 271.119104 -282.124912) (xy 270.780256 -282.124912) (xy 270.779761 -282.149519)
			(xy 270.771866 -282.198096) (xy 270.756282 -282.244777) (xy 270.733411 -282.288354) (xy 270.703846 -282.327698)
			(xy 270.668353 -282.36179) (xy 270.62785 -282.389746) (xy 270.583388 -282.410844) (xy 270.536117 -282.424536)
			(xy 270.487262 -282.430468) (xy 270.438087 -282.428487) (xy 270.389868 -282.418643) (xy 270.343852 -282.401191)
			(xy 270.301231 -282.376584) (xy 270.26311 -282.345459) (xy 270.230475 -282.308622) (xy 270.204172 -282.267026)
			(xy 270.184881 -282.22175) (xy 270.173104 -282.173966) (xy 270.169144 -282.124912) (xy 269.830042 -282.124912)
			(xy 269.829547 -282.149519) (xy 269.821652 -282.198096) (xy 269.806068 -282.244777) (xy 269.783197 -282.288354)
			(xy 269.753632 -282.327698) (xy 269.718139 -282.36179) (xy 269.677636 -282.389746) (xy 269.633174 -282.410844)
			(xy 269.585903 -282.424536) (xy 269.537048 -282.430468) (xy 269.487873 -282.428487) (xy 269.439654 -282.418643)
			(xy 269.393638 -282.401191) (xy 269.351017 -282.376584) (xy 269.312896 -282.345459) (xy 269.280261 -282.308622)
			(xy 269.253958 -282.267026) (xy 269.234667 -282.22175) (xy 269.22289 -282.173966) (xy 269.21893 -282.124912)
			(xy 268.880082 -282.124912) (xy 268.879587 -282.149519) (xy 268.871692 -282.198096) (xy 268.856108 -282.244777)
			(xy 268.833237 -282.288354) (xy 268.803672 -282.327698) (xy 268.768179 -282.36179) (xy 268.727676 -282.389746)
			(xy 268.683214 -282.410844) (xy 268.635943 -282.424536) (xy 268.587088 -282.430468) (xy 268.537913 -282.428487)
			(xy 268.489694 -282.418643) (xy 268.443678 -282.401191) (xy 268.401057 -282.376584) (xy 268.362936 -282.345459)
			(xy 268.330301 -282.308622) (xy 268.303998 -282.267026) (xy 268.284707 -282.22175) (xy 268.27293 -282.173966)
			(xy 268.26897 -282.124912) (xy 263.5758 -282.124912) (xy 263.5758 -282.720288) (xy 263.576142 -282.729276)
			(xy 263.582347 -282.746145) (xy 263.594026 -282.759808) (xy 263.601708 -282.764484) (xy 263.679178 -282.807918)
			(xy 263.689338 -282.812236) (xy 263.693188 -282.813281) (xy 263.701098 -282.814309) (xy 263.705086 -282.814268)
			(xy 263.719056 -282.814014) (xy 263.73074 -282.806648) (xy 263.753374 -282.793217) (xy 263.801553 -282.772035)
			(xy 263.852191 -282.757691) (xy 263.904323 -282.75046) (xy 263.930638 -282.750006) (xy 263.930892 -282.750006)
			(xy 263.958145 -282.750469) (xy 264.012096 -282.758225) (xy 264.064394 -282.77358) (xy 264.113974 -282.796223)
			(xy 264.159827 -282.825691) (xy 264.20102 -282.861385) (xy 264.236713 -282.902578) (xy 264.26618 -282.948431)
			(xy 264.288822 -282.998012) (xy 264.304176 -283.05031) (xy 264.307707 -283.074872) (xy 268.26897 -283.074872)
			(xy 268.27293 -283.025818) (xy 268.284707 -282.978034) (xy 268.303998 -282.932758) (xy 268.330301 -282.891162)
			(xy 268.362936 -282.854325) (xy 268.401057 -282.8232) (xy 268.443678 -282.798593) (xy 268.489694 -282.781141)
			(xy 268.537913 -282.771297) (xy 268.587088 -282.769316) (xy 268.635943 -282.775248) (xy 268.683214 -282.78894)
			(xy 268.727676 -282.810038) (xy 268.768179 -282.837994) (xy 268.803672 -282.872086) (xy 268.833237 -282.91143)
			(xy 268.856108 -282.955007) (xy 268.871692 -283.001688) (xy 268.879587 -283.050265) (xy 268.880082 -283.074872)
			(xy 269.21893 -283.074872) (xy 269.22289 -283.025818) (xy 269.234667 -282.978034) (xy 269.253958 -282.932758)
			(xy 269.280261 -282.891162) (xy 269.312896 -282.854325) (xy 269.351017 -282.8232) (xy 269.393638 -282.798593)
			(xy 269.439654 -282.781141) (xy 269.487873 -282.771297) (xy 269.537048 -282.769316) (xy 269.585903 -282.775248)
			(xy 269.633174 -282.78894) (xy 269.677636 -282.810038) (xy 269.718139 -282.837994) (xy 269.753632 -282.872086)
			(xy 269.783197 -282.91143) (xy 269.806068 -282.955007) (xy 269.821652 -283.001688) (xy 269.829547 -283.050265)
			(xy 269.830042 -283.074872) (xy 270.169144 -283.074872) (xy 270.173104 -283.025818) (xy 270.184881 -282.978034)
			(xy 270.204172 -282.932758) (xy 270.230475 -282.891162) (xy 270.26311 -282.854325) (xy 270.301231 -282.8232)
			(xy 270.343852 -282.798593) (xy 270.389868 -282.781141) (xy 270.438087 -282.771297) (xy 270.487262 -282.769316)
			(xy 270.536117 -282.775248) (xy 270.583388 -282.78894) (xy 270.62785 -282.810038) (xy 270.668353 -282.837994)
			(xy 270.703846 -282.872086) (xy 270.733411 -282.91143) (xy 270.756282 -282.955007) (xy 270.771866 -283.001688)
			(xy 270.779761 -283.050265) (xy 270.780256 -283.074872) (xy 271.119104 -283.074872) (xy 271.123064 -283.025818)
			(xy 271.134841 -282.978034) (xy 271.154132 -282.932758) (xy 271.180435 -282.891162) (xy 271.21307 -282.854325)
			(xy 271.251191 -282.8232) (xy 271.293812 -282.798593) (xy 271.339828 -282.781141) (xy 271.388047 -282.771297)
			(xy 271.437222 -282.769316) (xy 271.486077 -282.775248) (xy 271.533348 -282.78894) (xy 271.57781 -282.810038)
			(xy 271.618313 -282.837994) (xy 271.653806 -282.872086) (xy 271.683371 -282.91143) (xy 271.706242 -282.955007)
			(xy 271.721826 -283.001688) (xy 271.729721 -283.050265) (xy 271.730216 -283.074872) (xy 272.069064 -283.074872)
			(xy 272.073024 -283.025818) (xy 272.084801 -282.978034) (xy 272.104092 -282.932758) (xy 272.130395 -282.891162)
			(xy 272.16303 -282.854325) (xy 272.201151 -282.8232) (xy 272.243772 -282.798593) (xy 272.289788 -282.781141)
			(xy 272.338007 -282.771297) (xy 272.387182 -282.769316) (xy 272.436037 -282.775248) (xy 272.483308 -282.78894)
			(xy 272.52777 -282.810038) (xy 272.568273 -282.837994) (xy 272.603766 -282.872086) (xy 272.633331 -282.91143)
			(xy 272.656202 -282.955007) (xy 272.671786 -283.001688) (xy 272.679681 -283.050265) (xy 272.680176 -283.074872)
			(xy 273.019024 -283.074872) (xy 273.022984 -283.025818) (xy 273.034761 -282.978034) (xy 273.054052 -282.932758)
			(xy 273.080355 -282.891162) (xy 273.11299 -282.854325) (xy 273.151111 -282.8232) (xy 273.193732 -282.798593)
			(xy 273.239748 -282.781141) (xy 273.287967 -282.771297) (xy 273.337142 -282.769316) (xy 273.385997 -282.775248)
			(xy 273.433268 -282.78894) (xy 273.47773 -282.810038) (xy 273.518233 -282.837994) (xy 273.553726 -282.872086)
			(xy 273.583291 -282.91143) (xy 273.606162 -282.955007) (xy 273.621746 -283.001688) (xy 273.629641 -283.050265)
			(xy 273.630136 -283.074872) (xy 273.968984 -283.074872) (xy 273.972944 -283.025818) (xy 273.984721 -282.978034)
			(xy 274.004012 -282.932758) (xy 274.030315 -282.891162) (xy 274.06295 -282.854325) (xy 274.101071 -282.8232)
			(xy 274.143692 -282.798593) (xy 274.189708 -282.781141) (xy 274.237927 -282.771297) (xy 274.287102 -282.769316)
			(xy 274.335957 -282.775248) (xy 274.383228 -282.78894) (xy 274.42769 -282.810038) (xy 274.468193 -282.837994)
			(xy 274.503686 -282.872086) (xy 274.533251 -282.91143) (xy 274.556122 -282.955007) (xy 274.571706 -283.001688)
			(xy 274.579601 -283.050265) (xy 274.580096 -283.074872) (xy 274.579601 -283.099479) (xy 274.571706 -283.148056)
			(xy 274.556122 -283.194737) (xy 274.533251 -283.238314) (xy 274.503686 -283.277658) (xy 274.468193 -283.31175)
			(xy 274.42769 -283.339706) (xy 274.383228 -283.360804) (xy 274.335957 -283.374496) (xy 274.287102 -283.380428)
			(xy 274.237927 -283.378447) (xy 274.189708 -283.368603) (xy 274.143692 -283.351151) (xy 274.101071 -283.326544)
			(xy 274.06295 -283.295419) (xy 274.030315 -283.258582) (xy 274.004012 -283.216986) (xy 273.984721 -283.17171)
			(xy 273.972944 -283.123926) (xy 273.968984 -283.074872) (xy 273.630136 -283.074872) (xy 273.629641 -283.099479)
			(xy 273.621746 -283.148056) (xy 273.606162 -283.194737) (xy 273.583291 -283.238314) (xy 273.553726 -283.277658)
			(xy 273.518233 -283.31175) (xy 273.47773 -283.339706) (xy 273.433268 -283.360804) (xy 273.385997 -283.374496)
			(xy 273.337142 -283.380428) (xy 273.287967 -283.378447) (xy 273.239748 -283.368603) (xy 273.193732 -283.351151)
			(xy 273.151111 -283.326544) (xy 273.11299 -283.295419) (xy 273.080355 -283.258582) (xy 273.054052 -283.216986)
			(xy 273.034761 -283.17171) (xy 273.022984 -283.123926) (xy 273.019024 -283.074872) (xy 272.680176 -283.074872)
			(xy 272.679681 -283.099479) (xy 272.671786 -283.148056) (xy 272.656202 -283.194737) (xy 272.633331 -283.238314)
			(xy 272.603766 -283.277658) (xy 272.568273 -283.31175) (xy 272.52777 -283.339706) (xy 272.483308 -283.360804)
			(xy 272.436037 -283.374496) (xy 272.387182 -283.380428) (xy 272.338007 -283.378447) (xy 272.289788 -283.368603)
			(xy 272.243772 -283.351151) (xy 272.201151 -283.326544) (xy 272.16303 -283.295419) (xy 272.130395 -283.258582)
			(xy 272.104092 -283.216986) (xy 272.084801 -283.17171) (xy 272.073024 -283.123926) (xy 272.069064 -283.074872)
			(xy 271.730216 -283.074872) (xy 271.729721 -283.099479) (xy 271.721826 -283.148056) (xy 271.706242 -283.194737)
			(xy 271.683371 -283.238314) (xy 271.653806 -283.277658) (xy 271.618313 -283.31175) (xy 271.57781 -283.339706)
			(xy 271.533348 -283.360804) (xy 271.486077 -283.374496) (xy 271.437222 -283.380428) (xy 271.388047 -283.378447)
			(xy 271.339828 -283.368603) (xy 271.293812 -283.351151) (xy 271.251191 -283.326544) (xy 271.21307 -283.295419)
			(xy 271.180435 -283.258582) (xy 271.154132 -283.216986) (xy 271.134841 -283.17171) (xy 271.123064 -283.123926)
			(xy 271.119104 -283.074872) (xy 270.780256 -283.074872) (xy 270.779761 -283.099479) (xy 270.771866 -283.148056)
			(xy 270.756282 -283.194737) (xy 270.733411 -283.238314) (xy 270.703846 -283.277658) (xy 270.668353 -283.31175)
			(xy 270.62785 -283.339706) (xy 270.583388 -283.360804) (xy 270.536117 -283.374496) (xy 270.487262 -283.380428)
			(xy 270.438087 -283.378447) (xy 270.389868 -283.368603) (xy 270.343852 -283.351151) (xy 270.301231 -283.326544)
			(xy 270.26311 -283.295419) (xy 270.230475 -283.258582) (xy 270.204172 -283.216986) (xy 270.184881 -283.17171)
			(xy 270.173104 -283.123926) (xy 270.169144 -283.074872) (xy 269.830042 -283.074872) (xy 269.829547 -283.099479)
			(xy 269.821652 -283.148056) (xy 269.806068 -283.194737) (xy 269.783197 -283.238314) (xy 269.753632 -283.277658)
			(xy 269.718139 -283.31175) (xy 269.677636 -283.339706) (xy 269.633174 -283.360804) (xy 269.585903 -283.374496)
			(xy 269.537048 -283.380428) (xy 269.487873 -283.378447) (xy 269.439654 -283.368603) (xy 269.393638 -283.351151)
			(xy 269.351017 -283.326544) (xy 269.312896 -283.295419) (xy 269.280261 -283.258582) (xy 269.253958 -283.216986)
			(xy 269.234667 -283.17171) (xy 269.22289 -283.123926) (xy 269.21893 -283.074872) (xy 268.880082 -283.074872)
			(xy 268.879587 -283.099479) (xy 268.871692 -283.148056) (xy 268.856108 -283.194737) (xy 268.833237 -283.238314)
			(xy 268.803672 -283.277658) (xy 268.768179 -283.31175) (xy 268.727676 -283.339706) (xy 268.683214 -283.360804)
			(xy 268.635943 -283.374496) (xy 268.587088 -283.380428) (xy 268.537913 -283.378447) (xy 268.489694 -283.368603)
			(xy 268.443678 -283.351151) (xy 268.401057 -283.326544) (xy 268.362936 -283.295419) (xy 268.330301 -283.258582)
			(xy 268.303998 -283.216986) (xy 268.284707 -283.17171) (xy 268.27293 -283.123926) (xy 268.26897 -283.074872)
			(xy 264.307707 -283.074872) (xy 264.311932 -283.104261) (xy 264.3124 -283.131514) (xy 264.311836 -283.160893)
			(xy 264.302786 -283.218952) (xy 264.284947 -283.274939) (xy 264.258741 -283.327531) (xy 264.224787 -283.375488)
			(xy 264.183887 -283.417676) (xy 264.160762 -283.435806) (xy 264.160508 -283.435806) (xy 264.156045 -283.439418)
			(xy 264.148732 -283.448266) (xy 264.14603 -283.453332) (xy 264.143236 -283.458666) (xy 264.140696 -283.469588)
			(xy 264.13968 -283.555948) (xy 264.139752 -283.561723) (xy 264.142196 -283.573006) (xy 264.144506 -283.5783)
			(xy 264.146792 -283.58338) (xy 264.153904 -283.59227) (xy 264.158476 -283.59608) (xy 264.1803 -283.614311)
			(xy 264.218829 -283.656133) (xy 264.25073 -283.703206) (xy 264.275297 -283.754489) (xy 264.291988 -283.808848)
			(xy 264.300433 -283.865082) (xy 264.30097 -283.893514) (xy 264.934444 -283.893514) (xy 264.938515 -283.837892)
			(xy 264.950641 -283.783455) (xy 264.970564 -283.731364) (xy 264.99786 -283.682729) (xy 265.031946 -283.638586)
			(xy 265.072095 -283.599877) (xy 265.117453 -283.567426) (xy 265.167053 -283.541925) (xy 265.219837 -283.523918)
			(xy 265.27468 -283.513788) (xy 265.330414 -283.511751) (xy 265.385851 -283.517851) (xy 265.439808 -283.531957)
			(xy 265.491137 -283.553769) (xy 265.538743 -283.582823) (xy 265.581611 -283.618498) (xy 265.618828 -283.660035)
			(xy 265.649601 -283.706548) (xy 265.673273 -283.757045) (xy 265.689341 -283.810452) (xy 265.697461 -283.865628)
			(xy 265.69797 -283.893514) (xy 265.820904 -283.893514) (xy 265.824975 -283.837892) (xy 265.837101 -283.783455)
			(xy 265.857024 -283.731364) (xy 265.88432 -283.682729) (xy 265.918406 -283.638586) (xy 265.958555 -283.599877)
			(xy 266.003913 -283.567426) (xy 266.053513 -283.541925) (xy 266.106297 -283.523918) (xy 266.16114 -283.513788)
			(xy 266.216874 -283.511751) (xy 266.272311 -283.517851) (xy 266.326268 -283.531957) (xy 266.377597 -283.553769)
			(xy 266.425203 -283.582823) (xy 266.468071 -283.618498) (xy 266.505288 -283.660035) (xy 266.536061 -283.706548)
			(xy 266.559733 -283.757045) (xy 266.575801 -283.810452) (xy 266.583921 -283.865628) (xy 266.58443 -283.893514)
			(xy 266.583921 -283.9214) (xy 266.575801 -283.976576) (xy 266.561283 -284.024832) (xy 268.26897 -284.024832)
			(xy 268.27293 -283.975778) (xy 268.284707 -283.927994) (xy 268.303998 -283.882718) (xy 268.330301 -283.841122)
			(xy 268.362936 -283.804285) (xy 268.401057 -283.77316) (xy 268.443678 -283.748553) (xy 268.489694 -283.731101)
			(xy 268.537913 -283.721257) (xy 268.587088 -283.719276) (xy 268.635943 -283.725208) (xy 268.683214 -283.7389)
			(xy 268.727676 -283.759998) (xy 268.768179 -283.787954) (xy 268.803672 -283.822046) (xy 268.833237 -283.86139)
			(xy 268.856108 -283.904967) (xy 268.871692 -283.951648) (xy 268.879587 -284.000225) (xy 268.880082 -284.024832)
			(xy 269.21893 -284.024832) (xy 269.22289 -283.975778) (xy 269.234667 -283.927994) (xy 269.253958 -283.882718)
			(xy 269.280261 -283.841122) (xy 269.312896 -283.804285) (xy 269.351017 -283.77316) (xy 269.393638 -283.748553)
			(xy 269.439654 -283.731101) (xy 269.487873 -283.721257) (xy 269.537048 -283.719276) (xy 269.585903 -283.725208)
			(xy 269.633174 -283.7389) (xy 269.677636 -283.759998) (xy 269.718139 -283.787954) (xy 269.753632 -283.822046)
			(xy 269.783197 -283.86139) (xy 269.806068 -283.904967) (xy 269.821652 -283.951648) (xy 269.829547 -284.000225)
			(xy 269.830042 -284.024832) (xy 270.169144 -284.024832) (xy 270.173104 -283.975778) (xy 270.184881 -283.927994)
			(xy 270.204172 -283.882718) (xy 270.230475 -283.841122) (xy 270.26311 -283.804285) (xy 270.301231 -283.77316)
			(xy 270.343852 -283.748553) (xy 270.389868 -283.731101) (xy 270.438087 -283.721257) (xy 270.487262 -283.719276)
			(xy 270.536117 -283.725208) (xy 270.583388 -283.7389) (xy 270.62785 -283.759998) (xy 270.668353 -283.787954)
			(xy 270.703846 -283.822046) (xy 270.733411 -283.86139) (xy 270.756282 -283.904967) (xy 270.771866 -283.951648)
			(xy 270.779761 -284.000225) (xy 270.780256 -284.024832) (xy 271.119104 -284.024832) (xy 271.123064 -283.975778)
			(xy 271.134841 -283.927994) (xy 271.154132 -283.882718) (xy 271.180435 -283.841122) (xy 271.21307 -283.804285)
			(xy 271.251191 -283.77316) (xy 271.293812 -283.748553) (xy 271.339828 -283.731101) (xy 271.388047 -283.721257)
			(xy 271.437222 -283.719276) (xy 271.486077 -283.725208) (xy 271.533348 -283.7389) (xy 271.57781 -283.759998)
			(xy 271.618313 -283.787954) (xy 271.653806 -283.822046) (xy 271.683371 -283.86139) (xy 271.706242 -283.904967)
			(xy 271.721826 -283.951648) (xy 271.729721 -284.000225) (xy 271.730216 -284.024832) (xy 272.069064 -284.024832)
			(xy 272.073024 -283.975778) (xy 272.084801 -283.927994) (xy 272.104092 -283.882718) (xy 272.130395 -283.841122)
			(xy 272.16303 -283.804285) (xy 272.201151 -283.77316) (xy 272.243772 -283.748553) (xy 272.289788 -283.731101)
			(xy 272.338007 -283.721257) (xy 272.387182 -283.719276) (xy 272.436037 -283.725208) (xy 272.483308 -283.7389)
			(xy 272.52777 -283.759998) (xy 272.568273 -283.787954) (xy 272.603766 -283.822046) (xy 272.633331 -283.86139)
			(xy 272.656202 -283.904967) (xy 272.671786 -283.951648) (xy 272.679681 -284.000225) (xy 272.680176 -284.024832)
			(xy 272.679681 -284.049439) (xy 272.671786 -284.098016) (xy 272.656202 -284.144697) (xy 272.633331 -284.188274)
			(xy 272.603766 -284.227618) (xy 272.568273 -284.26171) (xy 272.52777 -284.289666) (xy 272.483308 -284.310764)
			(xy 272.436037 -284.324456) (xy 272.387182 -284.330388) (xy 272.338007 -284.328407) (xy 272.289788 -284.318563)
			(xy 272.243772 -284.301111) (xy 272.201151 -284.276504) (xy 272.16303 -284.245379) (xy 272.130395 -284.208542)
			(xy 272.104092 -284.166946) (xy 272.084801 -284.12167) (xy 272.073024 -284.073886) (xy 272.069064 -284.024832)
			(xy 271.730216 -284.024832) (xy 271.729721 -284.049439) (xy 271.721826 -284.098016) (xy 271.706242 -284.144697)
			(xy 271.683371 -284.188274) (xy 271.653806 -284.227618) (xy 271.618313 -284.26171) (xy 271.57781 -284.289666)
			(xy 271.533348 -284.310764) (xy 271.486077 -284.324456) (xy 271.437222 -284.330388) (xy 271.388047 -284.328407)
			(xy 271.339828 -284.318563) (xy 271.293812 -284.301111) (xy 271.251191 -284.276504) (xy 271.21307 -284.245379)
			(xy 271.180435 -284.208542) (xy 271.154132 -284.166946) (xy 271.134841 -284.12167) (xy 271.123064 -284.073886)
			(xy 271.119104 -284.024832) (xy 270.780256 -284.024832) (xy 270.779761 -284.049439) (xy 270.771866 -284.098016)
			(xy 270.756282 -284.144697) (xy 270.733411 -284.188274) (xy 270.703846 -284.227618) (xy 270.668353 -284.26171)
			(xy 270.62785 -284.289666) (xy 270.583388 -284.310764) (xy 270.536117 -284.324456) (xy 270.487262 -284.330388)
			(xy 270.438087 -284.328407) (xy 270.389868 -284.318563) (xy 270.343852 -284.301111) (xy 270.301231 -284.276504)
			(xy 270.26311 -284.245379) (xy 270.230475 -284.208542) (xy 270.204172 -284.166946) (xy 270.184881 -284.12167)
			(xy 270.173104 -284.073886) (xy 270.169144 -284.024832) (xy 269.830042 -284.024832) (xy 269.829547 -284.049439)
			(xy 269.821652 -284.098016) (xy 269.806068 -284.144697) (xy 269.783197 -284.188274) (xy 269.753632 -284.227618)
			(xy 269.718139 -284.26171) (xy 269.677636 -284.289666) (xy 269.633174 -284.310764) (xy 269.585903 -284.324456)
			(xy 269.537048 -284.330388) (xy 269.487873 -284.328407) (xy 269.439654 -284.318563) (xy 269.393638 -284.301111)
			(xy 269.351017 -284.276504) (xy 269.312896 -284.245379) (xy 269.280261 -284.208542) (xy 269.253958 -284.166946)
			(xy 269.234667 -284.12167) (xy 269.22289 -284.073886) (xy 269.21893 -284.024832) (xy 268.880082 -284.024832)
			(xy 268.879587 -284.049439) (xy 268.871692 -284.098016) (xy 268.856108 -284.144697) (xy 268.833237 -284.188274)
			(xy 268.803672 -284.227618) (xy 268.768179 -284.26171) (xy 268.727676 -284.289666) (xy 268.683214 -284.310764)
			(xy 268.635943 -284.324456) (xy 268.587088 -284.330388) (xy 268.537913 -284.328407) (xy 268.489694 -284.318563)
			(xy 268.443678 -284.301111) (xy 268.401057 -284.276504) (xy 268.362936 -284.245379) (xy 268.330301 -284.208542)
			(xy 268.303998 -284.166946) (xy 268.284707 -284.12167) (xy 268.27293 -284.073886) (xy 268.26897 -284.024832)
			(xy 266.561283 -284.024832) (xy 266.559733 -284.029983) (xy 266.536061 -284.08048) (xy 266.505288 -284.126993)
			(xy 266.468071 -284.16853) (xy 266.425203 -284.204205) (xy 266.377597 -284.233259) (xy 266.326268 -284.255071)
			(xy 266.272311 -284.269177) (xy 266.216874 -284.275277) (xy 266.16114 -284.27324) (xy 266.106297 -284.26311)
			(xy 266.053513 -284.245103) (xy 266.003913 -284.219602) (xy 265.958555 -284.187151) (xy 265.918406 -284.148442)
			(xy 265.88432 -284.104299) (xy 265.857024 -284.055664) (xy 265.837101 -284.003573) (xy 265.824975 -283.949136)
			(xy 265.820904 -283.893514) (xy 265.69797 -283.893514) (xy 265.697461 -283.9214) (xy 265.689341 -283.976576)
			(xy 265.673273 -284.029983) (xy 265.649601 -284.08048) (xy 265.618828 -284.126993) (xy 265.581611 -284.16853)
			(xy 265.538743 -284.204205) (xy 265.491137 -284.233259) (xy 265.439808 -284.255071) (xy 265.385851 -284.269177)
			(xy 265.330414 -284.275277) (xy 265.27468 -284.27324) (xy 265.219837 -284.26311) (xy 265.167053 -284.245103)
			(xy 265.117453 -284.219602) (xy 265.072095 -284.187151) (xy 265.031946 -284.148442) (xy 264.99786 -284.104299)
			(xy 264.970564 -284.055664) (xy 264.950641 -284.003573) (xy 264.938515 -283.949136) (xy 264.934444 -283.893514)
			(xy 264.30097 -283.893514) (xy 264.300506 -283.920765) (xy 264.292747 -283.974713) (xy 264.277389 -284.027007)
			(xy 264.254745 -284.076583) (xy 264.225276 -284.122431) (xy 264.189582 -284.163619) (xy 264.148389 -284.199308)
			(xy 264.102537 -284.22877) (xy 264.052958 -284.251407) (xy 264.000662 -284.266758) (xy 263.946713 -284.274509)
			(xy 263.919462 -284.275022) (xy 263.919208 -284.275022) (xy 263.894188 -284.274634) (xy 263.844578 -284.268096)
			(xy 263.796251 -284.255119) (xy 263.75004 -284.235926) (xy 263.7282 -284.223714) (xy 263.720326 -284.219555)
			(xy 263.7028 -284.216461) (xy 263.685274 -284.219555) (xy 263.6774 -284.223714) (xy 263.601454 -284.267402)
			(xy 263.595358 -284.271212) (xy 263.586482 -284.278851) (xy 263.576278 -284.299898) (xy 263.5758 -284.311598)
			(xy 263.5758 -284.974792) (xy 268.26897 -284.974792) (xy 268.27293 -284.925738) (xy 268.284707 -284.877954)
			(xy 268.303998 -284.832678) (xy 268.330301 -284.791082) (xy 268.362936 -284.754245) (xy 268.401057 -284.72312)
			(xy 268.443678 -284.698513) (xy 268.489694 -284.681061) (xy 268.537913 -284.671217) (xy 268.587088 -284.669236)
			(xy 268.635943 -284.675168) (xy 268.683214 -284.68886) (xy 268.727676 -284.709958) (xy 268.768179 -284.737914)
			(xy 268.803672 -284.772006) (xy 268.833237 -284.81135) (xy 268.856108 -284.854927) (xy 268.871692 -284.901608)
			(xy 268.879587 -284.950185) (xy 268.880082 -284.974792) (xy 269.21893 -284.974792) (xy 269.22289 -284.925738)
			(xy 269.234667 -284.877954) (xy 269.253958 -284.832678) (xy 269.280261 -284.791082) (xy 269.312896 -284.754245)
			(xy 269.351017 -284.72312) (xy 269.393638 -284.698513) (xy 269.439654 -284.681061) (xy 269.487873 -284.671217)
			(xy 269.537048 -284.669236) (xy 269.585903 -284.675168) (xy 269.633174 -284.68886) (xy 269.677636 -284.709958)
			(xy 269.718139 -284.737914) (xy 269.753632 -284.772006) (xy 269.783197 -284.81135) (xy 269.806068 -284.854927)
			(xy 269.821652 -284.901608) (xy 269.829547 -284.950185) (xy 269.830042 -284.974792) (xy 270.169144 -284.974792)
			(xy 270.173104 -284.925738) (xy 270.184881 -284.877954) (xy 270.204172 -284.832678) (xy 270.230475 -284.791082)
			(xy 270.26311 -284.754245) (xy 270.301231 -284.72312) (xy 270.343852 -284.698513) (xy 270.389868 -284.681061)
			(xy 270.438087 -284.671217) (xy 270.487262 -284.669236) (xy 270.536117 -284.675168) (xy 270.583388 -284.68886)
			(xy 270.62785 -284.709958) (xy 270.668353 -284.737914) (xy 270.703846 -284.772006) (xy 270.733411 -284.81135)
			(xy 270.756282 -284.854927) (xy 270.771866 -284.901608) (xy 270.779761 -284.950185) (xy 270.780256 -284.974792)
			(xy 271.119104 -284.974792) (xy 271.123064 -284.925738) (xy 271.134841 -284.877954) (xy 271.154132 -284.832678)
			(xy 271.180435 -284.791082) (xy 271.21307 -284.754245) (xy 271.251191 -284.72312) (xy 271.293812 -284.698513)
			(xy 271.339828 -284.681061) (xy 271.388047 -284.671217) (xy 271.437222 -284.669236) (xy 271.486077 -284.675168)
			(xy 271.533348 -284.68886) (xy 271.57781 -284.709958) (xy 271.618313 -284.737914) (xy 271.653806 -284.772006)
			(xy 271.683371 -284.81135) (xy 271.706242 -284.854927) (xy 271.721826 -284.901608) (xy 271.729721 -284.950185)
			(xy 271.730216 -284.974792) (xy 272.069064 -284.974792) (xy 272.073024 -284.925738) (xy 272.084801 -284.877954)
			(xy 272.104092 -284.832678) (xy 272.130395 -284.791082) (xy 272.16303 -284.754245) (xy 272.201151 -284.72312)
			(xy 272.243772 -284.698513) (xy 272.289788 -284.681061) (xy 272.338007 -284.671217) (xy 272.387182 -284.669236)
			(xy 272.436037 -284.675168) (xy 272.483308 -284.68886) (xy 272.52777 -284.709958) (xy 272.568273 -284.737914)
			(xy 272.603766 -284.772006) (xy 272.633331 -284.81135) (xy 272.656202 -284.854927) (xy 272.671786 -284.901608)
			(xy 272.679681 -284.950185) (xy 272.680176 -284.974792) (xy 272.679681 -284.999399) (xy 272.671786 -285.047976)
			(xy 272.656202 -285.094657) (xy 272.633331 -285.138234) (xy 272.603766 -285.177578) (xy 272.568273 -285.21167)
			(xy 272.52777 -285.239626) (xy 272.483308 -285.260724) (xy 272.436037 -285.274416) (xy 272.387182 -285.280348)
			(xy 272.338007 -285.278367) (xy 272.289788 -285.268523) (xy 272.243772 -285.251071) (xy 272.201151 -285.226464)
			(xy 272.16303 -285.195339) (xy 272.130395 -285.158502) (xy 272.104092 -285.116906) (xy 272.084801 -285.07163)
			(xy 272.073024 -285.023846) (xy 272.069064 -284.974792) (xy 271.730216 -284.974792) (xy 271.729721 -284.999399)
			(xy 271.721826 -285.047976) (xy 271.706242 -285.094657) (xy 271.683371 -285.138234) (xy 271.653806 -285.177578)
			(xy 271.618313 -285.21167) (xy 271.57781 -285.239626) (xy 271.533348 -285.260724) (xy 271.486077 -285.274416)
			(xy 271.437222 -285.280348) (xy 271.388047 -285.278367) (xy 271.339828 -285.268523) (xy 271.293812 -285.251071)
			(xy 271.251191 -285.226464) (xy 271.21307 -285.195339) (xy 271.180435 -285.158502) (xy 271.154132 -285.116906)
			(xy 271.134841 -285.07163) (xy 271.123064 -285.023846) (xy 271.119104 -284.974792) (xy 270.780256 -284.974792)
			(xy 270.779761 -284.999399) (xy 270.771866 -285.047976) (xy 270.756282 -285.094657) (xy 270.733411 -285.138234)
			(xy 270.703846 -285.177578) (xy 270.668353 -285.21167) (xy 270.62785 -285.239626) (xy 270.583388 -285.260724)
			(xy 270.536117 -285.274416) (xy 270.487262 -285.280348) (xy 270.438087 -285.278367) (xy 270.389868 -285.268523)
			(xy 270.343852 -285.251071) (xy 270.301231 -285.226464) (xy 270.26311 -285.195339) (xy 270.230475 -285.158502)
			(xy 270.204172 -285.116906) (xy 270.184881 -285.07163) (xy 270.173104 -285.023846) (xy 270.169144 -284.974792)
			(xy 269.830042 -284.974792) (xy 269.829547 -284.999399) (xy 269.821652 -285.047976) (xy 269.806068 -285.094657)
			(xy 269.783197 -285.138234) (xy 269.753632 -285.177578) (xy 269.718139 -285.21167) (xy 269.677636 -285.239626)
			(xy 269.633174 -285.260724) (xy 269.585903 -285.274416) (xy 269.537048 -285.280348) (xy 269.487873 -285.278367)
			(xy 269.439654 -285.268523) (xy 269.393638 -285.251071) (xy 269.351017 -285.226464) (xy 269.312896 -285.195339)
			(xy 269.280261 -285.158502) (xy 269.253958 -285.116906) (xy 269.234667 -285.07163) (xy 269.22289 -285.023846)
			(xy 269.21893 -284.974792) (xy 268.880082 -284.974792) (xy 268.879587 -284.999399) (xy 268.871692 -285.047976)
			(xy 268.856108 -285.094657) (xy 268.833237 -285.138234) (xy 268.803672 -285.177578) (xy 268.768179 -285.21167)
			(xy 268.727676 -285.239626) (xy 268.683214 -285.260724) (xy 268.635943 -285.274416) (xy 268.587088 -285.280348)
			(xy 268.537913 -285.278367) (xy 268.489694 -285.268523) (xy 268.443678 -285.251071) (xy 268.401057 -285.226464)
			(xy 268.362936 -285.195339) (xy 268.330301 -285.158502) (xy 268.303998 -285.116906) (xy 268.284707 -285.07163)
			(xy 268.27293 -285.023846) (xy 268.26897 -284.974792) (xy 263.5758 -284.974792) (xy 263.5758 -285.398718)
			(xy 263.576112 -285.40691) (xy 263.581299 -285.422453) (xy 263.58596 -285.429198) (xy 263.590786 -285.434786)
			(xy 263.840214 -285.684214) (xy 263.845802 -285.68904) (xy 263.852542 -285.693711) (xy 263.868088 -285.698899)
			(xy 263.876282 -285.6992)
		)
		(stroke
			(width 0)
			(type solid)
		)
		(fill yes)
		(layer "In11.Cu")
		(net "P1V8_PEX")
	)
	(gr_poly
		(pts
			(xy 129.641092 -250.463558) (xy 129.652843 -250.462953) (xy 129.673881 -250.452479) (xy 129.681478 -250.443492)
			(xy 129.7305 -250.379484) (xy 129.73401 -250.374645) (xy 129.738892 -250.363737) (xy 129.740152 -250.357894)
			(xy 129.742184 -250.346464) (xy 129.739136 -250.335034) (xy 129.732718 -250.310191) (xy 129.725837 -250.259343)
			(xy 129.72542 -250.233688) (xy 129.725906 -250.206437) (xy 129.733662 -250.152489) (xy 129.749017 -250.100194)
			(xy 129.771659 -250.050617) (xy 129.801125 -250.004767) (xy 129.836816 -249.963576) (xy 129.878007 -249.927885)
			(xy 129.923857 -249.898419) (xy 129.973434 -249.875777) (xy 130.025729 -249.860422) (xy 130.079677 -249.852666)
			(xy 130.134179 -249.852666) (xy 130.188127 -249.860422) (xy 130.240422 -249.875777) (xy 130.289999 -249.898419)
			(xy 130.335849 -249.927885) (xy 130.37704 -249.963576) (xy 130.412731 -250.004767) (xy 130.442197 -250.050617)
			(xy 130.464839 -250.100194) (xy 130.480194 -250.152489) (xy 130.48795 -250.206437) (xy 130.488436 -250.233688)
			(xy 130.488019 -250.259344) (xy 130.48114 -250.310191) (xy 130.47472 -250.335034) (xy 130.471672 -250.346464)
			(xy 130.473704 -250.357894) (xy 130.474971 -250.363735) (xy 130.479856 -250.374639) (xy 130.483356 -250.379484)
			(xy 130.532378 -250.443492) (xy 130.539971 -250.452478) (xy 130.561016 -250.462933) (xy 130.572764 -250.463558)
			(xy 136.940798 -250.463558) (xy 136.948926 -250.462796) (xy 136.949434 -250.462796) (xy 136.956952 -250.461195)
			(xy 136.97064 -250.454218) (xy 136.976358 -250.44908) (xy 145.002504 -242.422934) (xy 145.003012 -242.422426)
			(xy 145.008209 -242.416749) (xy 145.015199 -242.403045) (xy 145.016728 -242.395502) (xy 145.016728 -242.394994)
			(xy 145.01749 -242.386866) (xy 145.01749 -237.31347) (xy 145.017918 -237.303402) (xy 145.025639 -237.284804)
			(xy 145.032476 -237.277402) (xy 145.700242 -236.609636) (xy 145.707641 -236.602792) (xy 145.72624 -236.595068)
			(xy 145.73631 -236.59465) (xy 152.014428 -236.59465) (xy 152.022556 -236.593888) (xy 152.023064 -236.593888)
			(xy 152.03058 -236.592283) (xy 152.044261 -236.585299) (xy 152.049988 -236.580172) (xy 152.640538 -235.989622)
			(xy 152.641046 -235.989114) (xy 152.646239 -235.983435) (xy 152.65322 -235.969729) (xy 152.654762 -235.96219)
			(xy 152.654762 -235.961682) (xy 152.655524 -235.953554) (xy 152.655524 -232.777284) (xy 152.655035 -232.767194)
			(xy 152.647175 -232.748602) (xy 152.640284 -232.741216) (xy 152.588976 -232.690416) (xy 152.581619 -232.683769)
			(xy 152.563318 -232.676195) (xy 152.553416 -232.675684) (xy 152.548336 -232.675684) (xy 152.521082 -232.675223)
			(xy 152.467129 -232.66747) (xy 152.414828 -232.652117) (xy 152.365245 -232.629476) (xy 152.319389 -232.600009)
			(xy 152.278194 -232.564315) (xy 152.242498 -232.523121) (xy 152.21303 -232.477266) (xy 152.190387 -232.427683)
			(xy 152.175032 -232.375383) (xy 152.167278 -232.32143) (xy 152.166828 -232.294176) (xy 152.167248 -232.268778)
			(xy 152.173991 -232.218431) (xy 152.187354 -232.169424) (xy 152.207102 -232.122623) (xy 152.232884 -232.078856)
			(xy 152.264246 -232.038897) (xy 152.282144 -232.020872) (xy 152.287952 -232.014697) (xy 152.295476 -231.999515)
			(xy 152.296876 -231.991154) (xy 152.300827 -231.964332) (xy 152.315329 -231.912092) (xy 152.337083 -231.862433)
			(xy 152.36565 -231.816355) (xy 152.400455 -231.774787) (xy 152.440796 -231.738567) (xy 152.485859 -231.708425)
			(xy 152.534737 -231.684968) (xy 152.586444 -231.668669) (xy 152.613106 -231.663748) (xy 152.62225 -231.662224)
			(xy 152.63749 -231.653588) (xy 152.643586 -231.646476) (xy 152.64884 -231.639731) (xy 152.654926 -231.623764)
			(xy 152.655524 -231.615234) (xy 152.655524 -205.387448) (xy 152.65527 -205.382876) (xy 152.556972 -204.27442)
			(xy 152.555775 -204.265603) (xy 152.548232 -204.249503) (xy 152.54224 -204.242924) (xy 149.418802 -201.119486)
			(xy 149.414516 -201.115466) (xy 149.40451 -201.10931) (xy 149.39899 -201.107294) (xy 149.371141 -201.097448)
			(xy 149.318637 -201.070389) (xy 149.270931 -201.035562) (xy 149.229163 -200.993798) (xy 149.194331 -200.946095)
			(xy 149.167267 -200.893594) (xy 149.157436 -200.86574) (xy 149.153626 -200.85431) (xy 148.987256 -200.68794)
			(xy 148.981668 -200.683114) (xy 148.974926 -200.67845) (xy 148.95938 -200.673277) (xy 148.951188 -200.672954)
			(xy 128.50622 -200.672954) (xy 128.498025 -200.673259) (xy 128.482473 -200.678433) (xy 128.47574 -200.683114)
			(xy 128.470152 -200.68794) (xy 128.467104 -200.690988) (xy 128.448921 -200.711299) (xy 128.407748 -200.747027)
			(xy 128.361905 -200.776525) (xy 128.312328 -200.799193) (xy 128.260028 -200.814567) (xy 128.206071 -200.822335)
			(xy 128.178814 -200.822814) (xy 128.15156 -200.822309) (xy 128.097611 -200.814519) (xy 128.045318 -200.799137)
			(xy 127.995743 -200.776477) (xy 127.949894 -200.746998) (xy 127.908701 -200.7113) (xy 127.890524 -200.690988)
			(xy 127.887476 -200.68794) (xy 127.881888 -200.683114) (xy 127.875147 -200.678448) (xy 127.859601 -200.673268)
			(xy 127.851408 -200.672954) (xy 103.569516 -200.672954) (xy 103.565706 -200.673208) (xy 103.565198 -200.673208)
			(xy 103.556822 -200.674186) (xy 103.541376 -200.68093) (xy 103.534972 -200.686416) (xy 103.513724 -200.705311)
			(xy 103.466677 -200.737242) (xy 103.415409 -200.76183) (xy 103.361058 -200.778532) (xy 103.30483 -200.786977)
			(xy 103.24797 -200.786977) (xy 103.191742 -200.778532) (xy 103.137391 -200.76183) (xy 103.086123 -200.737242)
			(xy 103.039076 -200.705311) (xy 103.017828 -200.686416) (xy 103.011389 -200.680987) (xy 102.99596 -200.674261)
			(xy 102.987602 -200.673208) (xy 102.987094 -200.673208) (xy 102.983284 -200.672954) (xy 101.359716 -200.672954)
			(xy 101.355906 -200.673208) (xy 101.355398 -200.673208) (xy 101.347022 -200.674186) (xy 101.331576 -200.68093)
			(xy 101.325172 -200.686416) (xy 101.303924 -200.705311) (xy 101.256877 -200.737242) (xy 101.205609 -200.76183)
			(xy 101.151258 -200.778532) (xy 101.09503 -200.786977) (xy 101.03817 -200.786977) (xy 100.981942 -200.778532)
			(xy 100.927591 -200.76183) (xy 100.876323 -200.737242) (xy 100.829276 -200.705311) (xy 100.808028 -200.686416)
			(xy 100.801589 -200.680987) (xy 100.78616 -200.674261) (xy 100.777802 -200.673208) (xy 100.777294 -200.673208)
			(xy 100.773484 -200.672954) (xy 100.390452 -200.672954) (xy 100.381192 -200.673302) (xy 100.363857 -200.679805)
			(xy 100.35667 -200.685654) (xy 100.34996 -200.692144) (xy 100.341349 -200.70869) (xy 100.339906 -200.717912)
			(xy 100.336284 -200.745165) (xy 100.322218 -200.798311) (xy 100.300666 -200.848886) (xy 100.272073 -200.895842)
			(xy 100.237034 -200.938205) (xy 100.196274 -200.975096) (xy 100.150638 -201.005752) (xy 100.101073 -201.029536)
			(xy 100.074984 -201.038206) (xy 100.064062 -201.041762) (xy 100.056188 -201.048874) (xy 100.052172 -201.052729)
			(xy 100.045758 -201.061825) (xy 100.043488 -201.066908) (xy 100.013008 -201.138282) (xy 100.011051 -201.143454)
			(xy 100.009129 -201.154342) (xy 100.009198 -201.159872) (xy 100.009452 -201.170794) (xy 100.014532 -201.180954)
			(xy 100.027334 -201.207658) (xy 100.045442 -201.264039) (xy 100.054618 -201.322541) (xy 100.055172 -201.35215)
			(xy 100.054682 -201.379417) (xy 100.046915 -201.433396) (xy 100.031545 -201.48572) (xy 100.008886 -201.535325)
			(xy 99.979399 -201.5812) (xy 99.943684 -201.622412) (xy 99.902468 -201.658123) (xy 99.856589 -201.687605)
			(xy 99.806983 -201.710259) (xy 99.754657 -201.725623) (xy 99.700677 -201.733385) (xy 99.67341 -201.733912)
			(xy 98.80981 -201.733912) (xy 98.782539 -201.733426) (xy 98.728552 -201.725666) (xy 98.676218 -201.710302)
			(xy 98.626603 -201.687647) (xy 98.580718 -201.658162) (xy 98.539495 -201.622448) (xy 98.503774 -201.581231)
			(xy 98.474282 -201.535349) (xy 98.451619 -201.485738) (xy 98.436247 -201.433407) (xy 98.428478 -201.379421)
			(xy 98.428048 -201.35215) (xy 98.428553 -201.324192) (xy 98.436738 -201.268876) (xy 98.452896 -201.215344)
			(xy 98.46437 -201.189844) (xy 98.466678 -201.184551) (xy 98.469105 -201.173266) (xy 98.469196 -201.167492)
			(xy 98.469196 -201.156316) (xy 98.428556 -201.07402) (xy 98.42754 -201.072242) (xy 98.425508 -201.068432)
			(xy 98.423135 -201.065079) (xy 98.417519 -201.059085) (xy 98.414332 -201.056494) (xy 98.405442 -201.049636)
			(xy 98.393758 -201.04735) (xy 98.368037 -201.041384) (xy 98.318426 -201.02331) (xy 98.271784 -200.998564)
			(xy 98.229002 -200.967619) (xy 98.190899 -200.931068) (xy 98.158203 -200.889608) (xy 98.13154 -200.844035)
			(xy 98.11142 -200.795218) (xy 98.098228 -200.744092) (xy 98.0948 -200.717912) (xy 98.093323 -200.708699)
			(xy 98.084733 -200.692151) (xy 98.078036 -200.685654) (xy 98.070823 -200.679848) (xy 98.053505 -200.673336)
			(xy 98.044254 -200.672954) (xy 93.336618 -200.672954) (xy 93.328423 -200.67326) (xy 93.312871 -200.678433)
			(xy 93.306138 -200.683114) (xy 93.30055 -200.68794) (xy 92.00769 -201.9808) (xy 103.352092 -201.9808)
			(xy 103.352575 -201.951881) (xy 103.361307 -201.894707) (xy 103.378569 -201.839506) (xy 103.403967 -201.787544)
			(xy 103.436919 -201.740011) (xy 103.476668 -201.697997) (xy 103.499158 -201.67981) (xy 103.50654 -201.673523)
			(xy 103.516338 -201.656811) (xy 103.518208 -201.647298) (xy 103.518716 -201.639678) (xy 103.518716 -201.559922)
			(xy 103.518208 -201.552302) (xy 103.516362 -201.542782) (xy 103.506549 -201.52607) (xy 103.499158 -201.51979)
			(xy 103.476661 -201.501615) (xy 103.436929 -201.459591) (xy 103.403992 -201.412052) (xy 103.378607 -201.360088)
			(xy 103.361353 -201.304888) (xy 103.352626 -201.247717) (xy 103.352092 -201.2188) (xy 103.352578 -201.191549)
			(xy 103.360334 -201.137601) (xy 103.375689 -201.085306) (xy 103.398331 -201.035729) (xy 103.427797 -200.989879)
			(xy 103.463488 -200.948688) (xy 103.504679 -200.912997) (xy 103.550529 -200.883531) (xy 103.600106 -200.860889)
			(xy 103.652401 -200.845534) (xy 103.706349 -200.837778) (xy 103.760851 -200.837778) (xy 103.814799 -200.845534)
			(xy 103.867094 -200.860889) (xy 103.916671 -200.883531) (xy 103.962521 -200.912997) (xy 104.003712 -200.948688)
			(xy 104.039403 -200.989879) (xy 104.068869 -201.035729) (xy 104.091511 -201.085306) (xy 104.106866 -201.137601)
			(xy 104.114622 -201.191549) (xy 104.115108 -201.2188) (xy 104.114625 -201.247719) (xy 104.105893 -201.304893)
			(xy 104.088631 -201.360094) (xy 104.063233 -201.412056) (xy 104.030281 -201.459589) (xy 104.012015 -201.478896)
			(xy 128.984246 -201.478896) (xy 128.988317 -201.423274) (xy 129.000443 -201.368837) (xy 129.020366 -201.316746)
			(xy 129.047662 -201.268111) (xy 129.081748 -201.223968) (xy 129.121897 -201.185259) (xy 129.167255 -201.152808)
			(xy 129.216855 -201.127307) (xy 129.269639 -201.1093) (xy 129.324482 -201.09917) (xy 129.380216 -201.097133)
			(xy 129.435653 -201.103233) (xy 129.48961 -201.117339) (xy 129.540939 -201.139151) (xy 129.588545 -201.168205)
			(xy 129.631413 -201.20388) (xy 129.66863 -201.245417) (xy 129.699403 -201.29193) (xy 129.723075 -201.342427)
			(xy 129.739143 -201.395834) (xy 129.747263 -201.45101) (xy 129.747772 -201.478896) (xy 129.747263 -201.506782)
			(xy 129.739143 -201.561958) (xy 129.723075 -201.615365) (xy 129.699403 -201.665862) (xy 129.66863 -201.712375)
			(xy 129.631413 -201.753912) (xy 129.588545 -201.789587) (xy 129.540939 -201.818641) (xy 129.48961 -201.840453)
			(xy 129.435653 -201.854559) (xy 129.380216 -201.860659) (xy 129.324482 -201.858622) (xy 129.269639 -201.848492)
			(xy 129.216855 -201.830485) (xy 129.167255 -201.804984) (xy 129.121897 -201.772533) (xy 129.081748 -201.733824)
			(xy 129.047662 -201.689681) (xy 129.020366 -201.641046) (xy 129.000443 -201.588955) (xy 128.988317 -201.534518)
			(xy 128.984246 -201.478896) (xy 104.012015 -201.478896) (xy 103.990532 -201.501603) (xy 103.968042 -201.51979)
			(xy 103.96066 -201.526077) (xy 103.950862 -201.542789) (xy 103.948992 -201.552302) (xy 103.948484 -201.559922)
			(xy 103.948484 -201.639678) (xy 103.948992 -201.647298) (xy 103.950838 -201.656818) (xy 103.960651 -201.67353)
			(xy 103.968042 -201.67981) (xy 103.990539 -201.697985) (xy 104.030271 -201.740009) (xy 104.063208 -201.787548)
			(xy 104.088593 -201.839512) (xy 104.105847 -201.894712) (xy 104.114574 -201.951883) (xy 104.115108 -201.9808)
			(xy 104.114622 -202.008051) (xy 104.106866 -202.061999) (xy 104.100332 -202.084251) (xy 107.238778 -202.084251)
			(xy 107.238778 -202.029749) (xy 107.246534 -201.975801) (xy 107.261889 -201.923506) (xy 107.284531 -201.873929)
			(xy 107.313997 -201.828079) (xy 107.349688 -201.786888) (xy 107.390879 -201.751197) (xy 107.436729 -201.721731)
			(xy 107.486306 -201.699089) (xy 107.538601 -201.683734) (xy 107.592549 -201.675978) (xy 107.647051 -201.675978)
			(xy 107.700999 -201.683734) (xy 107.753294 -201.699089) (xy 107.802871 -201.721731) (xy 107.848721 -201.751197)
			(xy 107.889912 -201.786888) (xy 107.925603 -201.828079) (xy 107.955069 -201.873929) (xy 107.977711 -201.923506)
			(xy 107.993066 -201.975801) (xy 108.000822 -202.029749) (xy 108.001308 -202.057) (xy 108.000292 -202.08367)
			(xy 108.000292 -202.083924) (xy 107.999786 -202.098586) (xy 108.006225 -202.127196) (xy 108.02053 -202.152797)
			(xy 108.041521 -202.173277) (xy 108.067467 -202.186946) (xy 108.096228 -202.192678) (xy 108.125431 -202.19)
			(xy 108.13923 -202.185016) (xy 108.161697 -202.176484) (xy 108.208237 -202.164495) (xy 108.255916 -202.158455)
			(xy 108.279946 -202.158092) (xy 108.2802 -202.158092) (xy 108.307451 -202.158578) (xy 108.361399 -202.166334)
			(xy 108.413694 -202.181689) (xy 108.463271 -202.204331) (xy 108.509121 -202.233797) (xy 108.550312 -202.269488)
			(xy 108.586003 -202.310679) (xy 108.615469 -202.356529) (xy 108.638111 -202.406106) (xy 108.653466 -202.458401)
			(xy 108.661222 -202.512349) (xy 108.661222 -202.5396) (xy 108.990382 -202.5396) (xy 108.994453 -202.483978)
			(xy 109.006579 -202.429541) (xy 109.026502 -202.37745) (xy 109.053798 -202.328815) (xy 109.087884 -202.284672)
			(xy 109.128033 -202.245963) (xy 109.173391 -202.213512) (xy 109.222991 -202.188011) (xy 109.275775 -202.170004)
			(xy 109.330618 -202.159874) (xy 109.386352 -202.157837) (xy 109.441789 -202.163937) (xy 109.495746 -202.178043)
			(xy 109.547075 -202.199855) (xy 109.594681 -202.228909) (xy 109.637549 -202.264584) (xy 109.674766 -202.306121)
			(xy 109.705539 -202.352634) (xy 109.729211 -202.403131) (xy 109.745279 -202.456538) (xy 109.753399 -202.511714)
			(xy 109.753908 -202.5396) (xy 109.879382 -202.5396) (xy 109.883453 -202.483978) (xy 109.895579 -202.429541)
			(xy 109.915502 -202.37745) (xy 109.942798 -202.328815) (xy 109.976884 -202.284672) (xy 110.017033 -202.245963)
			(xy 110.062391 -202.213512) (xy 110.111991 -202.188011) (xy 110.164775 -202.170004) (xy 110.219618 -202.159874)
			(xy 110.275352 -202.157837) (xy 110.330789 -202.163937) (xy 110.364132 -202.172654) (xy 131.671247 -202.172654)
			(xy 131.671247 -202.118146) (xy 131.679005 -202.064193) (xy 131.694362 -202.011893) (xy 131.717006 -201.962311)
			(xy 131.746476 -201.916456) (xy 131.782172 -201.875262) (xy 131.823367 -201.839567) (xy 131.869223 -201.810099)
			(xy 131.918806 -201.787457) (xy 131.971106 -201.772102) (xy 132.02506 -201.764346) (xy 132.052314 -201.763884)
			(xy 132.081887 -201.764475) (xy 132.140317 -201.773664) (xy 132.168646 -201.782172) (xy 132.1689 -201.782172)
			(xy 132.175299 -201.783919) (xy 132.188548 -201.784438) (xy 132.195062 -201.783188) (xy 132.195316 -201.783188)
			(xy 132.200658 -201.781861) (xy 132.21065 -201.777246) (xy 132.215128 -201.774044) (xy 132.218938 -201.770742)
			(xy 132.283454 -201.71029) (xy 132.28838 -201.705474) (xy 132.29559 -201.693741) (xy 132.297678 -201.687176)
			(xy 132.297678 -201.686922) (xy 132.299335 -201.680499) (xy 132.299592 -201.667242) (xy 132.298186 -201.66076)
			(xy 132.298186 -201.660506) (xy 132.292843 -201.637702) (xy 132.287112 -201.591215) (xy 132.286756 -201.567796)
			(xy 132.28726 -201.540543) (xy 132.295017 -201.486592) (xy 132.310374 -201.434294) (xy 132.333018 -201.384714)
			(xy 132.362487 -201.338861) (xy 132.398182 -201.297669) (xy 132.439376 -201.261976) (xy 132.48523 -201.232509)
			(xy 132.534811 -201.209868) (xy 132.58711 -201.194513) (xy 132.641062 -201.186758) (xy 132.695568 -201.18676)
			(xy 132.749519 -201.19452) (xy 132.801816 -201.209878) (xy 132.851396 -201.232523) (xy 132.897248 -201.261993)
			(xy 132.938439 -201.297689) (xy 132.974131 -201.338884) (xy 133.003596 -201.384739) (xy 133.026236 -201.434321)
			(xy 133.041589 -201.48662) (xy 133.049342 -201.540572) (xy 133.049339 -201.595078) (xy 133.041578 -201.649029)
			(xy 133.026218 -201.701326) (xy 133.003572 -201.750905) (xy 132.9741 -201.796756) (xy 132.938403 -201.837946)
			(xy 132.897207 -201.873637) (xy 132.851351 -201.903101) (xy 132.829154 -201.913236) (xy 134.558532 -201.913236)
			(xy 134.559008 -201.886206) (xy 134.566653 -201.832688) (xy 134.581782 -201.780788) (xy 134.60409 -201.731544)
			(xy 134.63313 -201.685946) (xy 134.66832 -201.644907) (xy 134.688326 -201.626724) (xy 134.695692 -201.62012)
			(xy 134.70001 -201.61123) (xy 134.70203 -201.60702) (xy 134.704716 -201.598077) (xy 134.705344 -201.59345)
			(xy 134.711694 -201.523854) (xy 134.712076 -201.518987) (xy 134.711177 -201.509267) (xy 134.709916 -201.50455)
			(xy 134.707122 -201.495406) (xy 134.701026 -201.487532) (xy 134.685688 -201.467302) (xy 134.659944 -201.423546)
			(xy 134.640228 -201.376762) (xy 134.626889 -201.327778) (xy 134.620161 -201.277458) (xy 134.619746 -201.252074)
			(xy 134.620232 -201.224823) (xy 134.627988 -201.170875) (xy 134.643343 -201.11858) (xy 134.665985 -201.069003)
			(xy 134.695451 -201.023153) (xy 134.731142 -200.981962) (xy 134.772333 -200.946271) (xy 134.818183 -200.916805)
			(xy 134.86776 -200.894163) (xy 134.920055 -200.878808) (xy 134.974003 -200.871052) (xy 135.028505 -200.871052)
			(xy 135.082453 -200.878808) (xy 135.134748 -200.894163) (xy 135.184325 -200.916805) (xy 135.230175 -200.946271)
			(xy 135.271366 -200.981962) (xy 135.307057 -201.023153) (xy 135.336523 -201.069003) (xy 135.359165 -201.11858)
			(xy 135.37452 -201.170875) (xy 135.382276 -201.224823) (xy 135.382762 -201.252074) (xy 135.382295 -201.279105)
			(xy 135.374648 -201.332622) (xy 135.359518 -201.384523) (xy 135.337208 -201.433767) (xy 135.308167 -201.479365)
			(xy 135.272975 -201.520404) (xy 135.252968 -201.538586) (xy 135.245602 -201.54519) (xy 135.241284 -201.55408)
			(xy 135.239261 -201.558289) (xy 135.236577 -201.567232) (xy 135.23595 -201.57186) (xy 135.2296 -201.641456)
			(xy 135.229215 -201.646323) (xy 135.229352 -201.647806) (xy 136.924794 -201.647806) (xy 136.928865 -201.592184)
			(xy 136.940991 -201.537747) (xy 136.960914 -201.485656) (xy 136.98821 -201.437021) (xy 137.022296 -201.392878)
			(xy 137.062445 -201.354169) (xy 137.107803 -201.321718) (xy 137.157403 -201.296217) (xy 137.210187 -201.27821)
			(xy 137.26503 -201.26808) (xy 137.320764 -201.266043) (xy 137.376201 -201.272143) (xy 137.430158 -201.286249)
			(xy 137.481487 -201.308061) (xy 137.529093 -201.337115) (xy 137.571961 -201.37279) (xy 137.609178 -201.414327)
			(xy 137.639951 -201.46084) (xy 137.663623 -201.511337) (xy 137.679691 -201.564744) (xy 137.687811 -201.61992)
			(xy 137.688255 -201.64425) (xy 137.924792 -201.64425) (xy 137.928863 -201.588628) (xy 137.940989 -201.534191)
			(xy 137.960912 -201.4821) (xy 137.988208 -201.433465) (xy 138.022294 -201.389322) (xy 138.062443 -201.350613)
			(xy 138.107801 -201.318162) (xy 138.157401 -201.292661) (xy 138.210185 -201.274654) (xy 138.265028 -201.264524)
			(xy 138.320762 -201.262487) (xy 138.376199 -201.268587) (xy 138.430156 -201.282693) (xy 138.481485 -201.304505)
			(xy 138.529091 -201.333559) (xy 138.571959 -201.369234) (xy 138.609176 -201.410771) (xy 138.639949 -201.457284)
			(xy 138.663621 -201.507781) (xy 138.679689 -201.561188) (xy 138.686979 -201.610722) (xy 139.424662 -201.610722)
			(xy 139.428733 -201.5551) (xy 139.440859 -201.500663) (xy 139.460782 -201.448572) (xy 139.488078 -201.399937)
			(xy 139.522164 -201.355794) (xy 139.562313 -201.317085) (xy 139.607671 -201.284634) (xy 139.657271 -201.259133)
			(xy 139.710055 -201.241126) (xy 139.764898 -201.230996) (xy 139.820632 -201.228959) (xy 139.876069 -201.235059)
			(xy 139.930026 -201.249165) (xy 139.981355 -201.270977) (xy 140.028961 -201.300031) (xy 140.071829 -201.335706)
			(xy 140.109046 -201.377243) (xy 140.139819 -201.423756) (xy 140.163491 -201.474253) (xy 140.179559 -201.52766)
			(xy 140.187679 -201.582836) (xy 140.188188 -201.610722) (xy 140.187691 -201.637949) (xy 140.925751 -201.637949)
			(xy 140.925752 -201.583442) (xy 140.93351 -201.52949) (xy 140.948867 -201.477191) (xy 140.971511 -201.42761)
			(xy 141.000981 -201.381756) (xy 141.036676 -201.340563) (xy 141.077871 -201.30487) (xy 141.123726 -201.275402)
			(xy 141.173308 -201.252761) (xy 141.225607 -201.237406) (xy 141.27956 -201.22965) (xy 141.334067 -201.229652)
			(xy 141.388019 -201.237411) (xy 141.440317 -201.25277) (xy 141.489898 -201.275415) (xy 141.535751 -201.304886)
			(xy 141.576943 -201.340582) (xy 141.612635 -201.381778) (xy 141.642102 -201.427633) (xy 141.656347 -201.45883)
			(xy 148.477222 -201.45883) (xy 148.481293 -201.403208) (xy 148.493419 -201.348771) (xy 148.513342 -201.29668)
			(xy 148.540638 -201.248045) (xy 148.574724 -201.203902) (xy 148.614873 -201.165193) (xy 148.660231 -201.132742)
			(xy 148.709831 -201.107241) (xy 148.762615 -201.089234) (xy 148.817458 -201.079104) (xy 148.873192 -201.077067)
			(xy 148.928629 -201.083167) (xy 148.982586 -201.097273) (xy 149.033915 -201.119085) (xy 149.081521 -201.148139)
			(xy 149.124389 -201.183814) (xy 149.161606 -201.225351) (xy 149.192379 -201.271864) (xy 149.216051 -201.322361)
			(xy 149.232119 -201.375768) (xy 149.240239 -201.430944) (xy 149.240748 -201.45883) (xy 149.240239 -201.486716)
			(xy 149.232119 -201.541892) (xy 149.216051 -201.595299) (xy 149.192379 -201.645796) (xy 149.161606 -201.692309)
			(xy 149.124389 -201.733846) (xy 149.081521 -201.769521) (xy 149.033915 -201.798575) (xy 148.982586 -201.820387)
			(xy 148.928629 -201.834493) (xy 148.873192 -201.840593) (xy 148.817458 -201.838556) (xy 148.762615 -201.828426)
			(xy 148.709831 -201.810419) (xy 148.660231 -201.784918) (xy 148.614873 -201.752467) (xy 148.574724 -201.713758)
			(xy 148.540638 -201.669615) (xy 148.513342 -201.62098) (xy 148.493419 -201.568889) (xy 148.481293 -201.514452)
			(xy 148.477222 -201.45883) (xy 141.656347 -201.45883) (xy 141.664742 -201.477216) (xy 141.680096 -201.529516)
			(xy 141.68785 -201.583468) (xy 141.688312 -201.610722) (xy 141.68787 -201.636538) (xy 141.680915 -201.6877)
			(xy 141.667121 -201.737455) (xy 141.657324 -201.761344) (xy 141.651825 -201.775352) (xy 141.648462 -201.805244)
			(xy 141.653947 -201.83482) (xy 141.667804 -201.861518) (xy 141.688833 -201.883026) (xy 141.715213 -201.897481)
			(xy 141.744658 -201.90363) (xy 141.759686 -201.902822) (xy 141.793214 -201.901298) (xy 141.820464 -201.901793)
			(xy 141.874409 -201.909551) (xy 141.9267 -201.924907) (xy 141.976274 -201.947549) (xy 142.022122 -201.977015)
			(xy 142.063309 -202.012706) (xy 142.098998 -202.053895) (xy 142.128461 -202.099744) (xy 142.1511 -202.14932)
			(xy 142.166453 -202.201612) (xy 142.174208 -202.255557) (xy 142.174207 -202.310057) (xy 142.16645 -202.364002)
			(xy 142.151095 -202.416294) (xy 142.128454 -202.465869) (xy 142.098989 -202.511716) (xy 142.063299 -202.552904)
			(xy 142.02211 -202.588594) (xy 141.976262 -202.618058) (xy 141.926687 -202.640698) (xy 141.874394 -202.656052)
			(xy 141.820449 -202.663808) (xy 141.765949 -202.663808) (xy 141.712004 -202.656052) (xy 141.659712 -202.640697)
			(xy 141.610137 -202.618057) (xy 141.564289 -202.588593) (xy 141.523101 -202.552903) (xy 141.48741 -202.511715)
			(xy 141.457945 -202.465867) (xy 141.435305 -202.416293) (xy 141.41995 -202.364001) (xy 141.412193 -202.310056)
			(xy 141.411706 -202.282806) (xy 141.412123 -202.256989) (xy 141.419088 -202.205827) (xy 141.432892 -202.156072)
			(xy 141.442694 -202.132184) (xy 141.448142 -202.118158) (xy 141.451509 -202.088275) (xy 141.446031 -202.058706)
			(xy 141.432182 -202.032013) (xy 141.411163 -202.010507) (xy 141.384792 -201.996052) (xy 141.355356 -201.9899)
			(xy 141.340332 -201.990706) (xy 141.306804 -201.99223) (xy 141.27955 -201.991749) (xy 141.225598 -201.983992)
			(xy 141.173299 -201.968636) (xy 141.123717 -201.945993) (xy 141.077863 -201.916525) (xy 141.036669 -201.88083)
			(xy 141.000975 -201.839636) (xy 140.971506 -201.793782) (xy 140.948864 -201.7442) (xy 140.933508 -201.691901)
			(xy 140.925751 -201.637949) (xy 140.187691 -201.637949) (xy 140.187679 -201.638608) (xy 140.179559 -201.693784)
			(xy 140.163491 -201.747191) (xy 140.139819 -201.797688) (xy 140.109046 -201.844201) (xy 140.071829 -201.885738)
			(xy 140.028961 -201.921413) (xy 139.981355 -201.950467) (xy 139.930026 -201.972279) (xy 139.876069 -201.986385)
			(xy 139.820632 -201.992485) (xy 139.764898 -201.990448) (xy 139.710055 -201.980318) (xy 139.657271 -201.962311)
			(xy 139.607671 -201.93681) (xy 139.562313 -201.904359) (xy 139.522164 -201.86565) (xy 139.488078 -201.821507)
			(xy 139.460782 -201.772872) (xy 139.440859 -201.720781) (xy 139.428733 -201.666344) (xy 139.424662 -201.610722)
			(xy 138.686979 -201.610722) (xy 138.687809 -201.616364) (xy 138.688318 -201.64425) (xy 138.687809 -201.672136)
			(xy 138.679689 -201.727312) (xy 138.663621 -201.780719) (xy 138.639949 -201.831216) (xy 138.609176 -201.877729)
			(xy 138.571959 -201.919266) (xy 138.529091 -201.954941) (xy 138.481485 -201.983995) (xy 138.430156 -202.005807)
			(xy 138.376199 -202.019913) (xy 138.320762 -202.026013) (xy 138.265028 -202.023976) (xy 138.210185 -202.013846)
			(xy 138.157401 -201.995839) (xy 138.107801 -201.970338) (xy 138.062443 -201.937887) (xy 138.022294 -201.899178)
			(xy 137.988208 -201.855035) (xy 137.960912 -201.8064) (xy 137.940989 -201.754309) (xy 137.928863 -201.699872)
			(xy 137.924792 -201.64425) (xy 137.688255 -201.64425) (xy 137.68832 -201.647806) (xy 137.687811 -201.675692)
			(xy 137.679691 -201.730868) (xy 137.663623 -201.784275) (xy 137.639951 -201.834772) (xy 137.609178 -201.881285)
			(xy 137.571961 -201.922822) (xy 137.529093 -201.958497) (xy 137.481487 -201.987551) (xy 137.430158 -202.009363)
			(xy 137.376201 -202.023469) (xy 137.320764 -202.029569) (xy 137.26503 -202.027532) (xy 137.210187 -202.017402)
			(xy 137.157403 -201.999395) (xy 137.107803 -201.973894) (xy 137.062445 -201.941443) (xy 137.022296 -201.902734)
			(xy 136.98821 -201.858591) (xy 136.960914 -201.809956) (xy 136.940991 -201.757865) (xy 136.928865 -201.703428)
			(xy 136.924794 -201.647806) (xy 135.229352 -201.647806) (xy 135.230116 -201.656043) (xy 135.231378 -201.66076)
			(xy 135.234172 -201.669904) (xy 135.240268 -201.677778) (xy 135.25561 -201.698005) (xy 135.281353 -201.741762)
			(xy 135.301069 -201.788546) (xy 135.314407 -201.837531) (xy 135.321133 -201.887852) (xy 135.321548 -201.913236)
			(xy 135.321062 -201.940487) (xy 135.313306 -201.994435) (xy 135.297951 -202.04673) (xy 135.275309 -202.096307)
			(xy 135.245843 -202.142157) (xy 135.210152 -202.183348) (xy 135.168961 -202.219039) (xy 135.123111 -202.248505)
			(xy 135.073534 -202.271147) (xy 135.021239 -202.286502) (xy 134.967291 -202.294258) (xy 134.912789 -202.294258)
			(xy 134.858841 -202.286502) (xy 134.806546 -202.271147) (xy 134.756969 -202.248505) (xy 134.711119 -202.219039)
			(xy 134.669928 -202.183348) (xy 134.634237 -202.142157) (xy 134.604771 -202.096307) (xy 134.582129 -202.04673)
			(xy 134.566774 -201.994435) (xy 134.559018 -201.940487) (xy 134.558532 -201.913236) (xy 132.829154 -201.913236)
			(xy 132.801769 -201.92574) (xy 132.749469 -201.941091) (xy 132.695517 -201.948843) (xy 132.668264 -201.949304)
			(xy 132.638691 -201.948714) (xy 132.580261 -201.939524) (xy 132.551932 -201.931016) (xy 132.551678 -201.931016)
			(xy 132.545281 -201.929261) (xy 132.53203 -201.928748) (xy 132.525516 -201.93) (xy 132.525262 -201.93)
			(xy 132.519922 -201.931336) (xy 132.509928 -201.935944) (xy 132.50545 -201.939144) (xy 132.50164 -201.942446)
			(xy 132.437124 -202.002898) (xy 132.432198 -202.007714) (xy 132.424988 -202.019447) (xy 132.4229 -202.026012)
			(xy 132.4229 -202.026266) (xy 132.421248 -202.03269) (xy 132.420988 -202.045946) (xy 132.422392 -202.052428)
			(xy 132.422392 -202.052682) (xy 132.42544 -202.06589) (xy 132.42798 -202.078082) (xy 132.4356 -202.08748)
			(xy 132.439476 -202.091881) (xy 132.448847 -202.098929) (xy 132.454142 -202.10145) (xy 132.540756 -202.140312)
			(xy 132.552694 -202.139804) (xy 132.558574 -202.139243) (xy 132.569862 -202.135776) (xy 132.575046 -202.132946)
			(xy 132.5753 -202.132946) (xy 132.597037 -202.120932) (xy 132.642964 -202.102025) (xy 132.690958 -202.089241)
			(xy 132.740205 -202.082797) (xy 132.765038 -202.0824) (xy 132.792288 -202.082872) (xy 132.846233 -202.090633)
			(xy 132.898524 -202.105992) (xy 132.948098 -202.128636) (xy 132.993944 -202.158104) (xy 133.035131 -202.193796)
			(xy 133.070819 -202.234986) (xy 133.100282 -202.280836) (xy 133.122921 -202.330412) (xy 133.138275 -202.382704)
			(xy 133.14603 -202.43665) (xy 133.14603 -202.49115) (xy 133.138275 -202.545096) (xy 133.122921 -202.597388)
			(xy 133.100282 -202.646964) (xy 133.070819 -202.692814) (xy 133.064922 -202.69962) (xy 149.057612 -202.69962)
			(xy 149.061683 -202.643998) (xy 149.073809 -202.589561) (xy 149.093732 -202.53747) (xy 149.121028 -202.488835)
			(xy 149.155114 -202.444692) (xy 149.195263 -202.405983) (xy 149.240621 -202.373532) (xy 149.290221 -202.348031)
			(xy 149.343005 -202.330024) (xy 149.397848 -202.319894) (xy 149.453582 -202.317857) (xy 149.509019 -202.323957)
			(xy 149.562976 -202.338063) (xy 149.614305 -202.359875) (xy 149.661911 -202.388929) (xy 149.704779 -202.424604)
			(xy 149.741996 -202.466141) (xy 149.772769 -202.512654) (xy 149.796441 -202.563151) (xy 149.812509 -202.616558)
			(xy 149.820629 -202.671734) (xy 149.821138 -202.69962) (xy 149.820629 -202.727506) (xy 149.812509 -202.782682)
			(xy 149.796441 -202.836089) (xy 149.772769 -202.886586) (xy 149.741996 -202.933099) (xy 149.704779 -202.974636)
			(xy 149.661911 -203.010311) (xy 149.614305 -203.039365) (xy 149.562976 -203.061177) (xy 149.509019 -203.075283)
			(xy 149.453582 -203.081383) (xy 149.397848 -203.079346) (xy 149.343005 -203.069216) (xy 149.290221 -203.051209)
			(xy 149.240621 -203.025708) (xy 149.195263 -202.993257) (xy 149.155114 -202.954548) (xy 149.121028 -202.910405)
			(xy 149.093732 -202.86177) (xy 149.073809 -202.809679) (xy 149.061683 -202.755242) (xy 149.057612 -202.69962)
			(xy 133.064922 -202.69962) (xy 133.035131 -202.734004) (xy 132.993944 -202.769696) (xy 132.948098 -202.799164)
			(xy 132.898524 -202.821808) (xy 132.846233 -202.837167) (xy 132.792288 -202.844928) (xy 132.765038 -202.845416)
			(xy 132.736182 -202.844839) (xy 132.679126 -202.836151) (xy 132.624031 -202.818968) (xy 132.572153 -202.793681)
			(xy 132.524676 -202.760867) (xy 132.482684 -202.721277) (xy 132.447135 -202.675812) (xy 132.41884 -202.625511)
			(xy 132.398445 -202.571522) (xy 132.391912 -202.54341) (xy 132.389372 -202.531218) (xy 132.381752 -202.52182)
			(xy 132.377866 -202.517429) (xy 132.368502 -202.510375) (xy 132.36321 -202.50785) (xy 132.276596 -202.468988)
			(xy 132.264658 -202.469496) (xy 132.258781 -202.470074) (xy 132.247492 -202.473529) (xy 132.242306 -202.476354)
			(xy 132.242052 -202.476354) (xy 132.220304 -202.488348) (xy 132.174381 -202.50726) (xy 132.126391 -202.520049)
			(xy 132.077146 -202.526499) (xy 132.052314 -202.5269) (xy 132.02506 -202.526454) (xy 131.971106 -202.518698)
			(xy 131.918806 -202.503343) (xy 131.869223 -202.480701) (xy 131.823367 -202.451233) (xy 131.782172 -202.415538)
			(xy 131.746476 -202.374344) (xy 131.717006 -202.328489) (xy 131.694362 -202.278907) (xy 131.679005 -202.226607)
			(xy 131.671247 -202.172654) (xy 110.364132 -202.172654) (xy 110.384746 -202.178043) (xy 110.436075 -202.199855)
			(xy 110.483681 -202.228909) (xy 110.526549 -202.264584) (xy 110.563766 -202.306121) (xy 110.594539 -202.352634)
			(xy 110.618211 -202.403131) (xy 110.634279 -202.456538) (xy 110.642399 -202.511714) (xy 110.642908 -202.5396)
			(xy 110.642399 -202.567486) (xy 110.634279 -202.622662) (xy 110.618211 -202.676069) (xy 110.594539 -202.726566)
			(xy 110.563766 -202.773079) (xy 110.526549 -202.814616) (xy 110.483681 -202.850291) (xy 110.436075 -202.879345)
			(xy 110.384746 -202.901157) (xy 110.330789 -202.915263) (xy 110.275352 -202.921363) (xy 110.219618 -202.919326)
			(xy 110.164775 -202.909196) (xy 110.111991 -202.891189) (xy 110.062391 -202.865688) (xy 110.017033 -202.833237)
			(xy 109.976884 -202.794528) (xy 109.942798 -202.750385) (xy 109.915502 -202.70175) (xy 109.895579 -202.649659)
			(xy 109.883453 -202.595222) (xy 109.879382 -202.5396) (xy 109.753908 -202.5396) (xy 109.753399 -202.567486)
			(xy 109.745279 -202.622662) (xy 109.729211 -202.676069) (xy 109.705539 -202.726566) (xy 109.674766 -202.773079)
			(xy 109.637549 -202.814616) (xy 109.594681 -202.850291) (xy 109.547075 -202.879345) (xy 109.495746 -202.901157)
			(xy 109.441789 -202.915263) (xy 109.386352 -202.921363) (xy 109.330618 -202.919326) (xy 109.275775 -202.909196)
			(xy 109.222991 -202.891189) (xy 109.173391 -202.865688) (xy 109.128033 -202.833237) (xy 109.087884 -202.794528)
			(xy 109.053798 -202.750385) (xy 109.026502 -202.70175) (xy 109.006579 -202.649659) (xy 108.994453 -202.595222)
			(xy 108.990382 -202.5396) (xy 108.661222 -202.5396) (xy 108.661222 -202.566851) (xy 108.653466 -202.620799)
			(xy 108.638111 -202.673094) (xy 108.615469 -202.722671) (xy 108.586003 -202.768521) (xy 108.550312 -202.809712)
			(xy 108.509121 -202.845403) (xy 108.463271 -202.874869) (xy 108.413694 -202.897511) (xy 108.361399 -202.912866)
			(xy 108.307451 -202.920622) (xy 108.252949 -202.920622) (xy 108.199001 -202.912866) (xy 108.146706 -202.897511)
			(xy 108.097129 -202.874869) (xy 108.051279 -202.845403) (xy 108.010088 -202.809712) (xy 107.974397 -202.768521)
			(xy 107.944931 -202.722671) (xy 107.922289 -202.673094) (xy 107.906934 -202.620799) (xy 107.899178 -202.566851)
			(xy 107.898692 -202.5396) (xy 107.899708 -202.51293) (xy 107.899708 -202.512676) (xy 107.900214 -202.498014)
			(xy 107.893775 -202.469404) (xy 107.87947 -202.443803) (xy 107.858479 -202.423323) (xy 107.832533 -202.409654)
			(xy 107.803772 -202.403922) (xy 107.774569 -202.4066) (xy 107.76077 -202.411584) (xy 107.738303 -202.420116)
			(xy 107.691763 -202.432105) (xy 107.644084 -202.438145) (xy 107.620054 -202.438508) (xy 107.6198 -202.438508)
			(xy 107.592549 -202.438022) (xy 107.538601 -202.430266) (xy 107.486306 -202.414911) (xy 107.436729 -202.392269)
			(xy 107.390879 -202.362803) (xy 107.349688 -202.327112) (xy 107.313997 -202.285921) (xy 107.284531 -202.240071)
			(xy 107.261889 -202.190494) (xy 107.246534 -202.138199) (xy 107.238778 -202.084251) (xy 104.100332 -202.084251)
			(xy 104.091511 -202.114294) (xy 104.068869 -202.163871) (xy 104.039403 -202.209721) (xy 104.003712 -202.250912)
			(xy 103.962521 -202.286603) (xy 103.916671 -202.316069) (xy 103.867094 -202.338711) (xy 103.814799 -202.354066)
			(xy 103.760851 -202.361822) (xy 103.706349 -202.361822) (xy 103.652401 -202.354066) (xy 103.600106 -202.338711)
			(xy 103.550529 -202.316069) (xy 103.504679 -202.286603) (xy 103.463488 -202.250912) (xy 103.427797 -202.209721)
			(xy 103.398331 -202.163871) (xy 103.375689 -202.114294) (xy 103.360334 -202.061999) (xy 103.352578 -202.008051)
			(xy 103.352092 -201.9808) (xy 92.00769 -201.9808) (xy 91.35237 -202.63612) (xy 91.347544 -202.641708)
			(xy 91.342875 -202.648448) (xy 91.337691 -202.663994) (xy 91.337384 -202.672188) (xy 91.337384 -203.073)
			(xy 118.820182 -203.073) (xy 118.824253 -203.017378) (xy 118.836379 -202.962941) (xy 118.856302 -202.91085)
			(xy 118.883598 -202.862215) (xy 118.917684 -202.818072) (xy 118.957833 -202.779363) (xy 119.003191 -202.746912)
			(xy 119.052791 -202.721411) (xy 119.105575 -202.703404) (xy 119.160418 -202.693274) (xy 119.216152 -202.691237)
			(xy 119.271589 -202.697337) (xy 119.325546 -202.711443) (xy 119.376875 -202.733255) (xy 119.424481 -202.762309)
			(xy 119.467349 -202.797984) (xy 119.504566 -202.839521) (xy 119.535339 -202.886034) (xy 119.559011 -202.936531)
			(xy 119.575079 -202.989938) (xy 119.583199 -203.045114) (xy 119.583708 -203.073) (xy 119.583199 -203.100886)
			(xy 119.575079 -203.156062) (xy 119.559011 -203.209469) (xy 119.535339 -203.259966) (xy 119.504566 -203.306479)
			(xy 119.467349 -203.348016) (xy 119.424481 -203.383691) (xy 119.379613 -203.411074) (xy 147.827236 -203.411074)
			(xy 147.831307 -203.355452) (xy 147.843433 -203.301015) (xy 147.863356 -203.248924) (xy 147.890652 -203.200289)
			(xy 147.924738 -203.156146) (xy 147.964887 -203.117437) (xy 148.010245 -203.084986) (xy 148.059845 -203.059485)
			(xy 148.112629 -203.041478) (xy 148.167472 -203.031348) (xy 148.223206 -203.029311) (xy 148.278643 -203.035411)
			(xy 148.3326 -203.049517) (xy 148.383929 -203.071329) (xy 148.431535 -203.100383) (xy 148.474403 -203.136058)
			(xy 148.51162 -203.177595) (xy 148.542393 -203.224108) (xy 148.566065 -203.274605) (xy 148.582133 -203.328012)
			(xy 148.590253 -203.383188) (xy 148.590762 -203.411074) (xy 148.590253 -203.43896) (xy 148.582133 -203.494136)
			(xy 148.566065 -203.547543) (xy 148.548 -203.58608) (xy 149.029166 -203.58608) (xy 149.029652 -203.558829)
			(xy 149.037408 -203.504881) (xy 149.052763 -203.452586) (xy 149.075405 -203.403009) (xy 149.104871 -203.357159)
			(xy 149.140562 -203.315968) (xy 149.181753 -203.280277) (xy 149.227603 -203.250811) (xy 149.27718 -203.228169)
			(xy 149.329475 -203.212814) (xy 149.383423 -203.205058) (xy 149.437925 -203.205058) (xy 149.491873 -203.212814)
			(xy 149.544168 -203.228169) (xy 149.593745 -203.250811) (xy 149.639595 -203.280277) (xy 149.680786 -203.315968)
			(xy 149.716477 -203.357159) (xy 149.745943 -203.403009) (xy 149.768585 -203.452586) (xy 149.78394 -203.504881)
			(xy 149.791696 -203.558829) (xy 149.792182 -203.58608) (xy 149.791618 -203.615691) (xy 149.78245 -203.674198)
			(xy 149.764363 -203.73059) (xy 149.73779 -203.783515) (xy 149.703367 -203.831705) (xy 149.661919 -203.874005)
			(xy 149.638512 -203.89215) (xy 149.633432 -203.89596) (xy 149.625812 -203.905104) (xy 149.623272 -203.910438)
			(xy 149.620831 -203.91583) (xy 149.618261 -203.92738) (xy 149.618192 -203.933298) (xy 149.619208 -204.021944)
			(xy 149.622002 -204.033374) (xy 149.624796 -204.038708) (xy 149.627823 -204.043997) (xy 149.635903 -204.053113)
			(xy 149.640798 -204.056742) (xy 149.641052 -204.056742) (xy 149.662101 -204.07215) (xy 149.700216 -204.107764)
			(xy 149.733127 -204.148235) (xy 149.760222 -204.192811) (xy 149.780995 -204.24066) (xy 149.79506 -204.290893)
			(xy 149.802155 -204.342572) (xy 149.802596 -204.368654) (xy 149.80211 -204.395581) (xy 149.794531 -204.448898)
			(xy 149.77953 -204.50062) (xy 149.757406 -204.549719) (xy 149.728599 -204.595219) (xy 149.69368 -204.636217)
			(xy 149.673818 -204.654404) (xy 149.665182 -204.662024) (xy 149.660864 -204.67193) (xy 149.658774 -204.677203)
			(xy 149.656727 -204.688356) (xy 149.6568 -204.694028) (xy 149.660102 -204.784198) (xy 149.664928 -204.793596)
			(xy 149.667624 -204.798665) (xy 149.674941 -204.807511) (xy 149.679406 -204.811122) (xy 149.67966 -204.811122)
			(xy 149.702492 -204.829315) (xy 149.742898 -204.871448) (xy 149.776414 -204.919245) (xy 149.802259 -204.971589)
			(xy 149.819829 -205.027259) (xy 149.828714 -205.084956) (xy 149.829266 -205.114144) (xy 149.82878 -205.141395)
			(xy 149.821024 -205.195343) (xy 149.805669 -205.247638) (xy 149.783027 -205.297215) (xy 149.753561 -205.343065)
			(xy 149.71787 -205.384256) (xy 149.676679 -205.419947) (xy 149.630829 -205.449413) (xy 149.581252 -205.472055)
			(xy 149.528957 -205.48741) (xy 149.475009 -205.495166) (xy 149.420507 -205.495166) (xy 149.366559 -205.48741)
			(xy 149.314264 -205.472055) (xy 149.264687 -205.449413) (xy 149.218837 -205.419947) (xy 149.177646 -205.384256)
			(xy 149.141955 -205.343065) (xy 149.112489 -205.297215) (xy 149.089847 -205.247638) (xy 149.074492 -205.195343)
			(xy 149.066736 -205.141395) (xy 149.06625 -205.114144) (xy 149.066752 -205.087218) (xy 149.074331 -205.033903)
			(xy 149.089329 -204.982182) (xy 149.11145 -204.933083) (xy 149.140254 -204.887582) (xy 149.175169 -204.846582)
			(xy 149.195028 -204.828394) (xy 149.203664 -204.820774) (xy 149.207982 -204.810868) (xy 149.210075 -204.805596)
			(xy 149.21212 -204.794442) (xy 149.212046 -204.78877) (xy 149.208744 -204.6986) (xy 149.203918 -204.689202)
			(xy 149.201211 -204.684139) (xy 149.193902 -204.675288) (xy 149.18944 -204.671676) (xy 149.189186 -204.671676)
			(xy 149.166342 -204.653498) (xy 149.125939 -204.61136) (xy 149.092426 -204.56356) (xy 149.066584 -204.511213)
			(xy 149.049015 -204.455541) (xy 149.040131 -204.397843) (xy 149.03958 -204.368654) (xy 149.040144 -204.339043)
			(xy 149.049308 -204.280534) (xy 149.067393 -204.224141) (xy 149.093967 -204.171215) (xy 149.128391 -204.123026)
			(xy 149.169842 -204.080727) (xy 149.19325 -204.062584) (xy 149.19833 -204.058774) (xy 149.20595 -204.04963)
			(xy 149.20849 -204.044296) (xy 149.210923 -204.038901) (xy 149.213497 -204.027353) (xy 149.21357 -204.021436)
			(xy 149.212554 -203.93279) (xy 149.20976 -203.92136) (xy 149.206966 -203.916026) (xy 149.203961 -203.910723)
			(xy 149.195866 -203.901615) (xy 149.190964 -203.897992) (xy 149.19071 -203.897992) (xy 149.169668 -203.882574)
			(xy 149.131555 -203.846961) (xy 149.098644 -203.806491) (xy 149.07155 -203.761917) (xy 149.050775 -203.714069)
			(xy 149.036708 -203.663839) (xy 149.029609 -203.612161) (xy 149.029166 -203.58608) (xy 148.548 -203.58608)
			(xy 148.542393 -203.59804) (xy 148.51162 -203.644553) (xy 148.474403 -203.68609) (xy 148.431535 -203.721765)
			(xy 148.383929 -203.750819) (xy 148.3326 -203.772631) (xy 148.278643 -203.786737) (xy 148.223206 -203.792837)
			(xy 148.167472 -203.7908) (xy 148.112629 -203.78067) (xy 148.059845 -203.762663) (xy 148.010245 -203.737162)
			(xy 147.964887 -203.704711) (xy 147.924738 -203.666002) (xy 147.890652 -203.621859) (xy 147.863356 -203.573224)
			(xy 147.843433 -203.521133) (xy 147.831307 -203.466696) (xy 147.827236 -203.411074) (xy 119.379613 -203.411074)
			(xy 119.376875 -203.412745) (xy 119.325546 -203.434557) (xy 119.271589 -203.448663) (xy 119.216152 -203.454763)
			(xy 119.160418 -203.452726) (xy 119.105575 -203.442596) (xy 119.052791 -203.424589) (xy 119.003191 -203.399088)
			(xy 118.957833 -203.366637) (xy 118.917684 -203.327928) (xy 118.883598 -203.283785) (xy 118.856302 -203.23515)
			(xy 118.836379 -203.183059) (xy 118.824253 -203.128622) (xy 118.820182 -203.073) (xy 91.337384 -203.073)
			(xy 91.337384 -204.216) (xy 96.999296 -204.216) (xy 97.003367 -204.160378) (xy 97.015493 -204.105941)
			(xy 97.035416 -204.05385) (xy 97.062712 -204.005215) (xy 97.096798 -203.961072) (xy 97.136947 -203.922363)
			(xy 97.182305 -203.889912) (xy 97.231905 -203.864411) (xy 97.284689 -203.846404) (xy 97.339532 -203.836274)
			(xy 97.395266 -203.834237) (xy 97.450703 -203.840337) (xy 97.50466 -203.854443) (xy 97.555989 -203.876255)
			(xy 97.603595 -203.905309) (xy 97.646463 -203.940984) (xy 97.68368 -203.982521) (xy 97.714453 -204.029034)
			(xy 97.738125 -204.079531) (xy 97.754193 -204.132938) (xy 97.762313 -204.188114) (xy 97.762822 -204.216)
			(xy 97.762313 -204.243886) (xy 97.754193 -204.299062) (xy 97.741203 -204.342238) (xy 123.124466 -204.342238)
			(xy 123.128537 -204.286616) (xy 123.140663 -204.232179) (xy 123.160586 -204.180088) (xy 123.187882 -204.131453)
			(xy 123.221968 -204.08731) (xy 123.262117 -204.048601) (xy 123.307475 -204.01615) (xy 123.357075 -203.990649)
			(xy 123.409859 -203.972642) (xy 123.464702 -203.962512) (xy 123.520436 -203.960475) (xy 123.575873 -203.966575)
			(xy 123.62983 -203.980681) (xy 123.681159 -204.002493) (xy 123.728765 -204.031547) (xy 123.771633 -204.067222)
			(xy 123.80885 -204.108759) (xy 123.839623 -204.155272) (xy 123.863295 -204.205769) (xy 123.879363 -204.259176)
			(xy 123.887483 -204.314352) (xy 123.887992 -204.342238) (xy 123.887483 -204.370124) (xy 123.879363 -204.4253)
			(xy 123.863295 -204.478707) (xy 123.849635 -204.507846) (xy 131.886196 -204.507846) (xy 131.890267 -204.452224)
			(xy 131.902393 -204.397787) (xy 131.922316 -204.345696) (xy 131.949612 -204.297061) (xy 131.983698 -204.252918)
			(xy 132.023847 -204.214209) (xy 132.069205 -204.181758) (xy 132.118805 -204.156257) (xy 132.171589 -204.13825)
			(xy 132.226432 -204.12812) (xy 132.282166 -204.126083) (xy 132.337603 -204.132183) (xy 132.39156 -204.146289)
			(xy 132.442889 -204.168101) (xy 132.490495 -204.197155) (xy 132.533363 -204.23283) (xy 132.552193 -204.253846)
			(xy 138.236196 -204.253846) (xy 138.240267 -204.198224) (xy 138.252393 -204.143787) (xy 138.272316 -204.091696)
			(xy 138.299612 -204.043061) (xy 138.333698 -203.998918) (xy 138.373847 -203.960209) (xy 138.419205 -203.927758)
			(xy 138.468805 -203.902257) (xy 138.521589 -203.88425) (xy 138.576432 -203.87412) (xy 138.632166 -203.872083)
			(xy 138.687603 -203.878183) (xy 138.74156 -203.892289) (xy 138.792889 -203.914101) (xy 138.840495 -203.943155)
			(xy 138.883363 -203.97883) (xy 138.92058 -204.020367) (xy 138.951353 -204.06688) (xy 138.974344 -204.115924)
			(xy 142.127476 -204.115924) (xy 142.131547 -204.060302) (xy 142.143673 -204.005865) (xy 142.163596 -203.953774)
			(xy 142.190892 -203.905139) (xy 142.224978 -203.860996) (xy 142.265127 -203.822287) (xy 142.310485 -203.789836)
			(xy 142.360085 -203.764335) (xy 142.412869 -203.746328) (xy 142.467712 -203.736198) (xy 142.523446 -203.734161)
			(xy 142.578883 -203.740261) (xy 142.63284 -203.754367) (xy 142.684169 -203.776179) (xy 142.731775 -203.805233)
			(xy 142.774643 -203.840908) (xy 142.81186 -203.882445) (xy 142.842633 -203.928958) (xy 142.866305 -203.979455)
			(xy 142.882373 -204.032862) (xy 142.890493 -204.088038) (xy 142.891002 -204.115924) (xy 142.890493 -204.14381)
			(xy 142.882373 -204.198986) (xy 142.866305 -204.252393) (xy 142.842633 -204.30289) (xy 142.81186 -204.349403)
			(xy 142.774643 -204.39094) (xy 142.731775 -204.426615) (xy 142.684169 -204.455669) (xy 142.63284 -204.477481)
			(xy 142.578883 -204.491587) (xy 142.523446 -204.497687) (xy 142.467712 -204.49565) (xy 142.412869 -204.48552)
			(xy 142.360085 -204.467513) (xy 142.310485 -204.442012) (xy 142.265127 -204.409561) (xy 142.224978 -204.370852)
			(xy 142.190892 -204.326709) (xy 142.163596 -204.278074) (xy 142.143673 -204.225983) (xy 142.131547 -204.171546)
			(xy 142.127476 -204.115924) (xy 138.974344 -204.115924) (xy 138.975025 -204.117377) (xy 138.991093 -204.170784)
			(xy 138.999213 -204.22596) (xy 138.999722 -204.253846) (xy 138.999213 -204.281732) (xy 138.991093 -204.336908)
			(xy 138.975025 -204.390315) (xy 138.951353 -204.440812) (xy 138.92058 -204.487325) (xy 138.883363 -204.528862)
			(xy 138.840495 -204.564537) (xy 138.792889 -204.593591) (xy 138.74156 -204.615403) (xy 138.687603 -204.629509)
			(xy 138.632166 -204.635609) (xy 138.576432 -204.633572) (xy 138.521589 -204.623442) (xy 138.468805 -204.605435)
			(xy 138.419205 -204.579934) (xy 138.373847 -204.547483) (xy 138.333698 -204.508774) (xy 138.299612 -204.464631)
			(xy 138.272316 -204.415996) (xy 138.252393 -204.363905) (xy 138.240267 -204.309468) (xy 138.236196 -204.253846)
			(xy 132.552193 -204.253846) (xy 132.57058 -204.274367) (xy 132.601353 -204.32088) (xy 132.625025 -204.371377)
			(xy 132.641093 -204.424784) (xy 132.649213 -204.47996) (xy 132.649722 -204.507846) (xy 132.649213 -204.535732)
			(xy 132.641093 -204.590908) (xy 132.625025 -204.644315) (xy 132.601353 -204.694812) (xy 132.57058 -204.741325)
			(xy 132.535125 -204.780896) (xy 143.716246 -204.780896) (xy 143.720317 -204.725274) (xy 143.732443 -204.670837)
			(xy 143.752366 -204.618746) (xy 143.779662 -204.570111) (xy 143.813748 -204.525968) (xy 143.853897 -204.487259)
			(xy 143.899255 -204.454808) (xy 143.948855 -204.429307) (xy 144.001639 -204.4113) (xy 144.056482 -204.40117)
			(xy 144.112216 -204.399133) (xy 144.167653 -204.405233) (xy 144.22161 -204.419339) (xy 144.272939 -204.441151)
			(xy 144.320545 -204.470205) (xy 144.363413 -204.50588) (xy 144.40063 -204.547417) (xy 144.431403 -204.59393)
			(xy 144.455075 -204.644427) (xy 144.471143 -204.697834) (xy 144.479263 -204.75301) (xy 144.479772 -204.780896)
			(xy 144.479263 -204.808782) (xy 144.471143 -204.863958) (xy 144.455075 -204.917365) (xy 144.431403 -204.967862)
			(xy 144.40063 -205.014375) (xy 144.363413 -205.055912) (xy 144.320545 -205.091587) (xy 144.272939 -205.120641)
			(xy 144.22161 -205.142453) (xy 144.167653 -205.156559) (xy 144.112216 -205.162659) (xy 144.056482 -205.160622)
			(xy 144.001639 -205.150492) (xy 143.948855 -205.132485) (xy 143.899255 -205.106984) (xy 143.853897 -205.074533)
			(xy 143.813748 -205.035824) (xy 143.779662 -204.991681) (xy 143.752366 -204.943046) (xy 143.732443 -204.890955)
			(xy 143.720317 -204.836518) (xy 143.716246 -204.780896) (xy 132.535125 -204.780896) (xy 132.533363 -204.782862)
			(xy 132.490495 -204.818537) (xy 132.442889 -204.847591) (xy 132.39156 -204.869403) (xy 132.337603 -204.883509)
			(xy 132.282166 -204.889609) (xy 132.226432 -204.887572) (xy 132.171589 -204.877442) (xy 132.118805 -204.859435)
			(xy 132.069205 -204.833934) (xy 132.023847 -204.801483) (xy 131.983698 -204.762774) (xy 131.949612 -204.718631)
			(xy 131.922316 -204.669996) (xy 131.902393 -204.617905) (xy 131.890267 -204.563468) (xy 131.886196 -204.507846)
			(xy 123.849635 -204.507846) (xy 123.839623 -204.529204) (xy 123.80885 -204.575717) (xy 123.771633 -204.617254)
			(xy 123.728765 -204.652929) (xy 123.681159 -204.681983) (xy 123.62983 -204.703795) (xy 123.575873 -204.717901)
			(xy 123.520436 -204.724001) (xy 123.464702 -204.721964) (xy 123.409859 -204.711834) (xy 123.357075 -204.693827)
			(xy 123.307475 -204.668326) (xy 123.262117 -204.635875) (xy 123.221968 -204.597166) (xy 123.187882 -204.553023)
			(xy 123.160586 -204.504388) (xy 123.140663 -204.452297) (xy 123.128537 -204.39786) (xy 123.124466 -204.342238)
			(xy 97.741203 -204.342238) (xy 97.738125 -204.352469) (xy 97.714453 -204.402966) (xy 97.68368 -204.449479)
			(xy 97.646463 -204.491016) (xy 97.603595 -204.526691) (xy 97.555989 -204.555745) (xy 97.50466 -204.577557)
			(xy 97.450703 -204.591663) (xy 97.395266 -204.597763) (xy 97.339532 -204.595726) (xy 97.284689 -204.585596)
			(xy 97.231905 -204.567589) (xy 97.182305 -204.542088) (xy 97.136947 -204.509637) (xy 97.096798 -204.470928)
			(xy 97.062712 -204.426785) (xy 97.035416 -204.37815) (xy 97.015493 -204.326059) (xy 97.003367 -204.271622)
			(xy 96.999296 -204.216) (xy 91.337384 -204.216) (xy 91.337384 -205.016608) (xy 116.266212 -205.016608)
			(xy 116.270283 -204.960986) (xy 116.282409 -204.906549) (xy 116.302332 -204.854458) (xy 116.329628 -204.805823)
			(xy 116.363714 -204.76168) (xy 116.403863 -204.722971) (xy 116.449221 -204.69052) (xy 116.498821 -204.665019)
			(xy 116.551605 -204.647012) (xy 116.606448 -204.636882) (xy 116.662182 -204.634845) (xy 116.717619 -204.640945)
			(xy 116.771576 -204.655051) (xy 116.822905 -204.676863) (xy 116.870511 -204.705917) (xy 116.913379 -204.741592)
			(xy 116.950596 -204.783129) (xy 116.981369 -204.829642) (xy 117.005041 -204.880139) (xy 117.021109 -204.933546)
			(xy 117.029229 -204.988722) (xy 117.029738 -205.016608) (xy 117.029229 -205.044494) (xy 117.021109 -205.09967)
			(xy 117.005041 -205.153077) (xy 116.981369 -205.203574) (xy 116.950596 -205.250087) (xy 116.913379 -205.291624)
			(xy 116.870511 -205.327299) (xy 116.822905 -205.356353) (xy 116.771576 -205.378165) (xy 116.717619 -205.392271)
			(xy 116.662182 -205.398371) (xy 116.606448 -205.396334) (xy 116.551605 -205.386204) (xy 116.498821 -205.368197)
			(xy 116.449221 -205.342696) (xy 116.403863 -205.310245) (xy 116.363714 -205.271536) (xy 116.329628 -205.227393)
			(xy 116.302332 -205.178758) (xy 116.282409 -205.126667) (xy 116.270283 -205.07223) (xy 116.266212 -205.016608)
			(xy 91.337384 -205.016608) (xy 91.337384 -205.687168) (xy 117.02745 -205.687168) (xy 117.031521 -205.631546)
			(xy 117.043647 -205.577109) (xy 117.06357 -205.525018) (xy 117.090866 -205.476383) (xy 117.124952 -205.43224)
			(xy 117.165101 -205.393531) (xy 117.210459 -205.36108) (xy 117.260059 -205.335579) (xy 117.312843 -205.317572)
			(xy 117.367686 -205.307442) (xy 117.42342 -205.305405) (xy 117.478857 -205.311505) (xy 117.532814 -205.325611)
			(xy 117.584143 -205.347423) (xy 117.631749 -205.376477) (xy 117.674617 -205.412152) (xy 117.711834 -205.453689)
			(xy 117.742607 -205.500202) (xy 117.766279 -205.550699) (xy 117.782347 -205.604106) (xy 117.789226 -205.650846)
			(xy 137.982196 -205.650846) (xy 137.986267 -205.595224) (xy 137.998393 -205.540787) (xy 138.018316 -205.488696)
			(xy 138.045612 -205.440061) (xy 138.079698 -205.395918) (xy 138.119847 -205.357209) (xy 138.165205 -205.324758)
			(xy 138.214805 -205.299257) (xy 138.267589 -205.28125) (xy 138.322432 -205.27112) (xy 138.378166 -205.269083)
			(xy 138.433603 -205.275183) (xy 138.48756 -205.289289) (xy 138.538889 -205.311101) (xy 138.586495 -205.340155)
			(xy 138.629363 -205.37583) (xy 138.66658 -205.417367) (xy 138.697353 -205.46388) (xy 138.721025 -205.514377)
			(xy 138.737093 -205.567784) (xy 138.745213 -205.62296) (xy 138.745722 -205.650846) (xy 138.745213 -205.678732)
			(xy 138.737093 -205.733908) (xy 138.721025 -205.787315) (xy 138.697353 -205.837812) (xy 138.66658 -205.884325)
			(xy 138.629363 -205.925862) (xy 138.586495 -205.961537) (xy 138.538889 -205.990591) (xy 138.48756 -206.012403)
			(xy 138.433603 -206.026509) (xy 138.378166 -206.032609) (xy 138.322432 -206.030572) (xy 138.267589 -206.020442)
			(xy 138.214805 -206.002435) (xy 138.165205 -205.976934) (xy 138.119847 -205.944483) (xy 138.079698 -205.905774)
			(xy 138.045612 -205.861631) (xy 138.018316 -205.812996) (xy 137.998393 -205.760905) (xy 137.986267 -205.706468)
			(xy 137.982196 -205.650846) (xy 117.789226 -205.650846) (xy 117.790467 -205.659282) (xy 117.790976 -205.687168)
			(xy 117.790467 -205.715054) (xy 117.782347 -205.77023) (xy 117.766279 -205.823637) (xy 117.742607 -205.874134)
			(xy 117.711834 -205.920647) (xy 117.674617 -205.962184) (xy 117.631749 -205.997859) (xy 117.584143 -206.026913)
			(xy 117.532814 -206.048725) (xy 117.478857 -206.062831) (xy 117.42342 -206.068931) (xy 117.367686 -206.066894)
			(xy 117.312843 -206.056764) (xy 117.260059 -206.038757) (xy 117.210459 -206.013256) (xy 117.165101 -205.980805)
			(xy 117.124952 -205.942096) (xy 117.090866 -205.897953) (xy 117.06357 -205.849318) (xy 117.043647 -205.797227)
			(xy 117.031521 -205.74279) (xy 117.02745 -205.687168) (xy 91.337384 -205.687168) (xy 91.337384 -206.25816)
			(xy 127.720596 -206.25816) (xy 127.724667 -206.202538) (xy 127.736793 -206.148101) (xy 127.756716 -206.09601)
			(xy 127.784012 -206.047375) (xy 127.818098 -206.003232) (xy 127.858247 -205.964523) (xy 127.903605 -205.932072)
			(xy 127.953205 -205.906571) (xy 128.005989 -205.888564) (xy 128.060832 -205.878434) (xy 128.116566 -205.876397)
			(xy 128.172003 -205.882497) (xy 128.22596 -205.896603) (xy 128.277289 -205.918415) (xy 128.324895 -205.947469)
			(xy 128.367763 -205.983144) (xy 128.40498 -206.024681) (xy 128.434759 -206.069692) (xy 140.301216 -206.069692)
			(xy 140.305287 -206.01407) (xy 140.317413 -205.959633) (xy 140.337336 -205.907542) (xy 140.364632 -205.858907)
			(xy 140.398718 -205.814764) (xy 140.438867 -205.776055) (xy 140.484225 -205.743604) (xy 140.533825 -205.718103)
			(xy 140.586609 -205.700096) (xy 140.641452 -205.689966) (xy 140.697186 -205.687929) (xy 140.752623 -205.694029)
			(xy 140.80658 -205.708135) (xy 140.857909 -205.729947) (xy 140.905515 -205.759001) (xy 140.948383 -205.794676)
			(xy 140.9856 -205.836213) (xy 141.016373 -205.882726) (xy 141.040045 -205.933223) (xy 141.056113 -205.98663)
			(xy 141.064233 -206.041806) (xy 141.064482 -206.055468) (xy 142.213836 -206.055468) (xy 142.217907 -205.999846)
			(xy 142.230033 -205.945409) (xy 142.249956 -205.893318) (xy 142.277252 -205.844683) (xy 142.311338 -205.80054)
			(xy 142.351487 -205.761831) (xy 142.396845 -205.72938) (xy 142.446445 -205.703879) (xy 142.499229 -205.685872)
			(xy 142.554072 -205.675742) (xy 142.609806 -205.673705) (xy 142.665243 -205.679805) (xy 142.7192 -205.693911)
			(xy 142.770529 -205.715723) (xy 142.818135 -205.744777) (xy 142.861003 -205.780452) (xy 142.89822 -205.821989)
			(xy 142.928993 -205.868502) (xy 142.952665 -205.918999) (xy 142.968733 -205.972406) (xy 142.976853 -206.027582)
			(xy 142.977362 -206.055468) (xy 142.976853 -206.083354) (xy 142.968733 -206.13853) (xy 142.952665 -206.191937)
			(xy 142.928993 -206.242434) (xy 142.89822 -206.288947) (xy 142.861003 -206.330484) (xy 142.818135 -206.366159)
			(xy 142.770529 -206.395213) (xy 142.7192 -206.417025) (xy 142.665243 -206.431131) (xy 142.609806 -206.437231)
			(xy 142.554072 -206.435194) (xy 142.499229 -206.425064) (xy 142.446445 -206.407057) (xy 142.396845 -206.381556)
			(xy 142.351487 -206.349105) (xy 142.311338 -206.310396) (xy 142.277252 -206.266253) (xy 142.249956 -206.217618)
			(xy 142.230033 -206.165527) (xy 142.217907 -206.11109) (xy 142.213836 -206.055468) (xy 141.064482 -206.055468)
			(xy 141.064742 -206.069692) (xy 141.064233 -206.097578) (xy 141.056113 -206.152754) (xy 141.040045 -206.206161)
			(xy 141.016373 -206.256658) (xy 140.9856 -206.303171) (xy 140.948383 -206.344708) (xy 140.905515 -206.380383)
			(xy 140.857909 -206.409437) (xy 140.80658 -206.431249) (xy 140.752623 -206.445355) (xy 140.697186 -206.451455)
			(xy 140.641452 -206.449418) (xy 140.586609 -206.439288) (xy 140.533825 -206.421281) (xy 140.484225 -206.39578)
			(xy 140.438867 -206.363329) (xy 140.398718 -206.32462) (xy 140.364632 -206.280477) (xy 140.337336 -206.231842)
			(xy 140.317413 -206.179751) (xy 140.305287 -206.125314) (xy 140.301216 -206.069692) (xy 128.434759 -206.069692)
			(xy 128.435753 -206.071194) (xy 128.459425 -206.121691) (xy 128.475493 -206.175098) (xy 128.483613 -206.230274)
			(xy 128.484122 -206.25816) (xy 128.483613 -206.286046) (xy 128.475493 -206.341222) (xy 128.459425 -206.394629)
			(xy 128.435753 -206.445126) (xy 128.40498 -206.491639) (xy 128.367763 -206.533176) (xy 128.324895 -206.568851)
			(xy 128.277289 -206.597905) (xy 128.22596 -206.619717) (xy 128.172003 -206.633823) (xy 128.116566 -206.639923)
			(xy 128.060832 -206.637886) (xy 128.005989 -206.627756) (xy 127.953205 -206.609749) (xy 127.903605 -206.584248)
			(xy 127.858247 -206.551797) (xy 127.818098 -206.513088) (xy 127.784012 -206.468945) (xy 127.756716 -206.42031)
			(xy 127.736793 -206.368219) (xy 127.724667 -206.313782) (xy 127.720596 -206.25816) (xy 91.337384 -206.25816)
			(xy 91.337384 -206.952088) (xy 91.57665 -206.952088) (xy 91.580721 -206.896466) (xy 91.592847 -206.842029)
			(xy 91.61277 -206.789938) (xy 91.640066 -206.741303) (xy 91.674152 -206.69716) (xy 91.714301 -206.658451)
			(xy 91.759659 -206.626) (xy 91.809259 -206.600499) (xy 91.862043 -206.582492) (xy 91.916886 -206.572362)
			(xy 91.97262 -206.570325) (xy 92.028057 -206.576425) (xy 92.082014 -206.590531) (xy 92.133343 -206.612343)
			(xy 92.180949 -206.641397) (xy 92.223817 -206.677072) (xy 92.261034 -206.718609) (xy 92.291807 -206.765122)
			(xy 92.315479 -206.815619) (xy 92.331547 -206.869026) (xy 92.339667 -206.924202) (xy 92.340176 -206.952088)
			(xy 92.339667 -206.979974) (xy 92.331547 -207.03515) (xy 92.321195 -207.069557) (xy 92.504413 -207.069557)
			(xy 92.504413 -207.015043) (xy 92.512171 -206.961085) (xy 92.52753 -206.908781) (xy 92.550176 -206.859194)
			(xy 92.579648 -206.813335) (xy 92.615347 -206.772137) (xy 92.656546 -206.73644) (xy 92.702406 -206.706969)
			(xy 92.751994 -206.684325) (xy 92.804299 -206.668968) (xy 92.858257 -206.661212) (xy 92.885514 -206.66075)
			(xy 92.915169 -206.661329) (xy 92.973764 -206.670509) (xy 93.030233 -206.688645) (xy 93.083215 -206.715302)
			(xy 93.131434 -206.749835) (xy 93.152976 -206.770224) (xy 93.160596 -206.77759) (xy 93.16974 -206.7814)
			(xy 93.174684 -206.783203) (xy 93.185052 -206.785003) (xy 93.190314 -206.784956) (xy 93.26372 -206.78267)
			(xy 93.268837 -206.782408) (xy 93.278819 -206.780107) (xy 93.283532 -206.778098) (xy 93.292676 -206.77378)
			(xy 93.299788 -206.765906) (xy 93.318822 -206.745489) (xy 93.361575 -206.709604) (xy 93.408904 -206.680013)
			(xy 93.459888 -206.65729) (xy 93.513536 -206.641879) (xy 93.568805 -206.634077) (xy 93.596714 -206.633572)
			(xy 93.624689 -206.634034) (xy 93.680086 -206.641878) (xy 93.73385 -206.657367) (xy 93.784929 -206.6802)
			(xy 93.832326 -206.709931) (xy 93.875116 -206.745979) (xy 93.912462 -206.78764) (xy 93.928438 -206.81061)
			(xy 93.928692 -206.810864) (xy 93.931928 -206.815406) (xy 93.939997 -206.823099) (xy 93.944694 -206.826104)
			(xy 93.944948 -206.826104) (xy 93.95333 -206.829914) (xy 93.966538 -206.832962) (xy 94.056962 -206.840582)
			(xy 94.067376 -206.836518) (xy 94.072656 -206.834388) (xy 94.082146 -206.828098) (xy 94.086172 -206.824072)
			(xy 94.086426 -206.823818) (xy 94.104506 -206.805464) (xy 94.144748 -206.773293) (xy 94.18895 -206.746825)
			(xy 94.236309 -206.726541) (xy 94.285966 -206.712809) (xy 94.337018 -206.705878) (xy 94.362778 -206.705454)
			(xy 94.390029 -206.705992) (xy 94.443977 -206.713745) (xy 94.496272 -206.729098) (xy 94.54585 -206.751737)
			(xy 94.591702 -206.781201) (xy 94.632893 -206.816892) (xy 94.63606 -206.820547) (xy 96.553316 -206.820547)
			(xy 96.553316 -206.766053) (xy 96.561071 -206.712113) (xy 96.576423 -206.659825) (xy 96.59906 -206.610255)
			(xy 96.628521 -206.56441) (xy 96.664206 -206.523225) (xy 96.705389 -206.487537) (xy 96.751232 -206.458073)
			(xy 96.800801 -206.435433) (xy 96.853087 -206.420077) (xy 96.907027 -206.412318) (xy 96.934274 -206.41183)
			(xy 96.963191 -206.412356) (xy 97.020362 -206.421082) (xy 97.075561 -206.438337) (xy 97.127523 -206.463727)
			(xy 97.175057 -206.49667) (xy 97.217074 -206.536411) (xy 97.235264 -206.558896) (xy 97.23882 -206.563722)
			(xy 97.248218 -206.571088) (xy 97.253298 -206.573628) (xy 97.258652 -206.575958) (xy 97.270066 -206.578405)
			(xy 97.275904 -206.578454) (xy 97.357438 -206.577438) (xy 97.363314 -206.577187) (xy 97.374731 -206.574373)
			(xy 97.380044 -206.57185) (xy 97.38487 -206.56931) (xy 97.39376 -206.56169) (xy 97.397316 -206.55661)
			(xy 97.415454 -206.53289) (xy 97.457838 -206.490833) (xy 97.506252 -206.455885) (xy 97.559515 -206.428899)
			(xy 97.616329 -206.410533) (xy 97.675309 -206.401233) (xy 97.705164 -206.400654) (xy 97.734969 -206.40125)
			(xy 97.793851 -206.410536) (xy 97.85057 -206.42887) (xy 97.903747 -206.455807) (xy 97.952084 -206.49069)
			(xy 97.994404 -206.53267) (xy 98.012504 -206.556356) (xy 98.016822 -206.562198) (xy 98.026982 -206.570072)
			(xy 98.033078 -206.572866) (xy 98.039376 -206.575328) (xy 98.052756 -206.577256) (xy 98.059494 -206.576676)
			(xy 98.148394 -206.565754) (xy 98.16084 -206.562706) (xy 98.166936 -206.560166) (xy 98.17227 -206.556102)
			(xy 98.177545 -206.551887) (xy 98.185776 -206.541188) (xy 98.188526 -206.53502) (xy 98.188526 -206.534766)
			(xy 98.199728 -206.508917) (xy 98.228558 -206.46052) (xy 98.264194 -206.416892) (xy 98.305861 -206.378981)
			(xy 98.352652 -206.347613) (xy 98.40355 -206.32347) (xy 98.457445 -206.307079) (xy 98.513166 -206.298795)
			(xy 98.541332 -206.298292) (xy 98.568582 -206.29878) (xy 98.622526 -206.30654) (xy 98.674817 -206.321898)
			(xy 98.72439 -206.344541) (xy 98.770237 -206.374008) (xy 98.811423 -206.4097) (xy 98.847111 -206.450889)
			(xy 98.876574 -206.496738) (xy 98.899213 -206.546313) (xy 98.914567 -206.598605) (xy 98.922322 -206.65255)
			(xy 98.922322 -206.70705) (xy 98.914567 -206.760995) (xy 98.899213 -206.813287) (xy 98.876574 -206.862862)
			(xy 98.847111 -206.908711) (xy 98.811423 -206.9499) (xy 98.805381 -206.955136) (xy 128.420112 -206.955136)
			(xy 128.424183 -206.899514) (xy 128.436309 -206.845077) (xy 128.456232 -206.792986) (xy 128.483528 -206.744351)
			(xy 128.517614 -206.700208) (xy 128.557763 -206.661499) (xy 128.603121 -206.629048) (xy 128.652721 -206.603547)
			(xy 128.705505 -206.58554) (xy 128.760348 -206.57541) (xy 128.816082 -206.573373) (xy 128.871519 -206.579473)
			(xy 128.925476 -206.593579) (xy 128.976805 -206.615391) (xy 129.024411 -206.644445) (xy 129.067279 -206.68012)
			(xy 129.104496 -206.721657) (xy 129.127385 -206.756254) (xy 131.997194 -206.756254) (xy 132.001265 -206.700632)
			(xy 132.013391 -206.646195) (xy 132.033314 -206.594104) (xy 132.06061 -206.545469) (xy 132.094696 -206.501326)
			(xy 132.134845 -206.462617) (xy 132.180203 -206.430166) (xy 132.229803 -206.404665) (xy 132.282587 -206.386658)
			(xy 132.33743 -206.376528) (xy 132.393164 -206.374491) (xy 132.448601 -206.380591) (xy 132.502558 -206.394697)
			(xy 132.553887 -206.416509) (xy 132.601493 -206.445563) (xy 132.623527 -206.4639) (xy 143.777968 -206.4639)
			(xy 143.782039 -206.408278) (xy 143.794165 -206.353841) (xy 143.814088 -206.30175) (xy 143.841384 -206.253115)
			(xy 143.87547 -206.208972) (xy 143.915619 -206.170263) (xy 143.960977 -206.137812) (xy 144.010577 -206.112311)
			(xy 144.063361 -206.094304) (xy 144.118204 -206.084174) (xy 144.173938 -206.082137) (xy 144.229375 -206.088237)
			(xy 144.283332 -206.102343) (xy 144.334661 -206.124155) (xy 144.382267 -206.153209) (xy 144.425135 -206.188884)
			(xy 144.462352 -206.230421) (xy 144.493125 -206.276934) (xy 144.516797 -206.327431) (xy 144.532865 -206.380838)
			(xy 144.540985 -206.436014) (xy 144.541494 -206.4639) (xy 144.540985 -206.491786) (xy 144.532865 -206.546962)
			(xy 144.516797 -206.600369) (xy 144.493125 -206.650866) (xy 144.462352 -206.697379) (xy 144.425135 -206.738916)
			(xy 144.382267 -206.774591) (xy 144.361538 -206.787242) (xy 147.192236 -206.787242) (xy 147.196307 -206.73162)
			(xy 147.208433 -206.677183) (xy 147.228356 -206.625092) (xy 147.255652 -206.576457) (xy 147.289738 -206.532314)
			(xy 147.329887 -206.493605) (xy 147.375245 -206.461154) (xy 147.424845 -206.435653) (xy 147.477629 -206.417646)
			(xy 147.532472 -206.407516) (xy 147.588206 -206.405479) (xy 147.643643 -206.411579) (xy 147.6976 -206.425685)
			(xy 147.748929 -206.447497) (xy 147.796535 -206.476551) (xy 147.839403 -206.512226) (xy 147.87662 -206.553763)
			(xy 147.907393 -206.600276) (xy 147.931065 -206.650773) (xy 147.947133 -206.70418) (xy 147.955253 -206.759356)
			(xy 147.955762 -206.787242) (xy 147.955253 -206.815128) (xy 147.947133 -206.870304) (xy 147.931065 -206.923711)
			(xy 147.907393 -206.974208) (xy 147.87662 -207.020721) (xy 147.839403 -207.062258) (xy 147.796535 -207.097933)
			(xy 147.748929 -207.126987) (xy 147.6976 -207.148799) (xy 147.643643 -207.162905) (xy 147.588206 -207.169005)
			(xy 147.532472 -207.166968) (xy 147.477629 -207.156838) (xy 147.424845 -207.138831) (xy 147.375245 -207.11333)
			(xy 147.329887 -207.080879) (xy 147.289738 -207.04217) (xy 147.255652 -206.998027) (xy 147.228356 -206.949392)
			(xy 147.208433 -206.897301) (xy 147.196307 -206.842864) (xy 147.192236 -206.787242) (xy 144.361538 -206.787242)
			(xy 144.334661 -206.803645) (xy 144.283332 -206.825457) (xy 144.229375 -206.839563) (xy 144.173938 -206.845663)
			(xy 144.118204 -206.843626) (xy 144.063361 -206.833496) (xy 144.010577 -206.815489) (xy 143.960977 -206.789988)
			(xy 143.915619 -206.757537) (xy 143.87547 -206.718828) (xy 143.841384 -206.674685) (xy 143.814088 -206.62605)
			(xy 143.794165 -206.573959) (xy 143.782039 -206.519522) (xy 143.777968 -206.4639) (xy 132.623527 -206.4639)
			(xy 132.644361 -206.481238) (xy 132.681578 -206.522775) (xy 132.712351 -206.569288) (xy 132.736023 -206.619785)
			(xy 132.752091 -206.673192) (xy 132.760211 -206.728368) (xy 132.76072 -206.756254) (xy 132.760211 -206.78414)
			(xy 132.752091 -206.839316) (xy 132.736023 -206.892723) (xy 132.712351 -206.94322) (xy 132.681578 -206.989733)
			(xy 132.644361 -207.03127) (xy 132.601493 -207.066945) (xy 132.553887 -207.095999) (xy 132.502558 -207.117811)
			(xy 132.448601 -207.131917) (xy 132.393164 -207.138017) (xy 132.33743 -207.13598) (xy 132.282587 -207.12585)
			(xy 132.229803 -207.107843) (xy 132.180203 -207.082342) (xy 132.134845 -207.049891) (xy 132.094696 -207.011182)
			(xy 132.06061 -206.967039) (xy 132.033314 -206.918404) (xy 132.013391 -206.866313) (xy 132.001265 -206.811876)
			(xy 131.997194 -206.756254) (xy 129.127385 -206.756254) (xy 129.135269 -206.76817) (xy 129.158941 -206.818667)
			(xy 129.175009 -206.872074) (xy 129.183129 -206.92725) (xy 129.183638 -206.955136) (xy 129.183129 -206.983022)
			(xy 129.175009 -207.038198) (xy 129.158941 -207.091605) (xy 129.135269 -207.142102) (xy 129.104496 -207.188615)
			(xy 129.099764 -207.193896) (xy 134.661146 -207.193896) (xy 134.665217 -207.138274) (xy 134.677343 -207.083837)
			(xy 134.697266 -207.031746) (xy 134.724562 -206.983111) (xy 134.758648 -206.938968) (xy 134.798797 -206.900259)
			(xy 134.844155 -206.867808) (xy 134.893755 -206.842307) (xy 134.946539 -206.8243) (xy 135.001382 -206.81417)
			(xy 135.057116 -206.812133) (xy 135.112553 -206.818233) (xy 135.16651 -206.832339) (xy 135.217839 -206.854151)
			(xy 135.265445 -206.883205) (xy 135.308313 -206.91888) (xy 135.34553 -206.960417) (xy 135.376303 -207.00693)
			(xy 135.399975 -207.057427) (xy 135.416043 -207.110834) (xy 135.424163 -207.16601) (xy 135.424672 -207.193896)
			(xy 135.424163 -207.221782) (xy 135.416043 -207.276958) (xy 135.399975 -207.330365) (xy 135.376303 -207.380862)
			(xy 135.360185 -207.405224) (xy 136.98296 -207.405224) (xy 136.987031 -207.349602) (xy 136.999157 -207.295165)
			(xy 137.01908 -207.243074) (xy 137.046376 -207.194439) (xy 137.080462 -207.150296) (xy 137.120611 -207.111587)
			(xy 137.165969 -207.079136) (xy 137.215569 -207.053635) (xy 137.268353 -207.035628) (xy 137.323196 -207.025498)
			(xy 137.37893 -207.023461) (xy 137.434367 -207.029561) (xy 137.488324 -207.043667) (xy 137.539653 -207.065479)
			(xy 137.587259 -207.094533) (xy 137.630127 -207.130208) (xy 137.667344 -207.171745) (xy 137.698117 -207.218258)
			(xy 137.721789 -207.268755) (xy 137.737857 -207.322162) (xy 137.740848 -207.342486) (xy 138.016994 -207.342486)
			(xy 138.021065 -207.286864) (xy 138.033191 -207.232427) (xy 138.053114 -207.180336) (xy 138.08041 -207.131701)
			(xy 138.114496 -207.087558) (xy 138.154645 -207.048849) (xy 138.200003 -207.016398) (xy 138.249603 -206.990897)
			(xy 138.302387 -206.97289) (xy 138.35723 -206.96276) (xy 138.412964 -206.960723) (xy 138.468401 -206.966823)
			(xy 138.522358 -206.980929) (xy 138.573687 -207.002741) (xy 138.621293 -207.031795) (xy 138.664161 -207.06747)
			(xy 138.701378 -207.109007) (xy 138.732151 -207.15552) (xy 138.755823 -207.206017) (xy 138.771891 -207.259424)
			(xy 138.780011 -207.3146) (xy 138.78052 -207.342486) (xy 138.780011 -207.370372) (xy 138.771891 -207.425548)
			(xy 138.755823 -207.478955) (xy 138.732151 -207.529452) (xy 138.701378 -207.575965) (xy 138.664161 -207.617502)
			(xy 138.621293 -207.653177) (xy 138.573687 -207.682231) (xy 138.522358 -207.704043) (xy 138.468401 -207.718149)
			(xy 138.412964 -207.724249) (xy 138.35723 -207.722212) (xy 138.302387 -207.712082) (xy 138.249603 -207.694075)
			(xy 138.200003 -207.668574) (xy 138.154645 -207.636123) (xy 138.114496 -207.597414) (xy 138.08041 -207.553271)
			(xy 138.053114 -207.504636) (xy 138.033191 -207.452545) (xy 138.021065 -207.398108) (xy 138.016994 -207.342486)
			(xy 137.740848 -207.342486) (xy 137.745977 -207.377338) (xy 137.746486 -207.405224) (xy 137.745977 -207.43311)
			(xy 137.737857 -207.488286) (xy 137.721789 -207.541693) (xy 137.698117 -207.59219) (xy 137.667344 -207.638703)
			(xy 137.630127 -207.68024) (xy 137.587259 -207.715915) (xy 137.539653 -207.744969) (xy 137.488324 -207.766781)
			(xy 137.434367 -207.780887) (xy 137.37893 -207.786987) (xy 137.323196 -207.78495) (xy 137.268353 -207.77482)
			(xy 137.215569 -207.756813) (xy 137.165969 -207.731312) (xy 137.120611 -207.698861) (xy 137.080462 -207.660152)
			(xy 137.046376 -207.616009) (xy 137.01908 -207.567374) (xy 136.999157 -207.515283) (xy 136.987031 -207.460846)
			(xy 136.98296 -207.405224) (xy 135.360185 -207.405224) (xy 135.34553 -207.427375) (xy 135.308313 -207.468912)
			(xy 135.265445 -207.504587) (xy 135.217839 -207.533641) (xy 135.16651 -207.555453) (xy 135.112553 -207.569559)
			(xy 135.057116 -207.575659) (xy 135.001382 -207.573622) (xy 134.946539 -207.563492) (xy 134.893755 -207.545485)
			(xy 134.844155 -207.519984) (xy 134.798797 -207.487533) (xy 134.758648 -207.448824) (xy 134.724562 -207.404681)
			(xy 134.697266 -207.356046) (xy 134.677343 -207.303955) (xy 134.665217 -207.249518) (xy 134.661146 -207.193896)
			(xy 129.099764 -207.193896) (xy 129.067279 -207.230152) (xy 129.024411 -207.265827) (xy 128.976805 -207.294881)
			(xy 128.925476 -207.316693) (xy 128.871519 -207.330799) (xy 128.816082 -207.336899) (xy 128.760348 -207.334862)
			(xy 128.705505 -207.324732) (xy 128.652721 -207.306725) (xy 128.603121 -207.281224) (xy 128.557763 -207.248773)
			(xy 128.517614 -207.210064) (xy 128.483528 -207.165921) (xy 128.456232 -207.117286) (xy 128.436309 -207.065195)
			(xy 128.424183 -207.010758) (xy 128.420112 -206.955136) (xy 98.805381 -206.955136) (xy 98.770237 -206.985592)
			(xy 98.72439 -207.015059) (xy 98.674817 -207.037702) (xy 98.622526 -207.05306) (xy 98.568582 -207.06082)
			(xy 98.541332 -207.061308) (xy 98.511529 -207.060689) (xy 98.452649 -207.051405) (xy 98.395931 -207.033073)
			(xy 98.342755 -207.006141) (xy 98.294417 -206.971263) (xy 98.252094 -206.929289) (xy 98.233992 -206.905606)
			(xy 98.229674 -206.899764) (xy 98.219514 -206.89189) (xy 98.213418 -206.889096) (xy 98.20712 -206.886632)
			(xy 98.19374 -206.884706) (xy 98.187002 -206.885286) (xy 98.098102 -206.896208) (xy 98.085656 -206.899256)
			(xy 98.07956 -206.901796) (xy 98.074226 -206.90586) (xy 98.068974 -206.910101) (xy 98.060728 -206.920781)
			(xy 98.05797 -206.926942) (xy 98.05797 -206.927196) (xy 98.046802 -206.95306) (xy 98.017965 -207.001455)
			(xy 97.982323 -207.045081) (xy 97.94065 -207.08299) (xy 97.893854 -207.114355) (xy 97.842953 -207.138495)
			(xy 97.789055 -207.154885) (xy 97.733332 -207.163167) (xy 97.705164 -207.16367) (xy 97.676248 -207.163117)
			(xy 97.619078 -207.154397) (xy 97.563879 -207.137147) (xy 97.511917 -207.111762) (xy 97.464383 -207.078824)
			(xy 97.422365 -207.039087) (xy 97.404174 -207.016604) (xy 97.400618 -207.011778) (xy 97.39122 -207.004412)
			(xy 97.38614 -207.001872) (xy 97.380794 -206.999522) (xy 97.369374 -206.997088) (xy 97.363534 -206.997046)
			(xy 97.282 -206.998062) (xy 97.276122 -206.998293) (xy 97.264706 -207.001121) (xy 97.259394 -207.00365)
			(xy 97.254568 -207.00619) (xy 97.245678 -207.01381) (xy 97.242122 -207.01889) (xy 97.22402 -207.04264)
			(xy 97.181629 -207.084695) (xy 97.133208 -207.119639) (xy 97.079938 -207.14662) (xy 97.023117 -207.16498)
			(xy 96.964131 -207.174271) (xy 96.934274 -207.174846) (xy 96.907027 -207.174282) (xy 96.853087 -207.166523)
			(xy 96.800801 -207.151167) (xy 96.751232 -207.128527) (xy 96.705389 -207.099063) (xy 96.664206 -207.063375)
			(xy 96.628521 -207.02219) (xy 96.59906 -206.976345) (xy 96.576423 -206.926775) (xy 96.561071 -206.874487)
			(xy 96.553316 -206.820547) (xy 94.63606 -206.820547) (xy 94.668585 -206.858081) (xy 94.698052 -206.90393)
			(xy 94.720694 -206.953507) (xy 94.73605 -207.005801) (xy 94.743807 -207.059749) (xy 94.743807 -207.114251)
			(xy 94.73605 -207.168199) (xy 94.720694 -207.220493) (xy 94.698052 -207.27007) (xy 94.668585 -207.315919)
			(xy 94.632893 -207.357108) (xy 94.591702 -207.392799) (xy 94.54585 -207.422263) (xy 94.496272 -207.444902)
			(xy 94.443977 -207.460255) (xy 94.390029 -207.468008) (xy 94.362778 -207.46847) (xy 94.336879 -207.468042)
			(xy 94.285558 -207.461036) (xy 94.235655 -207.447155) (xy 94.188087 -207.426654) (xy 94.143727 -207.399911)
			(xy 94.103391 -207.367415) (xy 94.067819 -207.329764) (xy 94.05239 -207.308958) (xy 94.049088 -207.304386)
			(xy 94.040706 -207.296766) (xy 94.03588 -207.293972) (xy 94.03216 -207.292022) (xy 94.02425 -207.289207)
			(xy 94.020132 -207.288384) (xy 94.013782 -207.287622) (xy 93.923104 -207.282796) (xy 93.912944 -207.28686)
			(xy 93.907642 -207.289211) (xy 93.898153 -207.295874) (xy 93.894148 -207.300068) (xy 93.893894 -207.300576)
			(xy 93.874857 -207.321031) (xy 93.832078 -207.35698) (xy 93.784713 -207.386626) (xy 93.733683 -207.409392)
			(xy 93.679981 -207.424835) (xy 93.624653 -207.432655) (xy 93.596714 -207.433164) (xy 93.569646 -207.432708)
			(xy 93.51601 -207.425354) (xy 93.463857 -207.410833) (xy 93.414139 -207.38941) (xy 93.367765 -207.361477)
			(xy 93.325582 -207.327544) (xy 93.306646 -207.308196) (xy 93.29928 -207.300576) (xy 93.289882 -207.296512)
			(xy 93.285156 -207.2946) (xy 93.275168 -207.292558) (xy 93.27007 -207.292448) (xy 93.196664 -207.29194)
			(xy 93.183964 -207.293464) (xy 93.176344 -207.296004) (xy 93.1672 -207.299814) (xy 93.159834 -207.307434)
			(xy 93.141794 -207.325488) (xy 93.101739 -207.357117) (xy 93.057826 -207.383126) (xy 93.010838 -207.403051)
			(xy 92.961615 -207.416535) (xy 92.911033 -207.423339) (xy 92.885514 -207.423766) (xy 92.858257 -207.423388)
			(xy 92.804299 -207.415632) (xy 92.751994 -207.400275) (xy 92.702406 -207.377631) (xy 92.656546 -207.34816)
			(xy 92.615347 -207.312463) (xy 92.579648 -207.271265) (xy 92.550176 -207.225406) (xy 92.52753 -207.175819)
			(xy 92.512171 -207.123515) (xy 92.504413 -207.069557) (xy 92.321195 -207.069557) (xy 92.315479 -207.088557)
			(xy 92.291807 -207.139054) (xy 92.261034 -207.185567) (xy 92.223817 -207.227104) (xy 92.180949 -207.262779)
			(xy 92.133343 -207.291833) (xy 92.082014 -207.313645) (xy 92.028057 -207.327751) (xy 91.97262 -207.333851)
			(xy 91.916886 -207.331814) (xy 91.862043 -207.321684) (xy 91.809259 -207.303677) (xy 91.759659 -207.278176)
			(xy 91.714301 -207.245725) (xy 91.674152 -207.207016) (xy 91.640066 -207.162873) (xy 91.61277 -207.114238)
			(xy 91.592847 -207.062147) (xy 91.580721 -207.00771) (xy 91.57665 -206.952088) (xy 91.337384 -206.952088)
			(xy 91.337384 -208.593436) (xy 119.926098 -208.593436) (xy 119.930169 -208.537814) (xy 119.942295 -208.483377)
			(xy 119.962218 -208.431286) (xy 119.989514 -208.382651) (xy 120.0236 -208.338508) (xy 120.063749 -208.299799)
			(xy 120.109107 -208.267348) (xy 120.158707 -208.241847) (xy 120.211491 -208.22384) (xy 120.266334 -208.21371)
			(xy 120.322068 -208.211673) (xy 120.377505 -208.217773) (xy 120.408584 -208.225898) (xy 123.017278 -208.225898)
			(xy 123.021349 -208.170276) (xy 123.033475 -208.115839) (xy 123.053398 -208.063748) (xy 123.080694 -208.015113)
			(xy 123.11478 -207.97097) (xy 123.154929 -207.932261) (xy 123.200287 -207.89981) (xy 123.249887 -207.874309)
			(xy 123.302671 -207.856302) (xy 123.357514 -207.846172) (xy 123.413248 -207.844135) (xy 123.468685 -207.850235)
			(xy 123.522642 -207.864341) (xy 123.573971 -207.886153) (xy 123.621577 -207.915207) (xy 123.664445 -207.950882)
			(xy 123.701662 -207.992419) (xy 123.732435 -208.038932) (xy 123.756107 -208.089429) (xy 123.772175 -208.142836)
			(xy 123.780295 -208.198012) (xy 123.780804 -208.225898) (xy 123.780295 -208.253784) (xy 123.772175 -208.30896)
			(xy 123.756107 -208.362367) (xy 123.732435 -208.412864) (xy 123.701662 -208.459377) (xy 123.664445 -208.500914)
			(xy 123.645748 -208.516474) (xy 132.095492 -208.516474) (xy 132.099563 -208.460852) (xy 132.111689 -208.406415)
			(xy 132.131612 -208.354324) (xy 132.158908 -208.305689) (xy 132.192994 -208.261546) (xy 132.233143 -208.222837)
			(xy 132.278501 -208.190386) (xy 132.328101 -208.164885) (xy 132.380885 -208.146878) (xy 132.435728 -208.136748)
			(xy 132.491462 -208.134711) (xy 132.546899 -208.140811) (xy 132.600856 -208.154917) (xy 132.652185 -208.176729)
			(xy 132.699791 -208.205783) (xy 132.742659 -208.241458) (xy 132.779876 -208.282995) (xy 132.802933 -208.317846)
			(xy 141.030196 -208.317846) (xy 141.034267 -208.262224) (xy 141.046393 -208.207787) (xy 141.066316 -208.155696)
			(xy 141.093612 -208.107061) (xy 141.127698 -208.062918) (xy 141.167847 -208.024209) (xy 141.213205 -207.991758)
			(xy 141.262805 -207.966257) (xy 141.315589 -207.94825) (xy 141.370432 -207.93812) (xy 141.426166 -207.936083)
			(xy 141.481603 -207.942183) (xy 141.53556 -207.956289) (xy 141.586889 -207.978101) (xy 141.623754 -208.0006)
			(xy 142.467582 -208.0006) (xy 142.471653 -207.944978) (xy 142.483779 -207.890541) (xy 142.503702 -207.83845)
			(xy 142.530998 -207.789815) (xy 142.565084 -207.745672) (xy 142.605233 -207.706963) (xy 142.650591 -207.674512)
			(xy 142.700191 -207.649011) (xy 142.752975 -207.631004) (xy 142.807818 -207.620874) (xy 142.863552 -207.618837)
			(xy 142.918989 -207.624937) (xy 142.972946 -207.639043) (xy 143.024275 -207.660855) (xy 143.071881 -207.689909)
			(xy 143.095136 -207.709262) (xy 146.876514 -207.709262) (xy 146.880585 -207.65364) (xy 146.892711 -207.599203)
			(xy 146.912634 -207.547112) (xy 146.93993 -207.498477) (xy 146.974016 -207.454334) (xy 147.014165 -207.415625)
			(xy 147.059523 -207.383174) (xy 147.109123 -207.357673) (xy 147.161907 -207.339666) (xy 147.21675 -207.329536)
			(xy 147.272484 -207.327499) (xy 147.327921 -207.333599) (xy 147.381878 -207.347705) (xy 147.433207 -207.369517)
			(xy 147.480813 -207.398571) (xy 147.523681 -207.434246) (xy 147.560898 -207.475783) (xy 147.591671 -207.522296)
			(xy 147.615343 -207.572793) (xy 147.631411 -207.6262) (xy 147.639531 -207.681376) (xy 147.64004 -207.709262)
			(xy 147.639531 -207.737148) (xy 147.631411 -207.792324) (xy 147.615343 -207.845731) (xy 147.591671 -207.896228)
			(xy 147.560898 -207.942741) (xy 147.523681 -207.984278) (xy 147.480813 -208.019953) (xy 147.433207 -208.049007)
			(xy 147.381878 -208.070819) (xy 147.327921 -208.084925) (xy 147.272484 -208.091025) (xy 147.21675 -208.088988)
			(xy 147.161907 -208.078858) (xy 147.109123 -208.060851) (xy 147.059523 -208.03535) (xy 147.014165 -208.002899)
			(xy 146.974016 -207.96419) (xy 146.93993 -207.920047) (xy 146.912634 -207.871412) (xy 146.892711 -207.819321)
			(xy 146.880585 -207.764884) (xy 146.876514 -207.709262) (xy 143.095136 -207.709262) (xy 143.114749 -207.725584)
			(xy 143.151966 -207.767121) (xy 143.182739 -207.813634) (xy 143.206411 -207.864131) (xy 143.222479 -207.917538)
			(xy 143.230599 -207.972714) (xy 143.231108 -208.0006) (xy 143.230599 -208.028486) (xy 143.222479 -208.083662)
			(xy 143.206411 -208.137069) (xy 143.182739 -208.187566) (xy 143.151966 -208.234079) (xy 143.149282 -208.237074)
			(xy 147.63318 -208.237074) (xy 147.637251 -208.181452) (xy 147.649377 -208.127015) (xy 147.6693 -208.074924)
			(xy 147.696596 -208.026289) (xy 147.730682 -207.982146) (xy 147.770831 -207.943437) (xy 147.816189 -207.910986)
			(xy 147.865789 -207.885485) (xy 147.918573 -207.867478) (xy 147.973416 -207.857348) (xy 148.02915 -207.855311)
			(xy 148.084587 -207.861411) (xy 148.138544 -207.875517) (xy 148.189873 -207.897329) (xy 148.237479 -207.926383)
			(xy 148.280347 -207.962058) (xy 148.317564 -208.003595) (xy 148.348337 -208.050108) (xy 148.372009 -208.100605)
			(xy 148.388077 -208.154012) (xy 148.396197 -208.209188) (xy 148.396706 -208.237074) (xy 148.396197 -208.26496)
			(xy 148.388077 -208.320136) (xy 148.372009 -208.373543) (xy 148.348337 -208.42404) (xy 148.317564 -208.470553)
			(xy 148.280347 -208.51209) (xy 148.237479 -208.547765) (xy 148.189873 -208.576819) (xy 148.138544 -208.598631)
			(xy 148.084587 -208.612737) (xy 148.02915 -208.618837) (xy 147.973416 -208.6168) (xy 147.918573 -208.60667)
			(xy 147.865789 -208.588663) (xy 147.816189 -208.563162) (xy 147.770831 -208.530711) (xy 147.730682 -208.492002)
			(xy 147.696596 -208.447859) (xy 147.6693 -208.399224) (xy 147.649377 -208.347133) (xy 147.637251 -208.292696)
			(xy 147.63318 -208.237074) (xy 143.149282 -208.237074) (xy 143.114749 -208.275616) (xy 143.071881 -208.311291)
			(xy 143.024275 -208.340345) (xy 142.972946 -208.362157) (xy 142.918989 -208.376263) (xy 142.863552 -208.382363)
			(xy 142.807818 -208.380326) (xy 142.752975 -208.370196) (xy 142.700191 -208.352189) (xy 142.650591 -208.326688)
			(xy 142.605233 -208.294237) (xy 142.565084 -208.255528) (xy 142.530998 -208.211385) (xy 142.503702 -208.16275)
			(xy 142.483779 -208.110659) (xy 142.471653 -208.056222) (xy 142.467582 -208.0006) (xy 141.623754 -208.0006)
			(xy 141.634495 -208.007155) (xy 141.677363 -208.04283) (xy 141.71458 -208.084367) (xy 141.745353 -208.13088)
			(xy 141.769025 -208.181377) (xy 141.785093 -208.234784) (xy 141.793213 -208.28996) (xy 141.793722 -208.317846)
			(xy 141.793213 -208.345732) (xy 141.785093 -208.400908) (xy 141.769025 -208.454315) (xy 141.745353 -208.504812)
			(xy 141.71458 -208.551325) (xy 141.677363 -208.592862) (xy 141.634495 -208.628537) (xy 141.586889 -208.657591)
			(xy 141.53556 -208.679403) (xy 141.481603 -208.693509) (xy 141.426166 -208.699609) (xy 141.370432 -208.697572)
			(xy 141.315589 -208.687442) (xy 141.262805 -208.669435) (xy 141.213205 -208.643934) (xy 141.167847 -208.611483)
			(xy 141.127698 -208.572774) (xy 141.093612 -208.528631) (xy 141.066316 -208.479996) (xy 141.046393 -208.427905)
			(xy 141.034267 -208.373468) (xy 141.030196 -208.317846) (xy 132.802933 -208.317846) (xy 132.810649 -208.329508)
			(xy 132.834321 -208.380005) (xy 132.850389 -208.433412) (xy 132.858509 -208.488588) (xy 132.859018 -208.516474)
			(xy 132.858509 -208.54436) (xy 132.850389 -208.599536) (xy 132.834321 -208.652943) (xy 132.810649 -208.70344)
			(xy 132.779876 -208.749953) (xy 132.742659 -208.79149) (xy 132.699791 -208.827165) (xy 132.652185 -208.856219)
			(xy 132.600856 -208.878031) (xy 132.546899 -208.892137) (xy 132.491462 -208.898237) (xy 132.435728 -208.8962)
			(xy 132.380885 -208.88607) (xy 132.328101 -208.868063) (xy 132.278501 -208.842562) (xy 132.233143 -208.810111)
			(xy 132.192994 -208.771402) (xy 132.158908 -208.727259) (xy 132.131612 -208.678624) (xy 132.111689 -208.626533)
			(xy 132.099563 -208.572096) (xy 132.095492 -208.516474) (xy 123.645748 -208.516474) (xy 123.621577 -208.536589)
			(xy 123.573971 -208.565643) (xy 123.522642 -208.587455) (xy 123.468685 -208.601561) (xy 123.413248 -208.607661)
			(xy 123.357514 -208.605624) (xy 123.302671 -208.595494) (xy 123.249887 -208.577487) (xy 123.200287 -208.551986)
			(xy 123.154929 -208.519535) (xy 123.11478 -208.480826) (xy 123.080694 -208.436683) (xy 123.053398 -208.388048)
			(xy 123.033475 -208.335957) (xy 123.021349 -208.28152) (xy 123.017278 -208.225898) (xy 120.408584 -208.225898)
			(xy 120.431462 -208.231879) (xy 120.482791 -208.253691) (xy 120.530397 -208.282745) (xy 120.573265 -208.31842)
			(xy 120.610482 -208.359957) (xy 120.641255 -208.40647) (xy 120.664927 -208.456967) (xy 120.680995 -208.510374)
			(xy 120.689115 -208.56555) (xy 120.689624 -208.593436) (xy 120.689115 -208.621322) (xy 120.680995 -208.676498)
			(xy 120.664927 -208.729905) (xy 120.641255 -208.780402) (xy 120.610482 -208.826915) (xy 120.573265 -208.868452)
			(xy 120.530397 -208.904127) (xy 120.482791 -208.933181) (xy 120.431462 -208.954993) (xy 120.377505 -208.969099)
			(xy 120.322068 -208.975199) (xy 120.266334 -208.973162) (xy 120.211491 -208.963032) (xy 120.158707 -208.945025)
			(xy 120.109107 -208.919524) (xy 120.063749 -208.887073) (xy 120.0236 -208.848364) (xy 119.989514 -208.804221)
			(xy 119.962218 -208.755586) (xy 119.942295 -208.703495) (xy 119.930169 -208.649058) (xy 119.926098 -208.593436)
			(xy 91.337384 -208.593436) (xy 91.337384 -208.99247) (xy 123.96927 -208.99247) (xy 123.973341 -208.936848)
			(xy 123.985467 -208.882411) (xy 124.00539 -208.83032) (xy 124.032686 -208.781685) (xy 124.066772 -208.737542)
			(xy 124.106921 -208.698833) (xy 124.152279 -208.666382) (xy 124.201879 -208.640881) (xy 124.254663 -208.622874)
			(xy 124.309506 -208.612744) (xy 124.36524 -208.610707) (xy 124.420677 -208.616807) (xy 124.474634 -208.630913)
			(xy 124.525963 -208.652725) (xy 124.573569 -208.681779) (xy 124.616437 -208.717454) (xy 124.653654 -208.758991)
			(xy 124.684427 -208.805504) (xy 124.708099 -208.856001) (xy 124.724167 -208.909408) (xy 124.732204 -208.964022)
			(xy 134.571484 -208.964022) (xy 134.575555 -208.9084) (xy 134.587681 -208.853963) (xy 134.607604 -208.801872)
			(xy 134.6349 -208.753237) (xy 134.668986 -208.709094) (xy 134.709135 -208.670385) (xy 134.754493 -208.637934)
			(xy 134.804093 -208.612433) (xy 134.856877 -208.594426) (xy 134.91172 -208.584296) (xy 134.967454 -208.582259)
			(xy 135.022891 -208.588359) (xy 135.076848 -208.602465) (xy 135.128177 -208.624277) (xy 135.175783 -208.653331)
			(xy 135.218651 -208.689006) (xy 135.255868 -208.730543) (xy 135.286641 -208.777056) (xy 135.310313 -208.827553)
			(xy 135.326381 -208.88096) (xy 135.334501 -208.936136) (xy 135.33501 -208.964022) (xy 135.334501 -208.991908)
			(xy 135.326381 -209.047084) (xy 135.316524 -209.079846) (xy 137.982196 -209.079846) (xy 137.986267 -209.024224)
			(xy 137.998393 -208.969787) (xy 138.018316 -208.917696) (xy 138.045612 -208.869061) (xy 138.079698 -208.824918)
			(xy 138.119847 -208.786209) (xy 138.165205 -208.753758) (xy 138.214805 -208.728257) (xy 138.267589 -208.71025)
			(xy 138.322432 -208.70012) (xy 138.378166 -208.698083) (xy 138.433603 -208.704183) (xy 138.48756 -208.718289)
			(xy 138.538889 -208.740101) (xy 138.586495 -208.769155) (xy 138.629363 -208.80483) (xy 138.66658 -208.846367)
			(xy 138.697353 -208.89288) (xy 138.721025 -208.943377) (xy 138.737093 -208.996784) (xy 138.745213 -209.05196)
			(xy 138.745722 -209.079846) (xy 138.74569 -209.081624) (xy 138.927838 -209.081624) (xy 138.931909 -209.026002)
			(xy 138.944035 -208.971565) (xy 138.963958 -208.919474) (xy 138.991254 -208.870839) (xy 139.02534 -208.826696)
			(xy 139.065489 -208.787987) (xy 139.110847 -208.755536) (xy 139.160447 -208.730035) (xy 139.213231 -208.712028)
			(xy 139.268074 -208.701898) (xy 139.323808 -208.699861) (xy 139.379245 -208.705961) (xy 139.433202 -208.720067)
			(xy 139.484531 -208.741879) (xy 139.532137 -208.770933) (xy 139.575005 -208.806608) (xy 139.592242 -208.825846)
			(xy 141.792196 -208.825846) (xy 141.796267 -208.770224) (xy 141.808393 -208.715787) (xy 141.828316 -208.663696)
			(xy 141.855612 -208.615061) (xy 141.889698 -208.570918) (xy 141.929847 -208.532209) (xy 141.975205 -208.499758)
			(xy 142.024805 -208.474257) (xy 142.077589 -208.45625) (xy 142.132432 -208.44612) (xy 142.188166 -208.444083)
			(xy 142.243603 -208.450183) (xy 142.29756 -208.464289) (xy 142.348889 -208.486101) (xy 142.396495 -208.515155)
			(xy 142.439363 -208.55083) (xy 142.47658 -208.592367) (xy 142.507353 -208.63888) (xy 142.531025 -208.689377)
			(xy 142.547093 -208.742784) (xy 142.555213 -208.79796) (xy 142.555722 -208.825846) (xy 142.555213 -208.853732)
			(xy 142.547093 -208.908908) (xy 142.531025 -208.962315) (xy 142.507353 -209.012812) (xy 142.47658 -209.059325)
			(xy 142.439363 -209.100862) (xy 142.396495 -209.136537) (xy 142.35454 -209.162142) (xy 147.232114 -209.162142)
			(xy 147.236185 -209.10652) (xy 147.248311 -209.052083) (xy 147.268234 -208.999992) (xy 147.29553 -208.951357)
			(xy 147.329616 -208.907214) (xy 147.369765 -208.868505) (xy 147.415123 -208.836054) (xy 147.464723 -208.810553)
			(xy 147.517507 -208.792546) (xy 147.57235 -208.782416) (xy 147.628084 -208.780379) (xy 147.683521 -208.786479)
			(xy 147.737478 -208.800585) (xy 147.788807 -208.822397) (xy 147.836413 -208.851451) (xy 147.879281 -208.887126)
			(xy 147.916498 -208.928663) (xy 147.947271 -208.975176) (xy 147.970943 -209.025673) (xy 147.987011 -209.07908)
			(xy 147.995131 -209.134256) (xy 147.99564 -209.162142) (xy 147.995131 -209.190028) (xy 147.987011 -209.245204)
			(xy 147.970943 -209.298611) (xy 147.947271 -209.349108) (xy 147.916498 -209.395621) (xy 147.879281 -209.437158)
			(xy 147.836413 -209.472833) (xy 147.788807 -209.501887) (xy 147.737478 -209.523699) (xy 147.683521 -209.537805)
			(xy 147.628084 -209.543905) (xy 147.57235 -209.541868) (xy 147.517507 -209.531738) (xy 147.464723 -209.513731)
			(xy 147.415123 -209.48823) (xy 147.369765 -209.455779) (xy 147.329616 -209.41707) (xy 147.29553 -209.372927)
			(xy 147.268234 -209.324292) (xy 147.248311 -209.272201) (xy 147.236185 -209.217764) (xy 147.232114 -209.162142)
			(xy 142.35454 -209.162142) (xy 142.348889 -209.165591) (xy 142.29756 -209.187403) (xy 142.243603 -209.201509)
			(xy 142.188166 -209.207609) (xy 142.132432 -209.205572) (xy 142.077589 -209.195442) (xy 142.024805 -209.177435)
			(xy 141.975205 -209.151934) (xy 141.929847 -209.119483) (xy 141.889698 -209.080774) (xy 141.855612 -209.036631)
			(xy 141.828316 -208.987996) (xy 141.808393 -208.935905) (xy 141.796267 -208.881468) (xy 141.792196 -208.825846)
			(xy 139.592242 -208.825846) (xy 139.612222 -208.848145) (xy 139.642995 -208.894658) (xy 139.666667 -208.945155)
			(xy 139.682735 -208.998562) (xy 139.690855 -209.053738) (xy 139.691364 -209.081624) (xy 139.690855 -209.10951)
			(xy 139.682735 -209.164686) (xy 139.666667 -209.218093) (xy 139.642995 -209.26859) (xy 139.612222 -209.315103)
			(xy 139.575005 -209.35664) (xy 139.532137 -209.392315) (xy 139.484531 -209.421369) (xy 139.433202 -209.443181)
			(xy 139.379245 -209.457287) (xy 139.323808 -209.463387) (xy 139.268074 -209.46135) (xy 139.213231 -209.45122)
			(xy 139.160447 -209.433213) (xy 139.110847 -209.407712) (xy 139.065489 -209.375261) (xy 139.02534 -209.336552)
			(xy 138.991254 -209.292409) (xy 138.963958 -209.243774) (xy 138.944035 -209.191683) (xy 138.931909 -209.137246)
			(xy 138.927838 -209.081624) (xy 138.74569 -209.081624) (xy 138.745213 -209.107732) (xy 138.737093 -209.162908)
			(xy 138.721025 -209.216315) (xy 138.697353 -209.266812) (xy 138.66658 -209.313325) (xy 138.629363 -209.354862)
			(xy 138.586495 -209.390537) (xy 138.538889 -209.419591) (xy 138.48756 -209.441403) (xy 138.433603 -209.455509)
			(xy 138.378166 -209.461609) (xy 138.322432 -209.459572) (xy 138.267589 -209.449442) (xy 138.214805 -209.431435)
			(xy 138.165205 -209.405934) (xy 138.119847 -209.373483) (xy 138.079698 -209.334774) (xy 138.045612 -209.290631)
			(xy 138.018316 -209.241996) (xy 137.998393 -209.189905) (xy 137.986267 -209.135468) (xy 137.982196 -209.079846)
			(xy 135.316524 -209.079846) (xy 135.310313 -209.100491) (xy 135.286641 -209.150988) (xy 135.255868 -209.197501)
			(xy 135.218651 -209.239038) (xy 135.175783 -209.274713) (xy 135.128177 -209.303767) (xy 135.076848 -209.325579)
			(xy 135.022891 -209.339685) (xy 134.967454 -209.345785) (xy 134.91172 -209.343748) (xy 134.856877 -209.333618)
			(xy 134.804093 -209.315611) (xy 134.754493 -209.29011) (xy 134.709135 -209.257659) (xy 134.668986 -209.21895)
			(xy 134.6349 -209.174807) (xy 134.607604 -209.126172) (xy 134.587681 -209.074081) (xy 134.575555 -209.019644)
			(xy 134.571484 -208.964022) (xy 124.732204 -208.964022) (xy 124.732287 -208.964584) (xy 124.732796 -208.99247)
			(xy 124.732287 -209.020356) (xy 124.724167 -209.075532) (xy 124.708099 -209.128939) (xy 124.684427 -209.179436)
			(xy 124.653654 -209.225949) (xy 124.616437 -209.267486) (xy 124.573569 -209.303161) (xy 124.525963 -209.332215)
			(xy 124.474634 -209.354027) (xy 124.420677 -209.368133) (xy 124.36524 -209.374233) (xy 124.309506 -209.372196)
			(xy 124.254663 -209.362066) (xy 124.201879 -209.344059) (xy 124.152279 -209.318558) (xy 124.106921 -209.286107)
			(xy 124.066772 -209.247398) (xy 124.032686 -209.203255) (xy 124.00539 -209.15462) (xy 123.985467 -209.102529)
			(xy 123.973341 -209.048092) (xy 123.96927 -208.99247) (xy 91.337384 -208.99247) (xy 91.337384 -209.471006)
			(xy 128.204466 -209.471006) (xy 128.208537 -209.415384) (xy 128.220663 -209.360947) (xy 128.240586 -209.308856)
			(xy 128.267882 -209.260221) (xy 128.301968 -209.216078) (xy 128.342117 -209.177369) (xy 128.387475 -209.144918)
			(xy 128.437075 -209.119417) (xy 128.489859 -209.10141) (xy 128.544702 -209.09128) (xy 128.600436 -209.089243)
			(xy 128.655873 -209.095343) (xy 128.70983 -209.109449) (xy 128.761159 -209.131261) (xy 128.808765 -209.160315)
			(xy 128.851633 -209.19599) (xy 128.88885 -209.237527) (xy 128.919623 -209.28404) (xy 128.943295 -209.334537)
			(xy 128.959363 -209.387944) (xy 128.964971 -209.426048) (xy 129.072892 -209.426048) (xy 129.076963 -209.370426)
			(xy 129.089089 -209.315989) (xy 129.109012 -209.263898) (xy 129.136308 -209.215263) (xy 129.170394 -209.17112)
			(xy 129.210543 -209.132411) (xy 129.255901 -209.09996) (xy 129.305501 -209.074459) (xy 129.358285 -209.056452)
			(xy 129.413128 -209.046322) (xy 129.468862 -209.044285) (xy 129.524299 -209.050385) (xy 129.578256 -209.064491)
			(xy 129.629585 -209.086303) (xy 129.677191 -209.115357) (xy 129.720059 -209.151032) (xy 129.757276 -209.192569)
			(xy 129.788049 -209.239082) (xy 129.811721 -209.289579) (xy 129.827789 -209.342986) (xy 129.835909 -209.398162)
			(xy 129.836418 -209.426048) (xy 129.835909 -209.453934) (xy 129.827789 -209.50911) (xy 129.811721 -209.562517)
			(xy 129.788049 -209.613014) (xy 129.757276 -209.659527) (xy 129.720059 -209.701064) (xy 129.677191 -209.736739)
			(xy 129.629585 -209.765793) (xy 129.578256 -209.787605) (xy 129.524299 -209.801711) (xy 129.468862 -209.807811)
			(xy 129.413128 -209.805774) (xy 129.358285 -209.795644) (xy 129.305501 -209.777637) (xy 129.255901 -209.752136)
			(xy 129.210543 -209.719685) (xy 129.170394 -209.680976) (xy 129.136308 -209.636833) (xy 129.109012 -209.588198)
			(xy 129.089089 -209.536107) (xy 129.076963 -209.48167) (xy 129.072892 -209.426048) (xy 128.964971 -209.426048)
			(xy 128.967483 -209.44312) (xy 128.967992 -209.471006) (xy 128.967483 -209.498892) (xy 128.959363 -209.554068)
			(xy 128.943295 -209.607475) (xy 128.919623 -209.657972) (xy 128.88885 -209.704485) (xy 128.851633 -209.746022)
			(xy 128.808765 -209.781697) (xy 128.761159 -209.810751) (xy 128.70983 -209.832563) (xy 128.655873 -209.846669)
			(xy 128.600436 -209.852769) (xy 128.544702 -209.850732) (xy 128.489859 -209.840602) (xy 128.437075 -209.822595)
			(xy 128.387475 -209.797094) (xy 128.342117 -209.764643) (xy 128.301968 -209.725934) (xy 128.267882 -209.681791)
			(xy 128.240586 -209.633156) (xy 128.220663 -209.581065) (xy 128.208537 -209.526628) (xy 128.204466 -209.471006)
			(xy 91.337384 -209.471006) (xy 91.337384 -211.250022) (xy 104.08031 -211.250022) (xy 104.080787 -211.222652)
			(xy 104.088601 -211.168473) (xy 104.104088 -211.11597) (xy 104.126927 -211.066223) (xy 104.15665 -211.020256)
			(xy 104.17429 -210.999324) (xy 104.180386 -210.992212) (xy 104.183434 -210.98383) (xy 104.184955 -210.979542)
			(xy 104.186614 -210.970598) (xy 104.186736 -210.96605) (xy 104.186736 -210.898994) (xy 104.186621 -210.894445)
			(xy 104.18496 -210.8855) (xy 104.183434 -210.881214) (xy 104.180386 -210.872832) (xy 104.17429 -210.86572)
			(xy 104.156645 -210.844793) (xy 104.126935 -210.798818) (xy 104.1041 -210.74907) (xy 104.08861 -210.696568)
			(xy 104.080783 -210.642391) (xy 104.08031 -210.615022) (xy 104.080776 -210.587769) (xy 104.08853 -210.533817)
			(xy 104.103884 -210.481518) (xy 104.126526 -210.431937) (xy 104.155993 -210.386083) (xy 104.191687 -210.344889)
			(xy 104.23288 -210.309195) (xy 104.278733 -210.279728) (xy 104.328314 -210.257086) (xy 104.380613 -210.241731)
			(xy 104.434565 -210.233976) (xy 104.461818 -210.233514) (xy 104.489189 -210.233966) (xy 104.543369 -210.241787)
			(xy 104.595872 -210.257279) (xy 104.645619 -210.280124) (xy 104.691585 -210.309851) (xy 104.712516 -210.327494)
			(xy 104.719628 -210.33359) (xy 104.72801 -210.336638) (xy 104.732303 -210.338144) (xy 104.741243 -210.339812)
			(xy 104.74579 -210.33994) (xy 104.812846 -210.33994) (xy 104.817395 -210.339829) (xy 104.826339 -210.338162)
			(xy 104.830626 -210.336638) (xy 104.839008 -210.33359) (xy 104.84612 -210.327494) (xy 104.867053 -210.309853)
			(xy 104.913021 -210.280129) (xy 104.962767 -210.257283) (xy 105.015269 -210.241787) (xy 105.069447 -210.233958)
			(xy 105.124189 -210.233958) (xy 105.178367 -210.241787) (xy 105.230869 -210.257283) (xy 105.280615 -210.280129)
			(xy 105.326583 -210.309853) (xy 105.347516 -210.327494) (xy 105.354628 -210.33359) (xy 105.36301 -210.336638)
			(xy 105.367303 -210.338144) (xy 105.376243 -210.339812) (xy 105.38079 -210.33994) (xy 105.447846 -210.33994)
			(xy 105.452395 -210.339829) (xy 105.461339 -210.338162) (xy 105.465626 -210.336638) (xy 105.474008 -210.33359)
			(xy 105.48112 -210.327494) (xy 105.502071 -210.309878) (xy 105.548038 -210.280163) (xy 105.597781 -210.257323)
			(xy 105.650278 -210.241826) (xy 105.70445 -210.233992) (xy 105.731818 -210.233514) (xy 105.759072 -210.233938)
			(xy 105.813026 -210.241698) (xy 105.865326 -210.257058) (xy 105.914908 -210.279704) (xy 105.960762 -210.309176)
			(xy 106.001955 -210.344874) (xy 106.037648 -210.38607) (xy 106.067115 -210.431928) (xy 106.068818 -210.435658)
			(xy 121.39873 -210.435658) (xy 121.406486 -210.381703) (xy 121.421841 -210.329401) (xy 121.444484 -210.279817)
			(xy 121.473953 -210.233959) (xy 121.509648 -210.192763) (xy 121.550842 -210.157065) (xy 121.596698 -210.127594)
			(xy 121.646281 -210.104949) (xy 121.698582 -210.08959) (xy 121.752537 -210.081831) (xy 121.779792 -210.081368)
			(xy 121.793428 -210.081466) (xy 121.820632 -210.083372) (xy 121.834148 -210.085178) (xy 121.847763 -210.086756)
			(xy 121.874943 -210.083277) (xy 121.900221 -210.072699) (xy 121.921777 -210.055782) (xy 121.938062 -210.033743)
			(xy 121.947903 -210.008169) (xy 121.950592 -209.980899) (xy 121.948702 -209.967322) (xy 121.946089 -209.951193)
			(xy 121.943288 -209.918636) (xy 121.943114 -209.902298) (xy 121.94358 -209.875047) (xy 121.951336 -209.821101)
			(xy 121.966691 -209.768807) (xy 121.989332 -209.71923) (xy 122.018798 -209.673381) (xy 122.054488 -209.632191)
			(xy 122.095678 -209.5965) (xy 122.141527 -209.567034) (xy 122.191103 -209.544393) (xy 122.243397 -209.529037)
			(xy 122.297343 -209.52128) (xy 122.351845 -209.521279) (xy 122.405792 -209.529035) (xy 122.458086 -209.544389)
			(xy 122.507662 -209.567028) (xy 122.553513 -209.596493) (xy 122.594703 -209.632183) (xy 122.630395 -209.673371)
			(xy 122.659862 -209.71922) (xy 122.682504 -209.768796) (xy 122.697861 -209.821089) (xy 122.705619 -209.875035)
			(xy 122.705621 -209.929537) (xy 122.70176 -209.9564) (xy 131.11429 -209.9564) (xy 131.118361 -209.900778)
			(xy 131.130487 -209.846341) (xy 131.15041 -209.79425) (xy 131.177706 -209.745615) (xy 131.211792 -209.701472)
			(xy 131.251941 -209.662763) (xy 131.297299 -209.630312) (xy 131.346899 -209.604811) (xy 131.399683 -209.586804)
			(xy 131.454526 -209.576674) (xy 131.51026 -209.574637) (xy 131.565697 -209.580737) (xy 131.619654 -209.594843)
			(xy 131.670983 -209.616655) (xy 131.718589 -209.645709) (xy 131.761457 -209.681384) (xy 131.798674 -209.722921)
			(xy 131.829447 -209.769434) (xy 131.853119 -209.819931) (xy 131.869187 -209.873338) (xy 131.877307 -209.928514)
			(xy 131.877816 -209.9564) (xy 131.877677 -209.96402) (xy 134.571484 -209.96402) (xy 134.575555 -209.908398)
			(xy 134.587681 -209.853961) (xy 134.607604 -209.80187) (xy 134.6349 -209.753235) (xy 134.668986 -209.709092)
			(xy 134.709135 -209.670383) (xy 134.754493 -209.637932) (xy 134.804093 -209.612431) (xy 134.856877 -209.594424)
			(xy 134.91172 -209.584294) (xy 134.967454 -209.582257) (xy 135.022891 -209.588357) (xy 135.076848 -209.602463)
			(xy 135.128177 -209.624275) (xy 135.175783 -209.653329) (xy 135.218651 -209.689004) (xy 135.255868 -209.730541)
			(xy 135.286641 -209.777054) (xy 135.310313 -209.827551) (xy 135.326381 -209.880958) (xy 135.334501 -209.936134)
			(xy 135.33501 -209.96402) (xy 135.334501 -209.991906) (xy 135.326381 -210.047082) (xy 135.310313 -210.100489)
			(xy 135.286641 -210.150986) (xy 135.255868 -210.197499) (xy 135.218651 -210.239036) (xy 135.175783 -210.274711)
			(xy 135.128177 -210.303765) (xy 135.076848 -210.325577) (xy 135.022891 -210.339683) (xy 134.967454 -210.345783)
			(xy 134.91172 -210.343746) (xy 134.856877 -210.333616) (xy 134.804093 -210.315609) (xy 134.754493 -210.290108)
			(xy 134.709135 -210.257657) (xy 134.668986 -210.218948) (xy 134.6349 -210.174805) (xy 134.607604 -210.12617)
			(xy 134.587681 -210.074079) (xy 134.575555 -210.019642) (xy 134.571484 -209.96402) (xy 131.877677 -209.96402)
			(xy 131.877307 -209.984286) (xy 131.869187 -210.039462) (xy 131.853119 -210.092869) (xy 131.829447 -210.143366)
			(xy 131.798674 -210.189879) (xy 131.761457 -210.231416) (xy 131.718589 -210.267091) (xy 131.670983 -210.296145)
			(xy 131.619654 -210.317957) (xy 131.565697 -210.332063) (xy 131.51026 -210.338163) (xy 131.454526 -210.336126)
			(xy 131.399683 -210.325996) (xy 131.346899 -210.307989) (xy 131.297299 -210.282488) (xy 131.251941 -210.250037)
			(xy 131.211792 -210.211328) (xy 131.177706 -210.167185) (xy 131.15041 -210.11855) (xy 131.130487 -210.066459)
			(xy 131.118361 -210.012022) (xy 131.11429 -209.9564) (xy 122.70176 -209.9564) (xy 122.697867 -209.983484)
			(xy 122.682514 -210.035778) (xy 122.659876 -210.085355) (xy 122.630412 -210.131206) (xy 122.594723 -210.172397)
			(xy 122.553535 -210.20809) (xy 122.507687 -210.237558) (xy 122.458112 -210.260202) (xy 122.405819 -210.275559)
			(xy 122.351873 -210.283319) (xy 122.324622 -210.283806) (xy 122.310986 -210.283707) (xy 122.283782 -210.281802)
			(xy 122.270266 -210.279996) (xy 122.256648 -210.278462) (xy 122.229474 -210.281937) (xy 122.204201 -210.29251)
			(xy 122.182647 -210.309419) (xy 122.166363 -210.331449) (xy 122.15652 -210.357015) (xy 122.153826 -210.384278)
			(xy 122.155712 -210.397852) (xy 122.158335 -210.41398) (xy 122.161129 -210.446537) (xy 122.1613 -210.462876)
			(xy 122.160871 -210.490131) (xy 122.153117 -210.544086) (xy 122.137763 -210.596389) (xy 122.119152 -210.637147)
			(xy 124.49942 -210.637147) (xy 124.49942 -210.582653) (xy 124.507175 -210.528714) (xy 124.522527 -210.476428)
			(xy 124.545163 -210.426858) (xy 124.574624 -210.381014) (xy 124.610308 -210.339829) (xy 124.65149 -210.304142)
			(xy 124.697331 -210.274678) (xy 124.746899 -210.252037) (xy 124.799185 -210.236681) (xy 124.853123 -210.228922)
			(xy 124.88037 -210.228434) (xy 124.908018 -210.228961) (xy 124.962738 -210.236927) (xy 125.015734 -210.252712)
			(xy 125.065895 -210.275983) (xy 125.11217 -210.306254) (xy 125.153589 -210.34289) (xy 125.189283 -210.385123)
			(xy 125.196732 -210.39709) (xy 137.064748 -210.39709) (xy 137.068819 -210.341468) (xy 137.080945 -210.287031)
			(xy 137.100868 -210.23494) (xy 137.128164 -210.186305) (xy 137.16225 -210.142162) (xy 137.202399 -210.103453)
			(xy 137.247757 -210.071002) (xy 137.297357 -210.045501) (xy 137.350141 -210.027494) (xy 137.404984 -210.017364)
			(xy 137.460718 -210.015327) (xy 137.516155 -210.021427) (xy 137.570112 -210.035533) (xy 137.621441 -210.057345)
			(xy 137.669047 -210.086399) (xy 137.711915 -210.122074) (xy 137.749132 -210.163611) (xy 137.779905 -210.210124)
			(xy 137.794799 -210.241896) (xy 143.716246 -210.241896) (xy 143.720317 -210.186274) (xy 143.732443 -210.131837)
			(xy 143.752366 -210.079746) (xy 143.779662 -210.031111) (xy 143.813748 -209.986968) (xy 143.853897 -209.948259)
			(xy 143.899255 -209.915808) (xy 143.948855 -209.890307) (xy 144.001639 -209.8723) (xy 144.056482 -209.86217)
			(xy 144.112216 -209.860133) (xy 144.167653 -209.866233) (xy 144.22161 -209.880339) (xy 144.272939 -209.902151)
			(xy 144.320545 -209.931205) (xy 144.363413 -209.96688) (xy 144.40063 -210.008417) (xy 144.431403 -210.05493)
			(xy 144.455075 -210.105427) (xy 144.471143 -210.158834) (xy 144.479263 -210.21401) (xy 144.479772 -210.241896)
			(xy 144.479263 -210.269782) (xy 144.471143 -210.324958) (xy 144.455075 -210.378365) (xy 144.431403 -210.428862)
			(xy 144.40063 -210.475375) (xy 144.363413 -210.516912) (xy 144.320545 -210.552587) (xy 144.272939 -210.581641)
			(xy 144.22161 -210.603453) (xy 144.167653 -210.617559) (xy 144.112216 -210.623659) (xy 144.056482 -210.621622)
			(xy 144.001639 -210.611492) (xy 143.948855 -210.593485) (xy 143.899255 -210.567984) (xy 143.853897 -210.535533)
			(xy 143.813748 -210.496824) (xy 143.779662 -210.452681) (xy 143.752366 -210.404046) (xy 143.732443 -210.351955)
			(xy 143.720317 -210.297518) (xy 143.716246 -210.241896) (xy 137.794799 -210.241896) (xy 137.803577 -210.260621)
			(xy 137.819645 -210.314028) (xy 137.827765 -210.369204) (xy 137.828274 -210.39709) (xy 137.827765 -210.424976)
			(xy 137.819645 -210.480152) (xy 137.803577 -210.533559) (xy 137.779905 -210.584056) (xy 137.749132 -210.630569)
			(xy 137.711915 -210.672106) (xy 137.669047 -210.707781) (xy 137.621441 -210.736835) (xy 137.570112 -210.758647)
			(xy 137.516155 -210.772753) (xy 137.465344 -210.778344) (xy 139.34008 -210.778344) (xy 139.344151 -210.722722)
			(xy 139.356277 -210.668285) (xy 139.3762 -210.616194) (xy 139.403496 -210.567559) (xy 139.437582 -210.523416)
			(xy 139.477731 -210.484707) (xy 139.523089 -210.452256) (xy 139.572689 -210.426755) (xy 139.625473 -210.408748)
			(xy 139.680316 -210.398618) (xy 139.73605 -210.396581) (xy 139.791487 -210.402681) (xy 139.845444 -210.416787)
			(xy 139.896773 -210.438599) (xy 139.944379 -210.467653) (xy 139.987247 -210.503328) (xy 140.024464 -210.544865)
			(xy 140.055237 -210.591378) (xy 140.078909 -210.641875) (xy 140.094977 -210.695282) (xy 140.103097 -210.750458)
			(xy 140.103606 -210.778344) (xy 140.103097 -210.80623) (xy 140.101482 -210.817206) (xy 140.924786 -210.817206)
			(xy 140.928857 -210.761584) (xy 140.940983 -210.707147) (xy 140.960906 -210.655056) (xy 140.988202 -210.606421)
			(xy 141.022288 -210.562278) (xy 141.062437 -210.523569) (xy 141.107795 -210.491118) (xy 141.157395 -210.465617)
			(xy 141.210179 -210.44761) (xy 141.265022 -210.43748) (xy 141.320756 -210.435443) (xy 141.376193 -210.441543)
			(xy 141.43015 -210.455649) (xy 141.481479 -210.477461) (xy 141.529085 -210.506515) (xy 141.571953 -210.54219)
			(xy 141.60917 -210.583727) (xy 141.639943 -210.63024) (xy 141.663615 -210.680737) (xy 141.679683 -210.734144)
			(xy 141.687803 -210.78932) (xy 141.688312 -210.817206) (xy 141.687815 -210.844453) (xy 141.925761 -210.844453)
			(xy 141.925761 -210.789947) (xy 141.933518 -210.735997) (xy 141.948874 -210.6837) (xy 141.971516 -210.634121)
			(xy 142.000984 -210.588268) (xy 142.036677 -210.547076) (xy 142.07787 -210.511383) (xy 142.123722 -210.481915)
			(xy 142.173302 -210.459273) (xy 142.225599 -210.443918) (xy 142.279549 -210.436161) (xy 142.306802 -210.435698)
			(xy 142.333057 -210.436163) (xy 142.385073 -210.443349) (xy 142.435613 -210.457597) (xy 142.483722 -210.478638)
			(xy 142.528493 -210.506077) (xy 142.569079 -210.539393) (xy 142.587218 -210.55838) (xy 142.594584 -210.566508)
			(xy 142.604236 -210.570572) (xy 142.60921 -210.572551) (xy 142.619711 -210.574609) (xy 142.625064 -210.574636)
			(xy 142.70101 -210.57362) (xy 142.705074 -210.573366) (xy 142.709416 -210.572875) (xy 142.717846 -210.570572)
			(xy 142.721838 -210.568794) (xy 142.72641 -210.566508) (xy 142.735046 -210.559904) (xy 142.738602 -210.55584)
			(xy 142.756788 -210.535505) (xy 142.798011 -210.499772) (xy 142.843901 -210.470271) (xy 142.893524 -210.447605)
			(xy 142.945869 -210.432236) (xy 142.999869 -210.424475) (xy 143.027146 -210.424014) (xy 143.054397 -210.424459)
			(xy 143.108343 -210.432221) (xy 143.160635 -210.447581) (xy 143.210209 -210.470226) (xy 143.256056 -210.499696)
			(xy 143.297243 -210.535389) (xy 143.332932 -210.576581) (xy 143.362396 -210.622431) (xy 143.385035 -210.672008)
			(xy 143.398656 -210.7184) (xy 145.236182 -210.7184) (xy 145.240253 -210.662778) (xy 145.252379 -210.608341)
			(xy 145.272302 -210.55625) (xy 145.299598 -210.507615) (xy 145.333684 -210.463472) (xy 145.373833 -210.424763)
			(xy 145.419191 -210.392312) (xy 145.468791 -210.366811) (xy 145.521575 -210.348804) (xy 145.576418 -210.338674)
			(xy 145.632152 -210.336637) (xy 145.687589 -210.342737) (xy 145.741546 -210.356843) (xy 145.792875 -210.378655)
			(xy 145.840481 -210.407709) (xy 145.883349 -210.443384) (xy 145.920566 -210.484921) (xy 145.951339 -210.531434)
			(xy 145.975011 -210.581931) (xy 145.975491 -210.583526) (xy 146.303236 -210.583526) (xy 146.307307 -210.527904)
			(xy 146.319433 -210.473467) (xy 146.339356 -210.421376) (xy 146.366652 -210.372741) (xy 146.400738 -210.328598)
			(xy 146.440887 -210.289889) (xy 146.486245 -210.257438) (xy 146.535845 -210.231937) (xy 146.588629 -210.21393)
			(xy 146.643472 -210.2038) (xy 146.699206 -210.201763) (xy 146.754643 -210.207863) (xy 146.8086 -210.221969)
			(xy 146.859929 -210.243781) (xy 146.907535 -210.272835) (xy 146.950403 -210.30851) (xy 146.98762 -210.350047)
			(xy 147.018393 -210.39656) (xy 147.042065 -210.447057) (xy 147.058133 -210.500464) (xy 147.066253 -210.55564)
			(xy 147.066762 -210.583526) (xy 147.066253 -210.611412) (xy 147.058133 -210.666588) (xy 147.042065 -210.719995)
			(xy 147.039955 -210.724496) (xy 148.970236 -210.724496) (xy 148.974307 -210.668874) (xy 148.986433 -210.614437)
			(xy 149.006356 -210.562346) (xy 149.033652 -210.513711) (xy 149.067738 -210.469568) (xy 149.107887 -210.430859)
			(xy 149.153245 -210.398408) (xy 149.202845 -210.372907) (xy 149.255629 -210.3549) (xy 149.310472 -210.34477)
			(xy 149.366206 -210.342733) (xy 149.421643 -210.348833) (xy 149.4756 -210.362939) (xy 149.526929 -210.384751)
			(xy 149.574535 -210.413805) (xy 149.617403 -210.44948) (xy 149.65462 -210.491017) (xy 149.685393 -210.53753)
			(xy 149.709065 -210.588027) (xy 149.725133 -210.641434) (xy 149.733253 -210.69661) (xy 149.733762 -210.724496)
			(xy 149.733253 -210.752382) (xy 149.725133 -210.807558) (xy 149.709065 -210.860965) (xy 149.685393 -210.911462)
			(xy 149.65462 -210.957975) (xy 149.617403 -210.999512) (xy 149.574535 -211.035187) (xy 149.526929 -211.064241)
			(xy 149.4756 -211.086053) (xy 149.421643 -211.100159) (xy 149.366206 -211.106259) (xy 149.310472 -211.104222)
			(xy 149.255629 -211.094092) (xy 149.202845 -211.076085) (xy 149.153245 -211.050584) (xy 149.107887 -211.018133)
			(xy 149.067738 -210.979424) (xy 149.033652 -210.935281) (xy 149.006356 -210.886646) (xy 148.986433 -210.834555)
			(xy 148.974307 -210.780118) (xy 148.970236 -210.724496) (xy 147.039955 -210.724496) (xy 147.018393 -210.770492)
			(xy 146.98762 -210.817005) (xy 146.950403 -210.858542) (xy 146.907535 -210.894217) (xy 146.859929 -210.923271)
			(xy 146.8086 -210.945083) (xy 146.754643 -210.959189) (xy 146.699206 -210.965289) (xy 146.643472 -210.963252)
			(xy 146.588629 -210.953122) (xy 146.535845 -210.935115) (xy 146.486245 -210.909614) (xy 146.440887 -210.877163)
			(xy 146.400738 -210.838454) (xy 146.366652 -210.794311) (xy 146.339356 -210.745676) (xy 146.319433 -210.693585)
			(xy 146.307307 -210.639148) (xy 146.303236 -210.583526) (xy 145.975491 -210.583526) (xy 145.991079 -210.635338)
			(xy 145.999199 -210.690514) (xy 145.999708 -210.7184) (xy 145.999199 -210.746286) (xy 145.991079 -210.801462)
			(xy 145.975011 -210.854869) (xy 145.951339 -210.905366) (xy 145.920566 -210.951879) (xy 145.883349 -210.993416)
			(xy 145.840481 -211.029091) (xy 145.792875 -211.058145) (xy 145.741546 -211.079957) (xy 145.687589 -211.094063)
			(xy 145.632152 -211.100163) (xy 145.576418 -211.098126) (xy 145.521575 -211.087996) (xy 145.468791 -211.069989)
			(xy 145.419191 -211.044488) (xy 145.373833 -211.012037) (xy 145.333684 -210.973328) (xy 145.299598 -210.929185)
			(xy 145.272302 -210.88055) (xy 145.252379 -210.828459) (xy 145.240253 -210.774022) (xy 145.236182 -210.7184)
			(xy 143.398656 -210.7184) (xy 143.400389 -210.724302) (xy 143.408144 -210.778249) (xy 143.408144 -210.832751)
			(xy 143.400389 -210.886698) (xy 143.385035 -210.938992) (xy 143.362396 -210.988569) (xy 143.332932 -211.034419)
			(xy 143.297243 -211.075611) (xy 143.256056 -211.111304) (xy 143.210209 -211.140774) (xy 143.160635 -211.163419)
			(xy 143.108343 -211.178779) (xy 143.054397 -211.186541) (xy 143.027146 -211.18703) (xy 143.000889 -211.186622)
			(xy 142.94887 -211.179429) (xy 142.898328 -211.165171) (xy 142.850218 -211.144118) (xy 142.805449 -211.116669)
			(xy 142.764866 -211.08334) (xy 142.74673 -211.064348) (xy 142.739364 -211.05622) (xy 142.729712 -211.052156)
			(xy 142.724743 -211.050162) (xy 142.714238 -211.048113) (xy 142.708884 -211.048092) (xy 142.632938 -211.049108)
			(xy 142.628874 -211.049362) (xy 142.624533 -211.049863) (xy 142.616103 -211.052159) (xy 142.61211 -211.053934)
			(xy 142.607538 -211.05622) (xy 142.598902 -211.062824) (xy 142.595346 -211.066888) (xy 142.57712 -211.087186)
			(xy 142.535907 -211.122925) (xy 142.490026 -211.152432) (xy 142.44041 -211.175105) (xy 142.388072 -211.190482)
			(xy 142.334077 -211.19825) (xy 142.306802 -211.198714) (xy 142.279549 -211.198239) (xy 142.225599 -211.190482)
			(xy 142.173302 -211.175127) (xy 142.123722 -211.152485) (xy 142.07787 -211.123017) (xy 142.036677 -211.087324)
			(xy 142.000984 -211.046132) (xy 141.971516 -211.000279) (xy 141.948874 -210.9507) (xy 141.933518 -210.898403)
			(xy 141.925761 -210.844453) (xy 141.687815 -210.844453) (xy 141.687803 -210.845092) (xy 141.679683 -210.900268)
			(xy 141.663615 -210.953675) (xy 141.639943 -211.004172) (xy 141.60917 -211.050685) (xy 141.571953 -211.092222)
			(xy 141.529085 -211.127897) (xy 141.481479 -211.156951) (xy 141.43015 -211.178763) (xy 141.376193 -211.192869)
			(xy 141.320756 -211.198969) (xy 141.265022 -211.196932) (xy 141.210179 -211.186802) (xy 141.157395 -211.168795)
			(xy 141.107795 -211.143294) (xy 141.062437 -211.110843) (xy 141.022288 -211.072134) (xy 140.988202 -211.027991)
			(xy 140.960906 -210.979356) (xy 140.940983 -210.927265) (xy 140.928857 -210.872828) (xy 140.924786 -210.817206)
			(xy 140.101482 -210.817206) (xy 140.094977 -210.861406) (xy 140.078909 -210.914813) (xy 140.055237 -210.96531)
			(xy 140.024464 -211.011823) (xy 139.987247 -211.05336) (xy 139.944379 -211.089035) (xy 139.896773 -211.118089)
			(xy 139.845444 -211.139901) (xy 139.791487 -211.154007) (xy 139.73605 -211.160107) (xy 139.680316 -211.15807)
			(xy 139.625473 -211.14794) (xy 139.572689 -211.129933) (xy 139.523089 -211.104432) (xy 139.477731 -211.071981)
			(xy 139.437582 -211.033272) (xy 139.403496 -210.989129) (xy 139.3762 -210.940494) (xy 139.356277 -210.888403)
			(xy 139.344151 -210.833966) (xy 139.34008 -210.778344) (xy 137.465344 -210.778344) (xy 137.460718 -210.778853)
			(xy 137.404984 -210.776816) (xy 137.350141 -210.766686) (xy 137.297357 -210.748679) (xy 137.247757 -210.723178)
			(xy 137.202399 -210.690727) (xy 137.16225 -210.652018) (xy 137.128164 -210.607875) (xy 137.100868 -210.55924)
			(xy 137.080945 -210.507149) (xy 137.068819 -210.452712) (xy 137.064748 -210.39709) (xy 125.196732 -210.39709)
			(xy 125.218505 -210.432067) (xy 125.240642 -210.48274) (xy 125.255229 -210.536077) (xy 125.259084 -210.56346)
			(xy 125.261501 -210.578433) (xy 125.273908 -210.60609) (xy 125.293884 -210.62889) (xy 125.31967 -210.644826)
			(xy 125.348997 -210.652495) (xy 125.379283 -210.651223) (xy 125.407863 -210.641122) (xy 125.420374 -210.632548)
			(xy 125.445175 -210.614849) (xy 125.499241 -210.58676) (xy 125.557087 -210.567632) (xy 125.61724 -210.557953)
			(xy 125.647704 -210.557364) (xy 125.647958 -210.557364) (xy 125.675211 -210.55788) (xy 125.729162 -210.565632)
			(xy 125.781461 -210.580983) (xy 125.831043 -210.603622) (xy 125.876898 -210.633086) (xy 125.918093 -210.668777)
			(xy 125.953788 -210.709968) (xy 125.983258 -210.75582) (xy 126.005902 -210.805399) (xy 126.021259 -210.857697)
			(xy 126.029017 -210.911647) (xy 126.029017 -210.966153) (xy 126.021259 -211.020103) (xy 126.005902 -211.072401)
			(xy 125.983258 -211.12198) (xy 125.953788 -211.167832) (xy 125.918093 -211.209023) (xy 125.876898 -211.244714)
			(xy 125.831043 -211.274178) (xy 125.781461 -211.296817) (xy 125.729162 -211.312168) (xy 125.675211 -211.31992)
			(xy 125.647958 -211.32038) (xy 125.620308 -211.319907) (xy 125.565587 -211.311931) (xy 125.512591 -211.296138)
			(xy 125.46243 -211.272859) (xy 125.416156 -211.242581) (xy 125.374738 -211.20594) (xy 125.339045 -211.163702)
			(xy 125.309824 -211.116754) (xy 125.287687 -211.066079) (xy 125.273099 -211.012738) (xy 125.269244 -210.985354)
			(xy 125.266777 -210.970392) (xy 125.254377 -210.94274) (xy 125.23441 -210.919943) (xy 125.208633 -210.904007)
			(xy 125.179315 -210.896335) (xy 125.149037 -210.897602) (xy 125.120463 -210.907696) (xy 125.107954 -210.916266)
			(xy 125.083146 -210.933955) (xy 125.029083 -210.962046) (xy 124.971238 -210.981176) (xy 124.911087 -210.990858)
			(xy 124.880624 -210.99145) (xy 124.88037 -210.99145) (xy 124.853123 -210.990878) (xy 124.799185 -210.983119)
			(xy 124.746899 -210.967763) (xy 124.697331 -210.945122) (xy 124.65149 -210.915658) (xy 124.610308 -210.879971)
			(xy 124.574624 -210.838786) (xy 124.545163 -210.792942) (xy 124.522527 -210.743372) (xy 124.507175 -210.691086)
			(xy 124.49942 -210.637147) (xy 122.119152 -210.637147) (xy 122.115121 -210.645974) (xy 122.085654 -210.691832)
			(xy 122.04996 -210.73303) (xy 122.008766 -210.768728) (xy 121.962911 -210.798201) (xy 121.913329 -210.820848)
			(xy 121.861028 -210.836208) (xy 121.807073 -210.843968) (xy 121.752564 -210.84397) (xy 121.698609 -210.836215)
			(xy 121.646306 -210.820861) (xy 121.596721 -210.798219) (xy 121.550864 -210.768751) (xy 121.509666 -210.733056)
			(xy 121.473969 -210.691862) (xy 121.444497 -210.646007) (xy 121.42185 -210.596424) (xy 121.406491 -210.544123)
			(xy 121.398732 -210.490168) (xy 121.39873 -210.435658) (xy 106.068818 -210.435658) (xy 106.089756 -210.481512)
			(xy 106.10511 -210.533813) (xy 106.112865 -210.587768) (xy 106.113326 -210.615022) (xy 106.112891 -210.642394)
			(xy 106.105068 -210.696575) (xy 106.089573 -210.749079) (xy 106.066724 -210.798825) (xy 106.036991 -210.84479)
			(xy 106.019346 -210.86572) (xy 106.01325 -210.872832) (xy 106.010202 -210.881214) (xy 106.008693 -210.885505)
			(xy 106.007027 -210.894447) (xy 106.0069 -210.898994) (xy 106.0069 -210.96605) (xy 106.007013 -210.970598)
			(xy 106.00868 -210.979542) (xy 106.010202 -210.98383) (xy 106.01325 -210.992212) (xy 106.019346 -210.999324)
			(xy 106.036955 -211.020281) (xy 106.066673 -211.066246) (xy 106.089516 -211.115987) (xy 106.105014 -211.168483)
			(xy 106.112849 -211.222654) (xy 106.113326 -211.250022) (xy 106.112843 -211.277273) (xy 106.105084 -211.33122)
			(xy 106.089727 -211.383514) (xy 106.067084 -211.43309) (xy 106.037617 -211.478939) (xy 106.001926 -211.520129)
			(xy 105.960736 -211.55582) (xy 105.914886 -211.585286) (xy 105.907065 -211.588858) (xy 125.9746 -211.588858)
			(xy 125.978671 -211.533236) (xy 125.990797 -211.478799) (xy 126.01072 -211.426708) (xy 126.038016 -211.378073)
			(xy 126.072102 -211.33393) (xy 126.112251 -211.295221) (xy 126.157609 -211.26277) (xy 126.207209 -211.237269)
			(xy 126.259993 -211.219262) (xy 126.314836 -211.209132) (xy 126.37057 -211.207095) (xy 126.426007 -211.213195)
			(xy 126.479964 -211.227301) (xy 126.531293 -211.249113) (xy 126.578899 -211.278167) (xy 126.621767 -211.313842)
			(xy 126.658984 -211.355379) (xy 126.689757 -211.401892) (xy 126.713429 -211.452389) (xy 126.729497 -211.505796)
			(xy 126.737617 -211.560972) (xy 126.738126 -211.588858) (xy 126.737617 -211.616744) (xy 126.729497 -211.67192)
			(xy 126.713429 -211.725327) (xy 126.689757 -211.775824) (xy 126.658984 -211.822337) (xy 126.621767 -211.863874)
			(xy 126.578899 -211.899549) (xy 126.531293 -211.928603) (xy 126.479964 -211.950415) (xy 126.426007 -211.964521)
			(xy 126.37057 -211.970621) (xy 126.314836 -211.968584) (xy 126.259993 -211.958454) (xy 126.207209 -211.940447)
			(xy 126.157609 -211.914946) (xy 126.112251 -211.882495) (xy 126.072102 -211.843786) (xy 126.038016 -211.799643)
			(xy 126.01072 -211.751008) (xy 125.990797 -211.698917) (xy 125.978671 -211.64448) (xy 125.9746 -211.588858)
			(xy 105.907065 -211.588858) (xy 105.86531 -211.607928) (xy 105.813016 -211.623285) (xy 105.759069 -211.631043)
			(xy 105.731818 -211.63153) (xy 105.704447 -211.63107) (xy 105.650267 -211.623254) (xy 105.597763 -211.607764)
			(xy 105.548017 -211.58492) (xy 105.502051 -211.555193) (xy 105.48112 -211.53755) (xy 105.474008 -211.531454)
			(xy 105.465626 -211.528406) (xy 105.461339 -211.526882) (xy 105.452394 -211.525226) (xy 105.447846 -211.525104)
			(xy 105.38079 -211.525104) (xy 105.376242 -211.525227) (xy 105.367298 -211.526887) (xy 105.36301 -211.528406)
			(xy 105.354628 -211.531454) (xy 105.347516 -211.53755) (xy 105.326583 -211.555191) (xy 105.280615 -211.584915)
			(xy 105.230869 -211.607761) (xy 105.178367 -211.623257) (xy 105.124189 -211.631086) (xy 105.069447 -211.631086)
			(xy 105.015269 -211.623257) (xy 104.962767 -211.607761) (xy 104.913021 -211.584915) (xy 104.867053 -211.555191)
			(xy 104.84612 -211.53755) (xy 104.839008 -211.531454) (xy 104.830626 -211.528406) (xy 104.826339 -211.526882)
			(xy 104.817394 -211.525226) (xy 104.812846 -211.525104) (xy 104.74579 -211.525104) (xy 104.741242 -211.525227)
			(xy 104.732298 -211.526887) (xy 104.72801 -211.528406) (xy 104.719628 -211.531454) (xy 104.712516 -211.53755)
			(xy 104.691582 -211.555187) (xy 104.645611 -211.584901) (xy 104.595864 -211.607738) (xy 104.543363 -211.623229)
			(xy 104.489187 -211.631057) (xy 104.461818 -211.63153) (xy 104.434568 -211.631005) (xy 104.380623 -211.623252)
			(xy 104.32833 -211.6079) (xy 104.278755 -211.585262) (xy 104.232905 -211.5558) (xy 104.191716 -211.520113)
			(xy 104.156024 -211.478927) (xy 104.126557 -211.43308) (xy 104.103914 -211.383507) (xy 104.088557 -211.331216)
			(xy 104.080798 -211.277272) (xy 104.08031 -211.250022) (xy 91.337384 -211.250022) (xy 91.337384 -212.0392)
			(xy 106.915202 -212.0392) (xy 106.919273 -211.983578) (xy 106.931399 -211.929141) (xy 106.951322 -211.87705)
			(xy 106.978618 -211.828415) (xy 107.012704 -211.784272) (xy 107.052853 -211.745563) (xy 107.098211 -211.713112)
			(xy 107.147811 -211.687611) (xy 107.200595 -211.669604) (xy 107.255438 -211.659474) (xy 107.311172 -211.657437)
			(xy 107.366609 -211.663537) (xy 107.420566 -211.677643) (xy 107.471895 -211.699455) (xy 107.519501 -211.728509)
			(xy 107.562369 -211.764184) (xy 107.599586 -211.805721) (xy 107.630359 -211.852234) (xy 107.654031 -211.902731)
			(xy 107.670099 -211.956138) (xy 107.672828 -211.974684) (xy 124.447044 -211.974684) (xy 124.451115 -211.919062)
			(xy 124.463241 -211.864625) (xy 124.483164 -211.812534) (xy 124.51046 -211.763899) (xy 124.544546 -211.719756)
			(xy 124.584695 -211.681047) (xy 124.630053 -211.648596) (xy 124.679653 -211.623095) (xy 124.732437 -211.605088)
			(xy 124.78728 -211.594958) (xy 124.843014 -211.592921) (xy 124.898451 -211.599021) (xy 124.952408 -211.613127)
			(xy 125.003737 -211.634939) (xy 125.051343 -211.663993) (xy 125.094211 -211.699668) (xy 125.131428 -211.741205)
			(xy 125.162201 -211.787718) (xy 125.185873 -211.838215) (xy 125.201941 -211.891622) (xy 125.210061 -211.946798)
			(xy 125.21057 -211.974684) (xy 125.210061 -212.00257) (xy 125.201941 -212.057746) (xy 125.185873 -212.111153)
			(xy 125.162201 -212.16165) (xy 125.131428 -212.208163) (xy 125.103938 -212.238844) (xy 125.366524 -212.238844)
			(xy 125.370595 -212.183222) (xy 125.382721 -212.128785) (xy 125.402644 -212.076694) (xy 125.42994 -212.028059)
			(xy 125.464026 -211.983916) (xy 125.504175 -211.945207) (xy 125.549533 -211.912756) (xy 125.599133 -211.887255)
			(xy 125.651917 -211.869248) (xy 125.70676 -211.859118) (xy 125.762494 -211.857081) (xy 125.817931 -211.863181)
			(xy 125.871888 -211.877287) (xy 125.923217 -211.899099) (xy 125.970823 -211.928153) (xy 126.013691 -211.963828)
			(xy 126.050908 -212.005365) (xy 126.056063 -212.013157) (xy 130.348115 -212.013157) (xy 130.348115 -211.958643)
			(xy 130.355874 -211.904684) (xy 130.371233 -211.852378) (xy 130.39388 -211.802791) (xy 130.423353 -211.756932)
			(xy 130.459054 -211.715734) (xy 130.500254 -211.680036) (xy 130.546116 -211.650566) (xy 130.595705 -211.627923)
			(xy 130.648011 -211.612568) (xy 130.701971 -211.604813) (xy 130.729228 -211.604352) (xy 130.755544 -211.604802)
			(xy 130.807677 -211.612028) (xy 130.858321 -211.626353) (xy 130.906515 -211.647505) (xy 130.951343 -211.675082)
			(xy 130.991953 -211.708561) (xy 131.027576 -211.747305) (xy 131.042918 -211.76869) (xy 131.05134 -211.780152)
			(xy 131.073267 -211.79825) (xy 131.099338 -211.809593) (xy 131.127527 -211.813299) (xy 131.155644 -211.809081)
			(xy 131.181504 -211.797267) (xy 131.203099 -211.778773) (xy 131.21132 -211.767166) (xy 131.226511 -211.744988)
			(xy 131.262171 -211.704764) (xy 131.303127 -211.669947) (xy 131.348568 -211.641228) (xy 131.397592 -211.619176)
			(xy 131.449227 -211.604229) (xy 131.50245 -211.596682) (xy 131.529328 -211.596224) (xy 131.55658 -211.596648)
			(xy 131.610529 -211.604408) (xy 131.662825 -211.619767) (xy 131.712403 -211.642412) (xy 131.758254 -211.671881)
			(xy 131.799444 -211.707576) (xy 131.835136 -211.748769) (xy 131.864602 -211.794622) (xy 131.887243 -211.844201)
			(xy 131.902598 -211.896498) (xy 131.910354 -211.950448) (xy 131.910354 -212.004952) (xy 131.902598 -212.058902)
			(xy 131.887243 -212.111199) (xy 131.864602 -212.160778) (xy 131.835136 -212.206631) (xy 131.799444 -212.247824)
			(xy 131.758254 -212.283519) (xy 131.712403 -212.312988) (xy 131.662825 -212.335633) (xy 131.610529 -212.350992)
			(xy 131.55658 -212.358752) (xy 131.529328 -212.35924) (xy 131.503011 -212.358827) (xy 131.450876 -212.351595)
			(xy 131.400231 -212.337264) (xy 131.352037 -212.316106) (xy 131.307209 -212.288523) (xy 131.2666 -212.255039)
			(xy 131.230979 -212.21629) (xy 131.215638 -212.194902) (xy 131.207146 -212.183496) (xy 131.185234 -212.165401)
			(xy 131.159179 -212.154056) (xy 131.131005 -212.150343) (xy 131.1029 -212.15455) (xy 131.077049 -212.166351)
			(xy 131.055458 -212.184828) (xy 131.047236 -212.196426) (xy 131.032007 -212.218576) (xy 130.996353 -212.258801)
			(xy 130.955404 -212.29362) (xy 130.90997 -212.322343) (xy 130.860952 -212.344399) (xy 130.809322 -212.359352)
			(xy 130.756104 -212.366906) (xy 130.729228 -212.367368) (xy 130.701971 -212.366987) (xy 130.648011 -212.359232)
			(xy 130.595705 -212.343877) (xy 130.546116 -212.321234) (xy 130.500254 -212.291764) (xy 130.459054 -212.256066)
			(xy 130.423353 -212.214868) (xy 130.39388 -212.169009) (xy 130.371233 -212.119422) (xy 130.355874 -212.067116)
			(xy 130.348115 -212.013157) (xy 126.056063 -212.013157) (xy 126.081681 -212.051878) (xy 126.105353 -212.102375)
			(xy 126.121421 -212.155782) (xy 126.129541 -212.210958) (xy 126.13005 -212.238844) (xy 126.129541 -212.26673)
			(xy 126.121421 -212.321906) (xy 126.105353 -212.375313) (xy 126.081681 -212.42581) (xy 126.050908 -212.472323)
			(xy 126.013691 -212.51386) (xy 125.970823 -212.549535) (xy 125.923217 -212.578589) (xy 125.871888 -212.600401)
			(xy 125.817931 -212.614507) (xy 125.762494 -212.620607) (xy 125.70676 -212.61857) (xy 125.651917 -212.60844)
			(xy 125.599133 -212.590433) (xy 125.549533 -212.564932) (xy 125.504175 -212.532481) (xy 125.464026 -212.493772)
			(xy 125.42994 -212.449629) (xy 125.402644 -212.400994) (xy 125.382721 -212.348903) (xy 125.370595 -212.294466)
			(xy 125.366524 -212.238844) (xy 125.103938 -212.238844) (xy 125.094211 -212.2497) (xy 125.051343 -212.285375)
			(xy 125.003737 -212.314429) (xy 124.952408 -212.336241) (xy 124.898451 -212.350347) (xy 124.843014 -212.356447)
			(xy 124.78728 -212.35441) (xy 124.732437 -212.34428) (xy 124.679653 -212.326273) (xy 124.630053 -212.300772)
			(xy 124.584695 -212.268321) (xy 124.544546 -212.229612) (xy 124.51046 -212.185469) (xy 124.483164 -212.136834)
			(xy 124.463241 -212.084743) (xy 124.451115 -212.030306) (xy 124.447044 -211.974684) (xy 107.672828 -211.974684)
			(xy 107.678219 -212.011314) (xy 107.678728 -212.0392) (xy 107.678219 -212.067086) (xy 107.670099 -212.122262)
			(xy 107.654031 -212.175669) (xy 107.630359 -212.226166) (xy 107.599586 -212.272679) (xy 107.562369 -212.314216)
			(xy 107.519501 -212.349891) (xy 107.471895 -212.378945) (xy 107.420566 -212.400757) (xy 107.366609 -212.414863)
			(xy 107.311172 -212.420963) (xy 107.255438 -212.418926) (xy 107.200595 -212.408796) (xy 107.147811 -212.390789)
			(xy 107.098211 -212.365288) (xy 107.052853 -212.332837) (xy 107.012704 -212.294128) (xy 106.978618 -212.249985)
			(xy 106.951322 -212.20135) (xy 106.931399 -212.149259) (xy 106.919273 -212.094822) (xy 106.915202 -212.0392)
			(xy 91.337384 -212.0392) (xy 91.337384 -212.301074) (xy 91.3384 -212.310472) (xy 91.341194 -212.325966)
			(xy 91.342718 -212.329776) (xy 91.353623 -212.361504) (xy 91.365368 -212.427552) (xy 91.366086 -212.461094)
			(xy 91.366086 -212.461348) (xy 91.365722 -212.484651) (xy 91.360019 -212.530907) (xy 91.348727 -212.576125)
			(xy 91.340686 -212.598) (xy 91.337384 -212.60689) (xy 91.337384 -213.249764) (xy 119.607328 -213.249764)
			(xy 119.611399 -213.194142) (xy 119.623525 -213.139705) (xy 119.643448 -213.087614) (xy 119.670744 -213.038979)
			(xy 119.70483 -212.994836) (xy 119.744979 -212.956127) (xy 119.790337 -212.923676) (xy 119.839937 -212.898175)
			(xy 119.892721 -212.880168) (xy 119.947564 -212.870038) (xy 120.003298 -212.868001) (xy 120.058735 -212.874101)
			(xy 120.112692 -212.888207) (xy 120.164021 -212.910019) (xy 120.211627 -212.939073) (xy 120.254495 -212.974748)
			(xy 120.291712 -213.016285) (xy 120.292083 -213.016846) (xy 135.924796 -213.016846) (xy 135.928867 -212.961224)
			(xy 135.940993 -212.906787) (xy 135.960916 -212.854696) (xy 135.988212 -212.806061) (xy 136.022298 -212.761918)
			(xy 136.062447 -212.723209) (xy 136.107805 -212.690758) (xy 136.157405 -212.665257) (xy 136.210189 -212.64725)
			(xy 136.265032 -212.63712) (xy 136.320766 -212.635083) (xy 136.376203 -212.641183) (xy 136.43016 -212.655289)
			(xy 136.481489 -212.677101) (xy 136.529095 -212.706155) (xy 136.571963 -212.74183) (xy 136.60918 -212.783367)
			(xy 136.639953 -212.82988) (xy 136.663625 -212.880377) (xy 136.679693 -212.933784) (xy 136.687813 -212.98896)
			(xy 136.688322 -213.016846) (xy 136.687813 -213.044732) (xy 136.683843 -213.07171) (xy 137.064748 -213.07171)
			(xy 137.068819 -213.016088) (xy 137.080945 -212.961651) (xy 137.100868 -212.90956) (xy 137.128164 -212.860925)
			(xy 137.16225 -212.816782) (xy 137.202399 -212.778073) (xy 137.247757 -212.745622) (xy 137.297357 -212.720121)
			(xy 137.350141 -212.702114) (xy 137.404984 -212.691984) (xy 137.460718 -212.689947) (xy 137.516155 -212.696047)
			(xy 137.570112 -212.710153) (xy 137.621441 -212.731965) (xy 137.669047 -212.761019) (xy 137.711915 -212.796694)
			(xy 137.749132 -212.838231) (xy 137.779905 -212.884744) (xy 137.803577 -212.935241) (xy 137.819645 -212.988648)
			(xy 137.827765 -213.043824) (xy 137.828274 -213.07171) (xy 137.827765 -213.099596) (xy 137.819645 -213.154772)
			(xy 137.803577 -213.208179) (xy 137.779905 -213.258676) (xy 137.749132 -213.305189) (xy 137.711915 -213.346726)
			(xy 137.669047 -213.382401) (xy 137.621441 -213.411455) (xy 137.570112 -213.433267) (xy 137.516155 -213.447373)
			(xy 137.460718 -213.453473) (xy 137.404984 -213.451436) (xy 137.350141 -213.441306) (xy 137.297357 -213.423299)
			(xy 137.247757 -213.397798) (xy 137.202399 -213.365347) (xy 137.16225 -213.326638) (xy 137.128164 -213.282495)
			(xy 137.100868 -213.23386) (xy 137.080945 -213.181769) (xy 137.068819 -213.127332) (xy 137.064748 -213.07171)
			(xy 136.683843 -213.07171) (xy 136.679693 -213.099908) (xy 136.663625 -213.153315) (xy 136.639953 -213.203812)
			(xy 136.60918 -213.250325) (xy 136.571963 -213.291862) (xy 136.529095 -213.327537) (xy 136.481489 -213.356591)
			(xy 136.43016 -213.378403) (xy 136.376203 -213.392509) (xy 136.320766 -213.398609) (xy 136.265032 -213.396572)
			(xy 136.210189 -213.386442) (xy 136.157405 -213.368435) (xy 136.107805 -213.342934) (xy 136.062447 -213.310483)
			(xy 136.022298 -213.271774) (xy 135.988212 -213.227631) (xy 135.960916 -213.178996) (xy 135.940993 -213.126905)
			(xy 135.928867 -213.072468) (xy 135.924796 -213.016846) (xy 120.292083 -213.016846) (xy 120.322485 -213.062798)
			(xy 120.346157 -213.113295) (xy 120.362225 -213.166702) (xy 120.370345 -213.221878) (xy 120.370854 -213.249764)
			(xy 120.370345 -213.27765) (xy 120.362225 -213.332826) (xy 120.346157 -213.386233) (xy 120.322485 -213.43673)
			(xy 120.291712 -213.483243) (xy 120.254495 -213.52478) (xy 120.211627 -213.560455) (xy 120.164021 -213.589509)
			(xy 120.112692 -213.611321) (xy 120.058735 -213.625427) (xy 120.003298 -213.631527) (xy 119.947564 -213.62949)
			(xy 119.892721 -213.61936) (xy 119.839937 -213.601353) (xy 119.790337 -213.575852) (xy 119.744979 -213.543401)
			(xy 119.70483 -213.504692) (xy 119.670744 -213.460549) (xy 119.643448 -213.411914) (xy 119.623525 -213.359823)
			(xy 119.611399 -213.305386) (xy 119.607328 -213.249764) (xy 91.337384 -213.249764) (xy 91.337384 -214.067256)
			(xy 101.187413 -214.067256) (xy 101.187413 -214.012744) (xy 101.195171 -213.958787) (xy 101.210529 -213.906483)
			(xy 101.233174 -213.856897) (xy 101.262646 -213.811038) (xy 101.298344 -213.769841) (xy 101.339542 -213.734143)
			(xy 101.3854 -213.704672) (xy 101.434986 -213.682027) (xy 101.487291 -213.66667) (xy 101.541248 -213.658913)
			(xy 101.568504 -213.65845) (xy 101.595875 -213.658902) (xy 101.650055 -213.666721) (xy 101.702559 -213.682213)
			(xy 101.752306 -213.705058) (xy 101.798271 -213.734787) (xy 101.819202 -213.75243) (xy 101.826314 -213.758526)
			(xy 101.834696 -213.761574) (xy 101.838981 -213.763103) (xy 101.847928 -213.764756) (xy 101.852476 -213.764876)
			(xy 101.919532 -213.764876) (xy 101.92408 -213.76476) (xy 101.933024 -213.763096) (xy 101.937312 -213.761574)
			(xy 101.945694 -213.758526) (xy 101.952806 -213.75243) (xy 101.973729 -213.734779) (xy 102.019704 -213.705068)
			(xy 102.069453 -213.682234) (xy 102.121956 -213.666746) (xy 102.176134 -213.658922) (xy 102.203504 -213.65845)
			(xy 102.230752 -213.65902) (xy 102.284693 -213.666777) (xy 102.336982 -213.68213) (xy 102.386553 -213.704769)
			(xy 102.432398 -213.734232) (xy 102.473583 -213.76992) (xy 102.50927 -213.811105) (xy 102.538733 -213.856951)
			(xy 102.561371 -213.906522) (xy 102.576724 -213.958811) (xy 102.58448 -214.012752) (xy 102.58448 -214.058857)
			(xy 106.844731 -214.058857) (xy 106.844731 -214.004343) (xy 106.85249 -213.950385) (xy 106.867849 -213.89808)
			(xy 106.890496 -213.848494) (xy 106.919971 -213.802635) (xy 106.955671 -213.761439) (xy 106.996872 -213.725743)
			(xy 107.042734 -213.696274) (xy 107.092323 -213.673633) (xy 107.14463 -213.65828) (xy 107.198589 -213.650528)
			(xy 107.225846 -213.650068) (xy 107.253216 -213.650549) (xy 107.307395 -213.658361) (xy 107.359899 -213.673845)
			(xy 107.409646 -213.696684) (xy 107.455613 -213.726407) (xy 107.476544 -213.744048) (xy 107.483656 -213.750144)
			(xy 107.492038 -213.753192) (xy 107.496328 -213.754707) (xy 107.505271 -213.756369) (xy 107.509818 -213.756494)
			(xy 107.576874 -213.756494) (xy 107.581421 -213.756361) (xy 107.590365 -213.754708) (xy 107.594654 -213.753192)
			(xy 107.603036 -213.750144) (xy 107.610148 -213.744048) (xy 107.631095 -213.726427) (xy 107.677063 -213.696711)
			(xy 107.726807 -213.673871) (xy 107.779304 -213.658376) (xy 107.833478 -213.650544) (xy 107.860846 -213.650068)
			(xy 107.888093 -213.650605) (xy 107.942033 -213.658367) (xy 107.994319 -213.673725) (xy 108.043887 -213.696367)
			(xy 108.069066 -213.712552) (xy 139.125196 -213.712552) (xy 139.129267 -213.65693) (xy 139.141393 -213.602493)
			(xy 139.161316 -213.550402) (xy 139.188612 -213.501767) (xy 139.222698 -213.457624) (xy 139.262847 -213.418915)
			(xy 139.308205 -213.386464) (xy 139.357805 -213.360963) (xy 139.410589 -213.342956) (xy 139.465432 -213.332826)
			(xy 139.521166 -213.330789) (xy 139.576603 -213.336889) (xy 139.63056 -213.350995) (xy 139.681889 -213.372807)
			(xy 139.729495 -213.401861) (xy 139.772363 -213.437536) (xy 139.80958 -213.479073) (xy 139.840353 -213.525586)
			(xy 139.864025 -213.576083) (xy 139.880093 -213.62949) (xy 139.888213 -213.684666) (xy 139.888722 -213.712552)
			(xy 139.888213 -213.740438) (xy 139.880093 -213.795614) (xy 139.864025 -213.849021) (xy 139.840353 -213.899518)
			(xy 139.80958 -213.946031) (xy 139.800752 -213.955884) (xy 144.949926 -213.955884) (xy 144.950412 -213.928633)
			(xy 144.958168 -213.874685) (xy 144.973523 -213.82239) (xy 144.996165 -213.772813) (xy 145.025631 -213.726963)
			(xy 145.061322 -213.685772) (xy 145.102513 -213.650081) (xy 145.148363 -213.620615) (xy 145.19794 -213.597973)
			(xy 145.250235 -213.582618) (xy 145.304183 -213.574862) (xy 145.358685 -213.574862) (xy 145.412633 -213.582618)
			(xy 145.464928 -213.597973) (xy 145.514505 -213.620615) (xy 145.560355 -213.650081) (xy 145.601546 -213.685772)
			(xy 145.637237 -213.726963) (xy 145.666703 -213.772813) (xy 145.689345 -213.82239) (xy 145.7047 -213.874685)
			(xy 145.712456 -213.928633) (xy 145.712942 -213.955884) (xy 145.712434 -213.984697) (xy 145.703781 -214.041669)
			(xy 145.686654 -214.096691) (xy 145.661445 -214.14851) (xy 145.628725 -214.195946) (xy 145.589241 -214.23792)
			(xy 145.566892 -214.256112) (xy 145.555627 -214.265392) (xy 145.538637 -214.289116) (xy 145.52905 -214.316677)
			(xy 145.52765 -214.345823) (xy 145.53455 -214.374176) (xy 145.549188 -214.399419) (xy 145.570368 -214.419492)
			(xy 145.583148 -214.426546) (xy 145.60623 -214.438854) (xy 145.649072 -214.46887) (xy 145.687409 -214.504461)
			(xy 145.720521 -214.544959) (xy 145.747786 -214.589602) (xy 145.768693 -214.637554) (xy 145.782848 -214.687913)
			(xy 145.789987 -214.739734) (xy 145.790412 -214.76589) (xy 145.789926 -214.793141) (xy 145.78217 -214.847089)
			(xy 145.766815 -214.899384) (xy 145.744173 -214.948961) (xy 145.714707 -214.994811) (xy 145.679016 -215.036002)
			(xy 145.637825 -215.071693) (xy 145.591975 -215.101159) (xy 145.542398 -215.123801) (xy 145.490103 -215.139156)
			(xy 145.436155 -215.146912) (xy 145.381653 -215.146912) (xy 145.327705 -215.139156) (xy 145.27541 -215.123801)
			(xy 145.225833 -215.101159) (xy 145.179983 -215.071693) (xy 145.138792 -215.036002) (xy 145.103101 -214.994811)
			(xy 145.073635 -214.948961) (xy 145.050993 -214.899384) (xy 145.035638 -214.847089) (xy 145.027882 -214.793141)
			(xy 145.027396 -214.76589) (xy 145.027909 -214.737077) (xy 145.036565 -214.680106) (xy 145.053692 -214.625085)
			(xy 145.0789 -214.573267) (xy 145.111618 -214.525831) (xy 145.151098 -214.483856) (xy 145.173446 -214.465662)
			(xy 145.184624 -214.456288) (xy 145.201607 -214.432585) (xy 145.211195 -214.405048) (xy 145.212605 -214.375923)
			(xy 145.205722 -214.347588) (xy 145.191109 -214.322356) (xy 145.169956 -214.302285) (xy 145.15719 -214.295228)
			(xy 145.134124 -214.282891) (xy 145.091286 -214.252876) (xy 145.052951 -214.217287) (xy 145.01984 -214.176794)
			(xy 144.992574 -214.132155) (xy 144.971664 -214.084209) (xy 144.957503 -214.033855) (xy 144.950356 -213.982038)
			(xy 144.949926 -213.955884) (xy 139.800752 -213.955884) (xy 139.772363 -213.987568) (xy 139.729495 -214.023243)
			(xy 139.681889 -214.052297) (xy 139.63056 -214.074109) (xy 139.576603 -214.088215) (xy 139.521166 -214.094315)
			(xy 139.465432 -214.092278) (xy 139.410589 -214.082148) (xy 139.357805 -214.064141) (xy 139.308205 -214.03864)
			(xy 139.262847 -214.006189) (xy 139.222698 -213.96748) (xy 139.188612 -213.923337) (xy 139.161316 -213.874702)
			(xy 139.141393 -213.822611) (xy 139.129267 -213.768174) (xy 139.125196 -213.712552) (xy 108.069066 -213.712552)
			(xy 108.089728 -213.725833) (xy 108.130911 -213.761522) (xy 108.166595 -213.802708) (xy 108.196055 -213.848554)
			(xy 108.218691 -213.898125) (xy 108.234043 -213.950412) (xy 108.241798 -214.004353) (xy 108.241798 -214.058847)
			(xy 108.234043 -214.112788) (xy 108.218691 -214.165075) (xy 108.209132 -214.186008) (xy 120.27611 -214.186008)
			(xy 120.280181 -214.130386) (xy 120.292307 -214.075949) (xy 120.31223 -214.023858) (xy 120.339526 -213.975223)
			(xy 120.373612 -213.93108) (xy 120.413761 -213.892371) (xy 120.459119 -213.85992) (xy 120.508719 -213.834419)
			(xy 120.561503 -213.816412) (xy 120.616346 -213.806282) (xy 120.67208 -213.804245) (xy 120.727517 -213.810345)
			(xy 120.781474 -213.824451) (xy 120.832803 -213.846263) (xy 120.880409 -213.875317) (xy 120.923277 -213.910992)
			(xy 120.960494 -213.952529) (xy 120.991267 -213.999042) (xy 121.014939 -214.049539) (xy 121.031007 -214.102946)
			(xy 121.039127 -214.158122) (xy 121.039423 -214.174324) (xy 124.46584 -214.174324) (xy 124.469911 -214.118702)
			(xy 124.482037 -214.064265) (xy 124.50196 -214.012174) (xy 124.529256 -213.963539) (xy 124.563342 -213.919396)
			(xy 124.603491 -213.880687) (xy 124.648849 -213.848236) (xy 124.698449 -213.822735) (xy 124.751233 -213.804728)
			(xy 124.806076 -213.794598) (xy 124.86181 -213.792561) (xy 124.917247 -213.798661) (xy 124.971204 -213.812767)
			(xy 125.022533 -213.834579) (xy 125.070139 -213.863633) (xy 125.113007 -213.899308) (xy 125.150224 -213.940845)
			(xy 125.180997 -213.987358) (xy 125.204669 -214.037855) (xy 125.220737 -214.091262) (xy 125.228857 -214.146438)
			(xy 125.229366 -214.174324) (xy 125.228857 -214.20221) (xy 125.220737 -214.257386) (xy 125.204669 -214.310793)
			(xy 125.180997 -214.36129) (xy 125.150224 -214.407803) (xy 125.117044 -214.444834) (xy 125.467362 -214.444834)
			(xy 125.471433 -214.389212) (xy 125.483559 -214.334775) (xy 125.503482 -214.282684) (xy 125.530778 -214.234049)
			(xy 125.564864 -214.189906) (xy 125.605013 -214.151197) (xy 125.650371 -214.118746) (xy 125.699971 -214.093245)
			(xy 125.752755 -214.075238) (xy 125.807598 -214.065108) (xy 125.863332 -214.063071) (xy 125.918769 -214.069171)
			(xy 125.972726 -214.083277) (xy 126.004078 -214.0966) (xy 136.092182 -214.0966) (xy 136.096253 -214.040978)
			(xy 136.108379 -213.986541) (xy 136.128302 -213.93445) (xy 136.155598 -213.885815) (xy 136.189684 -213.841672)
			(xy 136.229833 -213.802963) (xy 136.275191 -213.770512) (xy 136.324791 -213.745011) (xy 136.377575 -213.727004)
			(xy 136.432418 -213.716874) (xy 136.488152 -213.714837) (xy 136.543589 -213.720937) (xy 136.597546 -213.735043)
			(xy 136.648875 -213.756855) (xy 136.696481 -213.785909) (xy 136.739349 -213.821584) (xy 136.776566 -213.863121)
			(xy 136.807339 -213.909634) (xy 136.831011 -213.960131) (xy 136.847079 -214.013538) (xy 136.855199 -214.068714)
			(xy 136.855708 -214.0966) (xy 136.855199 -214.124486) (xy 136.847079 -214.179662) (xy 136.831011 -214.233069)
			(xy 136.807339 -214.283566) (xy 136.776566 -214.330079) (xy 136.739349 -214.371616) (xy 136.696481 -214.407291)
			(xy 136.648875 -214.436345) (xy 136.597546 -214.458157) (xy 136.543589 -214.472263) (xy 136.488152 -214.478363)
			(xy 136.432418 -214.476326) (xy 136.377575 -214.466196) (xy 136.324791 -214.448189) (xy 136.275191 -214.422688)
			(xy 136.229833 -214.390237) (xy 136.189684 -214.351528) (xy 136.155598 -214.307385) (xy 136.128302 -214.25875)
			(xy 136.108379 -214.206659) (xy 136.096253 -214.152222) (xy 136.092182 -214.0966) (xy 126.004078 -214.0966)
			(xy 126.024055 -214.105089) (xy 126.071661 -214.134143) (xy 126.114529 -214.169818) (xy 126.151746 -214.211355)
			(xy 126.182519 -214.257868) (xy 126.206191 -214.308365) (xy 126.222259 -214.361772) (xy 126.230379 -214.416948)
			(xy 126.230888 -214.444834) (xy 126.230379 -214.47272) (xy 126.222259 -214.527896) (xy 126.206191 -214.581303)
			(xy 126.182519 -214.6318) (xy 126.151746 -214.678313) (xy 126.114529 -214.71985) (xy 126.071661 -214.755525)
			(xy 126.024055 -214.784579) (xy 125.972726 -214.806391) (xy 125.918769 -214.820497) (xy 125.863332 -214.826597)
			(xy 125.807598 -214.82456) (xy 125.752755 -214.81443) (xy 125.699971 -214.796423) (xy 125.650371 -214.770922)
			(xy 125.605013 -214.738471) (xy 125.564864 -214.699762) (xy 125.530778 -214.655619) (xy 125.503482 -214.606984)
			(xy 125.483559 -214.554893) (xy 125.471433 -214.500456) (xy 125.467362 -214.444834) (xy 125.117044 -214.444834)
			(xy 125.113007 -214.44934) (xy 125.070139 -214.485015) (xy 125.022533 -214.514069) (xy 124.971204 -214.535881)
			(xy 124.917247 -214.549987) (xy 124.86181 -214.556087) (xy 124.806076 -214.55405) (xy 124.751233 -214.54392)
			(xy 124.698449 -214.525913) (xy 124.648849 -214.500412) (xy 124.603491 -214.467961) (xy 124.563342 -214.429252)
			(xy 124.529256 -214.385109) (xy 124.50196 -214.336474) (xy 124.482037 -214.284383) (xy 124.469911 -214.229946)
			(xy 124.46584 -214.174324) (xy 121.039423 -214.174324) (xy 121.039636 -214.186008) (xy 121.039127 -214.213894)
			(xy 121.031007 -214.26907) (xy 121.014939 -214.322477) (xy 120.991267 -214.372974) (xy 120.960494 -214.419487)
			(xy 120.923277 -214.461024) (xy 120.880409 -214.496699) (xy 120.832803 -214.525753) (xy 120.781474 -214.547565)
			(xy 120.727517 -214.561671) (xy 120.67208 -214.567771) (xy 120.616346 -214.565734) (xy 120.561503 -214.555604)
			(xy 120.508719 -214.537597) (xy 120.459119 -214.512096) (xy 120.413761 -214.479645) (xy 120.373612 -214.440936)
			(xy 120.339526 -214.396793) (xy 120.31223 -214.348158) (xy 120.292307 -214.296067) (xy 120.280181 -214.24163)
			(xy 120.27611 -214.186008) (xy 108.209132 -214.186008) (xy 108.196055 -214.214646) (xy 108.166595 -214.260492)
			(xy 108.130911 -214.301678) (xy 108.089728 -214.337367) (xy 108.043887 -214.366833) (xy 107.994319 -214.389475)
			(xy 107.942033 -214.404833) (xy 107.888093 -214.412595) (xy 107.860846 -214.413084) (xy 107.833477 -214.412595)
			(xy 107.779298 -214.404783) (xy 107.726795 -214.3893) (xy 107.677048 -214.366463) (xy 107.63108 -214.336743)
			(xy 107.610148 -214.319104) (xy 107.603036 -214.313008) (xy 107.594654 -214.30996) (xy 107.590364 -214.308445)
			(xy 107.581421 -214.306782) (xy 107.576874 -214.306658) (xy 107.509818 -214.306658) (xy 107.50527 -214.306779)
			(xy 107.496325 -214.308436) (xy 107.492038 -214.30996) (xy 107.483656 -214.313008) (xy 107.476544 -214.319104)
			(xy 107.455607 -214.336737) (xy 107.409635 -214.366449) (xy 107.359889 -214.389286) (xy 107.30739 -214.404779)
			(xy 107.253215 -214.412609) (xy 107.225846 -214.413084) (xy 107.198589 -214.412672) (xy 107.14463 -214.40492)
			(xy 107.092323 -214.389567) (xy 107.042734 -214.366926) (xy 106.996872 -214.337457) (xy 106.955671 -214.301761)
			(xy 106.919971 -214.260565) (xy 106.890496 -214.214706) (xy 106.867849 -214.16512) (xy 106.85249 -214.112815)
			(xy 106.844731 -214.058857) (xy 102.58448 -214.058857) (xy 102.58448 -214.067248) (xy 102.576724 -214.121189)
			(xy 102.561371 -214.173478) (xy 102.538733 -214.223049) (xy 102.50927 -214.268895) (xy 102.473583 -214.31008)
			(xy 102.432398 -214.345768) (xy 102.386553 -214.375231) (xy 102.336982 -214.39787) (xy 102.284693 -214.413223)
			(xy 102.230752 -214.42098) (xy 102.203504 -214.421466) (xy 102.176133 -214.421006) (xy 102.121954 -214.413188)
			(xy 102.06945 -214.397698) (xy 102.019703 -214.374855) (xy 101.973737 -214.345128) (xy 101.952806 -214.327486)
			(xy 101.945694 -214.32139) (xy 101.937312 -214.318342) (xy 101.933026 -214.316816) (xy 101.92408 -214.315161)
			(xy 101.919532 -214.31504) (xy 101.852476 -214.31504) (xy 101.847928 -214.315157) (xy 101.838984 -214.316821)
			(xy 101.834696 -214.318342) (xy 101.826314 -214.32139) (xy 101.819202 -214.327486) (xy 101.798278 -214.345135)
			(xy 101.752303 -214.374846) (xy 101.702554 -214.39768) (xy 101.650051 -214.413169) (xy 101.595874 -214.420994)
			(xy 101.568504 -214.421466) (xy 101.541248 -214.421087) (xy 101.487291 -214.41333) (xy 101.434986 -214.397973)
			(xy 101.3854 -214.375328) (xy 101.339542 -214.345857) (xy 101.298344 -214.310159) (xy 101.262646 -214.268962)
			(xy 101.233174 -214.223103) (xy 101.210529 -214.173517) (xy 101.195171 -214.121213) (xy 101.187413 -214.067256)
			(xy 91.337384 -214.067256) (xy 91.337384 -215.10498) (xy 117.322598 -215.10498) (xy 117.326669 -215.049358)
			(xy 117.338795 -214.994921) (xy 117.358718 -214.94283) (xy 117.386014 -214.894195) (xy 117.4201 -214.850052)
			(xy 117.460249 -214.811343) (xy 117.505607 -214.778892) (xy 117.555207 -214.753391) (xy 117.607991 -214.735384)
			(xy 117.662834 -214.725254) (xy 117.718568 -214.723217) (xy 117.774005 -214.729317) (xy 117.827962 -214.743423)
			(xy 117.879291 -214.765235) (xy 117.926897 -214.794289) (xy 117.969765 -214.829964) (xy 118.006982 -214.871501)
			(xy 118.037755 -214.918014) (xy 118.061427 -214.968511) (xy 118.077495 -215.021918) (xy 118.085615 -215.077094)
			(xy 118.086124 -215.10498) (xy 118.085615 -215.132866) (xy 118.077495 -215.188042) (xy 118.061427 -215.241449)
			(xy 118.03848 -215.2904) (xy 121.461782 -215.2904) (xy 121.465853 -215.234778) (xy 121.477979 -215.180341)
			(xy 121.497902 -215.12825) (xy 121.525198 -215.079615) (xy 121.559284 -215.035472) (xy 121.599433 -214.996763)
			(xy 121.644791 -214.964312) (xy 121.694391 -214.938811) (xy 121.747175 -214.920804) (xy 121.802018 -214.910674)
			(xy 121.857752 -214.908637) (xy 121.913189 -214.914737) (xy 121.967146 -214.928843) (xy 122.018475 -214.950655)
			(xy 122.066081 -214.979709) (xy 122.100019 -215.007952) (xy 124.788928 -215.007952) (xy 124.792999 -214.95233)
			(xy 124.805125 -214.897893) (xy 124.825048 -214.845802) (xy 124.852344 -214.797167) (xy 124.88643 -214.753024)
			(xy 124.926579 -214.714315) (xy 124.971937 -214.681864) (xy 125.021537 -214.656363) (xy 125.074321 -214.638356)
			(xy 125.129164 -214.628226) (xy 125.184898 -214.626189) (xy 125.240335 -214.632289) (xy 125.294292 -214.646395)
			(xy 125.345621 -214.668207) (xy 125.393227 -214.697261) (xy 125.436095 -214.732936) (xy 125.473312 -214.774473)
			(xy 125.504085 -214.820986) (xy 125.527757 -214.871483) (xy 125.543825 -214.92489) (xy 125.551945 -214.980066)
			(xy 125.552454 -215.007952) (xy 125.551945 -215.035838) (xy 125.543825 -215.091014) (xy 125.54268 -215.09482)
			(xy 127.568196 -215.09482) (xy 127.572267 -215.039198) (xy 127.584393 -214.984761) (xy 127.604316 -214.93267)
			(xy 127.631612 -214.884035) (xy 127.665698 -214.839892) (xy 127.705847 -214.801183) (xy 127.751205 -214.768732)
			(xy 127.800805 -214.743231) (xy 127.853589 -214.725224) (xy 127.908432 -214.715094) (xy 127.964166 -214.713057)
			(xy 128.019603 -214.719157) (xy 128.07356 -214.733263) (xy 128.124889 -214.755075) (xy 128.172495 -214.784129)
			(xy 128.215363 -214.819804) (xy 128.25258 -214.861341) (xy 128.283353 -214.907854) (xy 128.307025 -214.958351)
			(xy 128.323093 -215.011758) (xy 128.328551 -215.048846) (xy 129.600196 -215.048846) (xy 129.604267 -214.993224)
			(xy 129.616393 -214.938787) (xy 129.636316 -214.886696) (xy 129.663612 -214.838061) (xy 129.697698 -214.793918)
			(xy 129.737847 -214.755209) (xy 129.783205 -214.722758) (xy 129.832805 -214.697257) (xy 129.885589 -214.67925)
			(xy 129.940432 -214.66912) (xy 129.996166 -214.667083) (xy 130.051603 -214.673183) (xy 130.10556 -214.687289)
			(xy 130.156889 -214.709101) (xy 130.204495 -214.738155) (xy 130.247363 -214.77383) (xy 130.28458 -214.815367)
			(xy 130.315353 -214.86188) (xy 130.339025 -214.912377) (xy 130.340651 -214.917782) (xy 131.880862 -214.917782)
			(xy 131.884933 -214.86216) (xy 131.897059 -214.807723) (xy 131.916982 -214.755632) (xy 131.944278 -214.706997)
			(xy 131.978364 -214.662854) (xy 132.018513 -214.624145) (xy 132.063871 -214.591694) (xy 132.113471 -214.566193)
			(xy 132.166255 -214.548186) (xy 132.221098 -214.538056) (xy 132.276832 -214.536019) (xy 132.332269 -214.542119)
			(xy 132.386226 -214.556225) (xy 132.437555 -214.578037) (xy 132.485161 -214.607091) (xy 132.528029 -214.642766)
			(xy 132.550501 -214.667846) (xy 132.902196 -214.667846) (xy 132.906267 -214.612224) (xy 132.918393 -214.557787)
			(xy 132.938316 -214.505696) (xy 132.965612 -214.457061) (xy 132.999698 -214.412918) (xy 133.039847 -214.374209)
			(xy 133.085205 -214.341758) (xy 133.134805 -214.316257) (xy 133.187589 -214.29825) (xy 133.242432 -214.28812)
			(xy 133.298166 -214.286083) (xy 133.353603 -214.292183) (xy 133.40756 -214.306289) (xy 133.458889 -214.328101)
			(xy 133.506495 -214.357155) (xy 133.549363 -214.39283) (xy 133.58658 -214.434367) (xy 133.617353 -214.48088)
			(xy 133.641025 -214.531377) (xy 133.657093 -214.584784) (xy 133.665213 -214.63996) (xy 133.665722 -214.667846)
			(xy 134.426196 -214.667846) (xy 134.430267 -214.612224) (xy 134.442393 -214.557787) (xy 134.462316 -214.505696)
			(xy 134.489612 -214.457061) (xy 134.523698 -214.412918) (xy 134.563847 -214.374209) (xy 134.609205 -214.341758)
			(xy 134.658805 -214.316257) (xy 134.711589 -214.29825) (xy 134.766432 -214.28812) (xy 134.822166 -214.286083)
			(xy 134.877603 -214.292183) (xy 134.93156 -214.306289) (xy 134.982889 -214.328101) (xy 135.030495 -214.357155)
			(xy 135.073363 -214.39283) (xy 135.11058 -214.434367) (xy 135.141353 -214.48088) (xy 135.165025 -214.531377)
			(xy 135.181093 -214.584784) (xy 135.189213 -214.63996) (xy 135.189722 -214.667846) (xy 135.189213 -214.695732)
			(xy 135.181093 -214.750908) (xy 135.165025 -214.804315) (xy 135.141353 -214.854812) (xy 135.11058 -214.901325)
			(xy 135.073363 -214.942862) (xy 135.030495 -214.978537) (xy 135.0235 -214.982806) (xy 138.297666 -214.982806)
			(xy 138.298108 -214.95645) (xy 138.305352 -214.904238) (xy 138.319716 -214.853521) (xy 138.340927 -214.805266)
			(xy 138.368581 -214.76039) (xy 138.40215 -214.71975) (xy 138.440996 -214.684119) (xy 138.484378 -214.654177)
			(xy 138.507724 -214.641938) (xy 138.520794 -214.634782) (xy 138.542412 -214.614295) (xy 138.5572 -214.588443)
			(xy 138.563901 -214.559423) (xy 138.561945 -214.529704) (xy 138.551498 -214.501813) (xy 138.533448 -214.478122)
			(xy 138.521694 -214.468964) (xy 138.501067 -214.453536) (xy 138.463757 -214.418023) (xy 138.431567 -214.37781)
			(xy 138.405084 -214.33363) (xy 138.38479 -214.286287) (xy 138.371054 -214.236642) (xy 138.364127 -214.185601)
			(xy 138.363706 -214.159846) (xy 138.364192 -214.132595) (xy 138.371948 -214.078647) (xy 138.387303 -214.026352)
			(xy 138.409945 -213.976775) (xy 138.439411 -213.930925) (xy 138.475102 -213.889734) (xy 138.516293 -213.854043)
			(xy 138.562143 -213.824577) (xy 138.61172 -213.801935) (xy 138.664015 -213.78658) (xy 138.717963 -213.778824)
			(xy 138.772465 -213.778824) (xy 138.826413 -213.78658) (xy 138.878708 -213.801935) (xy 138.928285 -213.824577)
			(xy 138.974135 -213.854043) (xy 139.015326 -213.889734) (xy 139.051017 -213.930925) (xy 139.080483 -213.976775)
			(xy 139.103125 -214.026352) (xy 139.11848 -214.078647) (xy 139.126236 -214.132595) (xy 139.126722 -214.159846)
			(xy 139.126247 -214.186201) (xy 139.119009 -214.238412) (xy 139.104651 -214.289128) (xy 139.083445 -214.337384)
			(xy 139.055796 -214.38226) (xy 139.02223 -214.4229) (xy 138.983388 -214.458532) (xy 138.940009 -214.488474)
			(xy 138.916664 -214.500714) (xy 138.90355 -214.507796) (xy 138.88193 -214.528299) (xy 138.867143 -214.554167)
			(xy 138.865997 -214.559134) (xy 144.141442 -214.559134) (xy 144.145513 -214.503512) (xy 144.157639 -214.449075)
			(xy 144.177562 -214.396984) (xy 144.204858 -214.348349) (xy 144.238944 -214.304206) (xy 144.279093 -214.265497)
			(xy 144.324451 -214.233046) (xy 144.374051 -214.207545) (xy 144.426835 -214.189538) (xy 144.481678 -214.179408)
			(xy 144.537412 -214.177371) (xy 144.592849 -214.183471) (xy 144.646806 -214.197577) (xy 144.698135 -214.219389)
			(xy 144.745741 -214.248443) (xy 144.788609 -214.284118) (xy 144.825826 -214.325655) (xy 144.856599 -214.372168)
			(xy 144.880271 -214.422665) (xy 144.896339 -214.476072) (xy 144.904459 -214.531248) (xy 144.904968 -214.559134)
			(xy 144.904459 -214.58702) (xy 144.896339 -214.642196) (xy 144.880271 -214.695603) (xy 144.856599 -214.7461)
			(xy 144.825826 -214.792613) (xy 144.788609 -214.83415) (xy 144.745741 -214.869825) (xy 144.698135 -214.898879)
			(xy 144.646806 -214.920691) (xy 144.592849 -214.934797) (xy 144.537412 -214.940897) (xy 144.481678 -214.93886)
			(xy 144.426835 -214.92873) (xy 144.374051 -214.910723) (xy 144.324451 -214.885222) (xy 144.279093 -214.852771)
			(xy 144.238944 -214.814062) (xy 144.204858 -214.769919) (xy 144.177562 -214.721284) (xy 144.157639 -214.669193)
			(xy 144.145513 -214.614756) (xy 144.141442 -214.559134) (xy 138.865997 -214.559134) (xy 138.860447 -214.583201)
			(xy 138.862412 -214.612932) (xy 138.87287 -214.640832) (xy 138.890933 -214.664529) (xy 138.902694 -214.673688)
			(xy 138.923295 -214.689149) (xy 138.960607 -214.724656) (xy 138.992799 -214.764863) (xy 139.019286 -214.809037)
			(xy 139.039584 -214.856375) (xy 139.053325 -214.906015) (xy 139.060258 -214.957053) (xy 139.060293 -214.959184)
			(xy 141.653766 -214.959184) (xy 141.657837 -214.903562) (xy 141.669963 -214.849125) (xy 141.689886 -214.797034)
			(xy 141.717182 -214.748399) (xy 141.751268 -214.704256) (xy 141.791417 -214.665547) (xy 141.836775 -214.633096)
			(xy 141.886375 -214.607595) (xy 141.939159 -214.589588) (xy 141.994002 -214.579458) (xy 142.049736 -214.577421)
			(xy 142.105173 -214.583521) (xy 142.15913 -214.597627) (xy 142.210459 -214.619439) (xy 142.258065 -214.648493)
			(xy 142.300933 -214.684168) (xy 142.33815 -214.725705) (xy 142.368923 -214.772218) (xy 142.392595 -214.822715)
			(xy 142.408663 -214.876122) (xy 142.416783 -214.931298) (xy 142.417292 -214.959184) (xy 142.416783 -214.98707)
			(xy 142.408663 -215.042246) (xy 142.392595 -215.095653) (xy 142.368923 -215.14615) (xy 142.33815 -215.192663)
			(xy 142.300933 -215.2342) (xy 142.258065 -215.269875) (xy 142.210459 -215.298929) (xy 142.15913 -215.320741)
			(xy 142.105173 -215.334847) (xy 142.049736 -215.340947) (xy 141.994002 -215.33891) (xy 141.939159 -215.32878)
			(xy 141.886375 -215.310773) (xy 141.836775 -215.285272) (xy 141.791417 -215.252821) (xy 141.751268 -215.214112)
			(xy 141.717182 -215.169969) (xy 141.689886 -215.121334) (xy 141.669963 -215.069243) (xy 141.657837 -215.014806)
			(xy 141.653766 -214.959184) (xy 139.060293 -214.959184) (xy 139.060682 -214.982806) (xy 139.060196 -215.010057)
			(xy 139.05244 -215.064005) (xy 139.037085 -215.1163) (xy 139.014443 -215.165877) (xy 138.984977 -215.211727)
			(xy 138.949286 -215.252918) (xy 138.908095 -215.288609) (xy 138.862245 -215.318075) (xy 138.812668 -215.340717)
			(xy 138.760373 -215.356072) (xy 138.706425 -215.363828) (xy 138.651923 -215.363828) (xy 138.597975 -215.356072)
			(xy 138.54568 -215.340717) (xy 138.496103 -215.318075) (xy 138.450253 -215.288609) (xy 138.409062 -215.252918)
			(xy 138.373371 -215.211727) (xy 138.343905 -215.165877) (xy 138.321263 -215.1163) (xy 138.305908 -215.064005)
			(xy 138.298152 -215.010057) (xy 138.297666 -214.982806) (xy 135.0235 -214.982806) (xy 134.982889 -215.007591)
			(xy 134.93156 -215.029403) (xy 134.877603 -215.043509) (xy 134.822166 -215.049609) (xy 134.766432 -215.047572)
			(xy 134.711589 -215.037442) (xy 134.658805 -215.019435) (xy 134.609205 -214.993934) (xy 134.563847 -214.961483)
			(xy 134.523698 -214.922774) (xy 134.489612 -214.878631) (xy 134.462316 -214.829996) (xy 134.442393 -214.777905)
			(xy 134.430267 -214.723468) (xy 134.426196 -214.667846) (xy 133.665722 -214.667846) (xy 133.665213 -214.695732)
			(xy 133.657093 -214.750908) (xy 133.641025 -214.804315) (xy 133.617353 -214.854812) (xy 133.58658 -214.901325)
			(xy 133.549363 -214.942862) (xy 133.506495 -214.978537) (xy 133.458889 -215.007591) (xy 133.40756 -215.029403)
			(xy 133.353603 -215.043509) (xy 133.298166 -215.049609) (xy 133.242432 -215.047572) (xy 133.187589 -215.037442)
			(xy 133.134805 -215.019435) (xy 133.085205 -214.993934) (xy 133.039847 -214.961483) (xy 132.999698 -214.922774)
			(xy 132.965612 -214.878631) (xy 132.938316 -214.829996) (xy 132.918393 -214.777905) (xy 132.906267 -214.723468)
			(xy 132.902196 -214.667846) (xy 132.550501 -214.667846) (xy 132.565246 -214.684303) (xy 132.596019 -214.730816)
			(xy 132.619691 -214.781313) (xy 132.635759 -214.83472) (xy 132.643879 -214.889896) (xy 132.644388 -214.917782)
			(xy 132.643879 -214.945668) (xy 132.635759 -215.000844) (xy 132.619691 -215.054251) (xy 132.596019 -215.104748)
			(xy 132.56965 -215.144604) (xy 133.662164 -215.144604) (xy 133.666235 -215.088982) (xy 133.678361 -215.034545)
			(xy 133.698284 -214.982454) (xy 133.72558 -214.933819) (xy 133.759666 -214.889676) (xy 133.799815 -214.850967)
			(xy 133.845173 -214.818516) (xy 133.894773 -214.793015) (xy 133.947557 -214.775008) (xy 134.0024 -214.764878)
			(xy 134.058134 -214.762841) (xy 134.113571 -214.768941) (xy 134.167528 -214.783047) (xy 134.218857 -214.804859)
			(xy 134.266463 -214.833913) (xy 134.309331 -214.869588) (xy 134.346548 -214.911125) (xy 134.377321 -214.957638)
			(xy 134.400993 -215.008135) (xy 134.417061 -215.061542) (xy 134.425181 -215.116718) (xy 134.42569 -215.144604)
			(xy 134.425181 -215.17249) (xy 134.417061 -215.227666) (xy 134.400993 -215.281073) (xy 134.377321 -215.33157)
			(xy 134.346548 -215.378083) (xy 134.309331 -215.41962) (xy 134.266463 -215.455295) (xy 134.218857 -215.484349)
			(xy 134.167528 -215.506161) (xy 134.113571 -215.520267) (xy 134.058134 -215.526367) (xy 134.0024 -215.52433)
			(xy 133.947557 -215.5142) (xy 133.894773 -215.496193) (xy 133.845173 -215.470692) (xy 133.799815 -215.438241)
			(xy 133.759666 -215.399532) (xy 133.72558 -215.355389) (xy 133.698284 -215.306754) (xy 133.678361 -215.254663)
			(xy 133.666235 -215.200226) (xy 133.662164 -215.144604) (xy 132.56965 -215.144604) (xy 132.565246 -215.151261)
			(xy 132.528029 -215.192798) (xy 132.485161 -215.228473) (xy 132.437555 -215.257527) (xy 132.386226 -215.279339)
			(xy 132.332269 -215.293445) (xy 132.276832 -215.299545) (xy 132.221098 -215.297508) (xy 132.166255 -215.287378)
			(xy 132.113471 -215.269371) (xy 132.063871 -215.24387) (xy 132.018513 -215.211419) (xy 131.978364 -215.17271)
			(xy 131.944278 -215.128567) (xy 131.916982 -215.079932) (xy 131.897059 -215.027841) (xy 131.884933 -214.973404)
			(xy 131.880862 -214.917782) (xy 130.340651 -214.917782) (xy 130.355093 -214.965784) (xy 130.363213 -215.02096)
			(xy 130.363722 -215.048846) (xy 130.363213 -215.076732) (xy 130.355093 -215.131908) (xy 130.339025 -215.185315)
			(xy 130.315353 -215.235812) (xy 130.28458 -215.282325) (xy 130.247363 -215.323862) (xy 130.204495 -215.359537)
			(xy 130.156889 -215.388591) (xy 130.10556 -215.410403) (xy 130.051603 -215.424509) (xy 129.996166 -215.430609)
			(xy 129.940432 -215.428572) (xy 129.885589 -215.418442) (xy 129.832805 -215.400435) (xy 129.783205 -215.374934)
			(xy 129.737847 -215.342483) (xy 129.697698 -215.303774) (xy 129.663612 -215.259631) (xy 129.636316 -215.210996)
			(xy 129.616393 -215.158905) (xy 129.604267 -215.104468) (xy 129.600196 -215.048846) (xy 128.328551 -215.048846)
			(xy 128.331213 -215.066934) (xy 128.331722 -215.09482) (xy 128.331213 -215.122706) (xy 128.323093 -215.177882)
			(xy 128.307025 -215.231289) (xy 128.283353 -215.281786) (xy 128.25258 -215.328299) (xy 128.215363 -215.369836)
			(xy 128.172495 -215.405511) (xy 128.124889 -215.434565) (xy 128.07356 -215.456377) (xy 128.019603 -215.470483)
			(xy 127.964166 -215.476583) (xy 127.908432 -215.474546) (xy 127.853589 -215.464416) (xy 127.800805 -215.446409)
			(xy 127.751205 -215.420908) (xy 127.705847 -215.388457) (xy 127.665698 -215.349748) (xy 127.631612 -215.305605)
			(xy 127.604316 -215.25697) (xy 127.584393 -215.204879) (xy 127.572267 -215.150442) (xy 127.568196 -215.09482)
			(xy 125.54268 -215.09482) (xy 125.527757 -215.144421) (xy 125.504085 -215.194918) (xy 125.473312 -215.241431)
			(xy 125.436095 -215.282968) (xy 125.393227 -215.318643) (xy 125.345621 -215.347697) (xy 125.294292 -215.369509)
			(xy 125.240335 -215.383615) (xy 125.184898 -215.389715) (xy 125.129164 -215.387678) (xy 125.074321 -215.377548)
			(xy 125.021537 -215.359541) (xy 124.971937 -215.33404) (xy 124.926579 -215.301589) (xy 124.88643 -215.26288)
			(xy 124.852344 -215.218737) (xy 124.825048 -215.170102) (xy 124.805125 -215.118011) (xy 124.792999 -215.063574)
			(xy 124.788928 -215.007952) (xy 122.100019 -215.007952) (xy 122.108949 -215.015384) (xy 122.146166 -215.056921)
			(xy 122.176939 -215.103434) (xy 122.200611 -215.153931) (xy 122.216679 -215.207338) (xy 122.224799 -215.262514)
			(xy 122.225308 -215.2904) (xy 122.224799 -215.318286) (xy 122.216679 -215.373462) (xy 122.200611 -215.426869)
			(xy 122.176939 -215.477366) (xy 122.146166 -215.523879) (xy 122.108949 -215.565416) (xy 122.066081 -215.601091)
			(xy 122.018475 -215.630145) (xy 121.967146 -215.651957) (xy 121.913189 -215.666063) (xy 121.857752 -215.672163)
			(xy 121.802018 -215.670126) (xy 121.747175 -215.659996) (xy 121.694391 -215.641989) (xy 121.644791 -215.616488)
			(xy 121.599433 -215.584037) (xy 121.559284 -215.545328) (xy 121.525198 -215.501185) (xy 121.497902 -215.45255)
			(xy 121.477979 -215.400459) (xy 121.465853 -215.346022) (xy 121.461782 -215.2904) (xy 118.03848 -215.2904)
			(xy 118.037755 -215.291946) (xy 118.006982 -215.338459) (xy 117.969765 -215.379996) (xy 117.926897 -215.415671)
			(xy 117.879291 -215.444725) (xy 117.827962 -215.466537) (xy 117.774005 -215.480643) (xy 117.718568 -215.486743)
			(xy 117.662834 -215.484706) (xy 117.607991 -215.474576) (xy 117.555207 -215.456569) (xy 117.505607 -215.431068)
			(xy 117.460249 -215.398617) (xy 117.4201 -215.359908) (xy 117.386014 -215.315765) (xy 117.358718 -215.26713)
			(xy 117.338795 -215.215039) (xy 117.326669 -215.160602) (xy 117.322598 -215.10498) (xy 91.337384 -215.10498)
			(xy 91.337384 -216.099256) (xy 101.187413 -216.099256) (xy 101.187413 -216.044744) (xy 101.195171 -215.990787)
			(xy 101.210529 -215.938483) (xy 101.233174 -215.888897) (xy 101.262646 -215.843038) (xy 101.298344 -215.801841)
			(xy 101.339542 -215.766143) (xy 101.3854 -215.736672) (xy 101.434986 -215.714027) (xy 101.487291 -215.69867)
			(xy 101.541248 -215.690913) (xy 101.568504 -215.69045) (xy 101.595875 -215.690902) (xy 101.650055 -215.698721)
			(xy 101.702559 -215.714213) (xy 101.752306 -215.737058) (xy 101.798271 -215.766787) (xy 101.819202 -215.78443)
			(xy 101.826314 -215.790526) (xy 101.834696 -215.793574) (xy 101.838981 -215.795103) (xy 101.847928 -215.796756)
			(xy 101.852476 -215.796876) (xy 101.919532 -215.796876) (xy 101.92408 -215.79676) (xy 101.933024 -215.795096)
			(xy 101.937312 -215.793574) (xy 101.945694 -215.790526) (xy 101.952806 -215.78443) (xy 101.973729 -215.766779)
			(xy 102.019704 -215.737068) (xy 102.069453 -215.714234) (xy 102.121956 -215.698746) (xy 102.176134 -215.690922)
			(xy 102.203504 -215.69045) (xy 102.230752 -215.69102) (xy 102.284693 -215.698777) (xy 102.336982 -215.71413)
			(xy 102.386553 -215.736769) (xy 102.432398 -215.766232) (xy 102.473583 -215.80192) (xy 102.50927 -215.843105)
			(xy 102.538733 -215.888951) (xy 102.561371 -215.938522) (xy 102.576724 -215.990811) (xy 102.58448 -216.044752)
			(xy 102.58448 -216.090857) (xy 106.844731 -216.090857) (xy 106.844731 -216.036343) (xy 106.85249 -215.982385)
			(xy 106.867849 -215.93008) (xy 106.890496 -215.880494) (xy 106.919971 -215.834635) (xy 106.955671 -215.793439)
			(xy 106.996872 -215.757743) (xy 107.042734 -215.728274) (xy 107.092323 -215.705633) (xy 107.14463 -215.69028)
			(xy 107.198589 -215.682528) (xy 107.225846 -215.682068) (xy 107.253216 -215.682549) (xy 107.307395 -215.690361)
			(xy 107.359899 -215.705845) (xy 107.409646 -215.728684) (xy 107.455613 -215.758407) (xy 107.476544 -215.776048)
			(xy 107.483656 -215.782144) (xy 107.492038 -215.785192) (xy 107.496328 -215.786707) (xy 107.505271 -215.788369)
			(xy 107.509818 -215.788494) (xy 107.576874 -215.788494) (xy 107.581421 -215.788361) (xy 107.590365 -215.786708)
			(xy 107.594654 -215.785192) (xy 107.603036 -215.782144) (xy 107.610148 -215.776048) (xy 107.631095 -215.758427)
			(xy 107.677063 -215.728711) (xy 107.726807 -215.705871) (xy 107.779304 -215.690376) (xy 107.833478 -215.682544)
			(xy 107.860846 -215.682068) (xy 107.888093 -215.682605) (xy 107.942033 -215.690367) (xy 107.994319 -215.705725)
			(xy 108.043887 -215.728367) (xy 108.069462 -215.744806) (xy 125.525782 -215.744806) (xy 125.529853 -215.689184)
			(xy 125.541979 -215.634747) (xy 125.561902 -215.582656) (xy 125.589198 -215.534021) (xy 125.623284 -215.489878)
			(xy 125.663433 -215.451169) (xy 125.708791 -215.418718) (xy 125.758391 -215.393217) (xy 125.811175 -215.37521)
			(xy 125.866018 -215.36508) (xy 125.921752 -215.363043) (xy 125.977189 -215.369143) (xy 126.031146 -215.383249)
			(xy 126.082475 -215.405061) (xy 126.130081 -215.434115) (xy 126.172949 -215.46979) (xy 126.210166 -215.511327)
			(xy 126.240939 -215.55784) (xy 126.264611 -215.608337) (xy 126.280679 -215.661744) (xy 126.288799 -215.71692)
			(xy 126.289308 -215.744806) (xy 126.288799 -215.772692) (xy 126.280679 -215.827868) (xy 126.264611 -215.881275)
			(xy 126.240939 -215.931772) (xy 126.210166 -215.978285) (xy 126.20771 -215.981026) (xy 138.10818 -215.981026)
			(xy 138.112251 -215.925404) (xy 138.124377 -215.870967) (xy 138.1443 -215.818876) (xy 138.171596 -215.770241)
			(xy 138.205682 -215.726098) (xy 138.245831 -215.687389) (xy 138.291189 -215.654938) (xy 138.340789 -215.629437)
			(xy 138.393573 -215.61143) (xy 138.448416 -215.6013) (xy 138.50415 -215.599263) (xy 138.559587 -215.605363)
			(xy 138.613544 -215.619469) (xy 138.664873 -215.641281) (xy 138.712479 -215.670335) (xy 138.755347 -215.70601)
			(xy 138.792564 -215.747547) (xy 138.823337 -215.79406) (xy 138.847009 -215.844557) (xy 138.863077 -215.897964)
			(xy 138.871197 -215.95314) (xy 138.871706 -215.981026) (xy 138.871335 -216.001346) (xy 138.978892 -216.001346)
			(xy 138.982963 -215.945724) (xy 138.995089 -215.891287) (xy 139.015012 -215.839196) (xy 139.042308 -215.790561)
			(xy 139.076394 -215.746418) (xy 139.116543 -215.707709) (xy 139.161901 -215.675258) (xy 139.211501 -215.649757)
			(xy 139.264285 -215.63175) (xy 139.319128 -215.62162) (xy 139.374862 -215.619583) (xy 139.430299 -215.625683)
			(xy 139.484256 -215.639789) (xy 139.535585 -215.661601) (xy 139.583191 -215.690655) (xy 139.626059 -215.72633)
			(xy 139.663276 -215.767867) (xy 139.694049 -215.81438) (xy 139.717721 -215.864877) (xy 139.733789 -215.918284)
			(xy 139.741909 -215.97346) (xy 139.742418 -216.001346) (xy 139.741909 -216.029232) (xy 139.733789 -216.084408)
			(xy 139.717721 -216.137815) (xy 139.694049 -216.188312) (xy 139.663276 -216.234825) (xy 139.626059 -216.276362)
			(xy 139.583191 -216.312037) (xy 139.56371 -216.323926) (xy 141.308326 -216.323926) (xy 141.312397 -216.268304)
			(xy 141.324523 -216.213867) (xy 141.344446 -216.161776) (xy 141.371742 -216.113141) (xy 141.405828 -216.068998)
			(xy 141.445977 -216.030289) (xy 141.491335 -215.997838) (xy 141.540935 -215.972337) (xy 141.593719 -215.95433)
			(xy 141.648562 -215.9442) (xy 141.704296 -215.942163) (xy 141.759733 -215.948263) (xy 141.81369 -215.962369)
			(xy 141.865019 -215.984181) (xy 141.912625 -216.013235) (xy 141.955493 -216.04891) (xy 141.99271 -216.090447)
			(xy 142.023483 -216.13696) (xy 142.047155 -216.187457) (xy 142.063223 -216.240864) (xy 142.071343 -216.29604)
			(xy 142.071852 -216.323926) (xy 142.071343 -216.351812) (xy 142.063223 -216.406988) (xy 142.047155 -216.460395)
			(xy 142.023483 -216.510892) (xy 141.99271 -216.557405) (xy 141.955493 -216.598942) (xy 141.912625 -216.634617)
			(xy 141.865019 -216.663671) (xy 141.81369 -216.685483) (xy 141.759733 -216.699589) (xy 141.704296 -216.705689)
			(xy 141.648562 -216.703652) (xy 141.593719 -216.693522) (xy 141.540935 -216.675515) (xy 141.491335 -216.650014)
			(xy 141.445977 -216.617563) (xy 141.405828 -216.578854) (xy 141.371742 -216.534711) (xy 141.344446 -216.486076)
			(xy 141.324523 -216.433985) (xy 141.312397 -216.379548) (xy 141.308326 -216.323926) (xy 139.56371 -216.323926)
			(xy 139.535585 -216.341091) (xy 139.484256 -216.362903) (xy 139.430299 -216.377009) (xy 139.374862 -216.383109)
			(xy 139.319128 -216.381072) (xy 139.264285 -216.370942) (xy 139.211501 -216.352935) (xy 139.161901 -216.327434)
			(xy 139.116543 -216.294983) (xy 139.076394 -216.256274) (xy 139.042308 -216.212131) (xy 139.015012 -216.163496)
			(xy 138.995089 -216.111405) (xy 138.982963 -216.056968) (xy 138.978892 -216.001346) (xy 138.871335 -216.001346)
			(xy 138.871197 -216.008912) (xy 138.863077 -216.064088) (xy 138.847009 -216.117495) (xy 138.823337 -216.167992)
			(xy 138.792564 -216.214505) (xy 138.755347 -216.256042) (xy 138.712479 -216.291717) (xy 138.664873 -216.320771)
			(xy 138.613544 -216.342583) (xy 138.559587 -216.356689) (xy 138.50415 -216.362789) (xy 138.448416 -216.360752)
			(xy 138.393573 -216.350622) (xy 138.340789 -216.332615) (xy 138.291189 -216.307114) (xy 138.245831 -216.274663)
			(xy 138.205682 -216.235954) (xy 138.171596 -216.191811) (xy 138.1443 -216.143176) (xy 138.124377 -216.091085)
			(xy 138.112251 -216.036648) (xy 138.10818 -215.981026) (xy 126.20771 -215.981026) (xy 126.172949 -216.019822)
			(xy 126.130081 -216.055497) (xy 126.082475 -216.084551) (xy 126.031146 -216.106363) (xy 125.977189 -216.120469)
			(xy 125.921752 -216.126569) (xy 125.866018 -216.124532) (xy 125.811175 -216.114402) (xy 125.758391 -216.096395)
			(xy 125.708791 -216.070894) (xy 125.663433 -216.038443) (xy 125.623284 -215.999734) (xy 125.589198 -215.955591)
			(xy 125.561902 -215.906956) (xy 125.541979 -215.854865) (xy 125.529853 -215.800428) (xy 125.525782 -215.744806)
			(xy 108.069462 -215.744806) (xy 108.089728 -215.757833) (xy 108.130911 -215.793522) (xy 108.166595 -215.834708)
			(xy 108.196055 -215.880554) (xy 108.218691 -215.930125) (xy 108.234043 -215.982412) (xy 108.241798 -216.036353)
			(xy 108.241798 -216.090847) (xy 108.234043 -216.144788) (xy 108.218691 -216.197075) (xy 108.196055 -216.246646)
			(xy 108.166595 -216.292492) (xy 108.130911 -216.333678) (xy 108.089728 -216.369367) (xy 108.043887 -216.398833)
			(xy 107.994319 -216.421475) (xy 107.942033 -216.436833) (xy 107.888093 -216.444595) (xy 107.860846 -216.445084)
			(xy 107.833477 -216.444595) (xy 107.779298 -216.436783) (xy 107.726795 -216.4213) (xy 107.677048 -216.398463)
			(xy 107.63108 -216.368743) (xy 107.610148 -216.351104) (xy 107.603036 -216.345008) (xy 107.594654 -216.34196)
			(xy 107.590364 -216.340445) (xy 107.581421 -216.338782) (xy 107.576874 -216.338658) (xy 107.509818 -216.338658)
			(xy 107.50527 -216.338779) (xy 107.496325 -216.340436) (xy 107.492038 -216.34196) (xy 107.483656 -216.345008)
			(xy 107.476544 -216.351104) (xy 107.455607 -216.368737) (xy 107.409635 -216.398449) (xy 107.359889 -216.421286)
			(xy 107.30739 -216.436779) (xy 107.253215 -216.444609) (xy 107.225846 -216.445084) (xy 107.198589 -216.444672)
			(xy 107.14463 -216.43692) (xy 107.092323 -216.421567) (xy 107.042734 -216.398926) (xy 106.996872 -216.369457)
			(xy 106.955671 -216.333761) (xy 106.919971 -216.292565) (xy 106.890496 -216.246706) (xy 106.867849 -216.19712)
			(xy 106.85249 -216.144815) (xy 106.844731 -216.090857) (xy 102.58448 -216.090857) (xy 102.58448 -216.099248)
			(xy 102.576724 -216.153189) (xy 102.561371 -216.205478) (xy 102.538733 -216.255049) (xy 102.50927 -216.300895)
			(xy 102.473583 -216.34208) (xy 102.432398 -216.377768) (xy 102.386553 -216.407231) (xy 102.336982 -216.42987)
			(xy 102.284693 -216.445223) (xy 102.230752 -216.45298) (xy 102.203504 -216.453466) (xy 102.176133 -216.453006)
			(xy 102.121954 -216.445188) (xy 102.06945 -216.429698) (xy 102.019703 -216.406855) (xy 101.973737 -216.377128)
			(xy 101.952806 -216.359486) (xy 101.945694 -216.35339) (xy 101.937312 -216.350342) (xy 101.933026 -216.348816)
			(xy 101.92408 -216.347161) (xy 101.919532 -216.34704) (xy 101.852476 -216.34704) (xy 101.847928 -216.347157)
			(xy 101.838984 -216.348821) (xy 101.834696 -216.350342) (xy 101.826314 -216.35339) (xy 101.819202 -216.359486)
			(xy 101.798278 -216.377135) (xy 101.752303 -216.406846) (xy 101.702554 -216.42968) (xy 101.650051 -216.445169)
			(xy 101.595874 -216.452994) (xy 101.568504 -216.453466) (xy 101.541248 -216.453087) (xy 101.487291 -216.44533)
			(xy 101.434986 -216.429973) (xy 101.3854 -216.407328) (xy 101.339542 -216.377857) (xy 101.298344 -216.342159)
			(xy 101.262646 -216.300962) (xy 101.233174 -216.255103) (xy 101.210529 -216.205517) (xy 101.195171 -216.153213)
			(xy 101.187413 -216.099256) (xy 91.337384 -216.099256) (xy 91.337384 -218.122857) (xy 106.844731 -218.122857)
			(xy 106.844731 -218.068343) (xy 106.85249 -218.014385) (xy 106.867849 -217.96208) (xy 106.890496 -217.912494)
			(xy 106.919971 -217.866635) (xy 106.955671 -217.825439) (xy 106.996872 -217.789743) (xy 107.042734 -217.760274)
			(xy 107.092323 -217.737633) (xy 107.14463 -217.72228) (xy 107.198589 -217.714528) (xy 107.225846 -217.714068)
			(xy 107.253216 -217.714549) (xy 107.307395 -217.722361) (xy 107.359899 -217.737845) (xy 107.409646 -217.760684)
			(xy 107.455613 -217.790407) (xy 107.476544 -217.808048) (xy 107.483656 -217.814144) (xy 107.492038 -217.817192)
			(xy 107.496328 -217.818707) (xy 107.505271 -217.820369) (xy 107.509818 -217.820494) (xy 107.576874 -217.820494)
			(xy 107.581421 -217.820361) (xy 107.590365 -217.818708) (xy 107.594654 -217.817192) (xy 107.603036 -217.814144)
			(xy 107.610148 -217.808048) (xy 107.631095 -217.790427) (xy 107.677063 -217.760711) (xy 107.726807 -217.737871)
			(xy 107.779304 -217.722376) (xy 107.833478 -217.714544) (xy 107.860846 -217.714068) (xy 107.888093 -217.714605)
			(xy 107.942033 -217.722367) (xy 107.994319 -217.737725) (xy 108.043887 -217.760367) (xy 108.089728 -217.789833)
			(xy 108.130911 -217.825522) (xy 108.166595 -217.866708) (xy 108.196055 -217.912554) (xy 108.218691 -217.962125)
			(xy 108.234043 -218.014412) (xy 108.241798 -218.068353) (xy 108.241798 -218.122847) (xy 108.234043 -218.176788)
			(xy 108.218691 -218.229075) (xy 108.214816 -218.237562) (xy 117.254018 -218.237562) (xy 117.258089 -218.18194)
			(xy 117.270215 -218.127503) (xy 117.290138 -218.075412) (xy 117.317434 -218.026777) (xy 117.35152 -217.982634)
			(xy 117.391669 -217.943925) (xy 117.437027 -217.911474) (xy 117.486627 -217.885973) (xy 117.539411 -217.867966)
			(xy 117.594254 -217.857836) (xy 117.649988 -217.855799) (xy 117.705425 -217.861899) (xy 117.759382 -217.876005)
			(xy 117.810711 -217.897817) (xy 117.83301 -217.911426) (xy 120.186194 -217.911426) (xy 120.190265 -217.855804)
			(xy 120.202391 -217.801367) (xy 120.222314 -217.749276) (xy 120.24961 -217.700641) (xy 120.283696 -217.656498)
			(xy 120.323845 -217.617789) (xy 120.369203 -217.585338) (xy 120.418803 -217.559837) (xy 120.471587 -217.54183)
			(xy 120.52643 -217.5317) (xy 120.582164 -217.529663) (xy 120.637601 -217.535763) (xy 120.691558 -217.549869)
			(xy 120.742887 -217.571681) (xy 120.790493 -217.600735) (xy 120.833361 -217.63641) (xy 120.849176 -217.654061)
			(xy 123.690028 -217.654061) (xy 123.697783 -217.600106) (xy 123.713138 -217.547803) (xy 123.735781 -217.498218)
			(xy 123.76525 -217.45236) (xy 123.800945 -217.411162) (xy 123.84214 -217.375464) (xy 123.887997 -217.345993)
			(xy 123.93758 -217.323347) (xy 123.989882 -217.307988) (xy 124.043838 -217.300229) (xy 124.098348 -217.300228)
			(xy 124.152303 -217.307985) (xy 124.204606 -217.323342) (xy 124.254191 -217.345985) (xy 124.300048 -217.375456)
			(xy 124.341244 -217.411152) (xy 124.376941 -217.452348) (xy 124.406412 -217.498205) (xy 124.429056 -217.547789)
			(xy 124.444414 -217.600091) (xy 124.452171 -217.654047) (xy 124.452634 -217.681302) (xy 124.452254 -217.704857)
			(xy 124.446397 -217.751601) (xy 124.44095 -217.77452) (xy 124.437816 -217.788931) (xy 124.439087 -217.818385)
			(xy 124.448711 -217.846251) (xy 124.465888 -217.870211) (xy 124.489189 -217.888271) (xy 124.516676 -217.89893)
			(xy 124.546062 -217.9013) (xy 124.560584 -217.898726) (xy 124.579854 -217.894924) (xy 124.618922 -217.890853)
			(xy 124.638562 -217.890598) (xy 124.639324 -217.890598) (xy 124.666573 -217.891104) (xy 124.720516 -217.898863)
			(xy 124.772806 -217.91422) (xy 124.822378 -217.936862) (xy 124.868223 -217.966328) (xy 124.909408 -218.002019)
			(xy 124.945094 -218.043208) (xy 124.974556 -218.089056) (xy 124.997193 -218.13863) (xy 125.012545 -218.190921)
			(xy 125.020299 -218.244865) (xy 125.020297 -218.299363) (xy 125.012539 -218.353306) (xy 124.997184 -218.405596)
			(xy 124.974543 -218.455169) (xy 124.945078 -218.501015) (xy 124.909388 -218.542201) (xy 124.8682 -218.577888)
			(xy 124.822353 -218.607351) (xy 124.772779 -218.62999) (xy 124.720489 -218.645343) (xy 124.666545 -218.653098)
			(xy 124.612047 -218.653098) (xy 124.558104 -218.645341) (xy 124.505813 -218.629987) (xy 124.45624 -218.607348)
			(xy 124.410393 -218.577884) (xy 124.369206 -218.542195) (xy 124.333518 -218.501008) (xy 124.304053 -218.455162)
			(xy 124.281414 -218.405589) (xy 124.266059 -218.353298) (xy 124.258303 -218.299355) (xy 124.257816 -218.272106)
			(xy 124.258199 -218.248552) (xy 124.264054 -218.201807) (xy 124.2695 -218.178888) (xy 124.272566 -218.164466)
			(xy 124.271297 -218.135025) (xy 124.26168 -218.10717) (xy 124.244514 -218.083217) (xy 124.221227 -218.065159)
			(xy 124.193755 -218.054496) (xy 124.164383 -218.052115) (xy 124.149866 -218.054682) (xy 124.130595 -218.058476)
			(xy 124.091527 -218.062553) (xy 124.071888 -218.06281) (xy 124.071126 -218.06281) (xy 124.043871 -218.062373)
			(xy 123.989915 -218.054619) (xy 123.937612 -218.039265) (xy 123.888026 -218.016623) (xy 123.842167 -217.987156)
			(xy 123.800969 -217.951461) (xy 123.76527 -217.910267) (xy 123.735797 -217.864412) (xy 123.71315 -217.814828)
			(xy 123.69779 -217.762527) (xy 123.69003 -217.708572) (xy 123.690028 -217.654061) (xy 120.849176 -217.654061)
			(xy 120.870578 -217.677947) (xy 120.901351 -217.72446) (xy 120.925023 -217.774957) (xy 120.941091 -217.828364)
			(xy 120.949211 -217.88354) (xy 120.94972 -217.911426) (xy 120.949211 -217.939312) (xy 120.941091 -217.994488)
			(xy 120.925023 -218.047895) (xy 120.901351 -218.098392) (xy 120.870578 -218.144905) (xy 120.833361 -218.186442)
			(xy 120.790493 -218.222117) (xy 120.742887 -218.251171) (xy 120.691558 -218.272983) (xy 120.637601 -218.287089)
			(xy 120.582164 -218.293189) (xy 120.52643 -218.291152) (xy 120.471587 -218.281022) (xy 120.418803 -218.263015)
			(xy 120.369203 -218.237514) (xy 120.323845 -218.205063) (xy 120.283696 -218.166354) (xy 120.24961 -218.122211)
			(xy 120.222314 -218.073576) (xy 120.202391 -218.021485) (xy 120.190265 -217.967048) (xy 120.186194 -217.911426)
			(xy 117.83301 -217.911426) (xy 117.858317 -217.926871) (xy 117.901185 -217.962546) (xy 117.938402 -218.004083)
			(xy 117.969175 -218.050596) (xy 117.992847 -218.101093) (xy 118.008915 -218.1545) (xy 118.017035 -218.209676)
			(xy 118.017544 -218.237562) (xy 118.017035 -218.265448) (xy 118.008915 -218.320624) (xy 117.992847 -218.374031)
			(xy 117.969175 -218.424528) (xy 117.938402 -218.471041) (xy 117.901185 -218.512578) (xy 117.858317 -218.548253)
			(xy 117.810711 -218.577307) (xy 117.759382 -218.599119) (xy 117.705425 -218.613225) (xy 117.649988 -218.619325)
			(xy 117.594254 -218.617288) (xy 117.539411 -218.607158) (xy 117.486627 -218.589151) (xy 117.437027 -218.56365)
			(xy 117.391669 -218.531199) (xy 117.35152 -218.49249) (xy 117.317434 -218.448347) (xy 117.290138 -218.399712)
			(xy 117.270215 -218.347621) (xy 117.258089 -218.293184) (xy 117.254018 -218.237562) (xy 108.214816 -218.237562)
			(xy 108.196055 -218.278646) (xy 108.166595 -218.324492) (xy 108.130911 -218.365678) (xy 108.089728 -218.401367)
			(xy 108.043887 -218.430833) (xy 107.994319 -218.453475) (xy 107.942033 -218.468833) (xy 107.888093 -218.476595)
			(xy 107.860846 -218.477084) (xy 107.833477 -218.476595) (xy 107.779298 -218.468783) (xy 107.726795 -218.4533)
			(xy 107.677048 -218.430463) (xy 107.63108 -218.400743) (xy 107.610148 -218.383104) (xy 107.603036 -218.377008)
			(xy 107.594654 -218.37396) (xy 107.590364 -218.372445) (xy 107.581421 -218.370782) (xy 107.576874 -218.370658)
			(xy 107.509818 -218.370658) (xy 107.50527 -218.370779) (xy 107.496325 -218.372436) (xy 107.492038 -218.37396)
			(xy 107.483656 -218.377008) (xy 107.476544 -218.383104) (xy 107.455607 -218.400737) (xy 107.409635 -218.430449)
			(xy 107.359889 -218.453286) (xy 107.30739 -218.468779) (xy 107.253215 -218.476609) (xy 107.225846 -218.477084)
			(xy 107.198589 -218.476672) (xy 107.14463 -218.46892) (xy 107.092323 -218.453567) (xy 107.042734 -218.430926)
			(xy 106.996872 -218.401457) (xy 106.955671 -218.365761) (xy 106.919971 -218.324565) (xy 106.890496 -218.278706)
			(xy 106.867849 -218.22912) (xy 106.85249 -218.176815) (xy 106.844731 -218.122857) (xy 91.337384 -218.122857)
			(xy 91.337384 -218.57589) (xy 97.01733 -218.57589) (xy 97.021401 -218.520268) (xy 97.033527 -218.465831)
			(xy 97.05345 -218.41374) (xy 97.080746 -218.365105) (xy 97.114832 -218.320962) (xy 97.154981 -218.282253)
			(xy 97.200339 -218.249802) (xy 97.249939 -218.224301) (xy 97.302723 -218.206294) (xy 97.357566 -218.196164)
			(xy 97.4133 -218.194127) (xy 97.468737 -218.200227) (xy 97.522694 -218.214333) (xy 97.574023 -218.236145)
			(xy 97.621629 -218.265199) (xy 97.664497 -218.300874) (xy 97.701714 -218.342411) (xy 97.732487 -218.388924)
			(xy 97.756159 -218.439421) (xy 97.772227 -218.492828) (xy 97.780347 -218.548004) (xy 97.780856 -218.57589)
			(xy 97.780347 -218.603776) (xy 97.772227 -218.658952) (xy 97.756159 -218.712359) (xy 97.732487 -218.762856)
			(xy 97.701714 -218.809369) (xy 97.664497 -218.850906) (xy 97.621629 -218.886581) (xy 97.574023 -218.915635)
			(xy 97.522694 -218.937447) (xy 97.511475 -218.94038) (xy 117.85295 -218.94038) (xy 117.857021 -218.884758)
			(xy 117.869147 -218.830321) (xy 117.88907 -218.77823) (xy 117.916366 -218.729595) (xy 117.950452 -218.685452)
			(xy 117.990601 -218.646743) (xy 118.035959 -218.614292) (xy 118.085559 -218.588791) (xy 118.138343 -218.570784)
			(xy 118.193186 -218.560654) (xy 118.24892 -218.558617) (xy 118.304357 -218.564717) (xy 118.358314 -218.578823)
			(xy 118.409643 -218.600635) (xy 118.457249 -218.629689) (xy 118.478062 -218.64701) (xy 120.921778 -218.64701)
			(xy 120.925849 -218.591388) (xy 120.937975 -218.536951) (xy 120.957898 -218.48486) (xy 120.985194 -218.436225)
			(xy 121.01928 -218.392082) (xy 121.059429 -218.353373) (xy 121.104787 -218.320922) (xy 121.154387 -218.295421)
			(xy 121.207171 -218.277414) (xy 121.262014 -218.267284) (xy 121.317748 -218.265247) (xy 121.373185 -218.271347)
			(xy 121.427142 -218.285453) (xy 121.478471 -218.307265) (xy 121.526077 -218.336319) (xy 121.568945 -218.371994)
			(xy 121.606162 -218.413531) (xy 121.636935 -218.460044) (xy 121.660607 -218.510541) (xy 121.676675 -218.563948)
			(xy 121.684795 -218.619124) (xy 121.685304 -218.64701) (xy 121.684795 -218.674896) (xy 121.676675 -218.730072)
			(xy 121.660607 -218.783479) (xy 121.638493 -218.830652) (xy 126.526542 -218.830652) (xy 126.530613 -218.77503)
			(xy 126.542739 -218.720593) (xy 126.562662 -218.668502) (xy 126.589958 -218.619867) (xy 126.624044 -218.575724)
			(xy 126.664193 -218.537015) (xy 126.709551 -218.504564) (xy 126.759151 -218.479063) (xy 126.811935 -218.461056)
			(xy 126.866778 -218.450926) (xy 126.922512 -218.448889) (xy 126.977949 -218.454989) (xy 127.031906 -218.469095)
			(xy 127.083235 -218.490907) (xy 127.130841 -218.519961) (xy 127.173709 -218.555636) (xy 127.210926 -218.597173)
			(xy 127.241699 -218.643686) (xy 127.265371 -218.694183) (xy 127.281439 -218.74759) (xy 127.289559 -218.802766)
			(xy 127.290068 -218.830652) (xy 127.289559 -218.858538) (xy 127.281439 -218.913714) (xy 127.265371 -218.967121)
			(xy 127.241699 -219.017618) (xy 127.210926 -219.064131) (xy 127.173709 -219.105668) (xy 127.130841 -219.141343)
			(xy 127.083235 -219.170397) (xy 127.031906 -219.192209) (xy 126.977949 -219.206315) (xy 126.959455 -219.20835)
			(xy 127.477264 -219.20835) (xy 127.481335 -219.152728) (xy 127.493461 -219.098291) (xy 127.513384 -219.0462)
			(xy 127.54068 -218.997565) (xy 127.574766 -218.953422) (xy 127.614915 -218.914713) (xy 127.660273 -218.882262)
			(xy 127.709873 -218.856761) (xy 127.762657 -218.838754) (xy 127.8175 -218.828624) (xy 127.873234 -218.826587)
			(xy 127.928671 -218.832687) (xy 127.982628 -218.846793) (xy 128.033957 -218.868605) (xy 128.081563 -218.897659)
			(xy 128.124431 -218.933334) (xy 128.161648 -218.974871) (xy 128.192421 -219.021384) (xy 128.216093 -219.071881)
			(xy 128.232161 -219.125288) (xy 128.240281 -219.180464) (xy 128.24079 -219.20835) (xy 128.240281 -219.236236)
			(xy 128.232161 -219.291412) (xy 128.216093 -219.344819) (xy 128.192421 -219.395316) (xy 128.161648 -219.441829)
			(xy 128.124431 -219.483366) (xy 128.081563 -219.519041) (xy 128.033957 -219.548095) (xy 127.982628 -219.569907)
			(xy 127.928671 -219.584013) (xy 127.873234 -219.590113) (xy 127.8175 -219.588076) (xy 127.762657 -219.577946)
			(xy 127.709873 -219.559939) (xy 127.660273 -219.534438) (xy 127.614915 -219.501987) (xy 127.574766 -219.463278)
			(xy 127.54068 -219.419135) (xy 127.513384 -219.3705) (xy 127.493461 -219.318409) (xy 127.481335 -219.263972)
			(xy 127.477264 -219.20835) (xy 126.959455 -219.20835) (xy 126.922512 -219.212415) (xy 126.866778 -219.210378)
			(xy 126.811935 -219.200248) (xy 126.759151 -219.182241) (xy 126.709551 -219.15674) (xy 126.664193 -219.124289)
			(xy 126.624044 -219.08558) (xy 126.589958 -219.041437) (xy 126.562662 -218.992802) (xy 126.542739 -218.940711)
			(xy 126.530613 -218.886274) (xy 126.526542 -218.830652) (xy 121.638493 -218.830652) (xy 121.636935 -218.833976)
			(xy 121.606162 -218.880489) (xy 121.568945 -218.922026) (xy 121.526077 -218.957701) (xy 121.478471 -218.986755)
			(xy 121.427142 -219.008567) (xy 121.373185 -219.022673) (xy 121.317748 -219.028773) (xy 121.262014 -219.026736)
			(xy 121.207171 -219.016606) (xy 121.154387 -218.998599) (xy 121.104787 -218.973098) (xy 121.059429 -218.940647)
			(xy 121.01928 -218.901938) (xy 120.985194 -218.857795) (xy 120.957898 -218.80916) (xy 120.937975 -218.757069)
			(xy 120.925849 -218.702632) (xy 120.921778 -218.64701) (xy 118.478062 -218.64701) (xy 118.500117 -218.665364)
			(xy 118.537334 -218.706901) (xy 118.568107 -218.753414) (xy 118.591779 -218.803911) (xy 118.607847 -218.857318)
			(xy 118.615967 -218.912494) (xy 118.616476 -218.94038) (xy 118.615967 -218.968266) (xy 118.607847 -219.023442)
			(xy 118.591779 -219.076849) (xy 118.568107 -219.127346) (xy 118.537334 -219.173859) (xy 118.500117 -219.215396)
			(xy 118.457249 -219.251071) (xy 118.409643 -219.280125) (xy 118.358314 -219.301937) (xy 118.304357 -219.316043)
			(xy 118.24892 -219.322143) (xy 118.193186 -219.320106) (xy 118.138343 -219.309976) (xy 118.085559 -219.291969)
			(xy 118.035959 -219.266468) (xy 117.990601 -219.234017) (xy 117.950452 -219.195308) (xy 117.916366 -219.151165)
			(xy 117.88907 -219.10253) (xy 117.869147 -219.050439) (xy 117.857021 -218.996002) (xy 117.85295 -218.94038)
			(xy 97.511475 -218.94038) (xy 97.468737 -218.951553) (xy 97.4133 -218.957653) (xy 97.357566 -218.955616)
			(xy 97.302723 -218.945486) (xy 97.249939 -218.927479) (xy 97.200339 -218.901978) (xy 97.154981 -218.869527)
			(xy 97.114832 -218.830818) (xy 97.080746 -218.786675) (xy 97.05345 -218.73804) (xy 97.033527 -218.685949)
			(xy 97.021401 -218.631512) (xy 97.01733 -218.57589) (xy 91.337384 -218.57589) (xy 91.337384 -219.559886)
			(xy 100.279706 -219.559886) (xy 100.283777 -219.504264) (xy 100.295903 -219.449827) (xy 100.315826 -219.397736)
			(xy 100.343122 -219.349101) (xy 100.377208 -219.304958) (xy 100.417357 -219.266249) (xy 100.462715 -219.233798)
			(xy 100.512315 -219.208297) (xy 100.565099 -219.19029) (xy 100.619942 -219.18016) (xy 100.675676 -219.178123)
			(xy 100.731113 -219.184223) (xy 100.78507 -219.198329) (xy 100.836399 -219.220141) (xy 100.884005 -219.249195)
			(xy 100.926873 -219.28487) (xy 100.96409 -219.326407) (xy 100.994863 -219.37292) (xy 101.018535 -219.423417)
			(xy 101.034603 -219.476824) (xy 101.042723 -219.532) (xy 101.043223 -219.559378) (xy 102.352854 -219.559378)
			(xy 102.356925 -219.503756) (xy 102.369051 -219.449319) (xy 102.388974 -219.397228) (xy 102.41627 -219.348593)
			(xy 102.450356 -219.30445) (xy 102.490505 -219.265741) (xy 102.535863 -219.23329) (xy 102.585463 -219.207789)
			(xy 102.638247 -219.189782) (xy 102.69309 -219.179652) (xy 102.748824 -219.177615) (xy 102.804261 -219.183715)
			(xy 102.858218 -219.197821) (xy 102.909547 -219.219633) (xy 102.957153 -219.248687) (xy 103.000021 -219.284362)
			(xy 103.037238 -219.325899) (xy 103.068011 -219.372412) (xy 103.091683 -219.422909) (xy 103.107751 -219.476316)
			(xy 103.115871 -219.531492) (xy 103.11638 -219.559378) (xy 103.115871 -219.587264) (xy 103.107751 -219.64244)
			(xy 103.091683 -219.695847) (xy 103.068011 -219.746344) (xy 103.037238 -219.792857) (xy 103.022265 -219.809568)
			(xy 126.23876 -219.809568) (xy 126.242831 -219.753946) (xy 126.254957 -219.699509) (xy 126.27488 -219.647418)
			(xy 126.302176 -219.598783) (xy 126.336262 -219.55464) (xy 126.376411 -219.515931) (xy 126.421769 -219.48348)
			(xy 126.471369 -219.457979) (xy 126.524153 -219.439972) (xy 126.578996 -219.429842) (xy 126.63473 -219.427805)
			(xy 126.690167 -219.433905) (xy 126.744124 -219.448011) (xy 126.795453 -219.469823) (xy 126.843059 -219.498877)
			(xy 126.885927 -219.534552) (xy 126.923144 -219.576089) (xy 126.953917 -219.622602) (xy 126.977589 -219.673099)
			(xy 126.993657 -219.726506) (xy 127.001777 -219.781682) (xy 127.002286 -219.809568) (xy 127.001777 -219.837454)
			(xy 126.993657 -219.89263) (xy 126.977589 -219.946037) (xy 126.953917 -219.996534) (xy 126.923144 -220.043047)
			(xy 126.885927 -220.084584) (xy 126.843059 -220.120259) (xy 126.795453 -220.149313) (xy 126.744124 -220.171125)
			(xy 126.690167 -220.185231) (xy 126.63473 -220.191331) (xy 126.578996 -220.189294) (xy 126.524153 -220.179164)
			(xy 126.471369 -220.161157) (xy 126.421769 -220.135656) (xy 126.376411 -220.103205) (xy 126.336262 -220.064496)
			(xy 126.302176 -220.020353) (xy 126.27488 -219.971718) (xy 126.254957 -219.919627) (xy 126.242831 -219.86519)
			(xy 126.23876 -219.809568) (xy 103.022265 -219.809568) (xy 103.000021 -219.834394) (xy 102.957153 -219.870069)
			(xy 102.909547 -219.899123) (xy 102.858218 -219.920935) (xy 102.804261 -219.935041) (xy 102.748824 -219.941141)
			(xy 102.69309 -219.939104) (xy 102.638247 -219.928974) (xy 102.585463 -219.910967) (xy 102.535863 -219.885466)
			(xy 102.490505 -219.853015) (xy 102.450356 -219.814306) (xy 102.41627 -219.770163) (xy 102.388974 -219.721528)
			(xy 102.369051 -219.669437) (xy 102.356925 -219.615) (xy 102.352854 -219.559378) (xy 101.043223 -219.559378)
			(xy 101.043232 -219.559886) (xy 101.042723 -219.587772) (xy 101.034603 -219.642948) (xy 101.018535 -219.696355)
			(xy 100.994863 -219.746852) (xy 100.96409 -219.793365) (xy 100.926873 -219.834902) (xy 100.884005 -219.870577)
			(xy 100.836399 -219.899631) (xy 100.78507 -219.921443) (xy 100.731113 -219.935549) (xy 100.675676 -219.941649)
			(xy 100.619942 -219.939612) (xy 100.565099 -219.929482) (xy 100.512315 -219.911475) (xy 100.462715 -219.885974)
			(xy 100.417357 -219.853523) (xy 100.377208 -219.814814) (xy 100.343122 -219.770671) (xy 100.315826 -219.722036)
			(xy 100.295903 -219.669945) (xy 100.283777 -219.615508) (xy 100.279706 -219.559886) (xy 91.337384 -219.559886)
			(xy 91.337384 -220.316044) (xy 91.337384 -220.318584) (xy 91.337892 -220.334332) (xy 91.337892 -220.33484)
			(xy 91.337384 -220.350588) (xy 91.337384 -220.544644) (xy 97.817938 -220.544644) (xy 97.822009 -220.489022)
			(xy 97.834135 -220.434585) (xy 97.854058 -220.382494) (xy 97.881354 -220.333859) (xy 97.91544 -220.289716)
			(xy 97.955589 -220.251007) (xy 98.000947 -220.218556) (xy 98.050547 -220.193055) (xy 98.103331 -220.175048)
			(xy 98.158174 -220.164918) (xy 98.213908 -220.162881) (xy 98.269345 -220.168981) (xy 98.323302 -220.183087)
			(xy 98.374631 -220.204899) (xy 98.422237 -220.233953) (xy 98.465105 -220.269628) (xy 98.495411 -220.303452)
			(xy 106.903244 -220.303452) (xy 106.903244 -220.248948) (xy 106.911 -220.194998) (xy 106.926355 -220.142702)
			(xy 106.948996 -220.093122) (xy 106.978461 -220.047269) (xy 107.014152 -220.006076) (xy 107.055342 -219.970382)
			(xy 107.101192 -219.940912) (xy 107.15077 -219.918267) (xy 107.203065 -219.902907) (xy 107.257014 -219.895146)
			(xy 107.284266 -219.894658) (xy 107.313258 -219.895214) (xy 107.370571 -219.904003) (xy 107.425897 -219.921355)
			(xy 107.477965 -219.94687) (xy 107.525578 -219.979962) (xy 107.567642 -220.019871) (xy 107.60319 -220.06568)
			(xy 107.617768 -220.090746) (xy 107.62107 -220.096842) (xy 107.630976 -220.107002) (xy 107.637072 -220.110304)
			(xy 107.643145 -220.113422) (xy 107.656407 -220.11664) (xy 107.663234 -220.116654) (xy 107.754166 -220.11386)
			(xy 107.7595 -220.113352) (xy 107.765033 -220.112498) (xy 107.775543 -220.10864) (xy 107.780328 -220.105732)
			(xy 107.785916 -220.102176) (xy 107.79506 -220.091508) (xy 107.798108 -220.084904) (xy 107.810113 -220.060839)
			(xy 107.839805 -220.016002) (xy 107.875497 -219.975776) (xy 107.916482 -219.940959) (xy 107.961948 -219.91224)
			(xy 108.010996 -219.890187) (xy 108.062653 -219.875237) (xy 108.115897 -219.867687) (xy 108.142786 -219.867226)
			(xy 108.171703 -219.867745) (xy 108.228875 -219.876472) (xy 108.284074 -219.893729) (xy 108.336036 -219.919121)
			(xy 108.38357 -219.952065) (xy 108.425586 -219.991806) (xy 108.443776 -220.014292) (xy 108.450061 -220.021675)
			(xy 108.466775 -220.031471) (xy 108.476288 -220.033342) (xy 108.483908 -220.03385) (xy 108.563664 -220.03385)
			(xy 108.571284 -220.033342) (xy 108.580799 -220.031479) (xy 108.597512 -220.021677) (xy 108.603796 -220.014292)
			(xy 108.621987 -219.991809) (xy 108.664007 -219.952074) (xy 108.711542 -219.919135) (xy 108.763503 -219.893747)
			(xy 108.818701 -219.87649) (xy 108.87587 -219.867761) (xy 108.904786 -219.867226) (xy 108.93204 -219.867668)
			(xy 108.985993 -219.875424) (xy 109.038294 -219.89078) (xy 109.087876 -219.913424) (xy 109.133731 -219.942893)
			(xy 109.174925 -219.978589) (xy 109.210619 -220.019785) (xy 109.240086 -220.065641) (xy 109.262727 -220.115225)
			(xy 109.27808 -220.167526) (xy 109.285833 -220.22148) (xy 109.285989 -220.2307) (xy 116.574062 -220.2307)
			(xy 116.574548 -220.203449) (xy 116.582304 -220.149501) (xy 116.597659 -220.097206) (xy 116.620301 -220.047629)
			(xy 116.649767 -220.001779) (xy 116.685458 -219.960588) (xy 116.726649 -219.924897) (xy 116.772499 -219.895431)
			(xy 116.822076 -219.872789) (xy 116.874371 -219.857434) (xy 116.928319 -219.849678) (xy 116.982821 -219.849678)
			(xy 117.036769 -219.857434) (xy 117.089064 -219.872789) (xy 117.138641 -219.895431) (xy 117.184491 -219.924897)
			(xy 117.225682 -219.960588) (xy 117.261373 -220.001779) (xy 117.290839 -220.047629) (xy 117.313481 -220.097206)
			(xy 117.328836 -220.149501) (xy 117.336592 -220.203449) (xy 117.337078 -220.2307) (xy 117.336566 -220.258749)
			(xy 117.328344 -220.314242) (xy 117.312092 -220.367935) (xy 117.288159 -220.418672) (xy 117.25706 -220.465362)
			(xy 117.219466 -220.506999) (xy 117.176183 -220.542688) (xy 117.15242 -220.557598) (xy 117.139755 -220.56592)
			(xy 117.119506 -220.588437) (xy 117.106763 -220.615908) (xy 117.102651 -220.645911) (xy 117.107533 -220.675797)
			(xy 117.120978 -220.702932) (xy 117.1418 -220.724921) (xy 117.154706 -220.732858) (xy 117.179476 -220.747499)
			(xy 117.224686 -220.78309) (xy 117.240461 -220.799914) (xy 142.146018 -220.799914) (xy 142.150089 -220.744292)
			(xy 142.162215 -220.689855) (xy 142.182138 -220.637764) (xy 142.209434 -220.589129) (xy 142.24352 -220.544986)
			(xy 142.283669 -220.506277) (xy 142.329027 -220.473826) (xy 142.378627 -220.448325) (xy 142.431411 -220.430318)
			(xy 142.486254 -220.420188) (xy 142.541988 -220.418151) (xy 142.597425 -220.424251) (xy 142.651382 -220.438357)
			(xy 142.702711 -220.460169) (xy 142.750317 -220.489223) (xy 142.793185 -220.524898) (xy 142.830402 -220.566435)
			(xy 142.861175 -220.612948) (xy 142.884847 -220.663445) (xy 142.900915 -220.716852) (xy 142.909035 -220.772028)
			(xy 142.909544 -220.799914) (xy 142.909035 -220.8278) (xy 142.900915 -220.882976) (xy 142.884847 -220.936383)
			(xy 142.861175 -220.98688) (xy 142.830402 -221.033393) (xy 142.793185 -221.07493) (xy 142.750317 -221.110605)
			(xy 142.702711 -221.139659) (xy 142.651382 -221.161471) (xy 142.597425 -221.175577) (xy 142.541988 -221.181677)
			(xy 142.486254 -221.17964) (xy 142.431411 -221.16951) (xy 142.378627 -221.151503) (xy 142.329027 -221.126002)
			(xy 142.283669 -221.093551) (xy 142.24352 -221.054842) (xy 142.209434 -221.010699) (xy 142.182138 -220.962064)
			(xy 142.162215 -220.909973) (xy 142.150089 -220.855536) (xy 142.146018 -220.799914) (xy 117.240461 -220.799914)
			(xy 117.264042 -220.825064) (xy 117.296652 -220.872469) (xy 117.321778 -220.924232) (xy 117.338849 -220.979179)
			(xy 117.34748 -221.036067) (xy 117.348 -221.064836) (xy 117.347514 -221.092087) (xy 117.339758 -221.146035)
			(xy 117.324403 -221.19833) (xy 117.301761 -221.247907) (xy 117.272295 -221.293757) (xy 117.23846 -221.332806)
			(xy 138.540742 -221.332806) (xy 138.544813 -221.277184) (xy 138.556939 -221.222747) (xy 138.576862 -221.170656)
			(xy 138.604158 -221.122021) (xy 138.638244 -221.077878) (xy 138.678393 -221.039169) (xy 138.723751 -221.006718)
			(xy 138.773351 -220.981217) (xy 138.826135 -220.96321) (xy 138.880978 -220.95308) (xy 138.936712 -220.951043)
			(xy 138.992149 -220.957143) (xy 139.046106 -220.971249) (xy 139.097435 -220.993061) (xy 139.145041 -221.022115)
			(xy 139.187909 -221.05779) (xy 139.225126 -221.099327) (xy 139.255899 -221.14584) (xy 139.279571 -221.196337)
			(xy 139.295639 -221.249744) (xy 139.303759 -221.30492) (xy 139.304268 -221.332806) (xy 139.303759 -221.360692)
			(xy 139.295639 -221.415868) (xy 139.279571 -221.469275) (xy 139.255899 -221.519772) (xy 139.225126 -221.566285)
			(xy 139.187909 -221.607822) (xy 139.145041 -221.643497) (xy 139.097435 -221.672551) (xy 139.046106 -221.694363)
			(xy 138.992149 -221.708469) (xy 138.936712 -221.714569) (xy 138.880978 -221.712532) (xy 138.826135 -221.702402)
			(xy 138.773351 -221.684395) (xy 138.723751 -221.658894) (xy 138.678393 -221.626443) (xy 138.638244 -221.587734)
			(xy 138.604158 -221.543591) (xy 138.576862 -221.494956) (xy 138.556939 -221.442865) (xy 138.544813 -221.388428)
			(xy 138.540742 -221.332806) (xy 117.23846 -221.332806) (xy 117.236604 -221.334948) (xy 117.195413 -221.370639)
			(xy 117.149563 -221.400105) (xy 117.099986 -221.422747) (xy 117.047691 -221.438102) (xy 116.993743 -221.445858)
			(xy 116.939241 -221.445858) (xy 116.885293 -221.438102) (xy 116.832998 -221.422747) (xy 116.783421 -221.400105)
			(xy 116.737571 -221.370639) (xy 116.69638 -221.334948) (xy 116.660689 -221.293757) (xy 116.631223 -221.247907)
			(xy 116.608581 -221.19833) (xy 116.593226 -221.146035) (xy 116.58547 -221.092087) (xy 116.584984 -221.064836)
			(xy 116.585542 -221.036789) (xy 116.593758 -220.981299) (xy 116.610004 -220.927608) (xy 116.633929 -220.876872)
			(xy 116.66502 -220.830181) (xy 116.702608 -220.788542) (xy 116.745882 -220.75285) (xy 116.769642 -220.737938)
			(xy 116.782372 -220.729705) (xy 116.802633 -220.707172) (xy 116.81538 -220.67968) (xy 116.819486 -220.649656)
			(xy 116.81459 -220.619751) (xy 116.801124 -220.592605) (xy 116.780276 -220.570613) (xy 116.767356 -220.562678)
			(xy 116.742593 -220.548026) (xy 116.697385 -220.512435) (xy 116.65803 -220.470462) (xy 116.62542 -220.423059)
			(xy 116.600293 -220.371299) (xy 116.583219 -220.316354) (xy 116.574584 -220.259468) (xy 116.574062 -220.2307)
			(xy 109.285989 -220.2307) (xy 109.286294 -220.248734) (xy 109.286294 -220.248988) (xy 109.285829 -220.275283)
			(xy 109.278585 -220.327371) (xy 109.264261 -220.377972) (xy 109.243126 -220.426129) (xy 109.215582 -220.470928)
			(xy 109.18215 -220.511524) (xy 109.163104 -220.529658) (xy 109.15572 -220.537194) (xy 109.147185 -220.556463)
			(xy 109.146594 -220.566996) (xy 109.146594 -220.641672) (xy 109.147127 -220.652221) (xy 109.15566 -220.671516)
			(xy 109.163104 -220.67901) (xy 109.182189 -220.697139) (xy 109.215666 -220.737761) (xy 109.243236 -220.782602)
			(xy 109.264374 -220.830811) (xy 109.278677 -220.881469) (xy 109.285874 -220.933614) (xy 109.286294 -220.959934)
			(xy 109.285845 -220.98625) (xy 109.278625 -221.038384) (xy 109.264311 -221.089033) (xy 109.243176 -221.137235)
			(xy 109.215619 -221.182077) (xy 109.182165 -221.222708) (xy 109.163104 -221.240858) (xy 109.15572 -221.248394)
			(xy 109.147185 -221.267663) (xy 109.146594 -221.278196) (xy 109.146594 -221.352872) (xy 109.147127 -221.363421)
			(xy 109.15566 -221.382716) (xy 109.163104 -221.39021) (xy 109.182189 -221.408339) (xy 109.215666 -221.448961)
			(xy 109.243236 -221.493802) (xy 109.264374 -221.542011) (xy 109.278677 -221.592669) (xy 109.285874 -221.644814)
			(xy 109.286294 -221.671134) (xy 109.285845 -221.69745) (xy 109.278625 -221.749584) (xy 109.264311 -221.800233)
			(xy 109.254317 -221.823026) (xy 128.712974 -221.823026) (xy 128.717045 -221.767404) (xy 128.729171 -221.712967)
			(xy 128.749094 -221.660876) (xy 128.77639 -221.612241) (xy 128.810476 -221.568098) (xy 128.850625 -221.529389)
			(xy 128.895983 -221.496938) (xy 128.945583 -221.471437) (xy 128.998367 -221.45343) (xy 129.05321 -221.4433)
			(xy 129.108944 -221.441263) (xy 129.164381 -221.447363) (xy 129.218338 -221.461469) (xy 129.269667 -221.483281)
			(xy 129.317273 -221.512335) (xy 129.360141 -221.54801) (xy 129.397358 -221.589547) (xy 129.428131 -221.63606)
			(xy 129.451803 -221.686557) (xy 129.467871 -221.739964) (xy 129.475991 -221.79514) (xy 129.4765 -221.823026)
			(xy 129.475991 -221.850912) (xy 129.467871 -221.906088) (xy 129.451803 -221.959495) (xy 129.428131 -222.009992)
			(xy 129.397358 -222.056505) (xy 129.360141 -222.098042) (xy 129.317273 -222.133717) (xy 129.269667 -222.162771)
			(xy 129.247299 -222.172276) (xy 131.918962 -222.172276) (xy 131.923033 -222.116654) (xy 131.935159 -222.062217)
			(xy 131.955082 -222.010126) (xy 131.982378 -221.961491) (xy 132.016464 -221.917348) (xy 132.056613 -221.878639)
			(xy 132.101971 -221.846188) (xy 132.151571 -221.820687) (xy 132.204355 -221.80268) (xy 132.259198 -221.79255)
			(xy 132.314932 -221.790513) (xy 132.370369 -221.796613) (xy 132.424326 -221.810719) (xy 132.475655 -221.832531)
			(xy 132.523261 -221.861585) (xy 132.566129 -221.89726) (xy 132.582456 -221.915482) (xy 133.950454 -221.915482)
			(xy 133.954525 -221.85986) (xy 133.966651 -221.805423) (xy 133.986574 -221.753332) (xy 134.01387 -221.704697)
			(xy 134.047956 -221.660554) (xy 134.088105 -221.621845) (xy 134.133463 -221.589394) (xy 134.183063 -221.563893)
			(xy 134.235847 -221.545886) (xy 134.29069 -221.535756) (xy 134.346424 -221.533719) (xy 134.401861 -221.539819)
			(xy 134.455818 -221.553925) (xy 134.507147 -221.575737) (xy 134.554753 -221.604791) (xy 134.597621 -221.640466)
			(xy 134.634838 -221.682003) (xy 134.665611 -221.728516) (xy 134.689283 -221.779013) (xy 134.705351 -221.83242)
			(xy 134.713471 -221.887596) (xy 134.71398 -221.915482) (xy 134.713471 -221.943368) (xy 134.705351 -221.998544)
			(xy 134.689283 -222.051951) (xy 134.665611 -222.102448) (xy 134.634838 -222.148961) (xy 134.597621 -222.190498)
			(xy 134.554753 -222.226173) (xy 134.507147 -222.255227) (xy 134.455818 -222.277039) (xy 134.401861 -222.291145)
			(xy 134.346424 -222.297245) (xy 134.29069 -222.295208) (xy 134.235847 -222.285078) (xy 134.183063 -222.267071)
			(xy 134.133463 -222.24157) (xy 134.088105 -222.209119) (xy 134.047956 -222.17041) (xy 134.01387 -222.126267)
			(xy 133.986574 -222.077632) (xy 133.966651 -222.025541) (xy 133.954525 -221.971104) (xy 133.950454 -221.915482)
			(xy 132.582456 -221.915482) (xy 132.603346 -221.938797) (xy 132.634119 -221.98531) (xy 132.657791 -222.035807)
			(xy 132.673859 -222.089214) (xy 132.681979 -222.14439) (xy 132.682488 -222.172276) (xy 132.681979 -222.200162)
			(xy 132.673859 -222.255338) (xy 132.657791 -222.308745) (xy 132.634119 -222.359242) (xy 132.603346 -222.405755)
			(xy 132.566129 -222.447292) (xy 132.523261 -222.482967) (xy 132.475655 -222.512021) (xy 132.424326 -222.533833)
			(xy 132.370369 -222.547939) (xy 132.314932 -222.554039) (xy 132.259198 -222.552002) (xy 132.204355 -222.541872)
			(xy 132.151571 -222.523865) (xy 132.101971 -222.498364) (xy 132.056613 -222.465913) (xy 132.016464 -222.427204)
			(xy 131.982378 -222.383061) (xy 131.955082 -222.334426) (xy 131.935159 -222.282335) (xy 131.923033 -222.227898)
			(xy 131.918962 -222.172276) (xy 129.247299 -222.172276) (xy 129.218338 -222.184583) (xy 129.164381 -222.198689)
			(xy 129.108944 -222.204789) (xy 129.05321 -222.202752) (xy 128.998367 -222.192622) (xy 128.945583 -222.174615)
			(xy 128.895983 -222.149114) (xy 128.850625 -222.116663) (xy 128.810476 -222.077954) (xy 128.77639 -222.033811)
			(xy 128.749094 -221.985176) (xy 128.729171 -221.933085) (xy 128.717045 -221.878648) (xy 128.712974 -221.823026)
			(xy 109.254317 -221.823026) (xy 109.243176 -221.848435) (xy 109.215619 -221.893277) (xy 109.182165 -221.933908)
			(xy 109.163104 -221.952058) (xy 109.15572 -221.959594) (xy 109.147185 -221.978863) (xy 109.146594 -221.989396)
			(xy 109.146594 -222.064072) (xy 109.147127 -222.074621) (xy 109.15566 -222.093916) (xy 109.163104 -222.10141)
			(xy 109.182189 -222.119539) (xy 109.215666 -222.160161) (xy 109.243236 -222.205002) (xy 109.264374 -222.253211)
			(xy 109.278677 -222.303869) (xy 109.285874 -222.356014) (xy 109.286294 -222.382334) (xy 109.285845 -222.40865)
			(xy 109.278625 -222.460784) (xy 109.264311 -222.511433) (xy 109.243176 -222.559635) (xy 109.215619 -222.604477)
			(xy 109.182165 -222.645108) (xy 109.163104 -222.663258) (xy 109.15572 -222.670794) (xy 109.147185 -222.690063)
			(xy 109.146594 -222.700596) (xy 109.146594 -222.775272) (xy 109.147127 -222.785821) (xy 109.15566 -222.805116)
			(xy 109.163104 -222.81261) (xy 109.182174 -222.830724) (xy 109.215629 -222.871309) (xy 109.243187 -222.916109)
			(xy 109.261749 -222.958406) (xy 128.662428 -222.958406) (xy 128.666499 -222.902784) (xy 128.678625 -222.848347)
			(xy 128.698548 -222.796256) (xy 128.725844 -222.747621) (xy 128.75993 -222.703478) (xy 128.800079 -222.664769)
			(xy 128.845437 -222.632318) (xy 128.895037 -222.606817) (xy 128.947821 -222.58881) (xy 129.002664 -222.57868)
			(xy 129.058398 -222.576643) (xy 129.113835 -222.582743) (xy 129.167792 -222.596849) (xy 129.219121 -222.618661)
			(xy 129.266727 -222.647715) (xy 129.309595 -222.68339) (xy 129.346812 -222.724927) (xy 129.377585 -222.77144)
			(xy 129.401257 -222.821937) (xy 129.417325 -222.875344) (xy 129.425445 -222.93052) (xy 129.425954 -222.958406)
			(xy 129.425445 -222.986292) (xy 129.417325 -223.041468) (xy 129.401257 -223.094875) (xy 129.377585 -223.145372)
			(xy 129.376255 -223.147382) (xy 135.118854 -223.147382) (xy 135.122925 -223.09176) (xy 135.135051 -223.037323)
			(xy 135.154974 -222.985232) (xy 135.18227 -222.936597) (xy 135.216356 -222.892454) (xy 135.256505 -222.853745)
			(xy 135.301863 -222.821294) (xy 135.351463 -222.795793) (xy 135.404247 -222.777786) (xy 135.45909 -222.767656)
			(xy 135.514824 -222.765619) (xy 135.570261 -222.771719) (xy 135.624218 -222.785825) (xy 135.675547 -222.807637)
			(xy 135.723153 -222.836691) (xy 135.766021 -222.872366) (xy 135.803238 -222.913903) (xy 135.834011 -222.960416)
			(xy 135.857683 -223.010913) (xy 135.873751 -223.06432) (xy 135.879508 -223.10344) (xy 137.023854 -223.10344)
			(xy 137.027925 -223.047818) (xy 137.040051 -222.993381) (xy 137.059974 -222.94129) (xy 137.08727 -222.892655)
			(xy 137.121356 -222.848512) (xy 137.161505 -222.809803) (xy 137.206863 -222.777352) (xy 137.256463 -222.751851)
			(xy 137.309247 -222.733844) (xy 137.36409 -222.723714) (xy 137.419824 -222.721677) (xy 137.475261 -222.727777)
			(xy 137.529218 -222.741883) (xy 137.580547 -222.763695) (xy 137.628153 -222.792749) (xy 137.671021 -222.828424)
			(xy 137.708238 -222.869961) (xy 137.739011 -222.916474) (xy 137.762683 -222.966971) (xy 137.765455 -222.976186)
			(xy 138.942826 -222.976186) (xy 138.943396 -222.947271) (xy 138.952113 -222.890102) (xy 138.96936 -222.834904)
			(xy 138.994742 -222.782941) (xy 139.027677 -222.735406) (xy 139.06741 -222.693388) (xy 139.089892 -222.675196)
			(xy 139.097284 -222.66892) (xy 139.107075 -222.6522) (xy 139.108942 -222.642684) (xy 139.10945 -222.635064)
			(xy 139.10945 -222.555308) (xy 139.108942 -222.547688) (xy 139.107046 -222.538181) (xy 139.097268 -222.521464)
			(xy 139.089892 -222.515176) (xy 139.067395 -222.497001) (xy 139.027661 -222.454977) (xy 138.994724 -222.407439)
			(xy 138.969338 -222.355475) (xy 138.952085 -222.300275) (xy 138.943359 -222.243103) (xy 138.942826 -222.214186)
			(xy 138.943312 -222.186935) (xy 138.951068 -222.132987) (xy 138.966423 -222.080692) (xy 138.989065 -222.031115)
			(xy 139.018531 -221.985265) (xy 139.054222 -221.944074) (xy 139.095413 -221.908383) (xy 139.141263 -221.878917)
			(xy 139.19084 -221.856275) (xy 139.243135 -221.84092) (xy 139.297083 -221.833164) (xy 139.351585 -221.833164)
			(xy 139.405533 -221.84092) (xy 139.457828 -221.856275) (xy 139.507405 -221.878917) (xy 139.553255 -221.908383)
			(xy 139.594446 -221.944074) (xy 139.630137 -221.985265) (xy 139.659603 -222.031115) (xy 139.674539 -222.063818)
			(xy 141.679422 -222.063818) (xy 141.679908 -222.036567) (xy 141.687664 -221.982619) (xy 141.703019 -221.930324)
			(xy 141.725661 -221.880747) (xy 141.755127 -221.834897) (xy 141.790818 -221.793706) (xy 141.832009 -221.758015)
			(xy 141.877859 -221.728549) (xy 141.927436 -221.705907) (xy 141.979731 -221.690552) (xy 142.033679 -221.682796)
			(xy 142.088181 -221.682796) (xy 142.142129 -221.690552) (xy 142.194424 -221.705907) (xy 142.244001 -221.728549)
			(xy 142.289851 -221.758015) (xy 142.331042 -221.793706) (xy 142.366733 -221.834897) (xy 142.396199 -221.880747)
			(xy 142.418841 -221.930324) (xy 142.434196 -221.982619) (xy 142.441952 -222.036567) (xy 142.442438 -222.063818)
			(xy 142.441943 -222.090681) (xy 142.434405 -222.143875) (xy 142.41948 -222.195486) (xy 142.397464 -222.244493)
			(xy 142.368792 -222.289928) (xy 142.35176 -222.310706) (xy 142.34414 -222.319596) (xy 142.341346 -222.330772)
			(xy 142.339987 -222.336389) (xy 142.339605 -222.347936) (xy 142.340584 -222.353632) (xy 142.356586 -222.432372)
			(xy 142.357602 -222.436182) (xy 142.358969 -222.440606) (xy 142.363053 -222.448914) (xy 142.36573 -222.452692)
			(xy 142.369286 -222.457264) (xy 142.37843 -222.464884) (xy 142.383256 -222.46717) (xy 142.406567 -222.479398)
			(xy 142.449839 -222.509373) (xy 142.488582 -222.545009) (xy 142.522061 -222.585632) (xy 142.54964 -222.630469)
			(xy 142.570796 -222.678671) (xy 142.585128 -222.729323) (xy 142.592363 -222.781464) (xy 142.592806 -222.807784)
			(xy 142.59232 -222.835035) (xy 142.584564 -222.888983) (xy 142.569209 -222.941278) (xy 142.546567 -222.990855)
			(xy 142.517101 -223.036705) (xy 142.48141 -223.077896) (xy 142.440219 -223.113587) (xy 142.394369 -223.143053)
			(xy 142.344792 -223.165695) (xy 142.292497 -223.18105) (xy 142.238549 -223.188806) (xy 142.184047 -223.188806)
			(xy 142.130099 -223.18105) (xy 142.077804 -223.165695) (xy 142.028227 -223.143053) (xy 141.982377 -223.113587)
			(xy 141.941186 -223.077896) (xy 141.905495 -223.036705) (xy 141.876029 -222.990855) (xy 141.853387 -222.941278)
			(xy 141.838032 -222.888983) (xy 141.830276 -222.835035) (xy 141.82979 -222.807784) (xy 141.830222 -222.780919)
			(xy 141.837774 -222.727722) (xy 141.852713 -222.67611) (xy 141.874744 -222.627104) (xy 141.90343 -222.581672)
			(xy 141.920468 -222.560896) (xy 141.928088 -222.552006) (xy 141.930882 -222.54083) (xy 141.932241 -222.535213)
			(xy 141.932623 -222.523666) (xy 141.931644 -222.51797) (xy 141.915642 -222.43923) (xy 141.914626 -222.43542)
			(xy 141.913255 -222.430997) (xy 141.909174 -222.422688) (xy 141.906498 -222.41891) (xy 141.902942 -222.414338)
			(xy 141.893798 -222.406718) (xy 141.888972 -222.404432) (xy 141.865668 -222.392191) (xy 141.822395 -222.362219)
			(xy 141.783651 -222.326585) (xy 141.750171 -222.285964) (xy 141.722591 -222.241129) (xy 141.701434 -222.192928)
			(xy 141.687101 -222.142277) (xy 141.679865 -222.090138) (xy 141.679422 -222.063818) (xy 139.674539 -222.063818)
			(xy 139.682245 -222.080692) (xy 139.6976 -222.132987) (xy 139.705356 -222.186935) (xy 139.705842 -222.214186)
			(xy 139.705336 -222.243104) (xy 139.696607 -222.300276) (xy 139.679348 -222.355476) (xy 139.653955 -222.407439)
			(xy 139.621008 -222.454972) (xy 139.581263 -222.496987) (xy 139.558776 -222.515176) (xy 139.551388 -222.521456)
			(xy 139.541596 -222.538173) (xy 139.539726 -222.547688) (xy 139.539218 -222.555308) (xy 139.539218 -222.635064)
			(xy 139.539726 -222.642684) (xy 139.541599 -222.652196) (xy 139.551394 -222.66891) (xy 139.558776 -222.675196)
			(xy 139.581253 -222.693395) (xy 139.620989 -222.735413) (xy 139.65393 -222.782946) (xy 139.67932 -222.834905)
			(xy 139.696577 -222.890102) (xy 139.705307 -222.94727) (xy 139.705842 -222.976186) (xy 139.705356 -223.003437)
			(xy 139.6976 -223.057385) (xy 139.682245 -223.10968) (xy 139.659603 -223.159257) (xy 139.630137 -223.205107)
			(xy 139.594446 -223.246298) (xy 139.553255 -223.281989) (xy 139.507405 -223.311455) (xy 139.457828 -223.334097)
			(xy 139.405533 -223.349452) (xy 139.351585 -223.357208) (xy 139.297083 -223.357208) (xy 139.243135 -223.349452)
			(xy 139.19084 -223.334097) (xy 139.141263 -223.311455) (xy 139.095413 -223.281989) (xy 139.054222 -223.246298)
			(xy 139.018531 -223.205107) (xy 138.989065 -223.159257) (xy 138.966423 -223.10968) (xy 138.951068 -223.057385)
			(xy 138.943312 -223.003437) (xy 138.942826 -222.976186) (xy 137.765455 -222.976186) (xy 137.778751 -223.020378)
			(xy 137.786871 -223.075554) (xy 137.78738 -223.10344) (xy 137.786871 -223.131326) (xy 137.778751 -223.186502)
			(xy 137.762683 -223.239909) (xy 137.739011 -223.290406) (xy 137.708238 -223.336919) (xy 137.671021 -223.378456)
			(xy 137.628153 -223.414131) (xy 137.580547 -223.443185) (xy 137.529218 -223.464997) (xy 137.475261 -223.479103)
			(xy 137.419824 -223.485203) (xy 137.36409 -223.483166) (xy 137.309247 -223.473036) (xy 137.256463 -223.455029)
			(xy 137.206863 -223.429528) (xy 137.161505 -223.397077) (xy 137.121356 -223.358368) (xy 137.08727 -223.314225)
			(xy 137.059974 -223.26559) (xy 137.040051 -223.213499) (xy 137.027925 -223.159062) (xy 137.023854 -223.10344)
			(xy 135.879508 -223.10344) (xy 135.881871 -223.119496) (xy 135.88238 -223.147382) (xy 135.881871 -223.175268)
			(xy 135.873751 -223.230444) (xy 135.857683 -223.283851) (xy 135.834011 -223.334348) (xy 135.803238 -223.380861)
			(xy 135.766021 -223.422398) (xy 135.723153 -223.458073) (xy 135.675547 -223.487127) (xy 135.624218 -223.508939)
			(xy 135.570261 -223.523045) (xy 135.514824 -223.529145) (xy 135.45909 -223.527108) (xy 135.404247 -223.516978)
			(xy 135.351463 -223.498971) (xy 135.301863 -223.47347) (xy 135.256505 -223.441019) (xy 135.216356 -223.40231)
			(xy 135.18227 -223.358167) (xy 135.154974 -223.309532) (xy 135.135051 -223.257441) (xy 135.122925 -223.203004)
			(xy 135.118854 -223.147382) (xy 129.376255 -223.147382) (xy 129.346812 -223.191885) (xy 129.309595 -223.233422)
			(xy 129.266727 -223.269097) (xy 129.219121 -223.298151) (xy 129.167792 -223.319963) (xy 129.113835 -223.334069)
			(xy 129.058398 -223.340169) (xy 129.002664 -223.338132) (xy 128.947821 -223.328002) (xy 128.895037 -223.309995)
			(xy 128.845437 -223.284494) (xy 128.800079 -223.252043) (xy 128.75993 -223.213334) (xy 128.725844 -223.169191)
			(xy 128.698548 -223.120556) (xy 128.678625 -223.068465) (xy 128.666499 -223.014028) (xy 128.662428 -222.958406)
			(xy 109.261749 -222.958406) (xy 109.264323 -222.964271) (xy 109.278638 -223.014883) (xy 109.285858 -223.066982)
			(xy 109.286294 -223.09328) (xy 109.286294 -223.093534) (xy 109.285854 -223.120787) (xy 109.278092 -223.174737)
			(xy 109.262732 -223.227033) (xy 109.240086 -223.276612) (xy 109.210615 -223.322462) (xy 109.174919 -223.363653)
			(xy 109.133724 -223.399344) (xy 109.087869 -223.428809) (xy 109.038288 -223.451449) (xy 108.98599 -223.466802)
			(xy 108.932039 -223.474557) (xy 108.904786 -223.475042) (xy 108.87587 -223.474484) (xy 108.8187 -223.465766)
			(xy 108.763501 -223.448518) (xy 108.711539 -223.423133) (xy 108.664004 -223.390196) (xy 108.621987 -223.350459)
			(xy 108.603796 -223.327976) (xy 108.597526 -223.320578) (xy 108.580801 -223.310791) (xy 108.571284 -223.308926)
			(xy 108.563664 -223.308418) (xy 108.483908 -223.308418) (xy 108.476288 -223.308926) (xy 108.466784 -223.310832)
			(xy 108.450066 -223.320604) (xy 108.443776 -223.327976) (xy 108.425592 -223.350466) (xy 108.383572 -223.390202)
			(xy 108.336036 -223.423141) (xy 108.284073 -223.448528) (xy 108.228874 -223.465783) (xy 108.171703 -223.474509)
			(xy 108.142786 -223.475042) (xy 108.115536 -223.474535) (xy 108.061591 -223.466778) (xy 108.009298 -223.451423)
			(xy 107.959723 -223.428782) (xy 107.913875 -223.399318) (xy 107.872686 -223.363629) (xy 107.836994 -223.322441)
			(xy 107.807527 -223.276594) (xy 107.784884 -223.22702) (xy 107.769526 -223.174729) (xy 107.761766 -223.120784)
			(xy 107.761278 -223.093534) (xy 107.761278 -223.09328) (xy 107.76173 -223.066985) (xy 107.768978 -223.014896)
			(xy 107.783306 -222.964295) (xy 107.804442 -222.916139) (xy 107.831988 -222.87134) (xy 107.865421 -222.830745)
			(xy 107.884468 -222.81261) (xy 107.891863 -222.805082) (xy 107.900392 -222.785807) (xy 107.900978 -222.775272)
			(xy 107.900978 -222.700596) (xy 107.900471 -222.690044) (xy 107.891921 -222.670748) (xy 107.884468 -222.663258)
			(xy 107.865381 -222.64513) (xy 107.831901 -222.60451) (xy 107.80433 -222.559669) (xy 107.783192 -222.511459)
			(xy 107.76889 -222.4608) (xy 107.761696 -222.408654) (xy 107.761278 -222.382334) (xy 107.761714 -222.356018)
			(xy 107.768939 -222.303883) (xy 107.783256 -222.253235) (xy 107.804393 -222.205033) (xy 107.831951 -222.160191)
			(xy 107.865407 -222.11956) (xy 107.884468 -222.10141) (xy 107.891863 -222.093882) (xy 107.900392 -222.074607)
			(xy 107.900978 -222.064072) (xy 107.900978 -221.989396) (xy 107.900471 -221.978844) (xy 107.891921 -221.959548)
			(xy 107.884468 -221.952058) (xy 107.865381 -221.93393) (xy 107.831901 -221.89331) (xy 107.80433 -221.848469)
			(xy 107.783192 -221.800259) (xy 107.76889 -221.7496) (xy 107.761696 -221.697454) (xy 107.761278 -221.671134)
			(xy 107.761714 -221.644818) (xy 107.768939 -221.592683) (xy 107.783256 -221.542035) (xy 107.804393 -221.493833)
			(xy 107.831951 -221.448991) (xy 107.865407 -221.40836) (xy 107.884468 -221.39021) (xy 107.891863 -221.382682)
			(xy 107.900392 -221.363407) (xy 107.900978 -221.352872) (xy 107.900978 -221.278196) (xy 107.900471 -221.267644)
			(xy 107.891921 -221.248348) (xy 107.884468 -221.240858) (xy 107.865381 -221.22273) (xy 107.831901 -221.18211)
			(xy 107.80433 -221.137269) (xy 107.783192 -221.089059) (xy 107.76889 -221.0384) (xy 107.761696 -220.986254)
			(xy 107.761278 -220.959934) (xy 107.761714 -220.933618) (xy 107.768939 -220.881483) (xy 107.783256 -220.830835)
			(xy 107.804393 -220.782633) (xy 107.831951 -220.737791) (xy 107.865407 -220.69716) (xy 107.884468 -220.67901)
			(xy 107.891863 -220.671482) (xy 107.900392 -220.652207) (xy 107.900978 -220.641672) (xy 107.900978 -220.566996)
			(xy 107.900471 -220.556444) (xy 107.891921 -220.537148) (xy 107.884468 -220.529658) (xy 107.862402 -220.508544)
			(xy 107.82463 -220.460559) (xy 107.809284 -220.434154) (xy 107.805982 -220.428058) (xy 107.796076 -220.417898)
			(xy 107.78998 -220.414596) (xy 107.783898 -220.411497) (xy 107.770643 -220.408266) (xy 107.763818 -220.408246)
			(xy 107.672886 -220.41104) (xy 107.667552 -220.411548) (xy 107.662022 -220.412418) (xy 107.651511 -220.416265)
			(xy 107.646724 -220.419168) (xy 107.641136 -220.422724) (xy 107.631992 -220.433392) (xy 107.628944 -220.439996)
			(xy 107.616976 -220.46408) (xy 107.587279 -220.508919) (xy 107.551582 -220.549144) (xy 107.510592 -220.58396)
			(xy 107.46512 -220.612677) (xy 107.416067 -220.634727) (xy 107.364405 -220.649672) (xy 107.311156 -220.657217)
			(xy 107.284266 -220.657674) (xy 107.257014 -220.657254) (xy 107.203065 -220.649493) (xy 107.15077 -220.634133)
			(xy 107.101192 -220.611488) (xy 107.055342 -220.582018) (xy 107.014152 -220.546324) (xy 106.978461 -220.505131)
			(xy 106.948996 -220.459278) (xy 106.926355 -220.409698) (xy 106.911 -220.357402) (xy 106.903244 -220.303452)
			(xy 98.495411 -220.303452) (xy 98.502322 -220.311165) (xy 98.533095 -220.357678) (xy 98.556767 -220.408175)
			(xy 98.572835 -220.461582) (xy 98.580955 -220.516758) (xy 98.581464 -220.544644) (xy 98.580955 -220.57253)
			(xy 98.572835 -220.627706) (xy 98.556767 -220.681113) (xy 98.533095 -220.73161) (xy 98.502322 -220.778123)
			(xy 98.465105 -220.81966) (xy 98.422237 -220.855335) (xy 98.374631 -220.884389) (xy 98.323302 -220.906201)
			(xy 98.269345 -220.920307) (xy 98.213908 -220.926407) (xy 98.158174 -220.92437) (xy 98.103331 -220.91424)
			(xy 98.050547 -220.896233) (xy 98.000947 -220.870732) (xy 97.955589 -220.838281) (xy 97.91544 -220.799572)
			(xy 97.881354 -220.755429) (xy 97.854058 -220.706794) (xy 97.834135 -220.654703) (xy 97.822009 -220.600266)
			(xy 97.817938 -220.544644) (xy 91.337384 -220.544644) (xy 91.337384 -221.018354) (xy 96.817432 -221.018354)
			(xy 96.821503 -220.962732) (xy 96.833629 -220.908295) (xy 96.853552 -220.856204) (xy 96.880848 -220.807569)
			(xy 96.914934 -220.763426) (xy 96.955083 -220.724717) (xy 97.000441 -220.692266) (xy 97.050041 -220.666765)
			(xy 97.102825 -220.648758) (xy 97.157668 -220.638628) (xy 97.213402 -220.636591) (xy 97.268839 -220.642691)
			(xy 97.322796 -220.656797) (xy 97.374125 -220.678609) (xy 97.421731 -220.707663) (xy 97.464599 -220.743338)
			(xy 97.501816 -220.784875) (xy 97.532589 -220.831388) (xy 97.556261 -220.881885) (xy 97.572329 -220.935292)
			(xy 97.580449 -220.990468) (xy 97.580958 -221.018354) (xy 97.580449 -221.04624) (xy 97.572329 -221.101416)
			(xy 97.558881 -221.146116) (xy 100.565456 -221.146116) (xy 100.569527 -221.090494) (xy 100.581653 -221.036057)
			(xy 100.601576 -220.983966) (xy 100.628872 -220.935331) (xy 100.662958 -220.891188) (xy 100.703107 -220.852479)
			(xy 100.748465 -220.820028) (xy 100.798065 -220.794527) (xy 100.850849 -220.77652) (xy 100.905692 -220.76639)
			(xy 100.961426 -220.764353) (xy 101.016863 -220.770453) (xy 101.07082 -220.784559) (xy 101.122149 -220.806371)
			(xy 101.169755 -220.835425) (xy 101.212623 -220.8711) (xy 101.24984 -220.912637) (xy 101.255253 -220.920818)
			(xy 102.937562 -220.920818) (xy 102.941633 -220.865196) (xy 102.953759 -220.810759) (xy 102.973682 -220.758668)
			(xy 103.000978 -220.710033) (xy 103.035064 -220.66589) (xy 103.075213 -220.627181) (xy 103.120571 -220.59473)
			(xy 103.170171 -220.569229) (xy 103.222955 -220.551222) (xy 103.277798 -220.541092) (xy 103.333532 -220.539055)
			(xy 103.388969 -220.545155) (xy 103.442926 -220.559261) (xy 103.494255 -220.581073) (xy 103.541861 -220.610127)
			(xy 103.584729 -220.645802) (xy 103.621946 -220.687339) (xy 103.652719 -220.733852) (xy 103.676391 -220.784349)
			(xy 103.692459 -220.837756) (xy 103.700579 -220.892932) (xy 103.701088 -220.920818) (xy 103.700579 -220.948704)
			(xy 103.692459 -221.00388) (xy 103.676391 -221.057287) (xy 103.652719 -221.107784) (xy 103.621946 -221.154297)
			(xy 103.584729 -221.195834) (xy 103.541861 -221.231509) (xy 103.494255 -221.260563) (xy 103.442926 -221.282375)
			(xy 103.388969 -221.296481) (xy 103.333532 -221.302581) (xy 103.277798 -221.300544) (xy 103.222955 -221.290414)
			(xy 103.170171 -221.272407) (xy 103.120571 -221.246906) (xy 103.075213 -221.214455) (xy 103.035064 -221.175746)
			(xy 103.000978 -221.131603) (xy 102.973682 -221.082968) (xy 102.953759 -221.030877) (xy 102.941633 -220.97644)
			(xy 102.937562 -220.920818) (xy 101.255253 -220.920818) (xy 101.280613 -220.95915) (xy 101.304285 -221.009647)
			(xy 101.320353 -221.063054) (xy 101.328473 -221.11823) (xy 101.328982 -221.146116) (xy 101.328473 -221.174002)
			(xy 101.320353 -221.229178) (xy 101.304285 -221.282585) (xy 101.280613 -221.333082) (xy 101.24984 -221.379595)
			(xy 101.212623 -221.421132) (xy 101.169755 -221.456807) (xy 101.122149 -221.485861) (xy 101.07082 -221.507673)
			(xy 101.016863 -221.521779) (xy 100.961426 -221.527879) (xy 100.905692 -221.525842) (xy 100.850849 -221.515712)
			(xy 100.798065 -221.497705) (xy 100.748465 -221.472204) (xy 100.703107 -221.439753) (xy 100.662958 -221.401044)
			(xy 100.628872 -221.356901) (xy 100.601576 -221.308266) (xy 100.581653 -221.256175) (xy 100.569527 -221.201738)
			(xy 100.565456 -221.146116) (xy 97.558881 -221.146116) (xy 97.556261 -221.154823) (xy 97.532589 -221.20532)
			(xy 97.501816 -221.251833) (xy 97.464599 -221.29337) (xy 97.421731 -221.329045) (xy 97.374125 -221.358099)
			(xy 97.322796 -221.379911) (xy 97.268839 -221.394017) (xy 97.213402 -221.400117) (xy 97.157668 -221.39808)
			(xy 97.102825 -221.38795) (xy 97.050041 -221.369943) (xy 97.000441 -221.344442) (xy 96.955083 -221.311991)
			(xy 96.914934 -221.273282) (xy 96.880848 -221.229139) (xy 96.853552 -221.180504) (xy 96.833629 -221.128413)
			(xy 96.821503 -221.073976) (xy 96.817432 -221.018354) (xy 91.337384 -221.018354) (xy 91.337384 -222.46463)
			(xy 99.334318 -222.46463) (xy 99.338389 -222.409008) (xy 99.350515 -222.354571) (xy 99.370438 -222.30248)
			(xy 99.397734 -222.253845) (xy 99.43182 -222.209702) (xy 99.471969 -222.170993) (xy 99.517327 -222.138542)
			(xy 99.566927 -222.113041) (xy 99.619711 -222.095034) (xy 99.674554 -222.084904) (xy 99.730288 -222.082867)
			(xy 99.785725 -222.088967) (xy 99.839682 -222.103073) (xy 99.891011 -222.124885) (xy 99.938617 -222.153939)
			(xy 99.981485 -222.189614) (xy 99.999177 -222.20936) (xy 102.847392 -222.20936) (xy 102.851463 -222.153738)
			(xy 102.863589 -222.099301) (xy 102.883512 -222.04721) (xy 102.910808 -221.998575) (xy 102.944894 -221.954432)
			(xy 102.985043 -221.915723) (xy 103.030401 -221.883272) (xy 103.080001 -221.857771) (xy 103.132785 -221.839764)
			(xy 103.187628 -221.829634) (xy 103.243362 -221.827597) (xy 103.298799 -221.833697) (xy 103.352756 -221.847803)
			(xy 103.404085 -221.869615) (xy 103.451691 -221.898669) (xy 103.494559 -221.934344) (xy 103.531776 -221.975881)
			(xy 103.562549 -222.022394) (xy 103.586221 -222.072891) (xy 103.602289 -222.126298) (xy 103.610409 -222.181474)
			(xy 103.610918 -222.20936) (xy 103.610409 -222.237246) (xy 103.602289 -222.292422) (xy 103.586221 -222.345829)
			(xy 103.562549 -222.396326) (xy 103.531776 -222.442839) (xy 103.494559 -222.484376) (xy 103.451691 -222.520051)
			(xy 103.404085 -222.549105) (xy 103.352756 -222.570917) (xy 103.298799 -222.585023) (xy 103.243362 -222.591123)
			(xy 103.187628 -222.589086) (xy 103.132785 -222.578956) (xy 103.080001 -222.560949) (xy 103.030401 -222.535448)
			(xy 102.985043 -222.502997) (xy 102.944894 -222.464288) (xy 102.910808 -222.420145) (xy 102.883512 -222.37151)
			(xy 102.863589 -222.319419) (xy 102.851463 -222.264982) (xy 102.847392 -222.20936) (xy 99.999177 -222.20936)
			(xy 100.018702 -222.231151) (xy 100.049475 -222.277664) (xy 100.073147 -222.328161) (xy 100.089215 -222.381568)
			(xy 100.097335 -222.436744) (xy 100.097844 -222.46463) (xy 100.097335 -222.492516) (xy 100.089215 -222.547692)
			(xy 100.073147 -222.601099) (xy 100.049475 -222.651596) (xy 100.018702 -222.698109) (xy 99.981485 -222.739646)
			(xy 99.938617 -222.775321) (xy 99.891011 -222.804375) (xy 99.839682 -222.826187) (xy 99.785725 -222.840293)
			(xy 99.730288 -222.846393) (xy 99.674554 -222.844356) (xy 99.619711 -222.834226) (xy 99.566927 -222.816219)
			(xy 99.517327 -222.790718) (xy 99.471969 -222.758267) (xy 99.43182 -222.719558) (xy 99.397734 -222.675415)
			(xy 99.370438 -222.62678) (xy 99.350515 -222.574689) (xy 99.338389 -222.520252) (xy 99.334318 -222.46463)
			(xy 91.337384 -222.46463) (xy 91.337384 -223.135698) (xy 101.499414 -223.135698) (xy 101.503485 -223.080076)
			(xy 101.515611 -223.025639) (xy 101.535534 -222.973548) (xy 101.56283 -222.924913) (xy 101.596916 -222.88077)
			(xy 101.637065 -222.842061) (xy 101.682423 -222.80961) (xy 101.732023 -222.784109) (xy 101.784807 -222.766102)
			(xy 101.83965 -222.755972) (xy 101.895384 -222.753935) (xy 101.950821 -222.760035) (xy 102.004778 -222.774141)
			(xy 102.056107 -222.795953) (xy 102.103713 -222.825007) (xy 102.146581 -222.860682) (xy 102.183798 -222.902219)
			(xy 102.214571 -222.948732) (xy 102.238243 -222.999229) (xy 102.254311 -223.052636) (xy 102.262431 -223.107812)
			(xy 102.26294 -223.135698) (xy 102.262431 -223.163584) (xy 102.254311 -223.21876) (xy 102.238243 -223.272167)
			(xy 102.214571 -223.322664) (xy 102.183798 -223.369177) (xy 102.146581 -223.410714) (xy 102.103713 -223.446389)
			(xy 102.056107 -223.475443) (xy 102.004778 -223.497255) (xy 101.950821 -223.511361) (xy 101.895384 -223.517461)
			(xy 101.83965 -223.515424) (xy 101.784807 -223.505294) (xy 101.732023 -223.487287) (xy 101.682423 -223.461786)
			(xy 101.637065 -223.429335) (xy 101.596916 -223.390626) (xy 101.56283 -223.346483) (xy 101.535534 -223.297848)
			(xy 101.515611 -223.245757) (xy 101.503485 -223.19132) (xy 101.499414 -223.135698) (xy 91.337384 -223.135698)
			(xy 91.337384 -223.849946) (xy 102.606856 -223.849946) (xy 102.607325 -223.82284) (xy 102.615006 -223.769174)
			(xy 102.630206 -223.717137) (xy 102.652619 -223.667774) (xy 102.681792 -223.622081) (xy 102.71714 -223.580977)
			(xy 102.75795 -223.54529) (xy 102.8034 -223.515739) (xy 102.852575 -223.492919) (xy 102.904485 -223.477289)
			(xy 102.931214 -223.472756) (xy 102.942644 -223.470978) (xy 102.951788 -223.464882) (xy 102.956449 -223.461569)
			(xy 102.964272 -223.453234) (xy 102.967282 -223.448372) (xy 103.007668 -223.3803) (xy 103.010306 -223.375458)
			(xy 103.013638 -223.364949) (xy 103.014272 -223.359472) (xy 103.015542 -223.348296) (xy 103.011478 -223.337374)
			(xy 103.000589 -223.305642) (xy 102.988837 -223.239597) (xy 102.98811 -223.206056) (xy 102.988596 -223.178805)
			(xy 102.996352 -223.124857) (xy 103.011707 -223.072562) (xy 103.034349 -223.022985) (xy 103.063815 -222.977135)
			(xy 103.099506 -222.935944) (xy 103.140697 -222.900253) (xy 103.186547 -222.870787) (xy 103.236124 -222.848145)
			(xy 103.288419 -222.83279) (xy 103.342367 -222.825034) (xy 103.396869 -222.825034) (xy 103.450817 -222.83279)
			(xy 103.503112 -222.848145) (xy 103.552689 -222.870787) (xy 103.598539 -222.900253) (xy 103.63973 -222.935944)
			(xy 103.675421 -222.977135) (xy 103.704887 -223.022985) (xy 103.727529 -223.072562) (xy 103.742884 -223.124857)
			(xy 103.75064 -223.178805) (xy 103.751126 -223.206056) (xy 103.750674 -223.233163) (xy 103.742992 -223.28683)
			(xy 103.727791 -223.338869) (xy 103.705377 -223.388232) (xy 103.676202 -223.433926) (xy 103.640852 -223.47503)
			(xy 103.60004 -223.510717) (xy 103.559585 -223.537018) (xy 132.52907 -223.537018) (xy 132.533141 -223.481396)
			(xy 132.545267 -223.426959) (xy 132.56519 -223.374868) (xy 132.592486 -223.326233) (xy 132.626572 -223.28209)
			(xy 132.666721 -223.243381) (xy 132.712079 -223.21093) (xy 132.761679 -223.185429) (xy 132.814463 -223.167422)
			(xy 132.869306 -223.157292) (xy 132.92504 -223.155255) (xy 132.980477 -223.161355) (xy 133.034434 -223.175461)
			(xy 133.085763 -223.197273) (xy 133.133369 -223.226327) (xy 133.176237 -223.262002) (xy 133.213454 -223.303539)
			(xy 133.244227 -223.350052) (xy 133.267899 -223.400549) (xy 133.283967 -223.453956) (xy 133.292087 -223.509132)
			(xy 133.292596 -223.537018) (xy 133.292087 -223.564904) (xy 133.283967 -223.62008) (xy 133.267899 -223.673487)
			(xy 133.26698 -223.675448) (xy 150.046944 -223.675448) (xy 150.047384 -223.649507) (xy 150.054409 -223.598102)
			(xy 150.068338 -223.548124) (xy 150.088912 -223.500495) (xy 150.115752 -223.456094) (xy 150.148362 -223.415741)
			(xy 150.186142 -223.38018) (xy 150.228392 -223.350068) (xy 150.25116 -223.337628) (xy 150.263035 -223.330802)
			(xy 150.283007 -223.312082) (xy 150.297281 -223.288724) (xy 150.304828 -223.262411) (xy 150.305105 -223.235038)
			(xy 150.298093 -223.208578) (xy 150.284295 -223.184935) (xy 150.264707 -223.165814) (xy 150.252938 -223.158812)
			(xy 150.227705 -223.144302) (xy 150.181599 -223.108776) (xy 150.14142 -223.066663) (xy 150.108101 -223.018938)
			(xy 150.082413 -222.966707) (xy 150.064953 -222.911183) (xy 150.056124 -222.853651) (xy 150.05558 -222.824548)
			(xy 150.056066 -222.797297) (xy 150.063822 -222.743349) (xy 150.079177 -222.691054) (xy 150.101819 -222.641477)
			(xy 150.131285 -222.595627) (xy 150.166976 -222.554436) (xy 150.208167 -222.518745) (xy 150.254017 -222.489279)
			(xy 150.303594 -222.466637) (xy 150.355889 -222.451282) (xy 150.409837 -222.443526) (xy 150.464339 -222.443526)
			(xy 150.518287 -222.451282) (xy 150.570582 -222.466637) (xy 150.620159 -222.489279) (xy 150.666009 -222.518745)
			(xy 150.7072 -222.554436) (xy 150.742891 -222.595627) (xy 150.772357 -222.641477) (xy 150.794999 -222.691054)
			(xy 150.810354 -222.743349) (xy 150.81811 -222.797297) (xy 150.818596 -222.824548) (xy 150.818132 -222.850488)
			(xy 150.811107 -222.901891) (xy 150.797181 -222.951868) (xy 150.77661 -222.999496) (xy 150.749773 -223.043896)
			(xy 150.717167 -223.08425) (xy 150.679392 -223.119812) (xy 150.637146 -223.149926) (xy 150.61438 -223.162368)
			(xy 150.602514 -223.169203) (xy 150.582553 -223.187926) (xy 150.568288 -223.211283) (xy 150.560745 -223.237591)
			(xy 150.560468 -223.264957) (xy 150.567475 -223.291413) (xy 150.581263 -223.315054) (xy 150.600839 -223.334179)
			(xy 150.612602 -223.341184) (xy 150.637842 -223.355681) (xy 150.683947 -223.391211) (xy 150.724123 -223.433327)
			(xy 150.757441 -223.481055) (xy 150.783127 -223.533286) (xy 150.800587 -223.588812) (xy 150.809416 -223.646345)
			(xy 150.80996 -223.675448) (xy 150.809474 -223.702699) (xy 150.801718 -223.756647) (xy 150.786363 -223.808942)
			(xy 150.763721 -223.858519) (xy 150.734255 -223.904369) (xy 150.698564 -223.94556) (xy 150.657373 -223.981251)
			(xy 150.611523 -224.010717) (xy 150.561946 -224.033359) (xy 150.509651 -224.048714) (xy 150.455703 -224.05647)
			(xy 150.401201 -224.05647) (xy 150.347253 -224.048714) (xy 150.294958 -224.033359) (xy 150.245381 -224.010717)
			(xy 150.199531 -223.981251) (xy 150.15834 -223.94556) (xy 150.122649 -223.904369) (xy 150.093183 -223.858519)
			(xy 150.070541 -223.808942) (xy 150.055186 -223.756647) (xy 150.04743 -223.702699) (xy 150.046944 -223.675448)
			(xy 133.26698 -223.675448) (xy 133.244227 -223.723984) (xy 133.213454 -223.770497) (xy 133.176237 -223.812034)
			(xy 133.133369 -223.847709) (xy 133.085763 -223.876763) (xy 133.034434 -223.898575) (xy 132.980477 -223.912681)
			(xy 132.92504 -223.918781) (xy 132.869306 -223.916744) (xy 132.814463 -223.906614) (xy 132.761679 -223.888607)
			(xy 132.712079 -223.863106) (xy 132.666721 -223.830655) (xy 132.626572 -223.791946) (xy 132.592486 -223.747803)
			(xy 132.56519 -223.699168) (xy 132.545267 -223.647077) (xy 132.533141 -223.59264) (xy 132.52907 -223.537018)
			(xy 103.559585 -223.537018) (xy 103.554588 -223.540267) (xy 103.50541 -223.563086) (xy 103.453498 -223.578715)
			(xy 103.426768 -223.583246) (xy 103.415338 -223.585024) (xy 103.406194 -223.59112) (xy 103.401544 -223.594446)
			(xy 103.393713 -223.602772) (xy 103.3907 -223.60763) (xy 103.350314 -223.675702) (xy 103.347674 -223.680543)
			(xy 103.344344 -223.691053) (xy 103.34371 -223.69653) (xy 103.34244 -223.707706) (xy 103.346504 -223.718628)
			(xy 103.357393 -223.75036) (xy 103.369145 -223.816405) (xy 103.369872 -223.849946) (xy 103.369641 -223.868613)
			(xy 103.365947 -223.905765) (xy 103.362506 -223.924114) (xy 103.360474 -223.935036) (xy 103.36276 -223.94545)
			(xy 103.364108 -223.950667) (xy 103.368728 -223.960401) (xy 103.371904 -223.964754) (xy 103.406913 -224.010728)
			(xy 129.104896 -224.010728) (xy 129.108967 -223.955106) (xy 129.121093 -223.900669) (xy 129.141016 -223.848578)
			(xy 129.168312 -223.799943) (xy 129.202398 -223.7558) (xy 129.242547 -223.717091) (xy 129.287905 -223.68464)
			(xy 129.337505 -223.659139) (xy 129.390289 -223.641132) (xy 129.445132 -223.631002) (xy 129.500866 -223.628965)
			(xy 129.556303 -223.635065) (xy 129.61026 -223.649171) (xy 129.661589 -223.670983) (xy 129.709195 -223.700037)
			(xy 129.752063 -223.735712) (xy 129.78928 -223.777249) (xy 129.820053 -223.823762) (xy 129.843725 -223.874259)
			(xy 129.859793 -223.927666) (xy 129.867913 -223.982842) (xy 129.868422 -224.010728) (xy 129.867913 -224.038614)
			(xy 129.859793 -224.09379) (xy 129.843725 -224.147197) (xy 129.820053 -224.197694) (xy 129.78928 -224.244207)
			(xy 129.752063 -224.285744) (xy 129.709195 -224.321419) (xy 129.661589 -224.350473) (xy 129.61026 -224.372285)
			(xy 129.556303 -224.386391) (xy 129.500866 -224.392491) (xy 129.445132 -224.390454) (xy 129.390289 -224.380324)
			(xy 129.337505 -224.362317) (xy 129.287905 -224.336816) (xy 129.242547 -224.304365) (xy 129.202398 -224.265656)
			(xy 129.168312 -224.221513) (xy 129.141016 -224.172878) (xy 129.121093 -224.120787) (xy 129.108967 -224.06635)
			(xy 129.104896 -224.010728) (xy 103.406913 -224.010728) (xy 103.418132 -224.02546) (xy 103.421462 -224.029603)
			(xy 103.42953 -224.03652) (xy 103.434134 -224.039176) (xy 103.443786 -224.04451) (xy 103.454708 -224.045272)
			(xy 103.483187 -224.047862) (xy 103.538962 -224.06048) (xy 103.592229 -224.081281) (xy 103.641795 -224.109799)
			(xy 103.686551 -224.145394) (xy 103.725492 -224.18727) (xy 103.757748 -224.234489) (xy 103.782595 -224.285993)
			(xy 103.799478 -224.340629) (xy 103.808018 -224.397172) (xy 103.80853 -224.425764) (xy 103.808044 -224.453015)
			(xy 103.800288 -224.506963) (xy 103.793179 -224.531174) (xy 107.58373 -224.531174) (xy 107.587801 -224.475552)
			(xy 107.599927 -224.421115) (xy 107.61985 -224.369024) (xy 107.647146 -224.320389) (xy 107.681232 -224.276246)
			(xy 107.721381 -224.237537) (xy 107.766739 -224.205086) (xy 107.816339 -224.179585) (xy 107.869123 -224.161578)
			(xy 107.923966 -224.151448) (xy 107.9797 -224.149411) (xy 108.035137 -224.155511) (xy 108.089094 -224.169617)
			(xy 108.140423 -224.191429) (xy 108.188029 -224.220483) (xy 108.230897 -224.256158) (xy 108.268114 -224.297695)
			(xy 108.298887 -224.344208) (xy 108.322559 -224.394705) (xy 108.338627 -224.448112) (xy 108.340534 -224.46107)
			(xy 119.436386 -224.46107) (xy 119.440457 -224.405448) (xy 119.452583 -224.351011) (xy 119.472506 -224.29892)
			(xy 119.499802 -224.250285) (xy 119.533888 -224.206142) (xy 119.574037 -224.167433) (xy 119.619395 -224.134982)
			(xy 119.668995 -224.109481) (xy 119.721779 -224.091474) (xy 119.776622 -224.081344) (xy 119.832356 -224.079307)
			(xy 119.887793 -224.085407) (xy 119.94175 -224.099513) (xy 119.993079 -224.121325) (xy 120.040685 -224.150379)
			(xy 120.083553 -224.186054) (xy 120.12077 -224.227591) (xy 120.151543 -224.274104) (xy 120.175215 -224.324601)
			(xy 120.191283 -224.378008) (xy 120.199403 -224.433184) (xy 120.199912 -224.46107) (xy 120.199403 -224.488956)
			(xy 120.191283 -224.544132) (xy 120.18554 -224.56322) (xy 143.847118 -224.56322) (xy 143.847122 -224.508724)
			(xy 143.854881 -224.454785) (xy 143.870238 -224.402498) (xy 143.892879 -224.352929) (xy 143.922344 -224.307086)
			(xy 143.958033 -224.265904) (xy 143.99922 -224.230219) (xy 144.045066 -224.200759) (xy 144.094637 -224.178123)
			(xy 144.146926 -224.162772) (xy 144.200866 -224.155019) (xy 144.255362 -224.155021) (xy 144.309302 -224.162778)
			(xy 144.361589 -224.178133) (xy 144.411159 -224.200772) (xy 144.457003 -224.230236) (xy 144.498187 -224.265923)
			(xy 144.533873 -224.307109) (xy 144.563334 -224.352953) (xy 144.585972 -224.402524) (xy 144.601325 -224.454812)
			(xy 144.60908 -224.508752) (xy 144.609566 -224.536) (xy 146.89404 -224.536) (xy 146.898111 -224.480378)
			(xy 146.910237 -224.425941) (xy 146.93016 -224.37385) (xy 146.957456 -224.325215) (xy 146.991542 -224.281072)
			(xy 147.031691 -224.242363) (xy 147.077049 -224.209912) (xy 147.126649 -224.184411) (xy 147.179433 -224.166404)
			(xy 147.234276 -224.156274) (xy 147.29001 -224.154237) (xy 147.345447 -224.160337) (xy 147.399404 -224.174443)
			(xy 147.450733 -224.196255) (xy 147.498339 -224.225309) (xy 147.541207 -224.260984) (xy 147.578424 -224.302521)
			(xy 147.609197 -224.349034) (xy 147.632869 -224.399531) (xy 147.648937 -224.452938) (xy 147.657057 -224.508114)
			(xy 147.657566 -224.536) (xy 147.657057 -224.563886) (xy 147.648937 -224.619062) (xy 147.632869 -224.672469)
			(xy 147.609197 -224.722966) (xy 147.578424 -224.769479) (xy 147.541207 -224.811016) (xy 147.498339 -224.846691)
			(xy 147.450733 -224.875745) (xy 147.399404 -224.897557) (xy 147.345447 -224.911663) (xy 147.29001 -224.917763)
			(xy 147.234276 -224.915726) (xy 147.179433 -224.905596) (xy 147.126649 -224.887589) (xy 147.077049 -224.862088)
			(xy 147.031691 -224.829637) (xy 146.991542 -224.790928) (xy 146.957456 -224.746785) (xy 146.93016 -224.69815)
			(xy 146.910237 -224.646059) (xy 146.898111 -224.591622) (xy 146.89404 -224.536) (xy 144.609566 -224.536)
			(xy 144.609566 -224.536508) (xy 144.6091 -224.56335) (xy 144.601542 -224.616499) (xy 144.586606 -224.668063)
			(xy 144.564585 -224.717024) (xy 144.550638 -224.739962) (xy 144.543483 -224.752063) (xy 144.535511 -224.779014)
			(xy 144.535196 -224.807116) (xy 144.542559 -224.834239) (xy 144.557044 -224.858323) (xy 144.57755 -224.877542)
			(xy 144.602522 -224.890436) (xy 144.630064 -224.896028) (xy 144.64411 -224.89541) (xy 144.672558 -224.894394)
			(xy 144.699815 -224.89481) (xy 144.753773 -224.902562) (xy 144.80608 -224.917915) (xy 144.855669 -224.940555)
			(xy 144.901531 -224.970023) (xy 144.942733 -225.005717) (xy 144.978435 -225.046912) (xy 145.007911 -225.092769)
			(xy 145.03056 -225.142354) (xy 145.045923 -225.194657) (xy 145.053685 -225.248615) (xy 145.053689 -225.303128)
			(xy 145.045935 -225.357087) (xy 145.03058 -225.409392) (xy 145.007938 -225.458981) (xy 144.978469 -225.504842)
			(xy 144.942773 -225.546042) (xy 144.935898 -225.552) (xy 146.89404 -225.552) (xy 146.898111 -225.496378)
			(xy 146.910237 -225.441941) (xy 146.93016 -225.38985) (xy 146.957456 -225.341215) (xy 146.991542 -225.297072)
			(xy 147.031691 -225.258363) (xy 147.077049 -225.225912) (xy 147.126649 -225.200411) (xy 147.179433 -225.182404)
			(xy 147.234276 -225.172274) (xy 147.29001 -225.170237) (xy 147.345447 -225.176337) (xy 147.399404 -225.190443)
			(xy 147.450733 -225.212255) (xy 147.498339 -225.241309) (xy 147.541207 -225.276984) (xy 147.578424 -225.318521)
			(xy 147.609197 -225.365034) (xy 147.632869 -225.415531) (xy 147.648937 -225.468938) (xy 147.657057 -225.524114)
			(xy 147.657566 -225.552) (xy 147.657057 -225.579886) (xy 147.648937 -225.635062) (xy 147.632869 -225.688469)
			(xy 147.609197 -225.738966) (xy 147.578424 -225.785479) (xy 147.541207 -225.827016) (xy 147.498339 -225.862691)
			(xy 147.450733 -225.891745) (xy 147.399404 -225.913557) (xy 147.345447 -225.927663) (xy 147.29001 -225.933763)
			(xy 147.234276 -225.931726) (xy 147.179433 -225.921596) (xy 147.126649 -225.903589) (xy 147.077049 -225.878088)
			(xy 147.031691 -225.845637) (xy 146.991542 -225.806928) (xy 146.957456 -225.762785) (xy 146.93016 -225.71415)
			(xy 146.910237 -225.662059) (xy 146.898111 -225.607622) (xy 146.89404 -225.552) (xy 144.935898 -225.552)
			(xy 144.901577 -225.581743) (xy 144.855719 -225.611217) (xy 144.806134 -225.633865) (xy 144.75383 -225.649226)
			(xy 144.699872 -225.656986) (xy 144.645359 -225.656988) (xy 144.5914 -225.649232) (xy 144.539095 -225.633876)
			(xy 144.489508 -225.611232) (xy 144.443648 -225.581761) (xy 144.402449 -225.546064) (xy 144.366749 -225.504866)
			(xy 144.337277 -225.459008) (xy 144.31463 -225.409421) (xy 144.299272 -225.357117) (xy 144.291513 -225.303158)
			(xy 144.29105 -225.275902) (xy 144.29105 -225.275394) (xy 144.29153 -225.248553) (xy 144.299086 -225.195404)
			(xy 144.314018 -225.14384) (xy 144.336034 -225.094879) (xy 144.349978 -225.07194) (xy 144.357117 -225.05983)
			(xy 144.365086 -225.032883) (xy 144.365401 -225.004784) (xy 144.358039 -224.977665) (xy 144.343557 -224.953584)
			(xy 144.323055 -224.934366) (xy 144.298088 -224.921471) (xy 144.27055 -224.915876) (xy 144.256506 -224.916492)
			(xy 144.228058 -224.917508) (xy 144.20081 -224.916977) (xy 144.146871 -224.909216) (xy 144.094585 -224.893857)
			(xy 144.045016 -224.871214) (xy 143.999175 -224.841747) (xy 143.957994 -224.806057) (xy 143.922311 -224.764869)
			(xy 143.892852 -224.719022) (xy 143.870218 -224.66945) (xy 143.854869 -224.617161) (xy 143.847118 -224.56322)
			(xy 120.18554 -224.56322) (xy 120.175215 -224.597539) (xy 120.151543 -224.648036) (xy 120.12077 -224.694549)
			(xy 120.083553 -224.736086) (xy 120.040685 -224.771761) (xy 119.993079 -224.800815) (xy 119.94175 -224.822627)
			(xy 119.887793 -224.836733) (xy 119.832356 -224.842833) (xy 119.776622 -224.840796) (xy 119.721779 -224.830666)
			(xy 119.668995 -224.812659) (xy 119.619395 -224.787158) (xy 119.574037 -224.754707) (xy 119.533888 -224.715998)
			(xy 119.499802 -224.671855) (xy 119.472506 -224.62322) (xy 119.452583 -224.571129) (xy 119.440457 -224.516692)
			(xy 119.436386 -224.46107) (xy 108.340534 -224.46107) (xy 108.346747 -224.503288) (xy 108.347256 -224.531174)
			(xy 108.346747 -224.55906) (xy 108.338627 -224.614236) (xy 108.322559 -224.667643) (xy 108.298887 -224.71814)
			(xy 108.268114 -224.764653) (xy 108.230897 -224.80619) (xy 108.188029 -224.841865) (xy 108.140423 -224.870919)
			(xy 108.089094 -224.892731) (xy 108.035137 -224.906837) (xy 107.9797 -224.912937) (xy 107.923966 -224.9109)
			(xy 107.869123 -224.90077) (xy 107.816339 -224.882763) (xy 107.766739 -224.857262) (xy 107.721381 -224.824811)
			(xy 107.681232 -224.786102) (xy 107.647146 -224.741959) (xy 107.61985 -224.693324) (xy 107.599927 -224.641233)
			(xy 107.587801 -224.586796) (xy 107.58373 -224.531174) (xy 103.793179 -224.531174) (xy 103.784933 -224.559258)
			(xy 103.762291 -224.608835) (xy 103.732825 -224.654685) (xy 103.697134 -224.695876) (xy 103.655943 -224.731567)
			(xy 103.610093 -224.761033) (xy 103.560516 -224.783675) (xy 103.508221 -224.79903) (xy 103.454273 -224.806786)
			(xy 103.399771 -224.806786) (xy 103.345823 -224.79903) (xy 103.293528 -224.783675) (xy 103.243951 -224.761033)
			(xy 103.198101 -224.731567) (xy 103.15691 -224.695876) (xy 103.121219 -224.654685) (xy 103.091753 -224.608835)
			(xy 103.069111 -224.559258) (xy 103.053756 -224.506963) (xy 103.046 -224.453015) (xy 103.045514 -224.425764)
			(xy 103.045747 -224.407097) (xy 103.049439 -224.369945) (xy 103.05288 -224.351596) (xy 103.054912 -224.340674)
			(xy 103.052626 -224.33026) (xy 103.051277 -224.325043) (xy 103.046658 -224.315309) (xy 103.043482 -224.310956)
			(xy 102.997254 -224.25025) (xy 102.993925 -224.246106) (xy 102.985857 -224.239189) (xy 102.981252 -224.236534)
			(xy 102.9716 -224.2312) (xy 102.960678 -224.230438) (xy 102.932195 -224.227863) (xy 102.876415 -224.215253)
			(xy 102.823141 -224.194457) (xy 102.773569 -224.165941) (xy 102.72881 -224.130345) (xy 102.689866 -224.088465)
			(xy 102.657611 -224.041241) (xy 102.632767 -223.989731) (xy 102.615892 -223.935089) (xy 102.607362 -223.87854)
			(xy 102.606856 -223.849946) (xy 91.337384 -223.849946) (xy 91.337384 -225.031808) (xy 120.279666 -225.031808)
			(xy 120.283737 -224.976186) (xy 120.295863 -224.921749) (xy 120.315786 -224.869658) (xy 120.343082 -224.821023)
			(xy 120.377168 -224.77688) (xy 120.417317 -224.738171) (xy 120.462675 -224.70572) (xy 120.512275 -224.680219)
			(xy 120.565059 -224.662212) (xy 120.619902 -224.652082) (xy 120.675636 -224.650045) (xy 120.731073 -224.656145)
			(xy 120.78503 -224.670251) (xy 120.836359 -224.692063) (xy 120.883965 -224.721117) (xy 120.926833 -224.756792)
			(xy 120.96405 -224.798329) (xy 120.994823 -224.844842) (xy 121.018495 -224.895339) (xy 121.034563 -224.948746)
			(xy 121.042683 -225.003922) (xy 121.043192 -225.031808) (xy 121.042683 -225.059694) (xy 121.034563 -225.11487)
			(xy 121.018495 -225.168277) (xy 120.994823 -225.218774) (xy 120.96405 -225.265287) (xy 120.926833 -225.306824)
			(xy 120.883965 -225.342499) (xy 120.836359 -225.371553) (xy 120.78503 -225.393365) (xy 120.731073 -225.407471)
			(xy 120.675636 -225.413571) (xy 120.619902 -225.411534) (xy 120.565059 -225.401404) (xy 120.512275 -225.383397)
			(xy 120.462675 -225.357896) (xy 120.417317 -225.325445) (xy 120.377168 -225.286736) (xy 120.343082 -225.242593)
			(xy 120.315786 -225.193958) (xy 120.295863 -225.141867) (xy 120.283737 -225.08743) (xy 120.279666 -225.031808)
			(xy 91.337384 -225.031808) (xy 91.337384 -225.65106) (xy 129.012694 -225.65106) (xy 129.016765 -225.595438)
			(xy 129.028891 -225.541001) (xy 129.048814 -225.48891) (xy 129.07611 -225.440275) (xy 129.110196 -225.396132)
			(xy 129.150345 -225.357423) (xy 129.195703 -225.324972) (xy 129.245303 -225.299471) (xy 129.298087 -225.281464)
			(xy 129.35293 -225.271334) (xy 129.408664 -225.269297) (xy 129.464101 -225.275397) (xy 129.518058 -225.289503)
			(xy 129.569387 -225.311315) (xy 129.616993 -225.340369) (xy 129.659861 -225.376044) (xy 129.697078 -225.417581)
			(xy 129.727851 -225.464094) (xy 129.751523 -225.514591) (xy 129.767591 -225.567998) (xy 129.775711 -225.623174)
			(xy 129.775724 -225.623882) (xy 134.483854 -225.623882) (xy 134.487925 -225.56826) (xy 134.500051 -225.513823)
			(xy 134.519974 -225.461732) (xy 134.54727 -225.413097) (xy 134.581356 -225.368954) (xy 134.621505 -225.330245)
			(xy 134.666863 -225.297794) (xy 134.716463 -225.272293) (xy 134.769247 -225.254286) (xy 134.82409 -225.244156)
			(xy 134.879824 -225.242119) (xy 134.935261 -225.248219) (xy 134.989218 -225.262325) (xy 135.040547 -225.284137)
			(xy 135.088153 -225.313191) (xy 135.131021 -225.348866) (xy 135.168238 -225.390403) (xy 135.199011 -225.436916)
			(xy 135.222683 -225.487413) (xy 135.238751 -225.54082) (xy 135.24163 -225.560382) (xy 136.388854 -225.560382)
			(xy 136.392925 -225.50476) (xy 136.405051 -225.450323) (xy 136.424974 -225.398232) (xy 136.45227 -225.349597)
			(xy 136.486356 -225.305454) (xy 136.526505 -225.266745) (xy 136.571863 -225.234294) (xy 136.621463 -225.208793)
			(xy 136.674247 -225.190786) (xy 136.72909 -225.180656) (xy 136.784824 -225.178619) (xy 136.840261 -225.184719)
			(xy 136.894218 -225.198825) (xy 136.945547 -225.220637) (xy 136.993153 -225.249691) (xy 137.036021 -225.285366)
			(xy 137.073238 -225.326903) (xy 137.104011 -225.373416) (xy 137.127683 -225.423913) (xy 137.143751 -225.47732)
			(xy 137.151871 -225.532496) (xy 137.15238 -225.560382) (xy 137.151871 -225.588268) (xy 137.143751 -225.643444)
			(xy 137.127683 -225.696851) (xy 137.104011 -225.747348) (xy 137.073238 -225.793861) (xy 137.036021 -225.835398)
			(xy 136.993153 -225.871073) (xy 136.945547 -225.900127) (xy 136.894218 -225.921939) (xy 136.840261 -225.936045)
			(xy 136.784824 -225.942145) (xy 136.72909 -225.940108) (xy 136.674247 -225.929978) (xy 136.621463 -225.911971)
			(xy 136.571863 -225.88647) (xy 136.526505 -225.854019) (xy 136.486356 -225.81531) (xy 136.45227 -225.771167)
			(xy 136.424974 -225.722532) (xy 136.405051 -225.670441) (xy 136.392925 -225.616004) (xy 136.388854 -225.560382)
			(xy 135.24163 -225.560382) (xy 135.246871 -225.595996) (xy 135.24738 -225.623882) (xy 135.246871 -225.651768)
			(xy 135.238751 -225.706944) (xy 135.222683 -225.760351) (xy 135.199011 -225.810848) (xy 135.168238 -225.857361)
			(xy 135.131021 -225.898898) (xy 135.088153 -225.934573) (xy 135.040547 -225.963627) (xy 134.989218 -225.985439)
			(xy 134.935261 -225.999545) (xy 134.879824 -226.005645) (xy 134.82409 -226.003608) (xy 134.769247 -225.993478)
			(xy 134.716463 -225.975471) (xy 134.666863 -225.94997) (xy 134.621505 -225.917519) (xy 134.581356 -225.87881)
			(xy 134.54727 -225.834667) (xy 134.519974 -225.786032) (xy 134.500051 -225.733941) (xy 134.487925 -225.679504)
			(xy 134.483854 -225.623882) (xy 129.775724 -225.623882) (xy 129.77622 -225.65106) (xy 129.775711 -225.678946)
			(xy 129.767591 -225.734122) (xy 129.751523 -225.787529) (xy 129.727851 -225.838026) (xy 129.697078 -225.884539)
			(xy 129.659861 -225.926076) (xy 129.616993 -225.961751) (xy 129.569387 -225.990805) (xy 129.518058 -226.012617)
			(xy 129.464101 -226.026723) (xy 129.408664 -226.032823) (xy 129.35293 -226.030786) (xy 129.298087 -226.020656)
			(xy 129.245303 -226.002649) (xy 129.195703 -225.977148) (xy 129.150345 -225.944697) (xy 129.110196 -225.905988)
			(xy 129.07611 -225.861845) (xy 129.048814 -225.81321) (xy 129.028891 -225.761119) (xy 129.016765 -225.706682)
			(xy 129.012694 -225.65106) (xy 91.337384 -225.65106) (xy 91.337384 -226.595686) (xy 104.066338 -226.595686)
			(xy 104.070409 -226.540064) (xy 104.082535 -226.485627) (xy 104.102458 -226.433536) (xy 104.129754 -226.384901)
			(xy 104.16384 -226.340758) (xy 104.203989 -226.302049) (xy 104.249347 -226.269598) (xy 104.298947 -226.244097)
			(xy 104.351731 -226.22609) (xy 104.406574 -226.21596) (xy 104.462308 -226.213923) (xy 104.517745 -226.220023)
			(xy 104.571702 -226.234129) (xy 104.623031 -226.255941) (xy 104.670637 -226.284995) (xy 104.713505 -226.32067)
			(xy 104.750722 -226.362207) (xy 104.781495 -226.40872) (xy 104.805167 -226.459217) (xy 104.821235 -226.512624)
			(xy 104.829355 -226.5678) (xy 104.829864 -226.595686) (xy 104.829355 -226.623572) (xy 104.821235 -226.678748)
			(xy 104.805167 -226.732155) (xy 104.781495 -226.782652) (xy 104.750722 -226.829165) (xy 104.713505 -226.870702)
			(xy 104.670637 -226.906377) (xy 104.623031 -226.935431) (xy 104.571702 -226.957243) (xy 104.517745 -226.971349)
			(xy 104.462308 -226.977449) (xy 104.406574 -226.975412) (xy 104.351731 -226.965282) (xy 104.298947 -226.947275)
			(xy 104.249347 -226.921774) (xy 104.203989 -226.889323) (xy 104.16384 -226.850614) (xy 104.129754 -226.806471)
			(xy 104.102458 -226.757836) (xy 104.082535 -226.705745) (xy 104.070409 -226.651308) (xy 104.066338 -226.595686)
			(xy 91.337384 -226.595686) (xy 91.337384 -228.714046) (xy 109.43082 -228.714046) (xy 109.43082 -228.713792)
			(xy 109.431267 -228.687497) (xy 109.438514 -228.635407) (xy 109.452842 -228.584805) (xy 109.473979 -228.536649)
			(xy 109.501527 -228.49185) (xy 109.534962 -228.451256) (xy 109.55401 -228.433122) (xy 109.561406 -228.425596)
			(xy 109.569933 -228.406319) (xy 109.57052 -228.395784) (xy 109.57052 -228.321108) (xy 109.569994 -228.310558)
			(xy 109.561456 -228.291263) (xy 109.55401 -228.28377) (xy 109.534918 -228.265648) (xy 109.501441 -228.225025)
			(xy 109.473872 -228.180182) (xy 109.452735 -228.131972) (xy 109.438434 -228.081312) (xy 109.431239 -228.029166)
			(xy 109.43082 -228.002846) (xy 109.431251 -227.976529) (xy 109.438475 -227.924394) (xy 109.452792 -227.873745)
			(xy 109.47393 -227.825543) (xy 109.50149 -227.780702) (xy 109.534948 -227.740071) (xy 109.55401 -227.721922)
			(xy 109.561406 -227.714396) (xy 109.569933 -227.695119) (xy 109.57052 -227.684584) (xy 109.57052 -227.609908)
			(xy 109.569994 -227.599358) (xy 109.561456 -227.580063) (xy 109.55401 -227.57257) (xy 109.534918 -227.554448)
			(xy 109.501441 -227.513825) (xy 109.473872 -227.468982) (xy 109.452735 -227.420772) (xy 109.438434 -227.370112)
			(xy 109.431239 -227.317966) (xy 109.43082 -227.291646) (xy 109.431251 -227.265329) (xy 109.438475 -227.213194)
			(xy 109.452792 -227.162545) (xy 109.47393 -227.114343) (xy 109.50149 -227.069502) (xy 109.534948 -227.028871)
			(xy 109.55401 -227.010722) (xy 109.561406 -227.003196) (xy 109.569933 -226.983919) (xy 109.57052 -226.973384)
			(xy 109.57052 -226.898708) (xy 109.569994 -226.888158) (xy 109.561456 -226.868863) (xy 109.55401 -226.86137)
			(xy 109.534933 -226.843263) (xy 109.501478 -226.802677) (xy 109.473921 -226.757876) (xy 109.452785 -226.709712)
			(xy 109.438473 -226.659099) (xy 109.431255 -226.606999) (xy 109.43082 -226.5807) (xy 109.43082 -226.580446)
			(xy 109.431306 -226.553195) (xy 109.439062 -226.499247) (xy 109.454417 -226.446952) (xy 109.477059 -226.397375)
			(xy 109.506525 -226.351525) (xy 109.542216 -226.310334) (xy 109.583407 -226.274643) (xy 109.629257 -226.245177)
			(xy 109.678834 -226.222535) (xy 109.731129 -226.20718) (xy 109.785077 -226.199424) (xy 109.839579 -226.199424)
			(xy 109.893527 -226.20718) (xy 109.945822 -226.222535) (xy 109.995399 -226.245177) (xy 110.041249 -226.274643)
			(xy 110.08244 -226.310334) (xy 110.09508 -226.324922) (xy 141.670022 -226.324922) (xy 141.674093 -226.2693)
			(xy 141.686219 -226.214863) (xy 141.706142 -226.162772) (xy 141.733438 -226.114137) (xy 141.767524 -226.069994)
			(xy 141.807673 -226.031285) (xy 141.853031 -225.998834) (xy 141.902631 -225.973333) (xy 141.955415 -225.955326)
			(xy 142.010258 -225.945196) (xy 142.065992 -225.943159) (xy 142.121429 -225.949259) (xy 142.175386 -225.963365)
			(xy 142.226715 -225.985177) (xy 142.274321 -226.014231) (xy 142.317189 -226.049906) (xy 142.354406 -226.091443)
			(xy 142.385179 -226.137956) (xy 142.408851 -226.188453) (xy 142.424919 -226.24186) (xy 142.433039 -226.297036)
			(xy 142.433548 -226.324922) (xy 142.433039 -226.352808) (xy 142.424919 -226.407984) (xy 142.408851 -226.461391)
			(xy 142.385179 -226.511888) (xy 142.354406 -226.558401) (xy 142.345805 -226.568) (xy 147.02104 -226.568)
			(xy 147.025111 -226.512378) (xy 147.037237 -226.457941) (xy 147.05716 -226.40585) (xy 147.084456 -226.357215)
			(xy 147.118542 -226.313072) (xy 147.158691 -226.274363) (xy 147.204049 -226.241912) (xy 147.253649 -226.216411)
			(xy 147.306433 -226.198404) (xy 147.361276 -226.188274) (xy 147.41701 -226.186237) (xy 147.472447 -226.192337)
			(xy 147.526404 -226.206443) (xy 147.577733 -226.228255) (xy 147.625339 -226.257309) (xy 147.668207 -226.292984)
			(xy 147.705424 -226.334521) (xy 147.736197 -226.381034) (xy 147.759869 -226.431531) (xy 147.775937 -226.484938)
			(xy 147.784057 -226.540114) (xy 147.784566 -226.568) (xy 147.784057 -226.595886) (xy 147.775937 -226.651062)
			(xy 147.759869 -226.704469) (xy 147.736197 -226.754966) (xy 147.705424 -226.801479) (xy 147.668207 -226.843016)
			(xy 147.625339 -226.878691) (xy 147.577733 -226.907745) (xy 147.526404 -226.929557) (xy 147.472447 -226.943663)
			(xy 147.41701 -226.949763) (xy 147.361276 -226.947726) (xy 147.306433 -226.937596) (xy 147.253649 -226.919589)
			(xy 147.204049 -226.894088) (xy 147.158691 -226.861637) (xy 147.118542 -226.822928) (xy 147.084456 -226.778785)
			(xy 147.05716 -226.73015) (xy 147.037237 -226.678059) (xy 147.025111 -226.623622) (xy 147.02104 -226.568)
			(xy 142.345805 -226.568) (xy 142.317189 -226.599938) (xy 142.274321 -226.635613) (xy 142.226715 -226.664667)
			(xy 142.175386 -226.686479) (xy 142.121429 -226.700585) (xy 142.065992 -226.706685) (xy 142.010258 -226.704648)
			(xy 141.955415 -226.694518) (xy 141.902631 -226.676511) (xy 141.853031 -226.65101) (xy 141.807673 -226.618559)
			(xy 141.767524 -226.57985) (xy 141.733438 -226.535707) (xy 141.706142 -226.487072) (xy 141.686219 -226.434981)
			(xy 141.674093 -226.380544) (xy 141.670022 -226.324922) (xy 110.09508 -226.324922) (xy 110.118131 -226.351525)
			(xy 110.147597 -226.397375) (xy 110.170239 -226.446952) (xy 110.185594 -226.499247) (xy 110.19335 -226.553195)
			(xy 110.193836 -226.580446) (xy 110.193836 -226.5807) (xy 110.193366 -226.606994) (xy 110.186121 -226.659082)
			(xy 110.171797 -226.709683) (xy 110.150663 -226.757839) (xy 110.123121 -226.802639) (xy 110.089691 -226.843235)
			(xy 110.070646 -226.86137) (xy 110.063263 -226.868907) (xy 110.054726 -226.888175) (xy 110.054136 -226.898708)
			(xy 110.054136 -226.973384) (xy 110.054649 -226.983936) (xy 110.063194 -227.003232) (xy 110.070646 -227.010722)
			(xy 110.089726 -227.028857) (xy 110.123206 -227.069476) (xy 110.150778 -227.114316) (xy 110.171916 -227.162524)
			(xy 110.176962 -227.180394) (xy 142.915892 -227.180394) (xy 142.919963 -227.124772) (xy 142.932089 -227.070335)
			(xy 142.952012 -227.018244) (xy 142.979308 -226.969609) (xy 143.013394 -226.925466) (xy 143.053543 -226.886757)
			(xy 143.098901 -226.854306) (xy 143.148501 -226.828805) (xy 143.201285 -226.810798) (xy 143.256128 -226.800668)
			(xy 143.311862 -226.798631) (xy 143.367299 -226.804731) (xy 143.421256 -226.818837) (xy 143.472585 -226.840649)
			(xy 143.520191 -226.869703) (xy 143.563059 -226.905378) (xy 143.600276 -226.946915) (xy 143.631049 -226.993428)
			(xy 143.654721 -227.043925) (xy 143.670789 -227.097332) (xy 143.678909 -227.152508) (xy 143.679418 -227.180394)
			(xy 143.678909 -227.20828) (xy 143.670789 -227.263456) (xy 143.654721 -227.316863) (xy 143.631049 -227.36736)
			(xy 143.600276 -227.413873) (xy 143.563059 -227.45541) (xy 143.52727 -227.485194) (xy 150.013922 -227.485194)
			(xy 150.017993 -227.429572) (xy 150.030119 -227.375135) (xy 150.050042 -227.323044) (xy 150.077338 -227.274409)
			(xy 150.111424 -227.230266) (xy 150.151573 -227.191557) (xy 150.196931 -227.159106) (xy 150.246531 -227.133605)
			(xy 150.299315 -227.115598) (xy 150.354158 -227.105468) (xy 150.409892 -227.103431) (xy 150.465329 -227.109531)
			(xy 150.519286 -227.123637) (xy 150.570615 -227.145449) (xy 150.618221 -227.174503) (xy 150.661089 -227.210178)
			(xy 150.698306 -227.251715) (xy 150.729079 -227.298228) (xy 150.752751 -227.348725) (xy 150.768819 -227.402132)
			(xy 150.776939 -227.457308) (xy 150.777448 -227.485194) (xy 150.776939 -227.51308) (xy 150.768819 -227.568256)
			(xy 150.752751 -227.621663) (xy 150.729079 -227.67216) (xy 150.698306 -227.718673) (xy 150.661089 -227.76021)
			(xy 150.618221 -227.795885) (xy 150.570615 -227.824939) (xy 150.519286 -227.846751) (xy 150.465329 -227.860857)
			(xy 150.409892 -227.866957) (xy 150.354158 -227.86492) (xy 150.299315 -227.85479) (xy 150.246531 -227.836783)
			(xy 150.196931 -227.811282) (xy 150.151573 -227.778831) (xy 150.111424 -227.740122) (xy 150.077338 -227.695979)
			(xy 150.050042 -227.647344) (xy 150.030119 -227.595253) (xy 150.017993 -227.540816) (xy 150.013922 -227.485194)
			(xy 143.52727 -227.485194) (xy 143.520191 -227.491085) (xy 143.472585 -227.520139) (xy 143.421256 -227.541951)
			(xy 143.367299 -227.556057) (xy 143.311862 -227.562157) (xy 143.256128 -227.56012) (xy 143.201285 -227.54999)
			(xy 143.148501 -227.531983) (xy 143.098901 -227.506482) (xy 143.053543 -227.474031) (xy 143.013394 -227.435322)
			(xy 142.979308 -227.391179) (xy 142.952012 -227.342544) (xy 142.932089 -227.290453) (xy 142.919963 -227.236016)
			(xy 142.915892 -227.180394) (xy 110.176962 -227.180394) (xy 110.18622 -227.213182) (xy 110.193417 -227.265326)
			(xy 110.193836 -227.291646) (xy 110.193382 -227.317962) (xy 110.18616 -227.370095) (xy 110.171847 -227.420743)
			(xy 110.150712 -227.468945) (xy 110.123158 -227.513787) (xy 110.089705 -227.554419) (xy 110.070646 -227.57257)
			(xy 110.063263 -227.580107) (xy 110.054726 -227.599375) (xy 110.054136 -227.609908) (xy 110.054136 -227.684584)
			(xy 110.054649 -227.695136) (xy 110.063194 -227.714432) (xy 110.070646 -227.721922) (xy 110.089726 -227.740057)
			(xy 110.123206 -227.780676) (xy 110.150778 -227.825516) (xy 110.171916 -227.873724) (xy 110.18622 -227.924382)
			(xy 110.191826 -227.965) (xy 131.981192 -227.965) (xy 131.985263 -227.909378) (xy 131.997389 -227.854941)
			(xy 132.017312 -227.80285) (xy 132.044608 -227.754215) (xy 132.078694 -227.710072) (xy 132.118843 -227.671363)
			(xy 132.164201 -227.638912) (xy 132.213801 -227.613411) (xy 132.266585 -227.595404) (xy 132.321428 -227.585274)
			(xy 132.377162 -227.583237) (xy 132.432599 -227.589337) (xy 132.486556 -227.603443) (xy 132.537885 -227.625255)
			(xy 132.585491 -227.654309) (xy 132.628359 -227.689984) (xy 132.665576 -227.731521) (xy 132.696349 -227.778034)
			(xy 132.720021 -227.828531) (xy 132.736089 -227.881938) (xy 132.744209 -227.937114) (xy 132.744718 -227.965)
			(xy 132.744209 -227.992886) (xy 132.736089 -228.048062) (xy 132.720021 -228.101469) (xy 132.696349 -228.151966)
			(xy 132.677878 -228.179884) (xy 133.977632 -228.179884) (xy 133.981703 -228.124262) (xy 133.993829 -228.069825)
			(xy 134.013752 -228.017734) (xy 134.041048 -227.969099) (xy 134.075134 -227.924956) (xy 134.115283 -227.886247)
			(xy 134.160641 -227.853796) (xy 134.210241 -227.828295) (xy 134.263025 -227.810288) (xy 134.317868 -227.800158)
			(xy 134.373602 -227.798121) (xy 134.429039 -227.804221) (xy 134.482996 -227.818327) (xy 134.534325 -227.840139)
			(xy 134.581931 -227.869193) (xy 134.624799 -227.904868) (xy 134.662016 -227.946405) (xy 134.692789 -227.992918)
			(xy 134.716461 -228.043415) (xy 134.724201 -228.06914) (xy 135.036304 -228.06914) (xy 135.040375 -228.013518)
			(xy 135.052501 -227.959081) (xy 135.072424 -227.90699) (xy 135.09972 -227.858355) (xy 135.133806 -227.814212)
			(xy 135.173955 -227.775503) (xy 135.219313 -227.743052) (xy 135.268913 -227.717551) (xy 135.321697 -227.699544)
			(xy 135.37654 -227.689414) (xy 135.432274 -227.687377) (xy 135.487711 -227.693477) (xy 135.541668 -227.707583)
			(xy 135.592997 -227.729395) (xy 135.640603 -227.758449) (xy 135.683471 -227.794124) (xy 135.720688 -227.835661)
			(xy 135.751461 -227.882174) (xy 135.775133 -227.932671) (xy 135.791201 -227.986078) (xy 135.799321 -228.041254)
			(xy 135.79983 -228.06914) (xy 135.799677 -228.077522) (xy 136.086848 -228.077522) (xy 136.090919 -228.0219)
			(xy 136.103045 -227.967463) (xy 136.122968 -227.915372) (xy 136.150264 -227.866737) (xy 136.18435 -227.822594)
			(xy 136.224499 -227.783885) (xy 136.269857 -227.751434) (xy 136.319457 -227.725933) (xy 136.372241 -227.707926)
			(xy 136.427084 -227.697796) (xy 136.482818 -227.695759) (xy 136.538255 -227.701859) (xy 136.592212 -227.715965)
			(xy 136.643541 -227.737777) (xy 136.691147 -227.766831) (xy 136.734015 -227.802506) (xy 136.771232 -227.844043)
			(xy 136.802005 -227.890556) (xy 136.825677 -227.941053) (xy 136.82715 -227.94595) (xy 141.658338 -227.94595)
			(xy 141.662409 -227.890328) (xy 141.674535 -227.835891) (xy 141.694458 -227.7838) (xy 141.721754 -227.735165)
			(xy 141.75584 -227.691022) (xy 141.795989 -227.652313) (xy 141.841347 -227.619862) (xy 141.890947 -227.594361)
			(xy 141.943731 -227.576354) (xy 141.998574 -227.566224) (xy 142.054308 -227.564187) (xy 142.109745 -227.570287)
			(xy 142.163702 -227.584393) (xy 142.215031 -227.606205) (xy 142.262637 -227.635259) (xy 142.305505 -227.670934)
			(xy 142.342722 -227.712471) (xy 142.373495 -227.758984) (xy 142.397167 -227.809481) (xy 142.413235 -227.862888)
			(xy 142.421355 -227.918064) (xy 142.421864 -227.94595) (xy 142.421355 -227.973836) (xy 142.413235 -228.029012)
			(xy 142.397167 -228.082419) (xy 142.373495 -228.132916) (xy 142.342722 -228.179429) (xy 142.305505 -228.220966)
			(xy 142.262637 -228.256641) (xy 142.215031 -228.285695) (xy 142.163702 -228.307507) (xy 142.109745 -228.321613)
			(xy 142.054308 -228.327713) (xy 141.998574 -228.325676) (xy 141.943731 -228.315546) (xy 141.890947 -228.297539)
			(xy 141.841347 -228.272038) (xy 141.795989 -228.239587) (xy 141.75584 -228.200878) (xy 141.721754 -228.156735)
			(xy 141.694458 -228.1081) (xy 141.674535 -228.056009) (xy 141.662409 -228.001572) (xy 141.658338 -227.94595)
			(xy 136.82715 -227.94595) (xy 136.841745 -227.99446) (xy 136.849865 -228.049636) (xy 136.850374 -228.077522)
			(xy 136.849865 -228.105408) (xy 136.841745 -228.160584) (xy 136.825677 -228.213991) (xy 136.802005 -228.264488)
			(xy 136.771232 -228.311001) (xy 136.734015 -228.352538) (xy 136.691147 -228.388213) (xy 136.668753 -228.40188)
			(xy 137.995404 -228.40188) (xy 137.999475 -228.346258) (xy 138.011601 -228.291821) (xy 138.031524 -228.23973)
			(xy 138.05882 -228.191095) (xy 138.092906 -228.146952) (xy 138.133055 -228.108243) (xy 138.178413 -228.075792)
			(xy 138.228013 -228.050291) (xy 138.280797 -228.032284) (xy 138.33564 -228.022154) (xy 138.391374 -228.020117)
			(xy 138.446811 -228.026217) (xy 138.500768 -228.040323) (xy 138.552097 -228.062135) (xy 138.599703 -228.091189)
			(xy 138.642571 -228.126864) (xy 138.679788 -228.168401) (xy 138.710561 -228.214914) (xy 138.734233 -228.265411)
			(xy 138.750301 -228.318818) (xy 138.758421 -228.373994) (xy 138.75893 -228.40188) (xy 138.758421 -228.429766)
			(xy 138.750301 -228.484942) (xy 138.734233 -228.538349) (xy 138.710561 -228.588846) (xy 138.679788 -228.635359)
			(xy 138.642571 -228.676896) (xy 138.599703 -228.712571) (xy 138.552097 -228.741625) (xy 138.500768 -228.763437)
			(xy 138.446811 -228.777543) (xy 138.391374 -228.783643) (xy 138.33564 -228.781606) (xy 138.280797 -228.771476)
			(xy 138.228013 -228.753469) (xy 138.178413 -228.727968) (xy 138.133055 -228.695517) (xy 138.092906 -228.656808)
			(xy 138.05882 -228.612665) (xy 138.031524 -228.56403) (xy 138.011601 -228.511939) (xy 137.999475 -228.457502)
			(xy 137.995404 -228.40188) (xy 136.668753 -228.40188) (xy 136.643541 -228.417267) (xy 136.592212 -228.439079)
			(xy 136.538255 -228.453185) (xy 136.482818 -228.459285) (xy 136.427084 -228.457248) (xy 136.372241 -228.447118)
			(xy 136.319457 -228.429111) (xy 136.269857 -228.40361) (xy 136.224499 -228.371159) (xy 136.18435 -228.33245)
			(xy 136.150264 -228.288307) (xy 136.122968 -228.239672) (xy 136.103045 -228.187581) (xy 136.090919 -228.133144)
			(xy 136.086848 -228.077522) (xy 135.799677 -228.077522) (xy 135.799321 -228.097026) (xy 135.791201 -228.152202)
			(xy 135.775133 -228.205609) (xy 135.751461 -228.256106) (xy 135.720688 -228.302619) (xy 135.683471 -228.344156)
			(xy 135.640603 -228.379831) (xy 135.592997 -228.408885) (xy 135.541668 -228.430697) (xy 135.487711 -228.444803)
			(xy 135.432274 -228.450903) (xy 135.37654 -228.448866) (xy 135.321697 -228.438736) (xy 135.268913 -228.420729)
			(xy 135.219313 -228.395228) (xy 135.173955 -228.362777) (xy 135.133806 -228.324068) (xy 135.09972 -228.279925)
			(xy 135.072424 -228.23129) (xy 135.052501 -228.179199) (xy 135.040375 -228.124762) (xy 135.036304 -228.06914)
			(xy 134.724201 -228.06914) (xy 134.732529 -228.096822) (xy 134.740649 -228.151998) (xy 134.741158 -228.179884)
			(xy 134.740649 -228.20777) (xy 134.732529 -228.262946) (xy 134.716461 -228.316353) (xy 134.692789 -228.36685)
			(xy 134.662016 -228.413363) (xy 134.624799 -228.4549) (xy 134.581931 -228.490575) (xy 134.534325 -228.519629)
			(xy 134.482996 -228.541441) (xy 134.429039 -228.555547) (xy 134.373602 -228.561647) (xy 134.317868 -228.55961)
			(xy 134.263025 -228.54948) (xy 134.210241 -228.531473) (xy 134.160641 -228.505972) (xy 134.115283 -228.473521)
			(xy 134.075134 -228.434812) (xy 134.041048 -228.390669) (xy 134.013752 -228.342034) (xy 133.993829 -228.289943)
			(xy 133.981703 -228.235506) (xy 133.977632 -228.179884) (xy 132.677878 -228.179884) (xy 132.665576 -228.198479)
			(xy 132.628359 -228.240016) (xy 132.585491 -228.275691) (xy 132.537885 -228.304745) (xy 132.486556 -228.326557)
			(xy 132.432599 -228.340663) (xy 132.377162 -228.346763) (xy 132.321428 -228.344726) (xy 132.266585 -228.334596)
			(xy 132.213801 -228.316589) (xy 132.164201 -228.291088) (xy 132.118843 -228.258637) (xy 132.078694 -228.219928)
			(xy 132.044608 -228.175785) (xy 132.017312 -228.12715) (xy 131.997389 -228.075059) (xy 131.985263 -228.020622)
			(xy 131.981192 -227.965) (xy 110.191826 -227.965) (xy 110.193417 -227.976526) (xy 110.193836 -228.002846)
			(xy 110.193382 -228.029162) (xy 110.18616 -228.081295) (xy 110.171847 -228.131943) (xy 110.150712 -228.180145)
			(xy 110.123158 -228.224987) (xy 110.089705 -228.265619) (xy 110.070646 -228.28377) (xy 110.063263 -228.291307)
			(xy 110.054726 -228.310575) (xy 110.054136 -228.321108) (xy 110.054136 -228.395784) (xy 110.054649 -228.406336)
			(xy 110.063194 -228.425632) (xy 110.070646 -228.433122) (xy 110.089711 -228.451241) (xy 110.123169 -228.491824)
			(xy 110.150728 -228.536622) (xy 110.171866 -228.584784) (xy 110.186181 -228.635395) (xy 110.19166 -228.67493)
			(xy 129.074924 -228.67493) (xy 129.078995 -228.619308) (xy 129.091121 -228.564871) (xy 129.111044 -228.51278)
			(xy 129.13834 -228.464145) (xy 129.172426 -228.420002) (xy 129.212575 -228.381293) (xy 129.257933 -228.348842)
			(xy 129.307533 -228.323341) (xy 129.360317 -228.305334) (xy 129.41516 -228.295204) (xy 129.470894 -228.293167)
			(xy 129.526331 -228.299267) (xy 129.580288 -228.313373) (xy 129.631617 -228.335185) (xy 129.679223 -228.364239)
			(xy 129.722091 -228.399914) (xy 129.759308 -228.441451) (xy 129.790081 -228.487964) (xy 129.813753 -228.538461)
			(xy 129.829821 -228.591868) (xy 129.837941 -228.647044) (xy 129.83845 -228.67493) (xy 129.837941 -228.702816)
			(xy 129.829821 -228.757992) (xy 129.813753 -228.811399) (xy 129.790081 -228.861896) (xy 129.759308 -228.908409)
			(xy 129.722091 -228.949946) (xy 129.684776 -228.981) (xy 132.09727 -228.981) (xy 132.101341 -228.925378)
			(xy 132.113467 -228.870941) (xy 132.13339 -228.81885) (xy 132.160686 -228.770215) (xy 132.194772 -228.726072)
			(xy 132.234921 -228.687363) (xy 132.280279 -228.654912) (xy 132.329879 -228.629411) (xy 132.382663 -228.611404)
			(xy 132.437506 -228.601274) (xy 132.49324 -228.599237) (xy 132.548677 -228.605337) (xy 132.602634 -228.619443)
			(xy 132.653963 -228.641255) (xy 132.701569 -228.670309) (xy 132.744437 -228.705984) (xy 132.781654 -228.747521)
			(xy 132.812427 -228.794034) (xy 132.836099 -228.844531) (xy 132.840629 -228.859588) (xy 142.064738 -228.859588)
			(xy 142.068809 -228.803966) (xy 142.080935 -228.749529) (xy 142.100858 -228.697438) (xy 142.128154 -228.648803)
			(xy 142.16224 -228.60466) (xy 142.202389 -228.565951) (xy 142.247747 -228.5335) (xy 142.297347 -228.507999)
			(xy 142.350131 -228.489992) (xy 142.404974 -228.479862) (xy 142.460708 -228.477825) (xy 142.516145 -228.483925)
			(xy 142.570102 -228.498031) (xy 142.621431 -228.519843) (xy 142.669037 -228.548897) (xy 142.711905 -228.584572)
			(xy 142.749122 -228.626109) (xy 142.779895 -228.672622) (xy 142.803567 -228.723119) (xy 142.819635 -228.776526)
			(xy 142.827755 -228.831702) (xy 142.828264 -228.859588) (xy 142.827755 -228.887474) (xy 142.819635 -228.94265)
			(xy 142.803567 -228.996057) (xy 142.779895 -229.046554) (xy 142.749122 -229.093067) (xy 142.711905 -229.134604)
			(xy 142.669037 -229.170279) (xy 142.621431 -229.199333) (xy 142.570102 -229.221145) (xy 142.516145 -229.235251)
			(xy 142.460708 -229.241351) (xy 142.404974 -229.239314) (xy 142.350131 -229.229184) (xy 142.297347 -229.211177)
			(xy 142.247747 -229.185676) (xy 142.202389 -229.153225) (xy 142.16224 -229.114516) (xy 142.128154 -229.070373)
			(xy 142.100858 -229.021738) (xy 142.080935 -228.969647) (xy 142.068809 -228.91521) (xy 142.064738 -228.859588)
			(xy 132.840629 -228.859588) (xy 132.852167 -228.897938) (xy 132.860287 -228.953114) (xy 132.860796 -228.981)
			(xy 132.860287 -229.008886) (xy 132.852167 -229.064062) (xy 132.836099 -229.117469) (xy 132.812427 -229.167966)
			(xy 132.781654 -229.214479) (xy 132.744437 -229.256016) (xy 132.701569 -229.291691) (xy 132.653963 -229.320745)
			(xy 132.602634 -229.342557) (xy 132.548677 -229.356663) (xy 132.49324 -229.362763) (xy 132.437506 -229.360726)
			(xy 132.382663 -229.350596) (xy 132.329879 -229.332589) (xy 132.280279 -229.307088) (xy 132.234921 -229.274637)
			(xy 132.194772 -229.235928) (xy 132.160686 -229.191785) (xy 132.13339 -229.14315) (xy 132.113467 -229.091059)
			(xy 132.101341 -229.036622) (xy 132.09727 -228.981) (xy 129.684776 -228.981) (xy 129.679223 -228.985621)
			(xy 129.631617 -229.014675) (xy 129.580288 -229.036487) (xy 129.526331 -229.050593) (xy 129.470894 -229.056693)
			(xy 129.41516 -229.054656) (xy 129.360317 -229.044526) (xy 129.307533 -229.026519) (xy 129.257933 -229.001018)
			(xy 129.212575 -228.968567) (xy 129.172426 -228.929858) (xy 129.13834 -228.885715) (xy 129.111044 -228.83708)
			(xy 129.091121 -228.784989) (xy 129.078995 -228.730552) (xy 129.074924 -228.67493) (xy 110.19166 -228.67493)
			(xy 110.193401 -228.687494) (xy 110.193836 -228.713792) (xy 110.193836 -228.714046) (xy 110.19335 -228.741297)
			(xy 110.185594 -228.795245) (xy 110.170239 -228.84754) (xy 110.147597 -228.897117) (xy 110.118131 -228.942967)
			(xy 110.08244 -228.984158) (xy 110.041249 -229.019849) (xy 109.995399 -229.049315) (xy 109.945822 -229.071957)
			(xy 109.893527 -229.087312) (xy 109.839579 -229.095068) (xy 109.785077 -229.095068) (xy 109.731129 -229.087312)
			(xy 109.678834 -229.071957) (xy 109.629257 -229.049315) (xy 109.583407 -229.019849) (xy 109.542216 -228.984158)
			(xy 109.506525 -228.942967) (xy 109.477059 -228.897117) (xy 109.454417 -228.84754) (xy 109.439062 -228.795245)
			(xy 109.431306 -228.741297) (xy 109.43082 -228.714046) (xy 91.337384 -228.714046) (xy 91.337384 -229.454456)
			(xy 146.747736 -229.454456) (xy 146.751807 -229.398834) (xy 146.763933 -229.344397) (xy 146.783856 -229.292306)
			(xy 146.811152 -229.243671) (xy 146.845238 -229.199528) (xy 146.885387 -229.160819) (xy 146.930745 -229.128368)
			(xy 146.980345 -229.102867) (xy 147.033129 -229.08486) (xy 147.087972 -229.07473) (xy 147.143706 -229.072693)
			(xy 147.199143 -229.078793) (xy 147.2531 -229.092899) (xy 147.304429 -229.114711) (xy 147.352035 -229.143765)
			(xy 147.394903 -229.17944) (xy 147.43212 -229.220977) (xy 147.462893 -229.26749) (xy 147.486565 -229.317987)
			(xy 147.502633 -229.371394) (xy 147.510753 -229.42657) (xy 147.510937 -229.436676) (xy 147.716492 -229.436676)
			(xy 147.720563 -229.381054) (xy 147.732689 -229.326617) (xy 147.752612 -229.274526) (xy 147.779908 -229.225891)
			(xy 147.813994 -229.181748) (xy 147.854143 -229.143039) (xy 147.899501 -229.110588) (xy 147.949101 -229.085087)
			(xy 148.001885 -229.06708) (xy 148.056728 -229.05695) (xy 148.112462 -229.054913) (xy 148.167899 -229.061013)
			(xy 148.221856 -229.075119) (xy 148.273185 -229.096931) (xy 148.320791 -229.125985) (xy 148.363659 -229.16166)
			(xy 148.400876 -229.203197) (xy 148.431649 -229.24971) (xy 148.455321 -229.300207) (xy 148.471389 -229.353614)
			(xy 148.479509 -229.40879) (xy 148.480018 -229.436676) (xy 148.479509 -229.464562) (xy 148.471389 -229.519738)
			(xy 148.455321 -229.573145) (xy 148.431649 -229.623642) (xy 148.400876 -229.670155) (xy 148.363659 -229.711692)
			(xy 148.320791 -229.747367) (xy 148.273185 -229.776421) (xy 148.221856 -229.798233) (xy 148.167899 -229.812339)
			(xy 148.112462 -229.818439) (xy 148.056728 -229.816402) (xy 148.001885 -229.806272) (xy 147.949101 -229.788265)
			(xy 147.899501 -229.762764) (xy 147.854143 -229.730313) (xy 147.813994 -229.691604) (xy 147.779908 -229.647461)
			(xy 147.752612 -229.598826) (xy 147.732689 -229.546735) (xy 147.720563 -229.492298) (xy 147.716492 -229.436676)
			(xy 147.510937 -229.436676) (xy 147.511262 -229.454456) (xy 147.510753 -229.482342) (xy 147.502633 -229.537518)
			(xy 147.486565 -229.590925) (xy 147.462893 -229.641422) (xy 147.43212 -229.687935) (xy 147.394903 -229.729472)
			(xy 147.352035 -229.765147) (xy 147.304429 -229.794201) (xy 147.2531 -229.816013) (xy 147.199143 -229.830119)
			(xy 147.143706 -229.836219) (xy 147.087972 -229.834182) (xy 147.033129 -229.824052) (xy 146.980345 -229.806045)
			(xy 146.930745 -229.780544) (xy 146.885387 -229.748093) (xy 146.845238 -229.709384) (xy 146.811152 -229.665241)
			(xy 146.783856 -229.616606) (xy 146.763933 -229.564515) (xy 146.751807 -229.510078) (xy 146.747736 -229.454456)
			(xy 91.337384 -229.454456) (xy 91.337384 -229.94493) (xy 128.9083 -229.94493) (xy 128.912371 -229.889308)
			(xy 128.924497 -229.834871) (xy 128.94442 -229.78278) (xy 128.971716 -229.734145) (xy 129.005802 -229.690002)
			(xy 129.045951 -229.651293) (xy 129.091309 -229.618842) (xy 129.140909 -229.593341) (xy 129.193693 -229.575334)
			(xy 129.248536 -229.565204) (xy 129.30427 -229.563167) (xy 129.359707 -229.569267) (xy 129.413664 -229.583373)
			(xy 129.464993 -229.605185) (xy 129.512599 -229.634239) (xy 129.555467 -229.669914) (xy 129.592684 -229.711451)
			(xy 129.623457 -229.757964) (xy 129.647129 -229.808461) (xy 129.663197 -229.861868) (xy 129.671317 -229.917044)
			(xy 129.671826 -229.94493) (xy 138.89304 -229.94493) (xy 138.897111 -229.889308) (xy 138.909237 -229.834871)
			(xy 138.92916 -229.78278) (xy 138.956456 -229.734145) (xy 138.990542 -229.690002) (xy 139.030691 -229.651293)
			(xy 139.076049 -229.618842) (xy 139.125649 -229.593341) (xy 139.178433 -229.575334) (xy 139.233276 -229.565204)
			(xy 139.28901 -229.563167) (xy 139.344447 -229.569267) (xy 139.398404 -229.583373) (xy 139.449733 -229.605185)
			(xy 139.497339 -229.634239) (xy 139.540207 -229.669914) (xy 139.577424 -229.711451) (xy 139.608197 -229.757964)
			(xy 139.631869 -229.808461) (xy 139.647937 -229.861868) (xy 139.656057 -229.917044) (xy 139.656566 -229.94493)
			(xy 139.656057 -229.972816) (xy 139.647937 -230.027992) (xy 139.631869 -230.081399) (xy 139.608197 -230.131896)
			(xy 139.577424 -230.178409) (xy 139.540207 -230.219946) (xy 139.497339 -230.255621) (xy 139.449733 -230.284675)
			(xy 139.398404 -230.306487) (xy 139.344447 -230.320593) (xy 139.28901 -230.326693) (xy 139.233276 -230.324656)
			(xy 139.178433 -230.314526) (xy 139.125649 -230.296519) (xy 139.076049 -230.271018) (xy 139.030691 -230.238567)
			(xy 138.990542 -230.199858) (xy 138.956456 -230.155715) (xy 138.92916 -230.10708) (xy 138.909237 -230.054989)
			(xy 138.897111 -230.000552) (xy 138.89304 -229.94493) (xy 129.671826 -229.94493) (xy 129.671317 -229.972816)
			(xy 129.663197 -230.027992) (xy 129.647129 -230.081399) (xy 129.623457 -230.131896) (xy 129.592684 -230.178409)
			(xy 129.555467 -230.219946) (xy 129.512599 -230.255621) (xy 129.464993 -230.284675) (xy 129.413664 -230.306487)
			(xy 129.359707 -230.320593) (xy 129.30427 -230.326693) (xy 129.248536 -230.324656) (xy 129.193693 -230.314526)
			(xy 129.140909 -230.296519) (xy 129.091309 -230.271018) (xy 129.045951 -230.238567) (xy 129.005802 -230.199858)
			(xy 128.971716 -230.155715) (xy 128.94442 -230.10708) (xy 128.924497 -230.054989) (xy 128.912371 -230.000552)
			(xy 128.9083 -229.94493) (xy 91.337384 -229.94493) (xy 91.337384 -231.506522) (xy 129.418332 -231.506522)
			(xy 129.422403 -231.4509) (xy 129.434529 -231.396463) (xy 129.454452 -231.344372) (xy 129.481748 -231.295737)
			(xy 129.515834 -231.251594) (xy 129.555983 -231.212885) (xy 129.601341 -231.180434) (xy 129.650941 -231.154933)
			(xy 129.703725 -231.136926) (xy 129.758568 -231.126796) (xy 129.814302 -231.124759) (xy 129.869739 -231.130859)
			(xy 129.923696 -231.144965) (xy 129.975025 -231.166777) (xy 130.022631 -231.195831) (xy 130.032151 -231.203754)
			(xy 130.91109 -231.203754) (xy 130.915161 -231.148132) (xy 130.927287 -231.093695) (xy 130.94721 -231.041604)
			(xy 130.974506 -230.992969) (xy 131.008592 -230.948826) (xy 131.048741 -230.910117) (xy 131.094099 -230.877666)
			(xy 131.143699 -230.852165) (xy 131.196483 -230.834158) (xy 131.251326 -230.824028) (xy 131.30706 -230.821991)
			(xy 131.362497 -230.828091) (xy 131.416454 -230.842197) (xy 131.467783 -230.864009) (xy 131.514221 -230.89235)
			(xy 138.084558 -230.89235) (xy 138.088629 -230.836728) (xy 138.100755 -230.782291) (xy 138.120678 -230.7302)
			(xy 138.147974 -230.681565) (xy 138.18206 -230.637422) (xy 138.222209 -230.598713) (xy 138.267567 -230.566262)
			(xy 138.317167 -230.540761) (xy 138.369951 -230.522754) (xy 138.424794 -230.512624) (xy 138.480528 -230.510587)
			(xy 138.535965 -230.516687) (xy 138.589922 -230.530793) (xy 138.641251 -230.552605) (xy 138.688857 -230.581659)
			(xy 138.731725 -230.617334) (xy 138.768942 -230.658871) (xy 138.799715 -230.705384) (xy 138.823387 -230.755881)
			(xy 138.839455 -230.809288) (xy 138.847575 -230.864464) (xy 138.847778 -230.875586) (xy 147.625306 -230.875586)
			(xy 147.629377 -230.819964) (xy 147.641503 -230.765527) (xy 147.661426 -230.713436) (xy 147.688722 -230.664801)
			(xy 147.722808 -230.620658) (xy 147.762957 -230.581949) (xy 147.808315 -230.549498) (xy 147.857915 -230.523997)
			(xy 147.910699 -230.50599) (xy 147.965542 -230.49586) (xy 148.021276 -230.493823) (xy 148.076713 -230.499923)
			(xy 148.13067 -230.514029) (xy 148.181999 -230.535841) (xy 148.229605 -230.564895) (xy 148.272473 -230.60057)
			(xy 148.30969 -230.642107) (xy 148.340463 -230.68862) (xy 148.364135 -230.739117) (xy 148.380203 -230.792524)
			(xy 148.388323 -230.8477) (xy 148.388721 -230.86949) (xy 148.496526 -230.86949) (xy 148.500597 -230.813868)
			(xy 148.512723 -230.759431) (xy 148.532646 -230.70734) (xy 148.559942 -230.658705) (xy 148.594028 -230.614562)
			(xy 148.634177 -230.575853) (xy 148.679535 -230.543402) (xy 148.729135 -230.517901) (xy 148.781919 -230.499894)
			(xy 148.836762 -230.489764) (xy 148.892496 -230.487727) (xy 148.947933 -230.493827) (xy 149.00189 -230.507933)
			(xy 149.053219 -230.529745) (xy 149.100825 -230.558799) (xy 149.143693 -230.594474) (xy 149.18091 -230.636011)
			(xy 149.211683 -230.682524) (xy 149.235355 -230.733021) (xy 149.251423 -230.786428) (xy 149.259543 -230.841604)
			(xy 149.260052 -230.86949) (xy 149.259543 -230.897376) (xy 149.251423 -230.952552) (xy 149.235355 -231.005959)
			(xy 149.211683 -231.056456) (xy 149.18091 -231.102969) (xy 149.143693 -231.144506) (xy 149.100825 -231.180181)
			(xy 149.053219 -231.209235) (xy 149.00189 -231.231047) (xy 148.947933 -231.245153) (xy 148.892496 -231.251253)
			(xy 148.836762 -231.249216) (xy 148.781919 -231.239086) (xy 148.729135 -231.221079) (xy 148.679535 -231.195578)
			(xy 148.634177 -231.163127) (xy 148.594028 -231.124418) (xy 148.559942 -231.080275) (xy 148.532646 -231.03164)
			(xy 148.512723 -230.979549) (xy 148.500597 -230.925112) (xy 148.496526 -230.86949) (xy 148.388721 -230.86949)
			(xy 148.388832 -230.875586) (xy 148.388323 -230.903472) (xy 148.380203 -230.958648) (xy 148.364135 -231.012055)
			(xy 148.340463 -231.062552) (xy 148.30969 -231.109065) (xy 148.272473 -231.150602) (xy 148.229605 -231.186277)
			(xy 148.181999 -231.215331) (xy 148.13067 -231.237143) (xy 148.076713 -231.251249) (xy 148.021276 -231.257349)
			(xy 147.965542 -231.255312) (xy 147.910699 -231.245182) (xy 147.857915 -231.227175) (xy 147.808315 -231.201674)
			(xy 147.762957 -231.169223) (xy 147.722808 -231.130514) (xy 147.688722 -231.086371) (xy 147.661426 -231.037736)
			(xy 147.641503 -230.985645) (xy 147.629377 -230.931208) (xy 147.625306 -230.875586) (xy 138.847778 -230.875586)
			(xy 138.848084 -230.89235) (xy 138.847575 -230.920236) (xy 138.839455 -230.975412) (xy 138.823387 -231.028819)
			(xy 138.799715 -231.079316) (xy 138.768942 -231.125829) (xy 138.731725 -231.167366) (xy 138.688857 -231.203041)
			(xy 138.641251 -231.232095) (xy 138.589922 -231.253907) (xy 138.535965 -231.268013) (xy 138.480528 -231.274113)
			(xy 138.424794 -231.272076) (xy 138.369951 -231.261946) (xy 138.317167 -231.243939) (xy 138.267567 -231.218438)
			(xy 138.222209 -231.185987) (xy 138.18206 -231.147278) (xy 138.147974 -231.103135) (xy 138.120678 -231.0545)
			(xy 138.100755 -231.002409) (xy 138.088629 -230.947972) (xy 138.084558 -230.89235) (xy 131.514221 -230.89235)
			(xy 131.515389 -230.893063) (xy 131.558257 -230.928738) (xy 131.595474 -230.970275) (xy 131.626247 -231.016788)
			(xy 131.649919 -231.067285) (xy 131.665987 -231.120692) (xy 131.674107 -231.175868) (xy 131.674616 -231.203754)
			(xy 131.674107 -231.23164) (xy 131.665987 -231.286816) (xy 131.649919 -231.340223) (xy 131.626247 -231.39072)
			(xy 131.595474 -231.437233) (xy 131.558257 -231.47877) (xy 131.515389 -231.514445) (xy 131.467783 -231.543499)
			(xy 131.416454 -231.565311) (xy 131.362497 -231.579417) (xy 131.30706 -231.585517) (xy 131.251326 -231.58348)
			(xy 131.196483 -231.57335) (xy 131.143699 -231.555343) (xy 131.094099 -231.529842) (xy 131.048741 -231.497391)
			(xy 131.008592 -231.458682) (xy 130.974506 -231.414539) (xy 130.94721 -231.365904) (xy 130.927287 -231.313813)
			(xy 130.915161 -231.259376) (xy 130.91109 -231.203754) (xy 130.032151 -231.203754) (xy 130.065499 -231.231506)
			(xy 130.102716 -231.273043) (xy 130.133489 -231.319556) (xy 130.157161 -231.370053) (xy 130.173229 -231.42346)
			(xy 130.181349 -231.478636) (xy 130.181858 -231.506522) (xy 130.181349 -231.534408) (xy 130.173229 -231.589584)
			(xy 130.157161 -231.642991) (xy 130.133489 -231.693488) (xy 130.102716 -231.740001) (xy 130.065499 -231.781538)
			(xy 130.022631 -231.817213) (xy 129.975025 -231.846267) (xy 129.923696 -231.868079) (xy 129.869739 -231.882185)
			(xy 129.814302 -231.888285) (xy 129.758568 -231.886248) (xy 129.703725 -231.876118) (xy 129.650941 -231.858111)
			(xy 129.601341 -231.83261) (xy 129.555983 -231.800159) (xy 129.515834 -231.76145) (xy 129.481748 -231.717307)
			(xy 129.454452 -231.668672) (xy 129.434529 -231.616581) (xy 129.422403 -231.562144) (xy 129.418332 -231.506522)
			(xy 91.337384 -231.506522) (xy 91.337384 -232.082564) (xy 133.009326 -232.082564) (xy 133.017081 -232.028608)
			(xy 133.032435 -231.976305) (xy 133.055078 -231.92672) (xy 133.084546 -231.880861) (xy 133.120241 -231.839664)
			(xy 133.161435 -231.803966) (xy 133.207291 -231.774493) (xy 133.256874 -231.751847) (xy 133.309176 -231.736488)
			(xy 133.363131 -231.728728) (xy 133.390386 -231.728264) (xy 133.408017 -231.7285) (xy 133.443125 -231.731806)
			(xy 133.46049 -231.734868) (xy 133.475012 -231.737124) (xy 133.504236 -231.734123) (xy 133.531396 -231.722925)
			(xy 133.554245 -231.704459) (xy 133.57089 -231.680251) (xy 133.579954 -231.652307) (xy 133.580688 -231.622938)
			(xy 133.57733 -231.60863) (xy 133.57129 -231.584505) (xy 133.564793 -231.535198) (xy 133.564376 -231.510332)
			(xy 133.564821 -231.483076) (xy 133.572574 -231.429119) (xy 133.587928 -231.376814) (xy 133.610569 -231.327226)
			(xy 133.640038 -231.281366) (xy 133.675733 -231.240166) (xy 133.716928 -231.204466) (xy 133.762784 -231.174992)
			(xy 133.812369 -231.152345) (xy 133.864672 -231.136984) (xy 133.918628 -231.129224) (xy 133.97314 -231.129222)
			(xy 134.027097 -231.136978) (xy 134.079401 -231.152334) (xy 134.128988 -231.174977) (xy 134.174847 -231.204447)
			(xy 134.216045 -231.240144) (xy 134.251743 -231.28134) (xy 134.281215 -231.327198) (xy 134.303861 -231.376784)
			(xy 134.319219 -231.429087) (xy 134.326977 -231.483044) (xy 134.326977 -231.537556) (xy 134.319219 -231.591513)
			(xy 134.303861 -231.643816) (xy 134.281215 -231.693402) (xy 134.251743 -231.73926) (xy 134.216045 -231.780456)
			(xy 134.174847 -231.816153) (xy 134.128988 -231.845623) (xy 134.079401 -231.868266) (xy 134.027097 -231.883622)
			(xy 133.97314 -231.891378) (xy 133.945884 -231.89184) (xy 133.928253 -231.891608) (xy 133.893145 -231.8883)
			(xy 133.87578 -231.885236) (xy 133.861248 -231.883045) (xy 133.832029 -231.88603) (xy 133.80487 -231.897213)
			(xy 133.782021 -231.915669) (xy 133.765375 -231.939869) (xy 133.762004 -231.95026) (xy 134.511286 -231.95026)
			(xy 134.515357 -231.894638) (xy 134.527483 -231.840201) (xy 134.547406 -231.78811) (xy 134.574702 -231.739475)
			(xy 134.608788 -231.695332) (xy 134.648937 -231.656623) (xy 134.694295 -231.624172) (xy 134.743895 -231.598671)
			(xy 134.796679 -231.580664) (xy 134.851522 -231.570534) (xy 134.907256 -231.568497) (xy 134.962693 -231.574597)
			(xy 135.01665 -231.588703) (xy 135.067979 -231.610515) (xy 135.115585 -231.639569) (xy 135.158453 -231.675244)
			(xy 135.19567 -231.716781) (xy 135.226443 -231.763294) (xy 135.250115 -231.813791) (xy 135.266183 -231.867198)
			(xy 135.274303 -231.922374) (xy 135.274812 -231.95026) (xy 135.274303 -231.978146) (xy 135.27108 -232.000044)
			(xy 151.288748 -232.000044) (xy 151.292819 -231.944422) (xy 151.304945 -231.889985) (xy 151.324868 -231.837894)
			(xy 151.352164 -231.789259) (xy 151.38625 -231.745116) (xy 151.426399 -231.706407) (xy 151.471757 -231.673956)
			(xy 151.521357 -231.648455) (xy 151.574141 -231.630448) (xy 151.628984 -231.620318) (xy 151.684718 -231.618281)
			(xy 151.740155 -231.624381) (xy 151.794112 -231.638487) (xy 151.845441 -231.660299) (xy 151.893047 -231.689353)
			(xy 151.935915 -231.725028) (xy 151.973132 -231.766565) (xy 152.003905 -231.813078) (xy 152.027577 -231.863575)
			(xy 152.043645 -231.916982) (xy 152.051765 -231.972158) (xy 152.052274 -232.000044) (xy 152.051765 -232.02793)
			(xy 152.043645 -232.083106) (xy 152.027577 -232.136513) (xy 152.003905 -232.18701) (xy 151.973132 -232.233523)
			(xy 151.935915 -232.27506) (xy 151.893047 -232.310735) (xy 151.845441 -232.339789) (xy 151.794112 -232.361601)
			(xy 151.740155 -232.375707) (xy 151.684718 -232.381807) (xy 151.628984 -232.37977) (xy 151.574141 -232.36964)
			(xy 151.521357 -232.351633) (xy 151.471757 -232.326132) (xy 151.426399 -232.293681) (xy 151.38625 -232.254972)
			(xy 151.352164 -232.210829) (xy 151.324868 -232.162194) (xy 151.304945 -232.110103) (xy 151.292819 -232.055666)
			(xy 151.288748 -232.000044) (xy 135.27108 -232.000044) (xy 135.266183 -232.033322) (xy 135.250115 -232.086729)
			(xy 135.226443 -232.137226) (xy 135.19567 -232.183739) (xy 135.158453 -232.225276) (xy 135.115585 -232.260951)
			(xy 135.067979 -232.290005) (xy 135.01665 -232.311817) (xy 134.962693 -232.325923) (xy 134.907256 -232.332023)
			(xy 134.851522 -232.329986) (xy 134.796679 -232.319856) (xy 134.743895 -232.301849) (xy 134.694295 -232.276348)
			(xy 134.648937 -232.243897) (xy 134.608788 -232.205188) (xy 134.574702 -232.161045) (xy 134.547406 -232.11241)
			(xy 134.527483 -232.060319) (xy 134.515357 -232.005882) (xy 134.511286 -231.95026) (xy 133.762004 -231.95026)
			(xy 133.756312 -231.967807) (xy 133.755581 -231.997169) (xy 133.75894 -232.011474) (xy 133.764982 -232.035599)
			(xy 133.771477 -232.084906) (xy 133.771894 -232.109772) (xy 133.771475 -232.137027) (xy 133.763721 -232.190983)
			(xy 133.748368 -232.243286) (xy 133.725727 -232.292872) (xy 133.69626 -232.338731) (xy 133.660566 -232.379929)
			(xy 133.619372 -232.415629) (xy 133.573517 -232.445102) (xy 133.523934 -232.46775) (xy 133.471633 -232.48311)
			(xy 133.417678 -232.490871) (xy 133.363168 -232.490875) (xy 133.309212 -232.48312) (xy 133.256909 -232.467766)
			(xy 133.207324 -232.445125) (xy 133.161465 -232.415657) (xy 133.120267 -232.379963) (xy 133.084568 -232.338768)
			(xy 133.055095 -232.292913) (xy 133.032449 -232.24333) (xy 133.017089 -232.191029) (xy 133.009328 -232.137074)
			(xy 133.009326 -232.082564) (xy 91.337384 -232.082564) (xy 91.337384 -234.080558) (xy 119.279922 -234.080558)
			(xy 119.283993 -234.024936) (xy 119.296119 -233.970499) (xy 119.316042 -233.918408) (xy 119.343338 -233.869773)
			(xy 119.377424 -233.82563) (xy 119.417573 -233.786921) (xy 119.462931 -233.75447) (xy 119.512531 -233.728969)
			(xy 119.565315 -233.710962) (xy 119.620158 -233.700832) (xy 119.675892 -233.698795) (xy 119.731329 -233.704895)
			(xy 119.785286 -233.719001) (xy 119.836615 -233.740813) (xy 119.884221 -233.769867) (xy 119.927089 -233.805542)
			(xy 119.964306 -233.847079) (xy 119.995079 -233.893592) (xy 120.018751 -233.944089) (xy 120.034819 -233.997496)
			(xy 120.042939 -234.052672) (xy 120.043448 -234.080558) (xy 120.042939 -234.108444) (xy 120.034819 -234.16362)
			(xy 120.018751 -234.217027) (xy 119.995079 -234.267524) (xy 119.964306 -234.314037) (xy 119.927089 -234.355574)
			(xy 119.884221 -234.391249) (xy 119.836615 -234.420303) (xy 119.785286 -234.442115) (xy 119.731329 -234.456221)
			(xy 119.675892 -234.462321) (xy 119.620158 -234.460284) (xy 119.565315 -234.450154) (xy 119.512531 -234.432147)
			(xy 119.462931 -234.406646) (xy 119.417573 -234.374195) (xy 119.377424 -234.335486) (xy 119.343338 -234.291343)
			(xy 119.316042 -234.242708) (xy 119.296119 -234.190617) (xy 119.283993 -234.13618) (xy 119.279922 -234.080558)
			(xy 91.337384 -234.080558) (xy 91.337384 -234.984544) (xy 93.10751 -234.984544) (xy 93.107996 -234.957293)
			(xy 93.115752 -234.903345) (xy 93.131107 -234.85105) (xy 93.153749 -234.801473) (xy 93.183215 -234.755623)
			(xy 93.218906 -234.714432) (xy 93.260097 -234.678741) (xy 93.305947 -234.649275) (xy 93.355524 -234.626633)
			(xy 93.407819 -234.611278) (xy 93.461767 -234.603522) (xy 93.516269 -234.603522) (xy 93.570217 -234.611278)
			(xy 93.622512 -234.626633) (xy 93.672089 -234.649275) (xy 93.717939 -234.678741) (xy 93.75913 -234.714432)
			(xy 93.794821 -234.755623) (xy 93.824287 -234.801473) (xy 93.837831 -234.831128) (xy 118.361458 -234.831128)
			(xy 118.365529 -234.775506) (xy 118.377655 -234.721069) (xy 118.397578 -234.668978) (xy 118.424874 -234.620343)
			(xy 118.45896 -234.5762) (xy 118.499109 -234.537491) (xy 118.544467 -234.50504) (xy 118.594067 -234.479539)
			(xy 118.646851 -234.461532) (xy 118.701694 -234.451402) (xy 118.757428 -234.449365) (xy 118.812865 -234.455465)
			(xy 118.866822 -234.469571) (xy 118.918151 -234.491383) (xy 118.965757 -234.520437) (xy 119.008625 -234.556112)
			(xy 119.045842 -234.597649) (xy 119.076615 -234.644162) (xy 119.100287 -234.694659) (xy 119.116355 -234.748066)
			(xy 119.124475 -234.803242) (xy 119.124984 -234.831128) (xy 119.124516 -234.856782) (xy 122.031504 -234.856782)
			(xy 122.035575 -234.80116) (xy 122.047701 -234.746723) (xy 122.067624 -234.694632) (xy 122.09492 -234.645997)
			(xy 122.129006 -234.601854) (xy 122.169155 -234.563145) (xy 122.214513 -234.530694) (xy 122.264113 -234.505193)
			(xy 122.316897 -234.487186) (xy 122.37174 -234.477056) (xy 122.427474 -234.475019) (xy 122.482911 -234.481119)
			(xy 122.536868 -234.495225) (xy 122.588197 -234.517037) (xy 122.635803 -234.546091) (xy 122.678671 -234.581766)
			(xy 122.715888 -234.623303) (xy 122.746661 -234.669816) (xy 122.770333 -234.720313) (xy 122.786401 -234.77372)
			(xy 122.794521 -234.828896) (xy 122.79503 -234.856782) (xy 122.794521 -234.884668) (xy 122.786401 -234.939844)
			(xy 122.770333 -234.993251) (xy 122.746661 -235.043748) (xy 122.715888 -235.090261) (xy 122.678671 -235.131798)
			(xy 122.635803 -235.167473) (xy 122.588197 -235.196527) (xy 122.536868 -235.218339) (xy 122.482911 -235.232445)
			(xy 122.427474 -235.238545) (xy 122.37174 -235.236508) (xy 122.316897 -235.226378) (xy 122.264113 -235.208371)
			(xy 122.214513 -235.18287) (xy 122.169155 -235.150419) (xy 122.129006 -235.11171) (xy 122.09492 -235.067567)
			(xy 122.067624 -235.018932) (xy 122.047701 -234.966841) (xy 122.035575 -234.912404) (xy 122.031504 -234.856782)
			(xy 119.124516 -234.856782) (xy 119.124475 -234.859014) (xy 119.116355 -234.91419) (xy 119.100287 -234.967597)
			(xy 119.076615 -235.018094) (xy 119.045842 -235.064607) (xy 119.008625 -235.106144) (xy 118.965757 -235.141819)
			(xy 118.918151 -235.170873) (xy 118.866822 -235.192685) (xy 118.812865 -235.206791) (xy 118.757428 -235.212891)
			(xy 118.701694 -235.210854) (xy 118.646851 -235.200724) (xy 118.594067 -235.182717) (xy 118.544467 -235.157216)
			(xy 118.499109 -235.124765) (xy 118.45896 -235.086056) (xy 118.424874 -235.041913) (xy 118.397578 -234.993278)
			(xy 118.377655 -234.941187) (xy 118.365529 -234.88675) (xy 118.361458 -234.831128) (xy 93.837831 -234.831128)
			(xy 93.846929 -234.85105) (xy 93.862284 -234.903345) (xy 93.87004 -234.957293) (xy 93.870526 -234.984544)
			(xy 93.870526 -234.984798) (xy 93.869963 -235.014886) (xy 93.860504 -235.074314) (xy 93.841836 -235.13152)
			(xy 93.814422 -235.185089) (xy 93.77894 -235.233691) (xy 93.758004 -235.255308) (xy 93.749622 -235.263182)
			(xy 93.745812 -235.273342) (xy 93.744073 -235.278619) (xy 93.74267 -235.28964) (xy 93.743018 -235.295186)
			(xy 93.750638 -235.384594) (xy 93.755972 -235.393992) (xy 93.758878 -235.398646) (xy 93.7663 -235.406722)
			(xy 93.770704 -235.409994) (xy 93.771212 -235.410502) (xy 93.793309 -235.426629) (xy 93.833336 -235.463915)
			(xy 93.867905 -235.506312) (xy 93.891242 -235.544614) (xy 120.151142 -235.544614) (xy 120.155213 -235.488992)
			(xy 120.167339 -235.434555) (xy 120.187262 -235.382464) (xy 120.214558 -235.333829) (xy 120.248644 -235.289686)
			(xy 120.288793 -235.250977) (xy 120.334151 -235.218526) (xy 120.383751 -235.193025) (xy 120.436535 -235.175018)
			(xy 120.491378 -235.164888) (xy 120.547112 -235.162851) (xy 120.602549 -235.168951) (xy 120.656506 -235.183057)
			(xy 120.707835 -235.204869) (xy 120.755441 -235.233923) (xy 120.798309 -235.269598) (xy 120.835526 -235.311135)
			(xy 120.866299 -235.357648) (xy 120.889971 -235.408145) (xy 120.906039 -235.461552) (xy 120.914159 -235.516728)
			(xy 120.914668 -235.544614) (xy 120.914159 -235.5725) (xy 120.906039 -235.627676) (xy 120.889971 -235.681083)
			(xy 120.866299 -235.73158) (xy 120.835526 -235.778093) (xy 120.798309 -235.81963) (xy 120.755441 -235.855305)
			(xy 120.707835 -235.884359) (xy 120.656506 -235.906171) (xy 120.602549 -235.920277) (xy 120.547112 -235.926377)
			(xy 120.491378 -235.92434) (xy 120.436535 -235.91421) (xy 120.383751 -235.896203) (xy 120.334151 -235.870702)
			(xy 120.288793 -235.838251) (xy 120.248644 -235.799542) (xy 120.214558 -235.755399) (xy 120.187262 -235.706764)
			(xy 120.167339 -235.654673) (xy 120.155213 -235.600236) (xy 120.151142 -235.544614) (xy 93.891242 -235.544614)
			(xy 93.896368 -235.553027) (xy 93.918194 -235.603187) (xy 93.932976 -235.655856) (xy 93.940436 -235.710048)
			(xy 93.940884 -235.7374) (xy 93.940884 -235.737908) (xy 93.940323 -235.76803) (xy 93.931259 -235.82759)
			(xy 93.913351 -235.885112) (xy 93.887007 -235.939292) (xy 93.852824 -235.9889) (xy 93.811578 -236.032812)
			(xy 93.78823 -236.051852) (xy 93.782896 -236.055916) (xy 93.775276 -236.066076) (xy 93.772736 -236.071664)
			(xy 93.770407 -236.077599) (xy 93.768471 -236.090197) (xy 93.768926 -236.096556) (xy 93.777054 -236.181646)
			(xy 93.777892 -236.188103) (xy 93.782393 -236.200318) (xy 93.785944 -236.205776) (xy 93.785944 -236.20603)
			(xy 93.789556 -236.21094) (xy 93.798679 -236.21902) (xy 93.803978 -236.222032) (xy 93.80474 -236.22254)
			(xy 93.827852 -236.234837) (xy 93.870782 -236.2648) (xy 93.909206 -236.300358) (xy 93.942399 -236.340842)
			(xy 93.969737 -236.38549) (xy 93.972453 -236.391704) (xy 99.087938 -236.391704) (xy 99.092009 -236.336082)
			(xy 99.104135 -236.281645) (xy 99.124058 -236.229554) (xy 99.151354 -236.180919) (xy 99.18544 -236.136776)
			(xy 99.225589 -236.098067) (xy 99.270947 -236.065616) (xy 99.320547 -236.040115) (xy 99.373331 -236.022108)
			(xy 99.428174 -236.011978) (xy 99.483908 -236.009941) (xy 99.539345 -236.016041) (xy 99.593302 -236.030147)
			(xy 99.644631 -236.051959) (xy 99.692237 -236.081013) (xy 99.735105 -236.116688) (xy 99.772322 -236.158225)
			(xy 99.803095 -236.204738) (xy 99.826767 -236.255235) (xy 99.842835 -236.308642) (xy 99.850955 -236.363818)
			(xy 99.851464 -236.391704) (xy 99.850955 -236.41959) (xy 99.842835 -236.474766) (xy 99.826767 -236.528173)
			(xy 99.803095 -236.57867) (xy 99.772322 -236.625183) (xy 99.735105 -236.66672) (xy 99.692237 -236.702395)
			(xy 99.644631 -236.731449) (xy 99.593302 -236.753261) (xy 99.539345 -236.767367) (xy 99.483908 -236.773467)
			(xy 99.428174 -236.77143) (xy 99.373331 -236.7613) (xy 99.320547 -236.743293) (xy 99.270947 -236.717792)
			(xy 99.225589 -236.685341) (xy 99.18544 -236.646632) (xy 99.151354 -236.602489) (xy 99.124058 -236.553854)
			(xy 99.104135 -236.501763) (xy 99.092009 -236.447326) (xy 99.087938 -236.391704) (xy 93.972453 -236.391704)
			(xy 93.990704 -236.43346) (xy 94.004907 -236.483849) (xy 94.012077 -236.535708) (xy 94.012512 -236.561884)
			(xy 94.012026 -236.589135) (xy 94.00427 -236.643083) (xy 93.988915 -236.695378) (xy 93.966273 -236.744955)
			(xy 93.936807 -236.790805) (xy 93.901116 -236.831996) (xy 93.859925 -236.867687) (xy 93.814075 -236.897153)
			(xy 93.764498 -236.919795) (xy 93.712203 -236.93515) (xy 93.658255 -236.942906) (xy 93.603753 -236.942906)
			(xy 93.549805 -236.93515) (xy 93.49751 -236.919795) (xy 93.447933 -236.897153) (xy 93.402083 -236.867687)
			(xy 93.360892 -236.831996) (xy 93.325201 -236.790805) (xy 93.295735 -236.744955) (xy 93.273093 -236.695378)
			(xy 93.257738 -236.643083) (xy 93.249982 -236.589135) (xy 93.249496 -236.561884) (xy 93.249964 -236.533841)
			(xy 93.258171 -236.47836) (xy 93.274421 -236.42468) (xy 93.298362 -236.373961) (xy 93.329477 -236.327299)
			(xy 93.367096 -236.2857) (xy 93.388434 -236.267498) (xy 93.393768 -236.26318) (xy 93.40088 -236.253274)
			(xy 93.40342 -236.247432) (xy 93.405625 -236.241404) (xy 93.40729 -236.22868) (xy 93.406722 -236.222286)
			(xy 93.396308 -236.136942) (xy 93.395346 -236.130752) (xy 93.390857 -236.119063) (xy 93.387418 -236.113828)
			(xy 93.383608 -236.108494) (xy 93.373702 -236.100366) (xy 93.36786 -236.097572) (xy 93.342778 -236.08503)
			(xy 93.296166 -236.053847) (xy 93.254372 -236.016454) (xy 93.218217 -235.973584) (xy 93.188411 -235.92608)
			(xy 93.165539 -235.874875) (xy 93.150052 -235.820976) (xy 93.142252 -235.765441) (xy 93.1418 -235.7374)
			(xy 93.14228 -235.710099) (xy 93.149698 -235.656003) (xy 93.16441 -235.60342) (xy 93.186141 -235.553329)
			(xy 93.214488 -235.506662) (xy 93.248923 -235.464287) (xy 93.268546 -235.4453) (xy 93.276928 -235.437426)
			(xy 93.280992 -235.42752) (xy 93.284548 -235.413804) (xy 93.284802 -235.405168) (xy 93.279722 -235.316268)
			(xy 93.274642 -235.306616) (xy 93.271897 -235.301743) (xy 93.264579 -235.293286) (xy 93.260164 -235.289852)
			(xy 93.236877 -235.271723) (xy 93.195687 -235.229461) (xy 93.16149 -235.181365) (xy 93.135102 -235.128579)
			(xy 93.117151 -235.072361) (xy 93.108063 -235.014051) (xy 93.10751 -234.984544) (xy 91.337384 -234.984544)
			(xy 91.337384 -237.3757) (xy 92.775276 -237.3757) (xy 92.779347 -237.320078) (xy 92.791473 -237.265641)
			(xy 92.811396 -237.21355) (xy 92.838692 -237.164915) (xy 92.872778 -237.120772) (xy 92.912927 -237.082063)
			(xy 92.958285 -237.049612) (xy 93.007885 -237.024111) (xy 93.060669 -237.006104) (xy 93.115512 -236.995974)
			(xy 93.171246 -236.993937) (xy 93.226683 -237.000037) (xy 93.28064 -237.014143) (xy 93.331969 -237.035955)
			(xy 93.379575 -237.065009) (xy 93.422443 -237.100684) (xy 93.45966 -237.142221) (xy 93.490433 -237.188734)
			(xy 93.514105 -237.239231) (xy 93.530173 -237.292638) (xy 93.538293 -237.347814) (xy 93.538802 -237.3757)
			(xy 93.538293 -237.403586) (xy 93.530173 -237.458762) (xy 93.514105 -237.512169) (xy 93.490433 -237.562666)
			(xy 93.45966 -237.609179) (xy 93.422443 -237.650716) (xy 93.379575 -237.686391) (xy 93.331969 -237.715445)
			(xy 93.28064 -237.737257) (xy 93.226683 -237.751363) (xy 93.171246 -237.757463) (xy 93.115512 -237.755426)
			(xy 93.060669 -237.745296) (xy 93.007885 -237.727289) (xy 92.958285 -237.701788) (xy 92.912927 -237.669337)
			(xy 92.872778 -237.630628) (xy 92.838692 -237.586485) (xy 92.811396 -237.53785) (xy 92.791473 -237.485759)
			(xy 92.779347 -237.431322) (xy 92.775276 -237.3757) (xy 91.337384 -237.3757) (xy 91.337384 -238.212753)
			(xy 93.33583 -238.212753) (xy 93.33583 -238.158247) (xy 93.343586 -238.104297) (xy 93.358941 -238.051999)
			(xy 93.381582 -238.002418) (xy 93.411048 -237.956564) (xy 93.446739 -237.91537) (xy 93.487929 -237.879674)
			(xy 93.53378 -237.850203) (xy 93.583358 -237.827556) (xy 93.635654 -237.812195) (xy 93.689603 -237.804433)
			(xy 93.716856 -237.803944) (xy 93.746465 -237.804497) (xy 93.804971 -237.813661) (xy 93.861351 -237.831774)
			(xy 93.888052 -237.844584) (xy 93.89618 -237.848648) (xy 93.90507 -237.849664) (xy 93.909601 -237.850049)
			(xy 93.918671 -237.849409) (xy 93.923104 -237.848394) (xy 93.987112 -237.832646) (xy 93.991436 -237.831441)
			(xy 93.999609 -237.827733) (xy 94.003368 -237.82528) (xy 94.010988 -237.8202) (xy 94.016322 -237.812834)
			(xy 94.033291 -237.789888) (xy 94.072723 -237.748632) (xy 94.117625 -237.713408) (xy 94.167084 -237.684934)
			(xy 94.220091 -237.663789) (xy 94.247716 -237.656624) (xy 94.25686 -237.654338) (xy 94.264226 -237.649258)
			(xy 94.267678 -237.646789) (xy 94.273813 -237.640924) (xy 94.276418 -237.637574) (xy 94.315534 -237.584234)
			(xy 94.318209 -237.580524) (xy 94.322292 -237.572342) (xy 94.323662 -237.567978) (xy 94.325948 -237.55985)
			(xy 94.32544 -237.550706) (xy 94.324424 -237.524798) (xy 94.324424 -237.52429) (xy 94.324937 -237.49705)
			(xy 94.332717 -237.443129) (xy 94.34809 -237.390863) (xy 94.370743 -237.341316) (xy 94.400215 -237.295495)
			(xy 94.435906 -237.254334) (xy 94.477089 -237.21867) (xy 94.522928 -237.189227) (xy 94.57249 -237.166606)
			(xy 94.624766 -237.151266) (xy 94.678692 -237.143519) (xy 94.705932 -237.143036) (xy 94.717454 -237.14313)
			(xy 94.740457 -237.144528) (xy 94.751906 -237.14583) (xy 94.763844 -237.147354) (xy 94.77502 -237.143544)
			(xy 94.779918 -237.141715) (xy 94.788879 -237.136334) (xy 94.7928 -237.132876) (xy 94.794578 -237.131098)
			(xy 94.850966 -237.073186) (xy 94.854975 -237.068779) (xy 94.861015 -237.058516) (xy 94.862904 -237.052866)
			(xy 94.86646 -237.041944) (xy 94.864682 -237.030006) (xy 94.862666 -237.015485) (xy 94.860508 -236.986245)
			(xy 94.860364 -236.971586) (xy 94.860881 -236.943052) (xy 94.869004 -236.886564) (xy 94.885082 -236.831807)
			(xy 94.908787 -236.779895) (xy 94.939639 -236.731885) (xy 94.977008 -236.688752) (xy 95.020134 -236.651377)
			(xy 95.068139 -236.620518) (xy 95.120048 -236.596804) (xy 95.174802 -236.580717) (xy 95.231288 -236.572586)
			(xy 95.288357 -236.572575) (xy 95.344846 -236.580684) (xy 95.399607 -236.59675) (xy 95.451525 -236.620443)
			(xy 95.499542 -236.651284) (xy 95.542683 -236.688643) (xy 95.580069 -236.731761) (xy 95.608034 -236.775244)
			(xy 101.503226 -236.775244) (xy 101.503712 -236.747874) (xy 101.511524 -236.693696) (xy 101.527008 -236.641193)
			(xy 101.549845 -236.591446) (xy 101.579566 -236.545478) (xy 101.597206 -236.524546) (xy 101.603302 -236.517434)
			(xy 101.60635 -236.509052) (xy 101.607866 -236.504763) (xy 101.609528 -236.49582) (xy 101.609652 -236.491272)
			(xy 101.609652 -236.424216) (xy 101.609525 -236.419668) (xy 101.607868 -236.410724) (xy 101.60635 -236.406436)
			(xy 101.603302 -236.398054) (xy 101.597206 -236.390942) (xy 101.579574 -236.370004) (xy 101.549861 -236.324033)
			(xy 101.527024 -236.274287) (xy 101.511531 -236.221788) (xy 101.503701 -236.167613) (xy 101.503226 -236.140244)
			(xy 101.503712 -236.112993) (xy 101.511468 -236.059045) (xy 101.526823 -236.00675) (xy 101.549465 -235.957173)
			(xy 101.578931 -235.911323) (xy 101.614622 -235.870132) (xy 101.655813 -235.834441) (xy 101.701663 -235.804975)
			(xy 101.75124 -235.782333) (xy 101.803535 -235.766978) (xy 101.857483 -235.759222) (xy 101.911985 -235.759222)
			(xy 101.965933 -235.766978) (xy 102.018228 -235.782333) (xy 102.067805 -235.804975) (xy 102.113655 -235.834441)
			(xy 102.154846 -235.870132) (xy 102.190537 -235.911323) (xy 102.220003 -235.957173) (xy 102.242645 -236.00675)
			(xy 102.258 -236.059045) (xy 102.265756 -236.112993) (xy 102.266242 -236.140244) (xy 102.265757 -236.167614)
			(xy 102.257946 -236.221793) (xy 102.242462 -236.274296) (xy 102.219624 -236.324043) (xy 102.189902 -236.37001)
			(xy 102.172262 -236.390942) (xy 102.166166 -236.398054) (xy 102.163118 -236.406436) (xy 102.161604 -236.410726)
			(xy 102.159941 -236.419669) (xy 102.159816 -236.424216) (xy 102.159816 -236.491272) (xy 102.159949 -236.495819)
			(xy 102.161602 -236.504763) (xy 102.163118 -236.509052) (xy 102.166166 -236.517434) (xy 102.172262 -236.524546)
			(xy 102.189883 -236.545492) (xy 102.219599 -236.591461) (xy 102.242439 -236.641205) (xy 102.257934 -236.693702)
			(xy 102.265766 -236.747876) (xy 102.266242 -236.775244) (xy 103.535226 -236.775244) (xy 103.535712 -236.747874)
			(xy 103.543524 -236.693696) (xy 103.559008 -236.641193) (xy 103.581845 -236.591446) (xy 103.611566 -236.545478)
			(xy 103.629206 -236.524546) (xy 103.635302 -236.517434) (xy 103.63835 -236.509052) (xy 103.639866 -236.504763)
			(xy 103.641528 -236.49582) (xy 103.641652 -236.491272) (xy 103.641652 -236.424216) (xy 103.641525 -236.419668)
			(xy 103.639868 -236.410724) (xy 103.63835 -236.406436) (xy 103.635302 -236.398054) (xy 103.629206 -236.390942)
			(xy 103.611574 -236.370004) (xy 103.581861 -236.324033) (xy 103.559024 -236.274287) (xy 103.543531 -236.221788)
			(xy 103.535701 -236.167613) (xy 103.535226 -236.140244) (xy 103.535712 -236.112993) (xy 103.543468 -236.059045)
			(xy 103.558823 -236.00675) (xy 103.581465 -235.957173) (xy 103.610931 -235.911323) (xy 103.646622 -235.870132)
			(xy 103.687813 -235.834441) (xy 103.733663 -235.804975) (xy 103.78324 -235.782333) (xy 103.835535 -235.766978)
			(xy 103.889483 -235.759222) (xy 103.943985 -235.759222) (xy 103.997933 -235.766978) (xy 104.050228 -235.782333)
			(xy 104.099805 -235.804975) (xy 104.145655 -235.834441) (xy 104.186846 -235.870132) (xy 104.222537 -235.911323)
			(xy 104.252003 -235.957173) (xy 104.274645 -236.00675) (xy 104.29 -236.059045) (xy 104.297756 -236.112993)
			(xy 104.298242 -236.140244) (xy 104.297757 -236.167614) (xy 104.289946 -236.221793) (xy 104.274462 -236.274296)
			(xy 104.251624 -236.324043) (xy 104.221902 -236.37001) (xy 104.204262 -236.390942) (xy 104.198166 -236.398054)
			(xy 104.195118 -236.406436) (xy 104.193604 -236.410726) (xy 104.191941 -236.419669) (xy 104.191816 -236.424216)
			(xy 104.191816 -236.491272) (xy 104.191949 -236.495819) (xy 104.193602 -236.504763) (xy 104.195118 -236.509052)
			(xy 104.198166 -236.517434) (xy 104.204262 -236.524546) (xy 104.221883 -236.545492) (xy 104.251599 -236.591461)
			(xy 104.274439 -236.641205) (xy 104.289934 -236.693702) (xy 104.297766 -236.747876) (xy 104.298242 -236.775244)
			(xy 105.567226 -236.775244) (xy 105.567712 -236.747874) (xy 105.575524 -236.693696) (xy 105.591008 -236.641193)
			(xy 105.613845 -236.591446) (xy 105.643566 -236.545478) (xy 105.661206 -236.524546) (xy 105.667302 -236.517434)
			(xy 105.67035 -236.509052) (xy 105.671866 -236.504763) (xy 105.673528 -236.49582) (xy 105.673652 -236.491272)
			(xy 105.673652 -236.424216) (xy 105.673525 -236.419668) (xy 105.671868 -236.410724) (xy 105.67035 -236.406436)
			(xy 105.667302 -236.398054) (xy 105.661206 -236.390942) (xy 105.643574 -236.370004) (xy 105.613861 -236.324033)
			(xy 105.591024 -236.274287) (xy 105.575531 -236.221788) (xy 105.567701 -236.167613) (xy 105.567226 -236.140244)
			(xy 105.567712 -236.112993) (xy 105.575468 -236.059045) (xy 105.590823 -236.00675) (xy 105.613465 -235.957173)
			(xy 105.642931 -235.911323) (xy 105.678622 -235.870132) (xy 105.719813 -235.834441) (xy 105.765663 -235.804975)
			(xy 105.81524 -235.782333) (xy 105.867535 -235.766978) (xy 105.921483 -235.759222) (xy 105.975985 -235.759222)
			(xy 106.029933 -235.766978) (xy 106.082228 -235.782333) (xy 106.131805 -235.804975) (xy 106.177655 -235.834441)
			(xy 106.218846 -235.870132) (xy 106.254537 -235.911323) (xy 106.284003 -235.957173) (xy 106.306645 -236.00675)
			(xy 106.322 -236.059045) (xy 106.329756 -236.112993) (xy 106.330242 -236.140244) (xy 106.329757 -236.167614)
			(xy 106.321946 -236.221793) (xy 106.306462 -236.274296) (xy 106.283624 -236.324043) (xy 106.253902 -236.37001)
			(xy 106.236262 -236.390942) (xy 106.230166 -236.398054) (xy 106.227118 -236.406436) (xy 106.225604 -236.410726)
			(xy 106.223941 -236.419669) (xy 106.223816 -236.424216) (xy 106.223816 -236.491272) (xy 106.223949 -236.495819)
			(xy 106.225602 -236.504763) (xy 106.227118 -236.509052) (xy 106.230166 -236.517434) (xy 106.236262 -236.524546)
			(xy 106.253883 -236.545492) (xy 106.283599 -236.591461) (xy 106.306439 -236.641205) (xy 106.321934 -236.693702)
			(xy 106.329766 -236.747876) (xy 106.330242 -236.775244) (xy 107.599226 -236.775244) (xy 107.599712 -236.747874)
			(xy 107.607524 -236.693696) (xy 107.623008 -236.641193) (xy 107.645845 -236.591446) (xy 107.675566 -236.545478)
			(xy 107.693206 -236.524546) (xy 107.699302 -236.517434) (xy 107.70235 -236.509052) (xy 107.703866 -236.504763)
			(xy 107.705528 -236.49582) (xy 107.705652 -236.491272) (xy 107.705652 -236.424216) (xy 107.705525 -236.419668)
			(xy 107.703868 -236.410724) (xy 107.70235 -236.406436) (xy 107.699302 -236.398054) (xy 107.693206 -236.390942)
			(xy 107.675574 -236.370004) (xy 107.645861 -236.324033) (xy 107.623024 -236.274287) (xy 107.607531 -236.221788)
			(xy 107.599701 -236.167613) (xy 107.599226 -236.140244) (xy 107.599712 -236.112993) (xy 107.607468 -236.059045)
			(xy 107.622823 -236.00675) (xy 107.645465 -235.957173) (xy 107.674931 -235.911323) (xy 107.710622 -235.870132)
			(xy 107.751813 -235.834441) (xy 107.797663 -235.804975) (xy 107.84724 -235.782333) (xy 107.899535 -235.766978)
			(xy 107.953483 -235.759222) (xy 108.007985 -235.759222) (xy 108.061933 -235.766978) (xy 108.114228 -235.782333)
			(xy 108.163805 -235.804975) (xy 108.209655 -235.834441) (xy 108.250846 -235.870132) (xy 108.286537 -235.911323)
			(xy 108.316003 -235.957173) (xy 108.338645 -236.00675) (xy 108.354 -236.059045) (xy 108.361756 -236.112993)
			(xy 108.362242 -236.140244) (xy 108.361757 -236.167614) (xy 108.353946 -236.221793) (xy 108.338462 -236.274296)
			(xy 108.335986 -236.27969) (xy 119.269254 -236.27969) (xy 119.273325 -236.224068) (xy 119.285451 -236.169631)
			(xy 119.305374 -236.11754) (xy 119.33267 -236.068905) (xy 119.366756 -236.024762) (xy 119.406905 -235.986053)
			(xy 119.452263 -235.953602) (xy 119.501863 -235.928101) (xy 119.554647 -235.910094) (xy 119.60949 -235.899964)
			(xy 119.665224 -235.897927) (xy 119.720661 -235.904027) (xy 119.774618 -235.918133) (xy 119.825947 -235.939945)
			(xy 119.873553 -235.968999) (xy 119.916421 -236.004674) (xy 119.953638 -236.046211) (xy 119.984411 -236.092724)
			(xy 120.008083 -236.143221) (xy 120.024151 -236.196628) (xy 120.032271 -236.251804) (xy 120.03278 -236.27969)
			(xy 120.032271 -236.307576) (xy 120.024151 -236.362752) (xy 120.008083 -236.416159) (xy 119.984411 -236.466656)
			(xy 119.953638 -236.513169) (xy 119.916421 -236.554706) (xy 119.873553 -236.590381) (xy 119.825947 -236.619435)
			(xy 119.774618 -236.641247) (xy 119.720661 -236.655353) (xy 119.665224 -236.661453) (xy 119.60949 -236.659416)
			(xy 119.554647 -236.649286) (xy 119.501863 -236.631279) (xy 119.452263 -236.605778) (xy 119.406905 -236.573327)
			(xy 119.366756 -236.534618) (xy 119.33267 -236.490475) (xy 119.305374 -236.44184) (xy 119.285451 -236.389749)
			(xy 119.273325 -236.335312) (xy 119.269254 -236.27969) (xy 108.335986 -236.27969) (xy 108.315624 -236.324043)
			(xy 108.285902 -236.37001) (xy 108.268262 -236.390942) (xy 108.262166 -236.398054) (xy 108.259118 -236.406436)
			(xy 108.257604 -236.410726) (xy 108.255941 -236.419669) (xy 108.255816 -236.424216) (xy 108.255816 -236.491272)
			(xy 108.255949 -236.495819) (xy 108.257602 -236.504763) (xy 108.259118 -236.509052) (xy 108.262166 -236.517434)
			(xy 108.268262 -236.524546) (xy 108.285883 -236.545492) (xy 108.315599 -236.591461) (xy 108.338439 -236.641205)
			(xy 108.353934 -236.693702) (xy 108.361766 -236.747876) (xy 108.362242 -236.775244) (xy 108.361756 -236.802495)
			(xy 108.354 -236.856443) (xy 108.338645 -236.908738) (xy 108.316003 -236.958315) (xy 108.286537 -237.004165)
			(xy 108.250846 -237.045356) (xy 108.209655 -237.081047) (xy 108.163805 -237.110513) (xy 108.114228 -237.133155)
			(xy 108.061933 -237.14851) (xy 108.007985 -237.156266) (xy 107.953483 -237.156266) (xy 107.899535 -237.14851)
			(xy 107.84724 -237.133155) (xy 107.797663 -237.110513) (xy 107.751813 -237.081047) (xy 107.710622 -237.045356)
			(xy 107.674931 -237.004165) (xy 107.645465 -236.958315) (xy 107.622823 -236.908738) (xy 107.607468 -236.856443)
			(xy 107.599712 -236.802495) (xy 107.599226 -236.775244) (xy 106.330242 -236.775244) (xy 106.329756 -236.802495)
			(xy 106.322 -236.856443) (xy 106.306645 -236.908738) (xy 106.284003 -236.958315) (xy 106.254537 -237.004165)
			(xy 106.218846 -237.045356) (xy 106.177655 -237.081047) (xy 106.131805 -237.110513) (xy 106.082228 -237.133155)
			(xy 106.029933 -237.14851) (xy 105.975985 -237.156266) (xy 105.921483 -237.156266) (xy 105.867535 -237.14851)
			(xy 105.81524 -237.133155) (xy 105.765663 -237.110513) (xy 105.719813 -237.081047) (xy 105.678622 -237.045356)
			(xy 105.642931 -237.004165) (xy 105.613465 -236.958315) (xy 105.590823 -236.908738) (xy 105.575468 -236.856443)
			(xy 105.567712 -236.802495) (xy 105.567226 -236.775244) (xy 104.298242 -236.775244) (xy 104.297756 -236.802495)
			(xy 104.29 -236.856443) (xy 104.274645 -236.908738) (xy 104.252003 -236.958315) (xy 104.222537 -237.004165)
			(xy 104.186846 -237.045356) (xy 104.145655 -237.081047) (xy 104.099805 -237.110513) (xy 104.050228 -237.133155)
			(xy 103.997933 -237.14851) (xy 103.943985 -237.156266) (xy 103.889483 -237.156266) (xy 103.835535 -237.14851)
			(xy 103.78324 -237.133155) (xy 103.733663 -237.110513) (xy 103.687813 -237.081047) (xy 103.646622 -237.045356)
			(xy 103.610931 -237.004165) (xy 103.581465 -236.958315) (xy 103.558823 -236.908738) (xy 103.543468 -236.856443)
			(xy 103.535712 -236.802495) (xy 103.535226 -236.775244) (xy 102.266242 -236.775244) (xy 102.265756 -236.802495)
			(xy 102.258 -236.856443) (xy 102.242645 -236.908738) (xy 102.220003 -236.958315) (xy 102.190537 -237.004165)
			(xy 102.154846 -237.045356) (xy 102.113655 -237.081047) (xy 102.067805 -237.110513) (xy 102.018228 -237.133155)
			(xy 101.965933 -237.14851) (xy 101.911985 -237.156266) (xy 101.857483 -237.156266) (xy 101.803535 -237.14851)
			(xy 101.75124 -237.133155) (xy 101.701663 -237.110513) (xy 101.655813 -237.081047) (xy 101.614622 -237.045356)
			(xy 101.578931 -237.004165) (xy 101.549465 -236.958315) (xy 101.526823 -236.908738) (xy 101.511468 -236.856443)
			(xy 101.503712 -236.802495) (xy 101.503226 -236.775244) (xy 95.608034 -236.775244) (xy 95.610938 -236.779759)
			(xy 95.634664 -236.831662) (xy 95.650763 -236.886413) (xy 95.658908 -236.942897) (xy 95.658932 -236.999966)
			(xy 95.650835 -237.056457) (xy 95.634782 -237.111221) (xy 95.6111 -237.163144) (xy 95.580271 -237.211169)
			(xy 95.542922 -237.254318) (xy 95.499813 -237.291714) (xy 95.451821 -237.322595) (xy 95.399924 -237.346332)
			(xy 95.345176 -237.362444) (xy 95.288694 -237.370601) (xy 95.26016 -237.371128) (xy 95.245246 -237.371023)
			(xy 95.215496 -237.368865) (xy 95.200724 -237.36681) (xy 95.18904 -237.365032) (xy 95.177864 -237.368588)
			(xy 95.172295 -237.370531) (xy 95.16216 -237.376556) (xy 95.157798 -237.380526) (xy 95.099886 -237.43666)
			(xy 95.095747 -237.440851) (xy 95.089345 -237.450737) (xy 95.087186 -237.456218) (xy 95.083376 -237.467394)
			(xy 95.084646 -237.479332) (xy 95.085936 -237.490591) (xy 95.087336 -237.513212) (xy 95.08744 -237.524544)
			(xy 95.086944 -237.551896) (xy 95.079112 -237.606038) (xy 95.06363 -237.658506) (xy 95.040814 -237.708227)
			(xy 95.011133 -237.754179) (xy 94.975194 -237.795423) (xy 94.933734 -237.831113) (xy 94.887603 -237.860516)
			(xy 94.837746 -237.883032) (xy 94.811596 -237.891066) (xy 94.802706 -237.893606) (xy 94.795848 -237.898686)
			(xy 94.792261 -237.901432) (xy 94.786002 -237.907946) (xy 94.783402 -237.91164) (xy 94.74708 -237.96625)
			(xy 94.744644 -237.970062) (xy 94.74107 -237.978372) (xy 94.739968 -237.98276) (xy 94.737936 -237.990888)
			(xy 94.738952 -238.000032) (xy 94.740146 -238.011233) (xy 94.741415 -238.033726) (xy 94.741492 -238.04499)
			(xy 94.741025 -238.07352) (xy 94.732908 -238.129999) (xy 94.716839 -238.18475) (xy 94.693143 -238.236657)
			(xy 94.662304 -238.284665) (xy 94.624949 -238.327797) (xy 94.581836 -238.365176) (xy 94.533845 -238.396041)
			(xy 94.487223 -238.417354) (xy 99.087938 -238.417354) (xy 99.092009 -238.361732) (xy 99.104135 -238.307295)
			(xy 99.124058 -238.255204) (xy 99.151354 -238.206569) (xy 99.18544 -238.162426) (xy 99.225589 -238.123717)
			(xy 99.270947 -238.091266) (xy 99.320547 -238.065765) (xy 99.373331 -238.047758) (xy 99.428174 -238.037628)
			(xy 99.483908 -238.035591) (xy 99.539345 -238.041691) (xy 99.593302 -238.055797) (xy 99.644631 -238.077609)
			(xy 99.692237 -238.106663) (xy 99.735105 -238.142338) (xy 99.772322 -238.183875) (xy 99.803095 -238.230388)
			(xy 99.826767 -238.280885) (xy 99.842835 -238.334292) (xy 99.850955 -238.389468) (xy 99.851464 -238.417354)
			(xy 99.850955 -238.44524) (xy 99.842835 -238.500416) (xy 99.826941 -238.553244) (xy 101.503226 -238.553244)
			(xy 101.503712 -238.525874) (xy 101.511524 -238.471696) (xy 101.527008 -238.419193) (xy 101.549845 -238.369446)
			(xy 101.579566 -238.323478) (xy 101.597206 -238.302546) (xy 101.603302 -238.295434) (xy 101.60635 -238.287052)
			(xy 101.607866 -238.282763) (xy 101.609528 -238.27382) (xy 101.609652 -238.269272) (xy 101.609652 -238.202216)
			(xy 101.609525 -238.197668) (xy 101.607868 -238.188724) (xy 101.60635 -238.184436) (xy 101.603302 -238.176054)
			(xy 101.597206 -238.168942) (xy 101.579574 -238.148004) (xy 101.549861 -238.102033) (xy 101.527024 -238.052287)
			(xy 101.511531 -237.999788) (xy 101.503701 -237.945613) (xy 101.503226 -237.918244) (xy 101.503712 -237.890993)
			(xy 101.511468 -237.837045) (xy 101.526823 -237.78475) (xy 101.549465 -237.735173) (xy 101.578931 -237.689323)
			(xy 101.614622 -237.648132) (xy 101.655813 -237.612441) (xy 101.701663 -237.582975) (xy 101.75124 -237.560333)
			(xy 101.803535 -237.544978) (xy 101.857483 -237.537222) (xy 101.911985 -237.537222) (xy 101.965933 -237.544978)
			(xy 102.018228 -237.560333) (xy 102.067805 -237.582975) (xy 102.113655 -237.612441) (xy 102.154846 -237.648132)
			(xy 102.190537 -237.689323) (xy 102.220003 -237.735173) (xy 102.242645 -237.78475) (xy 102.258 -237.837045)
			(xy 102.265756 -237.890993) (xy 102.266242 -237.918244) (xy 102.265757 -237.945614) (xy 102.257946 -237.999793)
			(xy 102.242462 -238.052296) (xy 102.219624 -238.102043) (xy 102.189902 -238.14801) (xy 102.172262 -238.168942)
			(xy 102.166166 -238.176054) (xy 102.163118 -238.184436) (xy 102.161604 -238.188726) (xy 102.159941 -238.197669)
			(xy 102.159816 -238.202216) (xy 102.159816 -238.269272) (xy 102.159949 -238.273819) (xy 102.161602 -238.282763)
			(xy 102.163118 -238.287052) (xy 102.166166 -238.295434) (xy 102.172262 -238.302546) (xy 102.189883 -238.323492)
			(xy 102.219599 -238.369461) (xy 102.242439 -238.419205) (xy 102.257934 -238.471702) (xy 102.265766 -238.525876)
			(xy 102.266242 -238.553244) (xy 103.535226 -238.553244) (xy 103.535712 -238.525874) (xy 103.543524 -238.471696)
			(xy 103.559008 -238.419193) (xy 103.581845 -238.369446) (xy 103.611566 -238.323478) (xy 103.629206 -238.302546)
			(xy 103.635302 -238.295434) (xy 103.63835 -238.287052) (xy 103.639866 -238.282763) (xy 103.641528 -238.27382)
			(xy 103.641652 -238.269272) (xy 103.641652 -238.202216) (xy 103.641525 -238.197668) (xy 103.639868 -238.188724)
			(xy 103.63835 -238.184436) (xy 103.635302 -238.176054) (xy 103.629206 -238.168942) (xy 103.611574 -238.148004)
			(xy 103.581861 -238.102033) (xy 103.559024 -238.052287) (xy 103.543531 -237.999788) (xy 103.535701 -237.945613)
			(xy 103.535226 -237.918244) (xy 103.535712 -237.890993) (xy 103.543468 -237.837045) (xy 103.558823 -237.78475)
			(xy 103.581465 -237.735173) (xy 103.610931 -237.689323) (xy 103.646622 -237.648132) (xy 103.687813 -237.612441)
			(xy 103.733663 -237.582975) (xy 103.78324 -237.560333) (xy 103.835535 -237.544978) (xy 103.889483 -237.537222)
			(xy 103.943985 -237.537222) (xy 103.997933 -237.544978) (xy 104.050228 -237.560333) (xy 104.099805 -237.582975)
			(xy 104.145655 -237.612441) (xy 104.186846 -237.648132) (xy 104.222537 -237.689323) (xy 104.252003 -237.735173)
			(xy 104.274645 -237.78475) (xy 104.29 -237.837045) (xy 104.297756 -237.890993) (xy 104.298242 -237.918244)
			(xy 104.297757 -237.945614) (xy 104.289946 -237.999793) (xy 104.274462 -238.052296) (xy 104.251624 -238.102043)
			(xy 104.221902 -238.14801) (xy 104.204262 -238.168942) (xy 104.198166 -238.176054) (xy 104.195118 -238.184436)
			(xy 104.193604 -238.188726) (xy 104.191941 -238.197669) (xy 104.191816 -238.202216) (xy 104.191816 -238.269272)
			(xy 104.191949 -238.273819) (xy 104.193602 -238.282763) (xy 104.195118 -238.287052) (xy 104.198166 -238.295434)
			(xy 104.204262 -238.302546) (xy 104.221883 -238.323492) (xy 104.251599 -238.369461) (xy 104.274439 -238.419205)
			(xy 104.289934 -238.471702) (xy 104.297766 -238.525876) (xy 104.298242 -238.553244) (xy 105.567226 -238.553244)
			(xy 105.567712 -238.525874) (xy 105.575524 -238.471696) (xy 105.591008 -238.419193) (xy 105.613845 -238.369446)
			(xy 105.643566 -238.323478) (xy 105.661206 -238.302546) (xy 105.667302 -238.295434) (xy 105.67035 -238.287052)
			(xy 105.671866 -238.282763) (xy 105.673528 -238.27382) (xy 105.673652 -238.269272) (xy 105.673652 -238.202216)
			(xy 105.673525 -238.197668) (xy 105.671868 -238.188724) (xy 105.67035 -238.184436) (xy 105.667302 -238.176054)
			(xy 105.661206 -238.168942) (xy 105.643574 -238.148004) (xy 105.613861 -238.102033) (xy 105.591024 -238.052287)
			(xy 105.575531 -237.999788) (xy 105.567701 -237.945613) (xy 105.567226 -237.918244) (xy 105.567712 -237.890993)
			(xy 105.575468 -237.837045) (xy 105.590823 -237.78475) (xy 105.613465 -237.735173) (xy 105.642931 -237.689323)
			(xy 105.678622 -237.648132) (xy 105.719813 -237.612441) (xy 105.765663 -237.582975) (xy 105.81524 -237.560333)
			(xy 105.867535 -237.544978) (xy 105.921483 -237.537222) (xy 105.975985 -237.537222) (xy 106.029933 -237.544978)
			(xy 106.082228 -237.560333) (xy 106.131805 -237.582975) (xy 106.177655 -237.612441) (xy 106.218846 -237.648132)
			(xy 106.254537 -237.689323) (xy 106.284003 -237.735173) (xy 106.306645 -237.78475) (xy 106.322 -237.837045)
			(xy 106.329756 -237.890993) (xy 106.330242 -237.918244) (xy 106.329757 -237.945614) (xy 106.321946 -237.999793)
			(xy 106.306462 -238.052296) (xy 106.283624 -238.102043) (xy 106.253902 -238.14801) (xy 106.236262 -238.168942)
			(xy 106.230166 -238.176054) (xy 106.227118 -238.184436) (xy 106.225604 -238.188726) (xy 106.223941 -238.197669)
			(xy 106.223816 -238.202216) (xy 106.223816 -238.269272) (xy 106.223949 -238.273819) (xy 106.225602 -238.282763)
			(xy 106.227118 -238.287052) (xy 106.230166 -238.295434) (xy 106.236262 -238.302546) (xy 106.253883 -238.323492)
			(xy 106.283599 -238.369461) (xy 106.306439 -238.419205) (xy 106.321934 -238.471702) (xy 106.329766 -238.525876)
			(xy 106.330242 -238.553244) (xy 107.599226 -238.553244) (xy 107.599712 -238.525874) (xy 107.607524 -238.471696)
			(xy 107.623008 -238.419193) (xy 107.645845 -238.369446) (xy 107.675566 -238.323478) (xy 107.693206 -238.302546)
			(xy 107.699302 -238.295434) (xy 107.70235 -238.287052) (xy 107.703866 -238.282763) (xy 107.705528 -238.27382)
			(xy 107.705652 -238.269272) (xy 107.705652 -238.202216) (xy 107.705525 -238.197668) (xy 107.703868 -238.188724)
			(xy 107.70235 -238.184436) (xy 107.699302 -238.176054) (xy 107.693206 -238.168942) (xy 107.675574 -238.148004)
			(xy 107.645861 -238.102033) (xy 107.623024 -238.052287) (xy 107.607531 -237.999788) (xy 107.599701 -237.945613)
			(xy 107.599226 -237.918244) (xy 107.599712 -237.890993) (xy 107.607468 -237.837045) (xy 107.622823 -237.78475)
			(xy 107.645465 -237.735173) (xy 107.674931 -237.689323) (xy 107.710622 -237.648132) (xy 107.751813 -237.612441)
			(xy 107.797663 -237.582975) (xy 107.84724 -237.560333) (xy 107.899535 -237.544978) (xy 107.953483 -237.537222)
			(xy 108.007985 -237.537222) (xy 108.061933 -237.544978) (xy 108.114228 -237.560333) (xy 108.163805 -237.582975)
			(xy 108.209655 -237.612441) (xy 108.250846 -237.648132) (xy 108.286537 -237.689323) (xy 108.316003 -237.735173)
			(xy 108.338645 -237.78475) (xy 108.354 -237.837045) (xy 108.361756 -237.890993) (xy 108.362242 -237.918244)
			(xy 108.361757 -237.945614) (xy 108.353946 -237.999793) (xy 108.338462 -238.052296) (xy 108.335869 -238.057944)
			(xy 119.474486 -238.057944) (xy 119.478557 -238.002322) (xy 119.490683 -237.947885) (xy 119.510606 -237.895794)
			(xy 119.537902 -237.847159) (xy 119.571988 -237.803016) (xy 119.612137 -237.764307) (xy 119.657495 -237.731856)
			(xy 119.707095 -237.706355) (xy 119.759879 -237.688348) (xy 119.814722 -237.678218) (xy 119.870456 -237.676181)
			(xy 119.925893 -237.682281) (xy 119.97985 -237.696387) (xy 120.031179 -237.718199) (xy 120.078785 -237.747253)
			(xy 120.121653 -237.782928) (xy 120.15887 -237.824465) (xy 120.189643 -237.870978) (xy 120.213315 -237.921475)
			(xy 120.22159 -237.948978) (xy 143.128744 -237.948978) (xy 143.132815 -237.893356) (xy 143.144941 -237.838919)
			(xy 143.164864 -237.786828) (xy 143.19216 -237.738193) (xy 143.226246 -237.69405) (xy 143.266395 -237.655341)
			(xy 143.311753 -237.62289) (xy 143.361353 -237.597389) (xy 143.414137 -237.579382) (xy 143.46898 -237.569252)
			(xy 143.524714 -237.567215) (xy 143.580151 -237.573315) (xy 143.634108 -237.587421) (xy 143.685437 -237.609233)
			(xy 143.733043 -237.638287) (xy 143.775911 -237.673962) (xy 143.813128 -237.715499) (xy 143.843901 -237.762012)
			(xy 143.867573 -237.812509) (xy 143.883641 -237.865916) (xy 143.891761 -237.921092) (xy 143.89227 -237.948978)
			(xy 144.017744 -237.948978) (xy 144.021815 -237.893356) (xy 144.033941 -237.838919) (xy 144.053864 -237.786828)
			(xy 144.08116 -237.738193) (xy 144.115246 -237.69405) (xy 144.155395 -237.655341) (xy 144.200753 -237.62289)
			(xy 144.250353 -237.597389) (xy 144.303137 -237.579382) (xy 144.35798 -237.569252) (xy 144.413714 -237.567215)
			(xy 144.469151 -237.573315) (xy 144.523108 -237.587421) (xy 144.574437 -237.609233) (xy 144.622043 -237.638287)
			(xy 144.664911 -237.673962) (xy 144.702128 -237.715499) (xy 144.732901 -237.762012) (xy 144.756573 -237.812509)
			(xy 144.772641 -237.865916) (xy 144.780761 -237.921092) (xy 144.78127 -237.948978) (xy 144.780761 -237.976864)
			(xy 144.772641 -238.03204) (xy 144.756573 -238.085447) (xy 144.732901 -238.135944) (xy 144.702128 -238.182457)
			(xy 144.664911 -238.223994) (xy 144.622043 -238.259669) (xy 144.574437 -238.288723) (xy 144.523108 -238.310535)
			(xy 144.469151 -238.324641) (xy 144.413714 -238.330741) (xy 144.35798 -238.328704) (xy 144.303137 -238.318574)
			(xy 144.250353 -238.300567) (xy 144.200753 -238.275066) (xy 144.155395 -238.242615) (xy 144.115246 -238.203906)
			(xy 144.08116 -238.159763) (xy 144.053864 -238.111128) (xy 144.033941 -238.059037) (xy 144.021815 -238.0046)
			(xy 144.017744 -237.948978) (xy 143.89227 -237.948978) (xy 143.891761 -237.976864) (xy 143.883641 -238.03204)
			(xy 143.867573 -238.085447) (xy 143.843901 -238.135944) (xy 143.813128 -238.182457) (xy 143.775911 -238.223994)
			(xy 143.733043 -238.259669) (xy 143.685437 -238.288723) (xy 143.634108 -238.310535) (xy 143.580151 -238.324641)
			(xy 143.524714 -238.330741) (xy 143.46898 -238.328704) (xy 143.414137 -238.318574) (xy 143.361353 -238.300567)
			(xy 143.311753 -238.275066) (xy 143.266395 -238.242615) (xy 143.226246 -238.203906) (xy 143.19216 -238.159763)
			(xy 143.164864 -238.111128) (xy 143.144941 -238.059037) (xy 143.132815 -238.0046) (xy 143.128744 -237.948978)
			(xy 120.22159 -237.948978) (xy 120.229383 -237.974882) (xy 120.237503 -238.030058) (xy 120.238012 -238.057944)
			(xy 120.237503 -238.08583) (xy 120.229383 -238.141006) (xy 120.213315 -238.194413) (xy 120.189643 -238.24491)
			(xy 120.15887 -238.291423) (xy 120.121653 -238.33296) (xy 120.078785 -238.368635) (xy 120.031179 -238.397689)
			(xy 119.97985 -238.419501) (xy 119.925893 -238.433607) (xy 119.870456 -238.439707) (xy 119.814722 -238.43767)
			(xy 119.759879 -238.42754) (xy 119.707095 -238.409533) (xy 119.657495 -238.384032) (xy 119.612137 -238.351581)
			(xy 119.571988 -238.312872) (xy 119.537902 -238.268729) (xy 119.510606 -238.220094) (xy 119.490683 -238.168003)
			(xy 119.478557 -238.113566) (xy 119.474486 -238.057944) (xy 108.335869 -238.057944) (xy 108.315624 -238.102043)
			(xy 108.285902 -238.14801) (xy 108.268262 -238.168942) (xy 108.262166 -238.176054) (xy 108.259118 -238.184436)
			(xy 108.257604 -238.188726) (xy 108.255941 -238.197669) (xy 108.255816 -238.202216) (xy 108.255816 -238.269272)
			(xy 108.255949 -238.273819) (xy 108.257602 -238.282763) (xy 108.259118 -238.287052) (xy 108.262166 -238.295434)
			(xy 108.268262 -238.302546) (xy 108.285883 -238.323492) (xy 108.315599 -238.369461) (xy 108.338439 -238.419205)
			(xy 108.353934 -238.471702) (xy 108.359276 -238.508652) (xy 123.66954 -238.508652) (xy 123.66954 -238.454148)
			(xy 123.677296 -238.400199) (xy 123.69265 -238.347903) (xy 123.71529 -238.298324) (xy 123.744755 -238.252472)
			(xy 123.780445 -238.211279) (xy 123.821633 -238.175583) (xy 123.867482 -238.146113) (xy 123.917058 -238.123467)
			(xy 123.969352 -238.108106) (xy 124.0233 -238.100343) (xy 124.050552 -238.099854) (xy 124.077103 -238.100284)
			(xy 124.129691 -238.107648) (xy 124.180747 -238.12224) (xy 124.229284 -238.143778) (xy 124.274362 -238.171844)
			(xy 124.315108 -238.205896) (xy 124.350733 -238.245273) (xy 124.36602 -238.266986) (xy 124.374695 -238.278936)
			(xy 124.397602 -238.297557) (xy 124.424872 -238.308861) (xy 124.454235 -238.311908) (xy 124.483245 -238.306443)
			(xy 124.509486 -238.292921) (xy 124.530774 -238.272469) (xy 124.538486 -238.259874) (xy 124.553149 -238.235104)
			(xy 124.588706 -238.189841) (xy 124.630658 -238.150433) (xy 124.678056 -238.117775) (xy 124.729821 -238.092609)
			(xy 124.78478 -238.075505) (xy 124.841685 -238.066853) (xy 124.870464 -238.066326) (xy 124.897721 -238.066718)
			(xy 124.951681 -238.074472) (xy 125.003988 -238.089826) (xy 125.053577 -238.112469) (xy 125.099438 -238.141938)
			(xy 125.140639 -238.177635) (xy 125.17634 -238.218833) (xy 125.205814 -238.264692) (xy 125.228461 -238.314279)
			(xy 125.24382 -238.366584) (xy 125.251579 -238.420543) (xy 125.251579 -238.475057) (xy 125.24382 -238.529016)
			(xy 125.238869 -238.545878) (xy 130.747006 -238.545878) (xy 130.751077 -238.490256) (xy 130.763203 -238.435819)
			(xy 130.783126 -238.383728) (xy 130.810422 -238.335093) (xy 130.844508 -238.29095) (xy 130.884657 -238.252241)
			(xy 130.930015 -238.21979) (xy 130.979615 -238.194289) (xy 131.032399 -238.176282) (xy 131.087242 -238.166152)
			(xy 131.142976 -238.164115) (xy 131.198413 -238.170215) (xy 131.25237 -238.184321) (xy 131.303699 -238.206133)
			(xy 131.351305 -238.235187) (xy 131.394173 -238.270862) (xy 131.43139 -238.312399) (xy 131.462163 -238.358912)
			(xy 131.485835 -238.409409) (xy 131.501903 -238.462816) (xy 131.510023 -238.517992) (xy 131.510532 -238.545878)
			(xy 131.510023 -238.573764) (xy 131.506979 -238.594449) (xy 131.736092 -238.594449) (xy 131.736092 -238.539951)
			(xy 131.743848 -238.486006) (xy 131.759202 -238.433715) (xy 131.781841 -238.38414) (xy 131.811305 -238.338293)
			(xy 131.846993 -238.297104) (xy 131.88818 -238.261414) (xy 131.934026 -238.231949) (xy 131.9836 -238.209307)
			(xy 132.035891 -238.193951) (xy 132.089835 -238.186193) (xy 132.117084 -238.185706) (xy 132.143203 -238.186155)
			(xy 132.194952 -238.193287) (xy 132.245247 -238.207406) (xy 132.293147 -238.228249) (xy 132.337759 -238.255426)
			(xy 132.37825 -238.288431) (xy 132.413865 -238.326647) (xy 132.42925 -238.347758) (xy 132.437721 -238.359102)
			(xy 132.459727 -238.376902) (xy 132.485776 -238.387974) (xy 132.513863 -238.391469) (xy 132.54183 -238.387116)
			(xy 132.567527 -238.375251) (xy 132.588978 -238.356786) (xy 132.597144 -238.345218) (xy 132.612371 -238.323033)
			(xy 132.648039 -238.282748) (xy 132.689016 -238.247876) (xy 132.734487 -238.21911) (xy 132.78355 -238.19702)
			(xy 132.83523 -238.182045) (xy 132.888503 -238.174483) (xy 132.915406 -238.174022) (xy 132.942659 -238.174448)
			(xy 132.99661 -238.182206) (xy 133.048909 -238.197563) (xy 133.098489 -238.220206) (xy 133.144342 -238.249675)
			(xy 133.185535 -238.285369) (xy 133.221229 -238.326563) (xy 133.250697 -238.372416) (xy 133.273339 -238.421997)
			(xy 133.288695 -238.474295) (xy 133.296452 -238.528247) (xy 133.296452 -238.582753) (xy 133.288695 -238.636705)
			(xy 133.273339 -238.689003) (xy 133.250697 -238.738584) (xy 133.221229 -238.784437) (xy 133.185535 -238.825631)
			(xy 133.144342 -238.861325) (xy 133.098489 -238.890794) (xy 133.048909 -238.913437) (xy 132.99661 -238.928794)
			(xy 132.942659 -238.936552) (xy 132.915406 -238.937038) (xy 132.889286 -238.93662) (xy 132.837534 -238.929485)
			(xy 132.787238 -238.915363) (xy 132.739337 -238.894515) (xy 132.694725 -238.867333) (xy 132.654235 -238.834322)
			(xy 132.618624 -238.7961) (xy 132.60324 -238.774986) (xy 132.594777 -238.763638) (xy 132.572766 -238.745848)
			(xy 132.546717 -238.734783) (xy 132.518631 -238.731292) (xy 132.490666 -238.735644) (xy 132.464969 -238.747504)
			(xy 132.443515 -238.765962) (xy 132.435346 -238.777526) (xy 132.420108 -238.799703) (xy 132.384443 -238.839991)
			(xy 132.34347 -238.874865) (xy 132.298001 -238.903634) (xy 132.248939 -238.925725) (xy 132.197259 -238.9407)
			(xy 132.143987 -238.948261) (xy 132.117084 -238.948722) (xy 132.089835 -238.948207) (xy 132.035891 -238.940449)
			(xy 131.9836 -238.925093) (xy 131.934026 -238.902451) (xy 131.88818 -238.872986) (xy 131.846993 -238.837296)
			(xy 131.811305 -238.796107) (xy 131.781841 -238.75026) (xy 131.759202 -238.700685) (xy 131.743848 -238.648394)
			(xy 131.736092 -238.594449) (xy 131.506979 -238.594449) (xy 131.501903 -238.62894) (xy 131.485835 -238.682347)
			(xy 131.462163 -238.732844) (xy 131.43139 -238.779357) (xy 131.394173 -238.820894) (xy 131.351305 -238.856569)
			(xy 131.303699 -238.885623) (xy 131.25237 -238.907435) (xy 131.198413 -238.921541) (xy 131.142976 -238.927641)
			(xy 131.087242 -238.925604) (xy 131.032399 -238.915474) (xy 130.979615 -238.897467) (xy 130.930015 -238.871966)
			(xy 130.884657 -238.839515) (xy 130.844508 -238.800806) (xy 130.810422 -238.756663) (xy 130.783126 -238.708028)
			(xy 130.763203 -238.655937) (xy 130.751077 -238.6015) (xy 130.747006 -238.545878) (xy 125.238869 -238.545878)
			(xy 125.228461 -238.581321) (xy 125.205814 -238.630908) (xy 125.17634 -238.676767) (xy 125.140639 -238.717965)
			(xy 125.099438 -238.753662) (xy 125.053577 -238.783131) (xy 125.003988 -238.805774) (xy 124.951681 -238.821128)
			(xy 124.897721 -238.828882) (xy 124.870464 -238.829342) (xy 124.843916 -238.828858) (xy 124.791332 -238.821498)
			(xy 124.740278 -238.806912) (xy 124.691743 -238.785382) (xy 124.646665 -238.757325) (xy 124.605916 -238.723284)
			(xy 124.570287 -238.683917) (xy 124.554996 -238.66221) (xy 124.5463 -238.650277) (xy 124.523398 -238.631657)
			(xy 124.496133 -238.620352) (xy 124.466774 -238.617304) (xy 124.437768 -238.622765) (xy 124.411529 -238.636283)
			(xy 124.390242 -238.65673) (xy 124.38253 -238.669322) (xy 124.367924 -238.694128) (xy 124.332359 -238.739392)
			(xy 124.290397 -238.778798) (xy 124.24299 -238.811452) (xy 124.191215 -238.836612) (xy 124.136247 -238.853707)
			(xy 124.079334 -238.862349) (xy 124.050552 -238.86287) (xy 124.0233 -238.862457) (xy 123.969352 -238.854694)
			(xy 123.917058 -238.839333) (xy 123.867482 -238.816687) (xy 123.821633 -238.787217) (xy 123.780445 -238.751521)
			(xy 123.744755 -238.710328) (xy 123.71529 -238.664476) (xy 123.69265 -238.614897) (xy 123.677296 -238.562601)
			(xy 123.66954 -238.508652) (xy 108.359276 -238.508652) (xy 108.361766 -238.525876) (xy 108.362242 -238.553244)
			(xy 108.361756 -238.580495) (xy 108.354 -238.634443) (xy 108.338645 -238.686738) (xy 108.316003 -238.736315)
			(xy 108.286537 -238.782165) (xy 108.250846 -238.823356) (xy 108.209655 -238.859047) (xy 108.163805 -238.888513)
			(xy 108.114228 -238.911155) (xy 108.061933 -238.92651) (xy 108.007985 -238.934266) (xy 107.953483 -238.934266)
			(xy 107.899535 -238.92651) (xy 107.84724 -238.911155) (xy 107.797663 -238.888513) (xy 107.751813 -238.859047)
			(xy 107.710622 -238.823356) (xy 107.674931 -238.782165) (xy 107.645465 -238.736315) (xy 107.622823 -238.686738)
			(xy 107.607468 -238.634443) (xy 107.599712 -238.580495) (xy 107.599226 -238.553244) (xy 106.330242 -238.553244)
			(xy 106.329756 -238.580495) (xy 106.322 -238.634443) (xy 106.306645 -238.686738) (xy 106.284003 -238.736315)
			(xy 106.254537 -238.782165) (xy 106.218846 -238.823356) (xy 106.177655 -238.859047) (xy 106.131805 -238.888513)
			(xy 106.082228 -238.911155) (xy 106.029933 -238.92651) (xy 105.975985 -238.934266) (xy 105.921483 -238.934266)
			(xy 105.867535 -238.92651) (xy 105.81524 -238.911155) (xy 105.765663 -238.888513) (xy 105.719813 -238.859047)
			(xy 105.678622 -238.823356) (xy 105.642931 -238.782165) (xy 105.613465 -238.736315) (xy 105.590823 -238.686738)
			(xy 105.575468 -238.634443) (xy 105.567712 -238.580495) (xy 105.567226 -238.553244) (xy 104.298242 -238.553244)
			(xy 104.297756 -238.580495) (xy 104.29 -238.634443) (xy 104.274645 -238.686738) (xy 104.252003 -238.736315)
			(xy 104.222537 -238.782165) (xy 104.186846 -238.823356) (xy 104.145655 -238.859047) (xy 104.099805 -238.888513)
			(xy 104.050228 -238.911155) (xy 103.997933 -238.92651) (xy 103.943985 -238.934266) (xy 103.889483 -238.934266)
			(xy 103.835535 -238.92651) (xy 103.78324 -238.911155) (xy 103.733663 -238.888513) (xy 103.687813 -238.859047)
			(xy 103.646622 -238.823356) (xy 103.610931 -238.782165) (xy 103.581465 -238.736315) (xy 103.558823 -238.686738)
			(xy 103.543468 -238.634443) (xy 103.535712 -238.580495) (xy 103.535226 -238.553244) (xy 102.266242 -238.553244)
			(xy 102.265756 -238.580495) (xy 102.258 -238.634443) (xy 102.242645 -238.686738) (xy 102.220003 -238.736315)
			(xy 102.190537 -238.782165) (xy 102.154846 -238.823356) (xy 102.113655 -238.859047) (xy 102.067805 -238.888513)
			(xy 102.018228 -238.911155) (xy 101.965933 -238.92651) (xy 101.911985 -238.934266) (xy 101.857483 -238.934266)
			(xy 101.803535 -238.92651) (xy 101.75124 -238.911155) (xy 101.701663 -238.888513) (xy 101.655813 -238.859047)
			(xy 101.614622 -238.823356) (xy 101.578931 -238.782165) (xy 101.549465 -238.736315) (xy 101.526823 -238.686738)
			(xy 101.511468 -238.634443) (xy 101.503712 -238.580495) (xy 101.503226 -238.553244) (xy 99.826941 -238.553244)
			(xy 99.826767 -238.553823) (xy 99.803095 -238.60432) (xy 99.772322 -238.650833) (xy 99.735105 -238.69237)
			(xy 99.692237 -238.728045) (xy 99.644631 -238.757099) (xy 99.593302 -238.778911) (xy 99.539345 -238.793017)
			(xy 99.483908 -238.799117) (xy 99.428174 -238.79708) (xy 99.373331 -238.78695) (xy 99.320547 -238.768943)
			(xy 99.270947 -238.743442) (xy 99.225589 -238.710991) (xy 99.18544 -238.672282) (xy 99.151354 -238.628139)
			(xy 99.124058 -238.579504) (xy 99.104135 -238.527413) (xy 99.092009 -238.472976) (xy 99.087938 -238.417354)
			(xy 94.487223 -238.417354) (xy 94.481951 -238.419764) (xy 94.427209 -238.435862) (xy 94.370734 -238.444009)
			(xy 94.342204 -238.444532) (xy 94.341696 -238.444532) (xy 94.316288 -238.444113) (xy 94.26588 -238.437675)
			(xy 94.216694 -238.424903) (xy 94.169523 -238.406002) (xy 94.147132 -238.393986) (xy 94.139004 -238.389668)
			(xy 94.130368 -238.388398) (xy 94.125877 -238.387752) (xy 94.116806 -238.387886) (xy 94.112334 -238.388652)
			(xy 94.04731 -238.40186) (xy 94.043021 -238.402798) (xy 94.034847 -238.405998) (xy 94.031054 -238.40821)
			(xy 94.02318 -238.413036) (xy 94.017592 -238.420148) (xy 93.999413 -238.442602) (xy 93.957416 -238.482274)
			(xy 93.909916 -238.515158) (xy 93.857999 -238.540501) (xy 93.802854 -238.557723) (xy 93.745742 -238.56643)
			(xy 93.716856 -238.56696) (xy 93.689603 -238.566567) (xy 93.635654 -238.558805) (xy 93.583358 -238.543444)
			(xy 93.53378 -238.520797) (xy 93.487929 -238.491326) (xy 93.446739 -238.45563) (xy 93.411048 -238.414436)
			(xy 93.381582 -238.368582) (xy 93.358941 -238.319001) (xy 93.343586 -238.266703) (xy 93.33583 -238.212753)
			(xy 91.337384 -238.212753) (xy 91.337384 -239.067848) (xy 125.173992 -239.067848) (xy 125.178063 -239.012226)
			(xy 125.190189 -238.957789) (xy 125.210112 -238.905698) (xy 125.237408 -238.857063) (xy 125.271494 -238.81292)
			(xy 125.311643 -238.774211) (xy 125.357001 -238.74176) (xy 125.406601 -238.716259) (xy 125.459385 -238.698252)
			(xy 125.514228 -238.688122) (xy 125.569962 -238.686085) (xy 125.625399 -238.692185) (xy 125.679356 -238.706291)
			(xy 125.730685 -238.728103) (xy 125.778291 -238.757157) (xy 125.821159 -238.792832) (xy 125.858376 -238.834369)
			(xy 125.889149 -238.880882) (xy 125.912821 -238.931379) (xy 125.928889 -238.984786) (xy 125.937009 -239.039962)
			(xy 125.937518 -239.067848) (xy 125.937009 -239.095734) (xy 125.928889 -239.15091) (xy 125.912821 -239.204317)
			(xy 125.889149 -239.254814) (xy 125.858376 -239.301327) (xy 125.821159 -239.342864) (xy 125.778291 -239.378539)
			(xy 125.730685 -239.407593) (xy 125.679356 -239.429405) (xy 125.625399 -239.443511) (xy 125.569962 -239.449611)
			(xy 125.514228 -239.447574) (xy 125.459385 -239.437444) (xy 125.406601 -239.419437) (xy 125.357001 -239.393936)
			(xy 125.311643 -239.361485) (xy 125.271494 -239.322776) (xy 125.237408 -239.278633) (xy 125.210112 -239.229998)
			(xy 125.190189 -239.177907) (xy 125.178063 -239.12347) (xy 125.173992 -239.067848) (xy 91.337384 -239.067848)
			(xy 91.337384 -240.503202) (xy 92.046804 -240.503202) (xy 92.050875 -240.44758) (xy 92.063001 -240.393143)
			(xy 92.082924 -240.341052) (xy 92.11022 -240.292417) (xy 92.144306 -240.248274) (xy 92.184455 -240.209565)
			(xy 92.229813 -240.177114) (xy 92.279413 -240.151613) (xy 92.332197 -240.133606) (xy 92.38704 -240.123476)
			(xy 92.442774 -240.121439) (xy 92.498211 -240.127539) (xy 92.552168 -240.141645) (xy 92.603497 -240.163457)
			(xy 92.651103 -240.192511) (xy 92.693971 -240.228186) (xy 92.731188 -240.269723) (xy 92.761961 -240.316236)
			(xy 92.769373 -240.332048) (xy 93.076806 -240.332048) (xy 93.076806 -240.277552) (xy 93.084561 -240.22361)
			(xy 93.099914 -240.171321) (xy 93.122552 -240.121749) (xy 93.152014 -240.075904) (xy 93.1877 -240.034717)
			(xy 93.228884 -239.999028) (xy 93.274728 -239.969563) (xy 93.324299 -239.946923) (xy 93.376587 -239.931567)
			(xy 93.430528 -239.923808) (xy 93.457776 -239.92332) (xy 93.478713 -239.923605) (xy 93.520336 -239.928187)
			(xy 93.540834 -239.932464) (xy 93.547438 -239.933988) (xy 93.55963 -239.93348) (xy 93.565726 -239.931702)
			(xy 93.571913 -239.929753) (xy 93.5831 -239.923194) (xy 93.587824 -239.918748) (xy 93.64853 -239.858042)
			(xy 93.656404 -239.847882) (xy 93.659452 -239.842548) (xy 93.66123 -239.836452) (xy 93.662778 -239.830344)
			(xy 93.663163 -239.817752) (xy 93.661992 -239.81156) (xy 93.661992 -239.811306) (xy 93.657721 -239.790807)
			(xy 93.653134 -239.749185) (xy 93.652848 -239.728248) (xy 93.653304 -239.70099) (xy 93.661056 -239.647029)
			(xy 93.676409 -239.59472) (xy 93.69905 -239.545129) (xy 93.728519 -239.499265) (xy 93.764215 -239.458061)
			(xy 93.805412 -239.422358) (xy 93.851271 -239.392881) (xy 93.900859 -239.370231) (xy 93.953165 -239.354869)
			(xy 94.007125 -239.347108) (xy 94.06164 -239.347106) (xy 94.115601 -239.354862) (xy 94.167909 -239.370219)
			(xy 94.217498 -239.392865) (xy 94.26336 -239.422337) (xy 94.30456 -239.458037) (xy 94.34026 -239.499237)
			(xy 94.369733 -239.545098) (xy 94.392379 -239.594687) (xy 94.407737 -239.646995) (xy 94.415494 -239.700956)
			(xy 94.415492 -239.755471) (xy 94.407731 -239.809431) (xy 94.39237 -239.861738) (xy 94.369721 -239.911325)
			(xy 94.340244 -239.957185) (xy 94.304542 -239.998382) (xy 94.263339 -240.034079) (xy 94.217475 -240.063548)
			(xy 94.167884 -240.08619) (xy 94.115575 -240.101544) (xy 94.061614 -240.109296) (xy 94.034356 -240.109756)
			(xy 94.013419 -240.109466) (xy 93.971796 -240.104888) (xy 93.951298 -240.100612) (xy 93.944694 -240.099088)
			(xy 93.932502 -240.099596) (xy 93.926406 -240.101374) (xy 93.920224 -240.103337) (xy 93.909034 -240.109887)
			(xy 93.904308 -240.114328) (xy 93.843602 -240.175034) (xy 93.835728 -240.185194) (xy 93.83268 -240.190528)
			(xy 93.830902 -240.196624) (xy 93.829362 -240.202734) (xy 93.828971 -240.215324) (xy 93.83014 -240.221516)
			(xy 93.83014 -240.22177) (xy 93.833073 -240.235594) (xy 93.837139 -240.263563) (xy 93.838268 -240.27765)
			(xy 93.83903 -240.288826) (xy 93.844364 -240.298478) (xy 93.847028 -240.303076) (xy 93.853947 -240.311139)
			(xy 93.85808 -240.31448) (xy 93.919294 -240.360962) (xy 93.923104 -240.363756) (xy 93.926624 -240.365789)
			(xy 93.934149 -240.368857) (xy 93.93809 -240.369852) (xy 93.948758 -240.372392) (xy 93.95968 -240.370106)
			(xy 93.978093 -240.366668) (xy 94.015372 -240.362982) (xy 94.034102 -240.36274) (xy 94.034356 -240.36274)
			(xy 94.061614 -240.363104) (xy 94.115577 -240.370857) (xy 94.167887 -240.386211) (xy 94.217479 -240.408854)
			(xy 94.263343 -240.438324) (xy 94.304546 -240.474023) (xy 94.340249 -240.515222) (xy 94.369725 -240.561083)
			(xy 94.392374 -240.610672) (xy 94.407734 -240.66298) (xy 94.415493 -240.716942) (xy 94.415493 -240.771458)
			(xy 94.413014 -240.788698) (xy 97.371406 -240.788698) (xy 97.375477 -240.733076) (xy 97.387603 -240.678639)
			(xy 97.407526 -240.626548) (xy 97.434822 -240.577913) (xy 97.468908 -240.53377) (xy 97.509057 -240.495061)
			(xy 97.554415 -240.46261) (xy 97.604015 -240.437109) (xy 97.656799 -240.419102) (xy 97.711642 -240.408972)
			(xy 97.767376 -240.406935) (xy 97.822813 -240.413035) (xy 97.87677 -240.427141) (xy 97.928099 -240.448953)
			(xy 97.975705 -240.478007) (xy 98.018573 -240.513682) (xy 98.05579 -240.555219) (xy 98.086563 -240.601732)
			(xy 98.110235 -240.652229) (xy 98.126303 -240.705636) (xy 98.134423 -240.760812) (xy 98.134932 -240.788698)
			(xy 98.134423 -240.816584) (xy 98.126303 -240.87176) (xy 98.110235 -240.925167) (xy 98.108839 -240.928144)
			(xy 101.89972 -240.928144) (xy 101.900206 -240.900893) (xy 101.907962 -240.846945) (xy 101.923317 -240.79465)
			(xy 101.945959 -240.745073) (xy 101.975425 -240.699223) (xy 102.011116 -240.658032) (xy 102.052307 -240.622341)
			(xy 102.098157 -240.592875) (xy 102.147734 -240.570233) (xy 102.200029 -240.554878) (xy 102.253977 -240.547122)
			(xy 102.308479 -240.547122) (xy 102.362427 -240.554878) (xy 102.414722 -240.570233) (xy 102.464299 -240.592875)
			(xy 102.510149 -240.622341) (xy 102.55134 -240.658032) (xy 102.587031 -240.699223) (xy 102.616497 -240.745073)
			(xy 102.639139 -240.79465) (xy 102.654494 -240.846945) (xy 102.66225 -240.900893) (xy 102.662736 -240.928144)
			(xy 102.66227 -240.954485) (xy 102.655022 -241.006665) (xy 102.640668 -241.057354) (xy 102.619482 -241.105587)
			(xy 102.591866 -241.15045) (xy 102.558344 -241.191091) (xy 102.519554 -241.226737) (xy 102.498144 -241.242088)
			(xy 102.486333 -241.250801) (xy 102.467897 -241.273622) (xy 102.456711 -241.300744) (xy 102.453701 -241.329927)
			(xy 102.459115 -241.35876) (xy 102.472506 -241.384864) (xy 102.492768 -241.406081) (xy 102.505256 -241.413792)
			(xy 102.529804 -241.428466) (xy 102.574559 -241.464075) (xy 102.613499 -241.505963) (xy 102.645752 -241.553193)
			(xy 102.670595 -241.604707) (xy 102.687474 -241.659352) (xy 102.696008 -241.715904) (xy 102.696518 -241.7445)
			(xy 102.696032 -241.771751) (xy 102.688276 -241.825699) (xy 102.672921 -241.877994) (xy 102.650279 -241.927571)
			(xy 102.620813 -241.973421) (xy 102.620354 -241.973951) (xy 120.012962 -241.973951) (xy 120.012962 -241.919449)
			(xy 120.020718 -241.865502) (xy 120.036072 -241.813207) (xy 120.058712 -241.76363) (xy 120.088176 -241.71778)
			(xy 120.123866 -241.676588) (xy 120.165054 -241.640895) (xy 120.210902 -241.611427) (xy 120.260477 -241.588783)
			(xy 120.312771 -241.573425) (xy 120.366717 -241.565664) (xy 120.393968 -241.565176) (xy 120.422514 -241.56573)
			(xy 120.478967 -241.574244) (xy 120.533522 -241.59107) (xy 120.584963 -241.615835) (xy 120.608852 -241.63147)
			(xy 120.616726 -241.636804) (xy 120.625362 -241.638836) (xy 120.62979 -241.639882) (xy 120.638865 -241.640516)
			(xy 120.643396 -241.640106) (xy 120.709944 -241.631978) (xy 120.714514 -241.631368) (xy 120.723331 -241.628676)
			(xy 120.72747 -241.626644) (xy 120.73509 -241.62258) (xy 120.74144 -241.615468) (xy 120.759642 -241.596066)
			(xy 120.800453 -241.561942) (xy 120.845605 -241.533814) (xy 120.894224 -241.512224) (xy 120.94537 -241.497593)
			(xy 120.998051 -241.490202) (xy 121.02465 -241.489738) (xy 121.050587 -241.490183) (xy 121.101982 -241.497206)
			(xy 121.151952 -241.511129) (xy 121.199574 -241.531696) (xy 121.24397 -241.558526) (xy 121.28432 -241.591126)
			(xy 121.31988 -241.628893) (xy 121.335292 -241.649758) (xy 121.339102 -241.655092) (xy 121.348246 -241.662966)
			(xy 121.353326 -241.665506) (xy 121.358982 -241.668207) (xy 121.371189 -241.671035) (xy 121.377456 -241.671094)
			(xy 121.46153 -241.669316) (xy 121.473976 -241.667538) (xy 121.479818 -241.666014) (xy 121.484898 -241.66322)
			(xy 121.490154 -241.660059) (xy 121.499147 -241.651724) (xy 121.502678 -241.64671) (xy 121.502932 -241.64671)
			(xy 121.502932 -241.646202) (xy 121.518167 -241.623958) (xy 121.553867 -241.583557) (xy 121.594896 -241.548582)
			(xy 121.640439 -241.519728) (xy 121.689589 -241.49757) (xy 121.741368 -241.482548) (xy 121.794745 -241.474962)
			(xy 121.821702 -241.474498) (xy 121.848954 -241.474972) (xy 121.902902 -241.482729) (xy 121.955197 -241.498084)
			(xy 122.004775 -241.520726) (xy 122.050626 -241.550193) (xy 122.091817 -241.585885) (xy 122.127508 -241.627076)
			(xy 122.156975 -241.672927) (xy 122.179616 -241.722505) (xy 122.194972 -241.7748) (xy 122.202728 -241.828748)
			(xy 122.202728 -241.846608) (xy 122.461526 -241.846608) (xy 122.465597 -241.790986) (xy 122.477723 -241.736549)
			(xy 122.497646 -241.684458) (xy 122.524942 -241.635823) (xy 122.559028 -241.59168) (xy 122.599177 -241.552971)
			(xy 122.644535 -241.52052) (xy 122.694135 -241.495019) (xy 122.746919 -241.477012) (xy 122.801762 -241.466882)
			(xy 122.857496 -241.464845) (xy 122.912933 -241.470945) (xy 122.96689 -241.485051) (xy 123.018219 -241.506863)
			(xy 123.065825 -241.535917) (xy 123.108693 -241.571592) (xy 123.14591 -241.613129) (xy 123.176683 -241.659642)
			(xy 123.200355 -241.710139) (xy 123.216423 -241.763546) (xy 123.224543 -241.818722) (xy 123.225052 -241.846608)
			(xy 123.22488 -241.856006) (xy 130.399026 -241.856006) (xy 130.403097 -241.800384) (xy 130.415223 -241.745947)
			(xy 130.435146 -241.693856) (xy 130.462442 -241.645221) (xy 130.496528 -241.601078) (xy 130.536677 -241.562369)
			(xy 130.582035 -241.529918) (xy 130.631635 -241.504417) (xy 130.684419 -241.48641) (xy 130.739262 -241.47628)
			(xy 130.794996 -241.474243) (xy 130.850433 -241.480343) (xy 130.90439 -241.494449) (xy 130.955719 -241.516261)
			(xy 131.003325 -241.545315) (xy 131.046193 -241.58099) (xy 131.08341 -241.622527) (xy 131.114183 -241.66904)
			(xy 131.137855 -241.719537) (xy 131.153923 -241.772944) (xy 131.162043 -241.82812) (xy 131.162552 -241.856006)
			(xy 131.162043 -241.883892) (xy 131.159253 -241.902852) (xy 132.042642 -241.902852) (xy 132.042642 -241.848348)
			(xy 132.050398 -241.794398) (xy 132.065753 -241.742102) (xy 132.088393 -241.692522) (xy 132.117859 -241.64667)
			(xy 132.153549 -241.605476) (xy 132.194739 -241.569782) (xy 132.240589 -241.540311) (xy 132.290166 -241.517666)
			(xy 132.342461 -241.502306) (xy 132.39641 -241.494544) (xy 132.423662 -241.494056) (xy 132.453273 -241.494618)
			(xy 132.511781 -241.503784) (xy 132.568174 -241.52187) (xy 132.6211 -241.548444) (xy 132.669289 -241.582868)
			(xy 132.711588 -241.624318) (xy 132.729732 -241.647726) (xy 132.733034 -241.652552) (xy 132.742432 -241.660426)
			(xy 132.747512 -241.662966) (xy 132.750845 -241.664549) (xy 132.757858 -241.666845) (xy 132.761482 -241.667538)
			(xy 132.770626 -241.6683) (xy 132.852922 -241.667538) (xy 132.858798 -241.667282) (xy 132.870215 -241.664471)
			(xy 132.875528 -241.66195) (xy 132.880862 -241.65941) (xy 132.889752 -241.65179) (xy 132.893308 -241.64671)
			(xy 132.909448 -241.625158) (xy 132.946646 -241.586227) (xy 132.988736 -241.552644) (xy 133.034954 -241.525019)
			(xy 133.084464 -241.503852) (xy 133.136369 -241.489526) (xy 133.189727 -241.482301) (xy 133.21665 -241.481864)
			(xy 133.246752 -241.482422) (xy 133.306274 -241.491469) (xy 133.363767 -241.509335) (xy 133.417932 -241.535616)
			(xy 133.467546 -241.56972) (xy 133.511488 -241.610875) (xy 133.548764 -241.658152) (xy 133.564122 -241.684048)
			(xy 133.567424 -241.690144) (xy 133.577076 -241.699796) (xy 133.582664 -241.702844) (xy 133.588695 -241.70612)
			(xy 133.601964 -241.709603) (xy 133.608826 -241.709702) (xy 133.698742 -241.707924) (xy 133.705578 -241.707555)
			(xy 133.718708 -241.703702) (xy 133.72465 -241.700304) (xy 133.729984 -241.697002) (xy 133.739382 -241.686842)
			(xy 133.74243 -241.680492) (xy 133.754787 -241.657529) (xy 133.784866 -241.614932) (xy 133.820465 -241.576827)
			(xy 133.860922 -241.543925) (xy 133.905482 -241.516838) (xy 133.953315 -241.49607) (xy 134.00353 -241.48201)
			(xy 134.055193 -241.474918) (xy 134.081266 -241.474498) (xy 134.108521 -241.474947) (xy 134.162476 -241.4827)
			(xy 134.214779 -241.498054) (xy 134.264364 -241.520694) (xy 134.310222 -241.550162) (xy 134.35142 -241.585856)
			(xy 134.387118 -241.62705) (xy 134.416589 -241.672906) (xy 134.439235 -241.722489) (xy 134.454593 -241.77479)
			(xy 134.462351 -241.828745) (xy 134.462351 -241.883255) (xy 134.454593 -241.93721) (xy 134.439235 -241.989511)
			(xy 134.416589 -242.039094) (xy 134.387118 -242.08495) (xy 134.35142 -242.126144) (xy 134.310222 -242.161838)
			(xy 134.264364 -242.191306) (xy 134.214779 -242.213946) (xy 134.162476 -242.2293) (xy 134.108521 -242.237053)
			(xy 134.081266 -242.237514) (xy 134.053098 -242.237017) (xy 133.997377 -242.228715) (xy 133.943482 -242.212312)
			(xy 133.892584 -242.188165) (xy 133.845789 -242.156796) (xy 133.804114 -242.11889) (xy 133.768464 -242.075268)
			(xy 133.753606 -242.051332) (xy 133.749796 -242.044982) (xy 133.740144 -242.035838) (xy 133.734556 -242.03279)
			(xy 133.730314 -242.030605) (xy 133.72124 -242.027658) (xy 133.716522 -242.026948) (xy 133.707632 -242.02644)
			(xy 133.618224 -242.03025) (xy 133.604762 -242.032536) (xy 133.598666 -242.034568) (xy 133.593078 -242.038124)
			(xy 133.587518 -242.042034) (xy 133.578496 -242.052193) (xy 133.575298 -242.05819) (xy 133.575044 -242.05819)
			(xy 133.575044 -242.058444) (xy 133.562354 -242.083192) (xy 133.531102 -242.129197) (xy 133.49377 -242.170422)
			(xy 133.45108 -242.20607) (xy 133.403857 -242.23545) (xy 133.353015 -242.257996) (xy 133.299538 -242.273271)
			(xy 133.244458 -242.280979) (xy 133.21665 -242.281456) (xy 133.189287 -242.281011) (xy 133.135077 -242.273524)
			(xy 133.082394 -242.258711) (xy 133.032226 -242.236848) (xy 132.98551 -242.208344) (xy 132.943119 -242.173734)
			(xy 132.905847 -242.133663) (xy 132.889752 -242.11153) (xy 132.889498 -242.111022) (xy 132.886029 -242.106465)
			(xy 132.877445 -242.09889) (xy 132.87248 -242.096036) (xy 132.867089 -242.093303) (xy 132.855403 -242.090229)
			(xy 132.849366 -242.08994) (xy 132.767324 -242.088162) (xy 132.761345 -242.088235) (xy 132.74967 -242.090803)
			(xy 132.74421 -242.093242) (xy 132.73913 -242.095782) (xy 132.729986 -242.103148) (xy 132.726176 -242.108228)
			(xy 132.70795 -242.130936) (xy 132.665832 -242.171138) (xy 132.6181 -242.20448) (xy 132.56586 -242.23019)
			(xy 132.510322 -242.247672) (xy 132.452774 -242.25652) (xy 132.423662 -242.257072) (xy 132.39641 -242.256656)
			(xy 132.342461 -242.248894) (xy 132.290166 -242.233534) (xy 132.240589 -242.210889) (xy 132.194739 -242.181418)
			(xy 132.153549 -242.145724) (xy 132.117859 -242.10453) (xy 132.088393 -242.058678) (xy 132.065753 -242.009098)
			(xy 132.050398 -241.956802) (xy 132.042642 -241.902852) (xy 131.159253 -241.902852) (xy 131.153923 -241.939068)
			(xy 131.137855 -241.992475) (xy 131.114183 -242.042972) (xy 131.08341 -242.089485) (xy 131.046193 -242.131022)
			(xy 131.003325 -242.166697) (xy 130.955719 -242.195751) (xy 130.90439 -242.217563) (xy 130.850433 -242.231669)
			(xy 130.794996 -242.237769) (xy 130.739262 -242.235732) (xy 130.684419 -242.225602) (xy 130.631635 -242.207595)
			(xy 130.582035 -242.182094) (xy 130.536677 -242.149643) (xy 130.496528 -242.110934) (xy 130.462442 -242.066791)
			(xy 130.435146 -242.018156) (xy 130.415223 -241.966065) (xy 130.403097 -241.911628) (xy 130.399026 -241.856006)
			(xy 123.22488 -241.856006) (xy 123.224543 -241.874494) (xy 123.216423 -241.92967) (xy 123.200355 -241.983077)
			(xy 123.176683 -242.033574) (xy 123.14591 -242.080087) (xy 123.108693 -242.121624) (xy 123.065825 -242.157299)
			(xy 123.018219 -242.186353) (xy 122.96689 -242.208165) (xy 122.912933 -242.222271) (xy 122.857496 -242.228371)
			(xy 122.801762 -242.226334) (xy 122.746919 -242.216204) (xy 122.694135 -242.198197) (xy 122.644535 -242.172696)
			(xy 122.599177 -242.140245) (xy 122.559028 -242.101536) (xy 122.524942 -242.057393) (xy 122.497646 -242.008758)
			(xy 122.477723 -241.956667) (xy 122.465597 -241.90223) (xy 122.461526 -241.846608) (xy 122.202728 -241.846608)
			(xy 122.202728 -241.883252) (xy 122.194972 -241.9372) (xy 122.179616 -241.989495) (xy 122.156975 -242.039073)
			(xy 122.127508 -242.084924) (xy 122.091817 -242.126115) (xy 122.050626 -242.161807) (xy 122.004775 -242.191274)
			(xy 121.955197 -242.213916) (xy 121.902902 -242.229271) (xy 121.848954 -242.237028) (xy 121.821702 -242.237514)
			(xy 121.795765 -242.237083) (xy 121.74437 -242.230055) (xy 121.6944 -242.216127) (xy 121.646779 -242.195558)
			(xy 121.602384 -242.168726) (xy 121.562034 -242.136126) (xy 121.526473 -242.098359) (xy 121.51106 -242.077494)
			(xy 121.50725 -242.07216) (xy 121.498106 -242.064286) (xy 121.493026 -242.061746) (xy 121.487375 -242.059033)
			(xy 121.475165 -242.056211) (xy 121.468896 -242.056158) (xy 121.384822 -242.057936) (xy 121.372376 -242.059714)
			(xy 121.366534 -242.061238) (xy 121.361454 -242.064032) (xy 121.356184 -242.067172) (xy 121.3472 -242.075521)
			(xy 121.343674 -242.080542) (xy 121.34342 -242.080542) (xy 121.34342 -242.08105) (xy 121.328233 -242.103328)
			(xy 121.292523 -242.143726) (xy 121.251485 -242.178697) (xy 121.205934 -242.207546) (xy 121.156777 -242.229698)
			(xy 121.104992 -242.244714) (xy 121.051609 -242.252293) (xy 121.02465 -242.252754) (xy 120.996104 -242.252203)
			(xy 120.93965 -242.243691) (xy 120.885095 -242.226863) (xy 120.833654 -242.202097) (xy 120.809766 -242.18646)
			(xy 120.801892 -242.181126) (xy 120.793256 -242.179094) (xy 120.788827 -242.178053) (xy 120.779753 -242.177415)
			(xy 120.775222 -242.177824) (xy 120.708674 -242.185952) (xy 120.704106 -242.186572) (xy 120.695288 -242.189257)
			(xy 120.691148 -242.191286) (xy 120.683528 -242.19535) (xy 120.677178 -242.202462) (xy 120.658974 -242.221861)
			(xy 120.618163 -242.255984) (xy 120.573011 -242.284113) (xy 120.524392 -242.305702) (xy 120.473247 -242.320335)
			(xy 120.420566 -242.327727) (xy 120.393968 -242.328192) (xy 120.366717 -242.327736) (xy 120.312771 -242.319975)
			(xy 120.260477 -242.304617) (xy 120.210902 -242.281973) (xy 120.165054 -242.252505) (xy 120.123866 -242.216812)
			(xy 120.088176 -242.17562) (xy 120.058712 -242.12977) (xy 120.036072 -242.080193) (xy 120.020718 -242.027898)
			(xy 120.012962 -241.973951) (xy 102.620354 -241.973951) (xy 102.585122 -242.014612) (xy 102.543931 -242.050303)
			(xy 102.498081 -242.079769) (xy 102.448504 -242.102411) (xy 102.396209 -242.117766) (xy 102.342261 -242.125522)
			(xy 102.287759 -242.125522) (xy 102.233811 -242.117766) (xy 102.181516 -242.102411) (xy 102.131939 -242.079769)
			(xy 102.086089 -242.050303) (xy 102.044898 -242.014612) (xy 102.009207 -241.973421) (xy 101.979741 -241.927571)
			(xy 101.957099 -241.877994) (xy 101.941744 -241.825699) (xy 101.933988 -241.771751) (xy 101.933502 -241.7445)
			(xy 101.933909 -241.718157) (xy 101.941166 -241.665973) (xy 101.955529 -241.615283) (xy 101.976724 -241.567048)
			(xy 102.00435 -241.522186) (xy 102.03788 -241.481548) (xy 102.07668 -241.445905) (xy 102.098094 -241.430556)
			(xy 102.109855 -241.421783) (xy 102.128283 -241.398974) (xy 102.139466 -241.371867) (xy 102.14248 -241.342699)
			(xy 102.137077 -241.313877) (xy 102.123702 -241.287782) (xy 102.10346 -241.266566) (xy 102.090982 -241.258852)
			(xy 102.066462 -241.244133) (xy 102.021705 -241.208533) (xy 101.982763 -241.166653) (xy 101.950506 -241.119431)
			(xy 101.925658 -241.067923) (xy 101.908774 -241.013285) (xy 101.900233 -240.956738) (xy 101.89972 -240.928144)
			(xy 98.108839 -240.928144) (xy 98.086563 -240.975664) (xy 98.05579 -241.022177) (xy 98.018573 -241.063714)
			(xy 97.975705 -241.099389) (xy 97.928099 -241.128443) (xy 97.87677 -241.150255) (xy 97.822813 -241.164361)
			(xy 97.767376 -241.170461) (xy 97.711642 -241.168424) (xy 97.656799 -241.158294) (xy 97.604015 -241.140287)
			(xy 97.554415 -241.114786) (xy 97.509057 -241.082335) (xy 97.468908 -241.043626) (xy 97.434822 -240.999483)
			(xy 97.407526 -240.950848) (xy 97.387603 -240.898757) (xy 97.375477 -240.84432) (xy 97.371406 -240.788698)
			(xy 94.413014 -240.788698) (xy 94.407734 -240.82542) (xy 94.392374 -240.877728) (xy 94.369725 -240.927317)
			(xy 94.340249 -240.973178) (xy 94.304546 -241.014377) (xy 94.263343 -241.050076) (xy 94.217479 -241.079546)
			(xy 94.167887 -241.102189) (xy 94.115577 -241.117543) (xy 94.061614 -241.125296) (xy 94.034356 -241.125756)
			(xy 94.005742 -241.125194) (xy 93.949156 -241.116639) (xy 93.894483 -241.099729) (xy 93.842949 -241.074842)
			(xy 93.795711 -241.042537) (xy 93.753827 -241.003539) (xy 93.718239 -240.958722) (xy 93.689743 -240.909092)
			(xy 93.668981 -240.855763) (xy 93.656416 -240.799931) (xy 93.653864 -240.771426) (xy 93.653102 -240.76025)
			(xy 93.647768 -240.750598) (xy 93.645103 -240.746) (xy 93.638184 -240.737937) (xy 93.634052 -240.734596)
			(xy 93.572838 -240.688114) (xy 93.569028 -240.68532) (xy 93.565517 -240.683272) (xy 93.557985 -240.680213)
			(xy 93.554042 -240.679224) (xy 93.543374 -240.676684) (xy 93.532452 -240.67897) (xy 93.514038 -240.682403)
			(xy 93.47676 -240.686093) (xy 93.45803 -240.686336) (xy 93.457776 -240.686336) (xy 93.430528 -240.685792)
			(xy 93.376587 -240.678033) (xy 93.324299 -240.662677) (xy 93.274728 -240.640037) (xy 93.228884 -240.610572)
			(xy 93.1877 -240.574883) (xy 93.152014 -240.533696) (xy 93.122552 -240.487851) (xy 93.099914 -240.438279)
			(xy 93.084561 -240.38599) (xy 93.076806 -240.332048) (xy 92.769373 -240.332048) (xy 92.785633 -240.366733)
			(xy 92.801701 -240.42014) (xy 92.809821 -240.475316) (xy 92.81033 -240.503202) (xy 92.809821 -240.531088)
			(xy 92.801701 -240.586264) (xy 92.785633 -240.639671) (xy 92.761961 -240.690168) (xy 92.731188 -240.736681)
			(xy 92.693971 -240.778218) (xy 92.651103 -240.813893) (xy 92.603497 -240.842947) (xy 92.552168 -240.864759)
			(xy 92.498211 -240.878865) (xy 92.442774 -240.884965) (xy 92.38704 -240.882928) (xy 92.332197 -240.872798)
			(xy 92.279413 -240.854791) (xy 92.229813 -240.82929) (xy 92.184455 -240.796839) (xy 92.144306 -240.75813)
			(xy 92.11022 -240.713987) (xy 92.082924 -240.665352) (xy 92.063001 -240.613261) (xy 92.050875 -240.558824)
			(xy 92.046804 -240.503202) (xy 91.337384 -240.503202) (xy 91.337384 -241.242596) (xy 96.119694 -241.242596)
			(xy 96.123765 -241.186974) (xy 96.135891 -241.132537) (xy 96.155814 -241.080446) (xy 96.18311 -241.031811)
			(xy 96.217196 -240.987668) (xy 96.257345 -240.948959) (xy 96.302703 -240.916508) (xy 96.352303 -240.891007)
			(xy 96.405087 -240.873) (xy 96.45993 -240.86287) (xy 96.515664 -240.860833) (xy 96.571101 -240.866933)
			(xy 96.625058 -240.881039) (xy 96.676387 -240.902851) (xy 96.723993 -240.931905) (xy 96.766861 -240.96758)
			(xy 96.804078 -241.009117) (xy 96.834851 -241.05563) (xy 96.858523 -241.106127) (xy 96.874591 -241.159534)
			(xy 96.882711 -241.21471) (xy 96.88322 -241.242596) (xy 96.882711 -241.270482) (xy 96.874591 -241.325658)
			(xy 96.858523 -241.379065) (xy 96.834851 -241.429562) (xy 96.804078 -241.476075) (xy 96.766861 -241.517612)
			(xy 96.723993 -241.553287) (xy 96.676387 -241.582341) (xy 96.625058 -241.604153) (xy 96.571101 -241.618259)
			(xy 96.515664 -241.624359) (xy 96.45993 -241.622322) (xy 96.405087 -241.612192) (xy 96.352303 -241.594185)
			(xy 96.302703 -241.568684) (xy 96.257345 -241.536233) (xy 96.217196 -241.497524) (xy 96.18311 -241.453381)
			(xy 96.155814 -241.404746) (xy 96.135891 -241.352655) (xy 96.123765 -241.298218) (xy 96.119694 -241.242596)
			(xy 91.337384 -241.242596) (xy 91.337384 -242.239546) (xy 93.623636 -242.239546) (xy 93.627707 -242.183924)
			(xy 93.639833 -242.129487) (xy 93.659756 -242.077396) (xy 93.687052 -242.028761) (xy 93.721138 -241.984618)
			(xy 93.761287 -241.945909) (xy 93.806645 -241.913458) (xy 93.856245 -241.887957) (xy 93.909029 -241.86995)
			(xy 93.963872 -241.85982) (xy 94.019606 -241.857783) (xy 94.075043 -241.863883) (xy 94.129 -241.877989)
			(xy 94.180329 -241.899801) (xy 94.227935 -241.928855) (xy 94.270803 -241.96453) (xy 94.30802 -242.006067)
			(xy 94.338793 -242.05258) (xy 94.362465 -242.103077) (xy 94.378533 -242.156484) (xy 94.386653 -242.21166)
			(xy 94.387162 -242.239546) (xy 94.386653 -242.267432) (xy 94.378533 -242.322608) (xy 94.362465 -242.376015)
			(xy 94.338793 -242.426512) (xy 94.30802 -242.473025) (xy 94.270803 -242.514562) (xy 94.227935 -242.550237)
			(xy 94.180329 -242.579291) (xy 94.129 -242.601103) (xy 94.075043 -242.615209) (xy 94.019606 -242.621309)
			(xy 93.963872 -242.619272) (xy 93.909029 -242.609142) (xy 93.856245 -242.591135) (xy 93.806645 -242.565634)
			(xy 93.761287 -242.533183) (xy 93.721138 -242.494474) (xy 93.687052 -242.450331) (xy 93.659756 -242.401696)
			(xy 93.639833 -242.349605) (xy 93.627707 -242.295168) (xy 93.623636 -242.239546) (xy 91.337384 -242.239546)
			(xy 91.337384 -242.987322) (xy 95.946212 -242.987322) (xy 95.950283 -242.9317) (xy 95.962409 -242.877263)
			(xy 95.982332 -242.825172) (xy 96.009628 -242.776537) (xy 96.043714 -242.732394) (xy 96.083863 -242.693685)
			(xy 96.129221 -242.661234) (xy 96.178821 -242.635733) (xy 96.231605 -242.617726) (xy 96.286448 -242.607596)
			(xy 96.342182 -242.605559) (xy 96.397619 -242.611659) (xy 96.451576 -242.625765) (xy 96.502905 -242.647577)
			(xy 96.523955 -242.660424) (xy 97.53803 -242.660424) (xy 97.542101 -242.604802) (xy 97.554227 -242.550365)
			(xy 97.57415 -242.498274) (xy 97.601446 -242.449639) (xy 97.635532 -242.405496) (xy 97.675681 -242.366787)
			(xy 97.721039 -242.334336) (xy 97.770639 -242.308835) (xy 97.823423 -242.290828) (xy 97.878266 -242.280698)
			(xy 97.934 -242.278661) (xy 97.989437 -242.284761) (xy 98.043394 -242.298867) (xy 98.094723 -242.320679)
			(xy 98.142329 -242.349733) (xy 98.185197 -242.385408) (xy 98.222414 -242.426945) (xy 98.253187 -242.473458)
			(xy 98.276859 -242.523955) (xy 98.292927 -242.577362) (xy 98.301047 -242.632538) (xy 98.301352 -242.649248)
			(xy 98.716082 -242.649248) (xy 98.720153 -242.593626) (xy 98.732279 -242.539189) (xy 98.752202 -242.487098)
			(xy 98.779498 -242.438463) (xy 98.813584 -242.39432) (xy 98.853733 -242.355611) (xy 98.899091 -242.32316)
			(xy 98.948691 -242.297659) (xy 99.001475 -242.279652) (xy 99.056318 -242.269522) (xy 99.112052 -242.267485)
			(xy 99.167489 -242.273585) (xy 99.221446 -242.287691) (xy 99.272775 -242.309503) (xy 99.320381 -242.338557)
			(xy 99.363249 -242.374232) (xy 99.400466 -242.415769) (xy 99.431239 -242.462282) (xy 99.454911 -242.512779)
			(xy 99.470979 -242.566186) (xy 99.479099 -242.621362) (xy 99.479608 -242.649248) (xy 99.479099 -242.677134)
			(xy 99.470979 -242.73231) (xy 99.454911 -242.785717) (xy 99.453873 -242.787932) (xy 100.24821 -242.787932)
			(xy 100.252281 -242.73231) (xy 100.264407 -242.677873) (xy 100.28433 -242.625782) (xy 100.311626 -242.577147)
			(xy 100.345712 -242.533004) (xy 100.385861 -242.494295) (xy 100.431219 -242.461844) (xy 100.480819 -242.436343)
			(xy 100.533603 -242.418336) (xy 100.588446 -242.408206) (xy 100.64418 -242.406169) (xy 100.699617 -242.412269)
			(xy 100.753574 -242.426375) (xy 100.804903 -242.448187) (xy 100.852509 -242.477241) (xy 100.895377 -242.512916)
			(xy 100.932594 -242.554453) (xy 100.963367 -242.600966) (xy 100.987039 -242.651463) (xy 101.003107 -242.70487)
			(xy 101.011227 -242.760046) (xy 101.011736 -242.787932) (xy 101.011227 -242.815818) (xy 101.003107 -242.870994)
			(xy 100.987039 -242.924401) (xy 100.963367 -242.974898) (xy 100.932594 -243.021411) (xy 100.895377 -243.062948)
			(xy 100.852509 -243.098623) (xy 100.804903 -243.127677) (xy 100.753574 -243.149489) (xy 100.699617 -243.163595)
			(xy 100.64418 -243.169695) (xy 100.588446 -243.167658) (xy 100.533603 -243.157528) (xy 100.480819 -243.139521)
			(xy 100.431219 -243.11402) (xy 100.385861 -243.081569) (xy 100.345712 -243.04286) (xy 100.311626 -242.998717)
			(xy 100.28433 -242.950082) (xy 100.264407 -242.897991) (xy 100.252281 -242.843554) (xy 100.24821 -242.787932)
			(xy 99.453873 -242.787932) (xy 99.431239 -242.836214) (xy 99.400466 -242.882727) (xy 99.363249 -242.924264)
			(xy 99.320381 -242.959939) (xy 99.272775 -242.988993) (xy 99.221446 -243.010805) (xy 99.167489 -243.024911)
			(xy 99.112052 -243.031011) (xy 99.056318 -243.028974) (xy 99.001475 -243.018844) (xy 98.948691 -243.000837)
			(xy 98.899091 -242.975336) (xy 98.853733 -242.942885) (xy 98.813584 -242.904176) (xy 98.779498 -242.860033)
			(xy 98.752202 -242.811398) (xy 98.732279 -242.759307) (xy 98.720153 -242.70487) (xy 98.716082 -242.649248)
			(xy 98.301352 -242.649248) (xy 98.301556 -242.660424) (xy 98.301047 -242.68831) (xy 98.292927 -242.743486)
			(xy 98.276859 -242.796893) (xy 98.253187 -242.84739) (xy 98.222414 -242.893903) (xy 98.185197 -242.93544)
			(xy 98.142329 -242.971115) (xy 98.094723 -243.000169) (xy 98.043394 -243.021981) (xy 97.989437 -243.036087)
			(xy 97.934 -243.042187) (xy 97.878266 -243.04015) (xy 97.823423 -243.03002) (xy 97.770639 -243.012013)
			(xy 97.721039 -242.986512) (xy 97.675681 -242.954061) (xy 97.635532 -242.915352) (xy 97.601446 -242.871209)
			(xy 97.57415 -242.822574) (xy 97.554227 -242.770483) (xy 97.542101 -242.716046) (xy 97.53803 -242.660424)
			(xy 96.523955 -242.660424) (xy 96.550511 -242.676631) (xy 96.593379 -242.712306) (xy 96.630596 -242.753843)
			(xy 96.661369 -242.800356) (xy 96.685041 -242.850853) (xy 96.701109 -242.90426) (xy 96.709229 -242.959436)
			(xy 96.709738 -242.987322) (xy 96.709229 -243.015208) (xy 96.701109 -243.070384) (xy 96.685041 -243.123791)
			(xy 96.661369 -243.174288) (xy 96.630596 -243.220801) (xy 96.593379 -243.262338) (xy 96.550511 -243.298013)
			(xy 96.502905 -243.327067) (xy 96.451576 -243.348879) (xy 96.397619 -243.362985) (xy 96.342182 -243.369085)
			(xy 96.286448 -243.367048) (xy 96.231605 -243.356918) (xy 96.178821 -243.338911) (xy 96.129221 -243.31341)
			(xy 96.083863 -243.280959) (xy 96.043714 -243.24225) (xy 96.009628 -243.198107) (xy 95.982332 -243.149472)
			(xy 95.962409 -243.097381) (xy 95.950283 -243.042944) (xy 95.946212 -242.987322) (xy 91.337384 -242.987322)
			(xy 91.337384 -243.792248) (xy 93.652338 -243.792248) (xy 93.656409 -243.736626) (xy 93.668535 -243.682189)
			(xy 93.688458 -243.630098) (xy 93.715754 -243.581463) (xy 93.74984 -243.53732) (xy 93.789989 -243.498611)
			(xy 93.835347 -243.46616) (xy 93.884947 -243.440659) (xy 93.937731 -243.422652) (xy 93.992574 -243.412522)
			(xy 94.048308 -243.410485) (xy 94.103745 -243.416585) (xy 94.157702 -243.430691) (xy 94.209031 -243.452503)
			(xy 94.256637 -243.481557) (xy 94.299505 -243.517232) (xy 94.336722 -243.558769) (xy 94.367495 -243.605282)
			(xy 94.391167 -243.655779) (xy 94.407235 -243.709186) (xy 94.415355 -243.764362) (xy 94.415864 -243.792248)
			(xy 94.415355 -243.820134) (xy 94.4143 -243.8273) (xy 97.5266 -243.8273) (xy 97.530671 -243.771678)
			(xy 97.542797 -243.717241) (xy 97.56272 -243.66515) (xy 97.590016 -243.616515) (xy 97.624102 -243.572372)
			(xy 97.664251 -243.533663) (xy 97.709609 -243.501212) (xy 97.759209 -243.475711) (xy 97.811993 -243.457704)
			(xy 97.866836 -243.447574) (xy 97.92257 -243.445537) (xy 97.978007 -243.451637) (xy 98.031964 -243.465743)
			(xy 98.083293 -243.487555) (xy 98.130899 -243.516609) (xy 98.173767 -243.552284) (xy 98.210984 -243.593821)
			(xy 98.241757 -243.640334) (xy 98.265429 -243.690831) (xy 98.281497 -243.744238) (xy 98.289617 -243.799414)
			(xy 98.289917 -243.81587) (xy 98.716082 -243.81587) (xy 98.720153 -243.760248) (xy 98.732279 -243.705811)
			(xy 98.752202 -243.65372) (xy 98.779498 -243.605085) (xy 98.813584 -243.560942) (xy 98.853733 -243.522233)
			(xy 98.899091 -243.489782) (xy 98.948691 -243.464281) (xy 99.001475 -243.446274) (xy 99.056318 -243.436144)
			(xy 99.112052 -243.434107) (xy 99.167489 -243.440207) (xy 99.221446 -243.454313) (xy 99.272775 -243.476125)
			(xy 99.320381 -243.505179) (xy 99.363249 -243.540854) (xy 99.400466 -243.582391) (xy 99.431239 -243.628904)
			(xy 99.454911 -243.679401) (xy 99.470783 -243.732157) (xy 101.008827 -243.732157) (xy 101.008827 -243.677643)
			(xy 101.016586 -243.623685) (xy 101.031945 -243.571379) (xy 101.054592 -243.521793) (xy 101.084066 -243.475934)
			(xy 101.119767 -243.434737) (xy 101.160968 -243.399041) (xy 101.20683 -243.369572) (xy 101.256419 -243.34693)
			(xy 101.308726 -243.331577) (xy 101.362685 -243.323824) (xy 101.389942 -243.323364) (xy 101.416936 -243.323799)
			(xy 101.470386 -243.331411) (xy 101.522229 -243.346477) (xy 101.571434 -243.368697) (xy 101.617017 -243.397627)
			(xy 101.637846 -243.414804) (xy 101.645974 -243.421916) (xy 101.656388 -243.424964) (xy 101.657658 -243.425218)
			(xy 101.662509 -243.426453) (xy 101.672488 -243.427226) (xy 101.67747 -243.426742) (xy 101.751638 -243.41709)
			(xy 101.756998 -243.416351) (xy 101.767248 -243.412895) (xy 101.771958 -243.410232) (xy 101.780848 -243.404644)
			(xy 101.786944 -243.396008) (xy 101.787452 -243.3955) (xy 101.805045 -243.371301) (xy 101.846512 -243.328178)
			(xy 101.870002 -243.309648) (xy 101.87813 -243.303552) (xy 101.88321 -243.29517) (xy 101.88568 -243.2908)
			(xy 101.889 -243.281328) (xy 101.889814 -243.276374) (xy 101.899974 -243.205508) (xy 101.900584 -243.200548)
			(xy 101.900065 -243.190569) (xy 101.898958 -243.185696) (xy 101.896672 -243.176552) (xy 101.89083 -243.168424)
			(xy 101.873309 -243.143692) (xy 101.84551 -243.089835) (xy 101.826579 -243.032259) (xy 101.816992 -242.972414)
			(xy 101.816408 -242.94211) (xy 101.816865 -242.914857) (xy 101.824621 -242.860905) (xy 101.839976 -242.808606)
			(xy 101.862619 -242.759025) (xy 101.892087 -242.713171) (xy 101.927782 -242.671977) (xy 101.968975 -242.636284)
			(xy 102.01483 -242.606816) (xy 102.064411 -242.584174) (xy 102.116711 -242.568819) (xy 102.170663 -242.561064)
			(xy 102.197916 -242.560602) (xy 102.223949 -242.561056) (xy 102.275531 -242.568144) (xy 102.325672 -242.582173)
			(xy 102.373443 -242.602882) (xy 102.417959 -242.629887) (xy 102.438454 -242.645946) (xy 102.446074 -242.652296)
			(xy 102.455472 -242.65509) (xy 102.460055 -242.656374) (xy 102.469516 -242.657397) (xy 102.474268 -242.657122)
			(xy 102.544372 -242.651534) (xy 102.54925 -242.651054) (xy 102.558712 -242.648497) (xy 102.563168 -242.646454)
			(xy 102.57155 -242.642136) (xy 102.578154 -242.63477) (xy 102.596347 -242.615136) (xy 102.637251 -242.58061)
			(xy 102.682577 -242.552138) (xy 102.731436 -242.530278) (xy 102.78287 -242.515459) (xy 102.835871 -242.507971)
			(xy 102.862634 -242.507516) (xy 102.889887 -242.507946) (xy 102.943838 -242.515708) (xy 102.996135 -242.531069)
			(xy 103.045714 -242.553716) (xy 103.091566 -242.583188) (xy 103.132756 -242.618885) (xy 103.168447 -242.660081)
			(xy 103.197912 -242.705937) (xy 103.220552 -242.755519) (xy 103.235904 -242.807819) (xy 103.243658 -242.861771)
			(xy 103.244142 -242.889024) (xy 103.243581 -242.917797) (xy 103.234937 -242.974689) (xy 103.217849 -243.029638)
			(xy 103.192704 -243.081399) (xy 103.160072 -243.128797) (xy 103.140764 -243.150136) (xy 103.133144 -243.158264)
			(xy 103.129842 -243.167916) (xy 103.128206 -243.172888) (xy 103.126807 -243.183261) (xy 103.127048 -243.18849)
			(xy 103.133398 -243.274342) (xy 103.138478 -243.283486) (xy 103.141028 -243.287889) (xy 103.147545 -243.295698)
			(xy 103.151432 -243.29898) (xy 103.15194 -243.299488) (xy 103.17115 -243.315236) (xy 127.416558 -243.315236)
			(xy 127.420629 -243.259614) (xy 127.432755 -243.205177) (xy 127.452678 -243.153086) (xy 127.479974 -243.104451)
			(xy 127.51406 -243.060308) (xy 127.554209 -243.021599) (xy 127.599567 -242.989148) (xy 127.649167 -242.963647)
			(xy 127.701951 -242.94564) (xy 127.756794 -242.93551) (xy 127.812528 -242.933473) (xy 127.867965 -242.939573)
			(xy 127.921922 -242.953679) (xy 127.973251 -242.975491) (xy 128.020857 -243.004545) (xy 128.063725 -243.04022)
			(xy 128.100942 -243.081757) (xy 128.131715 -243.12827) (xy 128.155387 -243.178767) (xy 128.171455 -243.232174)
			(xy 128.179575 -243.28735) (xy 128.180084 -243.315236) (xy 128.179575 -243.343122) (xy 128.171455 -243.398298)
			(xy 128.155387 -243.451705) (xy 128.131715 -243.502202) (xy 128.100942 -243.548715) (xy 128.063725 -243.590252)
			(xy 128.037703 -243.611908) (xy 139.886434 -243.611908) (xy 139.890505 -243.556286) (xy 139.902631 -243.501849)
			(xy 139.922554 -243.449758) (xy 139.94985 -243.401123) (xy 139.983936 -243.35698) (xy 140.024085 -243.318271)
			(xy 140.069443 -243.28582) (xy 140.119043 -243.260319) (xy 140.171827 -243.242312) (xy 140.22667 -243.232182)
			(xy 140.282404 -243.230145) (xy 140.337841 -243.236245) (xy 140.391798 -243.250351) (xy 140.443127 -243.272163)
			(xy 140.490733 -243.301217) (xy 140.533601 -243.336892) (xy 140.570818 -243.378429) (xy 140.601591 -243.424942)
			(xy 140.625263 -243.475439) (xy 140.641331 -243.528846) (xy 140.649451 -243.584022) (xy 140.64996 -243.611908)
			(xy 140.649451 -243.639794) (xy 140.641331 -243.69497) (xy 140.625263 -243.748377) (xy 140.601591 -243.798874)
			(xy 140.570818 -243.845387) (xy 140.533601 -243.886924) (xy 140.490733 -243.922599) (xy 140.443127 -243.951653)
			(xy 140.391798 -243.973465) (xy 140.337841 -243.987571) (xy 140.282404 -243.993671) (xy 140.22667 -243.991634)
			(xy 140.171827 -243.981504) (xy 140.119043 -243.963497) (xy 140.069443 -243.937996) (xy 140.024085 -243.905545)
			(xy 139.983936 -243.866836) (xy 139.94985 -243.822693) (xy 139.922554 -243.774058) (xy 139.902631 -243.721967)
			(xy 139.890505 -243.66753) (xy 139.886434 -243.611908) (xy 128.037703 -243.611908) (xy 128.020857 -243.625927)
			(xy 127.973251 -243.654981) (xy 127.921922 -243.676793) (xy 127.867965 -243.690899) (xy 127.812528 -243.696999)
			(xy 127.756794 -243.694962) (xy 127.701951 -243.684832) (xy 127.649167 -243.666825) (xy 127.599567 -243.641324)
			(xy 127.554209 -243.608873) (xy 127.51406 -243.570164) (xy 127.479974 -243.526021) (xy 127.452678 -243.477386)
			(xy 127.432755 -243.425295) (xy 127.420629 -243.370858) (xy 127.416558 -243.315236) (xy 103.17115 -243.315236)
			(xy 103.174144 -243.31769) (xy 103.213355 -243.359629) (xy 103.245839 -243.406969) (xy 103.270865 -243.458642)
			(xy 103.287866 -243.51348) (xy 103.29646 -243.570247) (xy 103.296974 -243.598954) (xy 103.296502 -243.626207)
			(xy 103.28875 -243.68016) (xy 103.273398 -243.732459) (xy 103.250759 -243.782042) (xy 103.221292 -243.827897)
			(xy 103.185599 -243.869091) (xy 103.144406 -243.904785) (xy 103.098552 -243.934253) (xy 103.048971 -243.956894)
			(xy 102.996671 -243.972248) (xy 102.942719 -243.980001) (xy 102.915466 -243.980462) (xy 102.888564 -243.98)
			(xy 102.835295 -243.972425) (xy 102.783618 -243.957443) (xy 102.734557 -243.935353) (xy 102.689085 -243.906591)
			(xy 102.648103 -243.871728) (xy 102.612423 -243.831455) (xy 102.597204 -243.809266) (xy 102.593648 -243.803932)
			(xy 102.58425 -243.795296) (xy 102.578662 -243.792502) (xy 102.572966 -243.789701) (xy 102.560625 -243.786754)
			(xy 102.554278 -243.78666) (xy 102.467918 -243.788438) (xy 102.455472 -243.789962) (xy 102.449376 -243.79174)
			(xy 102.443788 -243.795042) (xy 102.438455 -243.798343) (xy 102.42946 -243.807078) (xy 102.426008 -243.812314)
			(xy 102.425754 -243.812568) (xy 102.410835 -243.836172) (xy 102.375158 -243.879126) (xy 102.3336 -243.91642)
			(xy 102.287049 -243.947258) (xy 102.236501 -243.970981) (xy 102.183034 -243.987082) (xy 102.127791 -243.995218)
			(xy 102.099872 -243.995702) (xy 102.072879 -243.995243) (xy 102.019431 -243.987635) (xy 101.967588 -243.972573)
			(xy 101.918384 -243.950359) (xy 101.872799 -243.921435) (xy 101.851968 -243.904262) (xy 101.84384 -243.89715)
			(xy 101.833426 -243.894102) (xy 101.832156 -243.893848) (xy 101.827304 -243.892617) (xy 101.817326 -243.891841)
			(xy 101.812344 -243.892324) (xy 101.738176 -243.901976) (xy 101.732817 -243.902723) (xy 101.722567 -243.906174)
			(xy 101.717856 -243.908834) (xy 101.708966 -243.914422) (xy 101.70287 -243.923058) (xy 101.702362 -243.923566)
			(xy 101.687029 -243.94478) (xy 101.651458 -243.983178) (xy 101.610967 -244.016348) (xy 101.566317 -244.043663)
			(xy 101.518348 -244.06461) (xy 101.467965 -244.078795) (xy 101.416113 -244.085951) (xy 101.389942 -244.08638)
			(xy 101.362685 -244.085976) (xy 101.308726 -244.078223) (xy 101.256419 -244.06287) (xy 101.20683 -244.040228)
			(xy 101.160968 -244.010759) (xy 101.119767 -243.975063) (xy 101.084066 -243.933866) (xy 101.054592 -243.888007)
			(xy 101.031945 -243.838421) (xy 101.016586 -243.786115) (xy 101.008827 -243.732157) (xy 99.470783 -243.732157)
			(xy 99.470979 -243.732808) (xy 99.479099 -243.787984) (xy 99.479608 -243.81587) (xy 99.479099 -243.843756)
			(xy 99.470979 -243.898932) (xy 99.454911 -243.952339) (xy 99.431239 -244.002836) (xy 99.400466 -244.049349)
			(xy 99.363249 -244.090886) (xy 99.320381 -244.126561) (xy 99.272775 -244.155615) (xy 99.221446 -244.177427)
			(xy 99.167489 -244.191533) (xy 99.112052 -244.197633) (xy 99.056318 -244.195596) (xy 99.001475 -244.185466)
			(xy 98.948691 -244.167459) (xy 98.899091 -244.141958) (xy 98.853733 -244.109507) (xy 98.813584 -244.070798)
			(xy 98.779498 -244.026655) (xy 98.752202 -243.97802) (xy 98.732279 -243.925929) (xy 98.720153 -243.871492)
			(xy 98.716082 -243.81587) (xy 98.289917 -243.81587) (xy 98.290126 -243.8273) (xy 98.289617 -243.855186)
			(xy 98.281497 -243.910362) (xy 98.265429 -243.963769) (xy 98.241757 -244.014266) (xy 98.210984 -244.060779)
			(xy 98.173767 -244.102316) (xy 98.130899 -244.137991) (xy 98.083293 -244.167045) (xy 98.031964 -244.188857)
			(xy 97.978007 -244.202963) (xy 97.92257 -244.209063) (xy 97.866836 -244.207026) (xy 97.811993 -244.196896)
			(xy 97.759209 -244.178889) (xy 97.709609 -244.153388) (xy 97.664251 -244.120937) (xy 97.624102 -244.082228)
			(xy 97.590016 -244.038085) (xy 97.56272 -243.98945) (xy 97.542797 -243.937359) (xy 97.530671 -243.882922)
			(xy 97.5266 -243.8273) (xy 94.4143 -243.8273) (xy 94.407235 -243.87531) (xy 94.391167 -243.928717)
			(xy 94.367495 -243.979214) (xy 94.336722 -244.025727) (xy 94.299505 -244.067264) (xy 94.256637 -244.102939)
			(xy 94.209031 -244.131993) (xy 94.157702 -244.153805) (xy 94.103745 -244.167911) (xy 94.048308 -244.174011)
			(xy 93.992574 -244.171974) (xy 93.937731 -244.161844) (xy 93.884947 -244.143837) (xy 93.835347 -244.118336)
			(xy 93.789989 -244.085885) (xy 93.74984 -244.047176) (xy 93.715754 -244.003033) (xy 93.688458 -243.954398)
			(xy 93.668535 -243.902307) (xy 93.656409 -243.84787) (xy 93.652338 -243.792248) (xy 91.337384 -243.792248)
			(xy 91.337384 -244.312948) (xy 95.852232 -244.312948) (xy 95.856303 -244.257326) (xy 95.868429 -244.202889)
			(xy 95.888352 -244.150798) (xy 95.915648 -244.102163) (xy 95.949734 -244.05802) (xy 95.989883 -244.019311)
			(xy 96.035241 -243.98686) (xy 96.084841 -243.961359) (xy 96.137625 -243.943352) (xy 96.192468 -243.933222)
			(xy 96.248202 -243.931185) (xy 96.303639 -243.937285) (xy 96.357596 -243.951391) (xy 96.408925 -243.973203)
			(xy 96.456531 -244.002257) (xy 96.499399 -244.037932) (xy 96.536616 -244.079469) (xy 96.567389 -244.125982)
			(xy 96.591061 -244.176479) (xy 96.607129 -244.229886) (xy 96.615249 -244.285062) (xy 96.615758 -244.312948)
			(xy 96.615249 -244.340834) (xy 96.607129 -244.39601) (xy 96.591061 -244.449417) (xy 96.567389 -244.499914)
			(xy 96.536616 -244.546427) (xy 96.518457 -244.566694) (xy 100.51999 -244.566694) (xy 100.524061 -244.511072)
			(xy 100.536187 -244.456635) (xy 100.55611 -244.404544) (xy 100.583406 -244.355909) (xy 100.617492 -244.311766)
			(xy 100.657641 -244.273057) (xy 100.702999 -244.240606) (xy 100.752599 -244.215105) (xy 100.805383 -244.197098)
			(xy 100.860226 -244.186968) (xy 100.91596 -244.184931) (xy 100.971397 -244.191031) (xy 101.025354 -244.205137)
			(xy 101.076683 -244.226949) (xy 101.124289 -244.256003) (xy 101.167157 -244.291678) (xy 101.204374 -244.333215)
			(xy 101.235147 -244.379728) (xy 101.258819 -244.430225) (xy 101.262228 -244.441555) (xy 104.256749 -244.441555)
			(xy 104.256749 -244.387045) (xy 104.264508 -244.33309) (xy 104.279866 -244.280788) (xy 104.302512 -244.231204)
			(xy 104.331984 -244.185348) (xy 104.367682 -244.144154) (xy 104.40888 -244.10846) (xy 104.454739 -244.078992)
			(xy 104.504325 -244.056352) (xy 104.556629 -244.040999) (xy 104.610585 -244.033247) (xy 104.63784 -244.032786)
			(xy 104.66658 -244.033289) (xy 104.723408 -244.041917) (xy 104.778299 -244.058972) (xy 104.83001 -244.084068)
			(xy 104.877372 -244.116638) (xy 104.898698 -244.13591) (xy 104.90581 -244.142514) (xy 104.914192 -244.145816)
			(xy 104.918759 -244.147571) (xy 104.928351 -244.149489) (xy 104.933242 -244.149626) (xy 105.002838 -244.149626)
			(xy 105.007728 -244.149483) (xy 105.017321 -244.147568) (xy 105.021888 -244.145816) (xy 105.03027 -244.142514)
			(xy 105.037382 -244.13591) (xy 105.058709 -244.11664) (xy 105.106072 -244.084075) (xy 105.157783 -244.058984)
			(xy 105.212674 -244.041934) (xy 105.269501 -244.033312) (xy 105.326979 -244.033312) (xy 105.383806 -244.041934)
			(xy 105.438697 -244.058984) (xy 105.490408 -244.084075) (xy 105.537771 -244.11664) (xy 105.559098 -244.13591)
			(xy 105.56621 -244.142514) (xy 105.574592 -244.145816) (xy 105.579159 -244.147571) (xy 105.588751 -244.149489)
			(xy 105.593642 -244.149626) (xy 105.663238 -244.149626) (xy 105.668128 -244.149483) (xy 105.677721 -244.147568)
			(xy 105.682288 -244.145816) (xy 105.69067 -244.142514) (xy 105.697782 -244.13591) (xy 105.719089 -244.116616)
			(xy 105.766457 -244.084054) (xy 105.818174 -244.058966) (xy 105.873069 -244.041921) (xy 105.9299 -244.033304)
			(xy 105.95864 -244.032786) (xy 105.985889 -244.033286) (xy 106.039832 -244.041048) (xy 106.092121 -244.056406)
			(xy 106.141692 -244.079049) (xy 106.187537 -244.108516) (xy 106.228722 -244.144207) (xy 106.264408 -244.185395)
			(xy 106.29387 -244.231243) (xy 106.315638 -244.278912) (xy 134.358124 -244.278912) (xy 134.362195 -244.22329)
			(xy 134.374321 -244.168853) (xy 134.394244 -244.116762) (xy 134.42154 -244.068127) (xy 134.455626 -244.023984)
			(xy 134.495775 -243.985275) (xy 134.541133 -243.952824) (xy 134.590733 -243.927323) (xy 134.643517 -243.909316)
			(xy 134.69836 -243.899186) (xy 134.754094 -243.897149) (xy 134.809531 -243.903249) (xy 134.863488 -243.917355)
			(xy 134.914817 -243.939167) (xy 134.962423 -243.968221) (xy 135.005291 -244.003896) (xy 135.042508 -244.045433)
			(xy 135.073281 -244.091946) (xy 135.096953 -244.142443) (xy 135.113021 -244.19585) (xy 135.121141 -244.251026)
			(xy 135.12165 -244.278912) (xy 135.121141 -244.306798) (xy 135.113021 -244.361974) (xy 135.096953 -244.415381)
			(xy 135.073281 -244.465878) (xy 135.042508 -244.512391) (xy 135.005291 -244.553928) (xy 134.962423 -244.589603)
			(xy 134.914817 -244.618657) (xy 134.863488 -244.640469) (xy 134.809531 -244.654575) (xy 134.754094 -244.660675)
			(xy 134.69836 -244.658638) (xy 134.643517 -244.648508) (xy 134.590733 -244.630501) (xy 134.541133 -244.605)
			(xy 134.495775 -244.572549) (xy 134.455626 -244.53384) (xy 134.42154 -244.489697) (xy 134.394244 -244.441062)
			(xy 134.374321 -244.388971) (xy 134.362195 -244.334534) (xy 134.358124 -244.278912) (xy 106.315638 -244.278912)
			(xy 106.316508 -244.280817) (xy 106.331861 -244.333108) (xy 106.339616 -244.387051) (xy 106.339616 -244.441549)
			(xy 106.331861 -244.495492) (xy 106.316508 -244.547783) (xy 106.29387 -244.597357) (xy 106.264408 -244.643205)
			(xy 106.228722 -244.684393) (xy 106.187537 -244.720084) (xy 106.141692 -244.749551) (xy 106.092121 -244.772194)
			(xy 106.039832 -244.787552) (xy 105.985889 -244.795314) (xy 105.95864 -244.795802) (xy 105.9299 -244.795314)
			(xy 105.873071 -244.786683) (xy 105.81818 -244.769624) (xy 105.766469 -244.744525) (xy 105.719108 -244.711952)
			(xy 105.697782 -244.692678) (xy 105.69067 -244.686074) (xy 105.682288 -244.682772) (xy 105.677723 -244.681012)
			(xy 105.668129 -244.679097) (xy 105.663238 -244.678962) (xy 105.593642 -244.678962) (xy 105.588752 -244.6791)
			(xy 105.579159 -244.681018) (xy 105.574592 -244.682772) (xy 105.56621 -244.686074) (xy 105.559098 -244.692678)
			(xy 105.537771 -244.711948) (xy 105.490408 -244.744513) (xy 105.438697 -244.769604) (xy 105.383806 -244.786654)
			(xy 105.326979 -244.795276) (xy 105.269501 -244.795276) (xy 105.212674 -244.786654) (xy 105.157783 -244.769604)
			(xy 105.106072 -244.744513) (xy 105.058709 -244.711948) (xy 105.037382 -244.692678) (xy 105.03027 -244.686074)
			(xy 105.021888 -244.682772) (xy 105.017323 -244.681012) (xy 105.007729 -244.679097) (xy 105.002838 -244.678962)
			(xy 104.933242 -244.678962) (xy 104.928352 -244.6791) (xy 104.918759 -244.681018) (xy 104.914192 -244.682772)
			(xy 104.90581 -244.686074) (xy 104.898698 -244.692678) (xy 104.877357 -244.711932) (xy 104.829998 -244.7445)
			(xy 104.77829 -244.769596) (xy 104.723403 -244.78665) (xy 104.666578 -244.795278) (xy 104.63784 -244.795802)
			(xy 104.610585 -244.795353) (xy 104.556629 -244.787601) (xy 104.504325 -244.772248) (xy 104.454739 -244.749608)
			(xy 104.40888 -244.72014) (xy 104.367682 -244.684446) (xy 104.331984 -244.643252) (xy 104.302512 -244.597396)
			(xy 104.279866 -244.547812) (xy 104.264508 -244.49551) (xy 104.256749 -244.441555) (xy 101.262228 -244.441555)
			(xy 101.274887 -244.483632) (xy 101.283007 -244.538808) (xy 101.283516 -244.566694) (xy 101.283007 -244.59458)
			(xy 101.274887 -244.649756) (xy 101.258819 -244.703163) (xy 101.235147 -244.75366) (xy 101.204374 -244.800173)
			(xy 101.167157 -244.84171) (xy 101.161279 -244.846602) (xy 126.515112 -244.846602) (xy 126.519183 -244.79098)
			(xy 126.531309 -244.736543) (xy 126.551232 -244.684452) (xy 126.578528 -244.635817) (xy 126.612614 -244.591674)
			(xy 126.652763 -244.552965) (xy 126.698121 -244.520514) (xy 126.747721 -244.495013) (xy 126.800505 -244.477006)
			(xy 126.855348 -244.466876) (xy 126.911082 -244.464839) (xy 126.966519 -244.470939) (xy 127.020476 -244.485045)
			(xy 127.071805 -244.506857) (xy 127.119411 -244.535911) (xy 127.162279 -244.571586) (xy 127.199496 -244.613123)
			(xy 127.230269 -244.659636) (xy 127.253941 -244.710133) (xy 127.270009 -244.76354) (xy 127.278129 -244.818716)
			(xy 127.278638 -244.846602) (xy 127.278129 -244.874488) (xy 127.270009 -244.929664) (xy 127.253941 -244.983071)
			(xy 127.230269 -245.033568) (xy 127.204741 -245.072154) (xy 133.901178 -245.072154) (xy 133.905249 -245.016532)
			(xy 133.917375 -244.962095) (xy 133.937298 -244.910004) (xy 133.964594 -244.861369) (xy 133.99868 -244.817226)
			(xy 134.038829 -244.778517) (xy 134.084187 -244.746066) (xy 134.133787 -244.720565) (xy 134.186571 -244.702558)
			(xy 134.241414 -244.692428) (xy 134.297148 -244.690391) (xy 134.352585 -244.696491) (xy 134.406542 -244.710597)
			(xy 134.457871 -244.732409) (xy 134.505477 -244.761463) (xy 134.548345 -244.797138) (xy 134.585562 -244.838675)
			(xy 134.616335 -244.885188) (xy 134.640007 -244.935685) (xy 134.656075 -244.989092) (xy 134.664195 -245.044268)
			(xy 134.664704 -245.072154) (xy 134.664195 -245.10004) (xy 134.656075 -245.155216) (xy 134.640007 -245.208623)
			(xy 134.616335 -245.25912) (xy 134.585562 -245.305633) (xy 134.548345 -245.34717) (xy 134.505477 -245.382845)
			(xy 134.457871 -245.411899) (xy 134.406542 -245.433711) (xy 134.352585 -245.447817) (xy 134.297148 -245.453917)
			(xy 134.241414 -245.45188) (xy 134.186571 -245.44175) (xy 134.133787 -245.423743) (xy 134.084187 -245.398242)
			(xy 134.038829 -245.365791) (xy 133.99868 -245.327082) (xy 133.964594 -245.282939) (xy 133.937298 -245.234304)
			(xy 133.917375 -245.182213) (xy 133.905249 -245.127776) (xy 133.901178 -245.072154) (xy 127.204741 -245.072154)
			(xy 127.199496 -245.080081) (xy 127.162279 -245.121618) (xy 127.119411 -245.157293) (xy 127.071805 -245.186347)
			(xy 127.020476 -245.208159) (xy 126.966519 -245.222265) (xy 126.911082 -245.228365) (xy 126.855348 -245.226328)
			(xy 126.800505 -245.216198) (xy 126.747721 -245.198191) (xy 126.698121 -245.17269) (xy 126.652763 -245.140239)
			(xy 126.612614 -245.10153) (xy 126.578528 -245.057387) (xy 126.551232 -245.008752) (xy 126.531309 -244.956661)
			(xy 126.519183 -244.902224) (xy 126.515112 -244.846602) (xy 101.161279 -244.846602) (xy 101.124289 -244.877385)
			(xy 101.076683 -244.906439) (xy 101.025354 -244.928251) (xy 100.971397 -244.942357) (xy 100.91596 -244.948457)
			(xy 100.860226 -244.94642) (xy 100.805383 -244.93629) (xy 100.752599 -244.918283) (xy 100.702999 -244.892782)
			(xy 100.657641 -244.860331) (xy 100.617492 -244.821622) (xy 100.583406 -244.777479) (xy 100.55611 -244.728844)
			(xy 100.536187 -244.676753) (xy 100.524061 -244.622316) (xy 100.51999 -244.566694) (xy 96.518457 -244.566694)
			(xy 96.499399 -244.587964) (xy 96.456531 -244.623639) (xy 96.408925 -244.652693) (xy 96.357596 -244.674505)
			(xy 96.303639 -244.688611) (xy 96.248202 -244.694711) (xy 96.192468 -244.692674) (xy 96.137625 -244.682544)
			(xy 96.084841 -244.664537) (xy 96.035241 -244.639036) (xy 95.989883 -244.606585) (xy 95.949734 -244.567876)
			(xy 95.915648 -244.523733) (xy 95.888352 -244.475098) (xy 95.868429 -244.423007) (xy 95.856303 -244.36857)
			(xy 95.852232 -244.312948) (xy 91.337384 -244.312948) (xy 91.337384 -245.824248) (xy 93.652338 -245.824248)
			(xy 93.656409 -245.768626) (xy 93.668535 -245.714189) (xy 93.688458 -245.662098) (xy 93.715754 -245.613463)
			(xy 93.74984 -245.56932) (xy 93.789989 -245.530611) (xy 93.835347 -245.49816) (xy 93.884947 -245.472659)
			(xy 93.937731 -245.454652) (xy 93.992574 -245.444522) (xy 94.048308 -245.442485) (xy 94.103745 -245.448585)
			(xy 94.157702 -245.462691) (xy 94.209031 -245.484503) (xy 94.256637 -245.513557) (xy 94.299505 -245.549232)
			(xy 94.336722 -245.590769) (xy 94.367495 -245.637282) (xy 94.391167 -245.687779) (xy 94.407235 -245.741186)
			(xy 94.415355 -245.796362) (xy 94.415864 -245.824248) (xy 95.865694 -245.824248) (xy 95.869765 -245.768626)
			(xy 95.881891 -245.714189) (xy 95.901814 -245.662098) (xy 95.92911 -245.613463) (xy 95.963196 -245.56932)
			(xy 96.003345 -245.530611) (xy 96.048703 -245.49816) (xy 96.098303 -245.472659) (xy 96.151087 -245.454652)
			(xy 96.20593 -245.444522) (xy 96.261664 -245.442485) (xy 96.317101 -245.448585) (xy 96.371058 -245.462691)
			(xy 96.422387 -245.484503) (xy 96.469993 -245.513557) (xy 96.512861 -245.549232) (xy 96.550078 -245.590769)
			(xy 96.580851 -245.637282) (xy 96.604523 -245.687779) (xy 96.620591 -245.741186) (xy 96.628711 -245.796362)
			(xy 96.62922 -245.824248) (xy 96.628711 -245.852134) (xy 96.620591 -245.90731) (xy 96.609282 -245.944898)
			(xy 100.372416 -245.944898) (xy 100.376487 -245.889276) (xy 100.388613 -245.834839) (xy 100.408536 -245.782748)
			(xy 100.435832 -245.734113) (xy 100.469918 -245.68997) (xy 100.510067 -245.651261) (xy 100.555425 -245.61881)
			(xy 100.605025 -245.593309) (xy 100.657809 -245.575302) (xy 100.712652 -245.565172) (xy 100.768386 -245.563135)
			(xy 100.823823 -245.569235) (xy 100.87778 -245.583341) (xy 100.929109 -245.605153) (xy 100.976715 -245.634207)
			(xy 101.019583 -245.669882) (xy 101.0568 -245.711419) (xy 101.087573 -245.757932) (xy 101.111245 -245.808429)
			(xy 101.127313 -245.861836) (xy 101.135433 -245.917012) (xy 101.135942 -245.944898) (xy 101.135433 -245.972784)
			(xy 101.127313 -246.02796) (xy 101.111245 -246.081367) (xy 101.087573 -246.131864) (xy 101.0568 -246.178377)
			(xy 101.019583 -246.219914) (xy 100.976715 -246.255589) (xy 100.929109 -246.284643) (xy 100.87778 -246.306455)
			(xy 100.823823 -246.320561) (xy 100.768386 -246.326661) (xy 100.712652 -246.324624) (xy 100.657809 -246.314494)
			(xy 100.605025 -246.296487) (xy 100.555425 -246.270986) (xy 100.510067 -246.238535) (xy 100.469918 -246.199826)
			(xy 100.435832 -246.155683) (xy 100.408536 -246.107048) (xy 100.388613 -246.054957) (xy 100.376487 -246.00052)
			(xy 100.372416 -245.944898) (xy 96.609282 -245.944898) (xy 96.604523 -245.960717) (xy 96.580851 -246.011214)
			(xy 96.550078 -246.057727) (xy 96.512861 -246.099264) (xy 96.469993 -246.134939) (xy 96.422387 -246.163993)
			(xy 96.371058 -246.185805) (xy 96.317101 -246.199911) (xy 96.261664 -246.206011) (xy 96.20593 -246.203974)
			(xy 96.151087 -246.193844) (xy 96.098303 -246.175837) (xy 96.048703 -246.150336) (xy 96.003345 -246.117885)
			(xy 95.963196 -246.079176) (xy 95.92911 -246.035033) (xy 95.901814 -245.986398) (xy 95.881891 -245.934307)
			(xy 95.869765 -245.87987) (xy 95.865694 -245.824248) (xy 94.415864 -245.824248) (xy 94.415355 -245.852134)
			(xy 94.407235 -245.90731) (xy 94.391167 -245.960717) (xy 94.367495 -246.011214) (xy 94.336722 -246.057727)
			(xy 94.299505 -246.099264) (xy 94.256637 -246.134939) (xy 94.209031 -246.163993) (xy 94.157702 -246.185805)
			(xy 94.103745 -246.199911) (xy 94.048308 -246.206011) (xy 93.992574 -246.203974) (xy 93.937731 -246.193844)
			(xy 93.884947 -246.175837) (xy 93.835347 -246.150336) (xy 93.789989 -246.117885) (xy 93.74984 -246.079176)
			(xy 93.715754 -246.035033) (xy 93.688458 -245.986398) (xy 93.668535 -245.934307) (xy 93.656409 -245.87987)
			(xy 93.652338 -245.824248) (xy 91.337384 -245.824248) (xy 91.337384 -246.83212) (xy 99.693474 -246.83212)
			(xy 99.697545 -246.776498) (xy 99.709671 -246.722061) (xy 99.729594 -246.66997) (xy 99.75689 -246.621335)
			(xy 99.790976 -246.577192) (xy 99.831125 -246.538483) (xy 99.876483 -246.506032) (xy 99.926083 -246.480531)
			(xy 99.978867 -246.462524) (xy 100.03371 -246.452394) (xy 100.089444 -246.450357) (xy 100.144881 -246.456457)
			(xy 100.198838 -246.470563) (xy 100.250167 -246.492375) (xy 100.297773 -246.521429) (xy 100.340641 -246.557104)
			(xy 100.377858 -246.598641) (xy 100.408631 -246.645154) (xy 100.432303 -246.695651) (xy 100.448371 -246.749058)
			(xy 100.456491 -246.804234) (xy 100.457 -246.83212) (xy 100.456491 -246.860006) (xy 100.448371 -246.915182)
			(xy 100.432303 -246.968589) (xy 100.408631 -247.019086) (xy 100.377858 -247.065599) (xy 100.340641 -247.107136)
			(xy 100.297773 -247.142811) (xy 100.250167 -247.171865) (xy 100.198838 -247.193677) (xy 100.144881 -247.207783)
			(xy 100.089444 -247.213883) (xy 100.03371 -247.211846) (xy 99.978867 -247.201716) (xy 99.926083 -247.183709)
			(xy 99.876483 -247.158208) (xy 99.831125 -247.125757) (xy 99.790976 -247.087048) (xy 99.75689 -247.042905)
			(xy 99.729594 -246.99427) (xy 99.709671 -246.942179) (xy 99.697545 -246.887742) (xy 99.693474 -246.83212)
			(xy 91.337384 -246.83212) (xy 91.337384 -247.032272) (xy 91.337689 -247.040467) (xy 91.342862 -247.05602)
			(xy 91.347544 -247.062752) (xy 91.35237 -247.06834) (xy 92.615766 -248.331736) (xy 102.279196 -248.331736)
			(xy 102.279682 -248.302996) (xy 102.288314 -248.246167) (xy 102.305373 -248.191276) (xy 102.330473 -248.139564)
			(xy 102.363046 -248.092204) (xy 102.38232 -248.070878) (xy 102.388924 -248.063766) (xy 102.392226 -248.055384)
			(xy 102.393987 -248.050819) (xy 102.395901 -248.041225) (xy 102.396036 -248.036334) (xy 102.396036 -247.966738)
			(xy 102.395899 -247.961847) (xy 102.39398 -247.952255) (xy 102.392226 -247.947688) (xy 102.388924 -247.939306)
			(xy 102.38232 -247.932194) (xy 102.363085 -247.910836) (xy 102.330519 -247.863479) (xy 102.305426 -247.811772)
			(xy 102.288373 -247.756886) (xy 102.279747 -247.700063) (xy 102.279743 -247.642589) (xy 102.288361 -247.585765)
			(xy 102.305406 -247.530877) (xy 102.330493 -247.479167) (xy 102.363052 -247.431805) (xy 102.38232 -247.410478)
			(xy 102.388924 -247.403366) (xy 102.392226 -247.394984) (xy 102.393987 -247.390419) (xy 102.395901 -247.380825)
			(xy 102.396036 -247.375934) (xy 102.396036 -247.306338) (xy 102.395899 -247.301447) (xy 102.39398 -247.291855)
			(xy 102.392226 -247.287288) (xy 102.388924 -247.278906) (xy 102.38232 -247.271794) (xy 102.363063 -247.250455)
			(xy 102.330496 -247.203096) (xy 102.305401 -247.151387) (xy 102.288347 -247.096499) (xy 102.27972 -247.039674)
			(xy 102.279196 -247.010936) (xy 102.279684 -246.983567) (xy 102.287497 -246.929388) (xy 102.302981 -246.876886)
			(xy 102.325818 -246.827138) (xy 102.355537 -246.781171) (xy 102.373176 -246.760238) (xy 102.379272 -246.753126)
			(xy 102.38232 -246.744744) (xy 102.383837 -246.740455) (xy 102.385498 -246.731512) (xy 102.385622 -246.726964)
			(xy 102.385622 -246.659908) (xy 102.385504 -246.65536) (xy 102.383845 -246.646414) (xy 102.38232 -246.642128)
			(xy 102.379272 -246.633746) (xy 102.373176 -246.626634) (xy 102.355536 -246.605703) (xy 102.325825 -246.55973)
			(xy 102.30299 -246.509982) (xy 102.287499 -246.457481) (xy 102.27967 -246.403305) (xy 102.279196 -246.375936)
			(xy 102.279682 -246.348685) (xy 102.287438 -246.294737) (xy 102.302793 -246.242442) (xy 102.325435 -246.192865)
			(xy 102.354901 -246.147015) (xy 102.390592 -246.105824) (xy 102.431783 -246.070133) (xy 102.477633 -246.040667)
			(xy 102.52721 -246.018025) (xy 102.579505 -246.00267) (xy 102.633453 -245.994914) (xy 102.687955 -245.994914)
			(xy 102.741903 -246.00267) (xy 102.794198 -246.018025) (xy 102.843775 -246.040667) (xy 102.889625 -246.070133)
			(xy 102.930816 -246.105824) (xy 102.966507 -246.147015) (xy 102.995973 -246.192865) (xy 103.018615 -246.242442)
			(xy 103.03397 -246.294737) (xy 103.041726 -246.348685) (xy 103.042212 -246.375936) (xy 103.041764 -246.403307)
			(xy 103.033941 -246.457487) (xy 103.018448 -246.50999) (xy 102.995602 -246.559736) (xy 102.965875 -246.605703)
			(xy 102.948232 -246.626634) (xy 102.942136 -246.633746) (xy 102.939088 -246.642128) (xy 102.937575 -246.646418)
			(xy 102.935912 -246.655361) (xy 102.935786 -246.659908) (xy 102.935786 -246.726964) (xy 102.93591 -246.731512)
			(xy 102.937565 -246.740457) (xy 102.939088 -246.744744) (xy 102.942136 -246.753126) (xy 102.948232 -246.760238)
			(xy 102.96586 -246.781179) (xy 102.995573 -246.82715) (xy 103.01841 -246.876895) (xy 103.033904 -246.929394)
			(xy 103.041736 -246.983567) (xy 103.042212 -247.010936) (xy 103.041707 -247.039676) (xy 103.033079 -247.096504)
			(xy 103.016025 -247.151394) (xy 102.990929 -247.203106) (xy 102.95836 -247.250468) (xy 102.939088 -247.271794)
			(xy 102.932484 -247.278906) (xy 102.929182 -247.287288) (xy 102.927428 -247.291855) (xy 102.92551 -247.301448)
			(xy 102.925372 -247.306338) (xy 102.925372 -247.375934) (xy 102.925516 -247.380824) (xy 102.92743 -247.390416)
			(xy 102.929182 -247.394984) (xy 102.932484 -247.403366) (xy 102.939088 -247.410478) (xy 102.958394 -247.431774)
			(xy 102.990957 -247.479142) (xy 103.016046 -247.530859) (xy 103.033093 -247.585754) (xy 103.035216 -247.599753)
			(xy 114.289785 -247.599753) (xy 114.289785 -247.545247) (xy 114.297543 -247.491297) (xy 114.3129 -247.439)
			(xy 114.335543 -247.389421) (xy 114.365013 -247.34357) (xy 114.400708 -247.30238) (xy 114.441902 -247.266689)
			(xy 114.487757 -247.237224) (xy 114.537338 -247.214586) (xy 114.589636 -247.199234) (xy 114.643587 -247.191483)
			(xy 114.67084 -247.191022) (xy 114.699703 -247.191532) (xy 114.756772 -247.200215) (xy 114.811879 -247.217405)
			(xy 114.863762 -247.242709) (xy 114.911236 -247.27555) (xy 114.953214 -247.315174) (xy 114.988735 -247.360677)
			(xy 115.003326 -247.385586) (xy 115.007136 -247.39219) (xy 115.01628 -247.401334) (xy 115.022376 -247.40489)
			(xy 115.027918 -247.407816) (xy 115.039994 -247.411153) (xy 115.046252 -247.411494) (xy 115.048538 -247.411494)
			(xy 115.138708 -247.409462) (xy 115.145547 -247.409125) (xy 115.158677 -247.405252) (xy 115.164616 -247.401842)
			(xy 115.170204 -247.398286) (xy 115.179602 -247.388126) (xy 115.18265 -247.381776) (xy 115.194935 -247.358523)
			(xy 115.224882 -247.315293) (xy 115.260485 -247.276589) (xy 115.30107 -247.243144) (xy 115.345865 -247.215594)
			(xy 115.394021 -247.194461) (xy 115.444625 -247.180146) (xy 115.496715 -247.17292) (xy 115.52301 -247.17248)
			(xy 115.552381 -247.172987) (xy 115.610427 -247.182) (xy 115.666408 -247.199795) (xy 115.719004 -247.225953)
			(xy 115.766974 -247.259857) (xy 115.809186 -247.300708) (xy 115.844644 -247.347541) (xy 115.859052 -247.37314)
			(xy 115.8621 -247.378982) (xy 115.871498 -247.389142) (xy 115.877086 -247.392444) (xy 115.882862 -247.395716)
			(xy 115.895603 -247.399435) (xy 115.902232 -247.39981) (xy 115.991132 -247.402096) (xy 115.993418 -247.402096)
			(xy 115.999454 -247.401807) (xy 116.011135 -247.398719) (xy 116.016532 -247.396) (xy 116.022374 -247.392698)
			(xy 116.032026 -247.383554) (xy 116.035582 -247.377458) (xy 116.050432 -247.353639) (xy 116.086089 -247.310289)
			(xy 116.127714 -247.272634) (xy 116.17441 -247.241487) (xy 116.225167 -247.217521) (xy 116.278889 -247.201254)
			(xy 116.334415 -247.193038) (xy 116.36248 -247.192546) (xy 116.389731 -247.1931) (xy 116.443677 -247.200854)
			(xy 116.495971 -247.216206) (xy 116.545548 -247.238845) (xy 116.591398 -247.268309) (xy 116.632588 -247.303998)
			(xy 116.668279 -247.345186) (xy 116.697746 -247.391035) (xy 116.720387 -247.44061) (xy 116.735742 -247.492903)
			(xy 116.743499 -247.54685) (xy 116.743499 -247.60135) (xy 116.735742 -247.655297) (xy 116.720387 -247.70759)
			(xy 116.697746 -247.757165) (xy 116.668279 -247.803014) (xy 116.632588 -247.844202) (xy 116.591398 -247.879891)
			(xy 116.545548 -247.909355) (xy 116.495971 -247.931994) (xy 116.443677 -247.947346) (xy 116.389731 -247.9551)
			(xy 116.36248 -247.955562) (xy 116.333113 -247.95496) (xy 116.275072 -247.945963) (xy 116.219094 -247.928183)
			(xy 116.166499 -247.902039) (xy 116.118528 -247.86815) (xy 116.076313 -247.827314) (xy 116.04085 -247.780495)
			(xy 116.026438 -247.754902) (xy 116.02339 -247.74906) (xy 116.013992 -247.7389) (xy 116.008404 -247.735598)
			(xy 116.002611 -247.732359) (xy 115.989883 -247.728618) (xy 115.983258 -247.728232) (xy 115.894358 -247.725946)
			(xy 115.892072 -247.725946) (xy 115.886035 -247.726228) (xy 115.874354 -247.72932) (xy 115.868958 -247.732042)
			(xy 115.863116 -247.735344) (xy 115.853464 -247.744488) (xy 115.849908 -247.750584) (xy 115.835044 -247.774394)
			(xy 115.799392 -247.817747) (xy 115.75777 -247.855405) (xy 115.711076 -247.886554) (xy 115.660321 -247.910521)
			(xy 115.6066 -247.926789) (xy 115.551075 -247.935004) (xy 115.52301 -247.935496) (xy 115.494149 -247.934937)
			(xy 115.437083 -247.926262) (xy 115.381977 -247.90908) (xy 115.330094 -247.883783) (xy 115.28262 -247.850951)
			(xy 115.24064 -247.811333) (xy 115.205116 -247.765838) (xy 115.190524 -247.740932) (xy 115.186714 -247.734328)
			(xy 115.17757 -247.725184) (xy 115.171474 -247.721628) (xy 115.165924 -247.71872) (xy 115.153854 -247.715372)
			(xy 115.147598 -247.715024) (xy 115.145312 -247.715024) (xy 115.055142 -247.717056) (xy 115.048306 -247.717422)
			(xy 115.035176 -247.721276) (xy 115.029234 -247.724676) (xy 115.023646 -247.728232) (xy 115.014248 -247.738392)
			(xy 115.0112 -247.744742) (xy 114.998961 -247.76802) (xy 114.969007 -247.81125) (xy 114.933396 -247.849954)
			(xy 114.892805 -247.883396) (xy 114.848003 -247.910943) (xy 114.799841 -247.932072) (xy 114.749232 -247.946382)
			(xy 114.697137 -247.953601) (xy 114.67084 -247.954038) (xy 114.643587 -247.953517) (xy 114.589636 -247.945766)
			(xy 114.537338 -247.930414) (xy 114.487757 -247.907776) (xy 114.441902 -247.878311) (xy 114.400708 -247.84262)
			(xy 114.365013 -247.80143) (xy 114.335543 -247.755579) (xy 114.3129 -247.706) (xy 114.297543 -247.653703)
			(xy 114.289785 -247.599753) (xy 103.035216 -247.599753) (xy 103.041712 -247.642586) (xy 103.041708 -247.700067)
			(xy 103.033081 -247.756897) (xy 103.016026 -247.81179) (xy 102.990931 -247.863503) (xy 102.958361 -247.910867)
			(xy 102.939088 -247.932194) (xy 102.932484 -247.939306) (xy 102.929182 -247.947688) (xy 102.927428 -247.952255)
			(xy 102.92551 -247.961848) (xy 102.925372 -247.966738) (xy 102.925372 -248.036334) (xy 102.925516 -248.041224)
			(xy 102.92743 -248.050816) (xy 102.929182 -248.055384) (xy 102.932484 -248.063766) (xy 102.939088 -248.070878)
			(xy 102.95838 -248.092186) (xy 102.990942 -248.139554) (xy 103.01603 -248.19127) (xy 103.033076 -248.246165)
			(xy 103.041694 -248.302996) (xy 103.042212 -248.331736) (xy 103.041726 -248.358987) (xy 103.03397 -248.412935)
			(xy 103.018615 -248.46523) (xy 103.017828 -248.466954) (xy 104.083041 -248.466954) (xy 104.083041 -248.412446)
			(xy 104.090798 -248.358493) (xy 104.106155 -248.306192) (xy 104.128799 -248.25661) (xy 104.158268 -248.210755)
			(xy 104.193964 -248.169561) (xy 104.235158 -248.133866) (xy 104.281014 -248.104397) (xy 104.330596 -248.081754)
			(xy 104.382897 -248.066397) (xy 104.43685 -248.058641) (xy 104.464104 -248.058178) (xy 104.492843 -248.058705)
			(xy 104.54967 -248.067328) (xy 104.60456 -248.084377) (xy 104.656272 -248.109468) (xy 104.703635 -248.142032)
			(xy 104.724962 -248.161302) (xy 104.732074 -248.167906) (xy 104.740456 -248.171208) (xy 104.745026 -248.172953)
			(xy 104.754616 -248.174877) (xy 104.759506 -248.175018) (xy 104.829102 -248.175018) (xy 104.833993 -248.174893)
			(xy 104.843586 -248.172966) (xy 104.848152 -248.171208) (xy 104.856534 -248.167906) (xy 104.863646 -248.161302)
			(xy 104.884973 -248.142032) (xy 104.932336 -248.109467) (xy 104.984047 -248.084376) (xy 105.038938 -248.067326)
			(xy 105.095765 -248.058704) (xy 105.153243 -248.058704) (xy 105.21007 -248.067326) (xy 105.264961 -248.084376)
			(xy 105.316672 -248.109467) (xy 105.364035 -248.142032) (xy 105.385362 -248.161302) (xy 105.392474 -248.167906)
			(xy 105.400856 -248.171208) (xy 105.405426 -248.172953) (xy 105.415016 -248.174877) (xy 105.419906 -248.175018)
			(xy 105.489502 -248.175018) (xy 105.494393 -248.174893) (xy 105.503986 -248.172966) (xy 105.508552 -248.171208)
			(xy 105.516934 -248.167906) (xy 105.524046 -248.161302) (xy 105.545381 -248.14204) (xy 105.59274 -248.109471)
			(xy 105.644449 -248.084375) (xy 105.699339 -248.067323) (xy 105.756165 -248.058699) (xy 105.784904 -248.058178)
			(xy 105.812154 -248.058693) (xy 105.866099 -248.066449) (xy 105.918392 -248.081804) (xy 105.967966 -248.104445)
			(xy 106.013815 -248.13391) (xy 106.055003 -248.1696) (xy 106.080826 -248.199402) (xy 123.865384 -248.199402)
			(xy 123.869455 -248.14378) (xy 123.881581 -248.089343) (xy 123.901504 -248.037252) (xy 123.9288 -247.988617)
			(xy 123.962886 -247.944474) (xy 124.003035 -247.905765) (xy 124.048393 -247.873314) (xy 124.097993 -247.847813)
			(xy 124.150777 -247.829806) (xy 124.20562 -247.819676) (xy 124.261354 -247.817639) (xy 124.316791 -247.823739)
			(xy 124.370748 -247.837845) (xy 124.422077 -247.859657) (xy 124.469683 -247.888711) (xy 124.511861 -247.923812)
			(xy 124.852682 -247.923812) (xy 124.856753 -247.86819) (xy 124.868879 -247.813753) (xy 124.888802 -247.761662)
			(xy 124.916098 -247.713027) (xy 124.950184 -247.668884) (xy 124.990333 -247.630175) (xy 125.035691 -247.597724)
			(xy 125.085291 -247.572223) (xy 125.138075 -247.554216) (xy 125.192918 -247.544086) (xy 125.248652 -247.542049)
			(xy 125.304089 -247.548149) (xy 125.358046 -247.562255) (xy 125.409375 -247.584067) (xy 125.456981 -247.613121)
			(xy 125.499849 -247.648796) (xy 125.537066 -247.690333) (xy 125.567839 -247.736846) (xy 125.591511 -247.787343)
			(xy 125.607579 -247.84075) (xy 125.615699 -247.895926) (xy 125.616208 -247.923812) (xy 125.615699 -247.951698)
			(xy 125.607579 -248.006874) (xy 125.591511 -248.060281) (xy 125.567839 -248.110778) (xy 125.537066 -248.157291)
			(xy 125.499849 -248.198828) (xy 125.456981 -248.234503) (xy 125.409375 -248.263557) (xy 125.358046 -248.285369)
			(xy 125.304089 -248.299475) (xy 125.248652 -248.305575) (xy 125.192918 -248.303538) (xy 125.138075 -248.293408)
			(xy 125.085291 -248.275401) (xy 125.035691 -248.2499) (xy 124.990333 -248.217449) (xy 124.950184 -248.17874)
			(xy 124.916098 -248.134597) (xy 124.888802 -248.085962) (xy 124.868879 -248.033871) (xy 124.856753 -247.979434)
			(xy 124.852682 -247.923812) (xy 124.511861 -247.923812) (xy 124.512551 -247.924386) (xy 124.549768 -247.965923)
			(xy 124.580541 -248.012436) (xy 124.604213 -248.062933) (xy 124.620281 -248.11634) (xy 124.628401 -248.171516)
			(xy 124.62891 -248.199402) (xy 124.628401 -248.227288) (xy 124.620281 -248.282464) (xy 124.604213 -248.335871)
			(xy 124.580541 -248.386368) (xy 124.549768 -248.432881) (xy 124.512551 -248.474418) (xy 124.469683 -248.510093)
			(xy 124.422077 -248.539147) (xy 124.370748 -248.560959) (xy 124.316791 -248.575065) (xy 124.261354 -248.581165)
			(xy 124.20562 -248.579128) (xy 124.150777 -248.568998) (xy 124.097993 -248.550991) (xy 124.048393 -248.52549)
			(xy 124.003035 -248.493039) (xy 123.962886 -248.45433) (xy 123.9288 -248.410187) (xy 123.901504 -248.361552)
			(xy 123.881581 -248.309461) (xy 123.869455 -248.255024) (xy 123.865384 -248.199402) (xy 106.080826 -248.199402)
			(xy 106.090693 -248.210789) (xy 106.120157 -248.256637) (xy 106.142797 -248.306212) (xy 106.158152 -248.358505)
			(xy 106.165908 -248.41245) (xy 106.165908 -248.46695) (xy 106.158152 -248.520895) (xy 106.142797 -248.573188)
			(xy 106.120157 -248.622763) (xy 106.101022 -248.652538) (xy 128.32029 -248.652538) (xy 128.324361 -248.596916)
			(xy 128.336487 -248.542479) (xy 128.35641 -248.490388) (xy 128.383706 -248.441753) (xy 128.417792 -248.39761)
			(xy 128.457941 -248.358901) (xy 128.503299 -248.32645) (xy 128.552899 -248.300949) (xy 128.605683 -248.282942)
			(xy 128.660526 -248.272812) (xy 128.71626 -248.270775) (xy 128.771697 -248.276875) (xy 128.825654 -248.290981)
			(xy 128.876983 -248.312793) (xy 128.924589 -248.341847) (xy 128.967457 -248.377522) (xy 129.004674 -248.419059)
			(xy 129.035447 -248.465572) (xy 129.059119 -248.516069) (xy 129.075187 -248.569476) (xy 129.083307 -248.624652)
			(xy 129.083816 -248.652538) (xy 129.083307 -248.680424) (xy 129.075187 -248.7356) (xy 129.059119 -248.789007)
			(xy 129.035447 -248.839504) (xy 129.004674 -248.886017) (xy 128.967457 -248.927554) (xy 128.924589 -248.963229)
			(xy 128.876983 -248.992283) (xy 128.825654 -249.014095) (xy 128.771697 -249.028201) (xy 128.71626 -249.034301)
			(xy 128.660526 -249.032264) (xy 128.605683 -249.022134) (xy 128.552899 -249.004127) (xy 128.503299 -248.978626)
			(xy 128.457941 -248.946175) (xy 128.417792 -248.907466) (xy 128.383706 -248.863323) (xy 128.35641 -248.814688)
			(xy 128.336487 -248.762597) (xy 128.324361 -248.70816) (xy 128.32029 -248.652538) (xy 106.101022 -248.652538)
			(xy 106.090693 -248.668611) (xy 106.055003 -248.7098) (xy 106.013815 -248.74549) (xy 105.967966 -248.774955)
			(xy 105.918392 -248.797596) (xy 105.866099 -248.812951) (xy 105.812154 -248.820707) (xy 105.784904 -248.821194)
			(xy 105.756165 -248.820669) (xy 105.699338 -248.812047) (xy 105.644447 -248.794998) (xy 105.592735 -248.769906)
			(xy 105.545373 -248.737341) (xy 105.524046 -248.71807) (xy 105.516934 -248.711466) (xy 105.508552 -248.708164)
			(xy 105.503981 -248.70642) (xy 105.494392 -248.704495) (xy 105.489502 -248.704354) (xy 105.419906 -248.704354)
			(xy 105.415015 -248.704483) (xy 105.405423 -248.706407) (xy 105.400856 -248.708164) (xy 105.392474 -248.711466)
			(xy 105.385362 -248.71807) (xy 105.364035 -248.73734) (xy 105.316672 -248.769905) (xy 105.264961 -248.794996)
			(xy 105.21007 -248.812046) (xy 105.153243 -248.820668) (xy 105.095765 -248.820668) (xy 105.038938 -248.812046)
			(xy 104.984047 -248.794996) (xy 104.932336 -248.769905) (xy 104.884973 -248.73734) (xy 104.863646 -248.71807)
			(xy 104.856534 -248.711466) (xy 104.848152 -248.708164) (xy 104.843581 -248.70642) (xy 104.833992 -248.704495)
			(xy 104.829102 -248.704354) (xy 104.759506 -248.704354) (xy 104.754615 -248.704483) (xy 104.745023 -248.706407)
			(xy 104.740456 -248.708164) (xy 104.732074 -248.711466) (xy 104.724962 -248.71807) (xy 104.703634 -248.73734)
			(xy 104.656272 -248.769906) (xy 104.604561 -248.794999) (xy 104.54967 -248.812049) (xy 104.492843 -248.820673)
			(xy 104.464104 -248.821194) (xy 104.43685 -248.820759) (xy 104.382897 -248.813003) (xy 104.330596 -248.797646)
			(xy 104.281014 -248.775003) (xy 104.235158 -248.745534) (xy 104.193964 -248.709839) (xy 104.158268 -248.668645)
			(xy 104.128799 -248.62279) (xy 104.106155 -248.573208) (xy 104.090798 -248.520907) (xy 104.083041 -248.466954)
			(xy 103.017828 -248.466954) (xy 102.995973 -248.514807) (xy 102.966507 -248.560657) (xy 102.930816 -248.601848)
			(xy 102.889625 -248.637539) (xy 102.843775 -248.667005) (xy 102.794198 -248.689647) (xy 102.741903 -248.705002)
			(xy 102.687955 -248.712758) (xy 102.633453 -248.712758) (xy 102.579505 -248.705002) (xy 102.52721 -248.689647)
			(xy 102.477633 -248.667005) (xy 102.431783 -248.637539) (xy 102.390592 -248.601848) (xy 102.354901 -248.560657)
			(xy 102.325435 -248.514807) (xy 102.302793 -248.46523) (xy 102.287438 -248.412935) (xy 102.279682 -248.358987)
			(xy 102.279196 -248.331736) (xy 92.615766 -248.331736) (xy 93.557598 -249.273568) (xy 127.616964 -249.273568)
			(xy 127.621035 -249.217946) (xy 127.633161 -249.163509) (xy 127.653084 -249.111418) (xy 127.68038 -249.062783)
			(xy 127.714466 -249.01864) (xy 127.754615 -248.979931) (xy 127.799973 -248.94748) (xy 127.849573 -248.921979)
			(xy 127.902357 -248.903972) (xy 127.9572 -248.893842) (xy 128.012934 -248.891805) (xy 128.068371 -248.897905)
			(xy 128.122328 -248.912011) (xy 128.173657 -248.933823) (xy 128.221263 -248.962877) (xy 128.264131 -248.998552)
			(xy 128.301348 -249.040089) (xy 128.332121 -249.086602) (xy 128.355793 -249.137099) (xy 128.371861 -249.190506)
			(xy 128.379981 -249.245682) (xy 128.38049 -249.273568) (xy 128.379981 -249.301454) (xy 128.371861 -249.35663)
			(xy 128.371753 -249.35699) (xy 129.006347 -249.35699) (xy 129.006347 -249.299874) (xy 129.014476 -249.243341)
			(xy 129.030567 -249.188539) (xy 129.054293 -249.136586) (xy 129.085172 -249.088537) (xy 129.122575 -249.045373)
			(xy 129.165739 -249.00797) (xy 129.213788 -248.977091) (xy 129.265741 -248.953365) (xy 129.320543 -248.937274)
			(xy 129.377076 -248.929145) (xy 129.434192 -248.929145) (xy 129.490725 -248.937274) (xy 129.545527 -248.953365)
			(xy 129.59748 -248.977091) (xy 129.645529 -249.00797) (xy 129.688693 -249.045373) (xy 129.726096 -249.088537)
			(xy 129.756975 -249.136586) (xy 129.780701 -249.188539) (xy 129.796792 -249.243341) (xy 129.804921 -249.299874)
			(xy 129.80543 -249.328432) (xy 129.804921 -249.35699) (xy 129.796792 -249.413523) (xy 129.780701 -249.468325)
			(xy 129.756975 -249.520278) (xy 129.726096 -249.568327) (xy 129.688693 -249.611491) (xy 129.645529 -249.648894)
			(xy 129.59748 -249.679773) (xy 129.545527 -249.703499) (xy 129.490725 -249.71959) (xy 129.434192 -249.727719)
			(xy 129.377076 -249.727719) (xy 129.320543 -249.71959) (xy 129.265741 -249.703499) (xy 129.213788 -249.679773)
			(xy 129.165739 -249.648894) (xy 129.122575 -249.611491) (xy 129.085172 -249.568327) (xy 129.054293 -249.520278)
			(xy 129.030567 -249.468325) (xy 129.014476 -249.413523) (xy 129.006347 -249.35699) (xy 128.371753 -249.35699)
			(xy 128.355793 -249.410037) (xy 128.332121 -249.460534) (xy 128.301348 -249.507047) (xy 128.264131 -249.548584)
			(xy 128.221263 -249.584259) (xy 128.173657 -249.613313) (xy 128.122328 -249.635125) (xy 128.068371 -249.649231)
			(xy 128.012934 -249.655331) (xy 127.9572 -249.653294) (xy 127.902357 -249.643164) (xy 127.849573 -249.625157)
			(xy 127.799973 -249.599656) (xy 127.754615 -249.567205) (xy 127.714466 -249.528496) (xy 127.68038 -249.484353)
			(xy 127.653084 -249.435718) (xy 127.633161 -249.383627) (xy 127.621035 -249.32919) (xy 127.616964 -249.273568)
			(xy 93.557598 -249.273568) (xy 93.985685 -249.701655) (xy 102.324835 -249.701655) (xy 102.324835 -249.647145)
			(xy 102.332593 -249.59319) (xy 102.34795 -249.540888) (xy 102.370595 -249.491304) (xy 102.400066 -249.445448)
			(xy 102.435764 -249.404252) (xy 102.47696 -249.368557) (xy 102.522818 -249.339088) (xy 102.572403 -249.316445)
			(xy 102.624705 -249.301089) (xy 102.678661 -249.293334) (xy 102.705916 -249.292872) (xy 102.734655 -249.293393)
			(xy 102.791482 -249.302018) (xy 102.846372 -249.319069) (xy 102.898084 -249.344161) (xy 102.945447 -249.376726)
			(xy 102.966774 -249.395996) (xy 102.973886 -249.4026) (xy 102.982268 -249.405902) (xy 102.986837 -249.40765)
			(xy 102.996428 -249.409573) (xy 103.001318 -249.409712) (xy 103.070914 -249.409712) (xy 103.075804 -249.409563)
			(xy 103.085396 -249.407653) (xy 103.089964 -249.405902) (xy 103.098346 -249.4026) (xy 103.105458 -249.395996)
			(xy 103.126785 -249.376726) (xy 103.174148 -249.344161) (xy 103.225859 -249.31907) (xy 103.28075 -249.30202)
			(xy 103.337577 -249.293398) (xy 103.395055 -249.293398) (xy 103.451882 -249.30202) (xy 103.506773 -249.31907)
			(xy 103.558484 -249.344161) (xy 103.605847 -249.376726) (xy 103.627174 -249.395996) (xy 103.634286 -249.4026)
			(xy 103.642668 -249.405902) (xy 103.647237 -249.40765) (xy 103.656828 -249.409573) (xy 103.661718 -249.409712)
			(xy 103.731314 -249.409712) (xy 103.736204 -249.409563) (xy 103.745796 -249.407653) (xy 103.750364 -249.405902)
			(xy 103.758746 -249.4026) (xy 103.765858 -249.395996) (xy 103.787187 -249.376728) (xy 103.834548 -249.344159)
			(xy 103.886259 -249.319065) (xy 103.941149 -249.302014) (xy 103.997977 -249.293392) (xy 104.026716 -249.292872)
			(xy 104.053965 -249.293399) (xy 104.107908 -249.301157) (xy 104.160198 -249.316513) (xy 104.209771 -249.339154)
			(xy 104.255617 -249.368619) (xy 104.296803 -249.404309) (xy 104.332491 -249.445496) (xy 104.361954 -249.491343)
			(xy 104.384593 -249.540917) (xy 104.399946 -249.593208) (xy 104.407702 -249.647151) (xy 104.407702 -249.701649)
			(xy 104.399946 -249.755592) (xy 104.384593 -249.807883) (xy 104.361954 -249.857457) (xy 104.332491 -249.903304)
			(xy 104.296803 -249.944491) (xy 104.255617 -249.980181) (xy 104.209771 -250.009646) (xy 104.160198 -250.032287)
			(xy 104.107908 -250.047643) (xy 104.053965 -250.055401) (xy 104.026716 -250.055888) (xy 103.997977 -250.055358)
			(xy 103.94115 -250.046737) (xy 103.886259 -250.029689) (xy 103.834547 -250.004599) (xy 103.787185 -249.972034)
			(xy 103.765858 -249.952764) (xy 103.758746 -249.94616) (xy 103.750364 -249.942858) (xy 103.745801 -249.941091)
			(xy 103.736206 -249.939181) (xy 103.731314 -249.939048) (xy 103.661718 -249.939048) (xy 103.656827 -249.939181)
			(xy 103.647235 -249.941103) (xy 103.642668 -249.942858) (xy 103.634286 -249.94616) (xy 103.627174 -249.952764)
			(xy 103.605847 -249.972034) (xy 103.558484 -250.004599) (xy 103.506773 -250.02969) (xy 103.451882 -250.04674)
			(xy 103.395055 -250.055362) (xy 103.337577 -250.055362) (xy 103.28075 -250.04674) (xy 103.225859 -250.02969)
			(xy 103.174148 -250.004599) (xy 103.126785 -249.972034) (xy 103.105458 -249.952764) (xy 103.098346 -249.94616)
			(xy 103.089964 -249.942858) (xy 103.085401 -249.941091) (xy 103.075806 -249.939181) (xy 103.070914 -249.939048)
			(xy 103.001318 -249.939048) (xy 102.996427 -249.939181) (xy 102.986835 -249.941103) (xy 102.982268 -249.942858)
			(xy 102.973886 -249.94616) (xy 102.966774 -249.952764) (xy 102.945441 -249.972027) (xy 102.89808 -250.004595)
			(xy 102.84637 -250.029688) (xy 102.791481 -250.046741) (xy 102.734655 -250.055366) (xy 102.705916 -250.055888)
			(xy 102.678661 -250.055466) (xy 102.624705 -250.047711) (xy 102.572403 -250.032355) (xy 102.522818 -250.009712)
			(xy 102.47696 -249.980243) (xy 102.435764 -249.944548) (xy 102.400066 -249.903352) (xy 102.370595 -249.857496)
			(xy 102.34795 -249.807912) (xy 102.332593 -249.75561) (xy 102.324835 -249.701655) (xy 93.985685 -249.701655)
			(xy 94.732602 -250.448572) (xy 94.73819 -250.453398) (xy 94.744928 -250.458074) (xy 94.760474 -250.46327)
			(xy 94.76867 -250.463558)
		)
		(stroke
			(width 0)
			(type solid)
		)
		(fill yes)
		(layer "In11.Cu")
		(net "P3V3_AUX")
	)
	(gr_poly
		(pts
			(xy 359.259124 -325.62292) (xy 359.268261 -325.622535) (xy 359.285371 -325.616116) (xy 359.299142 -325.604104)
			(xy 359.303828 -325.59625) (xy 359.317269 -325.572435) (xy 359.349922 -325.52857) (xy 359.388501 -325.489815)
			(xy 359.432217 -325.456962) (xy 359.480174 -325.430685) (xy 359.531391 -325.411522) (xy 359.584818 -325.399865)
			(xy 359.639362 -325.395952) (xy 359.693906 -325.399865) (xy 359.747333 -325.411522) (xy 359.79855 -325.430685)
			(xy 359.846507 -325.456962) (xy 359.890223 -325.489815) (xy 359.928802 -325.52857) (xy 359.961455 -325.572435)
			(xy 359.974896 -325.59625) (xy 359.979574 -325.604108) (xy 359.99335 -325.616117) (xy 360.010463 -325.622529)
			(xy 360.0196 -325.62292) (xy 363.89183 -325.62292) (xy 363.898688 -325.622412) (xy 363.906068 -325.621019)
			(xy 363.919617 -325.614556) (xy 363.925358 -325.609712) (xy 363.928914 -325.606156) (xy 363.935917 -325.597536)
			(xy 363.942445 -325.576334) (xy 363.939471 -325.55435) (xy 363.933994 -325.544688) (xy 363.933486 -325.543926)
			(xy 363.899958 -325.493634) (xy 363.877242 -325.458856) (xy 363.837064 -325.386144) (xy 363.803135 -325.310314)
			(xy 363.775695 -325.231902) (xy 363.754938 -325.151463) (xy 363.741011 -325.069564) (xy 363.734013 -324.986785)
			(xy 363.733588 -324.945248) (xy 363.733588 -324.887336) (xy 363.733234 -324.878356) (xy 363.727011 -324.861508)
			(xy 363.715326 -324.847868) (xy 363.70768 -324.84314) (xy 363.701076 -324.839838) (xy 363.698536 -324.838822)
			(xy 363.671927 -324.828234) (xy 363.621932 -324.800308) (xy 363.598968 -324.783196) (xy 363.578114 -324.766453)
			(xy 363.540845 -324.728097) (xy 363.509298 -324.684913) (xy 363.48409 -324.637747) (xy 363.465715 -324.587522)
			(xy 363.454535 -324.535224) (xy 363.450767 -324.481877) (xy 363.454485 -324.428527) (xy 363.465617 -324.376218)
			(xy 363.483945 -324.325977) (xy 363.509109 -324.278787) (xy 363.540616 -324.235573) (xy 363.57785 -324.197183)
			(xy 363.598714 -324.180454) (xy 363.599222 -324.179946) (xy 363.602524 -324.177406) (xy 363.61624 -324.166992)
			(xy 363.625384 -324.133718) (xy 363.306868 -323.364606) (xy 363.288774 -323.319266) (xy 363.260476 -323.22583)
			(xy 363.241429 -323.130079) (xy 363.231814 -323.032927) (xy 363.231176 -322.984114) (xy 363.231176 -318.295274)
			(xy 363.231788 -318.246459) (xy 363.241372 -318.149299) (xy 363.260417 -318.053543) (xy 363.28874 -317.960111)
			(xy 363.306868 -317.914782) (xy 365.225838 -313.281822) (xy 365.245151 -313.236868) (xy 365.291334 -313.150606)
			(xy 365.31804 -313.10961) (xy 365.909352 -312.22442) (xy 365.914178 -312.215784) (xy 366.325912 -311.221628)
			(xy 366.326166 -311.221628) (xy 367.283492 -308.910228) (xy 367.388648 -308.656228) (xy 367.409984 -308.608222)
			(xy 367.428469 -308.570468) (xy 367.470965 -308.49793) (xy 367.519466 -308.429263) (xy 367.573622 -308.364962)
			(xy 367.603024 -308.334918) (xy 368.47145 -307.466746) (xy 368.474357 -307.463763) (xy 368.479213 -307.456996)
			(xy 368.481102 -307.453284) (xy 368.484404 -307.444902) (xy 368.486182 -307.431186) (xy 368.486182 -279.460452)
			(xy 368.485674 -279.452324) (xy 368.484481 -279.446434) (xy 368.479724 -279.435403) (xy 368.476276 -279.43048)
			(xy 368.471196 -279.424384) (xy 368.450368 -279.403556) (xy 368.44478 -279.39873) (xy 368.438152 -279.394123)
			(xy 368.422871 -279.388947) (xy 368.414808 -279.38857) (xy 368.3331 -279.387234) (xy 368.169947 -279.377638)
			(xy 368.007449 -279.360165) (xy 367.845986 -279.334857) (xy 367.685935 -279.301772) (xy 367.527671 -279.260988)
			(xy 367.371564 -279.2126) (xy 367.217978 -279.156722) (xy 367.067274 -279.093484) (xy 366.919803 -279.023034)
			(xy 366.847628 -278.98471) (xy 366.841375 -278.981544) (xy 366.827711 -278.978446) (xy 366.820704 -278.978614)
			(xy 366.806734 -278.979376) (xy 366.738662 -279.025858) (xy 366.73028 -279.0317) (xy 366.725191 -279.035383)
			(xy 366.716841 -279.044762) (xy 366.71377 -279.050242) (xy 366.69853 -279.079452) (xy 366.6998 -279.091136)
			(xy 366.700913 -279.102023) (xy 366.702055 -279.12388) (xy 366.702086 -279.134824) (xy 366.702086 -279.135332)
			(xy 366.701832 -279.14473) (xy 366.701832 -280.148792) (xy 366.701381 -280.17459) (xy 366.694386 -280.225709)
			(xy 366.680576 -280.275422) (xy 366.660203 -280.322826) (xy 366.633636 -280.367056) (xy 366.60136 -280.40731)
			(xy 366.58296 -280.425398) (xy 366.581944 -280.426414) (xy 366.521238 -280.48712) (xy 366.513264 -280.496082)
			(xy 366.505853 -280.518867) (xy 366.507014 -280.530808) (xy 366.521492 -280.59253) (xy 366.528096 -280.621232)
			(xy 366.531597 -280.630849) (xy 366.544829 -280.646441) (xy 366.55375 -280.651458) (xy 366.560862 -280.655014)
			(xy 366.56391 -280.65603) (xy 366.588571 -280.665037) (xy 366.635355 -280.688861) (xy 366.678434 -280.71887)
			(xy 366.716995 -280.754499) (xy 366.750311 -280.795075) (xy 366.777753 -280.839833) (xy 366.798804 -280.887929)
			(xy 366.813067 -280.938455) (xy 366.820272 -280.99046) (xy 366.820704 -281.01671) (xy 366.820218 -281.043961)
			(xy 366.81246 -281.097907) (xy 366.797104 -281.1502) (xy 366.774462 -281.199776) (xy 366.744995 -281.245625)
			(xy 366.709304 -281.286814) (xy 366.668114 -281.322504) (xy 366.622264 -281.351969) (xy 366.572687 -281.374609)
			(xy 366.520393 -281.389963) (xy 366.466447 -281.397719) (xy 366.439196 -281.398218) (xy 366.410398 -281.397692)
			(xy 366.353456 -281.389031) (xy 366.298464 -281.371908) (xy 366.246672 -281.346711) (xy 366.199257 -281.314013)
			(xy 366.157297 -281.274557) (xy 366.121747 -281.229242) (xy 366.093414 -281.179096) (xy 366.072943 -281.125261)
			(xy 366.066324 -281.097228) (xy 366.063784 -281.086306) (xy 366.057434 -281.07767) (xy 366.054173 -281.073481)
			(xy 366.046236 -281.066434) (xy 366.041686 -281.0637) (xy 366.041178 -281.063446) (xy 365.975392 -281.027124)
			(xy 365.973106 -281.025854) (xy 365.965862 -281.022679) (xy 365.950209 -281.020473) (xy 365.942372 -281.021536)
			(xy 365.933736 -281.02306) (xy 365.929672 -281.02433) (xy 365.918488 -281.028125) (xy 365.895738 -281.03448)
			(xy 365.884206 -281.03703) (xy 365.867188 -281.04084) (xy 365.861346 -281.041602) (xy 365.8489 -281.042872)
			(xy 365.838206 -281.044036) (xy 365.81673 -281.045306) (xy 365.805974 -281.045412) (xy 365.63554 -281.045412)
			(xy 365.629531 -281.04558) (xy 365.61785 -281.048407) (xy 365.612426 -281.051) (xy 365.60895 -281.052837)
			(xy 365.602567 -281.057427) (xy 365.599726 -281.060144) (xy 365.238284 -281.421586) (xy 365.218818 -281.440365)
			(xy 365.175536 -281.472804) (xy 365.128107 -281.498805) (xy 365.077483 -281.51785) (xy 365.024676 -281.529555)
			(xy 364.997746 -281.532076) (xy 364.98784 -281.532838) (xy 364.968536 -281.533346) (xy 364.941317 -281.532865)
			(xy 364.88743 -281.525133) (xy 364.83519 -281.509819) (xy 364.785656 -281.487237) (xy 364.739835 -281.457843)
			(xy 364.698658 -281.422234) (xy 364.662959 -281.381135) (xy 364.633465 -281.335378) (xy 364.610774 -281.285895)
			(xy 364.595346 -281.233688) (xy 364.587495 -281.179818) (xy 364.587028 -281.1526) (xy 364.587028 -281.147774)
			(xy 364.588095 -281.114655) (xy 364.600236 -281.049519) (xy 364.611158 -281.018234) (xy 364.611412 -281.017472)
			(xy 364.613272 -281.011958) (xy 364.614689 -281.000411) (xy 364.614206 -280.994612) (xy 364.612936 -280.983436)
			(xy 364.578646 -280.930604) (xy 364.578646 -280.930096) (xy 364.560612 -280.902918) (xy 364.556665 -280.897712)
			(xy 364.546633 -280.88935) (xy 364.5408 -280.886408) (xy 364.531148 -280.882344) (xy 364.505494 -280.880312)
			(xy 364.47222 -280.874978) (xy 364.455278 -280.87135) (xy 364.422079 -280.861431) (xy 364.405926 -280.855166)
			(xy 364.404656 -280.854658) (xy 364.401608 -280.853388) (xy 364.388654 -280.850594) (xy 364.380815 -280.849542)
			(xy 364.365162 -280.851734) (xy 364.35792 -280.854912) (xy 364.34522 -280.861008) (xy 364.343442 -280.86177)
			(xy 364.291118 -280.886662) (xy 364.286372 -280.88903) (xy 364.277918 -280.895434) (xy 364.274354 -280.899362)
			(xy 364.267496 -280.90749) (xy 364.266988 -280.909522) (xy 364.264194 -280.919428) (xy 364.259148 -280.935644)
			(xy 364.246558 -280.967188) (xy 364.239048 -280.98242) (xy 364.231428 -280.997152) (xy 364.229142 -281.000962)
			(xy 364.219998 -281.015694) (xy 364.204907 -281.038473) (xy 364.169244 -281.07987) (xy 364.128042 -281.115758)
			(xy 364.082142 -281.145403) (xy 364.032484 -281.168199) (xy 363.980082 -281.183679) (xy 363.926008 -281.191526)
			(xy 363.898688 -281.19197) (xy 363.89818 -281.19197) (xy 363.863382 -281.190192) (xy 363.85373 -281.189176)
			(xy 363.83595 -281.186636) (xy 363.807502 -281.180794) (xy 363.807248 -281.18054) (xy 363.80674 -281.18054)
			(xy 363.796834 -281.178) (xy 363.787182 -281.17927) (xy 363.781956 -281.180067) (xy 363.771968 -281.183521)
			(xy 363.76737 -281.186128) (xy 363.754162 -281.194002) (xy 363.753654 -281.194002) (xy 363.707426 -281.220672)
			(xy 363.699819 -281.225404) (xy 363.688244 -281.239063) (xy 363.68482 -281.247342) (xy 363.676922 -281.273691)
			(xy 363.6546 -281.323965) (xy 363.625291 -281.370512) (xy 363.5896 -281.412367) (xy 363.548269 -281.448663)
			(xy 363.502154 -281.478647) (xy 363.45221 -281.501699) (xy 363.399474 -281.517338) (xy 363.345039 -281.525243)
			(xy 363.317536 -281.525726) (xy 363.290281 -281.525266) (xy 363.236325 -281.517513) (xy 363.184022 -281.50216)
			(xy 363.134436 -281.47952) (xy 363.088577 -281.450053) (xy 363.047379 -281.41436) (xy 363.011679 -281.373166)
			(xy 362.982206 -281.327311) (xy 362.959559 -281.277729) (xy 362.944199 -281.225428) (xy 362.936438 -281.171473)
			(xy 362.936028 -281.144218) (xy 362.936087 -281.133655) (xy 362.937232 -281.112561) (xy 362.938314 -281.102054)
			(xy 362.938314 -281.101546) (xy 362.93888 -281.092246) (xy 362.93405 -281.07427) (xy 362.928916 -281.066494)
			(xy 362.88853 -281.010868) (xy 362.884591 -281.005779) (xy 362.874692 -280.997563) (xy 362.868972 -280.994612)
			(xy 362.857288 -280.990802) (xy 362.854748 -280.990294) (xy 362.826661 -280.983738) (xy 362.772726 -280.963307)
			(xy 362.722483 -280.934986) (xy 362.677078 -280.899423) (xy 362.637546 -280.857428) (xy 362.604788 -280.809958)
			(xy 362.579553 -280.758098) (xy 362.562414 -280.703028) (xy 362.553764 -280.646006) (xy 362.55325 -280.617168)
			(xy 362.553736 -280.589917) (xy 362.561492 -280.535969) (xy 362.576847 -280.483674) (xy 362.599489 -280.434097)
			(xy 362.628955 -280.388247) (xy 362.664646 -280.347056) (xy 362.705837 -280.311365) (xy 362.751687 -280.281899)
			(xy 362.801264 -280.259257) (xy 362.853559 -280.243902) (xy 362.907507 -280.236146) (xy 362.962009 -280.236146)
			(xy 363.015957 -280.243902) (xy 363.068252 -280.259257) (xy 363.117829 -280.281899) (xy 363.163679 -280.311365)
			(xy 363.20487 -280.347056) (xy 363.240561 -280.388247) (xy 363.270027 -280.434097) (xy 363.292669 -280.483674)
			(xy 363.308024 -280.535969) (xy 363.31578 -280.589917) (xy 363.316266 -280.617168) (xy 363.316208 -280.627731)
			(xy 363.315064 -280.648825) (xy 363.31398 -280.659332) (xy 363.31398 -280.65984) (xy 363.313411 -280.66914)
			(xy 363.318237 -280.68712) (xy 363.323378 -280.694892) (xy 363.343698 -280.722832) (xy 363.365034 -280.752042)
			(xy 363.36905 -280.756858) (xy 363.378942 -280.764561) (xy 363.384592 -280.767282) (xy 363.392974 -280.770076)
			(xy 363.393736 -280.77033) (xy 363.39399 -280.77033) (xy 363.394752 -280.770584) (xy 363.39907 -280.771346)
			(xy 363.400594 -280.771854) (xy 363.407198 -280.773378) (xy 363.40923 -280.773886) (xy 363.419136 -280.776426)
			(xy 363.428788 -280.775156) (xy 363.434014 -280.774361) (xy 363.444003 -280.770907) (xy 363.4486 -280.768298)
			(xy 363.461808 -280.760424) (xy 363.462316 -280.760424) (xy 363.508544 -280.733754) (xy 363.516157 -280.729027)
			(xy 363.527744 -280.715372) (xy 363.53115 -280.707084) (xy 363.539046 -280.680733) (xy 363.561365 -280.630454)
			(xy 363.590673 -280.583901) (xy 363.626362 -280.54204) (xy 363.667693 -280.505739) (xy 363.713808 -280.475749)
			(xy 363.763753 -280.452692) (xy 363.816491 -280.437047) (xy 363.870929 -280.429138) (xy 363.898434 -280.4287)
			(xy 363.913166 -280.4287) (xy 363.94623 -280.430688) (xy 364.010983 -280.444612) (xy 364.041944 -280.456386)
			(xy 364.047024 -280.458418) (xy 364.056168 -280.46045) (xy 364.064361 -280.461788) (xy 364.080819 -280.459711)
			(xy 364.088426 -280.456386) (xy 364.157768 -280.42362) (xy 364.165134 -280.420064) (xy 364.17885 -280.404062)
			(xy 364.180628 -280.398728) (xy 364.182152 -280.39314) (xy 364.19097 -280.365239) (xy 364.215901 -280.312304)
			(xy 364.248619 -280.263794) (xy 364.288355 -280.220845) (xy 364.33418 -280.184462) (xy 364.385021 -280.155497)
			(xy 364.439685 -280.13463) (xy 364.496894 -280.122349) (xy 364.526068 -280.12009) (xy 364.526322 -280.12009)
			(xy 364.537752 -280.119328) (xy 364.54461 -280.115772) (xy 364.547658 -280.113994) (xy 364.552704 -280.111095)
			(xy 364.561437 -280.103408) (xy 364.56493 -280.098754) (xy 364.58779 -280.066496) (xy 364.610904 -280.033984)
			(xy 364.611158 -280.033476) (xy 364.612174 -280.031952) (xy 364.617055 -280.02355) (xy 364.620699 -280.004482)
			(xy 364.619286 -279.994868) (xy 364.61827 -279.991058) (xy 364.611505 -279.965621) (xy 364.604237 -279.91349)
			(xy 364.603792 -279.887172) (xy 364.603792 -279.886918) (xy 364.604253 -279.859684) (xy 364.612003 -279.805769)
			(xy 364.627348 -279.753506) (xy 364.649975 -279.70396) (xy 364.679424 -279.658138) (xy 364.715095 -279.616975)
			(xy 364.756261 -279.581307) (xy 364.802085 -279.551862) (xy 364.851633 -279.529238) (xy 364.903896 -279.513898)
			(xy 364.957812 -279.506151) (xy 364.985046 -279.505664) (xy 364.985554 -279.505664) (xy 365.015469 -279.506275)
			(xy 365.074557 -279.515668) (xy 365.131455 -279.53417) (xy 365.184767 -279.561327) (xy 365.233187 -279.596472)
			(xy 365.254794 -279.61717) (xy 365.384334 -279.74671) (xy 365.395299 -279.756933) (xy 365.421718 -279.771073)
			(xy 365.451102 -279.776941) (xy 365.480925 -279.774031) (xy 365.508622 -279.762594) (xy 365.531809 -279.743614)
			(xy 365.548492 -279.718724) (xy 365.557237 -279.690063) (xy 365.557816 -279.675082) (xy 365.557816 -279.472136)
			(xy 365.557647 -279.466127) (xy 365.554821 -279.454446) (xy 365.552228 -279.449022) (xy 365.550391 -279.445546)
			(xy 365.545803 -279.439161) (xy 365.543084 -279.436322) (xy 363.935518 -277.828756) (xy 363.91818 -277.810805)
			(xy 363.88783 -277.771187) (xy 363.862894 -277.727956) (xy 363.852968 -277.705058) (xy 363.389926 -276.586696)
			(xy 363.143292 -275.99132) (xy 363.143038 -275.990812) (xy 363.129322 -275.954744) (xy 363.128306 -275.951696)
			(xy 363.12014 -275.923893) (xy 363.111341 -275.866622) (xy 363.11078 -275.83765) (xy 363.11078 -268.253464)
			(xy 363.110614 -268.247454) (xy 363.107792 -268.235771) (xy 363.105192 -268.23035) (xy 363.10335 -268.226877)
			(xy 363.098754 -268.220502) (xy 363.096048 -268.21765) (xy 358.711754 -263.833356) (xy 358.708385 -263.830159)
			(xy 358.700716 -263.824922) (xy 358.696514 -263.822942) (xy 355.496368 -262.497062) (xy 355.486716 -262.494268)
			(xy 355.4857 -262.494268) (xy 355.47681 -262.493252) (xy 355.100636 -262.493252) (xy 355.091353 -262.493649)
			(xy 355.074016 -262.500287) (xy 355.066854 -262.506206) (xy 354.974652 -262.598408) (xy 354.900992 -262.671814)
			(xy 354.898544 -262.674395) (xy 354.894338 -262.680134) (xy 354.89261 -262.683244) (xy 354.890234 -262.688016)
			(xy 354.887288 -262.698259) (xy 354.886768 -262.703564) (xy 354.886768 -263.18337) (xy 355.16896 -263.18337)
			(xy 355.173031 -263.127748) (xy 355.185157 -263.073311) (xy 355.20508 -263.02122) (xy 355.232376 -262.972585)
			(xy 355.266462 -262.928442) (xy 355.306611 -262.889733) (xy 355.351969 -262.857282) (xy 355.401569 -262.831781)
			(xy 355.454353 -262.813774) (xy 355.509196 -262.803644) (xy 355.56493 -262.801607) (xy 355.620367 -262.807707)
			(xy 355.674324 -262.821813) (xy 355.725653 -262.843625) (xy 355.773259 -262.872679) (xy 355.816127 -262.908354)
			(xy 355.853344 -262.949891) (xy 355.884117 -262.996404) (xy 355.907789 -263.046901) (xy 355.923857 -263.100308)
			(xy 355.931977 -263.155484) (xy 355.932486 -263.18337) (xy 355.931977 -263.211256) (xy 355.923857 -263.266432)
			(xy 355.907789 -263.319839) (xy 355.884117 -263.370336) (xy 355.853344 -263.416849) (xy 355.816127 -263.458386)
			(xy 355.773259 -263.494061) (xy 355.725653 -263.523115) (xy 355.674324 -263.544927) (xy 355.620367 -263.559033)
			(xy 355.56493 -263.565133) (xy 355.509196 -263.563096) (xy 355.454353 -263.552966) (xy 355.401569 -263.534959)
			(xy 355.351969 -263.509458) (xy 355.306611 -263.477007) (xy 355.266462 -263.438298) (xy 355.232376 -263.394155)
			(xy 355.20508 -263.34552) (xy 355.185157 -263.293429) (xy 355.173031 -263.238992) (xy 355.16896 -263.18337)
			(xy 354.886768 -263.18337) (xy 354.886768 -264.103866) (xy 355.18039 -264.103866) (xy 355.184461 -264.048244)
			(xy 355.196587 -263.993807) (xy 355.21651 -263.941716) (xy 355.243806 -263.893081) (xy 355.277892 -263.848938)
			(xy 355.318041 -263.810229) (xy 355.363399 -263.777778) (xy 355.412999 -263.752277) (xy 355.465783 -263.73427)
			(xy 355.520626 -263.72414) (xy 355.57636 -263.722103) (xy 355.631797 -263.728203) (xy 355.685754 -263.742309)
			(xy 355.737083 -263.764121) (xy 355.784689 -263.793175) (xy 355.827557 -263.82885) (xy 355.864774 -263.870387)
			(xy 355.895547 -263.9169) (xy 355.919219 -263.967397) (xy 355.935287 -264.020804) (xy 355.943407 -264.07598)
			(xy 355.943916 -264.103866) (xy 355.943407 -264.131752) (xy 355.935287 -264.186928) (xy 355.919219 -264.240335)
			(xy 355.895547 -264.290832) (xy 355.864774 -264.337345) (xy 355.827557 -264.378882) (xy 355.784689 -264.414557)
			(xy 355.737083 -264.443611) (xy 355.685754 -264.465423) (xy 355.631797 -264.479529) (xy 355.57636 -264.485629)
			(xy 355.520626 -264.483592) (xy 355.465783 -264.473462) (xy 355.412999 -264.455455) (xy 355.363399 -264.429954)
			(xy 355.318041 -264.397503) (xy 355.277892 -264.358794) (xy 355.243806 -264.314651) (xy 355.21651 -264.266016)
			(xy 355.196587 -264.213925) (xy 355.184461 -264.159488) (xy 355.18039 -264.103866) (xy 354.886768 -264.103866)
			(xy 354.886768 -265.453622) (xy 354.88753 -265.462258) (xy 354.889135 -265.469774) (xy 354.896119 -265.483455)
			(xy 354.901246 -265.489182) (xy 355.77526 -266.36345) (xy 355.77526 -266.363704) (xy 355.906578 -266.494768)
			(xy 355.927314 -266.516344) (xy 355.962478 -266.56476) (xy 355.989641 -266.618079) (xy 356.008134 -266.674988)
			(xy 356.017503 -266.734089) (xy 356.018084 -266.764008) (xy 356.018084 -269.417038) (xy 357.085646 -269.417038)
			(xy 357.086146 -269.388298) (xy 357.094777 -269.331471) (xy 357.111833 -269.27658) (xy 357.13693 -269.224869)
			(xy 357.169498 -269.177507) (xy 357.18877 -269.15618) (xy 357.195374 -269.149322) (xy 357.202486 -269.131288)
			(xy 357.202486 -269.042388) (xy 357.195374 -269.024354) (xy 357.18877 -269.017496) (xy 357.169523 -268.996149)
			(xy 357.136952 -268.948793) (xy 357.111854 -268.897086) (xy 357.094798 -268.8422) (xy 357.08617 -268.785376)
			(xy 357.085646 -268.756638) (xy 357.086213 -268.72939) (xy 357.093964 -268.675447) (xy 357.109312 -268.623157)
			(xy 357.131945 -268.573583) (xy 357.161403 -268.527735) (xy 357.197086 -268.486545) (xy 357.238267 -268.450853)
			(xy 357.284109 -268.421385) (xy 357.333678 -268.398741) (xy 357.385965 -268.383381) (xy 357.439906 -268.375619)
			(xy 357.467154 -268.37513) (xy 357.494524 -268.375616) (xy 357.548702 -268.383428) (xy 357.601205 -268.398912)
			(xy 357.650953 -268.421749) (xy 357.69692 -268.45147) (xy 357.717852 -268.46911) (xy 357.718106 -268.469364)
			(xy 357.725181 -268.474967) (xy 357.742107 -268.481202) (xy 357.751126 -268.481556) (xy 357.818182 -268.481556)
			(xy 357.827199 -268.4812) (xy 357.844117 -268.474953) (xy 357.851202 -268.469364) (xy 357.851202 -268.46911)
			(xy 357.851456 -268.46911) (xy 357.872389 -268.451469) (xy 357.918357 -268.421745) (xy 357.968103 -268.398899)
			(xy 358.020605 -268.383403) (xy 358.074783 -268.375574) (xy 358.129525 -268.375574) (xy 358.183703 -268.383403)
			(xy 358.236205 -268.398899) (xy 358.285951 -268.421745) (xy 358.331919 -268.451469) (xy 358.352852 -268.46911)
			(xy 358.353106 -268.469364) (xy 358.360181 -268.474967) (xy 358.377107 -268.481202) (xy 358.386126 -268.481556)
			(xy 358.453182 -268.481556) (xy 358.462199 -268.4812) (xy 358.479117 -268.474953) (xy 358.486202 -268.469364)
			(xy 358.486202 -268.46911) (xy 358.486456 -268.46911) (xy 358.507389 -268.451469) (xy 358.553357 -268.421745)
			(xy 358.603103 -268.398899) (xy 358.655605 -268.383403) (xy 358.709783 -268.375574) (xy 358.764525 -268.375574)
			(xy 358.818703 -268.383403) (xy 358.871205 -268.398899) (xy 358.920951 -268.421745) (xy 358.966919 -268.451469)
			(xy 358.987852 -268.46911) (xy 358.988106 -268.469364) (xy 358.995181 -268.474967) (xy 359.012107 -268.481202)
			(xy 359.021126 -268.481556) (xy 359.088182 -268.481556) (xy 359.097199 -268.4812) (xy 359.114117 -268.474953)
			(xy 359.121202 -268.469364) (xy 359.121202 -268.46911) (xy 359.121456 -268.46911) (xy 359.142389 -268.451469)
			(xy 359.188357 -268.421745) (xy 359.238103 -268.398899) (xy 359.290605 -268.383403) (xy 359.344783 -268.375574)
			(xy 359.399525 -268.375574) (xy 359.453703 -268.383403) (xy 359.506205 -268.398899) (xy 359.555951 -268.421745)
			(xy 359.601919 -268.451469) (xy 359.622852 -268.46911) (xy 359.623106 -268.469364) (xy 359.630181 -268.474967)
			(xy 359.647107 -268.481202) (xy 359.656126 -268.481556) (xy 359.723182 -268.481556) (xy 359.732199 -268.4812)
			(xy 359.749117 -268.474953) (xy 359.756202 -268.469364) (xy 359.756202 -268.46911) (xy 359.756456 -268.46911)
			(xy 359.777395 -268.45148) (xy 359.823366 -268.421766) (xy 359.873112 -268.398928) (xy 359.925611 -268.383435)
			(xy 359.979785 -268.375605) (xy 360.007154 -268.37513) (xy 360.034407 -268.375598) (xy 360.08836 -268.38335)
			(xy 360.14066 -268.398702) (xy 360.190243 -268.421342) (xy 360.236098 -268.450809) (xy 360.277292 -268.486502)
			(xy 360.312987 -268.527696) (xy 360.342454 -268.57355) (xy 360.365095 -268.623132) (xy 360.380448 -268.675432)
			(xy 360.388201 -268.729385) (xy 360.388662 -268.756638) (xy 360.388145 -268.785377) (xy 360.379518 -268.842204)
			(xy 360.362466 -268.897094) (xy 360.337373 -268.948806) (xy 360.304808 -268.996169) (xy 360.285538 -269.017496)
			(xy 360.278934 -269.024354) (xy 360.271822 -269.042388) (xy 360.271822 -269.131288) (xy 360.278934 -269.149322)
			(xy 360.285538 -269.15618) (xy 360.304823 -269.177495) (xy 360.337388 -269.22486) (xy 360.362478 -269.276574)
			(xy 360.379525 -269.331468) (xy 360.388144 -269.388298) (xy 360.388662 -269.417038) (xy 360.38828 -269.444294)
			(xy 360.380517 -269.49825) (xy 360.365154 -269.550552) (xy 360.342504 -269.600136) (xy 360.313027 -269.645991)
			(xy 360.277325 -269.687184) (xy 360.236124 -269.722878) (xy 360.190262 -269.752344) (xy 360.140674 -269.774983)
			(xy 360.088368 -269.790335) (xy 360.03441 -269.798086) (xy 360.007154 -269.798546) (xy 359.979784 -269.798061)
			(xy 359.925605 -269.79025) (xy 359.873102 -269.774766) (xy 359.823355 -269.751928) (xy 359.777388 -269.722206)
			(xy 359.756456 -269.704566) (xy 359.756202 -269.704312) (xy 359.749118 -269.698721) (xy 359.732199 -269.692477)
			(xy 359.723182 -269.69212) (xy 359.656126 -269.69212) (xy 359.64711 -269.692485) (xy 359.630193 -269.698727)
			(xy 359.623106 -269.704312) (xy 359.622852 -269.704566) (xy 359.601919 -269.722207) (xy 359.555951 -269.751931)
			(xy 359.506205 -269.774777) (xy 359.453703 -269.790273) (xy 359.399525 -269.798102) (xy 359.344783 -269.798102)
			(xy 359.290605 -269.790273) (xy 359.238103 -269.774777) (xy 359.188357 -269.751931) (xy 359.142389 -269.722207)
			(xy 359.121456 -269.704566) (xy 359.121202 -269.704312) (xy 359.114118 -269.698721) (xy 359.097199 -269.692477)
			(xy 359.088182 -269.69212) (xy 359.021126 -269.69212) (xy 359.01211 -269.692485) (xy 358.995193 -269.698727)
			(xy 358.988106 -269.704312) (xy 358.988106 -269.704566) (xy 358.987852 -269.704566) (xy 358.966919 -269.722207)
			(xy 358.920951 -269.751931) (xy 358.871205 -269.774777) (xy 358.818703 -269.790273) (xy 358.764525 -269.798102)
			(xy 358.709783 -269.798102) (xy 358.655605 -269.790273) (xy 358.603103 -269.774777) (xy 358.553357 -269.751931)
			(xy 358.507389 -269.722207) (xy 358.486456 -269.704566) (xy 358.486202 -269.704312) (xy 358.479118 -269.698721)
			(xy 358.462199 -269.692477) (xy 358.453182 -269.69212) (xy 358.386126 -269.69212) (xy 358.37711 -269.692485)
			(xy 358.360193 -269.698727) (xy 358.353106 -269.704312) (xy 358.353106 -269.704566) (xy 358.352852 -269.704566)
			(xy 358.331919 -269.722207) (xy 358.285951 -269.751931) (xy 358.236205 -269.774777) (xy 358.183703 -269.790273)
			(xy 358.129525 -269.798102) (xy 358.074783 -269.798102) (xy 358.020605 -269.790273) (xy 357.968103 -269.774777)
			(xy 357.918357 -269.751931) (xy 357.872389 -269.722207) (xy 357.851456 -269.704566) (xy 357.851202 -269.704312)
			(xy 357.844118 -269.698721) (xy 357.827199 -269.692477) (xy 357.818182 -269.69212) (xy 357.751126 -269.69212)
			(xy 357.74211 -269.692485) (xy 357.725193 -269.698727) (xy 357.718106 -269.704312) (xy 357.718106 -269.704566)
			(xy 357.717852 -269.704566) (xy 357.696907 -269.722189) (xy 357.650938 -269.751904) (xy 357.601194 -269.774744)
			(xy 357.548696 -269.790239) (xy 357.494522 -269.79807) (xy 357.467154 -269.798546) (xy 357.439903 -269.798065)
			(xy 357.385957 -269.790303) (xy 357.333665 -269.774944) (xy 357.28409 -269.752301) (xy 357.238242 -269.722833)
			(xy 357.197053 -269.687141) (xy 357.161362 -269.645952) (xy 357.131896 -269.600103) (xy 357.109253 -269.550528)
			(xy 357.093895 -269.498235) (xy 357.086134 -269.444289) (xy 357.085646 -269.417038) (xy 356.018084 -269.417038)
			(xy 356.018084 -276.046184) (xy 356.66045 -276.046184) (xy 356.660895 -276.018813) (xy 356.668716 -275.964632)
			(xy 356.684209 -275.912129) (xy 356.707056 -275.862382) (xy 356.736786 -275.816417) (xy 356.75443 -275.795486)
			(xy 356.754684 -275.795232) (xy 356.760262 -275.788139) (xy 356.766514 -275.771227) (xy 356.766876 -275.762212)
			(xy 356.766876 -275.695156) (xy 356.766497 -275.686141) (xy 356.760265 -275.669224) (xy 356.754684 -275.662136)
			(xy 356.75443 -275.662136) (xy 356.75443 -275.661882) (xy 356.736821 -275.640926) (xy 356.707103 -275.59496)
			(xy 356.684261 -275.545219) (xy 356.668763 -275.492723) (xy 356.660928 -275.438552) (xy 356.66045 -275.411184)
			(xy 356.660963 -275.383934) (xy 356.66872 -275.32999) (xy 356.684075 -275.277698) (xy 356.706715 -275.228124)
			(xy 356.736179 -275.182275) (xy 356.771868 -275.141086) (xy 356.813054 -275.105395) (xy 356.858901 -275.075928)
			(xy 356.908474 -275.053285) (xy 356.960764 -275.037926) (xy 357.014708 -275.030165) (xy 357.041958 -275.029676)
			(xy 357.069328 -275.030148) (xy 357.123508 -275.037962) (xy 357.176012 -275.053448) (xy 357.225759 -275.076289)
			(xy 357.271725 -275.106014) (xy 357.292656 -275.123656) (xy 357.29291 -275.12391) (xy 357.299989 -275.129508)
			(xy 357.316912 -275.135748) (xy 357.32593 -275.136102) (xy 357.392986 -275.136102) (xy 357.402002 -275.135738)
			(xy 357.418919 -275.129495) (xy 357.426006 -275.12391) (xy 357.426006 -275.123656) (xy 357.42626 -275.123656)
			(xy 357.447193 -275.106015) (xy 357.493161 -275.076291) (xy 357.542907 -275.053445) (xy 357.595409 -275.037949)
			(xy 357.649587 -275.03012) (xy 357.704329 -275.03012) (xy 357.758507 -275.037949) (xy 357.811009 -275.053445)
			(xy 357.860755 -275.076291) (xy 357.906723 -275.106015) (xy 357.927656 -275.123656) (xy 357.92791 -275.12391)
			(xy 357.934989 -275.129508) (xy 357.951912 -275.135748) (xy 357.96093 -275.136102) (xy 358.027986 -275.136102)
			(xy 358.037002 -275.135738) (xy 358.053919 -275.129495) (xy 358.061006 -275.12391) (xy 358.061006 -275.123656)
			(xy 358.06126 -275.123656) (xy 358.082193 -275.106015) (xy 358.128161 -275.076291) (xy 358.177907 -275.053445)
			(xy 358.230409 -275.037949) (xy 358.284587 -275.03012) (xy 358.339329 -275.03012) (xy 358.393507 -275.037949)
			(xy 358.446009 -275.053445) (xy 358.495755 -275.076291) (xy 358.541723 -275.106015) (xy 358.562656 -275.123656)
			(xy 358.56291 -275.12391) (xy 358.569989 -275.129508) (xy 358.586912 -275.135748) (xy 358.59593 -275.136102)
			(xy 358.662986 -275.136102) (xy 358.672002 -275.135738) (xy 358.688919 -275.129495) (xy 358.696006 -275.12391)
			(xy 358.696006 -275.123656) (xy 358.69626 -275.123656) (xy 358.717193 -275.106015) (xy 358.763161 -275.076291)
			(xy 358.812907 -275.053445) (xy 358.865409 -275.037949) (xy 358.919587 -275.03012) (xy 358.974329 -275.03012)
			(xy 359.028507 -275.037949) (xy 359.081009 -275.053445) (xy 359.130755 -275.076291) (xy 359.176723 -275.106015)
			(xy 359.197656 -275.123656) (xy 359.19791 -275.12391) (xy 359.204989 -275.129508) (xy 359.221912 -275.135748)
			(xy 359.23093 -275.136102) (xy 359.297986 -275.136102) (xy 359.307002 -275.135738) (xy 359.323919 -275.129495)
			(xy 359.331006 -275.12391) (xy 359.331006 -275.123656) (xy 359.33126 -275.123656) (xy 359.35219 -275.106015)
			(xy 359.398164 -275.076305) (xy 359.447912 -275.05347) (xy 359.500413 -275.037979) (xy 359.554589 -275.03015)
			(xy 359.581958 -275.029676) (xy 359.609209 -275.030194) (xy 359.663157 -275.037945) (xy 359.715453 -275.053295)
			(xy 359.765032 -275.075932) (xy 359.810885 -275.105394) (xy 359.852077 -275.141082) (xy 359.887772 -275.182269)
			(xy 359.917241 -275.228117) (xy 359.939885 -275.277693) (xy 359.955242 -275.329986) (xy 359.963002 -275.383933)
			(xy 359.963466 -275.411184) (xy 359.962999 -275.438554) (xy 359.955183 -275.492734) (xy 359.939694 -275.545237)
			(xy 359.916852 -275.594984) (xy 359.887128 -275.640951) (xy 359.869486 -275.661882) (xy 359.869232 -275.662136)
			(xy 359.863658 -275.669231) (xy 359.857406 -275.686142) (xy 359.85704 -275.695156) (xy 359.85704 -275.762212)
			(xy 359.857382 -275.771231) (xy 359.863639 -275.788148) (xy 359.869232 -275.795232) (xy 359.869486 -275.795232)
			(xy 359.869486 -275.795486) (xy 359.88713 -275.816414) (xy 359.916841 -275.862388) (xy 359.939677 -275.912136)
			(xy 359.955167 -275.964638) (xy 359.962993 -276.018815) (xy 359.963466 -276.046184) (xy 359.96303 -276.073438)
			(xy 359.955274 -276.127392) (xy 359.939918 -276.179693) (xy 359.917274 -276.229276) (xy 359.887804 -276.275131)
			(xy 359.852107 -276.316325) (xy 359.810911 -276.352019) (xy 359.765053 -276.381486) (xy 359.715469 -276.404127)
			(xy 359.663167 -276.419479) (xy 359.609212 -276.427232) (xy 359.581958 -276.427692) (xy 359.554589 -276.427194)
			(xy 359.500411 -276.419384) (xy 359.447908 -276.403903) (xy 359.398161 -276.381068) (xy 359.352193 -276.35135)
			(xy 359.33126 -276.333712) (xy 359.331006 -276.333458) (xy 359.323926 -276.327863) (xy 359.307004 -276.321622)
			(xy 359.297986 -276.321266) (xy 359.23093 -276.321266) (xy 359.221915 -276.321645) (xy 359.204999 -276.327878)
			(xy 359.19791 -276.333458) (xy 359.197656 -276.333712) (xy 359.176723 -276.351353) (xy 359.130755 -276.381077)
			(xy 359.081009 -276.403923) (xy 359.028507 -276.419419) (xy 358.974329 -276.427248) (xy 358.919587 -276.427248)
			(xy 358.865409 -276.419419) (xy 358.812907 -276.403923) (xy 358.763161 -276.381077) (xy 358.717193 -276.351353)
			(xy 358.69626 -276.333712) (xy 358.696006 -276.333458) (xy 358.688926 -276.327863) (xy 358.672004 -276.321622)
			(xy 358.662986 -276.321266) (xy 358.59593 -276.321266) (xy 358.586915 -276.321645) (xy 358.569999 -276.327878)
			(xy 358.56291 -276.333458) (xy 358.56291 -276.333712) (xy 358.562656 -276.333712) (xy 358.541723 -276.351353)
			(xy 358.495755 -276.381077) (xy 358.446009 -276.403923) (xy 358.393507 -276.419419) (xy 358.339329 -276.427248)
			(xy 358.284587 -276.427248) (xy 358.230409 -276.419419) (xy 358.177907 -276.403923) (xy 358.128161 -276.381077)
			(xy 358.082193 -276.351353) (xy 358.06126 -276.333712) (xy 358.061006 -276.333458) (xy 358.053926 -276.327863)
			(xy 358.037004 -276.321622) (xy 358.027986 -276.321266) (xy 357.96093 -276.321266) (xy 357.951915 -276.321645)
			(xy 357.934999 -276.327878) (xy 357.92791 -276.333458) (xy 357.92791 -276.333712) (xy 357.927656 -276.333712)
			(xy 357.906723 -276.351353) (xy 357.860755 -276.381077) (xy 357.811009 -276.403923) (xy 357.758507 -276.419419)
			(xy 357.704329 -276.427248) (xy 357.649587 -276.427248) (xy 357.595409 -276.419419) (xy 357.542907 -276.403923)
			(xy 357.493161 -276.381077) (xy 357.447193 -276.351353) (xy 357.42626 -276.333712) (xy 357.426006 -276.333458)
			(xy 357.418926 -276.327863) (xy 357.402004 -276.321622) (xy 357.392986 -276.321266) (xy 357.32593 -276.321266)
			(xy 357.316915 -276.321645) (xy 357.299999 -276.327878) (xy 357.29291 -276.333458) (xy 357.29291 -276.333712)
			(xy 357.292656 -276.333712) (xy 357.271715 -276.35134) (xy 357.225745 -276.381053) (xy 357.175999 -276.403891)
			(xy 357.123501 -276.419385) (xy 357.069327 -276.427216) (xy 357.041958 -276.427692) (xy 357.014705 -276.427261)
			(xy 356.960754 -276.419499) (xy 356.908458 -276.404137) (xy 356.858879 -276.38149) (xy 356.813028 -276.352018)
			(xy 356.771838 -276.316321) (xy 356.736147 -276.275125) (xy 356.706682 -276.22927) (xy 356.684042 -276.179688)
			(xy 356.668689 -276.127389) (xy 356.660935 -276.073437) (xy 356.66045 -276.046184) (xy 356.018084 -276.046184)
			(xy 356.018084 -276.313138) (xy 356.018513 -276.323206) (xy 356.026236 -276.341802) (xy 356.03307 -276.349206)
			(xy 356.180644 -276.49678) (xy 356.188044 -276.503622) (xy 356.206642 -276.511343) (xy 356.216712 -276.511766)
			(xy 356.322884 -276.617938) (xy 356.322884 -276.618446) (xy 356.323075 -276.624247) (xy 356.32578 -276.63553)
			(xy 356.328218 -276.640798) (xy 356.334822 -276.650704) (xy 357.32847 -277.644352) (xy 359.283762 -277.644352)
			(xy 359.284178 -277.618036) (xy 359.29142 -277.565904) (xy 359.305748 -277.51526) (xy 359.32689 -277.467061)
			(xy 359.354446 -277.422219) (xy 359.387895 -277.381582) (xy 359.406952 -277.363428) (xy 359.414336 -277.355891)
			(xy 359.422872 -277.336623) (xy 359.423462 -277.32609) (xy 359.423462 -277.251414) (xy 359.42295 -277.240862)
			(xy 359.414404 -277.221566) (xy 359.406952 -277.214076) (xy 359.387883 -277.195935) (xy 359.354429 -277.155301)
			(xy 359.326873 -277.110457) (xy 359.305737 -277.062254) (xy 359.291422 -277.011604) (xy 359.2842 -276.959469)
			(xy 359.283762 -276.933152) (xy 359.284248 -276.905901) (xy 359.292004 -276.851953) (xy 359.307359 -276.799658)
			(xy 359.330001 -276.750081) (xy 359.359467 -276.704231) (xy 359.395158 -276.66304) (xy 359.436349 -276.627349)
			(xy 359.482199 -276.597883) (xy 359.531776 -276.575241) (xy 359.584071 -276.559886) (xy 359.638019 -276.55213)
			(xy 359.692521 -276.55213) (xy 359.746469 -276.559886) (xy 359.798764 -276.575241) (xy 359.848341 -276.597883)
			(xy 359.894191 -276.627349) (xy 359.935382 -276.66304) (xy 359.971073 -276.704231) (xy 360.000539 -276.750081)
			(xy 360.023181 -276.799658) (xy 360.038536 -276.851953) (xy 360.046292 -276.905901) (xy 360.046778 -276.933152)
			(xy 360.046352 -276.959467) (xy 360.03911 -277.011598) (xy 360.024783 -277.062242) (xy 360.003643 -277.110441)
			(xy 359.976089 -277.155283) (xy 359.942643 -277.195921) (xy 359.923588 -277.214076) (xy 359.916193 -277.221603)
			(xy 359.907665 -277.240879) (xy 359.907078 -277.251414) (xy 359.907078 -277.32609) (xy 359.907605 -277.33664)
			(xy 359.916142 -277.355935) (xy 359.923588 -277.363428) (xy 359.942648 -277.381579) (xy 359.976105 -277.42221)
			(xy 360.003664 -277.467051) (xy 360.024802 -277.515252) (xy 360.039118 -277.565901) (xy 360.046341 -277.618036)
			(xy 360.046778 -277.644352) (xy 360.046292 -277.671603) (xy 360.038536 -277.725551) (xy 360.023181 -277.777846)
			(xy 360.000539 -277.827423) (xy 359.971073 -277.873273) (xy 359.935382 -277.914464) (xy 359.894191 -277.950155)
			(xy 359.848341 -277.979621) (xy 359.798764 -278.002263) (xy 359.746469 -278.017618) (xy 359.692521 -278.025374)
			(xy 359.638019 -278.025374) (xy 359.584071 -278.017618) (xy 359.531776 -278.002263) (xy 359.482199 -277.979621)
			(xy 359.436349 -277.950155) (xy 359.395158 -277.914464) (xy 359.359467 -277.873273) (xy 359.330001 -277.827423)
			(xy 359.307359 -277.777846) (xy 359.292004 -277.725551) (xy 359.284248 -277.671603) (xy 359.283762 -277.644352)
			(xy 357.32847 -277.644352) (xy 358.654604 -278.970486) (xy 358.675382 -278.992101) (xy 358.710616 -279.040607)
			(xy 358.737832 -279.094026) (xy 358.756361 -279.151044) (xy 358.765746 -279.210258) (xy 358.766364 -279.240234)
			(xy 358.766364 -280.138886) (xy 358.765807 -280.168867) (xy 358.756426 -280.22809) (xy 358.737893 -280.285115)
			(xy 358.710664 -280.338538) (xy 358.67541 -280.387041) (xy 358.654604 -280.408634) (xy 358.51084 -280.552398)
			(xy 358.50765 -280.555702) (xy 358.502407 -280.563241) (xy 358.500426 -280.567384) (xy 358.49813 -280.573003)
			(xy 358.495941 -280.584939) (xy 358.496108 -280.591006) (xy 358.499156 -280.646632) (xy 358.500426 -280.668984)
			(xy 358.500968 -280.673607) (xy 358.503516 -280.682557) (xy 358.505506 -280.686764) (xy 358.510332 -280.696162)
			(xy 358.518968 -280.70302) (xy 358.540614 -280.721252) (xy 358.578807 -280.763013) (xy 358.610419 -280.809954)
			(xy 358.634756 -280.861046) (xy 358.651287 -280.91517) (xy 358.659648 -280.971142) (xy 358.660192 -280.999438)
			(xy 358.660192 -280.999692) (xy 358.659729 -281.026945) (xy 358.651973 -281.080896) (xy 358.636618 -281.133194)
			(xy 358.613975 -281.182774) (xy 358.584507 -281.228627) (xy 358.548813 -281.269819) (xy 358.50762 -281.305512)
			(xy 358.461767 -281.334979) (xy 358.412186 -281.35762) (xy 358.359888 -281.372975) (xy 358.305937 -281.38073)
			(xy 358.278684 -281.3812) (xy 358.25016 -281.380667) (xy 358.193749 -281.37217) (xy 358.139232 -281.355368)
			(xy 358.087825 -281.330634) (xy 358.040674 -281.298522) (xy 357.99883 -281.259746) (xy 357.963228 -281.215171)
			(xy 357.934659 -281.165792) (xy 357.913762 -281.11271) (xy 357.906828 -281.085036) (xy 357.906828 -281.084782)
			(xy 357.906574 -281.083512) (xy 357.904248 -281.07569) (xy 357.895449 -281.061955) (xy 357.889302 -281.056588)
			(xy 357.882444 -281.051254) (xy 357.87457 -281.04846) (xy 357.870391 -281.047049) (xy 357.861707 -281.045514)
			(xy 357.857298 -281.045412) (xy 357.475028 -281.045412) (xy 357.469019 -281.045582) (xy 357.457339 -281.048411)
			(xy 357.451914 -281.051) (xy 357.448439 -281.052838) (xy 357.442057 -281.057428) (xy 357.439214 -281.060144)
			(xy 357.077772 -281.421586) (xy 357.058305 -281.440365) (xy 357.015023 -281.472802) (xy 356.967595 -281.498802)
			(xy 356.91697 -281.517845) (xy 356.864163 -281.529548) (xy 356.837234 -281.532076) (xy 356.827328 -281.532838)
			(xy 356.808024 -281.533346) (xy 356.780805 -281.532864) (xy 356.72692 -281.52513) (xy 356.674681 -281.509816)
			(xy 356.625149 -281.487233) (xy 356.57933 -281.457838) (xy 356.538153 -281.42223) (xy 356.502456 -281.381131)
			(xy 356.472963 -281.335375) (xy 356.450273 -281.285892) (xy 356.434846 -281.233686) (xy 356.426995 -281.179818)
			(xy 356.426516 -281.1526) (xy 356.426516 -281.147774) (xy 356.427583 -281.114655) (xy 356.439724 -281.049519)
			(xy 356.450646 -281.018234) (xy 356.4509 -281.017472) (xy 356.45276 -281.011958) (xy 356.454177 -281.000411)
			(xy 356.453694 -280.994612) (xy 356.452424 -280.983436) (xy 356.418134 -280.930604) (xy 356.418134 -280.930096)
			(xy 356.4001 -280.902918) (xy 356.396152 -280.897713) (xy 356.386119 -280.889353) (xy 356.380288 -280.886408)
			(xy 356.370636 -280.882344) (xy 356.344982 -280.880312) (xy 356.311708 -280.874978) (xy 356.294767 -280.871349)
			(xy 356.261568 -280.86143) (xy 356.245414 -280.855166) (xy 356.244144 -280.854658) (xy 356.241096 -280.853388)
			(xy 356.228142 -280.850594) (xy 356.220304 -280.849544) (xy 356.204652 -280.851739) (xy 356.197408 -280.854912)
			(xy 356.184708 -280.861008) (xy 356.18293 -280.86177) (xy 356.130606 -280.886662) (xy 356.12586 -280.889031)
			(xy 356.117409 -280.895436) (xy 356.113842 -280.899362) (xy 356.106984 -280.90749) (xy 356.106476 -280.909522)
			(xy 356.103682 -280.919428) (xy 356.098636 -280.935644) (xy 356.086045 -280.967187) (xy 356.078536 -280.98242)
			(xy 356.070916 -280.997152) (xy 356.06863 -281.000962) (xy 356.059486 -281.015694) (xy 356.044395 -281.038472)
			(xy 356.008732 -281.079869) (xy 355.967529 -281.115755) (xy 355.921629 -281.145399) (xy 355.871971 -281.168193)
			(xy 355.819569 -281.183671) (xy 355.765496 -281.191517) (xy 355.738176 -281.19197) (xy 355.737668 -281.19197)
			(xy 355.70287 -281.190192) (xy 355.693218 -281.189176) (xy 355.675438 -281.186636) (xy 355.64699 -281.180794)
			(xy 355.646736 -281.18054) (xy 355.646228 -281.18054) (xy 355.636322 -281.178) (xy 355.62667 -281.17927)
			(xy 355.621445 -281.180068) (xy 355.611458 -281.183524) (xy 355.606858 -281.186128) (xy 355.59365 -281.194002)
			(xy 355.593142 -281.194002) (xy 355.546914 -281.220672) (xy 355.539308 -281.225405) (xy 355.527736 -281.239065)
			(xy 355.524308 -281.247342) (xy 355.516409 -281.27369) (xy 355.494088 -281.323963) (xy 355.464778 -281.370509)
			(xy 355.429087 -281.412363) (xy 355.387756 -281.448658) (xy 355.34164 -281.478641) (xy 355.291697 -281.501691)
			(xy 355.238961 -281.517329) (xy 355.184527 -281.525232) (xy 355.157024 -281.525726) (xy 355.12977 -281.525265)
			(xy 355.075815 -281.517511) (xy 355.023513 -281.502157) (xy 354.973929 -281.479516) (xy 354.928071 -281.450049)
			(xy 354.886874 -281.414355) (xy 354.851176 -281.373162) (xy 354.821704 -281.327308) (xy 354.799058 -281.277726)
			(xy 354.783698 -281.225426) (xy 354.775938 -281.171472) (xy 354.775516 -281.144218) (xy 354.775575 -281.133655)
			(xy 354.77672 -281.112561) (xy 354.777802 -281.102054) (xy 354.777802 -281.101546) (xy 354.778368 -281.092247)
			(xy 354.773537 -281.074271) (xy 354.768404 -281.066494) (xy 354.728018 -281.010868) (xy 354.724079 -281.005779)
			(xy 354.714178 -280.997565) (xy 354.70846 -280.994612) (xy 354.696776 -280.990802) (xy 354.694236 -280.990294)
			(xy 354.666149 -280.983737) (xy 354.612216 -280.963305) (xy 354.561975 -280.934984) (xy 354.516571 -280.89942)
			(xy 354.47704 -280.857425) (xy 354.444284 -280.809956) (xy 354.419049 -280.758096) (xy 354.401911 -280.703027)
			(xy 354.393261 -280.646005) (xy 354.392738 -280.617168) (xy 354.393224 -280.589917) (xy 354.40098 -280.535969)
			(xy 354.416335 -280.483674) (xy 354.438977 -280.434097) (xy 354.468443 -280.388247) (xy 354.504134 -280.347056)
			(xy 354.545325 -280.311365) (xy 354.591175 -280.281899) (xy 354.640752 -280.259257) (xy 354.693047 -280.243902)
			(xy 354.746995 -280.236146) (xy 354.801497 -280.236146) (xy 354.855445 -280.243902) (xy 354.90774 -280.259257)
			(xy 354.957317 -280.281899) (xy 355.003167 -280.311365) (xy 355.044358 -280.347056) (xy 355.080049 -280.388247)
			(xy 355.109515 -280.434097) (xy 355.132157 -280.483674) (xy 355.147512 -280.535969) (xy 355.155268 -280.589917)
			(xy 355.155754 -280.617168) (xy 355.155696 -280.627731) (xy 355.154551 -280.648825) (xy 355.153468 -280.659332)
			(xy 355.153468 -280.65984) (xy 355.152899 -280.669141) (xy 355.157724 -280.687121) (xy 355.162866 -280.694892)
			(xy 355.186742 -280.727658) (xy 355.204522 -280.752042) (xy 355.208537 -280.756859) (xy 355.218428 -280.764565)
			(xy 355.22408 -280.767282) (xy 355.232462 -280.770076) (xy 355.233224 -280.77033) (xy 355.233478 -280.77033)
			(xy 355.23424 -280.770584) (xy 355.238558 -280.771346) (xy 355.240082 -280.771854) (xy 355.246686 -280.773378)
			(xy 355.248718 -280.773886) (xy 355.258624 -280.776426) (xy 355.268276 -280.775156) (xy 355.273503 -280.774362)
			(xy 355.283493 -280.770911) (xy 355.288088 -280.768298) (xy 355.301296 -280.760424) (xy 355.301804 -280.760424)
			(xy 355.348032 -280.733754) (xy 355.355646 -280.729028) (xy 355.367236 -280.715374) (xy 355.370638 -280.707084)
			(xy 355.378534 -280.680732) (xy 355.400852 -280.630453) (xy 355.43016 -280.583899) (xy 355.465849 -280.542037)
			(xy 355.50718 -280.505734) (xy 355.553295 -280.475743) (xy 355.60324 -280.452685) (xy 355.655978 -280.437038)
			(xy 355.710417 -280.429127) (xy 355.737922 -280.4287) (xy 355.752654 -280.4287) (xy 355.785718 -280.430687)
			(xy 355.850472 -280.444609) (xy 355.881432 -280.456386) (xy 355.886512 -280.458418) (xy 355.895656 -280.46045)
			(xy 355.903849 -280.46179) (xy 355.92031 -280.459717) (xy 355.927914 -280.456386) (xy 355.997256 -280.42362)
			(xy 356.004622 -280.420064) (xy 356.018338 -280.404062) (xy 356.020116 -280.398728) (xy 356.02164 -280.39314)
			(xy 356.030459 -280.365242) (xy 356.055393 -280.312314) (xy 356.088113 -280.263812) (xy 356.127851 -280.220871)
			(xy 356.173678 -280.184498) (xy 356.224518 -280.155545) (xy 356.279182 -280.13469) (xy 356.336389 -280.122422)
			(xy 356.365556 -280.12009) (xy 356.36581 -280.12009) (xy 356.37724 -280.119328) (xy 356.384098 -280.115772)
			(xy 356.387146 -280.113994) (xy 356.392186 -280.111089) (xy 356.400907 -280.103393) (xy 356.404418 -280.098754)
			(xy 356.427278 -280.066496) (xy 356.450392 -280.033984) (xy 356.450646 -280.033476) (xy 356.451662 -280.031952)
			(xy 356.456544 -280.023551) (xy 356.460188 -280.004482) (xy 356.458774 -279.994868) (xy 356.457758 -279.991058)
			(xy 356.450993 -279.965621) (xy 356.443725 -279.91349) (xy 356.44328 -279.887172) (xy 356.44328 -279.886918)
			(xy 356.443741 -279.859683) (xy 356.451491 -279.805768) (xy 356.466836 -279.753505) (xy 356.489463 -279.703958)
			(xy 356.518911 -279.658135) (xy 356.554582 -279.61697) (xy 356.595748 -279.581302) (xy 356.641572 -279.551855)
			(xy 356.69112 -279.52923) (xy 356.743384 -279.513888) (xy 356.797299 -279.50614) (xy 356.824534 -279.505664)
			(xy 356.825042 -279.505664) (xy 356.854957 -279.506274) (xy 356.914046 -279.515666) (xy 356.970945 -279.534166)
			(xy 357.024259 -279.561322) (xy 357.07268 -279.596466) (xy 357.094282 -279.61717) (xy 357.36403 -279.886918)
			(xy 357.36946 -279.891899) (xy 357.382499 -279.898748) (xy 357.389684 -279.90038) (xy 357.390192 -279.90038)
			(xy 357.39959 -279.901396) (xy 357.478584 -279.901396) (xy 357.487982 -279.90038) (xy 357.48849 -279.90038)
			(xy 357.495648 -279.898674) (xy 357.508672 -279.891838) (xy 357.514144 -279.886918) (xy 357.60787 -279.793192)
			(xy 357.612849 -279.787761) (xy 357.619696 -279.774722) (xy 357.621332 -279.767538) (xy 357.621332 -279.76703)
			(xy 357.622348 -279.757632) (xy 357.622348 -279.577292) (xy 357.622186 -279.571281) (xy 357.619374 -279.559593)
			(xy 357.61676 -279.554178) (xy 357.614919 -279.550705) (xy 357.610323 -279.544329) (xy 357.607616 -279.541478)
			(xy 355.290882 -277.224744) (xy 355.285294 -277.219156) (xy 355.28504 -277.218902) (xy 355.283008 -277.216616)
			(xy 354.986082 -276.919944) (xy 354.965347 -276.898367) (xy 354.930185 -276.84995) (xy 354.903024 -276.796632)
			(xy 354.884531 -276.739723) (xy 354.875161 -276.680623) (xy 354.874576 -276.650704) (xy 354.874576 -267.101574)
			(xy 354.874148 -267.091506) (xy 354.866424 -267.072911) (xy 354.85959 -267.065506) (xy 354.81895 -267.02512)
			(xy 354.786184 -266.992354) (xy 354.170234 -266.376658) (xy 354.164138 -266.37234) (xy 353.431856 -266.37234)
			(xy 353.415854 -266.371832) (xy 353.392232 -266.40155) (xy 353.387123 -266.408475) (xy 353.381419 -266.424701)
			(xy 353.381056 -266.4333) (xy 353.381056 -267.365226) (xy 353.380504 -267.395209) (xy 353.371131 -267.454436)
			(xy 353.352604 -267.511467) (xy 353.32538 -267.564896) (xy 353.29013 -267.613406) (xy 353.269296 -267.634974)
			(xy 351.048828 -269.855442) (xy 351.046124 -269.858295) (xy 351.041537 -269.864676) (xy 351.039684 -269.868142)
			(xy 351.037101 -269.873569) (xy 351.034278 -269.885249) (xy 351.034096 -269.891256) (xy 351.034096 -276.027896)
			(xy 352.727006 -276.027896) (xy 352.727468 -276.000526) (xy 352.735287 -275.946346) (xy 352.750777 -275.893843)
			(xy 352.773619 -275.844096) (xy 352.803344 -275.79813) (xy 352.820986 -275.777198) (xy 352.82124 -275.776944)
			(xy 352.826819 -275.769853) (xy 352.833069 -275.752939) (xy 352.833432 -275.743924) (xy 352.833432 -275.676868)
			(xy 352.833083 -275.66785) (xy 352.826829 -275.650934) (xy 352.82124 -275.643848) (xy 352.820986 -275.643848)
			(xy 352.820986 -275.643594) (xy 352.803343 -275.622664) (xy 352.773622 -275.576694) (xy 352.750779 -275.526948)
			(xy 352.735285 -275.474445) (xy 352.727457 -275.420267) (xy 352.727458 -275.365527) (xy 352.735286 -275.311349)
			(xy 352.750781 -275.258847) (xy 352.773624 -275.2091) (xy 352.803347 -275.163132) (xy 352.820986 -275.142198)
			(xy 352.82124 -275.141944) (xy 352.826819 -275.134853) (xy 352.833069 -275.117939) (xy 352.833432 -275.108924)
			(xy 352.833432 -275.041868) (xy 352.833083 -275.03285) (xy 352.826829 -275.015934) (xy 352.82124 -275.008848)
			(xy 352.820986 -275.008848) (xy 352.820986 -275.008594) (xy 352.803328 -274.987677) (xy 352.77362 -274.9417)
			(xy 352.750788 -274.891948) (xy 352.735301 -274.839444) (xy 352.727477 -274.785266) (xy 352.727006 -274.757896)
			(xy 352.727452 -274.730642) (xy 352.73521 -274.67669) (xy 352.750567 -274.624391) (xy 352.773211 -274.57481)
			(xy 352.80268 -274.528956) (xy 352.838376 -274.487763) (xy 352.879571 -274.45207) (xy 352.925426 -274.422602)
			(xy 352.975008 -274.39996) (xy 353.027308 -274.384606) (xy 353.08126 -274.37685) (xy 353.108514 -274.376388)
			(xy 353.135884 -274.376849) (xy 353.190064 -274.384668) (xy 353.242567 -274.400159) (xy 353.292313 -274.423002)
			(xy 353.33828 -274.452727) (xy 353.359212 -274.470368) (xy 353.359466 -274.470622) (xy 353.366556 -274.476203)
			(xy 353.38347 -274.482452) (xy 353.392486 -274.482814) (xy 353.459542 -274.482814) (xy 353.468556 -274.482426)
			(xy 353.485473 -274.4762) (xy 353.492562 -274.470622) (xy 353.492562 -274.470368) (xy 353.492816 -274.470368)
			(xy 353.513765 -274.45275) (xy 353.559734 -274.423036) (xy 353.609477 -274.400196) (xy 353.661974 -274.3847)
			(xy 353.716146 -274.376866) (xy 353.743514 -274.376388) (xy 353.770765 -274.376865) (xy 353.824713 -274.384623)
			(xy 353.877008 -274.39998) (xy 353.926585 -274.422622) (xy 353.972435 -274.45209) (xy 354.013625 -274.487782)
			(xy 354.049316 -274.528973) (xy 354.078783 -274.574824) (xy 354.101424 -274.624401) (xy 354.116779 -274.676697)
			(xy 354.124536 -274.730645) (xy 354.125022 -274.757896) (xy 354.124573 -274.785267) (xy 354.116754 -274.839448)
			(xy 354.101262 -274.891952) (xy 354.078416 -274.941698) (xy 354.048686 -274.987664) (xy 354.031042 -275.008594)
			(xy 354.030788 -275.008848) (xy 354.025216 -275.015944) (xy 354.018961 -275.032854) (xy 354.018596 -275.041868)
			(xy 354.018596 -275.108924) (xy 354.018943 -275.117942) (xy 354.025198 -275.134859) (xy 354.030788 -275.141944)
			(xy 354.031042 -275.141944) (xy 354.031042 -275.142198) (xy 354.04868 -275.163133) (xy 354.078407 -275.2091)
			(xy 354.101255 -275.258846) (xy 354.116753 -275.311347) (xy 354.124582 -275.365526) (xy 354.124583 -275.420268)
			(xy 354.116754 -275.474447) (xy 354.101257 -275.526949) (xy 354.07841 -275.576695) (xy 354.048684 -275.622662)
			(xy 354.031042 -275.643594) (xy 354.030788 -275.643848) (xy 354.025216 -275.650944) (xy 354.018961 -275.667854)
			(xy 354.018596 -275.676868) (xy 354.018596 -275.743924) (xy 354.018943 -275.752942) (xy 354.025198 -275.769859)
			(xy 354.030788 -275.776944) (xy 354.031042 -275.776944) (xy 354.031042 -275.777198) (xy 354.04868 -275.798133)
			(xy 354.078407 -275.8441) (xy 354.101255 -275.893846) (xy 354.116753 -275.946347) (xy 354.124582 -276.000526)
			(xy 354.124583 -276.055268) (xy 354.116754 -276.109447) (xy 354.101257 -276.161949) (xy 354.07841 -276.211695)
			(xy 354.048684 -276.257662) (xy 354.031042 -276.278594) (xy 354.030788 -276.278848) (xy 354.025216 -276.285944)
			(xy 354.018961 -276.302854) (xy 354.018596 -276.311868) (xy 354.018596 -276.378924) (xy 354.018943 -276.387942)
			(xy 354.025198 -276.404859) (xy 354.030788 -276.411944) (xy 354.031042 -276.411944) (xy 354.031042 -276.412198)
			(xy 354.048701 -276.433114) (xy 354.078408 -276.479092) (xy 354.10124 -276.528844) (xy 354.116727 -276.581348)
			(xy 354.124551 -276.635526) (xy 354.125022 -276.662896) (xy 354.124536 -276.690147) (xy 354.11678 -276.744095)
			(xy 354.101425 -276.79639) (xy 354.078783 -276.845967) (xy 354.049317 -276.891817) (xy 354.013626 -276.933008)
			(xy 353.972435 -276.968699) (xy 353.926585 -276.998165) (xy 353.877008 -277.020807) (xy 353.824713 -277.036162)
			(xy 353.770765 -277.043918) (xy 353.716263 -277.043918) (xy 353.662315 -277.036162) (xy 353.61002 -277.020807)
			(xy 353.560443 -276.998165) (xy 353.514593 -276.968699) (xy 353.473402 -276.933008) (xy 353.437711 -276.891817)
			(xy 353.408245 -276.845967) (xy 353.385603 -276.79639) (xy 353.370248 -276.744095) (xy 353.362492 -276.690147)
			(xy 353.362006 -276.662896) (xy 353.362542 -276.633418) (xy 353.371612 -276.575165) (xy 353.389535 -276.519)
			(xy 353.415885 -276.466261) (xy 353.450035 -276.418203) (xy 353.47021 -276.396704) (xy 353.476737 -276.389364)
			(xy 353.484187 -276.371208) (xy 353.484688 -276.361398) (xy 353.484688 -276.308058) (xy 353.477322 -276.3012)
			(xy 353.469975 -276.294682) (xy 353.451824 -276.287227) (xy 353.442016 -276.286722) (xy 353.410012 -276.286722)
			(xy 353.400199 -276.287218) (xy 353.382034 -276.294656) (xy 353.374706 -276.3012) (xy 353.353196 -276.321362)
			(xy 353.30514 -276.35551) (xy 353.252404 -276.38186) (xy 353.196241 -276.399783) (xy 353.13799 -276.408854)
			(xy 353.108514 -276.409404) (xy 353.081261 -276.408932) (xy 353.027311 -276.401176) (xy 352.975013 -276.385822)
			(xy 352.925432 -276.363181) (xy 352.879579 -276.333714) (xy 352.838386 -276.298021) (xy 352.802692 -276.256829)
			(xy 352.773224 -276.210977) (xy 352.750581 -276.161397) (xy 352.735226 -276.109099) (xy 352.727469 -276.055149)
			(xy 352.727006 -276.027896) (xy 351.034096 -276.027896) (xy 351.034096 -277.634192) (xy 352.285046 -277.634192)
			(xy 352.285601 -277.605067) (xy 352.294469 -277.547495) (xy 352.311982 -277.49194) (xy 352.337734 -277.43969)
			(xy 352.371127 -277.391961) (xy 352.411385 -277.349861) (xy 352.434144 -277.331678) (xy 352.443288 -277.324566)
			(xy 352.453702 -277.304246) (xy 352.455988 -277.213568) (xy 352.455627 -277.202192) (xy 352.446251 -277.181483)
			(xy 352.437954 -277.17369) (xy 352.417226 -277.155498) (xy 352.380759 -277.114124) (xy 352.35063 -277.06793)
			(xy 352.327467 -277.017878) (xy 352.311754 -276.965013) (xy 352.303818 -276.910436) (xy 352.303334 -276.88286)
			(xy 352.30382 -276.855609) (xy 352.311576 -276.801661) (xy 352.326931 -276.749366) (xy 352.349573 -276.699789)
			(xy 352.379039 -276.653939) (xy 352.41473 -276.612748) (xy 352.455921 -276.577057) (xy 352.501771 -276.547591)
			(xy 352.551348 -276.524949) (xy 352.603643 -276.509594) (xy 352.657591 -276.501838) (xy 352.712093 -276.501838)
			(xy 352.766041 -276.509594) (xy 352.818336 -276.524949) (xy 352.867913 -276.547591) (xy 352.913763 -276.577057)
			(xy 352.954954 -276.612748) (xy 352.990645 -276.653939) (xy 353.020111 -276.699789) (xy 353.042753 -276.749366)
			(xy 353.058108 -276.801661) (xy 353.065864 -276.855609) (xy 353.06635 -276.88286) (xy 353.065762 -276.911984)
			(xy 353.056902 -276.969554) (xy 353.039395 -277.025109) (xy 353.013649 -277.077359) (xy 352.980262 -277.125088)
			(xy 352.940009 -277.16719) (xy 352.917252 -277.185374) (xy 352.908108 -277.192486) (xy 352.897694 -277.212806)
			(xy 352.895408 -277.303484) (xy 352.895798 -277.314857) (xy 352.905153 -277.335566) (xy 352.913442 -277.343362)
			(xy 352.934146 -277.36158) (xy 352.970615 -277.402949) (xy 353.000747 -277.449137) (xy 353.023914 -277.499184)
			(xy 353.039632 -277.552045) (xy 353.040313 -277.556722) (xy 353.207826 -277.556722) (xy 353.211897 -277.5011)
			(xy 353.224023 -277.446663) (xy 353.243946 -277.394572) (xy 353.271242 -277.345937) (xy 353.305328 -277.301794)
			(xy 353.345477 -277.263085) (xy 353.390835 -277.230634) (xy 353.440435 -277.205133) (xy 353.493219 -277.187126)
			(xy 353.548062 -277.176996) (xy 353.603796 -277.174959) (xy 353.659233 -277.181059) (xy 353.71319 -277.195165)
			(xy 353.764519 -277.216977) (xy 353.812125 -277.246031) (xy 353.854993 -277.281706) (xy 353.89221 -277.323243)
			(xy 353.922983 -277.369756) (xy 353.946655 -277.420253) (xy 353.962723 -277.47366) (xy 353.970843 -277.528836)
			(xy 353.971352 -277.556722) (xy 353.970843 -277.584608) (xy 353.962723 -277.639784) (xy 353.946655 -277.693191)
			(xy 353.922983 -277.743688) (xy 353.89221 -277.790201) (xy 353.854993 -277.831738) (xy 353.812125 -277.867413)
			(xy 353.764519 -277.896467) (xy 353.71319 -277.918279) (xy 353.659233 -277.932385) (xy 353.603796 -277.938485)
			(xy 353.548062 -277.936448) (xy 353.493219 -277.926318) (xy 353.440435 -277.908311) (xy 353.390835 -277.88281)
			(xy 353.345477 -277.850359) (xy 353.305328 -277.81165) (xy 353.271242 -277.767507) (xy 353.243946 -277.718872)
			(xy 353.224023 -277.666781) (xy 353.211897 -277.612344) (xy 353.207826 -277.556722) (xy 353.040313 -277.556722)
			(xy 353.047575 -277.606618) (xy 353.048062 -277.634192) (xy 353.047576 -277.661443) (xy 353.03982 -277.715391)
			(xy 353.024465 -277.767686) (xy 353.001823 -277.817263) (xy 352.972357 -277.863113) (xy 352.936666 -277.904304)
			(xy 352.895475 -277.939995) (xy 352.849625 -277.969461) (xy 352.800048 -277.992103) (xy 352.747753 -278.007458)
			(xy 352.693805 -278.015214) (xy 352.639303 -278.015214) (xy 352.585355 -278.007458) (xy 352.53306 -277.992103)
			(xy 352.483483 -277.969461) (xy 352.437633 -277.939995) (xy 352.396442 -277.904304) (xy 352.360751 -277.863113)
			(xy 352.331285 -277.817263) (xy 352.308643 -277.767686) (xy 352.293288 -277.715391) (xy 352.285532 -277.661443)
			(xy 352.285046 -277.634192) (xy 351.034096 -277.634192) (xy 351.034096 -279.328372) (xy 351.03354 -279.358353)
			(xy 351.024159 -279.417575) (xy 351.005625 -279.4746) (xy 350.978394 -279.528021) (xy 350.943137 -279.576522)
			(xy 350.922336 -279.59812) (xy 349.976694 -280.543762) (xy 349.9739 -280.546556) (xy 349.97009 -280.552144)
			(xy 349.969836 -280.552398) (xy 349.969074 -280.553414) (xy 349.965185 -280.560585) (xy 349.961705 -280.576513)
			(xy 349.962216 -280.584656) (xy 349.965264 -280.615136) (xy 349.970598 -280.666444) (xy 349.97172 -280.671665)
			(xy 349.975814 -280.681526) (xy 349.978726 -280.686002) (xy 349.992188 -280.699464) (xy 349.995998 -280.702004)
			(xy 350.017532 -280.717341) (xy 350.05656 -280.753002) (xy 350.090293 -280.793707) (xy 350.118085 -280.838679)
			(xy 350.139405 -280.887057) (xy 350.153843 -280.937914) (xy 350.161124 -280.990277) (xy 350.161606 -281.01671)
			(xy 350.16112 -281.043961) (xy 350.153362 -281.097907) (xy 350.138006 -281.150201) (xy 350.115364 -281.199777)
			(xy 350.085898 -281.245626) (xy 350.050206 -281.286814) (xy 350.009016 -281.322505) (xy 349.963166 -281.35197)
			(xy 349.913589 -281.37461) (xy 349.861296 -281.389964) (xy 349.807349 -281.39772) (xy 349.780098 -281.398218)
			(xy 349.752045 -281.397716) (xy 349.696544 -281.389492) (xy 349.642843 -281.373237) (xy 349.592099 -281.349299)
			(xy 349.545403 -281.318196) (xy 349.50376 -281.280594) (xy 349.468066 -281.237305) (xy 349.43909 -281.189259)
			(xy 349.417456 -281.137491) (xy 349.41002 -281.110436) (xy 349.407988 -281.102562) (xy 349.394526 -281.08148)
			(xy 349.392152 -281.077901) (xy 349.386405 -281.071518) (xy 349.383096 -281.06878) (xy 349.366332 -281.055826)
			(xy 349.362917 -281.053235) (xy 349.355379 -281.049152) (xy 349.351346 -281.047698) (xy 349.343726 -281.045158)
			(xy 349.332296 -281.045158) (xy 349.317056 -281.045412) (xy 348.976442 -281.045412) (xy 348.970433 -281.04558)
			(xy 348.958751 -281.048406) (xy 348.953328 -281.051) (xy 348.949852 -281.052837) (xy 348.943469 -281.057426)
			(xy 348.940628 -281.060144) (xy 348.579186 -281.421586) (xy 348.557609 -281.442319) (xy 348.509191 -281.477477)
			(xy 348.455872 -281.504632) (xy 348.398963 -281.523118) (xy 348.339864 -281.53248) (xy 348.309946 -281.533092)
			(xy 348.309438 -281.533092) (xy 348.282202 -281.532609) (xy 348.228284 -281.524862) (xy 348.176018 -281.509521)
			(xy 348.126466 -281.486898) (xy 348.080639 -281.457453) (xy 348.039468 -281.421785) (xy 348.003793 -281.380622)
			(xy 347.974339 -281.334801) (xy 347.951706 -281.285254) (xy 347.936354 -281.23299) (xy 347.928596 -281.179074)
			(xy 347.928184 -281.151838) (xy 347.928376 -281.133177) (xy 347.93194 -281.096027) (xy 347.935296 -281.07767)
			(xy 347.935296 -281.077162) (xy 347.93682 -281.070304) (xy 347.93682 -281.07005) (xy 347.939809 -281.056806)
			(xy 347.947437 -281.030746) (xy 347.95206 -281.01798) (xy 347.952314 -281.017218) (xy 347.954167 -281.011703)
			(xy 347.955572 -281.000158) (xy 347.955108 -280.994358) (xy 347.953838 -280.983182) (xy 347.919548 -280.93035)
			(xy 347.901514 -280.902918) (xy 347.897567 -280.897712) (xy 347.887535 -280.88935) (xy 347.881702 -280.886408)
			(xy 347.87205 -280.882344) (xy 347.846396 -280.880312) (xy 347.813122 -280.874978) (xy 347.79618 -280.87135)
			(xy 347.762981 -280.861431) (xy 347.746828 -280.855166) (xy 347.745558 -280.854658) (xy 347.74251 -280.853388)
			(xy 347.729556 -280.850594) (xy 347.721717 -280.849541) (xy 347.706063 -280.851733) (xy 347.698822 -280.854912)
			(xy 347.686122 -280.861008) (xy 347.684344 -280.86177) (xy 347.63202 -280.886662) (xy 347.627273 -280.88903)
			(xy 347.61882 -280.895433) (xy 347.615256 -280.899362) (xy 347.608398 -280.90749) (xy 347.60789 -280.909522)
			(xy 347.605096 -280.919428) (xy 347.60005 -280.935644) (xy 347.58746 -280.967188) (xy 347.57995 -280.98242)
			(xy 347.57233 -280.997152) (xy 347.570044 -281.000962) (xy 347.5609 -281.015694) (xy 347.545809 -281.038473)
			(xy 347.510146 -281.079871) (xy 347.468944 -281.115759) (xy 347.423044 -281.145404) (xy 347.373386 -281.1682)
			(xy 347.320984 -281.18368) (xy 347.26691 -281.191528) (xy 347.23959 -281.19197) (xy 347.239082 -281.19197)
			(xy 347.204284 -281.190192) (xy 347.194632 -281.189176) (xy 347.176852 -281.186636) (xy 347.148404 -281.180794)
			(xy 347.14815 -281.18054) (xy 347.147642 -281.18054) (xy 347.137736 -281.178) (xy 347.128084 -281.17927)
			(xy 347.122858 -281.180066) (xy 347.11287 -281.18352) (xy 347.108272 -281.186128) (xy 347.095064 -281.194002)
			(xy 347.094556 -281.194002) (xy 347.048328 -281.220672) (xy 347.040721 -281.225403) (xy 347.029145 -281.239063)
			(xy 347.025722 -281.247342) (xy 347.017824 -281.273691) (xy 346.995503 -281.323965) (xy 346.966193 -281.370512)
			(xy 346.930502 -281.412368) (xy 346.889171 -281.448664) (xy 346.843056 -281.478648) (xy 346.793112 -281.5017)
			(xy 346.740377 -281.51734) (xy 346.685941 -281.525245) (xy 346.658438 -281.525726) (xy 346.631183 -281.525266)
			(xy 346.577227 -281.517513) (xy 346.524923 -281.502161) (xy 346.475337 -281.479521) (xy 346.429478 -281.450054)
			(xy 346.388279 -281.41436) (xy 346.35258 -281.373167) (xy 346.323106 -281.327312) (xy 346.300459 -281.277729)
			(xy 346.285099 -281.225428) (xy 346.277338 -281.171473) (xy 346.27693 -281.144218) (xy 346.276989 -281.133655)
			(xy 346.278134 -281.112561) (xy 346.279216 -281.102054) (xy 346.279216 -281.101546) (xy 346.279782 -281.092246)
			(xy 346.274952 -281.07427) (xy 346.269818 -281.066494) (xy 346.229432 -281.010868) (xy 346.225493 -281.005778)
			(xy 346.215594 -280.997562) (xy 346.209874 -280.994612) (xy 346.19819 -280.990802) (xy 346.19565 -280.990294)
			(xy 346.167563 -280.983738) (xy 346.113628 -280.963307) (xy 346.063385 -280.934987) (xy 346.017979 -280.899423)
			(xy 345.978447 -280.857428) (xy 345.945689 -280.809959) (xy 345.920453 -280.758098) (xy 345.903315 -280.703028)
			(xy 345.894664 -280.646006) (xy 345.894152 -280.617168) (xy 345.894638 -280.589917) (xy 345.902394 -280.535969)
			(xy 345.917749 -280.483674) (xy 345.940391 -280.434097) (xy 345.969857 -280.388247) (xy 346.005548 -280.347056)
			(xy 346.046739 -280.311365) (xy 346.092589 -280.281899) (xy 346.142166 -280.259257) (xy 346.194461 -280.243902)
			(xy 346.248409 -280.236146) (xy 346.302911 -280.236146) (xy 346.356859 -280.243902) (xy 346.409154 -280.259257)
			(xy 346.458731 -280.281899) (xy 346.504581 -280.311365) (xy 346.545772 -280.347056) (xy 346.581463 -280.388247)
			(xy 346.610929 -280.434097) (xy 346.633571 -280.483674) (xy 346.648926 -280.535969) (xy 346.656682 -280.589917)
			(xy 346.657168 -280.617168) (xy 346.65711 -280.627731) (xy 346.655966 -280.648825) (xy 346.654882 -280.659332)
			(xy 346.654882 -280.65984) (xy 346.654313 -280.66914) (xy 346.659139 -280.68712) (xy 346.66428 -280.694892)
			(xy 346.688156 -280.727658) (xy 346.705936 -280.752042) (xy 346.709958 -280.756854) (xy 346.719839 -280.764572)
			(xy 346.725494 -280.767282) (xy 346.733876 -280.770076) (xy 346.734638 -280.77033) (xy 346.734892 -280.77033)
			(xy 346.735654 -280.770584) (xy 346.739972 -280.771346) (xy 346.741496 -280.771854) (xy 346.7481 -280.773378)
			(xy 346.750132 -280.773886) (xy 346.760038 -280.776426) (xy 346.76969 -280.775156) (xy 346.774916 -280.774361)
			(xy 346.784905 -280.770907) (xy 346.789502 -280.768298) (xy 346.80271 -280.760424) (xy 346.803218 -280.760424)
			(xy 346.849446 -280.733754) (xy 346.857059 -280.729027) (xy 346.868646 -280.715372) (xy 346.872052 -280.707084)
			(xy 346.879948 -280.680733) (xy 346.902267 -280.630454) (xy 346.931575 -280.583902) (xy 346.967264 -280.542041)
			(xy 347.008595 -280.505739) (xy 347.054711 -280.47575) (xy 347.104655 -280.452693) (xy 347.157393 -280.437048)
			(xy 347.211831 -280.429139) (xy 347.239336 -280.4287) (xy 347.254068 -280.4287) (xy 347.287132 -280.430688)
			(xy 347.351885 -280.444613) (xy 347.382846 -280.456386) (xy 347.387926 -280.458418) (xy 347.39707 -280.46045)
			(xy 347.405263 -280.461788) (xy 347.421721 -280.45971) (xy 347.429328 -280.456386) (xy 347.49867 -280.42362)
			(xy 347.506036 -280.420064) (xy 347.519752 -280.404062) (xy 347.52153 -280.398728) (xy 347.523054 -280.39314)
			(xy 347.531872 -280.365239) (xy 347.556804 -280.312305) (xy 347.589521 -280.263795) (xy 347.629258 -280.220845)
			(xy 347.675083 -280.184462) (xy 347.725923 -280.155499) (xy 347.780588 -280.134632) (xy 347.837796 -280.122351)
			(xy 347.86697 -280.12009) (xy 347.867224 -280.12009) (xy 347.878654 -280.119328) (xy 347.885512 -280.115772)
			(xy 347.88856 -280.113994) (xy 347.893606 -280.111095) (xy 347.902339 -280.103407) (xy 347.905832 -280.098754)
			(xy 347.951806 -280.033984) (xy 347.952314 -280.033222) (xy 347.955285 -280.028637) (xy 347.95939 -280.018516)
			(xy 347.960442 -280.013156) (xy 347.96222 -280.002488) (xy 347.958918 -279.991312) (xy 347.952314 -279.96388)
			(xy 347.950282 -279.953212) (xy 347.950282 -279.952704) (xy 347.948758 -279.944068) (xy 347.948758 -279.94356)
			(xy 347.946758 -279.929484) (xy 347.944594 -279.901134) (xy 347.94444 -279.886918) (xy 347.94444 -279.865582)
			(xy 347.945964 -279.852628) (xy 347.945964 -279.85212) (xy 347.949046 -279.824066) (xy 347.962424 -279.769237)
			(xy 347.98374 -279.71698) (xy 348.012527 -279.668437) (xy 348.048155 -279.624668) (xy 348.089848 -279.58663)
			(xy 348.136692 -279.555155) (xy 348.187665 -279.530929) (xy 348.241653 -279.514484) (xy 348.297475 -279.506177)
			(xy 348.325694 -279.505664) (xy 348.326456 -279.505664) (xy 348.356371 -279.506275) (xy 348.415459 -279.515669)
			(xy 348.472356 -279.534171) (xy 348.525668 -279.561327) (xy 348.574088 -279.596473) (xy 348.595696 -279.61717)
			(xy 348.865444 -279.886918) (xy 348.870875 -279.891898) (xy 348.883914 -279.898742) (xy 348.891098 -279.90038)
			(xy 348.891606 -279.90038) (xy 348.901004 -279.901396) (xy 348.979998 -279.901396) (xy 348.989396 -279.90038)
			(xy 348.989904 -279.90038) (xy 348.997061 -279.898672) (xy 349.010082 -279.891834) (xy 349.015558 -279.886918)
			(xy 349.875602 -279.026874) (xy 349.880585 -279.021445) (xy 349.887436 -279.008406) (xy 349.889064 -279.00122)
			(xy 349.889064 -279.000712) (xy 349.89008 -278.991314) (xy 349.89008 -269.446502) (xy 349.890638 -269.416522)
			(xy 349.900021 -269.357301) (xy 349.918558 -269.300278) (xy 349.94579 -269.246859) (xy 349.981047 -269.19836)
			(xy 350.00184 -269.176754) (xy 352.203512 -266.975082) (xy 352.206215 -266.972229) (xy 352.210802 -266.965848)
			(xy 352.212656 -266.962382) (xy 352.215244 -266.956956) (xy 352.218076 -266.945277) (xy 352.218244 -266.939268)
			(xy 352.218244 -266.417806) (xy 352.214893 -266.415173) (xy 352.20749 -266.410953) (xy 352.203512 -266.409424)
			(xy 352.185732 -266.404852) (xy 352.185224 -266.404852) (xy 352.163724 -266.399214) (xy 352.122538 -266.382504)
			(xy 352.103182 -266.371578) (xy 352.097086 -266.368276) (xy 352.09099 -266.366498) (xy 352.077782 -266.36472)
			(xy 351.678494 -266.36472) (xy 351.674888 -266.364783) (xy 351.667749 -266.365802) (xy 351.66427 -266.366752)
			(xy 351.659698 -266.368276) (xy 351.650554 -266.372086) (xy 351.642934 -266.379706) (xy 350.803718 -267.218668)
			(xy 350.782104 -267.239448) (xy 350.733599 -267.274686) (xy 350.68018 -267.301905) (xy 350.623162 -267.320436)
			(xy 350.563947 -267.329823) (xy 350.53397 -267.330428) (xy 349.492824 -267.330428) (xy 349.482863 -267.330917)
			(xy 349.464444 -267.33851) (xy 349.45701 -267.34516) (xy 345.552268 -271.249902) (xy 345.549561 -271.252752)
			(xy 345.544965 -271.259129) (xy 345.543124 -271.262602) (xy 345.540535 -271.268028) (xy 345.537701 -271.279707)
			(xy 345.537536 -271.285716) (xy 345.537536 -278.49957) (xy 345.536932 -278.529487) (xy 345.52755 -278.588582)
			(xy 345.509057 -278.645488) (xy 345.481908 -278.69881) (xy 345.446769 -278.747239) (xy 345.42603 -278.76881)
			(xy 344.168222 -280.026618) (xy 344.146645 -280.047352) (xy 344.098227 -280.082511) (xy 344.044908 -280.109669)
			(xy 343.988 -280.128159) (xy 343.9289 -280.137525) (xy 343.898982 -280.138124) (xy 342.242902 -280.138124)
			(xy 342.232935 -280.138598) (xy 342.214495 -280.146171) (xy 342.207088 -280.152856) (xy 341.826596 -280.533348)
			(xy 341.819108 -280.541554) (xy 341.811454 -280.56238) (xy 341.811864 -280.57348) (xy 341.811864 -280.573734)
			(xy 341.818468 -280.651966) (xy 341.818722 -280.652728) (xy 341.820184 -280.661848) (xy 341.828657 -280.678244)
			(xy 341.835232 -280.684732) (xy 341.839804 -280.688034) (xy 341.860817 -280.703444) (xy 341.898867 -280.739045)
			(xy 341.931721 -280.779492) (xy 341.958768 -280.82403) (xy 341.979507 -280.871834) (xy 341.99355 -280.922014)
			(xy 342.000639 -280.973638) (xy 342.001094 -280.999692) (xy 342.000631 -281.026945) (xy 341.992875 -281.080896)
			(xy 341.97752 -281.133194) (xy 341.954877 -281.182774) (xy 341.925409 -281.228627) (xy 341.889715 -281.26982)
			(xy 341.848522 -281.305513) (xy 341.802669 -281.33498) (xy 341.753088 -281.357622) (xy 341.70079 -281.372976)
			(xy 341.646839 -281.380732) (xy 341.619586 -281.3812) (xy 341.599235 -281.380929) (xy 341.558762 -281.376606)
			(xy 341.538814 -281.372564) (xy 341.533526 -281.371564) (xy 341.522766 -281.371564) (xy 341.517478 -281.372564)
			(xy 341.497656 -281.376587) (xy 341.457438 -281.380912) (xy 341.437214 -281.3812) (xy 341.408677 -281.380668)
			(xy 341.352241 -281.372165) (xy 341.297701 -281.355348) (xy 341.246277 -281.33059) (xy 341.199116 -281.298447)
			(xy 341.157271 -281.259634) (xy 341.121677 -281.21502) (xy 341.093129 -281.165599) (xy 341.072264 -281.112476)
			(xy 341.065358 -281.084782) (xy 341.061294 -281.06751) (xy 341.033608 -281.045412) (xy 340.81593 -281.045412)
			(xy 340.809921 -281.045582) (xy 340.798241 -281.04841) (xy 340.792816 -281.051) (xy 340.78934 -281.052838)
			(xy 340.782958 -281.057428) (xy 340.780116 -281.060144) (xy 340.418674 -281.421586) (xy 340.397097 -281.442318)
			(xy 340.348678 -281.477474) (xy 340.295359 -281.504628) (xy 340.23845 -281.523113) (xy 340.179352 -281.532472)
			(xy 340.149434 -281.533092) (xy 340.148926 -281.533092) (xy 340.121691 -281.532608) (xy 340.067774 -281.52486)
			(xy 340.015509 -281.509518) (xy 339.965959 -281.486894) (xy 339.920133 -281.457448) (xy 339.878964 -281.421781)
			(xy 339.84329 -281.380618) (xy 339.813837 -281.334797) (xy 339.791205 -281.285251) (xy 339.775854 -281.232989)
			(xy 339.768096 -281.179073) (xy 339.767672 -281.151838) (xy 339.767864 -281.133177) (xy 339.771428 -281.096027)
			(xy 339.774784 -281.07767) (xy 339.774784 -281.077162) (xy 339.776308 -281.070304) (xy 339.776308 -281.07005)
			(xy 339.779296 -281.056806) (xy 339.786924 -281.030746) (xy 339.791548 -281.01798) (xy 339.791802 -281.017218)
			(xy 339.793656 -281.011703) (xy 339.795061 -281.000158) (xy 339.794596 -280.994358) (xy 339.793326 -280.983182)
			(xy 339.759036 -280.93035) (xy 339.741002 -280.902918) (xy 339.737054 -280.897713) (xy 339.727022 -280.889352)
			(xy 339.72119 -280.886408) (xy 339.711538 -280.882344) (xy 339.685884 -280.880312) (xy 339.65261 -280.874978)
			(xy 339.635669 -280.871349) (xy 339.60247 -280.86143) (xy 339.586316 -280.855166) (xy 339.585046 -280.854658)
			(xy 339.581998 -280.853388) (xy 339.569044 -280.850594) (xy 339.561206 -280.849543) (xy 339.545553 -280.851738)
			(xy 339.53831 -280.854912) (xy 339.52561 -280.861008) (xy 339.523832 -280.86177) (xy 339.471508 -280.886662)
			(xy 339.466762 -280.88903) (xy 339.45831 -280.895436) (xy 339.454744 -280.899362) (xy 339.447886 -280.90749)
			(xy 339.447378 -280.909522) (xy 339.444584 -280.919428) (xy 339.439538 -280.935644) (xy 339.426947 -280.967188)
			(xy 339.419438 -280.98242) (xy 339.411818 -280.997152) (xy 339.409532 -281.000962) (xy 339.400388 -281.015694)
			(xy 339.385297 -281.038472) (xy 339.349634 -281.079869) (xy 339.308431 -281.115756) (xy 339.262531 -281.1454)
			(xy 339.212873 -281.168194) (xy 339.160471 -281.183672) (xy 339.106398 -281.191519) (xy 339.079078 -281.19197)
			(xy 339.07857 -281.19197) (xy 339.043772 -281.190192) (xy 339.03412 -281.189176) (xy 339.01634 -281.186636)
			(xy 338.987892 -281.180794) (xy 338.987638 -281.18054) (xy 338.98713 -281.18054) (xy 338.977224 -281.178)
			(xy 338.967572 -281.17927) (xy 338.962347 -281.180067) (xy 338.95236 -281.183524) (xy 338.94776 -281.186128)
			(xy 338.934552 -281.194002) (xy 338.934044 -281.194002) (xy 338.887816 -281.220672) (xy 338.88021 -281.225405)
			(xy 338.868637 -281.239065) (xy 338.86521 -281.247342) (xy 338.857311 -281.273691) (xy 338.83499 -281.323963)
			(xy 338.80568 -281.370509) (xy 338.769989 -281.412364) (xy 338.728658 -281.448659) (xy 338.682542 -281.478642)
			(xy 338.632599 -281.501692) (xy 338.579864 -281.51733) (xy 338.525429 -281.525233) (xy 338.497926 -281.525726)
			(xy 338.470671 -281.525265) (xy 338.416717 -281.517511) (xy 338.364415 -281.502157) (xy 338.31483 -281.479517)
			(xy 338.268972 -281.45005) (xy 338.227775 -281.414356) (xy 338.192077 -281.373163) (xy 338.162604 -281.327309)
			(xy 338.139958 -281.277727) (xy 338.124598 -281.225426) (xy 338.116838 -281.171473) (xy 338.116418 -281.144218)
			(xy 338.116477 -281.133655) (xy 338.117622 -281.112561) (xy 338.118704 -281.102054) (xy 338.118704 -281.101546)
			(xy 338.11927 -281.092247) (xy 338.114439 -281.07427) (xy 338.109306 -281.066494) (xy 338.06892 -281.010868)
			(xy 338.064981 -281.005779) (xy 338.055081 -280.997565) (xy 338.049362 -280.994612) (xy 338.037678 -280.990802)
			(xy 338.035138 -280.990294) (xy 338.007051 -280.983737) (xy 337.953118 -280.963305) (xy 337.902876 -280.934984)
			(xy 337.857472 -280.89942) (xy 337.817941 -280.857425) (xy 337.785185 -280.809956) (xy 337.75995 -280.758096)
			(xy 337.742812 -280.703027) (xy 337.734162 -280.646005) (xy 337.73364 -280.617168) (xy 337.734126 -280.589917)
			(xy 337.741882 -280.535969) (xy 337.757237 -280.483674) (xy 337.779879 -280.434097) (xy 337.809345 -280.388247)
			(xy 337.845036 -280.347056) (xy 337.886227 -280.311365) (xy 337.932077 -280.281899) (xy 337.981654 -280.259257)
			(xy 338.033949 -280.243902) (xy 338.087897 -280.236146) (xy 338.142399 -280.236146) (xy 338.196347 -280.243902)
			(xy 338.248642 -280.259257) (xy 338.298219 -280.281899) (xy 338.344069 -280.311365) (xy 338.38526 -280.347056)
			(xy 338.420951 -280.388247) (xy 338.450417 -280.434097) (xy 338.473059 -280.483674) (xy 338.488414 -280.535969)
			(xy 338.49617 -280.589917) (xy 338.496656 -280.617168) (xy 338.496598 -280.627731) (xy 338.495453 -280.648825)
			(xy 338.49437 -280.659332) (xy 338.49437 -280.65984) (xy 338.493801 -280.669141) (xy 338.498626 -280.687121)
			(xy 338.503768 -280.694892) (xy 338.527644 -280.727658) (xy 338.545424 -280.752042) (xy 338.549439 -280.756859)
			(xy 338.55933 -280.764564) (xy 338.564982 -280.767282) (xy 338.573364 -280.770076) (xy 338.574126 -280.77033)
			(xy 338.57438 -280.77033) (xy 338.575142 -280.770584) (xy 338.57946 -280.771346) (xy 338.580984 -280.771854)
			(xy 338.587588 -280.773378) (xy 338.58962 -280.773886) (xy 338.599526 -280.776426) (xy 338.609178 -280.775156)
			(xy 338.614404 -280.774362) (xy 338.624394 -280.77091) (xy 338.62899 -280.768298) (xy 338.642198 -280.760424)
			(xy 338.642706 -280.760424) (xy 338.688934 -280.733754) (xy 338.696548 -280.729028) (xy 338.708138 -280.715374)
			(xy 338.71154 -280.707084) (xy 338.719436 -280.680732) (xy 338.741755 -280.630453) (xy 338.771062 -280.5839)
			(xy 338.806751 -280.542038) (xy 338.848082 -280.505735) (xy 338.894198 -280.475744) (xy 338.944142 -280.452686)
			(xy 338.99688 -280.437039) (xy 339.051319 -280.429129) (xy 339.078824 -280.4287) (xy 339.093556 -280.4287)
			(xy 339.12662 -280.430687) (xy 339.191374 -280.44461) (xy 339.222334 -280.456386) (xy 339.227414 -280.458418)
			(xy 339.236558 -280.46045) (xy 339.244751 -280.461789) (xy 339.261211 -280.459716) (xy 339.268816 -280.456386)
			(xy 339.338158 -280.42362) (xy 339.345524 -280.420064) (xy 339.35924 -280.404062) (xy 339.361018 -280.398728)
			(xy 339.362542 -280.39314) (xy 339.371361 -280.365242) (xy 339.396295 -280.312314) (xy 339.429015 -280.263812)
			(xy 339.468753 -280.220871) (xy 339.51458 -280.184499) (xy 339.565421 -280.155546) (xy 339.620085 -280.134691)
			(xy 339.677291 -280.122423) (xy 339.706458 -280.12009) (xy 339.706712 -280.12009) (xy 339.718142 -280.119328)
			(xy 339.725 -280.115772) (xy 339.728048 -280.113994) (xy 339.733095 -280.111096) (xy 339.741829 -280.10341)
			(xy 339.74532 -280.098754) (xy 339.791294 -280.033984) (xy 339.791802 -280.033222) (xy 339.794783 -280.028643)
			(xy 339.79889 -280.01852) (xy 339.79993 -280.013156) (xy 339.801708 -280.002488) (xy 339.798406 -279.991312)
			(xy 339.791802 -279.96388) (xy 339.78977 -279.953212) (xy 339.78977 -279.952704) (xy 339.788246 -279.944068)
			(xy 339.788246 -279.94356) (xy 339.786246 -279.929484) (xy 339.784082 -279.901134) (xy 339.783928 -279.886918)
			(xy 339.783928 -279.865582) (xy 339.785452 -279.852628) (xy 339.785452 -279.85212) (xy 339.788534 -279.824065)
			(xy 339.801912 -279.769236) (xy 339.823228 -279.716979) (xy 339.852014 -279.668434) (xy 339.887643 -279.624664)
			(xy 339.929335 -279.586625) (xy 339.976179 -279.555149) (xy 340.027152 -279.530922) (xy 340.08114 -279.514474)
			(xy 340.136963 -279.506166) (xy 340.165182 -279.505664) (xy 340.165944 -279.505664) (xy 340.195859 -279.506274)
			(xy 340.254948 -279.515666) (xy 340.311847 -279.534167) (xy 340.36516 -279.561322) (xy 340.413581 -279.596467)
			(xy 340.435184 -279.61717) (xy 340.653878 -279.835864) (xy 340.66129 -279.842548) (xy 340.679723 -279.850145)
			(xy 340.699661 -279.850145) (xy 340.718094 -279.842548) (xy 340.725506 -279.835864) (xy 341.454994 -279.106122)
			(xy 341.476571 -279.085387) (xy 341.524988 -279.050227) (xy 341.578306 -279.023068) (xy 341.635216 -279.004578)
			(xy 341.694315 -278.995213) (xy 341.724234 -278.994616) (xy 343.561162 -278.994616) (xy 343.569358 -278.994313)
			(xy 343.584912 -278.989142) (xy 343.591642 -278.984456) (xy 343.59723 -278.97963) (xy 344.379296 -278.197564)
			(xy 344.381999 -278.194711) (xy 344.386585 -278.188329) (xy 344.38844 -278.184864) (xy 344.391027 -278.179438)
			(xy 344.393855 -278.167758) (xy 344.394028 -278.16175) (xy 344.394028 -270.947896) (xy 344.394635 -270.91798)
			(xy 344.404021 -270.858887) (xy 344.422516 -270.801983) (xy 344.449666 -270.748664) (xy 344.484805 -270.700235)
			(xy 344.505534 -270.678656) (xy 348.886018 -266.298172) (xy 348.907632 -266.277392) (xy 348.956137 -266.24215)
			(xy 349.009556 -266.214926) (xy 349.066574 -266.196389) (xy 349.125788 -266.186994) (xy 349.155766 -266.186412)
			(xy 350.145858 -266.186412) (xy 350.150176 -266.186158) (xy 350.158145 -266.184953) (xy 350.17278 -266.178221)
			(xy 350.178878 -266.17295) (xy 350.228916 -266.122658) (xy 350.236701 -266.113045) (xy 350.24271 -266.089078)
			(xy 350.240346 -266.076938) (xy 350.15551 -265.992102) (xy 350.148112 -265.985254) (xy 350.129514 -265.977515)
			(xy 350.119442 -265.977116) (xy 348.607126 -265.977116) (xy 348.591262 -265.976867) (xy 348.559704 -265.973564)
			(xy 348.544134 -265.970512) (xy 348.533974 -265.969496) (xy 348.501716 -265.969496) (xy 348.491653 -265.969057)
			(xy 348.473071 -265.961321) (xy 348.465648 -265.95451) (xy 348.443042 -265.931904) (xy 348.435168 -265.9253)
			(xy 348.422565 -265.9168) (xy 348.398903 -265.897714) (xy 348.387924 -265.8872) (xy 348.385384 -265.88466)
			(xy 347.04782 -264.54735) (xy 347.047566 -264.535666) (xy 347.036644 -264.524744) (xy 347.031004 -264.519564)
			(xy 347.017442 -264.512473) (xy 347.009974 -264.510774) (xy 347.007434 -264.51052) (xy 347.004386 -264.510266)
			(xy 346.977088 -264.50786) (xy 346.923539 -264.496213) (xy 346.872208 -264.477024) (xy 346.824151 -264.450688)
			(xy 346.780356 -264.417748) (xy 346.741725 -264.37888) (xy 346.709053 -264.334885) (xy 346.683011 -264.286668)
			(xy 346.67317 -264.261092) (xy 346.665499 -264.239178) (xy 346.654925 -264.193966) (xy 346.652088 -264.170922)
			(xy 346.650818 -264.157206) (xy 346.650564 -264.155428) (xy 346.649802 -264.14984) (xy 346.648075 -264.14265)
			(xy 346.641102 -264.129619) (xy 346.636086 -264.124186) (xy 346.625672 -264.113772) (xy 346.613988 -264.113772)
			(xy 345.255596 -262.755126) (xy 345.249872 -262.753987) (xy 345.238206 -262.753987) (xy 345.232482 -262.755126)
			(xy 345.147138 -262.77697) (xy 345.140855 -262.778767) (xy 345.129414 -262.785071) (xy 345.124532 -262.789416)
			(xy 345.120214 -262.793734) (xy 345.113356 -262.804656) (xy 345.111324 -262.811768) (xy 345.103129 -262.837725)
			(xy 345.080407 -262.887187) (xy 345.050891 -262.93292) (xy 345.015178 -262.973998) (xy 344.973993 -263.009586)
			(xy 344.92817 -263.038963) (xy 344.878639 -263.061535) (xy 344.826405 -263.076842) (xy 344.772526 -263.084574)
			(xy 344.74531 -263.085072) (xy 344.718058 -263.084609) (xy 344.664108 -263.076853) (xy 344.611811 -263.061498)
			(xy 344.562231 -263.038855) (xy 344.51638 -263.009387) (xy 344.475189 -262.973693) (xy 344.439497 -262.9325)
			(xy 344.410032 -262.886646) (xy 344.387393 -262.837065) (xy 344.372041 -262.784767) (xy 344.364289 -262.730816)
			(xy 344.363802 -262.703564) (xy 344.364349 -262.674494) (xy 344.373167 -262.617027) (xy 344.390594 -262.561561)
			(xy 344.416226 -262.509377) (xy 344.449472 -262.461681) (xy 344.489564 -262.419575) (xy 344.535575 -262.384033)
			(xy 344.586441 -262.355876) (xy 344.640987 -262.335754) (xy 344.669364 -262.329422) (xy 344.672666 -262.328914)
			(xy 344.68186 -262.325956) (xy 344.697265 -262.314333) (xy 344.702638 -262.306308) (xy 344.716862 -262.2804)
			(xy 344.742008 -262.234934) (xy 344.743527 -262.231526) (xy 344.745696 -262.224388) (xy 344.746326 -262.22071)
			(xy 344.746326 -262.220202) (xy 344.736105 -262.197632) (xy 344.722126 -262.1501) (xy 344.715811 -262.100959)
			(xy 344.7161 -262.076184) (xy 344.71991 -261.947914) (xy 344.720169 -261.942797) (xy 344.72248 -261.932819)
			(xy 344.724482 -261.928102) (xy 344.770964 -261.828788) (xy 344.773302 -261.823967) (xy 344.779705 -261.81538)
			(xy 344.783664 -261.81177) (xy 344.824304 -261.776718) (xy 344.825066 -261.77621) (xy 344.837071 -261.764621)
			(xy 344.854711 -261.736312) (xy 344.86388 -261.704242) (xy 344.864436 -261.687564) (xy 344.863948 -261.672171)
			(xy 344.856071 -261.642409) (xy 344.840848 -261.61565) (xy 344.819292 -261.59367) (xy 344.792833 -261.577929)
			(xy 344.763231 -261.569474) (xy 344.74785 -261.568692) (xy 344.744548 -261.568692) (xy 344.733075 -261.569012)
			(xy 344.710568 -261.573492) (xy 344.699844 -261.577582) (xy 344.640662 -261.601966) (xy 344.635065 -261.604053)
			(xy 344.623259 -261.605846) (xy 344.617294 -261.605522) (xy 344.553286 -261.600442) (xy 344.527108 -261.597643)
			(xy 344.476155 -261.584405) (xy 344.428141 -261.562819) (xy 344.405966 -261.548626) (xy 344.335608 -261.50189)
			(xy 344.31458 -261.487221) (xy 344.277162 -261.452175) (xy 344.24595 -261.411505) (xy 344.221775 -261.366295)
			(xy 344.205282 -261.317753) (xy 344.196913 -261.267173) (xy 344.196416 -261.24154) (xy 344.196416 -260.541516)
			(xy 344.196416 -260.528816) (xy 344.196416 -260.526276) (xy 344.203782 -260.487922) (xy 344.204544 -260.478524)
			(xy 344.204544 -260.467856) (xy 344.204739 -260.461912) (xy 344.207572 -260.450365) (xy 344.210132 -260.444996)
			(xy 344.21445 -260.432042) (xy 344.215466 -260.427216) (xy 344.225173 -260.402291) (xy 344.251816 -260.355915)
			(xy 344.285933 -260.314724) (xy 344.30589 -260.296914) (xy 344.308684 -260.294374) (xy 344.449908 -260.15315)
			(xy 344.450416 -260.152642) (xy 344.486992 -260.114796) (xy 344.490732 -260.111101) (xy 344.499446 -260.105218)
			(xy 344.504264 -260.103112) (xy 344.602816 -260.063234) (xy 344.607383 -260.06148) (xy 344.616976 -260.059565)
			(xy 344.621866 -260.059424) (xy 346.75699 -260.059424) (xy 346.767062 -260.059003) (xy 346.785671 -260.051294)
			(xy 346.793058 -260.044438) (xy 346.85859 -259.978652) (xy 346.860181 -259.970532) (xy 346.858628 -259.954071)
			(xy 346.855542 -259.946394) (xy 346.852494 -259.939536) (xy 346.840556 -259.927344) (xy 346.834206 -259.922772)
			(xy 346.829888 -259.919978) (xy 346.816172 -259.916422) (xy 346.806774 -259.916676) (xy 346.799408 -259.91693)
			(xy 346.789502 -259.91693) (xy 346.762264 -259.916424) (xy 346.708347 -259.908633) (xy 346.656087 -259.893252)
			(xy 346.606546 -259.870595) (xy 346.560731 -259.841121) (xy 346.519575 -259.80543) (xy 346.483914 -259.764247)
			(xy 346.454473 -259.718411) (xy 346.431851 -259.668854) (xy 346.416508 -259.616583) (xy 346.408756 -259.56266)
			(xy 346.408248 -259.535422) (xy 346.408732 -259.508169) (xy 346.416486 -259.454216) (xy 346.431839 -259.401916)
			(xy 346.454478 -259.352333) (xy 346.483943 -259.306477) (xy 346.519634 -259.265281) (xy 346.560824 -259.229583)
			(xy 346.606675 -259.20011) (xy 346.656254 -259.177462) (xy 346.708552 -259.1621) (xy 346.762503 -259.154337)
			(xy 346.789756 -259.153914) (xy 346.818236 -259.15444) (xy 346.874563 -259.162904) (xy 346.929004 -259.179652)
			(xy 346.980349 -259.20431) (xy 347.027456 -259.236331) (xy 347.069277 -259.275001) (xy 347.104882 -259.31946)
			(xy 347.133478 -259.368721) (xy 347.15443 -259.421687) (xy 347.161358 -259.449316) (xy 347.163898 -259.461254)
			(xy 347.165422 -259.468874) (xy 347.168978 -259.475478) (xy 347.174152 -259.483979) (xy 347.189574 -259.496526)
			(xy 347.19895 -259.499862) (xy 347.279214 -259.524246) (xy 347.292422 -259.526024) (xy 347.301058 -259.526024)
			(xy 347.312742 -259.5245) (xy 347.47581 -259.361686) (xy 347.482664 -259.354291) (xy 347.490408 -259.335692)
			(xy 347.490796 -259.325618) (xy 347.490796 -258.986274) (xy 347.490862 -258.982467) (xy 347.49201 -258.974941)
			(xy 347.493082 -258.971288) (xy 347.519498 -258.885436) (xy 347.525594 -258.872482) (xy 347.543628 -258.844796)
			(xy 347.544644 -258.843272) (xy 347.552603 -258.829093) (xy 347.561359 -258.797793) (xy 347.561371 -258.765292)
			(xy 347.552637 -258.733986) (xy 347.544644 -258.719828) (xy 347.543628 -258.718304) (xy 347.525594 -258.690618)
			(xy 347.523667 -258.687585) (xy 347.52061 -258.681081) (xy 347.519498 -258.677664) (xy 347.493082 -258.591812)
			(xy 347.49203 -258.588155) (xy 347.490886 -258.580631) (xy 347.490796 -258.576826) (xy 347.490796 -255.617218)
			(xy 347.491339 -255.590478) (xy 347.500426 -255.537777) (xy 347.518338 -255.487387) (xy 347.544553 -255.440774)
			(xy 347.57831 -255.399295) (xy 347.618626 -255.364157) (xy 347.641164 -255.349756) (xy 347.705934 -255.310386)
			(xy 347.72087 -255.301572) (xy 347.752311 -255.286928) (xy 347.768672 -255.281176) (xy 347.777054 -255.276096)
			(xy 347.782777 -255.272857) (xy 347.795382 -255.269128) (xy 347.801946 -255.26873) (xy 347.820742 -255.268222)
			(xy 347.826584 -255.267714) (xy 347.836949 -255.266413) (xy 347.857794 -255.265016) (xy 347.86824 -255.26492)
			(xy 347.924882 -255.26492) (xy 347.92666 -255.265174) (xy 347.93555 -255.26492) (xy 347.935804 -255.26492)
			(xy 347.94233 -255.264857) (xy 347.955064 -255.26769) (xy 347.96095 -255.270508) (xy 347.969586 -255.274826)
			(xy 347.989906 -255.279652) (xy 348.001082 -255.283462) (xy 348.026482 -255.296162) (xy 348.027752 -255.29667)
			(xy 348.038726 -255.30146) (xy 348.062023 -255.306968) (xy 348.07398 -255.307592) (xy 348.077536 -255.307592)
			(xy 348.091616 -255.307194) (xy 348.118994 -255.300603) (xy 348.144073 -255.287794) (xy 348.165463 -255.269478)
			(xy 348.174056 -255.258316) (xy 348.174818 -255.2573) (xy 348.192598 -255.23317) (xy 348.199456 -255.225804)
			(xy 348.206568 -255.2192) (xy 348.208854 -255.213358) (xy 348.210372 -255.20907) (xy 348.212027 -255.200126)
			(xy 348.212156 -255.195578) (xy 348.212156 -255.181862) (xy 348.212035 -255.177314) (xy 348.210379 -255.168369)
			(xy 348.208854 -255.164082) (xy 348.206568 -255.15824) (xy 348.199456 -255.151636) (xy 348.192598 -255.14427)
			(xy 348.174818 -255.12014) (xy 348.174056 -255.119124) (xy 348.165734 -255.108226) (xy 348.145055 -255.090232)
			(xy 348.120807 -255.077447) (xy 348.094277 -255.070549) (xy 348.080584 -255.069848) (xy 348.077282 -255.069848)
			(xy 348.063145 -255.070251) (xy 348.035673 -255.07693) (xy 348.022926 -255.083056) (xy 348.021148 -255.084072)
			(xy 347.958664 -255.115314) (xy 347.952865 -255.11797) (xy 347.940404 -255.120667) (xy 347.934026 -255.120648)
			(xy 347.799152 -255.115568) (xy 347.790516 -255.118362) (xy 347.788992 -255.117346) (xy 347.780041 -255.112445)
			(xy 347.759872 -255.109446) (xy 347.749876 -255.111504) (xy 347.699584 -255.12395) (xy 347.695326 -255.125174)
			(xy 347.687277 -255.128873) (xy 347.683582 -255.131316) (xy 347.661992 -255.145794) (xy 347.656404 -255.155192)
			(xy 347.641407 -255.178682) (xy 347.605684 -255.221454) (xy 347.564127 -255.258585) (xy 347.517618 -255.289286)
			(xy 347.467144 -255.312908) (xy 347.413774 -255.328948) (xy 347.35864 -255.337067) (xy 347.330776 -255.337564)
			(xy 347.330522 -255.337564) (xy 347.299393 -255.336945) (xy 347.237961 -255.326844) (xy 347.178977 -255.306921)
			(xy 347.151198 -255.29286) (xy 347.149166 -255.291844) (xy 347.1418 -255.289812) (xy 347.135958 -255.288288)
			(xy 347.128678 -255.286742) (xy 347.113823 -255.287505) (xy 347.106748 -255.289812) (xy 347.096334 -255.293622)
			(xy 347.043502 -255.313434) (xy 347.039306 -255.315342) (xy 347.031636 -255.320454) (xy 347.028262 -255.323594)
			(xy 347.007434 -255.345184) (xy 347.003878 -255.354074) (xy 346.99277 -255.380085) (xy 346.964 -255.428777)
			(xy 346.928354 -255.472687) (xy 346.886614 -255.51085) (xy 346.839696 -255.54243) (xy 346.788627 -255.566735)
			(xy 346.734529 -255.583231) (xy 346.678589 -255.591556) (xy 346.65031 -255.592072) (xy 346.623059 -255.591609)
			(xy 346.569112 -255.583854) (xy 346.516818 -255.568501) (xy 346.467242 -255.545861) (xy 346.421391 -255.516396)
			(xy 346.380201 -255.480706) (xy 346.34451 -255.439517) (xy 346.315044 -255.393667) (xy 346.292403 -255.344091)
			(xy 346.277048 -255.291797) (xy 346.269291 -255.237851) (xy 346.269291 -255.183349) (xy 346.277048 -255.129403)
			(xy 346.292403 -255.077109) (xy 346.315044 -255.027533) (xy 346.34451 -254.981683) (xy 346.380201 -254.940494)
			(xy 346.421391 -254.904804) (xy 346.467242 -254.875339) (xy 346.516818 -254.852699) (xy 346.569112 -254.837346)
			(xy 346.623059 -254.829591) (xy 346.65031 -254.829056) (xy 346.680678 -254.829646) (xy 346.740646 -254.839277)
			(xy 346.798328 -254.858295) (xy 346.82557 -254.871728) (xy 346.83065 -254.874268) (xy 346.845128 -254.878078)
			(xy 346.852671 -254.879671) (xy 346.868054 -254.878776) (xy 346.875354 -254.8763) (xy 346.918026 -254.860298)
			(xy 346.937584 -254.852932) (xy 346.941617 -254.851101) (xy 346.949024 -254.846244) (xy 346.952316 -254.84328)
			(xy 346.961714 -254.833882) (xy 346.968064 -254.826008) (xy 346.973652 -254.817372) (xy 346.978224 -254.80899)
			(xy 346.989495 -254.783266) (xy 347.018476 -254.73516) (xy 347.054188 -254.691815) (xy 347.09586 -254.654166)
			(xy 347.142596 -254.623024) (xy 347.193387 -254.599059) (xy 347.24714 -254.582788) (xy 347.302695 -254.574563)
			(xy 347.330776 -254.57404) (xy 347.358018 -254.574542) (xy 347.411945 -254.582318) (xy 347.438218 -254.589534)
			(xy 347.438726 -254.589534) (xy 347.44787 -254.592328) (xy 347.46565 -254.591058) (xy 347.47327 -254.587502)
			(xy 347.478221 -254.585115) (xy 347.487051 -254.578573) (xy 347.490796 -254.574548) (xy 347.490796 -254.56261)
			(xy 347.520006 -254.499364) (xy 347.52026 -254.49911) (xy 347.525419 -254.48718) (xy 347.531051 -254.461811)
			(xy 347.531436 -254.448818) (xy 347.531436 -254.44831) (xy 347.531109 -254.435311) (xy 347.525473 -254.409931)
			(xy 347.52026 -254.398018) (xy 347.520006 -254.397764) (xy 347.495368 -254.344678) (xy 347.493202 -254.339614)
			(xy 347.490884 -254.328849) (xy 347.490796 -254.323342) (xy 347.490796 -253.143258) (xy 347.490796 -253.130558)
			(xy 347.490796 -253.128018) (xy 347.509846 -253.028958) (xy 347.519552 -253.004033) (xy 347.546196 -252.957657)
			(xy 347.580315 -252.916468) (xy 347.60027 -252.898656) (xy 347.60281 -252.896116) (xy 347.687646 -252.811534)
			(xy 347.688154 -252.811026) (xy 347.72473 -252.77318) (xy 347.728469 -252.769481) (xy 347.737178 -252.763591)
			(xy 347.742002 -252.761496) (xy 347.840554 -252.721618) (xy 347.84512 -252.719859) (xy 347.854713 -252.717933)
			(xy 347.859604 -252.717808) (xy 350.007174 -252.717808) (xy 350.019874 -252.717808) (xy 350.022414 -252.717808)
			(xy 350.121474 -252.736858) (xy 350.146397 -252.746566) (xy 350.192769 -252.773215) (xy 350.233954 -252.807337)
			(xy 350.251776 -252.827282) (xy 350.254316 -252.830076) (xy 350.40316 -252.97892) (xy 350.407599 -252.979899)
			(xy 350.416673 -252.980409) (xy 350.421194 -252.979936) (xy 350.421702 -252.979936) (xy 350.426528 -252.979174)
			(xy 350.499426 -252.96241) (xy 350.504397 -252.960932) (xy 350.513622 -252.956198) (xy 350.517714 -252.953012)
			(xy 350.527112 -252.94463) (xy 350.52762 -252.944122) (xy 350.537526 -252.935486) (xy 350.544638 -252.927358)
			(xy 350.547686 -252.923294) (xy 350.550226 -252.91669) (xy 350.561103 -252.890215) (xy 350.589631 -252.840596)
			(xy 350.625245 -252.79579) (xy 350.667146 -252.7568) (xy 350.714397 -252.7245) (xy 350.765939 -252.699613)
			(xy 350.820618 -252.682696) (xy 350.877208 -252.674129) (xy 350.905826 -252.673612) (xy 350.933075 -252.6741)
			(xy 350.987019 -252.68186) (xy 351.03931 -252.697217) (xy 351.088882 -252.71986) (xy 351.134728 -252.749327)
			(xy 351.175913 -252.785019) (xy 351.2116 -252.826209) (xy 351.241062 -252.872058) (xy 351.263699 -252.921633)
			(xy 351.27905 -252.973926) (xy 351.286803 -253.02787) (xy 351.287334 -253.05512) (xy 351.286809 -253.083546)
			(xy 351.27837 -253.139767) (xy 351.261682 -253.194114) (xy 351.237114 -253.245383) (xy 351.205211 -253.292439)
			(xy 351.166678 -253.33424) (xy 351.12237 -253.369861) (xy 351.091522 -253.38786) (xy 358.443274 -253.38786)
			(xy 358.447345 -253.332238) (xy 358.459471 -253.277801) (xy 358.479394 -253.22571) (xy 358.50669 -253.177075)
			(xy 358.540776 -253.132932) (xy 358.580925 -253.094223) (xy 358.626283 -253.061772) (xy 358.675883 -253.036271)
			(xy 358.728667 -253.018264) (xy 358.78351 -253.008134) (xy 358.839244 -253.006097) (xy 358.894681 -253.012197)
			(xy 358.948638 -253.026303) (xy 358.999967 -253.048115) (xy 359.047573 -253.077169) (xy 359.090441 -253.112844)
			(xy 359.127658 -253.154381) (xy 359.158431 -253.200894) (xy 359.182103 -253.251391) (xy 359.198171 -253.304798)
			(xy 359.206291 -253.359974) (xy 359.2068 -253.38786) (xy 359.206291 -253.415746) (xy 359.198171 -253.470922)
			(xy 359.182103 -253.524329) (xy 359.158431 -253.574826) (xy 359.127658 -253.621339) (xy 359.090441 -253.662876)
			(xy 359.047573 -253.698551) (xy 358.999967 -253.727605) (xy 358.948638 -253.749417) (xy 358.894681 -253.763523)
			(xy 358.839244 -253.769623) (xy 358.78351 -253.767586) (xy 358.728667 -253.757456) (xy 358.675883 -253.739449)
			(xy 358.626283 -253.713948) (xy 358.580925 -253.681497) (xy 358.540776 -253.642788) (xy 358.50669 -253.598645)
			(xy 358.479394 -253.55001) (xy 358.459471 -253.497919) (xy 358.447345 -253.443482) (xy 358.443274 -253.38786)
			(xy 351.091522 -253.38786) (xy 351.073266 -253.398512) (xy 351.020454 -253.41956) (xy 350.965104 -253.432538)
			(xy 350.936814 -253.435358) (xy 350.93529 -253.435358) (xy 350.933258 -253.435612) (xy 350.931226 -253.43612)
			(xy 350.921944 -253.438368) (xy 350.90588 -253.448674) (xy 350.899984 -253.456186) (xy 350.89973 -253.45644)
			(xy 350.879918 -253.484126) (xy 350.878394 -253.486412) (xy 350.878394 -253.48692) (xy 350.874076 -253.496572)
			(xy 350.884998 -253.523496) (xy 350.886752 -253.528063) (xy 350.888671 -253.537655) (xy 350.888808 -253.542546)
			(xy 350.888808 -253.985014) (xy 353.918772 -253.985014) (xy 353.922843 -253.929392) (xy 353.934969 -253.874955)
			(xy 353.954892 -253.822864) (xy 353.982188 -253.774229) (xy 354.016274 -253.730086) (xy 354.056423 -253.691377)
			(xy 354.101781 -253.658926) (xy 354.151381 -253.633425) (xy 354.204165 -253.615418) (xy 354.259008 -253.605288)
			(xy 354.314742 -253.603251) (xy 354.370179 -253.609351) (xy 354.424136 -253.623457) (xy 354.475465 -253.645269)
			(xy 354.523071 -253.674323) (xy 354.565939 -253.709998) (xy 354.603156 -253.751535) (xy 354.633929 -253.798048)
			(xy 354.657601 -253.848545) (xy 354.673669 -253.901952) (xy 354.681789 -253.957128) (xy 354.682298 -253.985014)
			(xy 354.681789 -254.0129) (xy 354.673669 -254.068076) (xy 354.657601 -254.121483) (xy 354.633929 -254.17198)
			(xy 354.603156 -254.218493) (xy 354.565939 -254.26003) (xy 354.523071 -254.295705) (xy 354.475465 -254.324759)
			(xy 354.424136 -254.346571) (xy 354.370179 -254.360677) (xy 354.314742 -254.366777) (xy 354.259008 -254.36474)
			(xy 354.204165 -254.35461) (xy 354.151381 -254.336603) (xy 354.101781 -254.311102) (xy 354.056423 -254.278651)
			(xy 354.016274 -254.239942) (xy 353.982188 -254.195799) (xy 353.954892 -254.147164) (xy 353.934969 -254.095073)
			(xy 353.922843 -254.040636) (xy 353.918772 -253.985014) (xy 350.888808 -253.985014) (xy 350.888808 -255.11125)
			(xy 353.193856 -255.11125) (xy 353.197927 -255.055628) (xy 353.210053 -255.001191) (xy 353.229976 -254.9491)
			(xy 353.257272 -254.900465) (xy 353.291358 -254.856322) (xy 353.331507 -254.817613) (xy 353.376865 -254.785162)
			(xy 353.426465 -254.759661) (xy 353.479249 -254.741654) (xy 353.534092 -254.731524) (xy 353.589826 -254.729487)
			(xy 353.645263 -254.735587) (xy 353.69922 -254.749693) (xy 353.750549 -254.771505) (xy 353.798155 -254.800559)
			(xy 353.841023 -254.836234) (xy 353.87824 -254.877771) (xy 353.909013 -254.924284) (xy 353.932685 -254.974781)
			(xy 353.948753 -255.028188) (xy 353.956873 -255.083364) (xy 353.957382 -255.11125) (xy 353.956873 -255.139136)
			(xy 353.948753 -255.194312) (xy 353.932685 -255.247719) (xy 353.909013 -255.298216) (xy 353.87824 -255.344729)
			(xy 353.841023 -255.386266) (xy 353.798155 -255.421941) (xy 353.750549 -255.450995) (xy 353.69922 -255.472807)
			(xy 353.645263 -255.486913) (xy 353.589826 -255.493013) (xy 353.534092 -255.490976) (xy 353.479249 -255.480846)
			(xy 353.426465 -255.462839) (xy 353.376865 -255.437338) (xy 353.331507 -255.404887) (xy 353.291358 -255.366178)
			(xy 353.257272 -255.322035) (xy 353.229976 -255.2734) (xy 353.210053 -255.221309) (xy 353.197927 -255.166872)
			(xy 353.193856 -255.11125) (xy 350.888808 -255.11125) (xy 350.888808 -256.226564) (xy 358.420668 -256.226564)
			(xy 358.424739 -256.170942) (xy 358.436865 -256.116505) (xy 358.456788 -256.064414) (xy 358.484084 -256.015779)
			(xy 358.51817 -255.971636) (xy 358.558319 -255.932927) (xy 358.603677 -255.900476) (xy 358.653277 -255.874975)
			(xy 358.706061 -255.856968) (xy 358.760904 -255.846838) (xy 358.816638 -255.844801) (xy 358.872075 -255.850901)
			(xy 358.926032 -255.865007) (xy 358.977361 -255.886819) (xy 359.024967 -255.915873) (xy 359.067835 -255.951548)
			(xy 359.105052 -255.993085) (xy 359.135825 -256.039598) (xy 359.159497 -256.090095) (xy 359.175565 -256.143502)
			(xy 359.183685 -256.198678) (xy 359.184194 -256.226564) (xy 359.183685 -256.25445) (xy 359.175565 -256.309626)
			(xy 359.159497 -256.363033) (xy 359.135825 -256.41353) (xy 359.105052 -256.460043) (xy 359.067835 -256.50158)
			(xy 359.024967 -256.537255) (xy 358.977361 -256.566309) (xy 358.926032 -256.588121) (xy 358.872075 -256.602227)
			(xy 358.816638 -256.608327) (xy 358.760904 -256.60629) (xy 358.706061 -256.59616) (xy 358.653277 -256.578153)
			(xy 358.603677 -256.552652) (xy 358.558319 -256.520201) (xy 358.51817 -256.481492) (xy 358.484084 -256.437349)
			(xy 358.456788 -256.388714) (xy 358.436865 -256.336623) (xy 358.424739 -256.282186) (xy 358.420668 -256.226564)
			(xy 350.888808 -256.226564) (xy 350.888808 -258.131564) (xy 358.458768 -258.131564) (xy 358.462839 -258.075942)
			(xy 358.474965 -258.021505) (xy 358.494888 -257.969414) (xy 358.522184 -257.920779) (xy 358.55627 -257.876636)
			(xy 358.596419 -257.837927) (xy 358.641777 -257.805476) (xy 358.691377 -257.779975) (xy 358.744161 -257.761968)
			(xy 358.799004 -257.751838) (xy 358.854738 -257.749801) (xy 358.910175 -257.755901) (xy 358.964132 -257.770007)
			(xy 359.015461 -257.791819) (xy 359.063067 -257.820873) (xy 359.105935 -257.856548) (xy 359.143152 -257.898085)
			(xy 359.173925 -257.944598) (xy 359.197597 -257.995095) (xy 359.213665 -258.048502) (xy 359.221785 -258.103678)
			(xy 359.222294 -258.131564) (xy 359.221785 -258.15945) (xy 359.213665 -258.214626) (xy 359.197597 -258.268033)
			(xy 359.173925 -258.31853) (xy 359.143152 -258.365043) (xy 359.105935 -258.40658) (xy 359.063067 -258.442255)
			(xy 359.015461 -258.471309) (xy 358.964132 -258.493121) (xy 358.910175 -258.507227) (xy 358.854738 -258.513327)
			(xy 358.799004 -258.51129) (xy 358.744161 -258.50116) (xy 358.691377 -258.483153) (xy 358.641777 -258.457652)
			(xy 358.596419 -258.425201) (xy 358.55627 -258.386492) (xy 358.522184 -258.342349) (xy 358.494888 -258.293714)
			(xy 358.474965 -258.241623) (xy 358.462839 -258.187186) (xy 358.458768 -258.131564) (xy 350.888808 -258.131564)
			(xy 350.888808 -259.19176) (xy 355.780592 -259.19176) (xy 355.784663 -259.136138) (xy 355.796789 -259.081701)
			(xy 355.816712 -259.02961) (xy 355.844008 -258.980975) (xy 355.878094 -258.936832) (xy 355.918243 -258.898123)
			(xy 355.963601 -258.865672) (xy 356.013201 -258.840171) (xy 356.065985 -258.822164) (xy 356.120828 -258.812034)
			(xy 356.176562 -258.809997) (xy 356.231999 -258.816097) (xy 356.285956 -258.830203) (xy 356.337285 -258.852015)
			(xy 356.384891 -258.881069) (xy 356.427759 -258.916744) (xy 356.464976 -258.958281) (xy 356.495749 -259.004794)
			(xy 356.519421 -259.055291) (xy 356.535489 -259.108698) (xy 356.543609 -259.163874) (xy 356.544118 -259.19176)
			(xy 356.543609 -259.219646) (xy 356.535489 -259.274822) (xy 356.519421 -259.328229) (xy 356.495749 -259.378726)
			(xy 356.464976 -259.425239) (xy 356.427759 -259.466776) (xy 356.384891 -259.502451) (xy 356.337285 -259.531505)
			(xy 356.285956 -259.553317) (xy 356.231999 -259.567423) (xy 356.176562 -259.573523) (xy 356.120828 -259.571486)
			(xy 356.065985 -259.561356) (xy 356.013201 -259.543349) (xy 355.963601 -259.517848) (xy 355.918243 -259.485397)
			(xy 355.878094 -259.446688) (xy 355.844008 -259.402545) (xy 355.816712 -259.35391) (xy 355.796789 -259.301819)
			(xy 355.784663 -259.247382) (xy 355.780592 -259.19176) (xy 350.888808 -259.19176) (xy 350.888808 -260.46811)
			(xy 350.889233 -260.478179) (xy 350.896951 -260.49678) (xy 350.903794 -260.504178) (xy 351.24771 -260.848094)
			(xy 351.255109 -260.854939) (xy 351.273707 -260.862671) (xy 351.283778 -260.86308) (xy 351.479612 -260.86308)
			(xy 351.49554 -260.863313) (xy 351.527226 -260.866617) (xy 351.542858 -260.869684) (xy 351.553018 -260.8707)
			(xy 354.04806 -260.8707) (xy 354.058125 -260.871134) (xy 354.076714 -260.878864) (xy 354.084128 -260.885686)
			(xy 354.533454 -261.335266) (xy 354.539684 -261.340746) (xy 354.554714 -261.347747) (xy 354.562918 -261.348982)
			(xy 354.56749 -261.349236) (xy 355.639116 -261.349236) (xy 355.665698 -261.349674) (xy 355.718344 -261.357067)
			(xy 355.744018 -261.363968) (xy 355.764592 -261.370572) (xy 355.784912 -261.378446) (xy 359.282238 -262.827008)
			(xy 359.305152 -262.836902) (xy 359.348393 -262.86183) (xy 359.388007 -262.892195) (xy 359.405936 -262.909558)
			(xy 364.143036 -267.646658) (xy 364.163814 -267.668273) (xy 364.199049 -267.71678) (xy 364.226267 -267.770199)
			(xy 364.244798 -267.827216) (xy 364.254186 -267.88643) (xy 364.254796 -267.916406) (xy 364.254796 -275.675852)
			(xy 364.25505 -275.6789) (xy 364.25505 -275.679916) (xy 364.256828 -275.690076) (xy 364.257336 -275.691346)
			(xy 364.327694 -275.861526) (xy 364.405418 -276.049232) (xy 364.849156 -277.12035) (xy 364.854998 -277.129748)
			(xy 365.181642 -277.456392) (xy 365.188053 -277.462261) (xy 365.203769 -277.469655) (xy 365.212376 -277.47087)
			(xy 365.220504 -277.471632) (xy 365.237776 -277.467314) (xy 365.245142 -277.462234) (xy 365.322612 -277.40991)
			(xy 365.328708 -277.405592) (xy 365.337362 -277.398762) (xy 365.348341 -277.379669) (xy 365.350389 -277.35774)
			(xy 365.34725 -277.347172) (xy 365.313751 -277.268065) (xy 365.253867 -277.107026) (xy 365.202244 -276.943153)
			(xy 365.159016 -276.776868) (xy 365.124293 -276.608601) (xy 365.098166 -276.438787) (xy 365.080703 -276.267865)
			(xy 365.071948 -276.096276) (xy 365.071406 -276.01037) (xy 365.071406 -276.010116) (xy 365.071901 -275.927738)
			(xy 365.079931 -275.763178) (xy 365.095972 -275.599206) (xy 365.119987 -275.43621) (xy 365.151918 -275.274578)
			(xy 365.19169 -275.114695) (xy 365.239207 -274.95694) (xy 365.294357 -274.801689) (xy 365.357009 -274.649311)
			(xy 365.427014 -274.500168) (xy 365.504206 -274.354614) (xy 365.5884 -274.212996) (xy 365.679397 -274.07565)
			(xy 365.776981 -273.942903) (xy 365.880919 -273.81507) (xy 365.990964 -273.692455) (xy 366.106855 -273.575349)
			(xy 366.228317 -273.464032) (xy 366.35506 -273.358768) (xy 366.486783 -273.259806) (xy 366.623173 -273.167383)
			(xy 366.763906 -273.081717) (xy 366.908648 -273.003013) (xy 367.057054 -272.931458) (xy 367.208771 -272.867221)
			(xy 367.363438 -272.810456) (xy 367.520689 -272.761297) (xy 367.680149 -272.719862) (xy 367.841439 -272.686248)
			(xy 368.004176 -272.660536) (xy 368.167973 -272.642787) (xy 368.33244 -272.633043) (xy 368.414808 -272.631662)
			(xy 368.422872 -272.631292) (xy 368.438151 -272.62611) (xy 368.44478 -272.621502) (xy 368.450368 -272.616676)
			(xy 368.471196 -272.595848) (xy 368.476276 -272.589752) (xy 368.479746 -272.584843) (xy 368.484492 -272.573802)
			(xy 368.485674 -272.567908) (xy 368.486182 -272.55978) (xy 368.486182 -256.766568) (xy 368.486017 -256.760558)
			(xy 368.483196 -256.748874) (xy 368.480594 -256.743454) (xy 368.478753 -256.739981) (xy 368.474156 -256.733605)
			(xy 368.47145 -256.730754) (xy 367.73612 -255.995424) (xy 367.728708 -255.98874) (xy 367.710275 -255.981143)
			(xy 367.690337 -255.981143) (xy 367.671904 -255.98874) (xy 367.664492 -255.995424) (xy 366.439196 -257.22072)
			(xy 366.436493 -257.223573) (xy 366.431905 -257.229954) (xy 366.430052 -257.23342) (xy 366.427464 -257.238846)
			(xy 366.424632 -257.250525) (xy 366.424464 -257.256534) (xy 366.424464 -261.193026) (xy 366.424035 -261.203093)
			(xy 366.41631 -261.221688) (xy 366.409478 -261.229094) (xy 365.940848 -261.69747) (xy 365.933448 -261.704311)
			(xy 365.91485 -261.712032) (xy 365.90478 -261.712456) (xy 360.387646 -261.712456) (xy 360.377581 -261.712022)
			(xy 360.358995 -261.704289) (xy 360.351578 -261.69747) (xy 359.857294 -261.20344) (xy 359.850458 -261.196038)
			(xy 359.842746 -261.17744) (xy 359.842308 -261.167372) (xy 359.842308 -256.1463) (xy 359.842731 -256.13623)
			(xy 359.850447 -256.117626) (xy 359.857294 -256.110232) (xy 359.874566 -256.09296) (xy 359.88141 -256.085561)
			(xy 359.889135 -256.066962) (xy 359.889552 -256.056892) (xy 359.889552 -253.211584) (xy 359.889125 -253.201516)
			(xy 359.881401 -253.182921) (xy 359.874566 -253.175516) (xy 358.020366 -251.321316) (xy 358.012966 -251.314473)
			(xy 357.994368 -251.306749) (xy 357.984298 -251.30633) (xy 357.876348 -251.30633) (xy 357.866823 -251.306722)
			(xy 357.849092 -251.313686) (xy 357.835147 -251.326665) (xy 357.82693 -251.343851) (xy 357.825802 -251.35332)
			(xy 357.823245 -251.380368) (xy 357.811446 -251.433399) (xy 357.792246 -251.48422) (xy 357.766032 -251.531805)
			(xy 357.733334 -251.575192) (xy 357.694813 -251.613502) (xy 357.651249 -251.645962) (xy 357.603521 -251.671916)
			(xy 357.552595 -251.690838) (xy 357.4995 -251.702347) (xy 357.44531 -251.706209) (xy 357.39112 -251.702347)
			(xy 357.338025 -251.690838) (xy 357.287099 -251.671916) (xy 357.239371 -251.645962) (xy 357.195807 -251.613502)
			(xy 357.157286 -251.575192) (xy 357.124588 -251.531805) (xy 357.098374 -251.48422) (xy 357.079174 -251.433399)
			(xy 357.067375 -251.380368) (xy 357.064818 -251.35332) (xy 357.063702 -251.343859) (xy 357.055437 -251.326711)
			(xy 357.041494 -251.31375) (xy 357.023789 -251.306757) (xy 357.014272 -251.30633) (xy 356.352348 -251.30633)
			(xy 356.342823 -251.306722) (xy 356.325092 -251.313686) (xy 356.311147 -251.326665) (xy 356.30293 -251.343851)
			(xy 356.301802 -251.35332) (xy 356.299245 -251.380368) (xy 356.287446 -251.433399) (xy 356.268246 -251.48422)
			(xy 356.242032 -251.531805) (xy 356.209334 -251.575192) (xy 356.170813 -251.613502) (xy 356.127249 -251.645962)
			(xy 356.079521 -251.671916) (xy 356.028595 -251.690838) (xy 355.9755 -251.702347) (xy 355.92131 -251.706209)
			(xy 355.86712 -251.702347) (xy 355.814025 -251.690838) (xy 355.763099 -251.671916) (xy 355.715371 -251.645962)
			(xy 355.671807 -251.613502) (xy 355.633286 -251.575192) (xy 355.600588 -251.531805) (xy 355.574374 -251.48422)
			(xy 355.555174 -251.433399) (xy 355.543375 -251.380368) (xy 355.540818 -251.35332) (xy 355.539702 -251.343859)
			(xy 355.531437 -251.326711) (xy 355.517494 -251.31375) (xy 355.499789 -251.306757) (xy 355.490272 -251.30633)
			(xy 345.997784 -251.30633) (xy 345.987716 -251.306757) (xy 345.969118 -251.314479) (xy 345.961716 -251.321316)
			(xy 345.358466 -251.924566) (xy 350.94113 -251.924566) (xy 350.945201 -251.868944) (xy 350.957327 -251.814507)
			(xy 350.97725 -251.762416) (xy 351.004546 -251.713781) (xy 351.038632 -251.669638) (xy 351.078781 -251.630929)
			(xy 351.124139 -251.598478) (xy 351.173739 -251.572977) (xy 351.226523 -251.55497) (xy 351.281366 -251.54484)
			(xy 351.3371 -251.542803) (xy 351.392537 -251.548903) (xy 351.446494 -251.563009) (xy 351.497823 -251.584821)
			(xy 351.545429 -251.613875) (xy 351.588297 -251.64955) (xy 351.625514 -251.691087) (xy 351.656287 -251.7376)
			(xy 351.679959 -251.788097) (xy 351.696027 -251.841504) (xy 351.704147 -251.89668) (xy 351.704656 -251.924566)
			(xy 351.704147 -251.952452) (xy 351.696027 -252.007628) (xy 351.679959 -252.061035) (xy 351.656287 -252.111532)
			(xy 351.655797 -252.112272) (xy 352.47275 -252.112272) (xy 352.476821 -252.05665) (xy 352.488947 -252.002213)
			(xy 352.50887 -251.950122) (xy 352.536166 -251.901487) (xy 352.570252 -251.857344) (xy 352.610401 -251.818635)
			(xy 352.655759 -251.786184) (xy 352.705359 -251.760683) (xy 352.758143 -251.742676) (xy 352.812986 -251.732546)
			(xy 352.86872 -251.730509) (xy 352.924157 -251.736609) (xy 352.978114 -251.750715) (xy 353.029443 -251.772527)
			(xy 353.077049 -251.801581) (xy 353.119917 -251.837256) (xy 353.157134 -251.878793) (xy 353.187907 -251.925306)
			(xy 353.211579 -251.975803) (xy 353.227647 -252.02921) (xy 353.235767 -252.084386) (xy 353.236276 -252.112272)
			(xy 353.235767 -252.140158) (xy 353.227647 -252.195334) (xy 353.211579 -252.248741) (xy 353.187907 -252.299238)
			(xy 353.157134 -252.345751) (xy 353.119917 -252.387288) (xy 353.077049 -252.422963) (xy 353.029443 -252.452017)
			(xy 352.978114 -252.473829) (xy 352.924157 -252.487935) (xy 352.86872 -252.494035) (xy 352.812986 -252.491998)
			(xy 352.758143 -252.481868) (xy 352.705359 -252.463861) (xy 352.655759 -252.43836) (xy 352.610401 -252.405909)
			(xy 352.570252 -252.3672) (xy 352.536166 -252.323057) (xy 352.50887 -252.274422) (xy 352.488947 -252.222331)
			(xy 352.476821 -252.167894) (xy 352.47275 -252.112272) (xy 351.655797 -252.112272) (xy 351.625514 -252.158045)
			(xy 351.588297 -252.199582) (xy 351.545429 -252.235257) (xy 351.497823 -252.264311) (xy 351.446494 -252.286123)
			(xy 351.392537 -252.300229) (xy 351.3371 -252.306329) (xy 351.281366 -252.304292) (xy 351.226523 -252.294162)
			(xy 351.173739 -252.276155) (xy 351.124139 -252.250654) (xy 351.078781 -252.218203) (xy 351.038632 -252.179494)
			(xy 351.004546 -252.135351) (xy 350.97725 -252.086716) (xy 350.957327 -252.034625) (xy 350.945201 -251.980188)
			(xy 350.94113 -251.924566) (xy 345.358466 -251.924566) (xy 341.759286 -255.523746) (xy 341.751889 -255.530596)
			(xy 341.733291 -255.538334) (xy 341.723218 -255.538732) (xy 330.994766 -255.538732) (xy 330.984765 -255.539226)
			(xy 330.966291 -255.546893) (xy 330.952156 -255.561046) (xy 330.944513 -255.579531) (xy 330.943966 -255.589532)
			(xy 330.943966 -259.020564) (xy 344.490292 -259.020564) (xy 344.494363 -258.964942) (xy 344.506489 -258.910505)
			(xy 344.526412 -258.858414) (xy 344.553708 -258.809779) (xy 344.587794 -258.765636) (xy 344.627943 -258.726927)
			(xy 344.673301 -258.694476) (xy 344.722901 -258.668975) (xy 344.775685 -258.650968) (xy 344.830528 -258.640838)
			(xy 344.886262 -258.638801) (xy 344.941699 -258.644901) (xy 344.995656 -258.659007) (xy 345.046985 -258.680819)
			(xy 345.094591 -258.709873) (xy 345.137459 -258.745548) (xy 345.174676 -258.787085) (xy 345.205449 -258.833598)
			(xy 345.229121 -258.884095) (xy 345.245189 -258.937502) (xy 345.253309 -258.992678) (xy 345.253818 -259.020564)
			(xy 345.379292 -259.020564) (xy 345.383363 -258.964942) (xy 345.395489 -258.910505) (xy 345.415412 -258.858414)
			(xy 345.442708 -258.809779) (xy 345.476794 -258.765636) (xy 345.516943 -258.726927) (xy 345.562301 -258.694476)
			(xy 345.611901 -258.668975) (xy 345.664685 -258.650968) (xy 345.719528 -258.640838) (xy 345.775262 -258.638801)
			(xy 345.830699 -258.644901) (xy 345.884656 -258.659007) (xy 345.935985 -258.680819) (xy 345.983591 -258.709873)
			(xy 346.026459 -258.745548) (xy 346.063676 -258.787085) (xy 346.094449 -258.833598) (xy 346.118121 -258.884095)
			(xy 346.134189 -258.937502) (xy 346.142309 -258.992678) (xy 346.142818 -259.020564) (xy 346.142309 -259.04845)
			(xy 346.134189 -259.103626) (xy 346.118121 -259.157033) (xy 346.094449 -259.20753) (xy 346.063676 -259.254043)
			(xy 346.026459 -259.29558) (xy 345.983591 -259.331255) (xy 345.935985 -259.360309) (xy 345.884656 -259.382121)
			(xy 345.830699 -259.396227) (xy 345.775262 -259.402327) (xy 345.719528 -259.40029) (xy 345.664685 -259.39016)
			(xy 345.611901 -259.372153) (xy 345.562301 -259.346652) (xy 345.516943 -259.314201) (xy 345.476794 -259.275492)
			(xy 345.442708 -259.231349) (xy 345.415412 -259.182714) (xy 345.395489 -259.130623) (xy 345.383363 -259.076186)
			(xy 345.379292 -259.020564) (xy 345.253818 -259.020564) (xy 345.253309 -259.04845) (xy 345.245189 -259.103626)
			(xy 345.229121 -259.157033) (xy 345.205449 -259.20753) (xy 345.174676 -259.254043) (xy 345.137459 -259.29558)
			(xy 345.094591 -259.331255) (xy 345.046985 -259.360309) (xy 344.995656 -259.382121) (xy 344.941699 -259.396227)
			(xy 344.886262 -259.402327) (xy 344.830528 -259.40029) (xy 344.775685 -259.39016) (xy 344.722901 -259.372153)
			(xy 344.673301 -259.346652) (xy 344.627943 -259.314201) (xy 344.587794 -259.275492) (xy 344.553708 -259.231349)
			(xy 344.526412 -259.182714) (xy 344.506489 -259.130623) (xy 344.494363 -259.076186) (xy 344.490292 -259.020564)
			(xy 330.943966 -259.020564) (xy 330.943966 -261.346442) (xy 340.147402 -261.346442) (xy 340.14783 -261.320127)
			(xy 340.155073 -261.267996) (xy 340.1694 -261.217353) (xy 340.190539 -261.169154) (xy 340.218092 -261.124312)
			(xy 340.251538 -261.083674) (xy 340.270592 -261.065518) (xy 340.277986 -261.05799) (xy 340.286515 -261.038715)
			(xy 340.287102 -261.02818) (xy 340.287102 -260.953504) (xy 340.286583 -260.942953) (xy 340.278041 -260.923658)
			(xy 340.270592 -260.916166) (xy 340.251525 -260.898022) (xy 340.21807 -260.857389) (xy 340.190512 -260.812547)
			(xy 340.169376 -260.764344) (xy 340.155061 -260.713694) (xy 340.147839 -260.661559) (xy 340.147402 -260.635242)
			(xy 340.147894 -260.60799) (xy 340.155646 -260.554039) (xy 340.170997 -260.501741) (xy 340.193635 -260.452161)
			(xy 340.2231 -260.406307) (xy 340.258791 -260.365114) (xy 340.299981 -260.329419) (xy 340.345833 -260.299951)
			(xy 340.395411 -260.277308) (xy 340.447708 -260.261953) (xy 340.501658 -260.254197) (xy 340.52891 -260.253734)
			(xy 340.555225 -260.254184) (xy 340.607354 -260.261421) (xy 340.657998 -260.275743) (xy 340.706197 -260.296878)
			(xy 340.75104 -260.324428) (xy 340.791678 -260.35787) (xy 340.809834 -260.376924) (xy 340.817351 -260.384332)
			(xy 340.836634 -260.392855) (xy 340.847172 -260.393434) (xy 340.921848 -260.393434) (xy 340.932395 -260.39288)
			(xy 340.95169 -260.384361) (xy 340.959186 -260.376924) (xy 340.97736 -260.357887) (xy 341.017985 -260.324427)
			(xy 341.062821 -260.296865) (xy 341.111019 -260.275723) (xy 341.161663 -260.261402) (xy 341.213795 -260.254174)
			(xy 341.24011 -260.253734) (xy 341.267365 -260.254146) (xy 341.32132 -260.261905) (xy 341.373621 -260.277265)
			(xy 341.423205 -260.299911) (xy 341.46906 -260.329384) (xy 341.510253 -260.365083) (xy 341.545947 -260.406282)
			(xy 341.575414 -260.452141) (xy 341.598054 -260.501727) (xy 341.613406 -260.554031) (xy 341.621158 -260.607987)
			(xy 341.621618 -260.635242) (xy 341.621173 -260.661557) (xy 341.613933 -260.713686) (xy 341.599609 -260.764329)
			(xy 341.578472 -260.812528) (xy 341.550922 -260.857371) (xy 341.517481 -260.89801) (xy 341.498428 -260.916166)
			(xy 341.491043 -260.923702) (xy 341.482508 -260.942971) (xy 341.481918 -260.953504) (xy 341.481918 -261.02818)
			(xy 341.482439 -261.038731) (xy 341.490979 -261.058026) (xy 341.498428 -261.065518) (xy 341.517491 -261.083666)
			(xy 341.550946 -261.124298) (xy 341.578503 -261.16914) (xy 341.59964 -261.217342) (xy 341.613956 -261.267991)
			(xy 341.62118 -261.320126) (xy 341.621618 -261.346442) (xy 341.621161 -261.373694) (xy 341.613399 -261.427642)
			(xy 341.598039 -261.479937) (xy 341.575394 -261.529513) (xy 341.545924 -261.575363) (xy 341.51023 -261.616553)
			(xy 341.469038 -261.652244) (xy 341.423185 -261.681709) (xy 341.373607 -261.704351) (xy 341.321311 -261.719706)
			(xy 341.267362 -261.727464) (xy 341.24011 -261.72795) (xy 341.213796 -261.727492) (xy 341.161666 -261.720257)
			(xy 341.111022 -261.705938) (xy 341.062823 -261.684803) (xy 341.01798 -261.657255) (xy 340.977342 -261.623813)
			(xy 340.959186 -261.60476) (xy 340.951664 -261.597359) (xy 340.932385 -261.588832) (xy 340.921848 -261.58825)
			(xy 340.847172 -261.58825) (xy 340.836627 -261.588819) (xy 340.817332 -261.597328) (xy 340.809834 -261.60476)
			(xy 340.791715 -261.623852) (xy 340.751076 -261.657304) (xy 340.706228 -261.684856) (xy 340.65802 -261.705988)
			(xy 340.607367 -261.720298) (xy 340.555228 -261.727515) (xy 340.52891 -261.72795) (xy 340.501661 -261.727413)
			(xy 340.447717 -261.719659) (xy 340.395426 -261.704307) (xy 340.345852 -261.68167) (xy 340.300003 -261.652209)
			(xy 340.258814 -261.616523) (xy 340.223123 -261.575338) (xy 340.193655 -261.529494) (xy 340.171011 -261.479923)
			(xy 340.155653 -261.427634) (xy 340.147891 -261.373691) (xy 340.147402 -261.346442) (xy 330.943966 -261.346442)
			(xy 330.943966 -262.504682) (xy 338.447378 -262.504682) (xy 338.451449 -262.44906) (xy 338.463575 -262.394623)
			(xy 338.483498 -262.342532) (xy 338.510794 -262.293897) (xy 338.54488 -262.249754) (xy 338.585029 -262.211045)
			(xy 338.630387 -262.178594) (xy 338.679987 -262.153093) (xy 338.732771 -262.135086) (xy 338.787614 -262.124956)
			(xy 338.843348 -262.122919) (xy 338.898785 -262.129019) (xy 338.952742 -262.143125) (xy 339.004071 -262.164937)
			(xy 339.051677 -262.193991) (xy 339.094545 -262.229666) (xy 339.131762 -262.271203) (xy 339.162535 -262.317716)
			(xy 339.186207 -262.368213) (xy 339.202275 -262.42162) (xy 339.210395 -262.476796) (xy 339.210904 -262.504682)
			(xy 339.210395 -262.532568) (xy 339.202275 -262.587744) (xy 339.186207 -262.641151) (xy 339.162535 -262.691648)
			(xy 339.131762 -262.738161) (xy 339.094545 -262.779698) (xy 339.051677 -262.815373) (xy 339.004071 -262.844427)
			(xy 338.952742 -262.866239) (xy 338.898785 -262.880345) (xy 338.843348 -262.886445) (xy 338.787614 -262.884408)
			(xy 338.732771 -262.874278) (xy 338.679987 -262.856271) (xy 338.630387 -262.83077) (xy 338.585029 -262.798319)
			(xy 338.54488 -262.75961) (xy 338.510794 -262.715467) (xy 338.483498 -262.666832) (xy 338.463575 -262.614741)
			(xy 338.451449 -262.560304) (xy 338.447378 -262.504682) (xy 330.943966 -262.504682) (xy 330.943966 -263.308084)
			(xy 331.439772 -263.308084) (xy 331.443843 -263.252462) (xy 331.455969 -263.198025) (xy 331.475892 -263.145934)
			(xy 331.503188 -263.097299) (xy 331.537274 -263.053156) (xy 331.577423 -263.014447) (xy 331.622781 -262.981996)
			(xy 331.672381 -262.956495) (xy 331.725165 -262.938488) (xy 331.780008 -262.928358) (xy 331.835742 -262.926321)
			(xy 331.891179 -262.932421) (xy 331.945136 -262.946527) (xy 331.996465 -262.968339) (xy 332.044071 -262.997393)
			(xy 332.086939 -263.033068) (xy 332.124156 -263.074605) (xy 332.154929 -263.121118) (xy 332.178601 -263.171615)
			(xy 332.194669 -263.225022) (xy 332.202789 -263.280198) (xy 332.20282 -263.281922) (xy 333.087724 -263.281922)
			(xy 333.091795 -263.2263) (xy 333.103921 -263.171863) (xy 333.123844 -263.119772) (xy 333.15114 -263.071137)
			(xy 333.185226 -263.026994) (xy 333.225375 -262.988285) (xy 333.270733 -262.955834) (xy 333.320333 -262.930333)
			(xy 333.373117 -262.912326) (xy 333.42796 -262.902196) (xy 333.483694 -262.900159) (xy 333.539131 -262.906259)
			(xy 333.593088 -262.920365) (xy 333.644417 -262.942177) (xy 333.692023 -262.971231) (xy 333.734891 -263.006906)
			(xy 333.772108 -263.048443) (xy 333.802881 -263.094956) (xy 333.826553 -263.145453) (xy 333.842621 -263.19886)
			(xy 333.850741 -263.254036) (xy 333.85125 -263.281922) (xy 333.850741 -263.309808) (xy 333.842621 -263.364984)
			(xy 333.826553 -263.418391) (xy 333.802881 -263.468888) (xy 333.772108 -263.515401) (xy 333.734891 -263.556938)
			(xy 333.692023 -263.592613) (xy 333.644417 -263.621667) (xy 333.593088 -263.643479) (xy 333.539131 -263.657585)
			(xy 333.483694 -263.663685) (xy 333.42796 -263.661648) (xy 333.373117 -263.651518) (xy 333.320333 -263.633511)
			(xy 333.270733 -263.60801) (xy 333.225375 -263.575559) (xy 333.185226 -263.53685) (xy 333.15114 -263.492707)
			(xy 333.123844 -263.444072) (xy 333.103921 -263.391981) (xy 333.091795 -263.337544) (xy 333.087724 -263.281922)
			(xy 332.20282 -263.281922) (xy 332.203298 -263.308084) (xy 332.202789 -263.33597) (xy 332.194669 -263.391146)
			(xy 332.178601 -263.444553) (xy 332.154929 -263.49505) (xy 332.124156 -263.541563) (xy 332.086939 -263.5831)
			(xy 332.044071 -263.618775) (xy 331.996465 -263.647829) (xy 331.945136 -263.669641) (xy 331.891179 -263.683747)
			(xy 331.835742 -263.689847) (xy 331.780008 -263.68781) (xy 331.725165 -263.67768) (xy 331.672381 -263.659673)
			(xy 331.622781 -263.634172) (xy 331.577423 -263.601721) (xy 331.537274 -263.563012) (xy 331.503188 -263.518869)
			(xy 331.475892 -263.470234) (xy 331.455969 -263.418143) (xy 331.443843 -263.363706) (xy 331.439772 -263.308084)
			(xy 330.943966 -263.308084) (xy 330.943966 -263.993376) (xy 333.820006 -263.993376) (xy 333.824077 -263.937754)
			(xy 333.836203 -263.883317) (xy 333.856126 -263.831226) (xy 333.883422 -263.782591) (xy 333.917508 -263.738448)
			(xy 333.957657 -263.699739) (xy 334.003015 -263.667288) (xy 334.052615 -263.641787) (xy 334.105399 -263.62378)
			(xy 334.160242 -263.61365) (xy 334.215976 -263.611613) (xy 334.271413 -263.617713) (xy 334.282089 -263.620504)
			(xy 335.037428 -263.620504) (xy 335.041499 -263.564882) (xy 335.053625 -263.510445) (xy 335.073548 -263.458354)
			(xy 335.100844 -263.409719) (xy 335.13493 -263.365576) (xy 335.175079 -263.326867) (xy 335.220437 -263.294416)
			(xy 335.270037 -263.268915) (xy 335.322821 -263.250908) (xy 335.377664 -263.240778) (xy 335.433398 -263.238741)
			(xy 335.488835 -263.244841) (xy 335.542792 -263.258947) (xy 335.594121 -263.280759) (xy 335.641727 -263.309813)
			(xy 335.684595 -263.345488) (xy 335.721812 -263.387025) (xy 335.752585 -263.433538) (xy 335.776257 -263.484035)
			(xy 335.792325 -263.537442) (xy 335.800445 -263.592618) (xy 335.800954 -263.620504) (xy 335.800445 -263.64839)
			(xy 335.792325 -263.703566) (xy 335.776257 -263.756973) (xy 335.752585 -263.80747) (xy 335.721812 -263.853983)
			(xy 335.684595 -263.89552) (xy 335.641727 -263.931195) (xy 335.594121 -263.960249) (xy 335.542792 -263.982061)
			(xy 335.488835 -263.996167) (xy 335.433398 -264.002267) (xy 335.377664 -264.00023) (xy 335.322821 -263.9901)
			(xy 335.270037 -263.972093) (xy 335.220437 -263.946592) (xy 335.175079 -263.914141) (xy 335.13493 -263.875432)
			(xy 335.100844 -263.831289) (xy 335.073548 -263.782654) (xy 335.053625 -263.730563) (xy 335.041499 -263.676126)
			(xy 335.037428 -263.620504) (xy 334.282089 -263.620504) (xy 334.32537 -263.631819) (xy 334.376699 -263.653631)
			(xy 334.424305 -263.682685) (xy 334.467173 -263.71836) (xy 334.50439 -263.759897) (xy 334.535163 -263.80641)
			(xy 334.558835 -263.856907) (xy 334.574903 -263.910314) (xy 334.583023 -263.96549) (xy 334.583532 -263.993376)
			(xy 334.583023 -264.021262) (xy 334.574903 -264.076438) (xy 334.558835 -264.129845) (xy 334.535163 -264.180342)
			(xy 334.50439 -264.226855) (xy 334.467173 -264.268392) (xy 334.424305 -264.304067) (xy 334.411067 -264.312146)
			(xy 335.602324 -264.312146) (xy 335.606395 -264.256524) (xy 335.618521 -264.202087) (xy 335.638444 -264.149996)
			(xy 335.66574 -264.101361) (xy 335.699826 -264.057218) (xy 335.739975 -264.018509) (xy 335.785333 -263.986058)
			(xy 335.834933 -263.960557) (xy 335.887717 -263.94255) (xy 335.94256 -263.93242) (xy 335.998294 -263.930383)
			(xy 336.053731 -263.936483) (xy 336.107688 -263.950589) (xy 336.159017 -263.972401) (xy 336.206623 -264.001455)
			(xy 336.249491 -264.03713) (xy 336.286708 -264.078667) (xy 336.317481 -264.12518) (xy 336.341153 -264.175677)
			(xy 336.357221 -264.229084) (xy 336.365341 -264.28426) (xy 336.36585 -264.312146) (xy 336.365341 -264.340032)
			(xy 336.357221 -264.395208) (xy 336.341153 -264.448615) (xy 336.317481 -264.499112) (xy 336.286708 -264.545625)
			(xy 336.249491 -264.587162) (xy 336.206623 -264.622837) (xy 336.159017 -264.651891) (xy 336.107688 -264.673703)
			(xy 336.053731 -264.687809) (xy 335.998294 -264.693909) (xy 335.94256 -264.691872) (xy 335.887717 -264.681742)
			(xy 335.834933 -264.663735) (xy 335.785333 -264.638234) (xy 335.739975 -264.605783) (xy 335.699826 -264.567074)
			(xy 335.66574 -264.522931) (xy 335.638444 -264.474296) (xy 335.618521 -264.422205) (xy 335.606395 -264.367768)
			(xy 335.602324 -264.312146) (xy 334.411067 -264.312146) (xy 334.376699 -264.333121) (xy 334.32537 -264.354933)
			(xy 334.271413 -264.369039) (xy 334.215976 -264.375139) (xy 334.160242 -264.373102) (xy 334.105399 -264.362972)
			(xy 334.052615 -264.344965) (xy 334.003015 -264.319464) (xy 333.957657 -264.287013) (xy 333.917508 -264.248304)
			(xy 333.883422 -264.204161) (xy 333.856126 -264.155526) (xy 333.836203 -264.103435) (xy 333.824077 -264.048998)
			(xy 333.820006 -263.993376) (xy 330.943966 -263.993376) (xy 330.943966 -264.87755) (xy 333.781906 -264.87755)
			(xy 333.785977 -264.821928) (xy 333.798103 -264.767491) (xy 333.818026 -264.7154) (xy 333.845322 -264.666765)
			(xy 333.879408 -264.622622) (xy 333.919557 -264.583913) (xy 333.964915 -264.551462) (xy 334.014515 -264.525961)
			(xy 334.067299 -264.507954) (xy 334.122142 -264.497824) (xy 334.177876 -264.495787) (xy 334.233313 -264.501887)
			(xy 334.28727 -264.515993) (xy 334.338599 -264.537805) (xy 334.386205 -264.566859) (xy 334.429073 -264.602534)
			(xy 334.46629 -264.644071) (xy 334.497063 -264.690584) (xy 334.520735 -264.741081) (xy 334.536803 -264.794488)
			(xy 334.544923 -264.849664) (xy 334.545432 -264.87755) (xy 334.544923 -264.905436) (xy 334.536803 -264.960612)
			(xy 334.520735 -265.014019) (xy 334.497063 -265.064516) (xy 334.46629 -265.111029) (xy 334.429073 -265.152566)
			(xy 334.386205 -265.188241) (xy 334.338599 -265.217295) (xy 334.28727 -265.239107) (xy 334.233313 -265.253213)
			(xy 334.177876 -265.259313) (xy 334.122142 -265.257276) (xy 334.067299 -265.247146) (xy 334.014515 -265.229139)
			(xy 333.964915 -265.203638) (xy 333.919557 -265.171187) (xy 333.879408 -265.132478) (xy 333.845322 -265.088335)
			(xy 333.818026 -265.0397) (xy 333.798103 -264.987609) (xy 333.785977 -264.933172) (xy 333.781906 -264.87755)
			(xy 330.943966 -264.87755) (xy 330.943966 -269.417038) (xy 334.700626 -269.417038) (xy 334.701132 -269.388299)
			(xy 334.709762 -269.331471) (xy 334.726817 -269.276581) (xy 334.751912 -269.22487) (xy 334.784479 -269.177507)
			(xy 334.80375 -269.15618) (xy 334.810354 -269.149322) (xy 334.817466 -269.131288) (xy 334.817466 -269.042388)
			(xy 334.810354 -269.024354) (xy 334.80375 -269.017496) (xy 334.784499 -268.996152) (xy 334.75193 -268.948795)
			(xy 334.726833 -268.897087) (xy 334.709778 -268.8422) (xy 334.70115 -268.785376) (xy 334.700626 -268.756638)
			(xy 334.701091 -268.729385) (xy 334.708843 -268.675432) (xy 334.724196 -268.623132) (xy 334.746837 -268.57355)
			(xy 334.776304 -268.527695) (xy 334.811998 -268.486501) (xy 334.853192 -268.450807) (xy 334.899046 -268.421339)
			(xy 334.948628 -268.398698) (xy 335.000928 -268.383344) (xy 335.054881 -268.375591) (xy 335.082134 -268.37513)
			(xy 335.109505 -268.375569) (xy 335.163686 -268.383392) (xy 335.21619 -268.398887) (xy 335.265936 -268.421735)
			(xy 335.311901 -268.451466) (xy 335.332832 -268.46911) (xy 335.333086 -268.469364) (xy 335.340167 -268.474958)
			(xy 335.357088 -268.481199) (xy 335.366106 -268.481556) (xy 335.433162 -268.481556) (xy 335.442178 -268.48119)
			(xy 335.459096 -268.47495) (xy 335.466182 -268.469364) (xy 335.466182 -268.46911) (xy 335.466436 -268.46911)
			(xy 335.487369 -268.451469) (xy 335.533337 -268.421745) (xy 335.583083 -268.398899) (xy 335.635585 -268.383403)
			(xy 335.689763 -268.375574) (xy 335.744505 -268.375574) (xy 335.798683 -268.383403) (xy 335.851185 -268.398899)
			(xy 335.900931 -268.421745) (xy 335.946899 -268.451469) (xy 335.967832 -268.46911) (xy 335.968086 -268.469364)
			(xy 335.975167 -268.474958) (xy 335.992088 -268.481199) (xy 336.001106 -268.481556) (xy 336.068162 -268.481556)
			(xy 336.077178 -268.48119) (xy 336.094096 -268.47495) (xy 336.101182 -268.469364) (xy 336.101182 -268.46911)
			(xy 336.101436 -268.46911) (xy 336.122369 -268.451469) (xy 336.168337 -268.421745) (xy 336.218083 -268.398899)
			(xy 336.270585 -268.383403) (xy 336.324763 -268.375574) (xy 336.379505 -268.375574) (xy 336.433683 -268.383403)
			(xy 336.486185 -268.398899) (xy 336.535931 -268.421745) (xy 336.581899 -268.451469) (xy 336.602832 -268.46911)
			(xy 336.603086 -268.469364) (xy 336.610167 -268.474958) (xy 336.627088 -268.481199) (xy 336.636106 -268.481556)
			(xy 336.703162 -268.481556) (xy 336.712178 -268.48119) (xy 336.729096 -268.47495) (xy 336.736182 -268.469364)
			(xy 336.736182 -268.46911) (xy 336.736436 -268.46911) (xy 336.757369 -268.451469) (xy 336.803337 -268.421745)
			(xy 336.853083 -268.398899) (xy 336.905585 -268.383403) (xy 336.959763 -268.375574) (xy 337.014505 -268.375574)
			(xy 337.068683 -268.383403) (xy 337.121185 -268.398899) (xy 337.170931 -268.421745) (xy 337.216899 -268.451469)
			(xy 337.237832 -268.46911) (xy 337.238086 -268.469364) (xy 337.245167 -268.474958) (xy 337.262088 -268.481199)
			(xy 337.271106 -268.481556) (xy 337.338162 -268.481556) (xy 337.347178 -268.48119) (xy 337.364096 -268.47495)
			(xy 337.371182 -268.469364) (xy 337.371182 -268.46911) (xy 337.371436 -268.46911) (xy 337.392383 -268.451489)
			(xy 337.438351 -268.421774) (xy 337.488095 -268.398935) (xy 337.540593 -268.383439) (xy 337.594766 -268.375606)
			(xy 337.622134 -268.37513) (xy 337.649389 -268.375523) (xy 337.703345 -268.383286) (xy 337.755646 -268.398648)
			(xy 337.805229 -268.421297) (xy 337.851084 -268.450773) (xy 337.892277 -268.486474) (xy 337.927971 -268.527674)
			(xy 337.957437 -268.573534) (xy 337.980077 -268.623121) (xy 337.995429 -268.675426) (xy 338.003182 -268.729382)
			(xy 338.003642 -268.756638) (xy 338.00313 -268.785377) (xy 337.994503 -268.842205) (xy 337.977449 -268.897095)
			(xy 337.952356 -268.948807) (xy 337.919789 -268.996169) (xy 337.900518 -269.017496) (xy 337.893914 -269.024354)
			(xy 337.886802 -269.042388) (xy 337.886802 -269.131288) (xy 337.893914 -269.149322) (xy 337.900518 -269.15618)
			(xy 337.919799 -269.177498) (xy 337.952366 -269.224862) (xy 337.977457 -269.276575) (xy 337.994505 -269.331469)
			(xy 338.003124 -269.388298) (xy 338.003642 -269.417038) (xy 338.003158 -269.444289) (xy 337.995397 -269.498235)
			(xy 337.980039 -269.550527) (xy 337.957396 -269.600102) (xy 337.927928 -269.645951) (xy 337.892237 -269.68714)
			(xy 337.851048 -269.722831) (xy 337.805199 -269.752297) (xy 337.755624 -269.77494) (xy 337.703331 -269.790298)
			(xy 337.649385 -269.798058) (xy 337.622134 -269.798546) (xy 337.594764 -269.798073) (xy 337.540585 -269.790259)
			(xy 337.488081 -269.774772) (xy 337.438334 -269.751932) (xy 337.392367 -269.722207) (xy 337.371436 -269.704566)
			(xy 337.371182 -269.704312) (xy 337.364104 -269.698713) (xy 337.347181 -269.692473) (xy 337.338162 -269.69212)
			(xy 337.271106 -269.69212) (xy 337.262089 -269.692475) (xy 337.245172 -269.698724) (xy 337.238086 -269.704312)
			(xy 337.237832 -269.704566) (xy 337.216899 -269.722207) (xy 337.170931 -269.751931) (xy 337.121185 -269.774777)
			(xy 337.068683 -269.790273) (xy 337.014505 -269.798102) (xy 336.959763 -269.798102) (xy 336.905585 -269.790273)
			(xy 336.853083 -269.774777) (xy 336.803337 -269.751931) (xy 336.757369 -269.722207) (xy 336.736436 -269.704566)
			(xy 336.736182 -269.704312) (xy 336.729104 -269.698713) (xy 336.712181 -269.692473) (xy 336.703162 -269.69212)
			(xy 336.636106 -269.69212) (xy 336.627089 -269.692475) (xy 336.610172 -269.698724) (xy 336.603086 -269.704312)
			(xy 336.603086 -269.704566) (xy 336.602832 -269.704566) (xy 336.581899 -269.722207) (xy 336.535931 -269.751931)
			(xy 336.486185 -269.774777) (xy 336.433683 -269.790273) (xy 336.379505 -269.798102) (xy 336.324763 -269.798102)
			(xy 336.270585 -269.790273) (xy 336.218083 -269.774777) (xy 336.168337 -269.751931) (xy 336.122369 -269.722207)
			(xy 336.101436 -269.704566) (xy 336.101182 -269.704312) (xy 336.094104 -269.698713) (xy 336.077181 -269.692473)
			(xy 336.068162 -269.69212) (xy 336.001106 -269.69212) (xy 335.992089 -269.692475) (xy 335.975172 -269.698724)
			(xy 335.968086 -269.704312) (xy 335.968086 -269.704566) (xy 335.967832 -269.704566) (xy 335.946899 -269.722207)
			(xy 335.900931 -269.751931) (xy 335.851185 -269.774777) (xy 335.798683 -269.790273) (xy 335.744505 -269.798102)
			(xy 335.689763 -269.798102) (xy 335.635585 -269.790273) (xy 335.583083 -269.774777) (xy 335.533337 -269.751931)
			(xy 335.487369 -269.722207) (xy 335.466436 -269.704566) (xy 335.466182 -269.704312) (xy 335.459104 -269.698713)
			(xy 335.442181 -269.692473) (xy 335.433162 -269.69212) (xy 335.366106 -269.69212) (xy 335.357089 -269.692475)
			(xy 335.340172 -269.698724) (xy 335.333086 -269.704312) (xy 335.333086 -269.704566) (xy 335.332832 -269.704566)
			(xy 335.311894 -269.722198) (xy 335.265924 -269.751912) (xy 335.216178 -269.77475) (xy 335.163678 -269.790243)
			(xy 335.109503 -269.798072) (xy 335.082134 -269.798546) (xy 335.054885 -269.79799) (xy 335.000942 -269.790239)
			(xy 334.948651 -269.77489) (xy 334.899077 -269.752256) (xy 334.853228 -269.722797) (xy 334.812038 -269.687113)
			(xy 334.776346 -269.64593) (xy 334.746878 -269.600087) (xy 334.724235 -269.550516) (xy 334.708876 -269.498228)
			(xy 334.701115 -269.444287) (xy 334.700626 -269.417038) (xy 330.943966 -269.417038) (xy 330.943966 -277.864824)
			(xy 335.665826 -277.864824) (xy 335.666352 -277.835907) (xy 335.675078 -277.778736) (xy 335.692334 -277.723537)
			(xy 335.717724 -277.671575) (xy 335.750667 -277.624041) (xy 335.790407 -277.582024) (xy 335.812892 -277.563834)
			(xy 335.821673 -277.556201) (xy 335.831871 -277.53532) (xy 335.83245 -277.523702) (xy 335.83245 -277.443946)
			(xy 335.831945 -277.432309) (xy 335.821734 -277.411399) (xy 335.812892 -277.403814) (xy 335.790414 -277.385617)
			(xy 335.750678 -277.343598) (xy 335.717739 -277.296065) (xy 335.69235 -277.244104) (xy 335.675092 -277.188908)
			(xy 335.666362 -277.13174) (xy 335.665826 -277.102824) (xy 335.666409 -277.073417) (xy 335.675439 -277.015299)
			(xy 335.693274 -276.959253) (xy 335.719492 -276.906605) (xy 335.753473 -276.858599) (xy 335.794413 -276.816372)
			(xy 335.841345 -276.780923) (xy 335.866994 -276.766528) (xy 335.878932 -276.760178) (xy 335.893156 -276.737826)
			(xy 335.898998 -276.624288) (xy 335.88706 -276.600412) (xy 335.876138 -276.593046) (xy 335.85438 -276.577735)
			(xy 335.814901 -276.542071) (xy 335.780757 -276.50127) (xy 335.75261 -276.456123) (xy 335.731005 -276.407505)
			(xy 335.716362 -276.356357) (xy 335.708964 -276.303671) (xy 335.708498 -276.27707) (xy 335.708947 -276.249699)
			(xy 335.716769 -276.195519) (xy 335.732262 -276.143016) (xy 335.755108 -276.09327) (xy 335.784835 -276.047303)
			(xy 335.802478 -276.026372) (xy 335.802732 -276.026118) (xy 335.808321 -276.019033) (xy 335.814565 -276.002115)
			(xy 335.814924 -275.993098) (xy 335.814924 -275.926042) (xy 335.814542 -275.917028) (xy 335.808311 -275.900111)
			(xy 335.802732 -275.893022) (xy 335.802478 -275.893022) (xy 335.802478 -275.892768) (xy 335.784854 -275.871824)
			(xy 335.755141 -275.825854) (xy 335.732302 -275.77611) (xy 335.716807 -275.723612) (xy 335.708975 -275.669438)
			(xy 335.708498 -275.64207) (xy 335.708498 -275.641816) (xy 335.709069 -275.612017) (xy 335.718346 -275.553146)
			(xy 335.736663 -275.496434) (xy 335.763574 -275.443258) (xy 335.798424 -275.394912) (xy 335.818988 -275.373338)
			(xy 335.826354 -275.365972) (xy 335.833974 -275.34743) (xy 335.832958 -275.25472) (xy 335.825084 -275.236178)
			(xy 335.817718 -275.229066) (xy 335.799761 -275.211015) (xy 335.768263 -275.171012) (xy 335.742365 -275.127176)
			(xy 335.722525 -275.080286) (xy 335.709097 -275.031173) (xy 335.70232 -274.980711) (xy 335.701894 -274.955254)
			(xy 335.702335 -274.928002) (xy 335.710098 -274.874052) (xy 335.725459 -274.821756) (xy 335.748106 -274.772179)
			(xy 335.777577 -274.726329) (xy 335.813273 -274.685139) (xy 335.854467 -274.649448) (xy 335.900321 -274.619983)
			(xy 335.949901 -274.597342) (xy 336.002199 -274.581988) (xy 336.056149 -274.574232) (xy 336.083402 -274.573746)
			(xy 336.11232 -274.574246) (xy 336.169493 -274.582976) (xy 336.224693 -274.600237) (xy 336.276655 -274.625632)
			(xy 336.324188 -274.658579) (xy 336.366203 -274.698324) (xy 336.384392 -274.720812) (xy 336.39201 -274.729607)
			(xy 336.412903 -274.739797) (xy 336.424524 -274.74037) (xy 336.50428 -274.74037) (xy 336.51591 -274.739816)
			(xy 336.536821 -274.729639) (xy 336.544412 -274.720812) (xy 336.561165 -274.700029) (xy 336.599519 -274.662899)
			(xy 336.642673 -274.631477) (xy 336.689787 -274.606378) (xy 336.739939 -274.588092) (xy 336.79215 -274.576975)
			(xy 336.845402 -274.573245) (xy 336.898654 -274.576975) (xy 336.950865 -274.588092) (xy 337.001017 -274.606378)
			(xy 337.048131 -274.631477) (xy 337.091285 -274.662899) (xy 337.129639 -274.700029) (xy 337.146392 -274.720812)
			(xy 337.15401 -274.729607) (xy 337.174903 -274.739797) (xy 337.186524 -274.74037) (xy 337.26628 -274.74037)
			(xy 337.27791 -274.739816) (xy 337.298821 -274.729639) (xy 337.306412 -274.720812) (xy 337.324599 -274.698325)
			(xy 337.366619 -274.65859) (xy 337.414155 -274.625651) (xy 337.466117 -274.600263) (xy 337.521315 -274.583007)
			(xy 337.578486 -274.57428) (xy 337.607402 -274.573746) (xy 337.634651 -274.574276) (xy 337.688595 -274.582031)
			(xy 337.740886 -274.597384) (xy 337.79046 -274.620022) (xy 337.836308 -274.649485) (xy 337.877497 -274.685171)
			(xy 337.913189 -274.726356) (xy 337.942656 -274.772201) (xy 337.9653 -274.821773) (xy 337.980659 -274.874062)
			(xy 337.988421 -274.928005) (xy 337.98891 -274.955254) (xy 337.98891 -274.955508) (xy 337.988352 -274.985307)
			(xy 337.979071 -275.044178) (xy 337.960751 -275.100891) (xy 337.933837 -275.154067) (xy 337.898985 -275.202413)
			(xy 337.87842 -275.223986) (xy 337.871054 -275.231352) (xy 337.863434 -275.249894) (xy 337.86445 -275.342604)
			(xy 337.872324 -275.361146) (xy 337.87969 -275.368258) (xy 337.89766 -275.386296) (xy 337.929156 -275.426302)
			(xy 337.955053 -275.470141) (xy 337.97489 -275.517034) (xy 337.988315 -275.566148) (xy 337.99509 -275.616612)
			(xy 337.995514 -275.64207) (xy 337.995007 -275.670988) (xy 337.98628 -275.728161) (xy 337.969022 -275.783361)
			(xy 337.943629 -275.835324) (xy 337.910681 -275.882857) (xy 337.870936 -275.924872) (xy 337.848448 -275.94306)
			(xy 337.83966 -275.950685) (xy 337.829468 -275.971573) (xy 337.82889 -275.983192) (xy 337.82889 -276.051264)
			(xy 341.2617 -276.051264) (xy 341.262145 -276.023893) (xy 341.269968 -275.969713) (xy 341.285462 -275.91721)
			(xy 341.308308 -275.867463) (xy 341.338037 -275.821497) (xy 341.35568 -275.800566) (xy 341.355934 -275.800312)
			(xy 341.361525 -275.793229) (xy 341.367768 -275.776309) (xy 341.368126 -275.767292) (xy 341.368126 -275.700236)
			(xy 341.367746 -275.691222) (xy 341.361514 -275.674305) (xy 341.355934 -275.667216) (xy 341.35568 -275.667216)
			(xy 341.35568 -275.666962) (xy 341.338006 -275.646057) (xy 341.308286 -275.600083) (xy 341.285446 -275.550332)
			(xy 341.269954 -275.497826) (xy 341.26213 -275.443645) (xy 341.262134 -275.388901) (xy 341.269966 -275.334721)
			(xy 341.285465 -275.282217) (xy 341.308312 -275.232469) (xy 341.338039 -275.1865) (xy 341.35568 -275.165566)
			(xy 341.355934 -275.165312) (xy 341.361525 -275.158229) (xy 341.367768 -275.141309) (xy 341.368126 -275.132292)
			(xy 341.368126 -275.065236) (xy 341.367746 -275.056222) (xy 341.361514 -275.039305) (xy 341.355934 -275.032216)
			(xy 341.35568 -275.032216) (xy 341.35568 -275.031962) (xy 341.338053 -275.01102) (xy 341.30834 -274.96505)
			(xy 341.285502 -274.915305) (xy 341.270008 -274.862806) (xy 341.262176 -274.808632) (xy 341.2617 -274.781264)
			(xy 341.262144 -274.754011) (xy 341.269906 -274.700062) (xy 341.285266 -274.647766) (xy 341.307912 -274.598188)
			(xy 341.337383 -274.552337) (xy 341.373079 -274.511147) (xy 341.414273 -274.475456) (xy 341.460127 -274.445991)
			(xy 341.509707 -274.423351) (xy 341.562005 -274.407997) (xy 341.615955 -274.400241) (xy 341.643208 -274.399756)
			(xy 341.670579 -274.400204) (xy 341.724759 -274.408024) (xy 341.777263 -274.423516) (xy 341.82701 -274.446363)
			(xy 341.872975 -274.476092) (xy 341.893906 -274.493736) (xy 341.89416 -274.49399) (xy 341.901255 -274.499565)
			(xy 341.918165 -274.505819) (xy 341.92718 -274.506182) (xy 341.994236 -274.506182) (xy 342.003255 -274.505846)
			(xy 342.020172 -274.499584) (xy 342.027256 -274.49399) (xy 342.027256 -274.493736) (xy 342.02751 -274.493736)
			(xy 342.048432 -274.476084) (xy 342.094407 -274.446373) (xy 342.144157 -274.423539) (xy 342.19666 -274.408051)
			(xy 342.250838 -274.400227) (xy 342.278208 -274.399756) (xy 342.305458 -274.40027) (xy 342.359403 -274.408027)
			(xy 342.411695 -274.423381) (xy 342.46127 -274.446021) (xy 342.507118 -274.475484) (xy 342.548307 -274.511173)
			(xy 342.583999 -274.552359) (xy 342.613466 -274.598206) (xy 342.636109 -274.647779) (xy 342.651467 -274.70007)
			(xy 342.659228 -274.754014) (xy 342.659716 -274.781264) (xy 342.659249 -274.808634) (xy 342.651435 -274.862814)
			(xy 342.635947 -274.915318) (xy 342.613105 -274.965065) (xy 342.583379 -275.011031) (xy 342.565736 -275.031962)
			(xy 342.565482 -275.032216) (xy 342.559881 -275.039292) (xy 342.553643 -275.056217) (xy 342.55329 -275.065236)
			(xy 342.55329 -275.132292) (xy 342.553653 -275.141308) (xy 342.559897 -275.158225) (xy 342.565482 -275.165312)
			(xy 342.565736 -275.165312) (xy 342.565736 -275.165566) (xy 342.583343 -275.186527) (xy 342.613072 -275.232489)
			(xy 342.635922 -275.28223) (xy 342.651422 -275.334728) (xy 342.659255 -275.388904) (xy 342.659259 -275.443642)
			(xy 342.651434 -275.497819) (xy 342.635941 -275.550319) (xy 342.613098 -275.600064) (xy 342.583376 -275.64603)
			(xy 342.565736 -275.666962) (xy 342.565482 -275.667216) (xy 342.559881 -275.674292) (xy 342.553643 -275.691217)
			(xy 342.55329 -275.700236) (xy 342.55329 -275.767292) (xy 342.553653 -275.776308) (xy 342.559897 -275.793225)
			(xy 342.565482 -275.800312) (xy 342.565736 -275.800312) (xy 342.565736 -275.800566) (xy 342.583343 -275.821527)
			(xy 342.613072 -275.867489) (xy 342.635922 -275.91723) (xy 342.651422 -275.969728) (xy 342.659255 -276.023904)
			(xy 342.659259 -276.078642) (xy 342.651434 -276.132819) (xy 342.635941 -276.185319) (xy 342.613098 -276.235064)
			(xy 342.583376 -276.28103) (xy 342.565736 -276.301962) (xy 342.565482 -276.302216) (xy 342.559881 -276.309292)
			(xy 342.553643 -276.326217) (xy 342.55329 -276.335236) (xy 342.55329 -276.402292) (xy 342.553653 -276.411308)
			(xy 342.559897 -276.428225) (xy 342.565482 -276.435312) (xy 342.565736 -276.435312) (xy 342.565736 -276.43582)
			(xy 342.581886 -276.454875) (xy 342.609553 -276.496465) (xy 342.631554 -276.54131) (xy 342.639904 -276.564852)
			(xy 342.643714 -276.576282) (xy 342.660224 -276.593046) (xy 342.748108 -276.622764) (xy 342.759411 -276.62603)
			(xy 342.782715 -276.622965) (xy 342.792812 -276.616922) (xy 342.793066 -276.616668) (xy 342.816823 -276.601327)
			(xy 342.867881 -276.577017) (xy 342.921967 -276.560507) (xy 342.977897 -276.552158) (xy 343.006172 -276.551644)
			(xy 343.03342 -276.552204) (xy 343.087363 -276.559956) (xy 343.139653 -276.575305) (xy 343.189227 -276.597939)
			(xy 343.235075 -276.627398) (xy 343.276265 -276.663082) (xy 343.311956 -276.704264) (xy 343.341424 -276.750106)
			(xy 343.364069 -276.799675) (xy 343.379428 -276.851963) (xy 343.38719 -276.905904) (xy 343.38768 -276.933152)
			(xy 343.387254 -276.959467) (xy 343.380011 -277.011598) (xy 343.365685 -277.062242) (xy 343.344544 -277.110441)
			(xy 343.316991 -277.155283) (xy 343.283545 -277.195921) (xy 343.26449 -277.214076) (xy 343.257095 -277.221603)
			(xy 343.248567 -277.240879) (xy 343.24798 -277.251414) (xy 343.24798 -277.32609) (xy 343.248507 -277.33664)
			(xy 343.257044 -277.355935) (xy 343.26449 -277.363428) (xy 343.28355 -277.381579) (xy 343.317007 -277.422209)
			(xy 343.344566 -277.467051) (xy 343.365704 -277.515252) (xy 343.38002 -277.565901) (xy 343.387243 -277.618036)
			(xy 343.38768 -277.644352) (xy 343.3872 -277.671605) (xy 343.379449 -277.725557) (xy 343.364097 -277.777856)
			(xy 343.341458 -277.827438) (xy 343.311993 -277.873293) (xy 343.276301 -277.914486) (xy 343.235109 -277.950181)
			(xy 343.189255 -277.979649) (xy 343.139675 -278.00229) (xy 343.087376 -278.017645) (xy 343.033425 -278.025399)
			(xy 343.006172 -278.02586) (xy 342.979701 -278.025468) (xy 342.927265 -278.01817) (xy 342.876343 -278.00369)
			(xy 342.827912 -277.982306) (xy 342.782904 -277.95443) (xy 342.742184 -277.920597) (xy 342.706535 -277.881457)
			(xy 342.676641 -277.837764) (xy 342.653077 -277.790356) (xy 342.636297 -277.740144) (xy 342.631014 -277.714202)
			(xy 342.628728 -277.701756) (xy 342.613488 -277.682452) (xy 342.513666 -277.638002) (xy 342.488774 -277.63978)
			(xy 342.478106 -277.646384) (xy 342.455508 -277.659731) (xy 342.40744 -277.680798) (xy 342.356939 -277.695082)
			(xy 342.304957 -277.702314) (xy 342.278716 -277.702772) (xy 342.278208 -277.702772) (xy 342.250954 -277.702337)
			(xy 342.197 -277.69458) (xy 342.144699 -277.679223) (xy 342.095117 -277.656579) (xy 342.049262 -277.627109)
			(xy 342.008068 -277.591412) (xy 341.972374 -277.550216) (xy 341.942907 -277.504359) (xy 341.920267 -277.454774)
			(xy 341.904914 -277.402473) (xy 341.897161 -277.348518) (xy 341.8967 -277.321264) (xy 341.897145 -277.293893)
			(xy 341.904968 -277.239713) (xy 341.920462 -277.18721) (xy 341.943308 -277.137463) (xy 341.973037 -277.091497)
			(xy 341.99068 -277.070566) (xy 341.990934 -277.070312) (xy 341.996525 -277.063229) (xy 342.002768 -277.046309)
			(xy 342.003126 -277.037292) (xy 342.003126 -276.970236) (xy 342.002746 -276.961222) (xy 341.996514 -276.944305)
			(xy 341.990934 -276.937216) (xy 341.99068 -276.937216) (xy 341.99068 -276.936962) (xy 341.973053 -276.91602)
			(xy 341.94334 -276.87005) (xy 341.920502 -276.820305) (xy 341.905008 -276.767806) (xy 341.897176 -276.713632)
			(xy 341.8967 -276.686264) (xy 341.89728 -276.656788) (xy 341.906339 -276.598537) (xy 341.924252 -276.542372)
			(xy 341.950593 -276.489632) (xy 341.984733 -276.441573) (xy 342.004904 -276.420072) (xy 342.011444 -276.412742)
			(xy 342.018886 -276.394578) (xy 342.019382 -276.384766) (xy 342.019382 -276.331426) (xy 342.012016 -276.324568)
			(xy 342.004674 -276.318043) (xy 341.986519 -276.310593) (xy 341.97671 -276.31009) (xy 341.944706 -276.31009)
			(xy 341.934893 -276.310591) (xy 341.916729 -276.318026) (xy 341.9094 -276.324568) (xy 341.887903 -276.344744)
			(xy 341.839843 -276.378888) (xy 341.787102 -276.405234) (xy 341.730938 -276.423154) (xy 341.672685 -276.432223)
			(xy 341.643208 -276.432772) (xy 341.615954 -276.432337) (xy 341.562 -276.42458) (xy 341.509699 -276.409223)
			(xy 341.460117 -276.386579) (xy 341.414262 -276.357109) (xy 341.373068 -276.321412) (xy 341.337374 -276.280216)
			(xy 341.307907 -276.234359) (xy 341.285267 -276.184774) (xy 341.269914 -276.132473) (xy 341.262161 -276.078518)
			(xy 341.2617 -276.051264) (xy 337.82889 -276.051264) (xy 337.82889 -276.062948) (xy 337.829419 -276.074581)
			(xy 337.839615 -276.09549) (xy 337.848448 -276.10308) (xy 337.870932 -276.12127) (xy 337.910665 -276.163292)
			(xy 337.943602 -276.210827) (xy 337.96899 -276.262788) (xy 337.986247 -276.317985) (xy 337.994978 -276.375154)
			(xy 337.995514 -276.40407) (xy 337.995017 -276.431322) (xy 337.987264 -276.485271) (xy 337.971912 -276.537568)
			(xy 337.949274 -276.587148) (xy 337.919809 -276.633001) (xy 337.884119 -276.674194) (xy 337.84293 -276.709888)
			(xy 337.797079 -276.739356) (xy 337.747502 -276.762) (xy 337.695206 -276.777356) (xy 337.641258 -276.785114)
			(xy 337.614006 -276.785578) (xy 337.585089 -276.785064) (xy 337.527917 -276.776335) (xy 337.472718 -276.759077)
			(xy 337.420756 -276.733684) (xy 337.373222 -276.70074) (xy 337.331206 -276.660998) (xy 337.313016 -276.638512)
			(xy 337.30539 -276.629724) (xy 337.284504 -276.619529) (xy 337.272884 -276.618954) (xy 337.193128 -276.618954)
			(xy 337.181497 -276.619505) (xy 337.160586 -276.629683) (xy 337.152996 -276.638512) (xy 337.142965 -276.651117)
			(xy 337.121089 -276.674769) (xy 337.109308 -276.685756) (xy 337.100418 -276.693884) (xy 337.091782 -276.715982)
			(xy 337.100418 -276.808692) (xy 337.102114 -276.820317) (xy 337.114422 -276.840299) (xy 337.12404 -276.847046)
			(xy 337.124294 -276.8473) (xy 337.147602 -276.862308) (xy 337.190041 -276.897972) (xy 337.226868 -276.939406)
			(xy 337.257308 -276.985735) (xy 337.28072 -277.035983) (xy 337.296609 -277.089091) (xy 337.304642 -277.143941)
			(xy 337.305142 -277.171658) (xy 337.304656 -277.198909) (xy 337.2969 -277.252857) (xy 337.281545 -277.305152)
			(xy 337.258903 -277.354729) (xy 337.229437 -277.400579) (xy 337.193746 -277.44177) (xy 337.152555 -277.477461)
			(xy 337.106705 -277.506927) (xy 337.057128 -277.529569) (xy 337.004833 -277.544924) (xy 336.950885 -277.55268)
			(xy 336.896383 -277.55268) (xy 336.842435 -277.544924) (xy 336.79014 -277.529569) (xy 336.740563 -277.506927)
			(xy 336.694713 -277.477461) (xy 336.653522 -277.44177) (xy 336.617831 -277.400579) (xy 336.588365 -277.354729)
			(xy 336.565723 -277.305152) (xy 336.550368 -277.252857) (xy 336.542612 -277.198909) (xy 336.542126 -277.171658)
			(xy 336.542599 -277.14524) (xy 336.549883 -277.09291) (xy 336.564319 -277.042086) (xy 336.585632 -276.99374)
			(xy 336.613413 -276.948798) (xy 336.647131 -276.908121) (xy 336.666332 -276.889972) (xy 336.675222 -276.881844)
			(xy 336.683858 -276.859746) (xy 336.675222 -276.767036) (xy 336.673535 -276.755408) (xy 336.661222 -276.735426)
			(xy 336.6516 -276.728682) (xy 336.651346 -276.728428) (xy 336.62973 -276.71459) (xy 336.590072 -276.682011)
			(xy 336.555155 -276.644394) (xy 336.525613 -276.602425) (xy 336.513424 -276.579838) (xy 336.507836 -276.56917)
			(xy 336.488786 -276.5552) (xy 336.396584 -276.539706) (xy 336.38488 -276.538458) (xy 336.362394 -276.545319)
			(xy 336.353404 -276.552914) (xy 336.35315 -276.553168) (xy 336.334296 -276.57061) (xy 336.292756 -276.600817)
			(xy 336.270346 -276.613366) (xy 336.258408 -276.619716) (xy 336.244184 -276.642068) (xy 336.238342 -276.755606)
			(xy 336.25028 -276.779482) (xy 336.261202 -276.786848) (xy 336.282944 -276.802182) (xy 336.322426 -276.83784)
			(xy 336.356574 -276.878636) (xy 336.384724 -276.923779) (xy 336.406331 -276.972394) (xy 336.420976 -277.02354)
			(xy 336.428376 -277.076224) (xy 336.428842 -277.102824) (xy 336.428291 -277.13174) (xy 336.419572 -277.188911)
			(xy 336.402322 -277.24411) (xy 336.376936 -277.296072) (xy 336.343997 -277.343607) (xy 336.30426 -277.385624)
			(xy 336.281776 -277.403814) (xy 336.272968 -277.411421) (xy 336.262786 -277.432322) (xy 336.262218 -277.443946)
			(xy 336.262218 -277.523702) (xy 336.262764 -277.535333) (xy 336.272947 -277.556243) (xy 336.281776 -277.563834)
			(xy 336.304271 -277.582012) (xy 336.344006 -277.624034) (xy 336.376945 -277.671571) (xy 336.402331 -277.723535)
			(xy 336.419585 -277.778735) (xy 336.42831 -277.835907) (xy 336.428842 -277.864824) (xy 336.428356 -277.892075)
			(xy 336.4206 -277.946023) (xy 336.405245 -277.998318) (xy 336.382603 -278.047895) (xy 336.353137 -278.093745)
			(xy 336.317446 -278.134936) (xy 336.276255 -278.170627) (xy 336.230405 -278.200093) (xy 336.180828 -278.222735)
			(xy 336.128533 -278.23809) (xy 336.074585 -278.245846) (xy 336.020083 -278.245846) (xy 335.966135 -278.23809)
			(xy 335.91384 -278.222735) (xy 335.864263 -278.200093) (xy 335.818413 -278.170627) (xy 335.777222 -278.134936)
			(xy 335.741531 -278.093745) (xy 335.712065 -278.047895) (xy 335.689423 -277.998318) (xy 335.674068 -277.946023)
			(xy 335.666312 -277.892075) (xy 335.665826 -277.864824) (xy 330.943966 -277.864824) (xy 330.943966 -282.904438)
			(xy 334.103218 -282.904438) (xy 334.103704 -282.876864) (xy 334.111651 -282.822292) (xy 334.127372 -282.769432)
			(xy 334.150538 -282.719386) (xy 334.180667 -282.673196) (xy 334.217132 -282.631824) (xy 334.237838 -282.613608)
			(xy 334.245916 -282.606056) (xy 334.255267 -282.586042) (xy 334.255872 -282.575) (xy 334.255872 -282.497276)
			(xy 334.255271 -282.486231) (xy 334.24593 -282.466209) (xy 334.237838 -282.458668) (xy 334.217116 -282.440469)
			(xy 334.180645 -282.399098) (xy 334.150513 -282.352906) (xy 334.127349 -282.302856) (xy 334.111635 -282.249991)
			(xy 334.1037 -282.195414) (xy 334.103218 -282.167838) (xy 334.103704 -282.140264) (xy 334.111651 -282.085692)
			(xy 334.127372 -282.032832) (xy 334.150538 -281.982786) (xy 334.180667 -281.936596) (xy 334.217132 -281.895224)
			(xy 334.237838 -281.877008) (xy 334.245916 -281.869456) (xy 334.255267 -281.849442) (xy 334.255872 -281.8384)
			(xy 334.255872 -281.760676) (xy 334.255271 -281.749631) (xy 334.24593 -281.729609) (xy 334.237838 -281.722068)
			(xy 334.217116 -281.703869) (xy 334.180645 -281.662498) (xy 334.150513 -281.616306) (xy 334.127349 -281.566256)
			(xy 334.111635 -281.513391) (xy 334.1037 -281.458814) (xy 334.103218 -281.431238) (xy 334.103691 -281.403985)
			(xy 334.111443 -281.350033) (xy 334.126796 -281.297734) (xy 334.149436 -281.248152) (xy 334.178902 -281.202297)
			(xy 334.214595 -281.161104) (xy 334.255788 -281.125409) (xy 334.301641 -281.095941) (xy 334.351222 -281.0733)
			(xy 334.403521 -281.057946) (xy 334.457473 -281.050192) (xy 334.484726 -281.04973) (xy 334.512583 -281.050207)
			(xy 334.567702 -281.058335) (xy 334.621054 -281.074386) (xy 334.671509 -281.098018) (xy 334.717994 -281.128731)
			(xy 334.759523 -281.165872) (xy 334.795215 -281.208653) (xy 334.824311 -281.256166) (xy 334.846196 -281.307402)
			(xy 334.853788 -281.33421) (xy 334.856074 -281.3431) (xy 334.866742 -281.35834) (xy 334.938624 -281.406092)
			(xy 334.956658 -281.410156) (xy 334.965802 -281.408886) (xy 334.978819 -281.407219) (xy 335.005003 -281.405438)
			(xy 335.018126 -281.40533) (xy 335.031249 -281.405426) (xy 335.057435 -281.407203) (xy 335.07045 -281.408886)
			(xy 335.079594 -281.410156) (xy 335.097628 -281.406092) (xy 335.16951 -281.35834) (xy 335.180178 -281.3431)
			(xy 335.182464 -281.33421) (xy 335.189975 -281.307375) (xy 335.211845 -281.25612) (xy 335.240938 -281.208592)
			(xy 335.276635 -281.165801) (xy 335.318177 -281.128657) (xy 335.36468 -281.097952) (xy 335.415154 -281.074337)
			(xy 335.468527 -281.058315) (xy 335.523663 -281.050228) (xy 335.551526 -281.04973) (xy 335.578781 -281.050131)
			(xy 335.632736 -281.057892) (xy 335.685038 -281.073254) (xy 335.734621 -281.095902) (xy 335.780476 -281.125376)
			(xy 335.821669 -281.161076) (xy 335.857362 -281.202276) (xy 335.886829 -281.248136) (xy 335.909469 -281.297722)
			(xy 335.924821 -281.350026) (xy 335.932574 -281.403983) (xy 335.933034 -281.431238) (xy 335.932564 -281.458537)
			(xy 335.924788 -281.512579) (xy 335.909386 -281.564959) (xy 335.886672 -281.614609) (xy 335.857111 -281.660512)
			(xy 335.839562 -281.681428) (xy 335.833212 -281.688794) (xy 335.826862 -281.706574) (xy 335.830164 -281.795728)
			(xy 335.838038 -281.813508) (xy 335.844896 -281.820112) (xy 335.866027 -281.841742) (xy 335.901827 -281.89047)
			(xy 335.929491 -281.944237) (xy 335.935762 -281.963368) (xy 340.481918 -281.963368) (xy 340.485989 -281.907746)
			(xy 340.498115 -281.853309) (xy 340.518038 -281.801218) (xy 340.545334 -281.752583) (xy 340.57942 -281.70844)
			(xy 340.619569 -281.669731) (xy 340.664927 -281.63728) (xy 340.714527 -281.611779) (xy 340.767311 -281.593772)
			(xy 340.822154 -281.583642) (xy 340.877888 -281.581605) (xy 340.933325 -281.587705) (xy 340.987282 -281.601811)
			(xy 341.038611 -281.623623) (xy 341.086217 -281.652677) (xy 341.129085 -281.688352) (xy 341.166302 -281.729889)
			(xy 341.197075 -281.776402) (xy 341.220747 -281.826899) (xy 341.236815 -281.880306) (xy 341.244935 -281.935482)
			(xy 341.245444 -281.963368) (xy 341.244935 -281.991254) (xy 341.236815 -282.04643) (xy 341.220747 -282.099837)
			(xy 341.197075 -282.150334) (xy 341.166302 -282.196847) (xy 341.129085 -282.238384) (xy 341.086217 -282.274059)
			(xy 341.038611 -282.303113) (xy 340.987282 -282.324925) (xy 340.933325 -282.339031) (xy 340.877888 -282.345131)
			(xy 340.822154 -282.343094) (xy 340.767311 -282.332964) (xy 340.714527 -282.314957) (xy 340.664927 -282.289456)
			(xy 340.619569 -282.257005) (xy 340.57942 -282.218296) (xy 340.545334 -282.174153) (xy 340.518038 -282.125518)
			(xy 340.498115 -282.073427) (xy 340.485989 -282.01899) (xy 340.481918 -281.963368) (xy 335.935762 -281.963368)
			(xy 335.948326 -282.001695) (xy 335.957859 -282.061405) (xy 335.958434 -282.091638) (xy 335.957939 -282.119276)
			(xy 335.949947 -282.173971) (xy 335.934149 -282.226942) (xy 335.910877 -282.277081) (xy 335.880617 -282.323339)
			(xy 335.862676 -282.344368) (xy 335.854294 -282.353766) (xy 335.848452 -282.37815) (xy 335.872582 -282.47213)
			(xy 335.876286 -282.484074) (xy 335.893061 -282.502583) (xy 335.904586 -282.507436) (xy 335.931994 -282.517774)
			(xy 335.983509 -282.545656) (xy 336.030154 -282.581087) (xy 336.070833 -282.623236) (xy 336.104587 -282.671109)
			(xy 336.130623 -282.72358) (xy 336.148329 -282.779417) (xy 336.157288 -282.837304) (xy 336.157824 -282.866592)
			(xy 336.15729 -282.893854) (xy 336.487447 -282.893854) (xy 336.487447 -282.839346) (xy 336.495205 -282.785392)
			(xy 336.510562 -282.733092) (xy 336.533206 -282.68351) (xy 336.562676 -282.637655) (xy 336.598372 -282.596461)
			(xy 336.639568 -282.560767) (xy 336.685424 -282.531299) (xy 336.735007 -282.508657) (xy 336.787308 -282.493302)
			(xy 336.841262 -282.485546) (xy 336.868516 -282.485084) (xy 336.895888 -282.48552) (xy 336.950069 -282.493342)
			(xy 337.002573 -282.508837) (xy 337.052319 -282.531686) (xy 337.098284 -282.561419) (xy 337.119214 -282.579064)
			(xy 337.119468 -282.579318) (xy 337.126558 -282.584899) (xy 337.143472 -282.591149) (xy 337.152488 -282.59151)
			(xy 337.219544 -282.59151) (xy 337.228558 -282.591124) (xy 337.245475 -282.584896) (xy 337.252564 -282.579318)
			(xy 337.252564 -282.579064) (xy 337.252818 -282.579064) (xy 337.273766 -282.561444) (xy 337.319735 -282.531731)
			(xy 337.369478 -282.508892) (xy 337.421975 -282.493396) (xy 337.476148 -282.485562) (xy 337.503516 -282.485084)
			(xy 337.530766 -282.485587) (xy 337.584711 -282.493345) (xy 337.637003 -282.508701) (xy 337.686577 -282.531343)
			(xy 337.732424 -282.560809) (xy 337.773612 -282.5965) (xy 337.809301 -282.637689) (xy 337.838765 -282.683537)
			(xy 337.861404 -282.733112) (xy 337.876758 -282.785405) (xy 337.884514 -282.83935) (xy 337.884514 -282.89385)
			(xy 337.882992 -282.904438) (xy 342.26373 -282.904438) (xy 342.264211 -282.876864) (xy 342.272159 -282.822291)
			(xy 342.28788 -282.769431) (xy 342.311047 -282.719385) (xy 342.341178 -282.673195) (xy 342.377644 -282.631824)
			(xy 342.39835 -282.613608) (xy 342.40643 -282.606057) (xy 342.415779 -282.586042) (xy 342.416384 -282.575)
			(xy 342.416384 -282.497276) (xy 342.415779 -282.486231) (xy 342.40644 -282.466209) (xy 342.39835 -282.458668)
			(xy 342.37761 -282.440488) (xy 342.341144 -282.399112) (xy 342.311017 -282.352915) (xy 342.287857 -282.302861)
			(xy 342.272146 -282.249993) (xy 342.264212 -282.195414) (xy 342.26373 -282.167838) (xy 342.264211 -282.140264)
			(xy 342.272159 -282.085691) (xy 342.28788 -282.032831) (xy 342.311047 -281.982785) (xy 342.341178 -281.936595)
			(xy 342.377644 -281.895224) (xy 342.39835 -281.877008) (xy 342.40643 -281.869457) (xy 342.415779 -281.849442)
			(xy 342.416384 -281.8384) (xy 342.416384 -281.760676) (xy 342.415779 -281.749631) (xy 342.40644 -281.729609)
			(xy 342.39835 -281.722068) (xy 342.37761 -281.703888) (xy 342.341144 -281.662512) (xy 342.311017 -281.616315)
			(xy 342.287857 -281.566261) (xy 342.272146 -281.513393) (xy 342.264212 -281.458814) (xy 342.26373 -281.431238)
			(xy 342.264191 -281.403984) (xy 342.271944 -281.350031) (xy 342.287297 -281.297731) (xy 342.309938 -281.248149)
			(xy 342.339405 -281.202293) (xy 342.375099 -281.161099) (xy 342.416293 -281.125405) (xy 342.462149 -281.095938)
			(xy 342.511731 -281.073297) (xy 342.564031 -281.057944) (xy 342.617984 -281.050191) (xy 342.645238 -281.04973)
			(xy 342.673095 -281.050197) (xy 342.728214 -281.058326) (xy 342.781567 -281.074378) (xy 342.832022 -281.098012)
			(xy 342.878507 -281.128726) (xy 342.920036 -281.165868) (xy 342.955727 -281.20865) (xy 342.984824 -281.256165)
			(xy 343.006708 -281.307402) (xy 343.0143 -281.33421) (xy 343.016586 -281.3431) (xy 343.027254 -281.35834)
			(xy 343.099136 -281.406092) (xy 343.11717 -281.410156) (xy 343.126314 -281.408886) (xy 343.139331 -281.407217)
			(xy 343.165515 -281.405437) (xy 343.178638 -281.40533) (xy 343.191761 -281.405424) (xy 343.217947 -281.407203)
			(xy 343.230962 -281.408886) (xy 343.240106 -281.410156) (xy 343.25814 -281.406092) (xy 343.330022 -281.35834)
			(xy 343.34069 -281.3431) (xy 343.342976 -281.33421) (xy 343.350566 -281.3074) (xy 343.37243 -281.25615)
			(xy 343.401514 -281.208625) (xy 343.437202 -281.165835) (xy 343.478733 -281.128691) (xy 343.525225 -281.097982)
			(xy 343.575689 -281.074362) (xy 343.629052 -281.058332) (xy 343.684179 -281.050234) (xy 343.712038 -281.04973)
			(xy 343.739292 -281.050143) (xy 343.793244 -281.057905) (xy 343.845543 -281.073267) (xy 343.895123 -281.095915)
			(xy 343.940975 -281.125389) (xy 343.982165 -281.161088) (xy 344.017856 -281.202286) (xy 344.047321 -281.248144)
			(xy 344.069959 -281.297729) (xy 344.085311 -281.35003) (xy 344.093063 -281.403984) (xy 344.093546 -281.431238)
			(xy 344.093073 -281.458537) (xy 344.085297 -281.512578) (xy 344.069896 -281.564959) (xy 344.047183 -281.614608)
			(xy 344.017623 -281.660512) (xy 344.000074 -281.681428) (xy 343.993724 -281.688794) (xy 343.987374 -281.706574)
			(xy 343.990676 -281.795728) (xy 343.99855 -281.813508) (xy 344.005408 -281.820112) (xy 344.026523 -281.841756)
			(xy 344.062329 -281.890479) (xy 344.089998 -281.944242) (xy 344.096269 -281.963368) (xy 348.64243 -281.963368)
			(xy 348.646501 -281.907746) (xy 348.658627 -281.853309) (xy 348.67855 -281.801218) (xy 348.705846 -281.752583)
			(xy 348.739932 -281.70844) (xy 348.780081 -281.669731) (xy 348.825439 -281.63728) (xy 348.875039 -281.611779)
			(xy 348.927823 -281.593772) (xy 348.982666 -281.583642) (xy 349.0384 -281.581605) (xy 349.093837 -281.587705)
			(xy 349.147794 -281.601811) (xy 349.199123 -281.623623) (xy 349.246729 -281.652677) (xy 349.289597 -281.688352)
			(xy 349.326814 -281.729889) (xy 349.357587 -281.776402) (xy 349.381259 -281.826899) (xy 349.397327 -281.880306)
			(xy 349.405447 -281.935482) (xy 349.405956 -281.963368) (xy 349.405447 -281.991254) (xy 349.397327 -282.04643)
			(xy 349.381259 -282.099837) (xy 349.357587 -282.150334) (xy 349.326814 -282.196847) (xy 349.289597 -282.238384)
			(xy 349.246729 -282.274059) (xy 349.199123 -282.303113) (xy 349.147794 -282.324925) (xy 349.093837 -282.339031)
			(xy 349.0384 -282.345131) (xy 348.982666 -282.343094) (xy 348.927823 -282.332964) (xy 348.875039 -282.314957)
			(xy 348.825439 -282.289456) (xy 348.780081 -282.257005) (xy 348.739932 -282.218296) (xy 348.705846 -282.174153)
			(xy 348.67855 -282.125518) (xy 348.658627 -282.073427) (xy 348.646501 -282.01899) (xy 348.64243 -281.963368)
			(xy 344.096269 -281.963368) (xy 344.108836 -282.001697) (xy 344.118371 -282.061406) (xy 344.118946 -282.091638)
			(xy 344.118448 -282.119276) (xy 344.110456 -282.173971) (xy 344.094659 -282.226942) (xy 344.071388 -282.27708)
			(xy 344.041128 -282.323338) (xy 344.023188 -282.344368) (xy 344.014806 -282.353766) (xy 344.008964 -282.37815)
			(xy 344.033094 -282.47213) (xy 344.036792 -282.484077) (xy 344.053571 -282.502585) (xy 344.065098 -282.507436)
			(xy 344.092509 -282.517767) (xy 344.144023 -282.545651) (xy 344.190668 -282.581084) (xy 344.231346 -282.623233)
			(xy 344.2651 -282.671107) (xy 344.291136 -282.723579) (xy 344.308841 -282.779416) (xy 344.3178 -282.837304)
			(xy 344.318336 -282.866592) (xy 344.317801 -282.893855) (xy 344.647947 -282.893855) (xy 344.647947 -282.839345)
			(xy 344.655705 -282.785391) (xy 344.671063 -282.73309) (xy 344.693708 -282.683507) (xy 344.723179 -282.637651)
			(xy 344.758877 -282.596457) (xy 344.800074 -282.560763) (xy 344.845931 -282.531295) (xy 344.895516 -282.508653)
			(xy 344.947818 -282.493299) (xy 345.001773 -282.485545) (xy 345.029028 -282.485084) (xy 345.0564 -282.485513)
			(xy 345.110581 -282.493337) (xy 345.163086 -282.508833) (xy 345.212832 -282.531684) (xy 345.258796 -282.561418)
			(xy 345.279726 -282.579064) (xy 345.27998 -282.579318) (xy 345.287067 -282.584904) (xy 345.303983 -282.591151)
			(xy 345.313 -282.59151) (xy 345.380056 -282.59151) (xy 345.389071 -282.59113) (xy 345.405988 -282.584898)
			(xy 345.413076 -282.579318) (xy 345.413076 -282.579064) (xy 345.41333 -282.579064) (xy 345.434273 -282.561439)
			(xy 345.480243 -282.531726) (xy 345.529988 -282.508888) (xy 345.582486 -282.493394) (xy 345.63666 -282.485561)
			(xy 345.664028 -282.485084) (xy 345.691277 -282.485588) (xy 345.745221 -282.493347) (xy 345.797511 -282.508704)
			(xy 345.847084 -282.531347) (xy 345.89293 -282.560813) (xy 345.934116 -282.596504) (xy 345.969804 -282.637693)
			(xy 345.999267 -282.683541) (xy 346.021905 -282.733115) (xy 346.037259 -282.785406) (xy 346.045014 -282.839351)
			(xy 346.045014 -282.893849) (xy 346.043492 -282.904438) (xy 350.762316 -282.904438) (xy 350.762802 -282.876864)
			(xy 350.77075 -282.822292) (xy 350.78647 -282.769432) (xy 350.809637 -282.719386) (xy 350.839766 -282.673196)
			(xy 350.87623 -282.631824) (xy 350.896936 -282.613608) (xy 350.905014 -282.606055) (xy 350.914365 -282.586042)
			(xy 350.91497 -282.575) (xy 350.91497 -282.497276) (xy 350.914369 -282.48623) (xy 350.905028 -282.466208)
			(xy 350.896936 -282.458668) (xy 350.876213 -282.440469) (xy 350.839742 -282.399099) (xy 350.809611 -282.352907)
			(xy 350.786447 -282.302856) (xy 350.770733 -282.249991) (xy 350.762798 -282.195414) (xy 350.762316 -282.167838)
			(xy 350.762802 -282.140264) (xy 350.77075 -282.085692) (xy 350.78647 -282.032832) (xy 350.809637 -281.982786)
			(xy 350.839766 -281.936596) (xy 350.87623 -281.895224) (xy 350.896936 -281.877008) (xy 350.905014 -281.869455)
			(xy 350.914365 -281.849442) (xy 350.91497 -281.8384) (xy 350.91497 -281.760676) (xy 350.914369 -281.74963)
			(xy 350.905028 -281.729608) (xy 350.896936 -281.722068) (xy 350.876213 -281.703869) (xy 350.839742 -281.662499)
			(xy 350.809611 -281.616307) (xy 350.786447 -281.566256) (xy 350.770733 -281.513391) (xy 350.762798 -281.458814)
			(xy 350.762316 -281.431238) (xy 350.762791 -281.403985) (xy 350.770543 -281.350033) (xy 350.785896 -281.297734)
			(xy 350.808535 -281.248153) (xy 350.838002 -281.202298) (xy 350.873694 -281.161104) (xy 350.914887 -281.12541)
			(xy 350.96074 -281.095942) (xy 351.010321 -281.0733) (xy 351.06262 -281.057946) (xy 351.116571 -281.050192)
			(xy 351.143824 -281.04973) (xy 351.171681 -281.050209) (xy 351.226799 -281.058337) (xy 351.280152 -281.074387)
			(xy 351.330606 -281.098019) (xy 351.377091 -281.128732) (xy 351.418621 -281.165872) (xy 351.454312 -281.208653)
			(xy 351.483409 -281.256166) (xy 351.505294 -281.307402) (xy 351.512886 -281.33421) (xy 351.515172 -281.3431)
			(xy 351.52584 -281.35834) (xy 351.597722 -281.406092) (xy 351.615756 -281.410156) (xy 351.6249 -281.408886)
			(xy 351.637917 -281.407219) (xy 351.664101 -281.405438) (xy 351.677224 -281.40533) (xy 351.690347 -281.405426)
			(xy 351.716533 -281.407203) (xy 351.729548 -281.408886) (xy 351.738692 -281.410156) (xy 351.756726 -281.406092)
			(xy 351.828608 -281.35834) (xy 351.839276 -281.3431) (xy 351.841562 -281.33421) (xy 351.849075 -281.307376)
			(xy 351.870945 -281.256121) (xy 351.900038 -281.208593) (xy 351.935734 -281.165802) (xy 351.977276 -281.128658)
			(xy 352.023779 -281.097952) (xy 352.074253 -281.074337) (xy 352.127626 -281.058316) (xy 352.182761 -281.050228)
			(xy 352.210624 -281.04973) (xy 352.237879 -281.050133) (xy 352.291834 -281.057894) (xy 352.344136 -281.073255)
			(xy 352.393718 -281.095903) (xy 352.439573 -281.125377) (xy 352.480767 -281.161077) (xy 352.51646 -281.202276)
			(xy 352.545927 -281.248136) (xy 352.568567 -281.297722) (xy 352.583919 -281.350026) (xy 352.591672 -281.403983)
			(xy 352.592132 -281.431238) (xy 352.591663 -281.458537) (xy 352.583886 -281.512579) (xy 352.568484 -281.564959)
			(xy 352.54577 -281.614609) (xy 352.51621 -281.660512) (xy 352.49866 -281.681428) (xy 352.49231 -281.688794)
			(xy 352.48596 -281.706574) (xy 352.489262 -281.795728) (xy 352.497136 -281.813508) (xy 352.503994 -281.820112)
			(xy 352.525124 -281.841742) (xy 352.560925 -281.890471) (xy 352.588589 -281.944237) (xy 352.59486 -281.963368)
			(xy 357.141016 -281.963368) (xy 357.145087 -281.907746) (xy 357.157213 -281.853309) (xy 357.177136 -281.801218)
			(xy 357.204432 -281.752583) (xy 357.238518 -281.70844) (xy 357.278667 -281.669731) (xy 357.324025 -281.63728)
			(xy 357.373625 -281.611779) (xy 357.426409 -281.593772) (xy 357.481252 -281.583642) (xy 357.536986 -281.581605)
			(xy 357.592423 -281.587705) (xy 357.64638 -281.601811) (xy 357.697709 -281.623623) (xy 357.745315 -281.652677)
			(xy 357.788183 -281.688352) (xy 357.8254 -281.729889) (xy 357.856173 -281.776402) (xy 357.879845 -281.826899)
			(xy 357.895913 -281.880306) (xy 357.904033 -281.935482) (xy 357.904542 -281.963368) (xy 357.904033 -281.991254)
			(xy 357.895913 -282.04643) (xy 357.879845 -282.099837) (xy 357.856173 -282.150334) (xy 357.8254 -282.196847)
			(xy 357.788183 -282.238384) (xy 357.745315 -282.274059) (xy 357.697709 -282.303113) (xy 357.64638 -282.324925)
			(xy 357.592423 -282.339031) (xy 357.536986 -282.345131) (xy 357.481252 -282.343094) (xy 357.426409 -282.332964)
			(xy 357.373625 -282.314957) (xy 357.324025 -282.289456) (xy 357.278667 -282.257005) (xy 357.238518 -282.218296)
			(xy 357.204432 -282.174153) (xy 357.177136 -282.125518) (xy 357.157213 -282.073427) (xy 357.145087 -282.01899)
			(xy 357.141016 -281.963368) (xy 352.59486 -281.963368) (xy 352.607424 -282.001695) (xy 352.616957 -282.061405)
			(xy 352.617532 -282.091638) (xy 352.617037 -282.119276) (xy 352.609045 -282.173971) (xy 352.593248 -282.226942)
			(xy 352.569975 -282.277081) (xy 352.539715 -282.323339) (xy 352.521774 -282.344368) (xy 352.513392 -282.353766)
			(xy 352.50755 -282.37815) (xy 352.53168 -282.47213) (xy 352.535385 -282.484074) (xy 352.552159 -282.502583)
			(xy 352.563684 -282.507436) (xy 352.591092 -282.517775) (xy 352.642607 -282.545657) (xy 352.689252 -282.581088)
			(xy 352.72993 -282.623236) (xy 352.763685 -282.671109) (xy 352.789721 -282.723581) (xy 352.807427 -282.779417)
			(xy 352.816386 -282.837304) (xy 352.816922 -282.866592) (xy 352.816388 -282.893854) (xy 353.146547 -282.893854)
			(xy 353.146547 -282.839346) (xy 353.154305 -282.785393) (xy 353.169662 -282.733093) (xy 353.192306 -282.683511)
			(xy 353.221776 -282.637656) (xy 353.257472 -282.596462) (xy 353.298667 -282.560767) (xy 353.344523 -282.531299)
			(xy 353.394106 -282.508657) (xy 353.446406 -282.493302) (xy 353.50036 -282.485546) (xy 353.527614 -282.485084)
			(xy 353.554986 -282.485521) (xy 353.609167 -282.493343) (xy 353.661671 -282.508838) (xy 353.711417 -282.531686)
			(xy 353.757382 -282.561419) (xy 353.778312 -282.579064) (xy 353.778566 -282.579318) (xy 353.785657 -282.584898)
			(xy 353.80257 -282.591148) (xy 353.811586 -282.59151) (xy 353.878642 -282.59151) (xy 353.887656 -282.591123)
			(xy 353.904573 -282.584896) (xy 353.911662 -282.579318) (xy 353.911662 -282.579064) (xy 353.911916 -282.579064)
			(xy 353.932864 -282.561445) (xy 353.978833 -282.531732) (xy 354.028577 -282.508892) (xy 354.081074 -282.493396)
			(xy 354.135246 -282.485562) (xy 354.162614 -282.485084) (xy 354.189864 -282.485587) (xy 354.243809 -282.493345)
			(xy 354.296101 -282.508701) (xy 354.345676 -282.531342) (xy 354.391523 -282.560808) (xy 354.432711 -282.596499)
			(xy 354.4684 -282.637688) (xy 354.497865 -282.683537) (xy 354.520504 -282.733112) (xy 354.535858 -282.785405)
			(xy 354.543614 -282.83935) (xy 354.543614 -282.89385) (xy 354.542092 -282.904438) (xy 358.922828 -282.904438)
			(xy 358.92331 -282.876864) (xy 358.931258 -282.822291) (xy 358.946979 -282.769431) (xy 358.970146 -282.719385)
			(xy 359.000276 -282.673195) (xy 359.036742 -282.631824) (xy 359.057448 -282.613608) (xy 359.065528 -282.606057)
			(xy 359.074877 -282.586042) (xy 359.075482 -282.575) (xy 359.075482 -282.497276) (xy 359.074877 -282.486231)
			(xy 359.065539 -282.466209) (xy 359.057448 -282.458668) (xy 359.036728 -282.440466) (xy 359.000256 -282.399097)
			(xy 358.970124 -282.352905) (xy 358.946959 -282.302855) (xy 358.931246 -282.24999) (xy 358.92331 -282.195413)
			(xy 358.922828 -282.167838) (xy 358.92331 -282.140264) (xy 358.931258 -282.085691) (xy 358.946979 -282.032831)
			(xy 358.970146 -281.982785) (xy 359.000276 -281.936595) (xy 359.036742 -281.895224) (xy 359.057448 -281.877008)
			(xy 359.065528 -281.869457) (xy 359.074877 -281.849442) (xy 359.075482 -281.8384) (xy 359.075482 -281.760676)
			(xy 359.074877 -281.749631) (xy 359.065539 -281.729609) (xy 359.057448 -281.722068) (xy 359.036728 -281.703866)
			(xy 359.000256 -281.662497) (xy 358.970124 -281.616305) (xy 358.946959 -281.566255) (xy 358.931246 -281.51339)
			(xy 358.92331 -281.458813) (xy 358.922828 -281.431238) (xy 358.923291 -281.403984) (xy 358.931043 -281.350032)
			(xy 358.946397 -281.297732) (xy 358.969037 -281.248149) (xy 358.998505 -281.202294) (xy 359.034199 -281.1611)
			(xy 359.075393 -281.125406) (xy 359.121247 -281.095938) (xy 359.17083 -281.073297) (xy 359.22313 -281.057944)
			(xy 359.277082 -281.050191) (xy 359.304336 -281.04973) (xy 359.332193 -281.050198) (xy 359.387312 -281.058328)
			(xy 359.440665 -281.07438) (xy 359.491119 -281.098013) (xy 359.537604 -281.128727) (xy 359.579133 -281.165869)
			(xy 359.614825 -281.208651) (xy 359.643922 -281.256165) (xy 359.665806 -281.307402) (xy 359.673398 -281.33421)
			(xy 359.675684 -281.3431) (xy 359.686352 -281.35834) (xy 359.758234 -281.406092) (xy 359.776268 -281.410156)
			(xy 359.785412 -281.408886) (xy 359.798429 -281.407218) (xy 359.824613 -281.405437) (xy 359.837736 -281.40533)
			(xy 359.850859 -281.405425) (xy 359.877045 -281.407203) (xy 359.89006 -281.408886) (xy 359.899204 -281.410156)
			(xy 359.917238 -281.406092) (xy 359.98912 -281.35834) (xy 359.999788 -281.3431) (xy 360.002074 -281.33421)
			(xy 360.009666 -281.3074) (xy 360.031529 -281.256151) (xy 360.060614 -281.208626) (xy 360.096301 -281.165836)
			(xy 360.137832 -281.128692) (xy 360.184324 -281.097983) (xy 360.234788 -281.074362) (xy 360.28815 -281.058332)
			(xy 360.343277 -281.050234) (xy 360.371136 -281.04973) (xy 360.398392 -281.050122) (xy 360.452347 -281.057884)
			(xy 360.504649 -281.073247) (xy 360.554231 -281.095896) (xy 360.600086 -281.125372) (xy 360.64128 -281.161073)
			(xy 360.676973 -281.202273) (xy 360.706439 -281.248134) (xy 360.729079 -281.297721) (xy 360.744431 -281.350025)
			(xy 360.752184 -281.403982) (xy 360.752644 -281.431238) (xy 360.752172 -281.458537) (xy 360.744396 -281.512578)
			(xy 360.728994 -281.564959) (xy 360.706281 -281.614608) (xy 360.676721 -281.660512) (xy 360.659172 -281.681428)
			(xy 360.652822 -281.688794) (xy 360.646472 -281.706574) (xy 360.649774 -281.795728) (xy 360.657648 -281.813508)
			(xy 360.664506 -281.820112) (xy 360.685621 -281.841757) (xy 360.721427 -281.89048) (xy 360.749095 -281.944242)
			(xy 360.755366 -281.963368) (xy 365.301528 -281.963368) (xy 365.305599 -281.907746) (xy 365.317725 -281.853309)
			(xy 365.337648 -281.801218) (xy 365.364944 -281.752583) (xy 365.39903 -281.70844) (xy 365.439179 -281.669731)
			(xy 365.484537 -281.63728) (xy 365.534137 -281.611779) (xy 365.586921 -281.593772) (xy 365.641764 -281.583642)
			(xy 365.697498 -281.581605) (xy 365.752935 -281.587705) (xy 365.806892 -281.601811) (xy 365.858221 -281.623623)
			(xy 365.905827 -281.652677) (xy 365.948695 -281.688352) (xy 365.985912 -281.729889) (xy 366.016685 -281.776402)
			(xy 366.040357 -281.826899) (xy 366.056425 -281.880306) (xy 366.064545 -281.935482) (xy 366.065054 -281.963368)
			(xy 366.064545 -281.991254) (xy 366.056425 -282.04643) (xy 366.040357 -282.099837) (xy 366.016685 -282.150334)
			(xy 365.985912 -282.196847) (xy 365.948695 -282.238384) (xy 365.905827 -282.274059) (xy 365.858221 -282.303113)
			(xy 365.806892 -282.324925) (xy 365.752935 -282.339031) (xy 365.697498 -282.345131) (xy 365.641764 -282.343094)
			(xy 365.586921 -282.332964) (xy 365.534137 -282.314957) (xy 365.484537 -282.289456) (xy 365.439179 -282.257005)
			(xy 365.39903 -282.218296) (xy 365.364944 -282.174153) (xy 365.337648 -282.125518) (xy 365.317725 -282.073427)
			(xy 365.305599 -282.01899) (xy 365.301528 -281.963368) (xy 360.755366 -281.963368) (xy 360.767934 -282.001698)
			(xy 360.777469 -282.061406) (xy 360.778044 -282.091638) (xy 360.777546 -282.119276) (xy 360.769554 -282.173971)
			(xy 360.753757 -282.226942) (xy 360.730486 -282.27708) (xy 360.700226 -282.323338) (xy 360.682286 -282.344368)
			(xy 360.673904 -282.353766) (xy 360.668062 -282.37815) (xy 360.692192 -282.47213) (xy 360.695891 -282.484077)
			(xy 360.712669 -282.502585) (xy 360.724196 -282.507436) (xy 360.751606 -282.517769) (xy 360.803121 -282.545652)
			(xy 360.849766 -282.581084) (xy 360.890444 -282.623233) (xy 360.924198 -282.671107) (xy 360.950234 -282.723579)
			(xy 360.967939 -282.779416) (xy 360.976898 -282.837304) (xy 360.977434 -282.866592) (xy 360.976899 -282.893855)
			(xy 361.307047 -282.893855) (xy 361.307047 -282.839345) (xy 361.314805 -282.785391) (xy 361.330163 -282.73309)
			(xy 361.352808 -282.683507) (xy 361.382279 -282.637652) (xy 361.417976 -282.596458) (xy 361.459173 -282.560763)
			(xy 361.50503 -282.531295) (xy 361.554614 -282.508654) (xy 361.606917 -282.4933) (xy 361.660871 -282.485546)
			(xy 361.688126 -282.485084) (xy 361.715498 -282.485514) (xy 361.769679 -282.493338) (xy 361.822183 -282.508834)
			(xy 361.87193 -282.531684) (xy 361.917894 -282.561418) (xy 361.938824 -282.579064) (xy 361.939078 -282.579318)
			(xy 361.946165 -282.584904) (xy 361.963082 -282.59115) (xy 361.972098 -282.59151) (xy 362.039154 -282.59151)
			(xy 362.048168 -282.591129) (xy 362.065085 -282.584898) (xy 362.072174 -282.579318) (xy 362.072174 -282.579064)
			(xy 362.072428 -282.579064) (xy 362.093372 -282.56144) (xy 362.139342 -282.531727) (xy 362.189087 -282.508889)
			(xy 362.241584 -282.493394) (xy 362.295758 -282.485561) (xy 362.323126 -282.485084) (xy 362.350375 -282.485588)
			(xy 362.404319 -282.493347) (xy 362.45661 -282.508704) (xy 362.506183 -282.531346) (xy 362.552029 -282.560812)
			(xy 362.593215 -282.596503) (xy 362.628903 -282.637692) (xy 362.658366 -282.68354) (xy 362.681005 -282.733115)
			(xy 362.696359 -282.785406) (xy 362.704114 -282.839351) (xy 362.704114 -282.893849) (xy 362.696359 -282.947794)
			(xy 362.681005 -283.000085) (xy 362.658366 -283.04966) (xy 362.628903 -283.095508) (xy 362.593215 -283.136697)
			(xy 362.552029 -283.172388) (xy 362.506183 -283.201854) (xy 362.45661 -283.224496) (xy 362.404319 -283.239853)
			(xy 362.350375 -283.247612) (xy 362.323126 -283.2481) (xy 362.295756 -283.247619) (xy 362.241578 -283.239805)
			(xy 362.189075 -283.224319) (xy 362.139328 -283.201481) (xy 362.09336 -283.17176) (xy 362.072428 -283.15412)
			(xy 362.072174 -283.153866) (xy 362.065073 -283.1483) (xy 362.048167 -283.142042) (xy 362.039154 -283.141674)
			(xy 361.972098 -283.141674) (xy 361.963082 -283.142036) (xy 361.946165 -283.148281) (xy 361.939078 -283.153866)
			(xy 361.939078 -283.15412) (xy 361.938824 -283.15412) (xy 361.917896 -283.171764) (xy 361.871922 -283.201475)
			(xy 361.822173 -283.224309) (xy 361.769672 -283.239799) (xy 361.715495 -283.247626) (xy 361.688126 -283.2481)
			(xy 361.660871 -283.247654) (xy 361.606917 -283.2399) (xy 361.554614 -283.224546) (xy 361.50503 -283.201905)
			(xy 361.459173 -283.172437) (xy 361.417976 -283.136742) (xy 361.382279 -283.095548) (xy 361.352808 -283.049693)
			(xy 361.330163 -283.00011) (xy 361.314805 -282.947809) (xy 361.307047 -282.893855) (xy 360.976899 -282.893855)
			(xy 360.976849 -282.89643) (xy 360.96754 -282.955376) (xy 360.958892 -282.98394) (xy 360.95559 -282.994354)
			(xy 360.957876 -283.015944) (xy 361.008168 -283.100526) (xy 361.02544 -283.112972) (xy 361.036362 -283.115004)
			(xy 361.062178 -283.120347) (xy 361.112094 -283.137315) (xy 361.159199 -283.160995) (xy 361.202593 -283.190935)
			(xy 361.241451 -283.226566) (xy 361.275033 -283.267209) (xy 361.302699 -283.312088) (xy 361.323921 -283.360349)
			(xy 361.338295 -283.411073) (xy 361.345547 -283.463293) (xy 361.345988 -283.489654) (xy 361.345406 -283.519777)
			(xy 361.33593 -283.579274) (xy 361.317223 -283.636542) (xy 361.289749 -283.69016) (xy 361.254191 -283.738794)
			(xy 361.233212 -283.760418) (xy 361.226373 -283.767819) (xy 361.218652 -283.786417) (xy 361.218226 -283.796486)
			(xy 361.218226 -283.868622) (xy 361.218633 -283.878693) (xy 361.226366 -283.897291) (xy 361.233212 -283.90469)
			(xy 361.254215 -283.926294) (xy 361.28978 -283.974929) (xy 361.317255 -284.02855) (xy 361.331634 -284.072584)
			(xy 366.233202 -284.072584) (xy 366.233658 -284.045213) (xy 366.241478 -283.991034) (xy 366.25697 -283.938531)
			(xy 366.279814 -283.888784) (xy 366.30954 -283.842817) (xy 366.327182 -283.821886) (xy 366.327436 -283.821632)
			(xy 366.333019 -283.814543) (xy 366.339267 -283.797628) (xy 366.339628 -283.788612) (xy 366.339628 -283.721556)
			(xy 366.339238 -283.712543) (xy 366.333013 -283.695626) (xy 366.327436 -283.688536) (xy 366.327182 -283.688536)
			(xy 366.327182 -283.688282) (xy 366.309565 -283.667332) (xy 366.279851 -283.621364) (xy 366.257011 -283.571621)
			(xy 366.241514 -283.519124) (xy 366.23368 -283.464952) (xy 366.233202 -283.437584) (xy 366.233688 -283.410333)
			(xy 366.241444 -283.356385) (xy 366.256799 -283.30409) (xy 366.279441 -283.254513) (xy 366.308907 -283.208663)
			(xy 366.344598 -283.167472) (xy 366.385789 -283.131781) (xy 366.431639 -283.102315) (xy 366.481216 -283.079673)
			(xy 366.533511 -283.064318) (xy 366.587459 -283.056562) (xy 366.641961 -283.056562) (xy 366.695909 -283.064318)
			(xy 366.748204 -283.079673) (xy 366.797781 -283.102315) (xy 366.843631 -283.131781) (xy 366.884822 -283.167472)
			(xy 366.920513 -283.208663) (xy 366.949979 -283.254513) (xy 366.972621 -283.30409) (xy 366.987976 -283.356385)
			(xy 366.995732 -283.410333) (xy 366.996218 -283.437584) (xy 366.995763 -283.464955) (xy 366.987945 -283.519135)
			(xy 366.972455 -283.571639) (xy 366.94961 -283.621386) (xy 366.919882 -283.667352) (xy 366.902238 -283.688282)
			(xy 366.901984 -283.688536) (xy 366.896416 -283.695635) (xy 366.890159 -283.712542) (xy 366.889792 -283.721556)
			(xy 366.889792 -283.788612) (xy 366.890145 -283.797629) (xy 366.896396 -283.814546) (xy 366.901984 -283.821632)
			(xy 366.902238 -283.821632) (xy 366.902238 -283.821886) (xy 366.91989 -283.842807) (xy 366.949599 -283.888784)
			(xy 366.972432 -283.938534) (xy 366.98792 -283.991037) (xy 366.995746 -284.045214) (xy 366.996218 -284.072584)
			(xy 366.995732 -284.099835) (xy 366.987976 -284.153783) (xy 366.972621 -284.206078) (xy 366.949979 -284.255655)
			(xy 366.920513 -284.301505) (xy 366.884822 -284.342696) (xy 366.843631 -284.378387) (xy 366.797781 -284.407853)
			(xy 366.748204 -284.430495) (xy 366.695909 -284.44585) (xy 366.641961 -284.453606) (xy 366.587459 -284.453606)
			(xy 366.533511 -284.44585) (xy 366.481216 -284.430495) (xy 366.431639 -284.407853) (xy 366.385789 -284.378387)
			(xy 366.344598 -284.342696) (xy 366.308907 -284.301505) (xy 366.279441 -284.255655) (xy 366.256799 -284.206078)
			(xy 366.241444 -284.153783) (xy 366.233688 -284.099835) (xy 366.233202 -284.072584) (xy 361.331634 -284.072584)
			(xy 361.335958 -284.085825) (xy 361.345423 -284.145328) (xy 361.345988 -284.175454) (xy 361.345502 -284.202705)
			(xy 361.337746 -284.256653) (xy 361.322391 -284.308948) (xy 361.299749 -284.358525) (xy 361.270283 -284.404375)
			(xy 361.234592 -284.445566) (xy 361.193401 -284.481257) (xy 361.147551 -284.510723) (xy 361.097974 -284.533365)
			(xy 361.045679 -284.54872) (xy 360.991731 -284.556476) (xy 360.937229 -284.556476) (xy 360.883281 -284.54872)
			(xy 360.830986 -284.533365) (xy 360.781409 -284.510723) (xy 360.735559 -284.481257) (xy 360.694368 -284.445566)
			(xy 360.658677 -284.404375) (xy 360.629211 -284.358525) (xy 360.606569 -284.308948) (xy 360.591214 -284.256653)
			(xy 360.583458 -284.202705) (xy 360.582972 -284.175454) (xy 360.583571 -284.145332) (xy 360.593044 -284.085836)
			(xy 360.611748 -284.028568) (xy 360.639218 -283.974951) (xy 360.674771 -283.926316) (xy 360.695748 -283.90469)
			(xy 360.702578 -283.897281) (xy 360.710305 -283.878689) (xy 360.710734 -283.868622) (xy 360.710734 -283.796486)
			(xy 360.710334 -283.786414) (xy 360.702597 -283.767815) (xy 360.695748 -283.760418) (xy 360.67476 -283.7388)
			(xy 360.63919 -283.690171) (xy 360.611711 -283.636552) (xy 360.593005 -283.57928) (xy 360.583538 -283.519779)
			(xy 360.582972 -283.489654) (xy 360.583545 -283.459815) (xy 360.592862 -283.400869) (xy 360.601514 -283.372306)
			(xy 360.604816 -283.361892) (xy 360.60253 -283.340302) (xy 360.552238 -283.25572) (xy 360.534966 -283.243274)
			(xy 360.524044 -283.241242) (xy 360.496194 -283.235394) (xy 360.44253 -283.216457) (xy 360.392273 -283.189761)
			(xy 360.346537 -283.1559) (xy 360.306335 -283.115623) (xy 360.272559 -283.069824) (xy 360.245957 -283.019517)
			(xy 360.22712 -282.965818) (xy 360.221276 -282.937966) (xy 360.218736 -282.92552) (xy 360.203496 -282.906216)
			(xy 360.102404 -282.862528) (xy 360.077766 -282.864306) (xy 360.067098 -282.871164) (xy 360.044129 -282.885204)
			(xy 359.995055 -282.907334) (xy 359.943352 -282.92233) (xy 359.890053 -282.929892) (xy 359.863136 -282.930346)
			(xy 359.845117 -282.930129) (xy 359.809242 -282.926692) (xy 359.791508 -282.923488) (xy 359.781856 -282.92171)
			(xy 359.762806 -282.925266) (xy 359.687876 -282.973272) (xy 359.676446 -282.98902) (xy 359.67416 -282.998418)
			(xy 359.666766 -283.025464) (xy 359.645138 -283.077192) (xy 359.616175 -283.125199) (xy 359.5805 -283.168452)
			(xy 359.53888 -283.20602) (xy 359.492211 -283.237094) (xy 359.441498 -283.261006) (xy 359.387833 -283.27724)
			(xy 359.33237 -283.285449) (xy 359.304336 -283.285946) (xy 359.277087 -283.285388) (xy 359.223144 -283.277638)
			(xy 359.170853 -283.262289) (xy 359.121279 -283.239655) (xy 359.07543 -283.210196) (xy 359.03424 -283.174512)
			(xy 358.998548 -283.133329) (xy 358.969081 -283.087486) (xy 358.946437 -283.037916) (xy 358.931078 -282.985628)
			(xy 358.923317 -282.931687) (xy 358.922828 -282.904438) (xy 354.542092 -282.904438) (xy 354.535858 -282.947795)
			(xy 354.520504 -283.000088) (xy 354.497865 -283.049663) (xy 354.4684 -283.095512) (xy 354.432711 -283.136701)
			(xy 354.391523 -283.172392) (xy 354.345676 -283.201858) (xy 354.296101 -283.224499) (xy 354.243809 -283.239855)
			(xy 354.189864 -283.247613) (xy 354.162614 -283.2481) (xy 354.135244 -283.247626) (xy 354.081065 -283.23981)
			(xy 354.028562 -283.224323) (xy 353.978815 -283.201483) (xy 353.932848 -283.17176) (xy 353.911916 -283.15412)
			(xy 353.911662 -283.153866) (xy 353.904565 -283.148295) (xy 353.887656 -283.14204) (xy 353.878642 -283.141674)
			(xy 353.811586 -283.141674) (xy 353.802569 -283.14203) (xy 353.785653 -283.148279) (xy 353.778566 -283.153866)
			(xy 353.778566 -283.15412) (xy 353.778312 -283.15412) (xy 353.757389 -283.17177) (xy 353.711413 -283.20148)
			(xy 353.661663 -283.224313) (xy 353.609161 -283.239802) (xy 353.554984 -283.247627) (xy 353.527614 -283.2481)
			(xy 353.50036 -283.247654) (xy 353.446406 -283.239898) (xy 353.394106 -283.224543) (xy 353.344523 -283.201901)
			(xy 353.298667 -283.172433) (xy 353.257472 -283.136738) (xy 353.221776 -283.095544) (xy 353.192306 -283.049689)
			(xy 353.169662 -283.000107) (xy 353.154305 -282.947807) (xy 353.146547 -282.893854) (xy 352.816388 -282.893854)
			(xy 352.816337 -282.89643) (xy 352.807028 -282.955376) (xy 352.79838 -282.98394) (xy 352.795078 -282.994354)
			(xy 352.797364 -283.015944) (xy 352.847656 -283.100526) (xy 352.864928 -283.112972) (xy 352.87585 -283.115004)
			(xy 352.901664 -283.120356) (xy 352.951581 -283.137322) (xy 352.998685 -283.161001) (xy 353.04208 -283.19094)
			(xy 353.080938 -283.22657) (xy 353.11452 -283.267211) (xy 353.142186 -283.31209) (xy 353.163408 -283.360351)
			(xy 353.177783 -283.411074) (xy 353.185035 -283.463294) (xy 353.185476 -283.489654) (xy 353.184869 -283.519776)
			(xy 353.175396 -283.57927) (xy 353.156693 -283.636537) (xy 353.129225 -283.690155) (xy 353.093675 -283.738792)
			(xy 353.0727 -283.760418) (xy 353.06586 -283.767818) (xy 353.05814 -283.786417) (xy 353.057714 -283.796486)
			(xy 353.057714 -283.868622) (xy 353.058125 -283.878693) (xy 353.065855 -283.897291) (xy 353.0727 -283.90469)
			(xy 353.093701 -283.926296) (xy 353.129266 -283.97493) (xy 353.156743 -284.028551) (xy 353.171122 -284.072584)
			(xy 358.07269 -284.072584) (xy 358.073149 -284.045214) (xy 358.080969 -283.991034) (xy 358.09646 -283.938531)
			(xy 358.119303 -283.888784) (xy 358.149028 -283.842818) (xy 358.16667 -283.821886) (xy 358.166924 -283.821632)
			(xy 358.172506 -283.814542) (xy 358.178755 -283.797628) (xy 358.179116 -283.788612) (xy 358.179116 -283.721556)
			(xy 358.178729 -283.712542) (xy 358.172502 -283.695625) (xy 358.166924 -283.688536) (xy 358.16667 -283.688536)
			(xy 358.16667 -283.688282) (xy 358.149051 -283.667334) (xy 358.119337 -283.621365) (xy 358.096498 -283.571621)
			(xy 358.081002 -283.519125) (xy 358.073168 -283.464952) (xy 358.07269 -283.437584) (xy 358.073176 -283.410333)
			(xy 358.080932 -283.356385) (xy 358.096287 -283.30409) (xy 358.118929 -283.254513) (xy 358.148395 -283.208663)
			(xy 358.184086 -283.167472) (xy 358.225277 -283.131781) (xy 358.271127 -283.102315) (xy 358.320704 -283.079673)
			(xy 358.372999 -283.064318) (xy 358.426947 -283.056562) (xy 358.481449 -283.056562) (xy 358.535397 -283.064318)
			(xy 358.587692 -283.079673) (xy 358.637269 -283.102315) (xy 358.683119 -283.131781) (xy 358.72431 -283.167472)
			(xy 358.760001 -283.208663) (xy 358.789467 -283.254513) (xy 358.812109 -283.30409) (xy 358.827464 -283.356385)
			(xy 358.83522 -283.410333) (xy 358.835706 -283.437584) (xy 358.835229 -283.464954) (xy 358.827414 -283.519132)
			(xy 358.811927 -283.571635) (xy 358.789088 -283.621382) (xy 358.759366 -283.66735) (xy 358.741726 -283.688282)
			(xy 358.741472 -283.688536) (xy 358.735903 -283.695634) (xy 358.729647 -283.712542) (xy 358.72928 -283.721556)
			(xy 358.72928 -283.788612) (xy 358.729636 -283.797629) (xy 358.735885 -283.814546) (xy 358.741472 -283.821632)
			(xy 358.741726 -283.821632) (xy 358.741726 -283.821886) (xy 358.759376 -283.842809) (xy 358.789085 -283.888785)
			(xy 358.811919 -283.938535) (xy 358.827407 -283.991037) (xy 358.835233 -284.045214) (xy 358.835706 -284.072584)
			(xy 358.83522 -284.099835) (xy 358.827464 -284.153783) (xy 358.812109 -284.206078) (xy 358.789467 -284.255655)
			(xy 358.760001 -284.301505) (xy 358.72431 -284.342696) (xy 358.683119 -284.378387) (xy 358.637269 -284.407853)
			(xy 358.587692 -284.430495) (xy 358.535397 -284.44585) (xy 358.481449 -284.453606) (xy 358.426947 -284.453606)
			(xy 358.372999 -284.44585) (xy 358.320704 -284.430495) (xy 358.271127 -284.407853) (xy 358.225277 -284.378387)
			(xy 358.184086 -284.342696) (xy 358.148395 -284.301505) (xy 358.118929 -284.255655) (xy 358.096287 -284.206078)
			(xy 358.080932 -284.153783) (xy 358.073176 -284.099835) (xy 358.07269 -284.072584) (xy 353.171122 -284.072584)
			(xy 353.175446 -284.085826) (xy 353.184911 -284.145328) (xy 353.185476 -284.175454) (xy 353.18499 -284.202705)
			(xy 353.177234 -284.256653) (xy 353.161879 -284.308948) (xy 353.139237 -284.358525) (xy 353.109771 -284.404375)
			(xy 353.07408 -284.445566) (xy 353.032889 -284.481257) (xy 352.987039 -284.510723) (xy 352.937462 -284.533365)
			(xy 352.885167 -284.54872) (xy 352.831219 -284.556476) (xy 352.776717 -284.556476) (xy 352.722769 -284.54872)
			(xy 352.670474 -284.533365) (xy 352.620897 -284.510723) (xy 352.575047 -284.481257) (xy 352.533856 -284.445566)
			(xy 352.498165 -284.404375) (xy 352.468699 -284.358525) (xy 352.446057 -284.308948) (xy 352.430702 -284.256653)
			(xy 352.422946 -284.202705) (xy 352.42246 -284.175454) (xy 352.423062 -284.145332) (xy 352.432535 -284.085837)
			(xy 352.451239 -284.028569) (xy 352.478708 -283.974952) (xy 352.51426 -283.926316) (xy 352.535236 -283.90469)
			(xy 352.542078 -283.897292) (xy 352.549796 -283.878691) (xy 352.550222 -283.868622) (xy 352.550222 -283.796486)
			(xy 352.549824 -283.786413) (xy 352.542086 -283.767815) (xy 352.535236 -283.760418) (xy 352.514246 -283.738802)
			(xy 352.478677 -283.690172) (xy 352.451198 -283.636553) (xy 352.432493 -283.579281) (xy 352.423026 -283.519779)
			(xy 352.42246 -283.489654) (xy 352.423033 -283.459815) (xy 352.43235 -283.400869) (xy 352.441002 -283.372306)
			(xy 352.444304 -283.361892) (xy 352.442018 -283.340302) (xy 352.391726 -283.25572) (xy 352.374454 -283.243274)
			(xy 352.363532 -283.241242) (xy 352.33568 -283.235403) (xy 352.282016 -283.216463) (xy 352.231759 -283.189767)
			(xy 352.186023 -283.155904) (xy 352.145822 -283.115626) (xy 352.112046 -283.069825) (xy 352.085445 -283.019518)
			(xy 352.066608 -282.965818) (xy 352.060764 -282.937966) (xy 352.058224 -282.92552) (xy 352.042984 -282.906216)
			(xy 351.941892 -282.862528) (xy 351.917254 -282.864306) (xy 351.906586 -282.871164) (xy 351.883596 -282.885167)
			(xy 351.834529 -282.907307) (xy 351.782833 -282.922313) (xy 351.729539 -282.929886) (xy 351.702624 -282.930346)
			(xy 351.684604 -282.930131) (xy 351.64873 -282.926693) (xy 351.630996 -282.923488) (xy 351.621344 -282.92171)
			(xy 351.602294 -282.925266) (xy 351.527364 -282.973272) (xy 351.515934 -282.98902) (xy 351.513648 -282.998418)
			(xy 351.506265 -283.025467) (xy 351.484636 -283.077196) (xy 351.455672 -283.125203) (xy 351.419995 -283.168456)
			(xy 351.378374 -283.206024) (xy 351.331704 -283.237098) (xy 351.28099 -283.261009) (xy 351.227323 -283.277243)
			(xy 351.171858 -283.28545) (xy 351.143824 -283.285946) (xy 351.116575 -283.2854) (xy 351.062632 -283.277647)
			(xy 351.01034 -283.262297) (xy 350.960766 -283.239662) (xy 350.914917 -283.210201) (xy 350.873728 -283.174516)
			(xy 350.838036 -283.133333) (xy 350.808568 -283.087489) (xy 350.785925 -283.037918) (xy 350.770566 -282.985629)
			(xy 350.762805 -282.931687) (xy 350.762316 -282.904438) (xy 346.043492 -282.904438) (xy 346.037259 -282.947794)
			(xy 346.021905 -283.000085) (xy 345.999267 -283.049659) (xy 345.969804 -283.095507) (xy 345.934116 -283.136696)
			(xy 345.89293 -283.172387) (xy 345.847084 -283.201853) (xy 345.797511 -283.224496) (xy 345.745221 -283.239853)
			(xy 345.691277 -283.247612) (xy 345.664028 -283.2481) (xy 345.636658 -283.247618) (xy 345.58248 -283.239804)
			(xy 345.529977 -283.224318) (xy 345.48023 -283.20148) (xy 345.434262 -283.171759) (xy 345.41333 -283.15412)
			(xy 345.413076 -283.153866) (xy 345.406003 -283.148259) (xy 345.389076 -283.142026) (xy 345.380056 -283.141674)
			(xy 345.313 -283.141674) (xy 345.303984 -283.142037) (xy 345.287067 -283.148281) (xy 345.27998 -283.153866)
			(xy 345.27998 -283.15412) (xy 345.279726 -283.15412) (xy 345.258798 -283.171763) (xy 345.212823 -283.201474)
			(xy 345.163075 -283.224309) (xy 345.110574 -283.239799) (xy 345.056397 -283.247626) (xy 345.029028 -283.2481)
			(xy 345.001773 -283.247655) (xy 344.947818 -283.239901) (xy 344.895516 -283.224547) (xy 344.845931 -283.201905)
			(xy 344.800074 -283.172437) (xy 344.758877 -283.136743) (xy 344.723179 -283.095549) (xy 344.693708 -283.049693)
			(xy 344.671063 -283.00011) (xy 344.655705 -282.947809) (xy 344.647947 -282.893855) (xy 344.317801 -282.893855)
			(xy 344.31775 -282.89643) (xy 344.308442 -282.955376) (xy 344.299794 -282.98394) (xy 344.296492 -282.994354)
			(xy 344.298778 -283.015944) (xy 344.34907 -283.100526) (xy 344.366342 -283.112972) (xy 344.377264 -283.115004)
			(xy 344.403081 -283.120346) (xy 344.452997 -283.137314) (xy 344.500101 -283.160994) (xy 344.543495 -283.190935)
			(xy 344.582354 -283.226566) (xy 344.615935 -283.267208) (xy 344.643601 -283.312088) (xy 344.664823 -283.360349)
			(xy 344.679197 -283.411073) (xy 344.686449 -283.463293) (xy 344.68689 -283.489654) (xy 344.686307 -283.519777)
			(xy 344.676832 -283.579274) (xy 344.658125 -283.636542) (xy 344.630651 -283.69016) (xy 344.595093 -283.738793)
			(xy 344.574114 -283.760418) (xy 344.567275 -283.767819) (xy 344.559554 -283.786418) (xy 344.559128 -283.796486)
			(xy 344.559128 -283.868622) (xy 344.559535 -283.878693) (xy 344.567268 -283.897291) (xy 344.574114 -283.90469)
			(xy 344.595117 -283.926294) (xy 344.630682 -283.974929) (xy 344.658157 -284.02855) (xy 344.672536 -284.072584)
			(xy 349.574104 -284.072584) (xy 349.57456 -284.045213) (xy 349.58238 -283.991034) (xy 349.597871 -283.938531)
			(xy 349.620715 -283.888784) (xy 349.650442 -283.842817) (xy 349.668084 -283.821886) (xy 349.668338 -283.821632)
			(xy 349.673922 -283.814544) (xy 349.680169 -283.797628) (xy 349.68053 -283.788612) (xy 349.68053 -283.721556)
			(xy 349.68014 -283.712543) (xy 349.673915 -283.695626) (xy 349.668338 -283.688536) (xy 349.668084 -283.688536)
			(xy 349.668084 -283.688282) (xy 349.650467 -283.667332) (xy 349.620753 -283.621364) (xy 349.597913 -283.571621)
			(xy 349.582416 -283.519124) (xy 349.574582 -283.464952) (xy 349.574104 -283.437584) (xy 349.57459 -283.410333)
			(xy 349.582346 -283.356385) (xy 349.597701 -283.30409) (xy 349.620343 -283.254513) (xy 349.649809 -283.208663)
			(xy 349.6855 -283.167472) (xy 349.726691 -283.131781) (xy 349.772541 -283.102315) (xy 349.822118 -283.079673)
			(xy 349.874413 -283.064318) (xy 349.928361 -283.056562) (xy 349.982863 -283.056562) (xy 350.036811 -283.064318)
			(xy 350.089106 -283.079673) (xy 350.138683 -283.102315) (xy 350.184533 -283.131781) (xy 350.225724 -283.167472)
			(xy 350.261415 -283.208663) (xy 350.290881 -283.254513) (xy 350.313523 -283.30409) (xy 350.328878 -283.356385)
			(xy 350.336634 -283.410333) (xy 350.33712 -283.437584) (xy 350.336664 -283.464955) (xy 350.328847 -283.519135)
			(xy 350.313356 -283.571639) (xy 350.290512 -283.621386) (xy 350.260783 -283.667351) (xy 350.24314 -283.688282)
			(xy 350.242886 -283.688536) (xy 350.237319 -283.695636) (xy 350.231061 -283.712542) (xy 350.230694 -283.721556)
			(xy 350.230694 -283.788612) (xy 350.231047 -283.797629) (xy 350.237297 -283.814546) (xy 350.242886 -283.821632)
			(xy 350.24314 -283.821632) (xy 350.24314 -283.821886) (xy 350.260793 -283.842807) (xy 350.290501 -283.888784)
			(xy 350.313334 -283.938534) (xy 350.328822 -283.991037) (xy 350.336648 -284.045214) (xy 350.33712 -284.072584)
			(xy 350.336634 -284.099835) (xy 350.328878 -284.153783) (xy 350.313523 -284.206078) (xy 350.290881 -284.255655)
			(xy 350.261415 -284.301505) (xy 350.225724 -284.342696) (xy 350.184533 -284.378387) (xy 350.138683 -284.407853)
			(xy 350.089106 -284.430495) (xy 350.036811 -284.44585) (xy 349.982863 -284.453606) (xy 349.928361 -284.453606)
			(xy 349.874413 -284.44585) (xy 349.822118 -284.430495) (xy 349.772541 -284.407853) (xy 349.726691 -284.378387)
			(xy 349.6855 -284.342696) (xy 349.649809 -284.301505) (xy 349.620343 -284.255655) (xy 349.597701 -284.206078)
			(xy 349.582346 -284.153783) (xy 349.57459 -284.099835) (xy 349.574104 -284.072584) (xy 344.672536 -284.072584)
			(xy 344.67686 -284.085825) (xy 344.686325 -284.145328) (xy 344.68689 -284.175454) (xy 344.686404 -284.202705)
			(xy 344.678648 -284.256653) (xy 344.663293 -284.308948) (xy 344.640651 -284.358525) (xy 344.611185 -284.404375)
			(xy 344.575494 -284.445566) (xy 344.534303 -284.481257) (xy 344.488453 -284.510723) (xy 344.438876 -284.533365)
			(xy 344.386581 -284.54872) (xy 344.332633 -284.556476) (xy 344.278131 -284.556476) (xy 344.224183 -284.54872)
			(xy 344.171888 -284.533365) (xy 344.122311 -284.510723) (xy 344.076461 -284.481257) (xy 344.03527 -284.445566)
			(xy 343.999579 -284.404375) (xy 343.970113 -284.358525) (xy 343.947471 -284.308948) (xy 343.932116 -284.256653)
			(xy 343.92436 -284.202705) (xy 343.923874 -284.175454) (xy 343.924472 -284.145332) (xy 343.933946 -284.085836)
			(xy 343.95265 -284.028568) (xy 343.98012 -283.974951) (xy 344.015673 -283.926316) (xy 344.03665 -283.90469)
			(xy 344.04348 -283.897282) (xy 344.051207 -283.878689) (xy 344.051636 -283.868622) (xy 344.051636 -283.796486)
			(xy 344.051235 -283.786414) (xy 344.043499 -283.767815) (xy 344.03665 -283.760418) (xy 344.015662 -283.7388)
			(xy 343.980093 -283.69017) (xy 343.952613 -283.636552) (xy 343.933907 -283.57928) (xy 343.92444 -283.519779)
			(xy 343.923874 -283.489654) (xy 343.924447 -283.459815) (xy 343.933764 -283.400869) (xy 343.942416 -283.372306)
			(xy 343.945718 -283.361892) (xy 343.943432 -283.340302) (xy 343.89314 -283.25572) (xy 343.875868 -283.243274)
			(xy 343.864946 -283.241242) (xy 343.837096 -283.235393) (xy 343.783432 -283.216456) (xy 343.733175 -283.18976)
			(xy 343.687439 -283.155899) (xy 343.647237 -283.115623) (xy 343.613461 -283.069823) (xy 343.586859 -283.019517)
			(xy 343.568022 -282.965818) (xy 343.562178 -282.937966) (xy 343.559638 -282.92552) (xy 343.544398 -282.906216)
			(xy 343.443306 -282.862528) (xy 343.418668 -282.864306) (xy 343.408 -282.871164) (xy 343.38503 -282.885203)
			(xy 343.335956 -282.907334) (xy 343.284254 -282.92233) (xy 343.230955 -282.929892) (xy 343.204038 -282.930346)
			(xy 343.186019 -282.930129) (xy 343.150144 -282.926692) (xy 343.13241 -282.923488) (xy 343.122758 -282.92171)
			(xy 343.103708 -282.925266) (xy 343.028778 -282.973272) (xy 343.017348 -282.98902) (xy 343.015062 -282.998418)
			(xy 343.007666 -283.025463) (xy 342.986039 -283.077191) (xy 342.957076 -283.125198) (xy 342.9214 -283.168451)
			(xy 342.879781 -283.206019) (xy 342.833112 -283.237093) (xy 342.7824 -283.261005) (xy 342.728735 -283.27724)
			(xy 342.673272 -283.285449) (xy 342.645238 -283.285946) (xy 342.617989 -283.285387) (xy 342.564046 -283.277636)
			(xy 342.511755 -283.262288) (xy 342.462181 -283.239654) (xy 342.416332 -283.210195) (xy 342.375143 -283.174511)
			(xy 342.33945 -283.133329) (xy 342.309983 -283.087486) (xy 342.287339 -283.037916) (xy 342.27198 -282.985628)
			(xy 342.264219 -282.931686) (xy 342.26373 -282.904438) (xy 337.882992 -282.904438) (xy 337.876758 -282.947795)
			(xy 337.861404 -283.000088) (xy 337.838765 -283.049663) (xy 337.809301 -283.095511) (xy 337.773612 -283.1367)
			(xy 337.732424 -283.172391) (xy 337.686577 -283.201857) (xy 337.637003 -283.224499) (xy 337.584711 -283.239855)
			(xy 337.530766 -283.247613) (xy 337.503516 -283.2481) (xy 337.476146 -283.247625) (xy 337.421967 -283.239809)
			(xy 337.369464 -283.224322) (xy 337.319717 -283.201482) (xy 337.27375 -283.17176) (xy 337.252818 -283.15412)
			(xy 337.252564 -283.153866) (xy 337.245466 -283.148296) (xy 337.228558 -283.142041) (xy 337.219544 -283.141674)
			(xy 337.152488 -283.141674) (xy 337.143471 -283.142031) (xy 337.126555 -283.148279) (xy 337.119468 -283.153866)
			(xy 337.119468 -283.15412) (xy 337.119214 -283.15412) (xy 337.09829 -283.171769) (xy 337.052315 -283.201479)
			(xy 337.002565 -283.224312) (xy 336.950063 -283.239801) (xy 336.895886 -283.247627) (xy 336.868516 -283.2481)
			(xy 336.841262 -283.247654) (xy 336.787308 -283.239898) (xy 336.735007 -283.224543) (xy 336.685424 -283.201901)
			(xy 336.639568 -283.172433) (xy 336.598372 -283.136739) (xy 336.562676 -283.095545) (xy 336.533206 -283.04969)
			(xy 336.510562 -283.000108) (xy 336.495205 -282.947808) (xy 336.487447 -282.893854) (xy 336.15729 -282.893854)
			(xy 336.157239 -282.89643) (xy 336.14793 -282.955376) (xy 336.139282 -282.98394) (xy 336.13598 -282.994354)
			(xy 336.138266 -283.015944) (xy 336.188558 -283.100526) (xy 336.20583 -283.112972) (xy 336.216752 -283.115004)
			(xy 336.242567 -283.120354) (xy 336.292483 -283.137321) (xy 336.339587 -283.161) (xy 336.382982 -283.190939)
			(xy 336.421841 -283.226569) (xy 336.455423 -283.267211) (xy 336.483088 -283.31209) (xy 336.50431 -283.36035)
			(xy 336.518685 -283.411074) (xy 336.525937 -283.463294) (xy 336.526378 -283.489654) (xy 336.52577 -283.519776)
			(xy 336.516297 -283.57927) (xy 336.497594 -283.636537) (xy 336.470127 -283.690155) (xy 336.434577 -283.738792)
			(xy 336.413602 -283.760418) (xy 336.406762 -283.767818) (xy 336.399042 -283.786417) (xy 336.398616 -283.796486)
			(xy 336.398616 -283.868622) (xy 336.399026 -283.878693) (xy 336.406757 -283.897291) (xy 336.413602 -283.90469)
			(xy 336.434603 -283.926296) (xy 336.470168 -283.97493) (xy 336.497645 -284.028551) (xy 336.512024 -284.072584)
			(xy 341.413592 -284.072584) (xy 341.414051 -284.045214) (xy 341.421871 -283.991034) (xy 341.437361 -283.938531)
			(xy 341.460205 -283.888784) (xy 341.48993 -283.842818) (xy 341.507572 -283.821886) (xy 341.507826 -283.821632)
			(xy 341.513408 -283.814543) (xy 341.519657 -283.797628) (xy 341.520018 -283.788612) (xy 341.520018 -283.721556)
			(xy 341.51963 -283.712542) (xy 341.513404 -283.695625) (xy 341.507826 -283.688536) (xy 341.507572 -283.688536)
			(xy 341.507572 -283.688282) (xy 341.489954 -283.667333) (xy 341.46024 -283.621365) (xy 341.4374 -283.571621)
			(xy 341.421904 -283.519125) (xy 341.41407 -283.464952) (xy 341.413592 -283.437584) (xy 341.414078 -283.410333)
			(xy 341.421834 -283.356385) (xy 341.437189 -283.30409) (xy 341.459831 -283.254513) (xy 341.489297 -283.208663)
			(xy 341.524988 -283.167472) (xy 341.566179 -283.131781) (xy 341.612029 -283.102315) (xy 341.661606 -283.079673)
			(xy 341.713901 -283.064318) (xy 341.767849 -283.056562) (xy 341.822351 -283.056562) (xy 341.876299 -283.064318)
			(xy 341.928594 -283.079673) (xy 341.978171 -283.102315) (xy 342.024021 -283.131781) (xy 342.065212 -283.167472)
			(xy 342.100903 -283.208663) (xy 342.130369 -283.254513) (xy 342.153011 -283.30409) (xy 342.168366 -283.356385)
			(xy 342.176122 -283.410333) (xy 342.176608 -283.437584) (xy 342.176131 -283.464954) (xy 342.168315 -283.519132)
			(xy 342.152829 -283.571635) (xy 342.12999 -283.621382) (xy 342.100268 -283.66735) (xy 342.082628 -283.688282)
			(xy 342.082374 -283.688536) (xy 342.076805 -283.695635) (xy 342.070549 -283.712542) (xy 342.070182 -283.721556)
			(xy 342.070182 -283.788612) (xy 342.070537 -283.797629) (xy 342.076787 -283.814546) (xy 342.082374 -283.821632)
			(xy 342.082628 -283.821632) (xy 342.082628 -283.821886) (xy 342.100278 -283.842809) (xy 342.129988 -283.888785)
			(xy 342.152821 -283.938535) (xy 342.168309 -283.991037) (xy 342.176135 -284.045214) (xy 342.176608 -284.072584)
			(xy 342.176122 -284.099835) (xy 342.168366 -284.153783) (xy 342.153011 -284.206078) (xy 342.130369 -284.255655)
			(xy 342.100903 -284.301505) (xy 342.065212 -284.342696) (xy 342.024021 -284.378387) (xy 341.978171 -284.407853)
			(xy 341.928594 -284.430495) (xy 341.876299 -284.44585) (xy 341.822351 -284.453606) (xy 341.767849 -284.453606)
			(xy 341.713901 -284.44585) (xy 341.661606 -284.430495) (xy 341.612029 -284.407853) (xy 341.566179 -284.378387)
			(xy 341.524988 -284.342696) (xy 341.489297 -284.301505) (xy 341.459831 -284.255655) (xy 341.437189 -284.206078)
			(xy 341.421834 -284.153783) (xy 341.414078 -284.099835) (xy 341.413592 -284.072584) (xy 336.512024 -284.072584)
			(xy 336.516348 -284.085826) (xy 336.525813 -284.145328) (xy 336.526378 -284.175454) (xy 336.525892 -284.202705)
			(xy 336.518136 -284.256653) (xy 336.502781 -284.308948) (xy 336.480139 -284.358525) (xy 336.450673 -284.404375)
			(xy 336.414982 -284.445566) (xy 336.373791 -284.481257) (xy 336.327941 -284.510723) (xy 336.278364 -284.533365)
			(xy 336.226069 -284.54872) (xy 336.172121 -284.556476) (xy 336.117619 -284.556476) (xy 336.063671 -284.54872)
			(xy 336.011376 -284.533365) (xy 335.961799 -284.510723) (xy 335.915949 -284.481257) (xy 335.874758 -284.445566)
			(xy 335.839067 -284.404375) (xy 335.809601 -284.358525) (xy 335.786959 -284.308948) (xy 335.771604 -284.256653)
			(xy 335.763848 -284.202705) (xy 335.763362 -284.175454) (xy 335.763964 -284.145332) (xy 335.773437 -284.085837)
			(xy 335.79214 -284.028569) (xy 335.819609 -283.974951) (xy 335.855162 -283.926316) (xy 335.876138 -283.90469)
			(xy 335.88298 -283.897292) (xy 335.890698 -283.878691) (xy 335.891124 -283.868622) (xy 335.891124 -283.796486)
			(xy 335.890726 -283.786413) (xy 335.882988 -283.767815) (xy 335.876138 -283.760418) (xy 335.855148 -283.738802)
			(xy 335.819579 -283.690172) (xy 335.7921 -283.636553) (xy 335.773395 -283.57928) (xy 335.763928 -283.519779)
			(xy 335.763362 -283.489654) (xy 335.763935 -283.459815) (xy 335.773252 -283.400869) (xy 335.781904 -283.372306)
			(xy 335.785206 -283.361892) (xy 335.78292 -283.340302) (xy 335.732628 -283.25572) (xy 335.715356 -283.243274)
			(xy 335.704434 -283.241242) (xy 335.676582 -283.235401) (xy 335.622919 -283.216462) (xy 335.572662 -283.189766)
			(xy 335.526925 -283.155903) (xy 335.486724 -283.115625) (xy 335.452948 -283.069825) (xy 335.426347 -283.019518)
			(xy 335.40751 -282.965818) (xy 335.401666 -282.937966) (xy 335.399126 -282.92552) (xy 335.383886 -282.906216)
			(xy 335.282794 -282.862528) (xy 335.258156 -282.864306) (xy 335.247488 -282.871164) (xy 335.224497 -282.885167)
			(xy 335.175431 -282.907306) (xy 335.123735 -282.922312) (xy 335.070441 -282.929886) (xy 335.043526 -282.930346)
			(xy 335.025506 -282.930131) (xy 334.989632 -282.926693) (xy 334.971898 -282.923488) (xy 334.962246 -282.92171)
			(xy 334.943196 -282.925266) (xy 334.868266 -282.973272) (xy 334.856836 -282.98902) (xy 334.85455 -282.998418)
			(xy 334.847165 -283.025466) (xy 334.825537 -283.077195) (xy 334.796572 -283.125203) (xy 334.760896 -283.168456)
			(xy 334.719275 -283.206023) (xy 334.672605 -283.237097) (xy 334.621891 -283.261008) (xy 334.568224 -283.277242)
			(xy 334.51276 -283.28545) (xy 334.484726 -283.285946) (xy 334.457477 -283.285398) (xy 334.403534 -283.277646)
			(xy 334.351242 -283.262296) (xy 334.301668 -283.23966) (xy 334.255819 -283.2102) (xy 334.21463 -283.174516)
			(xy 334.178938 -283.133332) (xy 334.14947 -283.087488) (xy 334.126827 -283.037918) (xy 334.111468 -282.985629)
			(xy 334.103707 -282.931687) (xy 334.103218 -282.904438) (xy 330.943966 -282.904438) (xy 330.943966 -286.352996)
			(xy 330.944488 -286.363265) (xy 330.952613 -286.382135) (xy 330.959714 -286.389572) (xy 330.967334 -286.396684)
			(xy 330.967842 -286.397192) (xy 331.015848 -286.441388) (xy 331.019772 -286.444842) (xy 331.028736 -286.450214)
			(xy 331.033628 -286.452056) (xy 331.043534 -286.455358) (xy 331.054456 -286.454342) (xy 331.128156 -286.448271)
			(xy 331.27591 -286.441791) (xy 331.349858 -286.441388) (xy 331.350874 -286.441388) (xy 331.433792 -286.441915)
			(xy 331.599427 -286.450089) (xy 331.764461 -286.46638) (xy 331.928497 -286.490747) (xy 332.09114 -286.523132)
			(xy 332.251999 -286.563458) (xy 332.410685 -286.611628) (xy 332.566817 -286.667524) (xy 332.643861 -286.699452)
			(xy 340.924132 -286.699452) (xy 340.928203 -286.64383) (xy 340.940329 -286.589393) (xy 340.960252 -286.537302)
			(xy 340.987548 -286.488667) (xy 341.021634 -286.444524) (xy 341.061783 -286.405815) (xy 341.107141 -286.373364)
			(xy 341.156741 -286.347863) (xy 341.209525 -286.329856) (xy 341.264368 -286.319726) (xy 341.320102 -286.317689)
			(xy 341.375539 -286.323789) (xy 341.429496 -286.337895) (xy 341.480825 -286.359707) (xy 341.528431 -286.388761)
			(xy 341.571299 -286.424436) (xy 341.608516 -286.465973) (xy 341.639289 -286.512486) (xy 341.662961 -286.562983)
			(xy 341.672993 -286.596328) (xy 341.832182 -286.596328) (xy 341.836253 -286.540706) (xy 341.848379 -286.486269)
			(xy 341.868302 -286.434178) (xy 341.895598 -286.385543) (xy 341.929684 -286.3414) (xy 341.969833 -286.302691)
			(xy 342.015191 -286.27024) (xy 342.064791 -286.244739) (xy 342.117575 -286.226732) (xy 342.172418 -286.216602)
			(xy 342.228152 -286.214565) (xy 342.283589 -286.220665) (xy 342.337546 -286.234771) (xy 342.388875 -286.256583)
			(xy 342.436481 -286.285637) (xy 342.479349 -286.321312) (xy 342.516566 -286.362849) (xy 342.547339 -286.409362)
			(xy 342.571011 -286.459859) (xy 342.587079 -286.513266) (xy 342.595199 -286.568442) (xy 342.595708 -286.596328)
			(xy 342.595199 -286.624214) (xy 342.587079 -286.67939) (xy 342.571011 -286.732797) (xy 342.547339 -286.783294)
			(xy 342.518786 -286.826452) (xy 357.611932 -286.826452) (xy 357.616003 -286.77083) (xy 357.628129 -286.716393)
			(xy 357.648052 -286.664302) (xy 357.675348 -286.615667) (xy 357.709434 -286.571524) (xy 357.749583 -286.532815)
			(xy 357.794941 -286.500364) (xy 357.844541 -286.474863) (xy 357.897325 -286.456856) (xy 357.952168 -286.446726)
			(xy 358.007902 -286.444689) (xy 358.063339 -286.450789) (xy 358.117296 -286.464895) (xy 358.168625 -286.486707)
			(xy 358.216231 -286.515761) (xy 358.259099 -286.551436) (xy 358.296316 -286.592973) (xy 358.327089 -286.639486)
			(xy 358.350761 -286.689983) (xy 358.365531 -286.739076) (xy 358.56494 -286.739076) (xy 358.569011 -286.683454)
			(xy 358.581137 -286.629017) (xy 358.60106 -286.576926) (xy 358.628356 -286.528291) (xy 358.662442 -286.484148)
			(xy 358.702591 -286.445439) (xy 358.747949 -286.412988) (xy 358.797549 -286.387487) (xy 358.850333 -286.36948)
			(xy 358.905176 -286.35935) (xy 358.96091 -286.357313) (xy 359.016347 -286.363413) (xy 359.070304 -286.377519)
			(xy 359.121633 -286.399331) (xy 359.169239 -286.428385) (xy 359.212107 -286.46406) (xy 359.249324 -286.505597)
			(xy 359.280097 -286.55211) (xy 359.303769 -286.602607) (xy 359.319837 -286.656014) (xy 359.327957 -286.71119)
			(xy 359.328466 -286.739076) (xy 359.327957 -286.766962) (xy 359.319837 -286.822138) (xy 359.303769 -286.875545)
			(xy 359.280097 -286.926042) (xy 359.249324 -286.972555) (xy 359.212107 -287.014092) (xy 359.169239 -287.049767)
			(xy 359.121633 -287.078821) (xy 359.070304 -287.100633) (xy 359.016347 -287.114739) (xy 358.96091 -287.120839)
			(xy 358.905176 -287.118802) (xy 358.850333 -287.108672) (xy 358.797549 -287.090665) (xy 358.747949 -287.065164)
			(xy 358.702591 -287.032713) (xy 358.662442 -286.994004) (xy 358.628356 -286.949861) (xy 358.60106 -286.901226)
			(xy 358.581137 -286.849135) (xy 358.569011 -286.794698) (xy 358.56494 -286.739076) (xy 358.365531 -286.739076)
			(xy 358.366829 -286.74339) (xy 358.374949 -286.798566) (xy 358.375458 -286.826452) (xy 358.374949 -286.854338)
			(xy 358.366829 -286.909514) (xy 358.350761 -286.962921) (xy 358.327089 -287.013418) (xy 358.296316 -287.059931)
			(xy 358.259099 -287.101468) (xy 358.216231 -287.137143) (xy 358.168625 -287.166197) (xy 358.117296 -287.188009)
			(xy 358.063339 -287.202115) (xy 358.007902 -287.208215) (xy 357.952168 -287.206178) (xy 357.897325 -287.196048)
			(xy 357.844541 -287.178041) (xy 357.794941 -287.15254) (xy 357.749583 -287.120089) (xy 357.709434 -287.08138)
			(xy 357.675348 -287.037237) (xy 357.648052 -286.988602) (xy 357.628129 -286.936511) (xy 357.616003 -286.882074)
			(xy 357.611932 -286.826452) (xy 342.518786 -286.826452) (xy 342.516566 -286.829807) (xy 342.479349 -286.871344)
			(xy 342.436481 -286.907019) (xy 342.388875 -286.936073) (xy 342.337546 -286.957885) (xy 342.283589 -286.971991)
			(xy 342.228152 -286.978091) (xy 342.172418 -286.976054) (xy 342.117575 -286.965924) (xy 342.064791 -286.947917)
			(xy 342.015191 -286.922416) (xy 341.969833 -286.889965) (xy 341.929684 -286.851256) (xy 341.895598 -286.807113)
			(xy 341.868302 -286.758478) (xy 341.848379 -286.706387) (xy 341.836253 -286.65195) (xy 341.832182 -286.596328)
			(xy 341.672993 -286.596328) (xy 341.679029 -286.61639) (xy 341.687149 -286.671566) (xy 341.687658 -286.699452)
			(xy 341.687149 -286.727338) (xy 341.679029 -286.782514) (xy 341.662961 -286.835921) (xy 341.639289 -286.886418)
			(xy 341.608516 -286.932931) (xy 341.571299 -286.974468) (xy 341.528431 -287.010143) (xy 341.480825 -287.039197)
			(xy 341.429496 -287.061009) (xy 341.375539 -287.075115) (xy 341.320102 -287.081215) (xy 341.264368 -287.079178)
			(xy 341.209525 -287.069048) (xy 341.156741 -287.051041) (xy 341.107141 -287.02554) (xy 341.061783 -286.993089)
			(xy 341.021634 -286.95438) (xy 340.987548 -286.910237) (xy 340.960252 -286.861602) (xy 340.940329 -286.809511)
			(xy 340.928203 -286.755074) (xy 340.924132 -286.699452) (xy 332.643861 -286.699452) (xy 332.720019 -286.731013)
			(xy 332.869921 -286.801942) (xy 333.016163 -286.880139) (xy 333.158393 -286.965418) (xy 333.296268 -287.057571)
			(xy 333.429455 -287.156377) (xy 333.557635 -287.261599) (xy 333.680498 -287.372983) (xy 333.797748 -287.49026)
			(xy 333.909104 -287.613149) (xy 334.014296 -287.741352) (xy 334.113073 -287.874562) (xy 334.205194 -288.012458)
			(xy 334.29044 -288.154707) (xy 334.368604 -288.300967) (xy 334.439499 -288.450885) (xy 334.502953 -288.604102)
			(xy 334.558814 -288.760246) (xy 334.606947 -288.918944) (xy 334.647236 -289.079811) (xy 334.679585 -289.242462)
			(xy 334.703915 -289.406504) (xy 334.720167 -289.571541) (xy 334.728304 -289.737178) (xy 334.72882 -289.820096)
			(xy 334.728311 -289.903026) (xy 334.720173 -290.068687) (xy 334.703916 -290.233749) (xy 334.67958 -290.397815)
			(xy 334.647222 -290.560488) (xy 334.606921 -290.721378) (xy 334.558775 -290.880097) (xy 334.502898 -291.036262)
			(xy 334.439427 -291.189498) (xy 334.368512 -291.339434) (xy 334.290326 -291.48571) (xy 334.205057 -291.627974)
			(xy 334.11291 -291.765882) (xy 334.014108 -291.899103) (xy 333.908887 -292.027315) (xy 333.797502 -292.15021)
			(xy 333.680221 -292.267491) (xy 333.557327 -292.378877) (xy 333.429115 -292.484098) (xy 333.295895 -292.582901)
			(xy 333.157987 -292.675049) (xy 333.015724 -292.760319) (xy 332.869448 -292.838505) (xy 332.719512 -292.90942)
			(xy 332.566277 -292.972893) (xy 332.410112 -293.02877) (xy 332.251394 -293.076917) (xy 332.090504 -293.117219)
			(xy 331.92783 -293.149577) (xy 331.763765 -293.173914) (xy 331.598703 -293.190172) (xy 331.433042 -293.198311)
			(xy 331.350112 -293.198804) (xy 331.349858 -293.198804) (xy 331.275783 -293.198404) (xy 331.127775 -293.191924)
			(xy 331.053948 -293.18585) (xy 331.04328 -293.184834) (xy 331.033374 -293.188136) (xy 331.028404 -293.190021)
			(xy 331.019318 -293.195532) (xy 331.01534 -293.199058) (xy 330.960476 -293.249604) (xy 330.953037 -293.2571)
			(xy 330.944515 -293.276395) (xy 330.943966 -293.286942) (xy 330.943966 -294.1828) (xy 342.809828 -294.1828)
			(xy 342.813899 -294.127178) (xy 342.826025 -294.072741) (xy 342.845948 -294.02065) (xy 342.873244 -293.972015)
			(xy 342.90733 -293.927872) (xy 342.947479 -293.889163) (xy 342.992837 -293.856712) (xy 343.042437 -293.831211)
			(xy 343.095221 -293.813204) (xy 343.150064 -293.803074) (xy 343.205798 -293.801037) (xy 343.261235 -293.807137)
			(xy 343.315192 -293.821243) (xy 343.366521 -293.843055) (xy 343.414127 -293.872109) (xy 343.456995 -293.907784)
			(xy 343.494212 -293.949321) (xy 343.524985 -293.995834) (xy 343.548657 -294.046331) (xy 343.564725 -294.099738)
			(xy 343.572845 -294.154914) (xy 343.573354 -294.1828) (xy 359.468926 -294.1828) (xy 359.472997 -294.127178)
			(xy 359.485123 -294.072741) (xy 359.505046 -294.02065) (xy 359.532342 -293.972015) (xy 359.566428 -293.927872)
			(xy 359.606577 -293.889163) (xy 359.651935 -293.856712) (xy 359.701535 -293.831211) (xy 359.754319 -293.813204)
			(xy 359.809162 -293.803074) (xy 359.864896 -293.801037) (xy 359.920333 -293.807137) (xy 359.97429 -293.821243)
			(xy 360.025619 -293.843055) (xy 360.073225 -293.872109) (xy 360.116093 -293.907784) (xy 360.15331 -293.949321)
			(xy 360.184083 -293.995834) (xy 360.207755 -294.046331) (xy 360.223823 -294.099738) (xy 360.231943 -294.154914)
			(xy 360.232452 -294.1828) (xy 360.231943 -294.210686) (xy 360.223823 -294.265862) (xy 360.207755 -294.319269)
			(xy 360.184083 -294.369766) (xy 360.15331 -294.416279) (xy 360.116093 -294.457816) (xy 360.073225 -294.493491)
			(xy 360.025619 -294.522545) (xy 359.97429 -294.544357) (xy 359.920333 -294.558463) (xy 359.864896 -294.564563)
			(xy 359.809162 -294.562526) (xy 359.754319 -294.552396) (xy 359.701535 -294.534389) (xy 359.651935 -294.508888)
			(xy 359.606577 -294.476437) (xy 359.566428 -294.437728) (xy 359.532342 -294.393585) (xy 359.505046 -294.34495)
			(xy 359.485123 -294.292859) (xy 359.472997 -294.238422) (xy 359.468926 -294.1828) (xy 343.573354 -294.1828)
			(xy 343.572845 -294.210686) (xy 343.564725 -294.265862) (xy 343.548657 -294.319269) (xy 343.524985 -294.369766)
			(xy 343.494212 -294.416279) (xy 343.456995 -294.457816) (xy 343.414127 -294.493491) (xy 343.366521 -294.522545)
			(xy 343.315192 -294.544357) (xy 343.261235 -294.558463) (xy 343.205798 -294.564563) (xy 343.150064 -294.562526)
			(xy 343.095221 -294.552396) (xy 343.042437 -294.534389) (xy 342.992837 -294.508888) (xy 342.947479 -294.476437)
			(xy 342.90733 -294.437728) (xy 342.873244 -294.393585) (xy 342.845948 -294.34495) (xy 342.826025 -294.292859)
			(xy 342.813899 -294.238422) (xy 342.809828 -294.1828) (xy 330.943966 -294.1828) (xy 330.943966 -294.851836)
			(xy 334.24698 -294.851836) (xy 334.251051 -294.796214) (xy 334.263177 -294.741777) (xy 334.2831 -294.689686)
			(xy 334.310396 -294.641051) (xy 334.344482 -294.596908) (xy 334.384631 -294.558199) (xy 334.429989 -294.525748)
			(xy 334.479589 -294.500247) (xy 334.532373 -294.48224) (xy 334.587216 -294.47211) (xy 334.64295 -294.470073)
			(xy 334.698387 -294.476173) (xy 334.752344 -294.490279) (xy 334.803673 -294.512091) (xy 334.851279 -294.541145)
			(xy 334.894147 -294.57682) (xy 334.931364 -294.618357) (xy 334.962137 -294.66487) (xy 334.985809 -294.715367)
			(xy 335.001877 -294.768774) (xy 335.009997 -294.82395) (xy 335.010506 -294.851836) (xy 349.340676 -294.851836)
			(xy 349.344747 -294.796214) (xy 349.356873 -294.741777) (xy 349.376796 -294.689686) (xy 349.404092 -294.641051)
			(xy 349.438178 -294.596908) (xy 349.478327 -294.558199) (xy 349.523685 -294.525748) (xy 349.573285 -294.500247)
			(xy 349.626069 -294.48224) (xy 349.680912 -294.47211) (xy 349.736646 -294.470073) (xy 349.792083 -294.476173)
			(xy 349.84604 -294.490279) (xy 349.897369 -294.512091) (xy 349.944975 -294.541145) (xy 349.987843 -294.57682)
			(xy 350.02506 -294.618357) (xy 350.055833 -294.66487) (xy 350.079505 -294.715367) (xy 350.095573 -294.768774)
			(xy 350.103693 -294.82395) (xy 350.104202 -294.851836) (xy 350.906078 -294.851836) (xy 350.910149 -294.796214)
			(xy 350.922275 -294.741777) (xy 350.942198 -294.689686) (xy 350.969494 -294.641051) (xy 351.00358 -294.596908)
			(xy 351.043729 -294.558199) (xy 351.089087 -294.525748) (xy 351.138687 -294.500247) (xy 351.191471 -294.48224)
			(xy 351.246314 -294.47211) (xy 351.302048 -294.470073) (xy 351.357485 -294.476173) (xy 351.411442 -294.490279)
			(xy 351.462771 -294.512091) (xy 351.510377 -294.541145) (xy 351.553245 -294.57682) (xy 351.590462 -294.618357)
			(xy 351.621235 -294.66487) (xy 351.644907 -294.715367) (xy 351.660975 -294.768774) (xy 351.669095 -294.82395)
			(xy 351.669604 -294.851836) (xy 365.999774 -294.851836) (xy 366.003845 -294.796214) (xy 366.015971 -294.741777)
			(xy 366.035894 -294.689686) (xy 366.06319 -294.641051) (xy 366.097276 -294.596908) (xy 366.137425 -294.558199)
			(xy 366.182783 -294.525748) (xy 366.232383 -294.500247) (xy 366.285167 -294.48224) (xy 366.34001 -294.47211)
			(xy 366.395744 -294.470073) (xy 366.451181 -294.476173) (xy 366.505138 -294.490279) (xy 366.556467 -294.512091)
			(xy 366.604073 -294.541145) (xy 366.646941 -294.57682) (xy 366.684158 -294.618357) (xy 366.714931 -294.66487)
			(xy 366.738603 -294.715367) (xy 366.754671 -294.768774) (xy 366.762791 -294.82395) (xy 366.7633 -294.851836)
			(xy 366.762791 -294.879722) (xy 366.754671 -294.934898) (xy 366.738603 -294.988305) (xy 366.714931 -295.038802)
			(xy 366.684158 -295.085315) (xy 366.646941 -295.126852) (xy 366.604073 -295.162527) (xy 366.556467 -295.191581)
			(xy 366.505138 -295.213393) (xy 366.451181 -295.227499) (xy 366.395744 -295.233599) (xy 366.34001 -295.231562)
			(xy 366.285167 -295.221432) (xy 366.232383 -295.203425) (xy 366.182783 -295.177924) (xy 366.137425 -295.145473)
			(xy 366.097276 -295.106764) (xy 366.06319 -295.062621) (xy 366.035894 -295.013986) (xy 366.015971 -294.961895)
			(xy 366.003845 -294.907458) (xy 365.999774 -294.851836) (xy 351.669604 -294.851836) (xy 351.669095 -294.879722)
			(xy 351.660975 -294.934898) (xy 351.644907 -294.988305) (xy 351.621235 -295.038802) (xy 351.590462 -295.085315)
			(xy 351.553245 -295.126852) (xy 351.510377 -295.162527) (xy 351.462771 -295.191581) (xy 351.411442 -295.213393)
			(xy 351.357485 -295.227499) (xy 351.302048 -295.233599) (xy 351.246314 -295.231562) (xy 351.191471 -295.221432)
			(xy 351.138687 -295.203425) (xy 351.089087 -295.177924) (xy 351.043729 -295.145473) (xy 351.00358 -295.106764)
			(xy 350.969494 -295.062621) (xy 350.942198 -295.013986) (xy 350.922275 -294.961895) (xy 350.910149 -294.907458)
			(xy 350.906078 -294.851836) (xy 350.104202 -294.851836) (xy 350.103693 -294.879722) (xy 350.095573 -294.934898)
			(xy 350.079505 -294.988305) (xy 350.055833 -295.038802) (xy 350.02506 -295.085315) (xy 349.987843 -295.126852)
			(xy 349.944975 -295.162527) (xy 349.897369 -295.191581) (xy 349.84604 -295.213393) (xy 349.792083 -295.227499)
			(xy 349.736646 -295.233599) (xy 349.680912 -295.231562) (xy 349.626069 -295.221432) (xy 349.573285 -295.203425)
			(xy 349.523685 -295.177924) (xy 349.478327 -295.145473) (xy 349.438178 -295.106764) (xy 349.404092 -295.062621)
			(xy 349.376796 -295.013986) (xy 349.356873 -294.961895) (xy 349.344747 -294.907458) (xy 349.340676 -294.851836)
			(xy 335.010506 -294.851836) (xy 335.009997 -294.879722) (xy 335.001877 -294.934898) (xy 334.985809 -294.988305)
			(xy 334.962137 -295.038802) (xy 334.931364 -295.085315) (xy 334.894147 -295.126852) (xy 334.851279 -295.162527)
			(xy 334.803673 -295.191581) (xy 334.752344 -295.213393) (xy 334.698387 -295.227499) (xy 334.64295 -295.233599)
			(xy 334.587216 -295.231562) (xy 334.532373 -295.221432) (xy 334.479589 -295.203425) (xy 334.429989 -295.177924)
			(xy 334.384631 -295.145473) (xy 334.344482 -295.106764) (xy 334.310396 -295.062621) (xy 334.2831 -295.013986)
			(xy 334.263177 -294.961895) (xy 334.251051 -294.907458) (xy 334.24698 -294.851836) (xy 330.943966 -294.851836)
			(xy 330.943966 -298.420536) (xy 335.694782 -298.420536) (xy 335.695249 -298.393166) (xy 335.703064 -298.338986)
			(xy 335.718551 -298.286482) (xy 335.741393 -298.236735) (xy 335.77112 -298.190769) (xy 335.788762 -298.169838)
			(xy 335.789016 -298.169584) (xy 335.794617 -298.162508) (xy 335.800855 -298.145583) (xy 335.801208 -298.136564)
			(xy 335.801208 -298.069508) (xy 335.800845 -298.060492) (xy 335.794602 -298.043575) (xy 335.789016 -298.036488)
			(xy 335.788762 -298.036488) (xy 335.788762 -298.036234) (xy 335.771155 -298.015273) (xy 335.741426 -297.969311)
			(xy 335.718577 -297.91957) (xy 335.703076 -297.867072) (xy 335.695243 -297.812896) (xy 335.695239 -297.758158)
			(xy 335.703064 -297.703981) (xy 335.718558 -297.651481) (xy 335.7414 -297.601736) (xy 335.771122 -297.55577)
			(xy 335.788762 -297.534838) (xy 335.789016 -297.534584) (xy 335.794617 -297.527508) (xy 335.800855 -297.510583)
			(xy 335.801208 -297.501564) (xy 335.801208 -297.434508) (xy 335.800845 -297.425492) (xy 335.794602 -297.408575)
			(xy 335.789016 -297.401488) (xy 335.788762 -297.401488) (xy 335.788762 -297.401234) (xy 335.771155 -297.380273)
			(xy 335.741426 -297.334311) (xy 335.718577 -297.28457) (xy 335.703076 -297.232072) (xy 335.695243 -297.177896)
			(xy 335.695239 -297.123158) (xy 335.703064 -297.068981) (xy 335.718558 -297.016481) (xy 335.7414 -296.966736)
			(xy 335.771122 -296.92077) (xy 335.788762 -296.899838) (xy 335.789016 -296.899584) (xy 335.794617 -296.892508)
			(xy 335.800855 -296.875583) (xy 335.801208 -296.866564) (xy 335.801208 -296.799508) (xy 335.800845 -296.790492)
			(xy 335.794602 -296.773575) (xy 335.789016 -296.766488) (xy 335.788762 -296.766488) (xy 335.788762 -296.766234)
			(xy 335.771155 -296.745273) (xy 335.741426 -296.699311) (xy 335.718577 -296.64957) (xy 335.703076 -296.597072)
			(xy 335.695243 -296.542896) (xy 335.695239 -296.488158) (xy 335.703064 -296.433981) (xy 335.718558 -296.381481)
			(xy 335.7414 -296.331736) (xy 335.771122 -296.28577) (xy 335.788762 -296.264838) (xy 335.789016 -296.264584)
			(xy 335.794617 -296.257508) (xy 335.800855 -296.240583) (xy 335.801208 -296.231564) (xy 335.801208 -296.164508)
			(xy 335.800845 -296.155492) (xy 335.794602 -296.138575) (xy 335.789016 -296.131488) (xy 335.788762 -296.131488)
			(xy 335.788762 -296.131234) (xy 335.771155 -296.110273) (xy 335.741426 -296.064311) (xy 335.718577 -296.01457)
			(xy 335.703076 -295.962072) (xy 335.695243 -295.907896) (xy 335.695239 -295.853158) (xy 335.703064 -295.798981)
			(xy 335.718558 -295.746481) (xy 335.7414 -295.696736) (xy 335.771122 -295.65077) (xy 335.788762 -295.629838)
			(xy 335.789016 -295.629584) (xy 335.794617 -295.622508) (xy 335.800855 -295.605583) (xy 335.801208 -295.596564)
			(xy 335.801208 -295.529508) (xy 335.800845 -295.520492) (xy 335.794602 -295.503575) (xy 335.789016 -295.496488)
			(xy 335.788762 -295.496488) (xy 335.788762 -295.496234) (xy 335.771119 -295.475305) (xy 335.741409 -295.429331)
			(xy 335.718574 -295.379582) (xy 335.703084 -295.327081) (xy 335.695256 -295.272905) (xy 335.694782 -295.245536)
			(xy 335.695289 -295.218284) (xy 335.703041 -295.164336) (xy 335.718392 -295.112039) (xy 335.741029 -295.06246)
			(xy 335.770492 -295.016607) (xy 335.806182 -294.975414) (xy 335.84737 -294.93972) (xy 335.893219 -294.910251)
			(xy 335.942796 -294.887608) (xy 335.995091 -294.87225) (xy 336.049039 -294.864492) (xy 336.07629 -294.864028)
			(xy 336.10366 -294.864493) (xy 336.15784 -294.87231) (xy 336.210343 -294.887799) (xy 336.26009 -294.910641)
			(xy 336.306057 -294.940366) (xy 336.326988 -294.958008) (xy 336.327242 -294.958262) (xy 336.334336 -294.963838)
			(xy 336.351247 -294.970089) (xy 336.360262 -294.970454) (xy 336.427318 -294.970454) (xy 336.436337 -294.970116)
			(xy 336.453254 -294.963856) (xy 336.460338 -294.958262) (xy 336.460338 -294.958008) (xy 336.460592 -294.958008)
			(xy 336.481517 -294.94036) (xy 336.527492 -294.91065) (xy 336.577241 -294.887815) (xy 336.629743 -294.872326)
			(xy 336.68392 -294.864501) (xy 336.71129 -294.864028) (xy 336.738544 -294.864465) (xy 336.792498 -294.872221)
			(xy 336.844799 -294.887578) (xy 336.894381 -294.910222) (xy 336.940236 -294.939692) (xy 336.98143 -294.975389)
			(xy 337.017123 -295.016585) (xy 337.046591 -295.062442) (xy 337.069231 -295.112026) (xy 337.084584 -295.164327)
			(xy 337.092337 -295.218282) (xy 337.092798 -295.245536) (xy 337.092354 -295.272907) (xy 337.084531 -295.327087)
			(xy 337.069036 -295.37959) (xy 337.04619 -295.429337) (xy 337.016461 -295.475303) (xy 336.998818 -295.496234)
			(xy 336.998564 -295.496488) (xy 336.992972 -295.503571) (xy 336.98673 -295.520491) (xy 336.986372 -295.529508)
			(xy 336.986372 -295.596564) (xy 336.986752 -295.605578) (xy 336.992984 -295.622495) (xy 336.998564 -295.629584)
			(xy 336.998818 -295.629584) (xy 336.998818 -295.629838) (xy 337.016492 -295.650743) (xy 337.046212 -295.696717)
			(xy 337.069052 -295.746468) (xy 337.084544 -295.798974) (xy 337.092368 -295.853155) (xy 337.092364 -295.907899)
			(xy 337.084532 -295.962079) (xy 337.069033 -296.014583) (xy 337.046186 -296.064331) (xy 337.016459 -296.1103)
			(xy 336.998818 -296.131234) (xy 336.998564 -296.131488) (xy 336.992972 -296.138571) (xy 336.98673 -296.155491)
			(xy 336.986372 -296.164508) (xy 336.986372 -296.231564) (xy 336.986752 -296.240578) (xy 336.992984 -296.257495)
			(xy 336.998564 -296.264584) (xy 336.998818 -296.264584) (xy 336.998818 -296.264838) (xy 337.016492 -296.285743)
			(xy 337.046212 -296.331717) (xy 337.069052 -296.381468) (xy 337.084544 -296.433974) (xy 337.092368 -296.488155)
			(xy 337.092364 -296.542899) (xy 337.084532 -296.597079) (xy 337.069033 -296.649583) (xy 337.046186 -296.699331)
			(xy 337.016459 -296.7453) (xy 336.998818 -296.766234) (xy 336.998564 -296.766488) (xy 336.992972 -296.773571)
			(xy 336.98673 -296.790491) (xy 336.986372 -296.799508) (xy 336.986372 -296.866564) (xy 336.986752 -296.875578)
			(xy 336.992984 -296.892495) (xy 336.998564 -296.899584) (xy 336.998818 -296.899584) (xy 336.998818 -296.899838)
			(xy 337.016492 -296.920743) (xy 337.046212 -296.966717) (xy 337.069052 -297.016468) (xy 337.084544 -297.068974)
			(xy 337.092368 -297.123155) (xy 337.092364 -297.177899) (xy 337.084532 -297.232079) (xy 337.069033 -297.284583)
			(xy 337.046186 -297.334331) (xy 337.016459 -297.3803) (xy 336.998818 -297.401234) (xy 336.998564 -297.401488)
			(xy 336.992972 -297.408571) (xy 336.98673 -297.425491) (xy 336.986372 -297.434508) (xy 336.986372 -297.501564)
			(xy 336.986752 -297.510578) (xy 336.992984 -297.527495) (xy 336.998564 -297.534584) (xy 336.998818 -297.534584)
			(xy 336.998818 -297.534838) (xy 337.016492 -297.555743) (xy 337.046212 -297.601717) (xy 337.069052 -297.651468)
			(xy 337.084544 -297.703974) (xy 337.092368 -297.758155) (xy 337.092364 -297.812899) (xy 337.084532 -297.867079)
			(xy 337.069033 -297.919583) (xy 337.046186 -297.969331) (xy 337.016459 -298.0153) (xy 336.998818 -298.036234)
			(xy 336.998564 -298.036488) (xy 336.992972 -298.043571) (xy 336.98673 -298.060491) (xy 336.986372 -298.069508)
			(xy 336.986372 -298.136564) (xy 336.986752 -298.145578) (xy 336.992984 -298.162495) (xy 336.998564 -298.169584)
			(xy 336.998818 -298.169584) (xy 336.998818 -298.169838) (xy 337.016444 -298.19078) (xy 337.046157 -298.236751)
			(xy 337.068996 -298.286496) (xy 337.08449 -298.338994) (xy 337.092322 -298.393168) (xy 337.092798 -298.420536)
			(xy 340.335362 -298.420536) (xy 340.335834 -298.393166) (xy 340.343648 -298.338986) (xy 340.359135 -298.286483)
			(xy 340.381976 -298.236736) (xy 340.4117 -298.190769) (xy 340.429342 -298.169838) (xy 340.429596 -298.169584)
			(xy 340.435195 -298.162506) (xy 340.441434 -298.145583) (xy 340.441788 -298.136564) (xy 340.441788 -298.069508)
			(xy 340.44143 -298.060491) (xy 340.435183 -298.043574) (xy 340.429596 -298.036488) (xy 340.429342 -298.036488)
			(xy 340.429342 -298.036234) (xy 340.411736 -298.015273) (xy 340.382009 -297.969311) (xy 340.35916 -297.919569)
			(xy 340.34366 -297.867071) (xy 340.335828 -297.812896) (xy 340.335824 -297.758158) (xy 340.343649 -297.703982)
			(xy 340.359141 -297.651482) (xy 340.381982 -297.601737) (xy 340.411703 -297.55577) (xy 340.429342 -297.534838)
			(xy 340.429596 -297.534584) (xy 340.435195 -297.527506) (xy 340.441434 -297.510583) (xy 340.441788 -297.501564)
			(xy 340.441788 -297.434508) (xy 340.44143 -297.425491) (xy 340.435183 -297.408574) (xy 340.429596 -297.401488)
			(xy 340.429342 -297.401488) (xy 340.429342 -297.401234) (xy 340.411736 -297.380273) (xy 340.382009 -297.334311)
			(xy 340.35916 -297.284569) (xy 340.34366 -297.232071) (xy 340.335828 -297.177896) (xy 340.335824 -297.123158)
			(xy 340.343649 -297.068982) (xy 340.359141 -297.016482) (xy 340.381982 -296.966737) (xy 340.411703 -296.92077)
			(xy 340.429342 -296.899838) (xy 340.429596 -296.899584) (xy 340.435195 -296.892506) (xy 340.441434 -296.875583)
			(xy 340.441788 -296.866564) (xy 340.441788 -296.799508) (xy 340.44143 -296.790491) (xy 340.435183 -296.773574)
			(xy 340.429596 -296.766488) (xy 340.429342 -296.766488) (xy 340.429342 -296.766234) (xy 340.411736 -296.745273)
			(xy 340.382009 -296.699311) (xy 340.35916 -296.649569) (xy 340.34366 -296.597071) (xy 340.335828 -296.542896)
			(xy 340.335824 -296.488158) (xy 340.343649 -296.433982) (xy 340.359141 -296.381482) (xy 340.381982 -296.331737)
			(xy 340.411703 -296.28577) (xy 340.429342 -296.264838) (xy 340.429596 -296.264584) (xy 340.435195 -296.257506)
			(xy 340.441434 -296.240583) (xy 340.441788 -296.231564) (xy 340.441788 -296.164508) (xy 340.44143 -296.155491)
			(xy 340.435183 -296.138574) (xy 340.429596 -296.131488) (xy 340.429342 -296.131488) (xy 340.429342 -296.131234)
			(xy 340.411736 -296.110273) (xy 340.382009 -296.064311) (xy 340.35916 -296.014569) (xy 340.34366 -295.962071)
			(xy 340.335828 -295.907896) (xy 340.335824 -295.853158) (xy 340.343649 -295.798982) (xy 340.359141 -295.746482)
			(xy 340.381982 -295.696737) (xy 340.411703 -295.65077) (xy 340.429342 -295.629838) (xy 340.429596 -295.629584)
			(xy 340.435195 -295.622506) (xy 340.441434 -295.605583) (xy 340.441788 -295.596564) (xy 340.441788 -295.529508)
			(xy 340.44143 -295.520491) (xy 340.435183 -295.503574) (xy 340.429596 -295.496488) (xy 340.429342 -295.496488)
			(xy 340.429342 -295.496234) (xy 340.411712 -295.475295) (xy 340.381997 -295.429324) (xy 340.359159 -295.379579)
			(xy 340.343666 -295.32708) (xy 340.335836 -295.272905) (xy 340.335362 -295.245536) (xy 340.335889 -295.218285)
			(xy 340.34364 -295.164338) (xy 340.35899 -295.112043) (xy 340.381626 -295.062465) (xy 340.411088 -295.016614)
			(xy 340.446775 -294.975421) (xy 340.487961 -294.939727) (xy 340.533807 -294.910258) (xy 340.583382 -294.887613)
			(xy 340.635674 -294.872254) (xy 340.689619 -294.864493) (xy 340.71687 -294.864028) (xy 340.74424 -294.864505)
			(xy 340.798419 -294.872319) (xy 340.850922 -294.887805) (xy 340.900669 -294.910645) (xy 340.946636 -294.940367)
			(xy 340.967568 -294.958008) (xy 340.967822 -294.958262) (xy 340.974893 -294.963871) (xy 340.991822 -294.970103)
			(xy 341.000842 -294.970454) (xy 341.067898 -294.970454) (xy 341.076916 -294.970106) (xy 341.093833 -294.963853)
			(xy 341.100918 -294.958262) (xy 341.100918 -294.958008) (xy 341.101172 -294.958008) (xy 341.122105 -294.94037)
			(xy 341.168077 -294.910658) (xy 341.217825 -294.887821) (xy 341.270325 -294.87233) (xy 341.324501 -294.864502)
			(xy 341.35187 -294.864028) (xy 341.379124 -294.864483) (xy 341.433077 -294.872237) (xy 341.485377 -294.887591)
			(xy 341.534959 -294.910233) (xy 341.580814 -294.939701) (xy 341.622008 -294.975396) (xy 341.657703 -295.01659)
			(xy 341.68717 -295.062446) (xy 341.709811 -295.112029) (xy 341.725164 -295.164329) (xy 341.732917 -295.218282)
			(xy 341.733378 -295.245536) (xy 341.732938 -295.272907) (xy 341.725115 -295.327088) (xy 341.70962 -295.379591)
			(xy 341.686772 -295.429338) (xy 341.657042 -295.475303) (xy 341.639398 -295.496234) (xy 341.639144 -295.496488)
			(xy 341.63355 -295.503569) (xy 341.627309 -295.52049) (xy 341.626952 -295.529508) (xy 341.626952 -295.596564)
			(xy 341.627315 -295.60558) (xy 341.633557 -295.622498) (xy 341.639144 -295.629584) (xy 341.639398 -295.629584)
			(xy 341.639398 -295.629838) (xy 341.657073 -295.650743) (xy 341.686794 -295.696716) (xy 341.709636 -295.746467)
			(xy 341.725128 -295.798973) (xy 341.732953 -295.853155) (xy 341.732949 -295.907899) (xy 341.725117 -295.96208)
			(xy 341.709617 -296.014584) (xy 341.686768 -296.064332) (xy 341.65704 -296.110301) (xy 341.639398 -296.131234)
			(xy 341.639144 -296.131488) (xy 341.63355 -296.138569) (xy 341.627309 -296.15549) (xy 341.626952 -296.164508)
			(xy 341.626952 -296.231564) (xy 341.627315 -296.24058) (xy 341.633557 -296.257498) (xy 341.639144 -296.264584)
			(xy 341.639398 -296.264584) (xy 341.639398 -296.264838) (xy 341.657073 -296.285743) (xy 341.686794 -296.331716)
			(xy 341.709636 -296.381467) (xy 341.725128 -296.433973) (xy 341.732953 -296.488155) (xy 341.732949 -296.542899)
			(xy 341.725117 -296.59708) (xy 341.709617 -296.649584) (xy 341.686768 -296.699332) (xy 341.65704 -296.745301)
			(xy 341.639398 -296.766234) (xy 341.639144 -296.766488) (xy 341.63355 -296.773569) (xy 341.627309 -296.79049)
			(xy 341.626952 -296.799508) (xy 341.626952 -296.866564) (xy 341.627315 -296.87558) (xy 341.633557 -296.892498)
			(xy 341.639144 -296.899584) (xy 341.639398 -296.899584) (xy 341.639398 -296.899838) (xy 341.657073 -296.920743)
			(xy 341.686794 -296.966716) (xy 341.709636 -297.016467) (xy 341.725128 -297.068973) (xy 341.732953 -297.123155)
			(xy 341.732949 -297.177899) (xy 341.725117 -297.23208) (xy 341.709617 -297.284584) (xy 341.686768 -297.334332)
			(xy 341.65704 -297.380301) (xy 341.639398 -297.401234) (xy 341.639144 -297.401488) (xy 341.63355 -297.408569)
			(xy 341.627309 -297.42549) (xy 341.626952 -297.434508) (xy 341.626952 -297.501564) (xy 341.627315 -297.51058)
			(xy 341.633557 -297.527498) (xy 341.639144 -297.534584) (xy 341.639398 -297.534584) (xy 341.639398 -297.534838)
			(xy 341.657073 -297.555743) (xy 341.686794 -297.601716) (xy 341.709636 -297.651467) (xy 341.725128 -297.703973)
			(xy 341.732953 -297.758155) (xy 341.732949 -297.812899) (xy 341.725117 -297.86708) (xy 341.709617 -297.919584)
			(xy 341.686768 -297.969332) (xy 341.65704 -298.015301) (xy 341.639398 -298.036234) (xy 341.639144 -298.036488)
			(xy 341.63355 -298.043569) (xy 341.627309 -298.06049) (xy 341.626952 -298.069508) (xy 341.626952 -298.136564)
			(xy 341.627315 -298.14558) (xy 341.633557 -298.162498) (xy 341.639144 -298.169584) (xy 341.639398 -298.169584)
			(xy 341.639398 -298.169838) (xy 341.657021 -298.190783) (xy 341.686735 -298.236752) (xy 341.709575 -298.286496)
			(xy 341.725069 -298.338994) (xy 341.732902 -298.393168) (xy 341.733378 -298.420536) (xy 342.763094 -298.420536)
			(xy 342.763583 -298.393167) (xy 342.771395 -298.338989) (xy 342.786879 -298.286486) (xy 342.809716 -298.236739)
			(xy 342.839435 -298.190771) (xy 342.857074 -298.169838) (xy 342.857328 -298.169584) (xy 342.862931 -298.162508)
			(xy 342.869167 -298.145583) (xy 342.86952 -298.136564) (xy 342.86952 -298.069508) (xy 342.869155 -298.060492)
			(xy 342.862912 -298.043575) (xy 342.857328 -298.036488) (xy 342.857074 -298.036488) (xy 342.857074 -298.036234)
			(xy 342.839467 -298.015274) (xy 342.809737 -297.969312) (xy 342.786886 -297.91957) (xy 342.771385 -297.867072)
			(xy 342.763552 -297.812897) (xy 342.763548 -297.758158) (xy 342.771374 -297.703981) (xy 342.786867 -297.65148)
			(xy 342.809711 -297.601736) (xy 342.839434 -297.55577) (xy 342.857074 -297.534838) (xy 342.857328 -297.534584)
			(xy 342.862931 -297.527508) (xy 342.869167 -297.510583) (xy 342.86952 -297.501564) (xy 342.86952 -297.434508)
			(xy 342.869155 -297.425492) (xy 342.862912 -297.408575) (xy 342.857328 -297.401488) (xy 342.857074 -297.401488)
			(xy 342.857074 -297.401234) (xy 342.839467 -297.380274) (xy 342.809737 -297.334312) (xy 342.786886 -297.28457)
			(xy 342.771385 -297.232072) (xy 342.763552 -297.177897) (xy 342.763548 -297.123158) (xy 342.771374 -297.068981)
			(xy 342.786867 -297.01648) (xy 342.809711 -296.966736) (xy 342.839434 -296.92077) (xy 342.857074 -296.899838)
			(xy 342.857328 -296.899584) (xy 342.862931 -296.892508) (xy 342.869167 -296.875583) (xy 342.86952 -296.866564)
			(xy 342.86952 -296.799508) (xy 342.869155 -296.790492) (xy 342.862912 -296.773575) (xy 342.857328 -296.766488)
			(xy 342.857074 -296.766488) (xy 342.857074 -296.766234) (xy 342.839467 -296.745274) (xy 342.809737 -296.699312)
			(xy 342.786886 -296.64957) (xy 342.771385 -296.597072) (xy 342.763552 -296.542897) (xy 342.763548 -296.488158)
			(xy 342.771374 -296.433981) (xy 342.786867 -296.38148) (xy 342.809711 -296.331736) (xy 342.839434 -296.28577)
			(xy 342.857074 -296.264838) (xy 342.857328 -296.264584) (xy 342.862931 -296.257508) (xy 342.869167 -296.240583)
			(xy 342.86952 -296.231564) (xy 342.86952 -296.164508) (xy 342.869155 -296.155492) (xy 342.862912 -296.138575)
			(xy 342.857328 -296.131488) (xy 342.857074 -296.131488) (xy 342.857074 -296.131234) (xy 342.839467 -296.110274)
			(xy 342.809737 -296.064312) (xy 342.786886 -296.01457) (xy 342.771385 -295.962072) (xy 342.763552 -295.907897)
			(xy 342.763548 -295.853158) (xy 342.771374 -295.798981) (xy 342.786867 -295.74648) (xy 342.809711 -295.696736)
			(xy 342.839434 -295.65077) (xy 342.857074 -295.629838) (xy 342.857328 -295.629584) (xy 342.862931 -295.622508)
			(xy 342.869167 -295.605583) (xy 342.86952 -295.596564) (xy 342.86952 -295.529508) (xy 342.869155 -295.520492)
			(xy 342.862912 -295.503575) (xy 342.857328 -295.496488) (xy 342.857074 -295.496488) (xy 342.857074 -295.496234)
			(xy 342.839433 -295.475303) (xy 342.809723 -295.42933) (xy 342.786887 -295.379582) (xy 342.771397 -295.327081)
			(xy 342.763568 -295.272905) (xy 342.763094 -295.245536) (xy 342.763589 -295.218284) (xy 342.771341 -295.164334)
			(xy 342.786692 -295.112037) (xy 342.809331 -295.062457) (xy 342.838795 -295.016603) (xy 342.874486 -294.97541)
			(xy 342.915676 -294.939716) (xy 342.961527 -294.910247) (xy 343.011105 -294.887604) (xy 343.063401 -294.872248)
			(xy 343.11735 -294.864491) (xy 343.144602 -294.864028) (xy 343.171973 -294.864486) (xy 343.226152 -294.872305)
			(xy 343.278656 -294.887795) (xy 343.328403 -294.910639) (xy 343.374369 -294.940366) (xy 343.3953 -294.958008)
			(xy 343.395554 -294.958262) (xy 343.402644 -294.963843) (xy 343.419558 -294.970091) (xy 343.428574 -294.970454)
			(xy 343.49563 -294.970454) (xy 343.50465 -294.970121) (xy 343.521567 -294.963858) (xy 343.52865 -294.958262)
			(xy 343.52865 -294.958008) (xy 343.528904 -294.958008) (xy 343.549825 -294.940355) (xy 343.595801 -294.910645)
			(xy 343.645551 -294.887811) (xy 343.698054 -294.872324) (xy 343.752232 -294.8645) (xy 343.779602 -294.864028)
			(xy 343.806857 -294.864454) (xy 343.860811 -294.872212) (xy 343.913111 -294.88757) (xy 343.962694 -294.910215)
			(xy 344.008549 -294.939687) (xy 344.049742 -294.975385) (xy 344.085436 -295.016582) (xy 344.114903 -295.062439)
			(xy 344.137543 -295.112024) (xy 344.152896 -295.164326) (xy 344.160649 -295.218281) (xy 344.16111 -295.245536)
			(xy 344.160663 -295.272907) (xy 344.15284 -295.327087) (xy 344.137346 -295.37959) (xy 344.114501 -295.429336)
			(xy 344.084773 -295.475303) (xy 344.06713 -295.496234) (xy 344.066876 -295.496488) (xy 344.061286 -295.503572)
			(xy 344.055042 -295.520491) (xy 344.054684 -295.529508) (xy 344.054684 -295.596564) (xy 344.055062 -295.605579)
			(xy 344.061295 -295.622496) (xy 344.066876 -295.629584) (xy 344.06713 -295.629584) (xy 344.06713 -295.629838)
			(xy 344.084808 -295.650741) (xy 344.114534 -295.696713) (xy 344.13738 -295.746464) (xy 344.152876 -295.798971)
			(xy 344.160702 -295.853154) (xy 344.160698 -295.9079) (xy 344.152864 -295.962082) (xy 344.137361 -296.014587)
			(xy 344.114508 -296.064334) (xy 344.084775 -296.110302) (xy 344.06713 -296.131234) (xy 344.066876 -296.131488)
			(xy 344.061286 -296.138572) (xy 344.055042 -296.155491) (xy 344.054684 -296.164508) (xy 344.054684 -296.231564)
			(xy 344.055062 -296.240579) (xy 344.061295 -296.257496) (xy 344.066876 -296.264584) (xy 344.06713 -296.264584)
			(xy 344.06713 -296.264838) (xy 344.084808 -296.285741) (xy 344.114534 -296.331713) (xy 344.13738 -296.381464)
			(xy 344.152876 -296.433971) (xy 344.160702 -296.488154) (xy 344.160698 -296.5429) (xy 344.152864 -296.597082)
			(xy 344.137361 -296.649587) (xy 344.114508 -296.699334) (xy 344.084775 -296.745302) (xy 344.06713 -296.766234)
			(xy 344.066876 -296.766488) (xy 344.061286 -296.773572) (xy 344.055042 -296.790491) (xy 344.054684 -296.799508)
			(xy 344.054684 -296.866564) (xy 344.055062 -296.875579) (xy 344.061295 -296.892496) (xy 344.066876 -296.899584)
			(xy 344.06713 -296.899584) (xy 344.06713 -296.899838) (xy 344.084808 -296.920741) (xy 344.114534 -296.966713)
			(xy 344.13738 -297.016464) (xy 344.152876 -297.068971) (xy 344.160702 -297.123154) (xy 344.160698 -297.1779)
			(xy 344.152864 -297.232082) (xy 344.137361 -297.284587) (xy 344.114508 -297.334334) (xy 344.084775 -297.380302)
			(xy 344.06713 -297.401234) (xy 344.066876 -297.401488) (xy 344.061286 -297.408572) (xy 344.055042 -297.425491)
			(xy 344.054684 -297.434508) (xy 344.054684 -297.501564) (xy 344.055062 -297.510579) (xy 344.061295 -297.527496)
			(xy 344.066876 -297.534584) (xy 344.06713 -297.534584) (xy 344.06713 -297.534838) (xy 344.084808 -297.555741)
			(xy 344.114534 -297.601713) (xy 344.13738 -297.651464) (xy 344.152876 -297.703971) (xy 344.160702 -297.758154)
			(xy 344.160698 -297.8129) (xy 344.152864 -297.867082) (xy 344.137361 -297.919587) (xy 344.114508 -297.969334)
			(xy 344.084775 -298.015302) (xy 344.06713 -298.036234) (xy 344.066876 -298.036488) (xy 344.061286 -298.043572)
			(xy 344.055042 -298.060491) (xy 344.054684 -298.069508) (xy 344.054684 -298.136564) (xy 344.055062 -298.145579)
			(xy 344.061295 -298.162496) (xy 344.066876 -298.169584) (xy 344.06713 -298.169584) (xy 344.06713 -298.169838)
			(xy 344.084758 -298.190779) (xy 344.114471 -298.23675) (xy 344.137308 -298.286495) (xy 344.152802 -298.338994)
			(xy 344.160634 -298.393168) (xy 344.16111 -298.420536) (xy 347.403674 -298.420536) (xy 347.404143 -298.393166)
			(xy 347.411957 -298.338986) (xy 347.427445 -298.286482) (xy 347.450286 -298.236735) (xy 347.480012 -298.190769)
			(xy 347.497654 -298.169838) (xy 347.497908 -298.169584) (xy 347.503508 -298.162507) (xy 347.509746 -298.145583)
			(xy 347.5101 -298.136564) (xy 347.5101 -298.069508) (xy 347.509739 -298.060492) (xy 347.503494 -298.043575)
			(xy 347.497908 -298.036488) (xy 347.497654 -298.036488) (xy 347.497654 -298.036234) (xy 347.480047 -298.015273)
			(xy 347.450319 -297.969311) (xy 347.42747 -297.91957) (xy 347.41197 -297.867071) (xy 347.404137 -297.812896)
			(xy 347.404133 -297.758158) (xy 347.411958 -297.703982) (xy 347.427451 -297.651481) (xy 347.450293 -297.601737)
			(xy 347.480015 -297.55577) (xy 347.497654 -297.534838) (xy 347.497908 -297.534584) (xy 347.503508 -297.527507)
			(xy 347.509746 -297.510583) (xy 347.5101 -297.501564) (xy 347.5101 -297.434508) (xy 347.509739 -297.425492)
			(xy 347.503494 -297.408575) (xy 347.497908 -297.401488) (xy 347.497654 -297.401488) (xy 347.497654 -297.401234)
			(xy 347.480047 -297.380273) (xy 347.450319 -297.334311) (xy 347.42747 -297.28457) (xy 347.41197 -297.232071)
			(xy 347.404137 -297.177896) (xy 347.404133 -297.123158) (xy 347.411958 -297.068982) (xy 347.427451 -297.016481)
			(xy 347.450293 -296.966737) (xy 347.480015 -296.92077) (xy 347.497654 -296.899838) (xy 347.497908 -296.899584)
			(xy 347.503508 -296.892507) (xy 347.509746 -296.875583) (xy 347.5101 -296.866564) (xy 347.5101 -296.799508)
			(xy 347.509739 -296.790492) (xy 347.503494 -296.773575) (xy 347.497908 -296.766488) (xy 347.497654 -296.766488)
			(xy 347.497654 -296.766234) (xy 347.480047 -296.745273) (xy 347.450319 -296.699311) (xy 347.42747 -296.64957)
			(xy 347.41197 -296.597071) (xy 347.404137 -296.542896) (xy 347.404133 -296.488158) (xy 347.411958 -296.433982)
			(xy 347.427451 -296.381481) (xy 347.450293 -296.331737) (xy 347.480015 -296.28577) (xy 347.497654 -296.264838)
			(xy 347.497908 -296.264584) (xy 347.503508 -296.257507) (xy 347.509746 -296.240583) (xy 347.5101 -296.231564)
			(xy 347.5101 -296.164508) (xy 347.509739 -296.155492) (xy 347.503494 -296.138575) (xy 347.497908 -296.131488)
			(xy 347.497654 -296.131488) (xy 347.497654 -296.131234) (xy 347.480047 -296.110273) (xy 347.450319 -296.064311)
			(xy 347.42747 -296.01457) (xy 347.41197 -295.962071) (xy 347.404137 -295.907896) (xy 347.404133 -295.853158)
			(xy 347.411958 -295.798982) (xy 347.427451 -295.746481) (xy 347.450293 -295.696737) (xy 347.480015 -295.65077)
			(xy 347.497654 -295.629838) (xy 347.497908 -295.629584) (xy 347.503508 -295.622507) (xy 347.509746 -295.605583)
			(xy 347.5101 -295.596564) (xy 347.5101 -295.529508) (xy 347.509739 -295.520492) (xy 347.503494 -295.503575)
			(xy 347.497908 -295.496488) (xy 347.497654 -295.496488) (xy 347.497654 -295.496234) (xy 347.480026 -295.475293)
			(xy 347.45031 -295.429323) (xy 347.427472 -295.379578) (xy 347.411978 -295.327079) (xy 347.404148 -295.272905)
			(xy 347.403674 -295.245536) (xy 347.404189 -295.218285) (xy 347.41194 -295.164337) (xy 347.427291 -295.112041)
			(xy 347.449928 -295.062462) (xy 347.47939 -295.01661) (xy 347.515079 -294.975417) (xy 347.556266 -294.939723)
			(xy 347.602115 -294.910254) (xy 347.65169 -294.88761) (xy 347.703984 -294.872252) (xy 347.757931 -294.864493)
			(xy 347.785182 -294.864028) (xy 347.812552 -294.864498) (xy 347.866731 -294.872314) (xy 347.919235 -294.887802)
			(xy 347.968982 -294.910643) (xy 348.014948 -294.940367) (xy 348.03588 -294.958008) (xy 348.036134 -294.958262)
			(xy 348.04323 -294.963834) (xy 348.06014 -294.970088) (xy 348.069154 -294.970454) (xy 348.13621 -294.970454)
			(xy 348.145229 -294.970111) (xy 348.162146 -294.963855) (xy 348.16923 -294.958262) (xy 348.16923 -294.958008)
			(xy 348.169484 -294.958008) (xy 348.190412 -294.940364) (xy 348.236386 -294.910653) (xy 348.286134 -294.887818)
			(xy 348.338636 -294.872328) (xy 348.392813 -294.864501) (xy 348.420182 -294.864028) (xy 348.447436 -294.864472)
			(xy 348.50139 -294.872228) (xy 348.55369 -294.887583) (xy 348.603272 -294.910226) (xy 348.649127 -294.939696)
			(xy 348.690321 -294.975392) (xy 348.726015 -295.016587) (xy 348.755482 -295.062443) (xy 348.778123 -295.112027)
			(xy 348.793476 -295.164328) (xy 348.801229 -295.218282) (xy 348.80169 -295.245536) (xy 348.801247 -295.272907)
			(xy 348.793424 -295.327087) (xy 348.77793 -295.379591) (xy 348.755083 -295.429337) (xy 348.725353 -295.475303)
			(xy 348.70771 -295.496234) (xy 348.707456 -295.496488) (xy 348.701863 -295.50357) (xy 348.695621 -295.52049)
			(xy 348.695264 -295.529508) (xy 348.695264 -295.596564) (xy 348.695646 -295.605578) (xy 348.701877 -295.622495)
			(xy 348.707456 -295.629584) (xy 348.70771 -295.629584) (xy 348.70771 -295.629838) (xy 348.725384 -295.650743)
			(xy 348.755105 -295.696716) (xy 348.777946 -295.746468) (xy 348.793438 -295.798974) (xy 348.801262 -295.853155)
			(xy 348.801258 -295.907899) (xy 348.793426 -295.96208) (xy 348.777927 -296.014583) (xy 348.755079 -296.064331)
			(xy 348.725352 -296.1103) (xy 348.70771 -296.131234) (xy 348.707456 -296.131488) (xy 348.701863 -296.13857)
			(xy 348.695621 -296.15549) (xy 348.695264 -296.164508) (xy 348.695264 -296.231564) (xy 348.695646 -296.240578)
			(xy 348.701877 -296.257495) (xy 348.707456 -296.264584) (xy 348.70771 -296.264584) (xy 348.70771 -296.264838)
			(xy 348.725384 -296.285743) (xy 348.755105 -296.331716) (xy 348.777946 -296.381468) (xy 348.793438 -296.433974)
			(xy 348.801262 -296.488155) (xy 348.801258 -296.542899) (xy 348.793426 -296.59708) (xy 348.777927 -296.649583)
			(xy 348.755079 -296.699331) (xy 348.725352 -296.7453) (xy 348.70771 -296.766234) (xy 348.707456 -296.766488)
			(xy 348.701863 -296.77357) (xy 348.695621 -296.79049) (xy 348.695264 -296.799508) (xy 348.695264 -296.866564)
			(xy 348.695646 -296.875578) (xy 348.701877 -296.892495) (xy 348.707456 -296.899584) (xy 348.70771 -296.899584)
			(xy 348.70771 -296.899838) (xy 348.725384 -296.920743) (xy 348.755105 -296.966716) (xy 348.777946 -297.016468)
			(xy 348.793438 -297.068974) (xy 348.801262 -297.123155) (xy 348.801258 -297.177899) (xy 348.793426 -297.23208)
			(xy 348.777927 -297.284583) (xy 348.755079 -297.334331) (xy 348.725352 -297.3803) (xy 348.70771 -297.401234)
			(xy 348.707456 -297.401488) (xy 348.701863 -297.40857) (xy 348.695621 -297.42549) (xy 348.695264 -297.434508)
			(xy 348.695264 -297.501564) (xy 348.695646 -297.510578) (xy 348.701877 -297.527495) (xy 348.707456 -297.534584)
			(xy 348.70771 -297.534584) (xy 348.70771 -297.534838) (xy 348.725384 -297.555743) (xy 348.755105 -297.601716)
			(xy 348.777946 -297.651468) (xy 348.793438 -297.703974) (xy 348.801262 -297.758155) (xy 348.801258 -297.812899)
			(xy 348.793426 -297.86708) (xy 348.777927 -297.919583) (xy 348.755079 -297.969331) (xy 348.725352 -298.0153)
			(xy 348.70771 -298.036234) (xy 348.707456 -298.036488) (xy 348.701863 -298.04357) (xy 348.695621 -298.06049)
			(xy 348.695264 -298.069508) (xy 348.695264 -298.136564) (xy 348.695646 -298.145578) (xy 348.701877 -298.162495)
			(xy 348.707456 -298.169584) (xy 348.70771 -298.169584) (xy 348.70771 -298.169838) (xy 348.725335 -298.190781)
			(xy 348.755049 -298.236751) (xy 348.777887 -298.286496) (xy 348.793382 -298.338994) (xy 348.801214 -298.393168)
			(xy 348.80169 -298.420536) (xy 352.35388 -298.420536) (xy 352.354348 -298.393166) (xy 352.362162 -298.338986)
			(xy 352.37765 -298.286482) (xy 352.400492 -298.236735) (xy 352.430218 -298.190769) (xy 352.44786 -298.169838)
			(xy 352.448114 -298.169584) (xy 352.453715 -298.162507) (xy 352.459953 -298.145583) (xy 352.460306 -298.136564)
			(xy 352.460306 -298.069508) (xy 352.459944 -298.060492) (xy 352.4537 -298.043575) (xy 352.448114 -298.036488)
			(xy 352.44786 -298.036488) (xy 352.44786 -298.036234) (xy 352.430253 -298.015273) (xy 352.400524 -297.969311)
			(xy 352.377675 -297.91957) (xy 352.362174 -297.867072) (xy 352.354342 -297.812896) (xy 352.354338 -297.758158)
			(xy 352.362163 -297.703981) (xy 352.377656 -297.651481) (xy 352.400498 -297.601736) (xy 352.43022 -297.55577)
			(xy 352.44786 -297.534838) (xy 352.448114 -297.534584) (xy 352.453715 -297.527507) (xy 352.459953 -297.510583)
			(xy 352.460306 -297.501564) (xy 352.460306 -297.434508) (xy 352.459944 -297.425492) (xy 352.4537 -297.408575)
			(xy 352.448114 -297.401488) (xy 352.44786 -297.401488) (xy 352.44786 -297.401234) (xy 352.430253 -297.380273)
			(xy 352.400524 -297.334311) (xy 352.377675 -297.28457) (xy 352.362174 -297.232072) (xy 352.354342 -297.177896)
			(xy 352.354338 -297.123158) (xy 352.362163 -297.068981) (xy 352.377656 -297.016481) (xy 352.400498 -296.966736)
			(xy 352.43022 -296.92077) (xy 352.44786 -296.899838) (xy 352.448114 -296.899584) (xy 352.453715 -296.892507)
			(xy 352.459953 -296.875583) (xy 352.460306 -296.866564) (xy 352.460306 -296.799508) (xy 352.459944 -296.790492)
			(xy 352.4537 -296.773575) (xy 352.448114 -296.766488) (xy 352.44786 -296.766488) (xy 352.44786 -296.766234)
			(xy 352.430253 -296.745273) (xy 352.400524 -296.699311) (xy 352.377675 -296.64957) (xy 352.362174 -296.597072)
			(xy 352.354342 -296.542896) (xy 352.354338 -296.488158) (xy 352.362163 -296.433981) (xy 352.377656 -296.381481)
			(xy 352.400498 -296.331736) (xy 352.43022 -296.28577) (xy 352.44786 -296.264838) (xy 352.448114 -296.264584)
			(xy 352.453715 -296.257507) (xy 352.459953 -296.240583) (xy 352.460306 -296.231564) (xy 352.460306 -296.164508)
			(xy 352.459944 -296.155492) (xy 352.4537 -296.138575) (xy 352.448114 -296.131488) (xy 352.44786 -296.131488)
			(xy 352.44786 -296.131234) (xy 352.430253 -296.110273) (xy 352.400524 -296.064311) (xy 352.377675 -296.01457)
			(xy 352.362174 -295.962072) (xy 352.354342 -295.907896) (xy 352.354338 -295.853158) (xy 352.362163 -295.798981)
			(xy 352.377656 -295.746481) (xy 352.400498 -295.696736) (xy 352.43022 -295.65077) (xy 352.44786 -295.629838)
			(xy 352.448114 -295.629584) (xy 352.453715 -295.622507) (xy 352.459953 -295.605583) (xy 352.460306 -295.596564)
			(xy 352.460306 -295.529508) (xy 352.459944 -295.520492) (xy 352.4537 -295.503575) (xy 352.448114 -295.496488)
			(xy 352.44786 -295.496488) (xy 352.44786 -295.496234) (xy 352.430217 -295.475305) (xy 352.400507 -295.429331)
			(xy 352.377672 -295.379583) (xy 352.362182 -295.327081) (xy 352.354354 -295.272905) (xy 352.35388 -295.245536)
			(xy 352.354389 -295.218285) (xy 352.362141 -295.164336) (xy 352.377491 -295.11204) (xy 352.400129 -295.06246)
			(xy 352.429592 -295.016608) (xy 352.465281 -294.975415) (xy 352.506469 -294.939721) (xy 352.552318 -294.910252)
			(xy 352.601895 -294.887608) (xy 352.654189 -294.872251) (xy 352.708137 -294.864492) (xy 352.735388 -294.864028)
			(xy 352.762758 -294.864494) (xy 352.816938 -294.872311) (xy 352.869441 -294.8878) (xy 352.919188 -294.910642)
			(xy 352.965155 -294.940366) (xy 352.986086 -294.958008) (xy 352.98634 -294.958262) (xy 352.993434 -294.963837)
			(xy 353.010345 -294.970089) (xy 353.01936 -294.970454) (xy 353.086416 -294.970454) (xy 353.095435 -294.970115)
			(xy 353.112352 -294.963856) (xy 353.119436 -294.958262) (xy 353.119436 -294.958008) (xy 353.11969 -294.958008)
			(xy 353.140616 -294.940361) (xy 353.18659 -294.91065) (xy 353.236339 -294.887816) (xy 353.288841 -294.872327)
			(xy 353.343018 -294.864501) (xy 353.370388 -294.864028) (xy 353.397642 -294.864467) (xy 353.451596 -294.872223)
			(xy 353.503896 -294.887579) (xy 353.553479 -294.910223) (xy 353.599334 -294.939693) (xy 353.640528 -294.975389)
			(xy 353.676221 -295.016585) (xy 353.705689 -295.062442) (xy 353.728329 -295.112026) (xy 353.743682 -295.164328)
			(xy 353.751435 -295.218282) (xy 353.751896 -295.245536) (xy 353.751452 -295.272907) (xy 353.743629 -295.327087)
			(xy 353.728135 -295.379591) (xy 353.705288 -295.429337) (xy 353.675559 -295.475303) (xy 353.657916 -295.496234)
			(xy 353.657662 -295.496488) (xy 353.65207 -295.503571) (xy 353.645828 -295.520491) (xy 353.64547 -295.529508)
			(xy 353.64547 -295.596564) (xy 353.645851 -295.605578) (xy 353.652083 -295.622495) (xy 353.657662 -295.629584)
			(xy 353.657916 -295.629584) (xy 353.657916 -295.629838) (xy 353.67559 -295.650743) (xy 353.70531 -295.696717)
			(xy 353.728151 -295.746468) (xy 353.743643 -295.798974) (xy 353.751467 -295.853155) (xy 353.751463 -295.907899)
			(xy 353.743631 -295.962079) (xy 353.728132 -296.014583) (xy 353.705284 -296.064331) (xy 353.675557 -296.1103)
			(xy 353.657916 -296.131234) (xy 353.657662 -296.131488) (xy 353.65207 -296.138571) (xy 353.645828 -296.155491)
			(xy 353.64547 -296.164508) (xy 353.64547 -296.231564) (xy 353.645851 -296.240578) (xy 353.652083 -296.257495)
			(xy 353.657662 -296.264584) (xy 353.657916 -296.264584) (xy 353.657916 -296.264838) (xy 353.67559 -296.285743)
			(xy 353.70531 -296.331717) (xy 353.728151 -296.381468) (xy 353.743643 -296.433974) (xy 353.751467 -296.488155)
			(xy 353.751463 -296.542899) (xy 353.743631 -296.597079) (xy 353.728132 -296.649583) (xy 353.705284 -296.699331)
			(xy 353.675557 -296.7453) (xy 353.657916 -296.766234) (xy 353.657662 -296.766488) (xy 353.65207 -296.773571)
			(xy 353.645828 -296.790491) (xy 353.64547 -296.799508) (xy 353.64547 -296.866564) (xy 353.645851 -296.875578)
			(xy 353.652083 -296.892495) (xy 353.657662 -296.899584) (xy 353.657916 -296.899584) (xy 353.657916 -296.899838)
			(xy 353.67559 -296.920743) (xy 353.70531 -296.966717) (xy 353.728151 -297.016468) (xy 353.743643 -297.068974)
			(xy 353.751467 -297.123155) (xy 353.751463 -297.177899) (xy 353.743631 -297.232079) (xy 353.728132 -297.284583)
			(xy 353.705284 -297.334331) (xy 353.675557 -297.3803) (xy 353.657916 -297.401234) (xy 353.657662 -297.401488)
			(xy 353.65207 -297.408571) (xy 353.645828 -297.425491) (xy 353.64547 -297.434508) (xy 353.64547 -297.501564)
			(xy 353.645851 -297.510578) (xy 353.652083 -297.527495) (xy 353.657662 -297.534584) (xy 353.657916 -297.534584)
			(xy 353.657916 -297.534838) (xy 353.67559 -297.555743) (xy 353.70531 -297.601717) (xy 353.728151 -297.651468)
			(xy 353.743643 -297.703974) (xy 353.751467 -297.758155) (xy 353.751463 -297.812899) (xy 353.743631 -297.867079)
			(xy 353.728132 -297.919583) (xy 353.705284 -297.969331) (xy 353.675557 -298.0153) (xy 353.657916 -298.036234)
			(xy 353.657662 -298.036488) (xy 353.65207 -298.043571) (xy 353.645828 -298.060491) (xy 353.64547 -298.069508)
			(xy 353.64547 -298.136564) (xy 353.645851 -298.145578) (xy 353.652083 -298.162495) (xy 353.657662 -298.169584)
			(xy 353.657916 -298.169584) (xy 353.657916 -298.169838) (xy 353.675542 -298.190781) (xy 353.705255 -298.236751)
			(xy 353.728093 -298.286496) (xy 353.743588 -298.338994) (xy 353.75142 -298.393168) (xy 353.751896 -298.420536)
			(xy 356.99446 -298.420536) (xy 356.994933 -298.393166) (xy 357.002747 -298.338986) (xy 357.018233 -298.286483)
			(xy 357.041074 -298.236736) (xy 357.070798 -298.190769) (xy 357.08844 -298.169838) (xy 357.088694 -298.169584)
			(xy 357.094293 -298.162506) (xy 357.100532 -298.145583) (xy 357.100886 -298.136564) (xy 357.100886 -298.069508)
			(xy 357.100528 -298.060491) (xy 357.094282 -298.043574) (xy 357.088694 -298.036488) (xy 357.08844 -298.036488)
			(xy 357.08844 -298.036234) (xy 357.070834 -298.015273) (xy 357.041107 -297.96931) (xy 357.018259 -297.919569)
			(xy 357.002759 -297.867071) (xy 356.994927 -297.812896) (xy 356.994923 -297.758158) (xy 357.002747 -297.703982)
			(xy 357.018239 -297.651482) (xy 357.041081 -297.601737) (xy 357.070801 -297.55577) (xy 357.08844 -297.534838)
			(xy 357.088694 -297.534584) (xy 357.094293 -297.527506) (xy 357.100532 -297.510583) (xy 357.100886 -297.501564)
			(xy 357.100886 -297.434508) (xy 357.100528 -297.425491) (xy 357.094282 -297.408574) (xy 357.088694 -297.401488)
			(xy 357.08844 -297.401488) (xy 357.08844 -297.401234) (xy 357.070834 -297.380273) (xy 357.041107 -297.33431)
			(xy 357.018259 -297.284569) (xy 357.002759 -297.232071) (xy 356.994927 -297.177896) (xy 356.994923 -297.123158)
			(xy 357.002747 -297.068982) (xy 357.018239 -297.016482) (xy 357.041081 -296.966737) (xy 357.070801 -296.92077)
			(xy 357.08844 -296.899838) (xy 357.088694 -296.899584) (xy 357.094293 -296.892506) (xy 357.100532 -296.875583)
			(xy 357.100886 -296.866564) (xy 357.100886 -296.799508) (xy 357.100528 -296.790491) (xy 357.094282 -296.773574)
			(xy 357.088694 -296.766488) (xy 357.08844 -296.766488) (xy 357.08844 -296.766234) (xy 357.070834 -296.745273)
			(xy 357.041107 -296.69931) (xy 357.018259 -296.649569) (xy 357.002759 -296.597071) (xy 356.994927 -296.542896)
			(xy 356.994923 -296.488158) (xy 357.002747 -296.433982) (xy 357.018239 -296.381482) (xy 357.041081 -296.331737)
			(xy 357.070801 -296.28577) (xy 357.08844 -296.264838) (xy 357.088694 -296.264584) (xy 357.094293 -296.257506)
			(xy 357.100532 -296.240583) (xy 357.100886 -296.231564) (xy 357.100886 -296.164508) (xy 357.100528 -296.155491)
			(xy 357.094282 -296.138574) (xy 357.088694 -296.131488) (xy 357.08844 -296.131488) (xy 357.08844 -296.131234)
			(xy 357.070834 -296.110273) (xy 357.041107 -296.06431) (xy 357.018259 -296.014569) (xy 357.002759 -295.962071)
			(xy 356.994927 -295.907896) (xy 356.994923 -295.853158) (xy 357.002747 -295.798982) (xy 357.018239 -295.746482)
			(xy 357.041081 -295.696737) (xy 357.070801 -295.65077) (xy 357.08844 -295.629838) (xy 357.088694 -295.629584)
			(xy 357.094293 -295.622506) (xy 357.100532 -295.605583) (xy 357.100886 -295.596564) (xy 357.100886 -295.529508)
			(xy 357.100528 -295.520491) (xy 357.094282 -295.503574) (xy 357.088694 -295.496488) (xy 357.08844 -295.496488)
			(xy 357.08844 -295.496234) (xy 357.07081 -295.475295) (xy 357.041095 -295.429325) (xy 357.018257 -295.379579)
			(xy 357.002764 -295.32708) (xy 356.994934 -295.272905) (xy 356.99446 -295.245536) (xy 356.994989 -295.218285)
			(xy 357.00274 -295.164339) (xy 357.01809 -295.112044) (xy 357.040726 -295.062466) (xy 357.070187 -295.016614)
			(xy 357.105874 -294.975422) (xy 357.14706 -294.939728) (xy 357.192906 -294.910258) (xy 357.24248 -294.887614)
			(xy 357.294772 -294.872254) (xy 357.348718 -294.864494) (xy 357.375968 -294.864028) (xy 357.403338 -294.864506)
			(xy 357.457517 -294.87232) (xy 357.51002 -294.887806) (xy 357.559767 -294.910645) (xy 357.605734 -294.940368)
			(xy 357.626666 -294.958008) (xy 357.62692 -294.958262) (xy 357.633991 -294.96387) (xy 357.65092 -294.970102)
			(xy 357.65994 -294.970454) (xy 357.726996 -294.970454) (xy 357.736014 -294.970105) (xy 357.752931 -294.963853)
			(xy 357.760016 -294.958262) (xy 357.760016 -294.958008) (xy 357.76027 -294.958008) (xy 357.781204 -294.940371)
			(xy 357.827176 -294.910658) (xy 357.876923 -294.887822) (xy 357.929423 -294.87233) (xy 357.983599 -294.864502)
			(xy 358.010968 -294.864028) (xy 358.038222 -294.864485) (xy 358.092175 -294.872239) (xy 358.144475 -294.887593)
			(xy 358.194057 -294.910234) (xy 358.239912 -294.939702) (xy 358.281106 -294.975397) (xy 358.3168 -295.016591)
			(xy 358.346268 -295.062446) (xy 358.368909 -295.112029) (xy 358.384262 -295.164329) (xy 358.392015 -295.218282)
			(xy 358.392476 -295.245536) (xy 358.392037 -295.272907) (xy 358.384213 -295.327088) (xy 358.368718 -295.379591)
			(xy 358.345871 -295.429338) (xy 358.31614 -295.475303) (xy 358.298496 -295.496234) (xy 358.298242 -295.496488)
			(xy 358.292647 -295.503569) (xy 358.286407 -295.52049) (xy 358.28605 -295.529508) (xy 358.28605 -295.596564)
			(xy 358.286413 -295.60558) (xy 358.292655 -295.622498) (xy 358.298242 -295.629584) (xy 358.298496 -295.629584)
			(xy 358.298496 -295.629838) (xy 358.316171 -295.650743) (xy 358.345893 -295.696716) (xy 358.368734 -295.746467)
			(xy 358.384227 -295.798973) (xy 358.392052 -295.853155) (xy 358.392048 -295.907899) (xy 358.384215 -295.96208)
			(xy 358.368715 -296.014584) (xy 358.345866 -296.064332) (xy 358.316138 -296.110301) (xy 358.298496 -296.131234)
			(xy 358.298242 -296.131488) (xy 358.292647 -296.138569) (xy 358.286407 -296.15549) (xy 358.28605 -296.164508)
			(xy 358.28605 -296.231564) (xy 358.286413 -296.24058) (xy 358.292655 -296.257498) (xy 358.298242 -296.264584)
			(xy 358.298496 -296.264584) (xy 358.298496 -296.264838) (xy 358.316171 -296.285743) (xy 358.345893 -296.331716)
			(xy 358.368734 -296.381467) (xy 358.384227 -296.433973) (xy 358.392052 -296.488155) (xy 358.392048 -296.542899)
			(xy 358.384215 -296.59708) (xy 358.368715 -296.649584) (xy 358.345866 -296.699332) (xy 358.316138 -296.745301)
			(xy 358.298496 -296.766234) (xy 358.298242 -296.766488) (xy 358.292647 -296.773569) (xy 358.286407 -296.79049)
			(xy 358.28605 -296.799508) (xy 358.28605 -296.866564) (xy 358.286413 -296.87558) (xy 358.292655 -296.892498)
			(xy 358.298242 -296.899584) (xy 358.298496 -296.899584) (xy 358.298496 -296.899838) (xy 358.316171 -296.920743)
			(xy 358.345893 -296.966716) (xy 358.368734 -297.016467) (xy 358.384227 -297.068973) (xy 358.392052 -297.123155)
			(xy 358.392048 -297.177899) (xy 358.384215 -297.23208) (xy 358.368715 -297.284584) (xy 358.345866 -297.334332)
			(xy 358.316138 -297.380301) (xy 358.298496 -297.401234) (xy 358.298242 -297.401488) (xy 358.292647 -297.408569)
			(xy 358.286407 -297.42549) (xy 358.28605 -297.434508) (xy 358.28605 -297.501564) (xy 358.286413 -297.51058)
			(xy 358.292655 -297.527498) (xy 358.298242 -297.534584) (xy 358.298496 -297.534584) (xy 358.298496 -297.534838)
			(xy 358.316171 -297.555743) (xy 358.345893 -297.601716) (xy 358.368734 -297.651467) (xy 358.384227 -297.703973)
			(xy 358.392052 -297.758155) (xy 358.392048 -297.812899) (xy 358.384215 -297.86708) (xy 358.368715 -297.919584)
			(xy 358.345866 -297.969332) (xy 358.316138 -298.015301) (xy 358.298496 -298.036234) (xy 358.298242 -298.036488)
			(xy 358.292647 -298.043569) (xy 358.286407 -298.06049) (xy 358.28605 -298.069508) (xy 358.28605 -298.136564)
			(xy 358.286413 -298.14558) (xy 358.292655 -298.162498) (xy 358.298242 -298.169584) (xy 358.298496 -298.169584)
			(xy 358.298496 -298.169838) (xy 358.316119 -298.190783) (xy 358.345833 -298.236752) (xy 358.368672 -298.286496)
			(xy 358.384167 -298.338994) (xy 358.392 -298.393168) (xy 358.392476 -298.420536) (xy 359.422192 -298.420536)
			(xy 359.422681 -298.393167) (xy 359.430494 -298.338989) (xy 359.445977 -298.286486) (xy 359.468814 -298.236739)
			(xy 359.498533 -298.190771) (xy 359.516172 -298.169838) (xy 359.516426 -298.169584) (xy 359.522028 -298.162508)
			(xy 359.528265 -298.145583) (xy 359.528618 -298.136564) (xy 359.528618 -298.069508) (xy 359.528253 -298.060492)
			(xy 359.522011 -298.043575) (xy 359.516426 -298.036488) (xy 359.516172 -298.036488) (xy 359.516172 -298.036234)
			(xy 359.498565 -298.015274) (xy 359.468835 -297.969312) (xy 359.445985 -297.91957) (xy 359.430484 -297.867072)
			(xy 359.422651 -297.812897) (xy 359.422647 -297.758158) (xy 359.430472 -297.703981) (xy 359.445966 -297.651481)
			(xy 359.468809 -297.601736) (xy 359.498532 -297.55577) (xy 359.516172 -297.534838) (xy 359.516426 -297.534584)
			(xy 359.522028 -297.527508) (xy 359.528265 -297.510583) (xy 359.528618 -297.501564) (xy 359.528618 -297.434508)
			(xy 359.528253 -297.425492) (xy 359.522011 -297.408575) (xy 359.516426 -297.401488) (xy 359.516172 -297.401488)
			(xy 359.516172 -297.401234) (xy 359.498565 -297.380274) (xy 359.468835 -297.334312) (xy 359.445985 -297.28457)
			(xy 359.430484 -297.232072) (xy 359.422651 -297.177897) (xy 359.422647 -297.123158) (xy 359.430472 -297.068981)
			(xy 359.445966 -297.016481) (xy 359.468809 -296.966736) (xy 359.498532 -296.92077) (xy 359.516172 -296.899838)
			(xy 359.516426 -296.899584) (xy 359.522028 -296.892508) (xy 359.528265 -296.875583) (xy 359.528618 -296.866564)
			(xy 359.528618 -296.799508) (xy 359.528253 -296.790492) (xy 359.522011 -296.773575) (xy 359.516426 -296.766488)
			(xy 359.516172 -296.766488) (xy 359.516172 -296.766234) (xy 359.498565 -296.745274) (xy 359.468835 -296.699312)
			(xy 359.445985 -296.64957) (xy 359.430484 -296.597072) (xy 359.422651 -296.542897) (xy 359.422647 -296.488158)
			(xy 359.430472 -296.433981) (xy 359.445966 -296.381481) (xy 359.468809 -296.331736) (xy 359.498532 -296.28577)
			(xy 359.516172 -296.264838) (xy 359.516426 -296.264584) (xy 359.522028 -296.257508) (xy 359.528265 -296.240583)
			(xy 359.528618 -296.231564) (xy 359.528618 -296.164508) (xy 359.528253 -296.155492) (xy 359.522011 -296.138575)
			(xy 359.516426 -296.131488) (xy 359.516172 -296.131488) (xy 359.516172 -296.131234) (xy 359.498565 -296.110274)
			(xy 359.468835 -296.064312) (xy 359.445985 -296.01457) (xy 359.430484 -295.962072) (xy 359.422651 -295.907897)
			(xy 359.422647 -295.853158) (xy 359.430472 -295.798981) (xy 359.445966 -295.746481) (xy 359.468809 -295.696736)
			(xy 359.498532 -295.65077) (xy 359.516172 -295.629838) (xy 359.516426 -295.629584) (xy 359.522028 -295.622508)
			(xy 359.528265 -295.605583) (xy 359.528618 -295.596564) (xy 359.528618 -295.529508) (xy 359.528253 -295.520492)
			(xy 359.522011 -295.503575) (xy 359.516426 -295.496488) (xy 359.516172 -295.496488) (xy 359.516172 -295.496234)
			(xy 359.498531 -295.475304) (xy 359.46882 -295.42933) (xy 359.445985 -295.379582) (xy 359.430495 -295.327081)
			(xy 359.422666 -295.272905) (xy 359.422192 -295.245536) (xy 359.422689 -295.218284) (xy 359.430441 -295.164334)
			(xy 359.445792 -295.112037) (xy 359.468431 -295.062457) (xy 359.497895 -295.016604) (xy 359.533585 -294.975411)
			(xy 359.574775 -294.939716) (xy 359.620625 -294.910248) (xy 359.670203 -294.887605) (xy 359.722499 -294.872249)
			(xy 359.776448 -294.864491) (xy 359.8037 -294.864028) (xy 359.831071 -294.864487) (xy 359.88525 -294.872306)
			(xy 359.937754 -294.887796) (xy 359.9875 -294.910639) (xy 360.033467 -294.940366) (xy 360.054398 -294.958008)
			(xy 360.054652 -294.958262) (xy 360.061743 -294.963842) (xy 360.078657 -294.970091) (xy 360.087672 -294.970454)
			(xy 360.154728 -294.970454) (xy 360.163747 -294.97012) (xy 360.180665 -294.963858) (xy 360.187748 -294.958262)
			(xy 360.187748 -294.958008) (xy 360.188002 -294.958008) (xy 360.208924 -294.940356) (xy 360.254899 -294.910646)
			(xy 360.304649 -294.887812) (xy 360.357152 -294.872324) (xy 360.41133 -294.8645) (xy 360.4387 -294.864028)
			(xy 360.465954 -294.864455) (xy 360.519909 -294.872213) (xy 360.572209 -294.887571) (xy 360.621792 -294.910216)
			(xy 360.667647 -294.939688) (xy 360.70884 -294.975385) (xy 360.744534 -295.016582) (xy 360.774001 -295.06244)
			(xy 360.796641 -295.112024) (xy 360.811994 -295.164327) (xy 360.819747 -295.218281) (xy 360.820208 -295.245536)
			(xy 360.819761 -295.272907) (xy 360.811938 -295.327087) (xy 360.796445 -295.37959) (xy 360.773599 -295.429336)
			(xy 360.743871 -295.475303) (xy 360.726228 -295.496234) (xy 360.725974 -295.496488) (xy 360.720383 -295.503572)
			(xy 360.71414 -295.520491) (xy 360.713782 -295.529508) (xy 360.713782 -295.596564) (xy 360.71416 -295.605579)
			(xy 360.720393 -295.622496) (xy 360.725974 -295.629584) (xy 360.726228 -295.629584) (xy 360.726228 -295.629838)
			(xy 360.743906 -295.650741) (xy 360.773633 -295.696713) (xy 360.796479 -295.746464) (xy 360.811974 -295.798971)
			(xy 360.8198 -295.853154) (xy 360.819796 -295.9079) (xy 360.811962 -295.962082) (xy 360.79646 -296.014587)
			(xy 360.773606 -296.064335) (xy 360.743873 -296.110302) (xy 360.726228 -296.131234) (xy 360.725974 -296.131488)
			(xy 360.720383 -296.138572) (xy 360.71414 -296.155491) (xy 360.713782 -296.164508) (xy 360.713782 -296.231564)
			(xy 360.71416 -296.240579) (xy 360.720393 -296.257496) (xy 360.725974 -296.264584) (xy 360.726228 -296.264584)
			(xy 360.726228 -296.264838) (xy 360.743906 -296.285741) (xy 360.773633 -296.331713) (xy 360.796479 -296.381464)
			(xy 360.811974 -296.433971) (xy 360.8198 -296.488154) (xy 360.819796 -296.5429) (xy 360.811962 -296.597082)
			(xy 360.79646 -296.649587) (xy 360.773606 -296.699335) (xy 360.743873 -296.745302) (xy 360.726228 -296.766234)
			(xy 360.725974 -296.766488) (xy 360.720383 -296.773572) (xy 360.71414 -296.790491) (xy 360.713782 -296.799508)
			(xy 360.713782 -296.866564) (xy 360.71416 -296.875579) (xy 360.720393 -296.892496) (xy 360.725974 -296.899584)
			(xy 360.726228 -296.899584) (xy 360.726228 -296.899838) (xy 360.743906 -296.920741) (xy 360.773633 -296.966713)
			(xy 360.796479 -297.016464) (xy 360.811974 -297.068971) (xy 360.8198 -297.123154) (xy 360.819796 -297.1779)
			(xy 360.811962 -297.232082) (xy 360.79646 -297.284587) (xy 360.773606 -297.334335) (xy 360.743873 -297.380302)
			(xy 360.726228 -297.401234) (xy 360.725974 -297.401488) (xy 360.720383 -297.408572) (xy 360.71414 -297.425491)
			(xy 360.713782 -297.434508) (xy 360.713782 -297.501564) (xy 360.71416 -297.510579) (xy 360.720393 -297.527496)
			(xy 360.725974 -297.534584) (xy 360.726228 -297.534584) (xy 360.726228 -297.534838) (xy 360.743906 -297.555741)
			(xy 360.773633 -297.601713) (xy 360.796479 -297.651464) (xy 360.811974 -297.703971) (xy 360.8198 -297.758154)
			(xy 360.819796 -297.8129) (xy 360.811962 -297.867082) (xy 360.79646 -297.919587) (xy 360.773606 -297.969335)
			(xy 360.743873 -298.015302) (xy 360.726228 -298.036234) (xy 360.725974 -298.036488) (xy 360.720383 -298.043572)
			(xy 360.71414 -298.060491) (xy 360.713782 -298.069508) (xy 360.713782 -298.136564) (xy 360.71416 -298.145579)
			(xy 360.720393 -298.162496) (xy 360.725974 -298.169584) (xy 360.726228 -298.169584) (xy 360.726228 -298.169838)
			(xy 360.743856 -298.190779) (xy 360.773568 -298.23675) (xy 360.796406 -298.286495) (xy 360.8119 -298.338994)
			(xy 360.819732 -298.393168) (xy 360.820208 -298.420536) (xy 364.062772 -298.420536) (xy 364.063242 -298.393166)
			(xy 364.071056 -298.338986) (xy 364.086543 -298.286482) (xy 364.109385 -298.236735) (xy 364.13911 -298.190769)
			(xy 364.156752 -298.169838) (xy 364.157006 -298.169584) (xy 364.162606 -298.162507) (xy 364.168844 -298.145583)
			(xy 364.169198 -298.136564) (xy 364.169198 -298.069508) (xy 364.168838 -298.060491) (xy 364.162592 -298.043574)
			(xy 364.157006 -298.036488) (xy 364.156752 -298.036488) (xy 364.156752 -298.036234) (xy 364.139146 -298.015273)
			(xy 364.109417 -297.969311) (xy 364.086568 -297.919569) (xy 364.071068 -297.867071) (xy 364.063236 -297.812896)
			(xy 364.063232 -297.758158) (xy 364.071057 -297.703982) (xy 364.086549 -297.651481) (xy 364.109391 -297.601737)
			(xy 364.139113 -297.55577) (xy 364.156752 -297.534838) (xy 364.157006 -297.534584) (xy 364.162606 -297.527507)
			(xy 364.168844 -297.510583) (xy 364.169198 -297.501564) (xy 364.169198 -297.434508) (xy 364.168838 -297.425491)
			(xy 364.162592 -297.408574) (xy 364.157006 -297.401488) (xy 364.156752 -297.401488) (xy 364.156752 -297.401234)
			(xy 364.139146 -297.380273) (xy 364.109417 -297.334311) (xy 364.086568 -297.284569) (xy 364.071068 -297.232071)
			(xy 364.063236 -297.177896) (xy 364.063232 -297.123158) (xy 364.071057 -297.068982) (xy 364.086549 -297.016481)
			(xy 364.109391 -296.966737) (xy 364.139113 -296.92077) (xy 364.156752 -296.899838) (xy 364.157006 -296.899584)
			(xy 364.162606 -296.892507) (xy 364.168844 -296.875583) (xy 364.169198 -296.866564) (xy 364.169198 -296.799508)
			(xy 364.168838 -296.790491) (xy 364.162592 -296.773574) (xy 364.157006 -296.766488) (xy 364.156752 -296.766488)
			(xy 364.156752 -296.766234) (xy 364.139146 -296.745273) (xy 364.109417 -296.699311) (xy 364.086568 -296.649569)
			(xy 364.071068 -296.597071) (xy 364.063236 -296.542896) (xy 364.063232 -296.488158) (xy 364.071057 -296.433982)
			(xy 364.086549 -296.381481) (xy 364.109391 -296.331737) (xy 364.139113 -296.28577) (xy 364.156752 -296.264838)
			(xy 364.157006 -296.264584) (xy 364.162606 -296.257507) (xy 364.168844 -296.240583) (xy 364.169198 -296.231564)
			(xy 364.169198 -296.164508) (xy 364.168838 -296.155491) (xy 364.162592 -296.138574) (xy 364.157006 -296.131488)
			(xy 364.156752 -296.131488) (xy 364.156752 -296.131234) (xy 364.139146 -296.110273) (xy 364.109417 -296.064311)
			(xy 364.086568 -296.014569) (xy 364.071068 -295.962071) (xy 364.063236 -295.907896) (xy 364.063232 -295.853158)
			(xy 364.071057 -295.798982) (xy 364.086549 -295.746481) (xy 364.109391 -295.696737) (xy 364.139113 -295.65077)
			(xy 364.156752 -295.629838) (xy 364.157006 -295.629584) (xy 364.162606 -295.622507) (xy 364.168844 -295.605583)
			(xy 364.169198 -295.596564) (xy 364.169198 -295.529508) (xy 364.168838 -295.520491) (xy 364.162592 -295.503574)
			(xy 364.157006 -295.496488) (xy 364.156752 -295.496488) (xy 364.156752 -295.496234) (xy 364.139123 -295.475293)
			(xy 364.109408 -295.429324) (xy 364.086569 -295.379578) (xy 364.071076 -295.327079) (xy 364.063246 -295.272905)
			(xy 364.062772 -295.245536) (xy 364.063289 -295.218285) (xy 364.07104 -295.164337) (xy 364.086391 -295.112041)
			(xy 364.109028 -295.062463) (xy 364.13849 -295.01661) (xy 364.174178 -294.975418) (xy 364.215365 -294.939724)
			(xy 364.261213 -294.910254) (xy 364.310789 -294.88761) (xy 364.363082 -294.872252) (xy 364.417029 -294.864493)
			(xy 364.44428 -294.864028) (xy 364.47165 -294.864499) (xy 364.525829 -294.872315) (xy 364.578333 -294.887802)
			(xy 364.62808 -294.910643) (xy 364.674046 -294.940367) (xy 364.694978 -294.958008) (xy 364.695232 -294.958262)
			(xy 364.702329 -294.963834) (xy 364.719238 -294.970088) (xy 364.728252 -294.970454) (xy 364.795308 -294.970454)
			(xy 364.804326 -294.970111) (xy 364.821244 -294.963855) (xy 364.828328 -294.958262) (xy 364.828328 -294.958008)
			(xy 364.828582 -294.958008) (xy 364.849511 -294.940365) (xy 364.895485 -294.910654) (xy 364.945233 -294.887818)
			(xy 364.997734 -294.872328) (xy 365.051911 -294.864501) (xy 365.07928 -294.864028) (xy 365.106534 -294.864474)
			(xy 365.160487 -294.872229) (xy 365.212788 -294.887585) (xy 365.26237 -294.910227) (xy 365.308225 -294.939697)
			(xy 365.349419 -294.975392) (xy 365.385113 -295.016588) (xy 365.41458 -295.062444) (xy 365.437221 -295.112027)
			(xy 365.452574 -295.164328) (xy 365.460327 -295.218282) (xy 365.460788 -295.245536) (xy 365.460346 -295.272907)
			(xy 365.452523 -295.327087) (xy 365.437028 -295.379591) (xy 365.414181 -295.429337) (xy 365.384452 -295.475303)
			(xy 365.366808 -295.496234) (xy 365.366554 -295.496488) (xy 365.360961 -295.50357) (xy 365.354719 -295.52049)
			(xy 365.354362 -295.529508) (xy 365.354362 -295.596564) (xy 365.354745 -295.605578) (xy 365.360975 -295.622495)
			(xy 365.366554 -295.629584) (xy 365.366808 -295.629584) (xy 365.366808 -295.629838) (xy 365.384482 -295.650743)
			(xy 365.414203 -295.696716) (xy 365.437044 -295.746467) (xy 365.452536 -295.798973) (xy 365.460361 -295.853155)
			(xy 365.460357 -295.907899) (xy 365.452525 -295.96208) (xy 365.437025 -296.014583) (xy 365.414177 -296.064331)
			(xy 365.38445 -296.110301) (xy 365.366808 -296.131234) (xy 365.366554 -296.131488) (xy 365.360961 -296.13857)
			(xy 365.354719 -296.15549) (xy 365.354362 -296.164508) (xy 365.354362 -296.231564) (xy 365.354745 -296.240578)
			(xy 365.360975 -296.257495) (xy 365.366554 -296.264584) (xy 365.366808 -296.264584) (xy 365.366808 -296.264838)
			(xy 365.384482 -296.285743) (xy 365.414203 -296.331716) (xy 365.437044 -296.381467) (xy 365.452536 -296.433973)
			(xy 365.460361 -296.488155) (xy 365.460357 -296.542899) (xy 365.452525 -296.59708) (xy 365.437025 -296.649583)
			(xy 365.414177 -296.699331) (xy 365.38445 -296.745301) (xy 365.366808 -296.766234) (xy 365.366554 -296.766488)
			(xy 365.360961 -296.77357) (xy 365.354719 -296.79049) (xy 365.354362 -296.799508) (xy 365.354362 -296.866564)
			(xy 365.354745 -296.875578) (xy 365.360975 -296.892495) (xy 365.366554 -296.899584) (xy 365.366808 -296.899584)
			(xy 365.366808 -296.899838) (xy 365.384482 -296.920743) (xy 365.414203 -296.966716) (xy 365.437044 -297.016467)
			(xy 365.452536 -297.068973) (xy 365.460361 -297.123155) (xy 365.460357 -297.177899) (xy 365.452525 -297.23208)
			(xy 365.437025 -297.284583) (xy 365.414177 -297.334331) (xy 365.38445 -297.380301) (xy 365.366808 -297.401234)
			(xy 365.366554 -297.401488) (xy 365.360961 -297.40857) (xy 365.354719 -297.42549) (xy 365.354362 -297.434508)
			(xy 365.354362 -297.501564) (xy 365.354745 -297.510578) (xy 365.360975 -297.527495) (xy 365.366554 -297.534584)
			(xy 365.366808 -297.534584) (xy 365.366808 -297.534838) (xy 365.384482 -297.555743) (xy 365.414203 -297.601716)
			(xy 365.437044 -297.651467) (xy 365.452536 -297.703973) (xy 365.460361 -297.758155) (xy 365.460357 -297.812899)
			(xy 365.452525 -297.86708) (xy 365.437025 -297.919583) (xy 365.414177 -297.969331) (xy 365.38445 -298.015301)
			(xy 365.366808 -298.036234) (xy 365.366554 -298.036488) (xy 365.360961 -298.04357) (xy 365.354719 -298.06049)
			(xy 365.354362 -298.069508) (xy 365.354362 -298.136564) (xy 365.354745 -298.145578) (xy 365.360975 -298.162495)
			(xy 365.366554 -298.169584) (xy 365.366808 -298.169584) (xy 365.366808 -298.169838) (xy 365.384433 -298.190782)
			(xy 365.414146 -298.236751) (xy 365.436985 -298.286496) (xy 365.45248 -298.338994) (xy 365.460312 -298.393168)
			(xy 365.460788 -298.420536) (xy 365.460356 -298.447789) (xy 365.452594 -298.50174) (xy 365.437233 -298.554037)
			(xy 365.414586 -298.603615) (xy 365.385114 -298.649467) (xy 365.349417 -298.690657) (xy 365.308222 -298.726348)
			(xy 365.262366 -298.755813) (xy 365.212784 -298.778453) (xy 365.160485 -298.793806) (xy 365.106533 -298.80156)
			(xy 365.07928 -298.802044) (xy 365.051909 -298.801603) (xy 364.997728 -298.793781) (xy 364.945224 -298.778287)
			(xy 364.895478 -298.755439) (xy 364.849512 -298.725708) (xy 364.828582 -298.708064) (xy 364.828328 -298.70781)
			(xy 364.821237 -298.70223) (xy 364.804324 -298.695979) (xy 364.795308 -298.695618) (xy 364.728252 -298.695618)
			(xy 364.719237 -298.695996) (xy 364.70232 -298.702229) (xy 364.695232 -298.70781) (xy 364.695232 -298.708064)
			(xy 364.694978 -298.708064) (xy 364.674023 -298.725674) (xy 364.628057 -298.755392) (xy 364.578315 -298.778234)
			(xy 364.52582 -298.793731) (xy 364.471648 -298.801567) (xy 364.44428 -298.802044) (xy 364.41703 -298.801541)
			(xy 364.363085 -298.793783) (xy 364.310792 -298.778427) (xy 364.261218 -298.755786) (xy 364.215369 -298.726321)
			(xy 364.17418 -298.690631) (xy 364.138489 -298.649444) (xy 364.109022 -298.603597) (xy 364.086379 -298.554023)
			(xy 364.071021 -298.501731) (xy 364.06326 -298.447786) (xy 364.062772 -298.420536) (xy 360.820208 -298.420536)
			(xy 360.819756 -298.447788) (xy 360.811994 -298.501737) (xy 360.796635 -298.554032) (xy 360.773989 -298.60361)
			(xy 360.744519 -298.64946) (xy 360.708824 -298.69065) (xy 360.667631 -298.726341) (xy 360.621778 -298.755807)
			(xy 360.572199 -298.778447) (xy 360.519902 -298.793802) (xy 360.465952 -298.801558) (xy 360.4387 -298.802044)
			(xy 360.411329 -298.801592) (xy 360.357149 -298.793773) (xy 360.304645 -298.778281) (xy 360.254898 -298.755436)
			(xy 360.208933 -298.725707) (xy 360.188002 -298.708064) (xy 360.187748 -298.70781) (xy 360.180651 -298.702238)
			(xy 360.163742 -298.695982) (xy 360.154728 -298.695618) (xy 360.087672 -298.695618) (xy 360.078653 -298.695958)
			(xy 360.061736 -298.702217) (xy 360.054652 -298.70781) (xy 360.054652 -298.708064) (xy 360.054398 -298.708064)
			(xy 360.033473 -298.725712) (xy 359.987499 -298.755424) (xy 359.93775 -298.778258) (xy 359.885247 -298.793747)
			(xy 359.83107 -298.801572) (xy 359.8037 -298.802044) (xy 359.77645 -298.801522) (xy 359.722506 -298.793767)
			(xy 359.670214 -298.778413) (xy 359.620639 -298.755775) (xy 359.57479 -298.726312) (xy 359.533601 -298.690624)
			(xy 359.49791 -298.649438) (xy 359.468442 -298.603593) (xy 359.445799 -298.55402) (xy 359.430441 -298.501729)
			(xy 359.42268 -298.447786) (xy 359.422192 -298.420536) (xy 358.392476 -298.420536) (xy 358.392056 -298.44779)
			(xy 358.384293 -298.501741) (xy 358.368932 -298.554039) (xy 358.346284 -298.603619) (xy 358.316811 -298.64947)
			(xy 358.281113 -298.690661) (xy 358.239916 -298.726352) (xy 358.194059 -298.755817) (xy 358.144475 -298.778456)
			(xy 358.092175 -298.793808) (xy 358.038222 -298.80156) (xy 358.010968 -298.802044) (xy 357.983596 -298.80161)
			(xy 357.929415 -298.793787) (xy 357.876911 -298.778291) (xy 357.827165 -298.755442) (xy 357.7812 -298.725709)
			(xy 357.76027 -298.708064) (xy 357.760016 -298.70781) (xy 357.752928 -298.702225) (xy 357.736012 -298.695977)
			(xy 357.726996 -298.695618) (xy 357.65994 -298.695618) (xy 357.650925 -298.69599) (xy 357.634007 -298.702227)
			(xy 357.62692 -298.70781) (xy 357.62692 -298.708064) (xy 357.626666 -298.708064) (xy 357.605715 -298.72568)
			(xy 357.559748 -298.755397) (xy 357.510005 -298.778238) (xy 357.457509 -298.793734) (xy 357.403336 -298.801567)
			(xy 357.375968 -298.802044) (xy 357.348718 -298.801552) (xy 357.294772 -298.793792) (xy 357.24248 -298.778435)
			(xy 357.192905 -298.755793) (xy 357.147056 -298.726326) (xy 357.105867 -298.690636) (xy 357.070176 -298.649447)
			(xy 357.040709 -298.603599) (xy 357.018067 -298.554024) (xy 357.002709 -298.501732) (xy 356.994948 -298.447786)
			(xy 356.99446 -298.420536) (xy 353.751896 -298.420536) (xy 353.751456 -298.447789) (xy 353.743694 -298.501739)
			(xy 353.728334 -298.554035) (xy 353.705687 -298.603613) (xy 353.676216 -298.649464) (xy 353.64052 -298.690654)
			(xy 353.599325 -298.726345) (xy 353.553471 -298.75581) (xy 353.50389 -298.77845) (xy 353.451592 -298.793804)
			(xy 353.397641 -298.801559) (xy 353.370388 -298.802044) (xy 353.343017 -298.801599) (xy 353.288836 -298.793778)
			(xy 353.236332 -298.778285) (xy 353.186586 -298.755438) (xy 353.14062 -298.725708) (xy 353.11969 -298.708064)
			(xy 353.119436 -298.70781) (xy 353.112342 -298.702233) (xy 353.095431 -298.69598) (xy 353.086416 -298.695618)
			(xy 353.01936 -298.695618) (xy 353.010341 -298.695952) (xy 352.993424 -298.702215) (xy 352.98634 -298.70781)
			(xy 352.98634 -298.708064) (xy 352.986086 -298.708064) (xy 352.965128 -298.725671) (xy 352.919163 -298.755389)
			(xy 352.869422 -298.778231) (xy 352.816927 -298.79373) (xy 352.762755 -298.801566) (xy 352.735388 -298.802044)
			(xy 352.708138 -298.801533) (xy 352.654193 -298.793776) (xy 352.601901 -298.778421) (xy 352.552326 -298.755782)
			(xy 352.506478 -298.726317) (xy 352.465288 -298.690629) (xy 352.429597 -298.649442) (xy 352.40013 -298.603595)
			(xy 352.377487 -298.554021) (xy 352.362129 -298.50173) (xy 352.354368 -298.447786) (xy 352.35388 -298.420536)
			(xy 348.80169 -298.420536) (xy 348.801256 -298.447789) (xy 348.793494 -298.501739) (xy 348.778133 -298.554036)
			(xy 348.755486 -298.603615) (xy 348.726015 -298.649466) (xy 348.690318 -298.690656) (xy 348.649123 -298.726347)
			(xy 348.603267 -298.755812) (xy 348.553686 -298.778452) (xy 348.501387 -298.793805) (xy 348.447435 -298.801559)
			(xy 348.420182 -298.802044) (xy 348.392811 -298.801602) (xy 348.33863 -298.793781) (xy 348.286126 -298.778287)
			(xy 348.23638 -298.755439) (xy 348.190414 -298.725708) (xy 348.169484 -298.708064) (xy 348.16923 -298.70781)
			(xy 348.162138 -298.702231) (xy 348.145225 -298.695979) (xy 348.13621 -298.695618) (xy 348.069154 -298.695618)
			(xy 348.060139 -298.695997) (xy 348.043222 -298.702229) (xy 348.036134 -298.70781) (xy 348.036134 -298.708064)
			(xy 348.03588 -298.708064) (xy 348.014924 -298.725673) (xy 347.968958 -298.755391) (xy 347.919217 -298.778233)
			(xy 347.866721 -298.793731) (xy 347.81255 -298.801566) (xy 347.785182 -298.802044) (xy 347.757932 -298.801539)
			(xy 347.703987 -298.793781) (xy 347.651695 -298.778425) (xy 347.60212 -298.755785) (xy 347.556271 -298.72632)
			(xy 347.515082 -298.690631) (xy 347.479391 -298.649443) (xy 347.449924 -298.603596) (xy 347.427281 -298.554022)
			(xy 347.411923 -298.501731) (xy 347.404162 -298.447786) (xy 347.403674 -298.420536) (xy 344.16111 -298.420536)
			(xy 344.160656 -298.447788) (xy 344.152894 -298.501737) (xy 344.137535 -298.554032) (xy 344.11489 -298.603609)
			(xy 344.08542 -298.649459) (xy 344.049725 -298.690649) (xy 344.008532 -298.72634) (xy 343.962679 -298.755806)
			(xy 343.9131 -298.778447) (xy 343.860804 -298.793802) (xy 343.806854 -298.801558) (xy 343.779602 -298.802044)
			(xy 343.752231 -298.80159) (xy 343.698051 -298.793772) (xy 343.645547 -298.77828) (xy 343.595801 -298.755436)
			(xy 343.549835 -298.725707) (xy 343.528904 -298.708064) (xy 343.52865 -298.70781) (xy 343.521552 -298.702239)
			(xy 343.504644 -298.695983) (xy 343.49563 -298.695618) (xy 343.428574 -298.695618) (xy 343.419555 -298.695959)
			(xy 343.402638 -298.702217) (xy 343.395554 -298.70781) (xy 343.395554 -298.708064) (xy 343.3953 -298.708064)
			(xy 343.374374 -298.725711) (xy 343.3284 -298.755423) (xy 343.278651 -298.778258) (xy 343.226149 -298.793747)
			(xy 343.171972 -298.801572) (xy 343.144602 -298.802044) (xy 343.117352 -298.80152) (xy 343.063408 -298.793765)
			(xy 343.011116 -298.778412) (xy 342.961541 -298.755774) (xy 342.915693 -298.726311) (xy 342.874503 -298.690624)
			(xy 342.838812 -298.649438) (xy 342.809344 -298.603592) (xy 342.786701 -298.55402) (xy 342.771343 -298.501729)
			(xy 342.763582 -298.447786) (xy 342.763094 -298.420536) (xy 341.733378 -298.420536) (xy 341.732956 -298.44779)
			(xy 341.725193 -298.501741) (xy 341.709832 -298.554039) (xy 341.687185 -298.603618) (xy 341.657712 -298.64947)
			(xy 341.622014 -298.69066) (xy 341.580817 -298.726351) (xy 341.53496 -298.755816) (xy 341.485377 -298.778455)
			(xy 341.433076 -298.793807) (xy 341.379124 -298.80156) (xy 341.35187 -298.802044) (xy 341.324498 -298.801609)
			(xy 341.270318 -298.793786) (xy 341.217814 -298.77829) (xy 341.168067 -298.755441) (xy 341.122102 -298.725709)
			(xy 341.101172 -298.708064) (xy 341.100918 -298.70781) (xy 341.09383 -298.702226) (xy 341.076914 -298.695977)
			(xy 341.067898 -298.695618) (xy 341.000842 -298.695618) (xy 340.991827 -298.695991) (xy 340.974909 -298.702227)
			(xy 340.967822 -298.70781) (xy 340.967822 -298.708064) (xy 340.967568 -298.708064) (xy 340.946616 -298.725679)
			(xy 340.90065 -298.755396) (xy 340.850907 -298.778237) (xy 340.798411 -298.793733) (xy 340.744238 -298.801567)
			(xy 340.71687 -298.802044) (xy 340.68962 -298.80155) (xy 340.635674 -298.793791) (xy 340.583382 -298.778433)
			(xy 340.533807 -298.755791) (xy 340.487958 -298.726325) (xy 340.446769 -298.690635) (xy 340.411078 -298.649447)
			(xy 340.381611 -298.603599) (xy 340.358969 -298.554024) (xy 340.343611 -298.501732) (xy 340.33585 -298.447786)
			(xy 340.335362 -298.420536) (xy 337.092798 -298.420536) (xy 337.092356 -298.447789) (xy 337.084594 -298.501738)
			(xy 337.069234 -298.554035) (xy 337.046588 -298.603613) (xy 337.017117 -298.649463) (xy 336.981421 -298.690653)
			(xy 336.940226 -298.726344) (xy 336.894372 -298.75581) (xy 336.844791 -298.77845) (xy 336.792493 -298.793804)
			(xy 336.738543 -298.801559) (xy 336.71129 -298.802044) (xy 336.683919 -298.801597) (xy 336.629738 -298.793777)
			(xy 336.577235 -298.778284) (xy 336.527488 -298.755438) (xy 336.481523 -298.725708) (xy 336.460592 -298.708064)
			(xy 336.460338 -298.70781) (xy 336.453244 -298.702234) (xy 336.436333 -298.695981) (xy 336.427318 -298.695618)
			(xy 336.360262 -298.695618) (xy 336.351243 -298.695953) (xy 336.334326 -298.702215) (xy 336.327242 -298.70781)
			(xy 336.327242 -298.708064) (xy 336.326988 -298.708064) (xy 336.306029 -298.72567) (xy 336.260064 -298.755388)
			(xy 336.210324 -298.778231) (xy 336.157829 -298.79373) (xy 336.103657 -298.801566) (xy 336.07629 -298.802044)
			(xy 336.04904 -298.801532) (xy 335.995095 -298.793775) (xy 335.942803 -298.77842) (xy 335.893228 -298.75578)
			(xy 335.84738 -298.726316) (xy 335.806191 -298.690628) (xy 335.770499 -298.649441) (xy 335.741032 -298.603595)
			(xy 335.718389 -298.554021) (xy 335.703031 -298.50173) (xy 335.69527 -298.447786) (xy 335.694782 -298.420536)
			(xy 330.943966 -298.420536) (xy 330.943966 -301.424086) (xy 335.023714 -301.424086) (xy 335.024168 -301.396715)
			(xy 335.031989 -301.342536) (xy 335.04748 -301.290032) (xy 335.070325 -301.240286) (xy 335.100052 -301.194319)
			(xy 335.117694 -301.173388) (xy 335.117948 -301.173134) (xy 335.123532 -301.166046) (xy 335.129779 -301.14913)
			(xy 335.13014 -301.140114) (xy 335.13014 -301.073058) (xy 335.129768 -301.064042) (xy 335.123532 -301.047125)
			(xy 335.117948 -301.040038) (xy 335.117694 -301.040038) (xy 335.117694 -301.039784) (xy 335.100041 -301.018862)
			(xy 335.070319 -300.972891) (xy 335.047477 -300.923143) (xy 335.031983 -300.87064) (xy 335.024156 -300.81646)
			(xy 335.024158 -300.761719) (xy 335.031987 -300.70754) (xy 335.047484 -300.655037) (xy 335.070329 -300.60529)
			(xy 335.100054 -300.559321) (xy 335.117694 -300.538388) (xy 335.117948 -300.538134) (xy 335.123532 -300.531046)
			(xy 335.129779 -300.51413) (xy 335.13014 -300.505114) (xy 335.13014 -300.438058) (xy 335.129768 -300.429042)
			(xy 335.123532 -300.412125) (xy 335.117948 -300.405038) (xy 335.117694 -300.405038) (xy 335.117694 -300.404784)
			(xy 335.100041 -300.383862) (xy 335.070319 -300.337891) (xy 335.047477 -300.288143) (xy 335.031983 -300.23564)
			(xy 335.024156 -300.18146) (xy 335.024158 -300.126719) (xy 335.031987 -300.07254) (xy 335.047484 -300.020037)
			(xy 335.070329 -299.97029) (xy 335.100054 -299.924321) (xy 335.117694 -299.903388) (xy 335.117948 -299.903134)
			(xy 335.123532 -299.896046) (xy 335.129779 -299.87913) (xy 335.13014 -299.870114) (xy 335.13014 -299.803058)
			(xy 335.129768 -299.794042) (xy 335.123532 -299.777125) (xy 335.117948 -299.770038) (xy 335.117694 -299.770038)
			(xy 335.117694 -299.769784) (xy 335.10008 -299.748832) (xy 335.070365 -299.702864) (xy 335.047524 -299.653122)
			(xy 335.032027 -299.600626) (xy 335.024192 -299.546454) (xy 335.023714 -299.519086) (xy 335.0242 -299.491835)
			(xy 335.031956 -299.437887) (xy 335.047311 -299.385592) (xy 335.069953 -299.336015) (xy 335.099419 -299.290165)
			(xy 335.13511 -299.248974) (xy 335.176301 -299.213283) (xy 335.222151 -299.183817) (xy 335.271728 -299.161175)
			(xy 335.324023 -299.14582) (xy 335.377971 -299.138064) (xy 335.432473 -299.138064) (xy 335.486421 -299.14582)
			(xy 335.538716 -299.161175) (xy 335.588293 -299.183817) (xy 335.634143 -299.213283) (xy 335.675334 -299.248974)
			(xy 335.711025 -299.290165) (xy 335.740491 -299.336015) (xy 335.763133 -299.385592) (xy 335.778488 -299.437887)
			(xy 335.786244 -299.491835) (xy 335.78673 -299.519086) (xy 335.786273 -299.546457) (xy 335.778455 -299.600637)
			(xy 335.762965 -299.653141) (xy 335.740121 -299.702888) (xy 335.710393 -299.748853) (xy 335.69275 -299.769784)
			(xy 335.692496 -299.770038) (xy 335.686929 -299.777138) (xy 335.680671 -299.794044) (xy 335.680304 -299.803058)
			(xy 335.680304 -299.870114) (xy 335.680654 -299.879132) (xy 335.686906 -299.896049) (xy 335.692496 -299.903134)
			(xy 335.69275 -299.903134) (xy 335.69275 -299.903388) (xy 335.710378 -299.924331) (xy 335.740105 -299.970297)
			(xy 335.762953 -300.020041) (xy 335.778451 -300.072542) (xy 335.786281 -300.126719) (xy 335.786283 -300.18146)
			(xy 335.778455 -300.235638) (xy 335.76296 -300.288139) (xy 335.740115 -300.337885) (xy 335.710391 -300.383852)
			(xy 335.69275 -300.404784) (xy 335.692496 -300.405038) (xy 335.686929 -300.412138) (xy 335.680671 -300.429044)
			(xy 335.680304 -300.438058) (xy 335.680304 -300.505114) (xy 335.680654 -300.514132) (xy 335.686906 -300.531049)
			(xy 335.692496 -300.538134) (xy 335.69275 -300.538134) (xy 335.69275 -300.538388) (xy 335.710378 -300.559331)
			(xy 335.740105 -300.605297) (xy 335.762953 -300.655041) (xy 335.778451 -300.707542) (xy 335.786281 -300.761719)
			(xy 335.786283 -300.81646) (xy 335.778455 -300.870638) (xy 335.76296 -300.923139) (xy 335.740115 -300.972885)
			(xy 335.710391 -301.018852) (xy 335.69275 -301.039784) (xy 335.692496 -301.040038) (xy 335.686929 -301.047138)
			(xy 335.680671 -301.064044) (xy 335.680304 -301.073058) (xy 335.680304 -301.140114) (xy 335.680654 -301.149132)
			(xy 335.686906 -301.166049) (xy 335.692496 -301.173134) (xy 335.69275 -301.173134) (xy 335.69275 -301.173388)
			(xy 335.710389 -301.19432) (xy 335.740103 -301.240292) (xy 335.762939 -301.29004) (xy 335.77843 -301.342541)
			(xy 335.786257 -301.396717) (xy 335.78673 -301.424086) (xy 335.786244 -301.451337) (xy 335.78242 -301.477934)
			(xy 338.655914 -301.477934) (xy 338.656397 -301.450564) (xy 338.66421 -301.396386) (xy 338.679695 -301.343883)
			(xy 338.702533 -301.294136) (xy 338.732254 -301.248168) (xy 338.749894 -301.227236) (xy 338.750148 -301.226982)
			(xy 338.755754 -301.219909) (xy 338.761988 -301.202982) (xy 338.76234 -301.193962) (xy 338.76234 -301.126906)
			(xy 338.761993 -301.117888) (xy 338.75574 -301.10097) (xy 338.750148 -301.093886) (xy 338.749894 -301.093886)
			(xy 338.749894 -301.093632) (xy 338.732288 -301.072672) (xy 338.702564 -301.026708) (xy 338.679719 -300.976966)
			(xy 338.664222 -300.924468) (xy 338.65639 -300.870294) (xy 338.656387 -300.815557) (xy 338.664211 -300.761382)
			(xy 338.679701 -300.708882) (xy 338.70254 -300.659137) (xy 338.732257 -300.613169) (xy 338.749894 -300.592236)
			(xy 338.750148 -300.591982) (xy 338.755754 -300.584909) (xy 338.761988 -300.567982) (xy 338.76234 -300.558962)
			(xy 338.76234 -300.491906) (xy 338.761993 -300.482888) (xy 338.75574 -300.46597) (xy 338.750148 -300.458886)
			(xy 338.749894 -300.458886) (xy 338.749894 -300.458632) (xy 338.732288 -300.437672) (xy 338.702564 -300.391708)
			(xy 338.679719 -300.341966) (xy 338.664222 -300.289468) (xy 338.65639 -300.235294) (xy 338.656387 -300.180557)
			(xy 338.664211 -300.126382) (xy 338.679701 -300.073882) (xy 338.70254 -300.024137) (xy 338.732257 -299.978169)
			(xy 338.749894 -299.957236) (xy 338.750148 -299.956982) (xy 338.755754 -299.949909) (xy 338.761988 -299.932982)
			(xy 338.76234 -299.923962) (xy 338.76234 -299.856906) (xy 338.761993 -299.847888) (xy 338.75574 -299.83097)
			(xy 338.750148 -299.823886) (xy 338.749894 -299.823886) (xy 338.749894 -299.823632) (xy 338.732256 -299.802699)
			(xy 338.702544 -299.756727) (xy 338.679708 -299.706979) (xy 338.664217 -299.654479) (xy 338.656388 -299.600303)
			(xy 338.655914 -299.572934) (xy 338.6564 -299.545683) (xy 338.664156 -299.491735) (xy 338.679511 -299.43944)
			(xy 338.702153 -299.389863) (xy 338.731619 -299.344013) (xy 338.76731 -299.302822) (xy 338.808501 -299.267131)
			(xy 338.854351 -299.237665) (xy 338.903928 -299.215023) (xy 338.956223 -299.199668) (xy 339.010171 -299.191912)
			(xy 339.064673 -299.191912) (xy 339.118621 -299.199668) (xy 339.170916 -299.215023) (xy 339.220493 -299.237665)
			(xy 339.266343 -299.267131) (xy 339.307534 -299.302822) (xy 339.343225 -299.344013) (xy 339.372691 -299.389863)
			(xy 339.395333 -299.43944) (xy 339.410688 -299.491735) (xy 339.418444 -299.545683) (xy 339.41893 -299.572934)
			(xy 339.418501 -299.600306) (xy 339.410677 -299.654487) (xy 339.39518 -299.706991) (xy 339.37233 -299.756738)
			(xy 339.342596 -299.802702) (xy 339.32495 -299.823632) (xy 339.324696 -299.823886) (xy 339.319109 -299.830972)
			(xy 339.312863 -299.847889) (xy 339.312504 -299.856906) (xy 339.312504 -299.923962) (xy 339.312879 -299.932977)
			(xy 339.319114 -299.949894) (xy 339.324696 -299.956982) (xy 339.32495 -299.956982) (xy 339.32495 -299.957236)
			(xy 339.342625 -299.978141) (xy 339.37235 -300.024113) (xy 339.395195 -300.073864) (xy 339.41069 -300.12637)
			(xy 339.418515 -300.180553) (xy 339.418512 -300.235298) (xy 339.410679 -300.28948) (xy 339.395177 -300.341984)
			(xy 339.372325 -300.391732) (xy 339.342594 -300.4377) (xy 339.32495 -300.458632) (xy 339.324696 -300.458886)
			(xy 339.319109 -300.465972) (xy 339.312863 -300.482889) (xy 339.312504 -300.491906) (xy 339.312504 -300.558962)
			(xy 339.312879 -300.567977) (xy 339.319114 -300.584894) (xy 339.324696 -300.591982) (xy 339.32495 -300.591982)
			(xy 339.32495 -300.592236) (xy 339.342625 -300.613141) (xy 339.37235 -300.659113) (xy 339.395195 -300.708864)
			(xy 339.41069 -300.76137) (xy 339.418515 -300.815553) (xy 339.418512 -300.870298) (xy 339.410679 -300.92448)
			(xy 339.395177 -300.976984) (xy 339.372325 -301.026732) (xy 339.342594 -301.0727) (xy 339.32495 -301.093632)
			(xy 339.324696 -301.093886) (xy 339.319109 -301.100972) (xy 339.312863 -301.117889) (xy 339.312504 -301.126906)
			(xy 339.312504 -301.193962) (xy 339.312879 -301.202977) (xy 339.319114 -301.219894) (xy 339.324696 -301.226982)
			(xy 339.32495 -301.226982) (xy 339.32495 -301.227236) (xy 339.342565 -301.248188) (xy 339.372282 -301.294154)
			(xy 339.395123 -301.343897) (xy 339.41062 -301.396393) (xy 339.414624 -301.424086) (xy 341.863934 -301.424086)
			(xy 341.864384 -301.396715) (xy 341.872204 -301.342535) (xy 341.887697 -301.290031) (xy 341.910542 -301.240285)
			(xy 341.940271 -301.194319) (xy 341.957914 -301.173388) (xy 341.958168 -301.173134) (xy 341.963754 -301.166048)
			(xy 341.969999 -301.14913) (xy 341.97036 -301.140114) (xy 341.97036 -301.073058) (xy 341.969984 -301.064043)
			(xy 341.963751 -301.047125) (xy 341.958168 -301.040038) (xy 341.957914 -301.040038) (xy 341.957914 -301.039784)
			(xy 341.94026 -301.018862) (xy 341.910537 -300.972892) (xy 341.887693 -300.923144) (xy 341.872199 -300.87064)
			(xy 341.864372 -300.816461) (xy 341.864373 -300.761718) (xy 341.872203 -300.707539) (xy 341.887701 -300.655036)
			(xy 341.910547 -300.605289) (xy 341.940273 -300.559321) (xy 341.957914 -300.538388) (xy 341.958168 -300.538134)
			(xy 341.963754 -300.531048) (xy 341.969999 -300.51413) (xy 341.97036 -300.505114) (xy 341.97036 -300.438058)
			(xy 341.969984 -300.429043) (xy 341.963751 -300.412125) (xy 341.958168 -300.405038) (xy 341.957914 -300.405038)
			(xy 341.957914 -300.404784) (xy 341.94026 -300.383862) (xy 341.910537 -300.337892) (xy 341.887693 -300.288144)
			(xy 341.872199 -300.23564) (xy 341.864372 -300.181461) (xy 341.864373 -300.126718) (xy 341.872203 -300.072539)
			(xy 341.887701 -300.020036) (xy 341.910547 -299.970289) (xy 341.940273 -299.924321) (xy 341.957914 -299.903388)
			(xy 341.958168 -299.903134) (xy 341.963754 -299.896048) (xy 341.969999 -299.87913) (xy 341.97036 -299.870114)
			(xy 341.97036 -299.803058) (xy 341.969984 -299.794043) (xy 341.963751 -299.777125) (xy 341.958168 -299.770038)
			(xy 341.957914 -299.770038) (xy 341.957914 -299.769784) (xy 341.940303 -299.748829) (xy 341.910586 -299.702863)
			(xy 341.887745 -299.653121) (xy 341.872247 -299.600625) (xy 341.864412 -299.546454) (xy 341.863934 -299.519086)
			(xy 341.86442 -299.491835) (xy 341.872176 -299.437887) (xy 341.887531 -299.385592) (xy 341.910173 -299.336015)
			(xy 341.939639 -299.290165) (xy 341.97533 -299.248974) (xy 342.016521 -299.213283) (xy 342.062371 -299.183817)
			(xy 342.111948 -299.161175) (xy 342.164243 -299.14582) (xy 342.218191 -299.138064) (xy 342.272693 -299.138064)
			(xy 342.326641 -299.14582) (xy 342.378936 -299.161175) (xy 342.428513 -299.183817) (xy 342.474363 -299.213283)
			(xy 342.515554 -299.248974) (xy 342.551245 -299.290165) (xy 342.580711 -299.336015) (xy 342.603353 -299.385592)
			(xy 342.618708 -299.437887) (xy 342.626464 -299.491835) (xy 342.62695 -299.519086) (xy 342.626488 -299.546457)
			(xy 342.618671 -299.600636) (xy 342.603182 -299.65314) (xy 342.580339 -299.702887) (xy 342.550612 -299.748853)
			(xy 342.53297 -299.769784) (xy 342.532716 -299.770038) (xy 342.527151 -299.777139) (xy 342.520891 -299.794045)
			(xy 342.520524 -299.803058) (xy 342.520524 -299.870114) (xy 342.520869 -299.879132) (xy 342.527124 -299.896049)
			(xy 342.532716 -299.903134) (xy 342.53297 -299.903134) (xy 342.53297 -299.903388) (xy 342.550597 -299.924332)
			(xy 342.580323 -299.970298) (xy 342.603169 -300.020042) (xy 342.618667 -300.072542) (xy 342.626497 -300.126719)
			(xy 342.626498 -300.181459) (xy 342.618671 -300.235637) (xy 342.603176 -300.288138) (xy 342.580333 -300.337884)
			(xy 342.55061 -300.383851) (xy 342.53297 -300.404784) (xy 342.532716 -300.405038) (xy 342.527151 -300.412139)
			(xy 342.520891 -300.429045) (xy 342.520524 -300.438058) (xy 342.520524 -300.505114) (xy 342.520869 -300.514132)
			(xy 342.527124 -300.531049) (xy 342.532716 -300.538134) (xy 342.53297 -300.538134) (xy 342.53297 -300.538388)
			(xy 342.550597 -300.559332) (xy 342.580323 -300.605298) (xy 342.603169 -300.655042) (xy 342.618667 -300.707542)
			(xy 342.626497 -300.761719) (xy 342.626498 -300.816459) (xy 342.618671 -300.870637) (xy 342.603176 -300.923138)
			(xy 342.580333 -300.972884) (xy 342.55061 -301.018851) (xy 342.53297 -301.039784) (xy 342.532716 -301.040038)
			(xy 342.527151 -301.047139) (xy 342.520891 -301.064045) (xy 342.520524 -301.073058) (xy 342.520524 -301.140114)
			(xy 342.520869 -301.149132) (xy 342.527124 -301.166049) (xy 342.532716 -301.173134) (xy 342.53297 -301.173134)
			(xy 342.53297 -301.173388) (xy 342.550612 -301.194318) (xy 342.580325 -301.240291) (xy 342.60316 -301.290039)
			(xy 342.618651 -301.34254) (xy 342.626477 -301.396717) (xy 342.62695 -301.424086) (xy 342.626464 -301.451337)
			(xy 342.62264 -301.477934) (xy 345.496134 -301.477934) (xy 345.496612 -301.450564) (xy 345.504425 -301.396385)
			(xy 345.519911 -301.343882) (xy 345.542751 -301.294135) (xy 345.572473 -301.248168) (xy 345.590114 -301.227236)
			(xy 345.590368 -301.226982) (xy 345.595976 -301.219911) (xy 345.602208 -301.202982) (xy 345.60256 -301.193962)
			(xy 345.60256 -301.126906) (xy 345.602209 -301.117888) (xy 345.595958 -301.100971) (xy 345.590368 -301.093886)
			(xy 345.590114 -301.093886) (xy 345.590114 -301.093632) (xy 345.572507 -301.072672) (xy 345.542782 -301.026709)
			(xy 345.519935 -300.976967) (xy 345.504437 -300.924469) (xy 345.496606 -300.870294) (xy 345.496602 -300.815557)
			(xy 345.504426 -300.761381) (xy 345.519917 -300.708881) (xy 345.542757 -300.659136) (xy 345.572476 -300.613169)
			(xy 345.590114 -300.592236) (xy 345.590368 -300.591982) (xy 345.595976 -300.584911) (xy 345.602208 -300.567982)
			(xy 345.60256 -300.558962) (xy 345.60256 -300.491906) (xy 345.602209 -300.482888) (xy 345.595958 -300.465971)
			(xy 345.590368 -300.458886) (xy 345.590114 -300.458886) (xy 345.590114 -300.458632) (xy 345.572507 -300.437672)
			(xy 345.542782 -300.391709) (xy 345.519935 -300.341967) (xy 345.504437 -300.289469) (xy 345.496606 -300.235294)
			(xy 345.496602 -300.180557) (xy 345.504426 -300.126381) (xy 345.519917 -300.073881) (xy 345.542757 -300.024136)
			(xy 345.572476 -299.978169) (xy 345.590114 -299.957236) (xy 345.590368 -299.956982) (xy 345.595976 -299.949911)
			(xy 345.602208 -299.932982) (xy 345.60256 -299.923962) (xy 345.60256 -299.856906) (xy 345.602209 -299.847888)
			(xy 345.595958 -299.830971) (xy 345.590368 -299.823886) (xy 345.590114 -299.823886) (xy 345.590114 -299.823632)
			(xy 345.572479 -299.802697) (xy 345.542766 -299.756725) (xy 345.519929 -299.706978) (xy 345.504437 -299.654478)
			(xy 345.496608 -299.600303) (xy 345.496134 -299.572934) (xy 345.49662 -299.545683) (xy 345.504376 -299.491735)
			(xy 345.519731 -299.43944) (xy 345.542373 -299.389863) (xy 345.571839 -299.344013) (xy 345.60753 -299.302822)
			(xy 345.648721 -299.267131) (xy 345.694571 -299.237665) (xy 345.744148 -299.215023) (xy 345.796443 -299.199668)
			(xy 345.850391 -299.191912) (xy 345.904893 -299.191912) (xy 345.958841 -299.199668) (xy 346.011136 -299.215023)
			(xy 346.060713 -299.237665) (xy 346.106563 -299.267131) (xy 346.147754 -299.302822) (xy 346.183445 -299.344013)
			(xy 346.212911 -299.389863) (xy 346.235553 -299.43944) (xy 346.250908 -299.491735) (xy 346.258664 -299.545683)
			(xy 346.25915 -299.572934) (xy 346.258716 -299.600306) (xy 346.250892 -299.654486) (xy 346.235396 -299.70699)
			(xy 346.212547 -299.756737) (xy 346.182815 -299.802702) (xy 346.16517 -299.823632) (xy 346.164916 -299.823886)
			(xy 346.159331 -299.830974) (xy 346.153083 -299.84789) (xy 346.152724 -299.856906) (xy 346.152724 -299.923962)
			(xy 346.153094 -299.932978) (xy 346.159332 -299.949895) (xy 346.164916 -299.956982) (xy 346.16517 -299.956982)
			(xy 346.16517 -299.957236) (xy 346.182844 -299.978142) (xy 346.212568 -300.024114) (xy 346.235411 -300.073865)
			(xy 346.250905 -300.126371) (xy 346.258731 -300.180553) (xy 346.258727 -300.235298) (xy 346.250894 -300.289479)
			(xy 346.235393 -300.341983) (xy 346.212543 -300.391731) (xy 346.182813 -300.437699) (xy 346.16517 -300.458632)
			(xy 346.164916 -300.458886) (xy 346.159331 -300.465974) (xy 346.153083 -300.48289) (xy 346.152724 -300.491906)
			(xy 346.152724 -300.558962) (xy 346.153094 -300.567978) (xy 346.159332 -300.584895) (xy 346.164916 -300.591982)
			(xy 346.16517 -300.591982) (xy 346.16517 -300.592236) (xy 346.182844 -300.613142) (xy 346.212568 -300.659114)
			(xy 346.235411 -300.708865) (xy 346.250905 -300.761371) (xy 346.258731 -300.815553) (xy 346.258727 -300.870298)
			(xy 346.250894 -300.924479) (xy 346.235393 -300.976983) (xy 346.212543 -301.026731) (xy 346.182813 -301.072699)
			(xy 346.16517 -301.093632) (xy 346.164916 -301.093886) (xy 346.159331 -301.100974) (xy 346.153083 -301.11789)
			(xy 346.152724 -301.126906) (xy 346.152724 -301.193962) (xy 346.153094 -301.202978) (xy 346.159332 -301.219895)
			(xy 346.164916 -301.226982) (xy 346.16517 -301.226982) (xy 346.16517 -301.227236) (xy 346.182788 -301.248185)
			(xy 346.212504 -301.294153) (xy 346.235344 -301.343896) (xy 346.25084 -301.396393) (xy 346.254845 -301.424086)
			(xy 353.617022 -301.424086) (xy 353.617475 -301.396715) (xy 353.625295 -301.342535) (xy 353.640787 -301.290032)
			(xy 353.663632 -301.240285) (xy 353.693359 -301.194319) (xy 353.711002 -301.173388) (xy 353.711256 -301.173134)
			(xy 353.716841 -301.166047) (xy 353.723087 -301.14913) (xy 353.723448 -301.140114) (xy 353.723448 -301.073058)
			(xy 353.723075 -301.064043) (xy 353.71684 -301.047125) (xy 353.711256 -301.040038) (xy 353.711002 -301.040038)
			(xy 353.711002 -301.039784) (xy 353.693349 -301.018862) (xy 353.663626 -300.972892) (xy 353.640783 -300.923143)
			(xy 353.625289 -300.87064) (xy 353.617462 -300.81646) (xy 353.617464 -300.761718) (xy 353.625294 -300.707539)
			(xy 353.640791 -300.655037) (xy 353.663636 -300.60529) (xy 353.693361 -300.559321) (xy 353.711002 -300.538388)
			(xy 353.711256 -300.538134) (xy 353.716841 -300.531047) (xy 353.723087 -300.51413) (xy 353.723448 -300.505114)
			(xy 353.723448 -300.438058) (xy 353.723075 -300.429043) (xy 353.71684 -300.412125) (xy 353.711256 -300.405038)
			(xy 353.711002 -300.405038) (xy 353.711002 -300.404784) (xy 353.693349 -300.383862) (xy 353.663626 -300.337892)
			(xy 353.640783 -300.288143) (xy 353.625289 -300.23564) (xy 353.617462 -300.18146) (xy 353.617464 -300.126718)
			(xy 353.625294 -300.072539) (xy 353.640791 -300.020037) (xy 353.663636 -299.97029) (xy 353.693361 -299.924321)
			(xy 353.711002 -299.903388) (xy 353.711256 -299.903134) (xy 353.716841 -299.896047) (xy 353.723087 -299.87913)
			(xy 353.723448 -299.870114) (xy 353.723448 -299.803058) (xy 353.723075 -299.794043) (xy 353.71684 -299.777125)
			(xy 353.711256 -299.770038) (xy 353.711002 -299.770038) (xy 353.711002 -299.769784) (xy 353.693389 -299.748831)
			(xy 353.663673 -299.702864) (xy 353.640832 -299.653122) (xy 353.625335 -299.600626) (xy 353.6175 -299.546454)
			(xy 353.617022 -299.519086) (xy 353.617508 -299.491835) (xy 353.625264 -299.437887) (xy 353.640619 -299.385592)
			(xy 353.663261 -299.336015) (xy 353.692727 -299.290165) (xy 353.728418 -299.248974) (xy 353.769609 -299.213283)
			(xy 353.815459 -299.183817) (xy 353.865036 -299.161175) (xy 353.917331 -299.14582) (xy 353.971279 -299.138064)
			(xy 354.025781 -299.138064) (xy 354.079729 -299.14582) (xy 354.132024 -299.161175) (xy 354.181601 -299.183817)
			(xy 354.227451 -299.213283) (xy 354.268642 -299.248974) (xy 354.304333 -299.290165) (xy 354.333799 -299.336015)
			(xy 354.356441 -299.385592) (xy 354.371796 -299.437887) (xy 354.379552 -299.491835) (xy 354.380038 -299.519086)
			(xy 354.379579 -299.546457) (xy 354.371762 -299.600637) (xy 354.356272 -299.65314) (xy 354.333428 -299.702887)
			(xy 354.303701 -299.748853) (xy 354.286058 -299.769784) (xy 354.285804 -299.770038) (xy 354.280238 -299.777139)
			(xy 354.273979 -299.794045) (xy 354.273612 -299.803058) (xy 354.273612 -299.870114) (xy 354.27396 -299.879132)
			(xy 354.280213 -299.896049) (xy 354.285804 -299.903134) (xy 354.286058 -299.903134) (xy 354.286058 -299.903388)
			(xy 354.303686 -299.924332) (xy 354.333412 -299.970297) (xy 354.356259 -300.020041) (xy 354.371757 -300.072542)
			(xy 354.379587 -300.126719) (xy 354.379589 -300.18146) (xy 354.371762 -300.235637) (xy 354.356267 -300.288139)
			(xy 354.333422 -300.337884) (xy 354.303698 -300.383852) (xy 354.286058 -300.404784) (xy 354.285804 -300.405038)
			(xy 354.280238 -300.412139) (xy 354.273979 -300.429045) (xy 354.273612 -300.438058) (xy 354.273612 -300.505114)
			(xy 354.27396 -300.514132) (xy 354.280213 -300.531049) (xy 354.285804 -300.538134) (xy 354.286058 -300.538134)
			(xy 354.286058 -300.538388) (xy 354.303686 -300.559332) (xy 354.333412 -300.605297) (xy 354.356259 -300.655041)
			(xy 354.371757 -300.707542) (xy 354.379587 -300.761719) (xy 354.379589 -300.81646) (xy 354.371762 -300.870637)
			(xy 354.356267 -300.923139) (xy 354.333422 -300.972884) (xy 354.303698 -301.018852) (xy 354.286058 -301.039784)
			(xy 354.285804 -301.040038) (xy 354.280238 -301.047139) (xy 354.273979 -301.064045) (xy 354.273612 -301.073058)
			(xy 354.273612 -301.140114) (xy 354.27396 -301.149132) (xy 354.280213 -301.166049) (xy 354.285804 -301.173134)
			(xy 354.286058 -301.173134) (xy 354.286058 -301.173388) (xy 354.303698 -301.194319) (xy 354.333411 -301.240292)
			(xy 354.356248 -301.290039) (xy 354.371738 -301.34254) (xy 354.379565 -301.396717) (xy 354.380038 -301.424086)
			(xy 354.379552 -301.451337) (xy 354.375728 -301.477934) (xy 357.249222 -301.477934) (xy 357.249703 -301.450564)
			(xy 357.257516 -301.396386) (xy 357.273002 -301.343882) (xy 357.29584 -301.294135) (xy 357.325562 -301.248168)
			(xy 357.343202 -301.227236) (xy 357.343456 -301.226982) (xy 357.349063 -301.21991) (xy 357.355296 -301.202982)
			(xy 357.355648 -301.193962) (xy 357.355648 -301.126906) (xy 357.355299 -301.117888) (xy 357.349047 -301.100971)
			(xy 357.343456 -301.093886) (xy 357.343202 -301.093886) (xy 357.343202 -301.093632) (xy 357.325596 -301.072672)
			(xy 357.295871 -301.026708) (xy 357.273026 -300.976966) (xy 357.257528 -300.924469) (xy 357.249697 -300.870294)
			(xy 357.249693 -300.815557) (xy 357.257517 -300.761381) (xy 357.273008 -300.708882) (xy 357.295847 -300.659137)
			(xy 357.325565 -300.613169) (xy 357.343202 -300.592236) (xy 357.343456 -300.591982) (xy 357.349063 -300.58491)
			(xy 357.355296 -300.567982) (xy 357.355648 -300.558962) (xy 357.355648 -300.491906) (xy 357.355299 -300.482888)
			(xy 357.349047 -300.465971) (xy 357.343456 -300.458886) (xy 357.343202 -300.458886) (xy 357.343202 -300.458632)
			(xy 357.325596 -300.437672) (xy 357.295871 -300.391708) (xy 357.273026 -300.341966) (xy 357.257528 -300.289469)
			(xy 357.249697 -300.235294) (xy 357.249693 -300.180557) (xy 357.257517 -300.126381) (xy 357.273008 -300.073882)
			(xy 357.295847 -300.024137) (xy 357.325565 -299.978169) (xy 357.343202 -299.957236) (xy 357.343456 -299.956982)
			(xy 357.349063 -299.94991) (xy 357.355296 -299.932982) (xy 357.355648 -299.923962) (xy 357.355648 -299.856906)
			(xy 357.355299 -299.847888) (xy 357.349047 -299.830971) (xy 357.343456 -299.823886) (xy 357.343202 -299.823886)
			(xy 357.343202 -299.823632) (xy 357.325565 -299.802698) (xy 357.295853 -299.756726) (xy 357.273016 -299.706979)
			(xy 357.257525 -299.654479) (xy 357.249696 -299.600303) (xy 357.249222 -299.572934) (xy 357.249708 -299.545683)
			(xy 357.257464 -299.491735) (xy 357.272819 -299.43944) (xy 357.295461 -299.389863) (xy 357.324927 -299.344013)
			(xy 357.360618 -299.302822) (xy 357.401809 -299.267131) (xy 357.447659 -299.237665) (xy 357.497236 -299.215023)
			(xy 357.549531 -299.199668) (xy 357.603479 -299.191912) (xy 357.657981 -299.191912) (xy 357.711929 -299.199668)
			(xy 357.764224 -299.215023) (xy 357.813801 -299.237665) (xy 357.859651 -299.267131) (xy 357.900842 -299.302822)
			(xy 357.936533 -299.344013) (xy 357.965999 -299.389863) (xy 357.988641 -299.43944) (xy 358.003996 -299.491735)
			(xy 358.011752 -299.545683) (xy 358.012238 -299.572934) (xy 358.011807 -299.600306) (xy 358.003983 -299.654487)
			(xy 357.988487 -299.706991) (xy 357.965637 -299.756737) (xy 357.935904 -299.802702) (xy 357.918258 -299.823632)
			(xy 357.918004 -299.823886) (xy 357.912418 -299.830973) (xy 357.906171 -299.847889) (xy 357.905812 -299.856906)
			(xy 357.905812 -299.923962) (xy 357.906185 -299.932977) (xy 357.912421 -299.949894) (xy 357.918004 -299.956982)
			(xy 357.918258 -299.956982) (xy 357.918258 -299.957236) (xy 357.935933 -299.978141) (xy 357.965657 -300.024114)
			(xy 357.988501 -300.073864) (xy 358.003996 -300.126371) (xy 358.011822 -300.180553) (xy 358.011818 -300.235298)
			(xy 358.003985 -300.289479) (xy 357.988483 -300.341984) (xy 357.965633 -300.391731) (xy 357.935902 -300.437699)
			(xy 357.918258 -300.458632) (xy 357.918004 -300.458886) (xy 357.912418 -300.465973) (xy 357.906171 -300.482889)
			(xy 357.905812 -300.491906) (xy 357.905812 -300.558962) (xy 357.906185 -300.567977) (xy 357.912421 -300.584894)
			(xy 357.918004 -300.591982) (xy 357.918258 -300.591982) (xy 357.918258 -300.592236) (xy 357.935933 -300.613141)
			(xy 357.965657 -300.659114) (xy 357.988501 -300.708864) (xy 358.003996 -300.761371) (xy 358.011822 -300.815553)
			(xy 358.011818 -300.870298) (xy 358.003985 -300.924479) (xy 357.988483 -300.976984) (xy 357.965633 -301.026731)
			(xy 357.935902 -301.072699) (xy 357.918258 -301.093632) (xy 357.918004 -301.093886) (xy 357.912418 -301.100973)
			(xy 357.906171 -301.117889) (xy 357.905812 -301.126906) (xy 357.905812 -301.193962) (xy 357.906185 -301.202977)
			(xy 357.912421 -301.219894) (xy 357.918004 -301.226982) (xy 357.918258 -301.226982) (xy 357.918258 -301.227236)
			(xy 357.935874 -301.248187) (xy 357.965591 -301.294154) (xy 357.988432 -301.343896) (xy 358.003928 -301.396393)
			(xy 358.007932 -301.424086) (xy 360.457242 -301.424086) (xy 360.45769 -301.396715) (xy 360.46551 -301.342535)
			(xy 360.481003 -301.290031) (xy 360.503849 -301.240284) (xy 360.533578 -301.194319) (xy 360.551222 -301.173388)
			(xy 360.551476 -301.173134) (xy 360.557063 -301.166048) (xy 360.563308 -301.149131) (xy 360.563668 -301.140114)
			(xy 360.563668 -301.073058) (xy 360.56329 -301.064043) (xy 360.557058 -301.047126) (xy 360.551476 -301.040038)
			(xy 360.551222 -301.040038) (xy 360.551222 -301.039784) (xy 360.533568 -301.018862) (xy 360.503844 -300.972892)
			(xy 360.481 -300.923144) (xy 360.465505 -300.870641) (xy 360.457678 -300.816461) (xy 360.457679 -300.761718)
			(xy 360.465509 -300.707539) (xy 360.481007 -300.655036) (xy 360.503854 -300.605289) (xy 360.533581 -300.559321)
			(xy 360.551222 -300.538388) (xy 360.551476 -300.538134) (xy 360.557063 -300.531048) (xy 360.563308 -300.514131)
			(xy 360.563668 -300.505114) (xy 360.563668 -300.438058) (xy 360.56329 -300.429043) (xy 360.557058 -300.412126)
			(xy 360.551476 -300.405038) (xy 360.551222 -300.405038) (xy 360.551222 -300.404784) (xy 360.533568 -300.383862)
			(xy 360.503844 -300.337892) (xy 360.481 -300.288144) (xy 360.465505 -300.235641) (xy 360.457678 -300.181461)
			(xy 360.457679 -300.126718) (xy 360.465509 -300.072539) (xy 360.481007 -300.020036) (xy 360.503854 -299.970289)
			(xy 360.533581 -299.924321) (xy 360.551222 -299.903388) (xy 360.551476 -299.903134) (xy 360.557063 -299.896048)
			(xy 360.563308 -299.879131) (xy 360.563668 -299.870114) (xy 360.563668 -299.803058) (xy 360.56329 -299.794043)
			(xy 360.557058 -299.777126) (xy 360.551476 -299.770038) (xy 360.551222 -299.770038) (xy 360.551222 -299.769784)
			(xy 360.533612 -299.748828) (xy 360.503895 -299.702862) (xy 360.481053 -299.653121) (xy 360.465555 -299.600625)
			(xy 360.45772 -299.546454) (xy 360.457242 -299.519086) (xy 360.457728 -299.491835) (xy 360.465484 -299.437887)
			(xy 360.480839 -299.385592) (xy 360.503481 -299.336015) (xy 360.532947 -299.290165) (xy 360.568638 -299.248974)
			(xy 360.609829 -299.213283) (xy 360.655679 -299.183817) (xy 360.705256 -299.161175) (xy 360.757551 -299.14582)
			(xy 360.811499 -299.138064) (xy 360.866001 -299.138064) (xy 360.919949 -299.14582) (xy 360.972244 -299.161175)
			(xy 361.021821 -299.183817) (xy 361.067671 -299.213283) (xy 361.108862 -299.248974) (xy 361.144553 -299.290165)
			(xy 361.174019 -299.336015) (xy 361.196661 -299.385592) (xy 361.212016 -299.437887) (xy 361.219772 -299.491835)
			(xy 361.220258 -299.519086) (xy 361.219794 -299.546456) (xy 361.211977 -299.600636) (xy 361.196488 -299.65314)
			(xy 361.173646 -299.702886) (xy 361.14392 -299.748853) (xy 361.126278 -299.769784) (xy 361.126024 -299.770038)
			(xy 361.120448 -299.777132) (xy 361.114197 -299.794043) (xy 361.113832 -299.803058) (xy 361.113832 -299.870114)
			(xy 361.114175 -299.879132) (xy 361.120432 -299.89605) (xy 361.126024 -299.903134) (xy 361.126278 -299.903134)
			(xy 361.126278 -299.903388) (xy 361.143905 -299.924332) (xy 361.17363 -299.970298) (xy 361.196476 -300.020042)
			(xy 361.211973 -300.072543) (xy 361.219803 -300.12672) (xy 361.219804 -300.181459) (xy 361.211977 -300.235637)
			(xy 361.196483 -300.288138) (xy 361.17364 -300.337884) (xy 361.143917 -300.383851) (xy 361.126278 -300.404784)
			(xy 361.126024 -300.405038) (xy 361.120448 -300.412132) (xy 361.114197 -300.429043) (xy 361.113832 -300.438058)
			(xy 361.113832 -300.505114) (xy 361.114175 -300.514132) (xy 361.120432 -300.53105) (xy 361.126024 -300.538134)
			(xy 361.126278 -300.538134) (xy 361.126278 -300.538388) (xy 361.143905 -300.559332) (xy 361.17363 -300.605298)
			(xy 361.196476 -300.655042) (xy 361.211973 -300.707543) (xy 361.219803 -300.76172) (xy 361.219804 -300.816459)
			(xy 361.211977 -300.870637) (xy 361.196483 -300.923138) (xy 361.17364 -300.972884) (xy 361.143917 -301.018851)
			(xy 361.126278 -301.039784) (xy 361.126024 -301.040038) (xy 361.120448 -301.047132) (xy 361.114197 -301.064043)
			(xy 361.113832 -301.073058) (xy 361.113832 -301.140114) (xy 361.114175 -301.149132) (xy 361.120432 -301.16605)
			(xy 361.126024 -301.173134) (xy 361.126278 -301.173134) (xy 361.126278 -301.173388) (xy 361.143922 -301.194317)
			(xy 361.173633 -301.24029) (xy 361.196469 -301.290038) (xy 361.211959 -301.34254) (xy 361.219785 -301.396717)
			(xy 361.220258 -301.424086) (xy 361.219772 -301.451337) (xy 361.215948 -301.477934) (xy 364.089442 -301.477934)
			(xy 364.089918 -301.450564) (xy 364.097732 -301.396385) (xy 364.113218 -301.343882) (xy 364.136058 -301.294134)
			(xy 364.165781 -301.248168) (xy 364.183422 -301.227236) (xy 364.183676 -301.226982) (xy 364.189285 -301.219911)
			(xy 364.195516 -301.202982) (xy 364.195868 -301.193962) (xy 364.195868 -301.126906) (xy 364.195515 -301.117889)
			(xy 364.189265 -301.100971) (xy 364.183676 -301.093886) (xy 364.183422 -301.093886) (xy 364.183422 -301.093632)
			(xy 364.165815 -301.072672) (xy 364.136089 -301.026709) (xy 364.113242 -300.976967) (xy 364.097743 -300.924469)
			(xy 364.089912 -300.870295) (xy 364.089908 -300.815557) (xy 364.097732 -300.761381) (xy 364.113224 -300.708881)
			(xy 364.136064 -300.659136) (xy 364.165784 -300.613169) (xy 364.183422 -300.592236) (xy 364.183676 -300.591982)
			(xy 364.189285 -300.584911) (xy 364.195516 -300.567982) (xy 364.195868 -300.558962) (xy 364.195868 -300.491906)
			(xy 364.195515 -300.482889) (xy 364.189265 -300.465971) (xy 364.183676 -300.458886) (xy 364.183422 -300.458886)
			(xy 364.183422 -300.458632) (xy 364.165815 -300.437672) (xy 364.136089 -300.391709) (xy 364.113242 -300.341967)
			(xy 364.097743 -300.289469) (xy 364.089912 -300.235295) (xy 364.089908 -300.180557) (xy 364.097732 -300.126381)
			(xy 364.113224 -300.073881) (xy 364.136064 -300.024136) (xy 364.165784 -299.978169) (xy 364.183422 -299.957236)
			(xy 364.183676 -299.956982) (xy 364.189285 -299.949911) (xy 364.195516 -299.932982) (xy 364.195868 -299.923962)
			(xy 364.195868 -299.856906) (xy 364.195515 -299.847889) (xy 364.189265 -299.830971) (xy 364.183676 -299.823886)
			(xy 364.183422 -299.823886) (xy 364.183422 -299.823632) (xy 364.165788 -299.802696) (xy 364.136075 -299.756725)
			(xy 364.113237 -299.706978) (xy 364.097745 -299.654478) (xy 364.089916 -299.600303) (xy 364.089442 -299.572934)
			(xy 364.089928 -299.545683) (xy 364.097684 -299.491735) (xy 364.113039 -299.43944) (xy 364.135681 -299.389863)
			(xy 364.165147 -299.344013) (xy 364.200838 -299.302822) (xy 364.242029 -299.267131) (xy 364.287879 -299.237665)
			(xy 364.337456 -299.215023) (xy 364.389751 -299.199668) (xy 364.443699 -299.191912) (xy 364.498201 -299.191912)
			(xy 364.552149 -299.199668) (xy 364.604444 -299.215023) (xy 364.654021 -299.237665) (xy 364.699871 -299.267131)
			(xy 364.741062 -299.302822) (xy 364.776753 -299.344013) (xy 364.806219 -299.389863) (xy 364.828861 -299.43944)
			(xy 364.844216 -299.491735) (xy 364.851972 -299.545683) (xy 364.852458 -299.572934) (xy 364.852022 -299.600305)
			(xy 364.844199 -299.654486) (xy 364.828703 -299.70699) (xy 364.805854 -299.756736) (xy 364.776123 -299.802702)
			(xy 364.758478 -299.823632) (xy 364.758224 -299.823886) (xy 364.752628 -299.830966) (xy 364.746389 -299.847888)
			(xy 364.746032 -299.856906) (xy 364.746032 -299.923962) (xy 364.7464 -299.932978) (xy 364.752639 -299.949895)
			(xy 364.758224 -299.956982) (xy 364.758478 -299.956982) (xy 364.758478 -299.957236) (xy 364.776152 -299.978142)
			(xy 364.805875 -300.024114) (xy 364.828718 -300.073865) (xy 364.844211 -300.126371) (xy 364.852037 -300.180553)
			(xy 364.852033 -300.235298) (xy 364.8442 -300.289479) (xy 364.8287 -300.341983) (xy 364.80585 -300.391731)
			(xy 364.776121 -300.437699) (xy 364.758478 -300.458632) (xy 364.758224 -300.458886) (xy 364.752628 -300.465966)
			(xy 364.746389 -300.482888) (xy 364.746032 -300.491906) (xy 364.746032 -300.558962) (xy 364.7464 -300.567978)
			(xy 364.752639 -300.584895) (xy 364.758224 -300.591982) (xy 364.758478 -300.591982) (xy 364.758478 -300.592236)
			(xy 364.776152 -300.613142) (xy 364.805875 -300.659114) (xy 364.828718 -300.708865) (xy 364.844211 -300.761371)
			(xy 364.852037 -300.815553) (xy 364.852033 -300.870298) (xy 364.8442 -300.924479) (xy 364.8287 -300.976983)
			(xy 364.80585 -301.026731) (xy 364.776121 -301.072699) (xy 364.758478 -301.093632) (xy 364.758224 -301.093886)
			(xy 364.752628 -301.100966) (xy 364.746389 -301.117888) (xy 364.746032 -301.126906) (xy 364.746032 -301.193962)
			(xy 364.7464 -301.202978) (xy 364.752639 -301.219895) (xy 364.758224 -301.226982) (xy 364.758478 -301.226982)
			(xy 364.758478 -301.227236) (xy 364.776097 -301.248184) (xy 364.805813 -301.294152) (xy 364.828653 -301.343896)
			(xy 364.844149 -301.396393) (xy 364.851982 -301.450566) (xy 364.852458 -301.477934) (xy 364.851972 -301.505185)
			(xy 364.844216 -301.559133) (xy 364.828861 -301.611428) (xy 364.806219 -301.661005) (xy 364.776753 -301.706855)
			(xy 364.741062 -301.748046) (xy 364.699871 -301.783737) (xy 364.654021 -301.813203) (xy 364.604444 -301.835845)
			(xy 364.552149 -301.8512) (xy 364.498201 -301.858956) (xy 364.443699 -301.858956) (xy 364.389751 -301.8512)
			(xy 364.337456 -301.835845) (xy 364.287879 -301.813203) (xy 364.242029 -301.783737) (xy 364.200838 -301.748046)
			(xy 364.165147 -301.706855) (xy 364.135681 -301.661005) (xy 364.113039 -301.611428) (xy 364.097684 -301.559133)
			(xy 364.089928 -301.505185) (xy 364.089442 -301.477934) (xy 361.215948 -301.477934) (xy 361.212016 -301.505285)
			(xy 361.196661 -301.55758) (xy 361.174019 -301.607157) (xy 361.144553 -301.653007) (xy 361.108862 -301.694198)
			(xy 361.067671 -301.729889) (xy 361.021821 -301.759355) (xy 360.972244 -301.781997) (xy 360.919949 -301.797352)
			(xy 360.866001 -301.805108) (xy 360.811499 -301.805108) (xy 360.757551 -301.797352) (xy 360.705256 -301.781997)
			(xy 360.655679 -301.759355) (xy 360.609829 -301.729889) (xy 360.568638 -301.694198) (xy 360.532947 -301.653007)
			(xy 360.503481 -301.607157) (xy 360.480839 -301.55758) (xy 360.465484 -301.505285) (xy 360.457728 -301.451337)
			(xy 360.457242 -301.424086) (xy 358.007932 -301.424086) (xy 358.011761 -301.450566) (xy 358.012238 -301.477934)
			(xy 358.011752 -301.505185) (xy 358.003996 -301.559133) (xy 357.988641 -301.611428) (xy 357.965999 -301.661005)
			(xy 357.936533 -301.706855) (xy 357.900842 -301.748046) (xy 357.859651 -301.783737) (xy 357.813801 -301.813203)
			(xy 357.764224 -301.835845) (xy 357.711929 -301.8512) (xy 357.657981 -301.858956) (xy 357.603479 -301.858956)
			(xy 357.549531 -301.8512) (xy 357.497236 -301.835845) (xy 357.447659 -301.813203) (xy 357.401809 -301.783737)
			(xy 357.360618 -301.748046) (xy 357.324927 -301.706855) (xy 357.295461 -301.661005) (xy 357.272819 -301.611428)
			(xy 357.257464 -301.559133) (xy 357.249708 -301.505185) (xy 357.249222 -301.477934) (xy 354.375728 -301.477934)
			(xy 354.371796 -301.505285) (xy 354.356441 -301.55758) (xy 354.333799 -301.607157) (xy 354.304333 -301.653007)
			(xy 354.268642 -301.694198) (xy 354.227451 -301.729889) (xy 354.181601 -301.759355) (xy 354.132024 -301.781997)
			(xy 354.079729 -301.797352) (xy 354.025781 -301.805108) (xy 353.971279 -301.805108) (xy 353.917331 -301.797352)
			(xy 353.865036 -301.781997) (xy 353.815459 -301.759355) (xy 353.769609 -301.729889) (xy 353.728418 -301.694198)
			(xy 353.692727 -301.653007) (xy 353.663261 -301.607157) (xy 353.640619 -301.55758) (xy 353.625264 -301.505285)
			(xy 353.617508 -301.451337) (xy 353.617022 -301.424086) (xy 346.254845 -301.424086) (xy 346.258674 -301.450566)
			(xy 346.25915 -301.477934) (xy 346.258664 -301.505185) (xy 346.250908 -301.559133) (xy 346.235553 -301.611428)
			(xy 346.212911 -301.661005) (xy 346.183445 -301.706855) (xy 346.147754 -301.748046) (xy 346.106563 -301.783737)
			(xy 346.060713 -301.813203) (xy 346.011136 -301.835845) (xy 345.958841 -301.8512) (xy 345.904893 -301.858956)
			(xy 345.850391 -301.858956) (xy 345.796443 -301.8512) (xy 345.744148 -301.835845) (xy 345.694571 -301.813203)
			(xy 345.648721 -301.783737) (xy 345.60753 -301.748046) (xy 345.571839 -301.706855) (xy 345.542373 -301.661005)
			(xy 345.519731 -301.611428) (xy 345.504376 -301.559133) (xy 345.49662 -301.505185) (xy 345.496134 -301.477934)
			(xy 342.62264 -301.477934) (xy 342.618708 -301.505285) (xy 342.603353 -301.55758) (xy 342.580711 -301.607157)
			(xy 342.551245 -301.653007) (xy 342.515554 -301.694198) (xy 342.474363 -301.729889) (xy 342.428513 -301.759355)
			(xy 342.378936 -301.781997) (xy 342.326641 -301.797352) (xy 342.272693 -301.805108) (xy 342.218191 -301.805108)
			(xy 342.164243 -301.797352) (xy 342.111948 -301.781997) (xy 342.062371 -301.759355) (xy 342.016521 -301.729889)
			(xy 341.97533 -301.694198) (xy 341.939639 -301.653007) (xy 341.910173 -301.607157) (xy 341.887531 -301.55758)
			(xy 341.872176 -301.505285) (xy 341.86442 -301.451337) (xy 341.863934 -301.424086) (xy 339.414624 -301.424086)
			(xy 339.418453 -301.450566) (xy 339.41893 -301.477934) (xy 339.418444 -301.505185) (xy 339.410688 -301.559133)
			(xy 339.395333 -301.611428) (xy 339.372691 -301.661005) (xy 339.343225 -301.706855) (xy 339.307534 -301.748046)
			(xy 339.266343 -301.783737) (xy 339.220493 -301.813203) (xy 339.170916 -301.835845) (xy 339.118621 -301.8512)
			(xy 339.064673 -301.858956) (xy 339.010171 -301.858956) (xy 338.956223 -301.8512) (xy 338.903928 -301.835845)
			(xy 338.854351 -301.813203) (xy 338.808501 -301.783737) (xy 338.76731 -301.748046) (xy 338.731619 -301.706855)
			(xy 338.702153 -301.661005) (xy 338.679511 -301.611428) (xy 338.664156 -301.559133) (xy 338.6564 -301.505185)
			(xy 338.655914 -301.477934) (xy 335.78242 -301.477934) (xy 335.778488 -301.505285) (xy 335.763133 -301.55758)
			(xy 335.740491 -301.607157) (xy 335.711025 -301.653007) (xy 335.675334 -301.694198) (xy 335.634143 -301.729889)
			(xy 335.588293 -301.759355) (xy 335.538716 -301.781997) (xy 335.486421 -301.797352) (xy 335.432473 -301.805108)
			(xy 335.377971 -301.805108) (xy 335.324023 -301.797352) (xy 335.271728 -301.781997) (xy 335.222151 -301.759355)
			(xy 335.176301 -301.729889) (xy 335.13511 -301.694198) (xy 335.099419 -301.653007) (xy 335.069953 -301.607157)
			(xy 335.047311 -301.55758) (xy 335.031956 -301.505285) (xy 335.0242 -301.451337) (xy 335.023714 -301.424086)
			(xy 330.943966 -301.424086) (xy 330.943966 -302.925734) (xy 334.435704 -302.925734) (xy 334.436189 -302.898364)
			(xy 334.444002 -302.844186) (xy 334.459487 -302.791683) (xy 334.482324 -302.741936) (xy 334.512045 -302.695968)
			(xy 334.529684 -302.675036) (xy 334.529938 -302.674782) (xy 334.535542 -302.667708) (xy 334.541777 -302.650781)
			(xy 334.54213 -302.641762) (xy 334.54213 -302.574706) (xy 334.541763 -302.56569) (xy 334.535522 -302.548774)
			(xy 334.529938 -302.541686) (xy 334.529684 -302.541686) (xy 334.529684 -302.541432) (xy 334.512044 -302.520501)
			(xy 334.482333 -302.474527) (xy 334.459497 -302.42478) (xy 334.444006 -302.372279) (xy 334.436178 -302.318103)
			(xy 334.435704 -302.290734) (xy 334.43619 -302.263483) (xy 334.443946 -302.209535) (xy 334.459301 -302.15724)
			(xy 334.481943 -302.107663) (xy 334.511409 -302.061813) (xy 334.5471 -302.020622) (xy 334.588291 -301.984931)
			(xy 334.634141 -301.955465) (xy 334.683718 -301.932823) (xy 334.736013 -301.917468) (xy 334.789961 -301.909712)
			(xy 334.844463 -301.909712) (xy 334.898411 -301.917468) (xy 334.950706 -301.932823) (xy 335.000283 -301.955465)
			(xy 335.046133 -301.984931) (xy 335.087324 -302.020622) (xy 335.123015 -302.061813) (xy 335.152481 -302.107663)
			(xy 335.175123 -302.15724) (xy 335.190478 -302.209535) (xy 335.198234 -302.263483) (xy 335.19872 -302.290734)
			(xy 335.198293 -302.318106) (xy 335.190469 -302.372287) (xy 335.174972 -302.424792) (xy 335.152121 -302.474538)
			(xy 335.122386 -302.520502) (xy 335.10474 -302.541432) (xy 335.104486 -302.541686) (xy 335.098898 -302.548771)
			(xy 335.092652 -302.565689) (xy 335.092294 -302.574706) (xy 335.092294 -302.641762) (xy 335.09267 -302.650777)
			(xy 335.098905 -302.667694) (xy 335.104486 -302.674782) (xy 335.10474 -302.674782) (xy 335.10474 -302.675036)
			(xy 335.122369 -302.695976) (xy 335.152081 -302.741947) (xy 335.174919 -302.791693) (xy 335.190412 -302.844191)
			(xy 335.198244 -302.898365) (xy 335.19872 -302.925734) (xy 337.855814 -302.925734) (xy 337.856297 -302.898364)
			(xy 337.86411 -302.844186) (xy 337.879595 -302.791683) (xy 337.902433 -302.741936) (xy 337.932154 -302.695968)
			(xy 337.949794 -302.675036) (xy 337.950048 -302.674782) (xy 337.955654 -302.667709) (xy 337.961888 -302.650782)
			(xy 337.96224 -302.641762) (xy 337.96224 -302.574706) (xy 337.961893 -302.565688) (xy 337.95564 -302.54877)
			(xy 337.950048 -302.541686) (xy 337.949794 -302.541686) (xy 337.949794 -302.541432) (xy 337.932156 -302.520499)
			(xy 337.902444 -302.474527) (xy 337.879608 -302.424779) (xy 337.864117 -302.372279) (xy 337.856288 -302.318103)
			(xy 337.855814 -302.290734) (xy 337.8563 -302.263483) (xy 337.864056 -302.209535) (xy 337.879411 -302.15724)
			(xy 337.902053 -302.107663) (xy 337.931519 -302.061813) (xy 337.96721 -302.020622) (xy 338.008401 -301.984931)
			(xy 338.054251 -301.955465) (xy 338.103828 -301.932823) (xy 338.156123 -301.917468) (xy 338.210071 -301.909712)
			(xy 338.264573 -301.909712) (xy 338.318521 -301.917468) (xy 338.370816 -301.932823) (xy 338.420393 -301.955465)
			(xy 338.466243 -301.984931) (xy 338.507434 -302.020622) (xy 338.543125 -302.061813) (xy 338.572591 -302.107663)
			(xy 338.595233 -302.15724) (xy 338.610588 -302.209535) (xy 338.618344 -302.263483) (xy 338.61883 -302.290734)
			(xy 338.618401 -302.318106) (xy 338.610577 -302.372287) (xy 338.59508 -302.424791) (xy 338.57223 -302.474538)
			(xy 338.542496 -302.520502) (xy 338.52485 -302.541432) (xy 338.524596 -302.541686) (xy 338.519009 -302.548772)
			(xy 338.512763 -302.565689) (xy 338.512404 -302.574706) (xy 338.512404 -302.641762) (xy 338.512779 -302.650777)
			(xy 338.519014 -302.667694) (xy 338.524596 -302.674782) (xy 338.52485 -302.674782) (xy 338.52485 -302.675036)
			(xy 338.542465 -302.695988) (xy 338.572182 -302.741954) (xy 338.595023 -302.791697) (xy 338.61052 -302.844193)
			(xy 338.618353 -302.898366) (xy 338.61883 -302.925734) (xy 339.243924 -302.925734) (xy 339.244404 -302.898364)
			(xy 339.252218 -302.844185) (xy 339.267703 -302.791682) (xy 339.290542 -302.741935) (xy 339.320264 -302.695968)
			(xy 339.337904 -302.675036) (xy 339.338158 -302.674782) (xy 339.343765 -302.66771) (xy 339.349998 -302.650782)
			(xy 339.35035 -302.641762) (xy 339.35035 -302.574706) (xy 339.350001 -302.565688) (xy 339.343749 -302.548771)
			(xy 339.338158 -302.541686) (xy 339.337904 -302.541686) (xy 339.337904 -302.541432) (xy 339.320267 -302.520498)
			(xy 339.290555 -302.474526) (xy 339.267718 -302.424779) (xy 339.252227 -302.372279) (xy 339.244398 -302.318103)
			(xy 339.243924 -302.290734) (xy 339.24441 -302.263483) (xy 339.252166 -302.209535) (xy 339.267521 -302.15724)
			(xy 339.290163 -302.107663) (xy 339.319629 -302.061813) (xy 339.35532 -302.020622) (xy 339.396511 -301.984931)
			(xy 339.442361 -301.955465) (xy 339.491938 -301.932823) (xy 339.544233 -301.917468) (xy 339.598181 -301.909712)
			(xy 339.652683 -301.909712) (xy 339.706631 -301.917468) (xy 339.758926 -301.932823) (xy 339.808503 -301.955465)
			(xy 339.854353 -301.984931) (xy 339.895544 -302.020622) (xy 339.931235 -302.061813) (xy 339.960701 -302.107663)
			(xy 339.983343 -302.15724) (xy 339.998698 -302.209535) (xy 340.006454 -302.263483) (xy 340.00694 -302.290734)
			(xy 340.006508 -302.318106) (xy 339.998685 -302.372287) (xy 339.983188 -302.424791) (xy 339.960338 -302.474537)
			(xy 339.930605 -302.520502) (xy 339.91296 -302.541432) (xy 339.912706 -302.541686) (xy 339.90712 -302.548773)
			(xy 339.900873 -302.565689) (xy 339.900514 -302.574706) (xy 339.900514 -302.641762) (xy 339.900886 -302.650777)
			(xy 339.907123 -302.667695) (xy 339.912706 -302.674782) (xy 339.91296 -302.674782) (xy 339.91296 -302.675036)
			(xy 339.930576 -302.695987) (xy 339.960293 -302.741954) (xy 339.983134 -302.791696) (xy 339.99863 -302.844193)
			(xy 340.006463 -302.898366) (xy 340.00694 -302.925734) (xy 341.275924 -302.925734) (xy 341.276404 -302.898364)
			(xy 341.284218 -302.844185) (xy 341.299703 -302.791682) (xy 341.322542 -302.741935) (xy 341.352264 -302.695968)
			(xy 341.369904 -302.675036) (xy 341.370158 -302.674782) (xy 341.375765 -302.66771) (xy 341.381998 -302.650782)
			(xy 341.38235 -302.641762) (xy 341.38235 -302.574706) (xy 341.382001 -302.565688) (xy 341.375749 -302.548771)
			(xy 341.370158 -302.541686) (xy 341.369904 -302.541686) (xy 341.369904 -302.541432) (xy 341.352267 -302.520498)
			(xy 341.322555 -302.474526) (xy 341.299718 -302.424779) (xy 341.284227 -302.372279) (xy 341.276398 -302.318103)
			(xy 341.275924 -302.290734) (xy 341.27641 -302.263483) (xy 341.284166 -302.209535) (xy 341.299521 -302.15724)
			(xy 341.322163 -302.107663) (xy 341.351629 -302.061813) (xy 341.38732 -302.020622) (xy 341.428511 -301.984931)
			(xy 341.474361 -301.955465) (xy 341.523938 -301.932823) (xy 341.576233 -301.917468) (xy 341.630181 -301.909712)
			(xy 341.684683 -301.909712) (xy 341.738631 -301.917468) (xy 341.790926 -301.932823) (xy 341.840503 -301.955465)
			(xy 341.886353 -301.984931) (xy 341.927544 -302.020622) (xy 341.963235 -302.061813) (xy 341.992701 -302.107663)
			(xy 342.015343 -302.15724) (xy 342.030698 -302.209535) (xy 342.038454 -302.263483) (xy 342.03894 -302.290734)
			(xy 342.038508 -302.318106) (xy 342.030685 -302.372287) (xy 342.015188 -302.424791) (xy 341.992338 -302.474537)
			(xy 341.962605 -302.520502) (xy 341.94496 -302.541432) (xy 341.944706 -302.541686) (xy 341.93912 -302.548773)
			(xy 341.932873 -302.565689) (xy 341.932514 -302.574706) (xy 341.932514 -302.641762) (xy 341.932886 -302.650777)
			(xy 341.939123 -302.667695) (xy 341.944706 -302.674782) (xy 341.94496 -302.674782) (xy 341.94496 -302.675036)
			(xy 341.962576 -302.695987) (xy 341.992293 -302.741954) (xy 342.015134 -302.791696) (xy 342.03063 -302.844193)
			(xy 342.038463 -302.898366) (xy 342.03894 -302.925734) (xy 346.084144 -302.925734) (xy 346.084619 -302.898364)
			(xy 346.092433 -302.844185) (xy 346.10792 -302.791681) (xy 346.13076 -302.741934) (xy 346.160483 -302.695968)
			(xy 346.178124 -302.675036) (xy 346.178378 -302.674782) (xy 346.183987 -302.667711) (xy 346.190218 -302.650782)
			(xy 346.19057 -302.641762) (xy 346.19057 -302.574706) (xy 346.190217 -302.565689) (xy 346.183967 -302.548771)
			(xy 346.178378 -302.541686) (xy 346.178124 -302.541686) (xy 346.178124 -302.541432) (xy 346.16049 -302.520496)
			(xy 346.130777 -302.474524) (xy 346.107939 -302.424778) (xy 346.092447 -302.372278) (xy 346.084618 -302.318103)
			(xy 346.084144 -302.290734) (xy 346.08463 -302.263483) (xy 346.092386 -302.209535) (xy 346.107741 -302.15724)
			(xy 346.130383 -302.107663) (xy 346.159849 -302.061813) (xy 346.19554 -302.020622) (xy 346.236731 -301.984931)
			(xy 346.282581 -301.955465) (xy 346.332158 -301.932823) (xy 346.384453 -301.917468) (xy 346.438401 -301.909712)
			(xy 346.492903 -301.909712) (xy 346.546851 -301.917468) (xy 346.599146 -301.932823) (xy 346.648723 -301.955465)
			(xy 346.694573 -301.984931) (xy 346.735764 -302.020622) (xy 346.771455 -302.061813) (xy 346.800921 -302.107663)
			(xy 346.823563 -302.15724) (xy 346.838918 -302.209535) (xy 346.846674 -302.263483) (xy 346.84716 -302.290734)
			(xy 346.846724 -302.318105) (xy 346.8389 -302.372286) (xy 346.823405 -302.42479) (xy 346.800556 -302.474536)
			(xy 346.770825 -302.520502) (xy 346.75318 -302.541432) (xy 346.752926 -302.541686) (xy 346.74733 -302.548766)
			(xy 346.741091 -302.565688) (xy 346.740734 -302.574706) (xy 346.740734 -302.641762) (xy 346.741102 -302.650778)
			(xy 346.747341 -302.667695) (xy 346.752926 -302.674782) (xy 346.75318 -302.674782) (xy 346.75318 -302.675036)
			(xy 346.770799 -302.695984) (xy 346.800515 -302.741952) (xy 346.823355 -302.791696) (xy 346.838851 -302.844193)
			(xy 346.846684 -302.898366) (xy 346.84716 -302.925734) (xy 346.846674 -302.952985) (xy 346.838918 -303.006933)
			(xy 346.823563 -303.059228) (xy 346.800921 -303.108805) (xy 346.779823 -303.141634) (xy 348.984568 -303.141634)
			(xy 348.988639 -303.086012) (xy 349.000765 -303.031575) (xy 349.020688 -302.979484) (xy 349.047984 -302.930849)
			(xy 349.08207 -302.886706) (xy 349.122219 -302.847997) (xy 349.167577 -302.815546) (xy 349.217177 -302.790045)
			(xy 349.269961 -302.772038) (xy 349.324804 -302.761908) (xy 349.380538 -302.759871) (xy 349.435975 -302.765971)
			(xy 349.489932 -302.780077) (xy 349.541261 -302.801889) (xy 349.588867 -302.830943) (xy 349.631735 -302.866618)
			(xy 349.668952 -302.908155) (xy 349.699725 -302.954668) (xy 349.723397 -303.005165) (xy 349.739465 -303.058572)
			(xy 349.747585 -303.113748) (xy 349.748094 -303.141634) (xy 350.127568 -303.141634) (xy 350.131639 -303.086012)
			(xy 350.143765 -303.031575) (xy 350.163688 -302.979484) (xy 350.190984 -302.930849) (xy 350.22507 -302.886706)
			(xy 350.265219 -302.847997) (xy 350.310577 -302.815546) (xy 350.360177 -302.790045) (xy 350.412961 -302.772038)
			(xy 350.467804 -302.761908) (xy 350.523538 -302.759871) (xy 350.578975 -302.765971) (xy 350.632932 -302.780077)
			(xy 350.684261 -302.801889) (xy 350.731867 -302.830943) (xy 350.774735 -302.866618) (xy 350.811952 -302.908155)
			(xy 350.823582 -302.925734) (xy 353.029012 -302.925734) (xy 353.029495 -302.898364) (xy 353.037308 -302.844186)
			(xy 353.052793 -302.791683) (xy 353.075631 -302.741936) (xy 353.105352 -302.695968) (xy 353.122992 -302.675036)
			(xy 353.123246 -302.674782) (xy 353.128852 -302.667709) (xy 353.135086 -302.650782) (xy 353.135438 -302.641762)
			(xy 353.135438 -302.574706) (xy 353.13507 -302.56569) (xy 353.128829 -302.548774) (xy 353.123246 -302.541686)
			(xy 353.122992 -302.541686) (xy 353.122992 -302.541432) (xy 353.105353 -302.5205) (xy 353.075642 -302.474527)
			(xy 353.052806 -302.424779) (xy 353.037315 -302.372279) (xy 353.029486 -302.318103) (xy 353.029012 -302.290734)
			(xy 353.029498 -302.263483) (xy 353.037254 -302.209535) (xy 353.052609 -302.15724) (xy 353.075251 -302.107663)
			(xy 353.104717 -302.061813) (xy 353.140408 -302.020622) (xy 353.181599 -301.984931) (xy 353.227449 -301.955465)
			(xy 353.277026 -301.932823) (xy 353.329321 -301.917468) (xy 353.383269 -301.909712) (xy 353.437771 -301.909712)
			(xy 353.491719 -301.917468) (xy 353.544014 -301.932823) (xy 353.593591 -301.955465) (xy 353.639441 -301.984931)
			(xy 353.680632 -302.020622) (xy 353.716323 -302.061813) (xy 353.745789 -302.107663) (xy 353.768431 -302.15724)
			(xy 353.783786 -302.209535) (xy 353.791542 -302.263483) (xy 353.792028 -302.290734) (xy 353.791599 -302.318106)
			(xy 353.783775 -302.372287) (xy 353.768278 -302.424791) (xy 353.745428 -302.474538) (xy 353.715694 -302.520502)
			(xy 353.698048 -302.541432) (xy 353.697794 -302.541686) (xy 353.692206 -302.548772) (xy 353.685961 -302.565689)
			(xy 353.685602 -302.574706) (xy 353.685602 -302.641762) (xy 353.685977 -302.650777) (xy 353.692212 -302.667694)
			(xy 353.697794 -302.674782) (xy 353.698048 -302.674782) (xy 353.698048 -302.675036) (xy 353.715662 -302.695988)
			(xy 353.74538 -302.741955) (xy 353.768221 -302.791697) (xy 353.783718 -302.844193) (xy 353.791551 -302.898366)
			(xy 353.792028 -302.925734) (xy 356.449122 -302.925734) (xy 356.449603 -302.898364) (xy 356.457416 -302.844186)
			(xy 356.472902 -302.791682) (xy 356.49574 -302.741935) (xy 356.525462 -302.695968) (xy 356.543102 -302.675036)
			(xy 356.543356 -302.674782) (xy 356.548963 -302.66771) (xy 356.555196 -302.650782) (xy 356.555548 -302.641762)
			(xy 356.555548 -302.574706) (xy 356.555199 -302.565688) (xy 356.548947 -302.548771) (xy 356.543356 -302.541686)
			(xy 356.543102 -302.541686) (xy 356.543102 -302.541432) (xy 356.525465 -302.520498) (xy 356.495753 -302.474526)
			(xy 356.472916 -302.424779) (xy 356.457425 -302.372279) (xy 356.449596 -302.318103) (xy 356.449122 -302.290734)
			(xy 356.449608 -302.263483) (xy 356.457364 -302.209535) (xy 356.472719 -302.15724) (xy 356.495361 -302.107663)
			(xy 356.524827 -302.061813) (xy 356.560518 -302.020622) (xy 356.601709 -301.984931) (xy 356.647559 -301.955465)
			(xy 356.697136 -301.932823) (xy 356.749431 -301.917468) (xy 356.803379 -301.909712) (xy 356.857881 -301.909712)
			(xy 356.911829 -301.917468) (xy 356.964124 -301.932823) (xy 357.013701 -301.955465) (xy 357.059551 -301.984931)
			(xy 357.100742 -302.020622) (xy 357.136433 -302.061813) (xy 357.165899 -302.107663) (xy 357.188541 -302.15724)
			(xy 357.203896 -302.209535) (xy 357.211652 -302.263483) (xy 357.212138 -302.290734) (xy 357.211707 -302.318106)
			(xy 357.203883 -302.372287) (xy 357.188387 -302.424791) (xy 357.165537 -302.474537) (xy 357.135804 -302.520502)
			(xy 357.118158 -302.541432) (xy 357.117904 -302.541686) (xy 357.112318 -302.548773) (xy 357.106071 -302.565689)
			(xy 357.105712 -302.574706) (xy 357.105712 -302.641762) (xy 357.106085 -302.650777) (xy 357.112321 -302.667694)
			(xy 357.117904 -302.674782) (xy 357.118158 -302.674782) (xy 357.118158 -302.675036) (xy 357.135774 -302.695987)
			(xy 357.165491 -302.741954) (xy 357.188332 -302.791696) (xy 357.203828 -302.844193) (xy 357.211661 -302.898366)
			(xy 357.212138 -302.925734) (xy 357.837232 -302.925734) (xy 357.83771 -302.898364) (xy 357.845524 -302.844185)
			(xy 357.86101 -302.791682) (xy 357.883849 -302.741935) (xy 357.913572 -302.695968) (xy 357.931212 -302.675036)
			(xy 357.931466 -302.674782) (xy 357.937074 -302.66771) (xy 357.943306 -302.650782) (xy 357.943658 -302.641762)
			(xy 357.943658 -302.574706) (xy 357.943307 -302.565688) (xy 357.937056 -302.548771) (xy 357.931466 -302.541686)
			(xy 357.931212 -302.541686) (xy 357.931212 -302.541432) (xy 357.913576 -302.520497) (xy 357.883864 -302.474525)
			(xy 357.861027 -302.424779) (xy 357.845535 -302.372278) (xy 357.837706 -302.318103) (xy 357.837232 -302.290734)
			(xy 357.837718 -302.263483) (xy 357.845474 -302.209535) (xy 357.860829 -302.15724) (xy 357.883471 -302.107663)
			(xy 357.912937 -302.061813) (xy 357.948628 -302.020622) (xy 357.989819 -301.984931) (xy 358.035669 -301.955465)
			(xy 358.085246 -301.932823) (xy 358.137541 -301.917468) (xy 358.191489 -301.909712) (xy 358.245991 -301.909712)
			(xy 358.299939 -301.917468) (xy 358.352234 -301.932823) (xy 358.401811 -301.955465) (xy 358.447661 -301.984931)
			(xy 358.488852 -302.020622) (xy 358.524543 -302.061813) (xy 358.554009 -302.107663) (xy 358.576651 -302.15724)
			(xy 358.592006 -302.209535) (xy 358.599762 -302.263483) (xy 358.600248 -302.290734) (xy 358.599815 -302.318106)
			(xy 358.591991 -302.372287) (xy 358.576495 -302.424791) (xy 358.553645 -302.474537) (xy 358.523913 -302.520502)
			(xy 358.506268 -302.541432) (xy 358.506014 -302.541686) (xy 358.500429 -302.548774) (xy 358.494181 -302.56569)
			(xy 358.493822 -302.574706) (xy 358.493822 -302.641762) (xy 358.494193 -302.650778) (xy 358.50043 -302.667695)
			(xy 358.506014 -302.674782) (xy 358.506268 -302.674782) (xy 358.506268 -302.675036) (xy 358.523886 -302.695985)
			(xy 358.553602 -302.741953) (xy 358.576442 -302.791696) (xy 358.591938 -302.844193) (xy 358.599772 -302.898366)
			(xy 358.600248 -302.925734) (xy 359.869232 -302.925734) (xy 359.86971 -302.898364) (xy 359.877524 -302.844185)
			(xy 359.89301 -302.791682) (xy 359.915849 -302.741935) (xy 359.945572 -302.695968) (xy 359.963212 -302.675036)
			(xy 359.963466 -302.674782) (xy 359.969074 -302.66771) (xy 359.975306 -302.650782) (xy 359.975658 -302.641762)
			(xy 359.975658 -302.574706) (xy 359.975307 -302.565688) (xy 359.969056 -302.548771) (xy 359.963466 -302.541686)
			(xy 359.963212 -302.541686) (xy 359.963212 -302.541432) (xy 359.945576 -302.520497) (xy 359.915864 -302.474525)
			(xy 359.893027 -302.424779) (xy 359.877535 -302.372278) (xy 359.869706 -302.318103) (xy 359.869232 -302.290734)
			(xy 359.869718 -302.263483) (xy 359.877474 -302.209535) (xy 359.892829 -302.15724) (xy 359.915471 -302.107663)
			(xy 359.944937 -302.061813) (xy 359.980628 -302.020622) (xy 360.021819 -301.984931) (xy 360.067669 -301.955465)
			(xy 360.117246 -301.932823) (xy 360.169541 -301.917468) (xy 360.223489 -301.909712) (xy 360.277991 -301.909712)
			(xy 360.331939 -301.917468) (xy 360.384234 -301.932823) (xy 360.433811 -301.955465) (xy 360.479661 -301.984931)
			(xy 360.520852 -302.020622) (xy 360.556543 -302.061813) (xy 360.586009 -302.107663) (xy 360.608651 -302.15724)
			(xy 360.624006 -302.209535) (xy 360.631762 -302.263483) (xy 360.632248 -302.290734) (xy 360.631815 -302.318106)
			(xy 360.623991 -302.372287) (xy 360.608495 -302.424791) (xy 360.585645 -302.474537) (xy 360.555913 -302.520502)
			(xy 360.538268 -302.541432) (xy 360.538014 -302.541686) (xy 360.532429 -302.548774) (xy 360.526181 -302.56569)
			(xy 360.525822 -302.574706) (xy 360.525822 -302.641762) (xy 360.526193 -302.650778) (xy 360.53243 -302.667695)
			(xy 360.538014 -302.674782) (xy 360.538268 -302.674782) (xy 360.538268 -302.675036) (xy 360.555886 -302.695985)
			(xy 360.585602 -302.741953) (xy 360.608442 -302.791696) (xy 360.623938 -302.844193) (xy 360.631772 -302.898366)
			(xy 360.632248 -302.925734) (xy 364.677452 -302.925734) (xy 364.677925 -302.898364) (xy 364.685739 -302.844185)
			(xy 364.701226 -302.791681) (xy 364.724067 -302.741934) (xy 364.753791 -302.695967) (xy 364.771432 -302.675036)
			(xy 364.771686 -302.674782) (xy 364.777285 -302.667704) (xy 364.783525 -302.650781) (xy 364.783878 -302.641762)
			(xy 364.783878 -302.574706) (xy 364.783523 -302.565689) (xy 364.777275 -302.548772) (xy 364.771686 -302.541686)
			(xy 364.771432 -302.541686) (xy 364.771432 -302.541432) (xy 364.753799 -302.520495) (xy 364.724086 -302.474524)
			(xy 364.701248 -302.424778) (xy 364.685755 -302.372278) (xy 364.677926 -302.318103) (xy 364.677452 -302.290734)
			(xy 364.677938 -302.263483) (xy 364.685694 -302.209535) (xy 364.701049 -302.15724) (xy 364.723691 -302.107663)
			(xy 364.753157 -302.061813) (xy 364.788848 -302.020622) (xy 364.830039 -301.984931) (xy 364.875889 -301.955465)
			(xy 364.925466 -301.932823) (xy 364.977761 -301.917468) (xy 365.031709 -301.909712) (xy 365.086211 -301.909712)
			(xy 365.140159 -301.917468) (xy 365.192454 -301.932823) (xy 365.242031 -301.955465) (xy 365.287881 -301.984931)
			(xy 365.329072 -302.020622) (xy 365.364763 -302.061813) (xy 365.394229 -302.107663) (xy 365.416871 -302.15724)
			(xy 365.432226 -302.209535) (xy 365.439982 -302.263483) (xy 365.440468 -302.290734) (xy 365.44003 -302.318105)
			(xy 365.432206 -302.372286) (xy 365.416711 -302.42479) (xy 365.393863 -302.474536) (xy 365.364132 -302.520501)
			(xy 365.346488 -302.541432) (xy 365.346234 -302.541686) (xy 365.340639 -302.548767) (xy 365.334399 -302.565688)
			(xy 365.334042 -302.574706) (xy 365.334042 -302.641762) (xy 365.334408 -302.650778) (xy 365.340648 -302.667696)
			(xy 365.346234 -302.674782) (xy 365.346488 -302.674782) (xy 365.346488 -302.675036) (xy 365.364109 -302.695983)
			(xy 365.393824 -302.741951) (xy 365.416663 -302.791695) (xy 365.432159 -302.844193) (xy 365.439992 -302.898366)
			(xy 365.440468 -302.925734) (xy 365.439982 -302.952985) (xy 365.432226 -303.006933) (xy 365.416871 -303.059228)
			(xy 365.394229 -303.108805) (xy 365.364763 -303.154655) (xy 365.329072 -303.195846) (xy 365.287881 -303.231537)
			(xy 365.242031 -303.261003) (xy 365.192454 -303.283645) (xy 365.140159 -303.299) (xy 365.086211 -303.306756)
			(xy 365.031709 -303.306756) (xy 364.977761 -303.299) (xy 364.925466 -303.283645) (xy 364.875889 -303.261003)
			(xy 364.830039 -303.231537) (xy 364.788848 -303.195846) (xy 364.753157 -303.154655) (xy 364.723691 -303.108805)
			(xy 364.701049 -303.059228) (xy 364.685694 -303.006933) (xy 364.677938 -302.952985) (xy 364.677452 -302.925734)
			(xy 360.632248 -302.925734) (xy 360.631762 -302.952985) (xy 360.624006 -303.006933) (xy 360.608651 -303.059228)
			(xy 360.586009 -303.108805) (xy 360.556543 -303.154655) (xy 360.520852 -303.195846) (xy 360.479661 -303.231537)
			(xy 360.433811 -303.261003) (xy 360.384234 -303.283645) (xy 360.331939 -303.299) (xy 360.277991 -303.306756)
			(xy 360.223489 -303.306756) (xy 360.169541 -303.299) (xy 360.117246 -303.283645) (xy 360.067669 -303.261003)
			(xy 360.021819 -303.231537) (xy 359.980628 -303.195846) (xy 359.944937 -303.154655) (xy 359.915471 -303.108805)
			(xy 359.892829 -303.059228) (xy 359.877474 -303.006933) (xy 359.869718 -302.952985) (xy 359.869232 -302.925734)
			(xy 358.600248 -302.925734) (xy 358.599762 -302.952985) (xy 358.592006 -303.006933) (xy 358.576651 -303.059228)
			(xy 358.554009 -303.108805) (xy 358.524543 -303.154655) (xy 358.488852 -303.195846) (xy 358.447661 -303.231537)
			(xy 358.401811 -303.261003) (xy 358.352234 -303.283645) (xy 358.299939 -303.299) (xy 358.245991 -303.306756)
			(xy 358.191489 -303.306756) (xy 358.137541 -303.299) (xy 358.085246 -303.283645) (xy 358.035669 -303.261003)
			(xy 357.989819 -303.231537) (xy 357.948628 -303.195846) (xy 357.912937 -303.154655) (xy 357.883471 -303.108805)
			(xy 357.860829 -303.059228) (xy 357.845474 -303.006933) (xy 357.837718 -302.952985) (xy 357.837232 -302.925734)
			(xy 357.212138 -302.925734) (xy 357.211652 -302.952985) (xy 357.203896 -303.006933) (xy 357.188541 -303.059228)
			(xy 357.165899 -303.108805) (xy 357.136433 -303.154655) (xy 357.100742 -303.195846) (xy 357.059551 -303.231537)
			(xy 357.013701 -303.261003) (xy 356.964124 -303.283645) (xy 356.911829 -303.299) (xy 356.857881 -303.306756)
			(xy 356.803379 -303.306756) (xy 356.749431 -303.299) (xy 356.697136 -303.283645) (xy 356.647559 -303.261003)
			(xy 356.601709 -303.231537) (xy 356.560518 -303.195846) (xy 356.524827 -303.154655) (xy 356.495361 -303.108805)
			(xy 356.472719 -303.059228) (xy 356.457364 -303.006933) (xy 356.449608 -302.952985) (xy 356.449122 -302.925734)
			(xy 353.792028 -302.925734) (xy 353.791542 -302.952985) (xy 353.783786 -303.006933) (xy 353.768431 -303.059228)
			(xy 353.745789 -303.108805) (xy 353.716323 -303.154655) (xy 353.680632 -303.195846) (xy 353.639441 -303.231537)
			(xy 353.593591 -303.261003) (xy 353.544014 -303.283645) (xy 353.491719 -303.299) (xy 353.437771 -303.306756)
			(xy 353.383269 -303.306756) (xy 353.329321 -303.299) (xy 353.277026 -303.283645) (xy 353.227449 -303.261003)
			(xy 353.181599 -303.231537) (xy 353.140408 -303.195846) (xy 353.104717 -303.154655) (xy 353.075251 -303.108805)
			(xy 353.052609 -303.059228) (xy 353.037254 -303.006933) (xy 353.029498 -302.952985) (xy 353.029012 -302.925734)
			(xy 350.823582 -302.925734) (xy 350.842725 -302.954668) (xy 350.866397 -303.005165) (xy 350.882465 -303.058572)
			(xy 350.890585 -303.113748) (xy 350.891094 -303.141634) (xy 350.890585 -303.16952) (xy 350.882465 -303.224696)
			(xy 350.866397 -303.278103) (xy 350.842725 -303.3286) (xy 350.811952 -303.375113) (xy 350.774735 -303.41665)
			(xy 350.731867 -303.452325) (xy 350.684261 -303.481379) (xy 350.632932 -303.503191) (xy 350.578975 -303.517297)
			(xy 350.523538 -303.523397) (xy 350.467804 -303.52136) (xy 350.412961 -303.51123) (xy 350.360177 -303.493223)
			(xy 350.310577 -303.467722) (xy 350.265219 -303.435271) (xy 350.22507 -303.396562) (xy 350.190984 -303.352419)
			(xy 350.163688 -303.303784) (xy 350.143765 -303.251693) (xy 350.131639 -303.197256) (xy 350.127568 -303.141634)
			(xy 349.748094 -303.141634) (xy 349.747585 -303.16952) (xy 349.739465 -303.224696) (xy 349.723397 -303.278103)
			(xy 349.699725 -303.3286) (xy 349.668952 -303.375113) (xy 349.631735 -303.41665) (xy 349.588867 -303.452325)
			(xy 349.541261 -303.481379) (xy 349.489932 -303.503191) (xy 349.435975 -303.517297) (xy 349.380538 -303.523397)
			(xy 349.324804 -303.52136) (xy 349.269961 -303.51123) (xy 349.217177 -303.493223) (xy 349.167577 -303.467722)
			(xy 349.122219 -303.435271) (xy 349.08207 -303.396562) (xy 349.047984 -303.352419) (xy 349.020688 -303.303784)
			(xy 349.000765 -303.251693) (xy 348.988639 -303.197256) (xy 348.984568 -303.141634) (xy 346.779823 -303.141634)
			(xy 346.771455 -303.154655) (xy 346.735764 -303.195846) (xy 346.694573 -303.231537) (xy 346.648723 -303.261003)
			(xy 346.599146 -303.283645) (xy 346.546851 -303.299) (xy 346.492903 -303.306756) (xy 346.438401 -303.306756)
			(xy 346.384453 -303.299) (xy 346.332158 -303.283645) (xy 346.282581 -303.261003) (xy 346.236731 -303.231537)
			(xy 346.19554 -303.195846) (xy 346.159849 -303.154655) (xy 346.130383 -303.108805) (xy 346.107741 -303.059228)
			(xy 346.092386 -303.006933) (xy 346.08463 -302.952985) (xy 346.084144 -302.925734) (xy 342.03894 -302.925734)
			(xy 342.038454 -302.952985) (xy 342.030698 -303.006933) (xy 342.015343 -303.059228) (xy 341.992701 -303.108805)
			(xy 341.963235 -303.154655) (xy 341.927544 -303.195846) (xy 341.886353 -303.231537) (xy 341.840503 -303.261003)
			(xy 341.790926 -303.283645) (xy 341.738631 -303.299) (xy 341.684683 -303.306756) (xy 341.630181 -303.306756)
			(xy 341.576233 -303.299) (xy 341.523938 -303.283645) (xy 341.474361 -303.261003) (xy 341.428511 -303.231537)
			(xy 341.38732 -303.195846) (xy 341.351629 -303.154655) (xy 341.322163 -303.108805) (xy 341.299521 -303.059228)
			(xy 341.284166 -303.006933) (xy 341.27641 -302.952985) (xy 341.275924 -302.925734) (xy 340.00694 -302.925734)
			(xy 340.006454 -302.952985) (xy 339.998698 -303.006933) (xy 339.983343 -303.059228) (xy 339.960701 -303.108805)
			(xy 339.931235 -303.154655) (xy 339.895544 -303.195846) (xy 339.854353 -303.231537) (xy 339.808503 -303.261003)
			(xy 339.758926 -303.283645) (xy 339.706631 -303.299) (xy 339.652683 -303.306756) (xy 339.598181 -303.306756)
			(xy 339.544233 -303.299) (xy 339.491938 -303.283645) (xy 339.442361 -303.261003) (xy 339.396511 -303.231537)
			(xy 339.35532 -303.195846) (xy 339.319629 -303.154655) (xy 339.290163 -303.108805) (xy 339.267521 -303.059228)
			(xy 339.252166 -303.006933) (xy 339.24441 -302.952985) (xy 339.243924 -302.925734) (xy 338.61883 -302.925734)
			(xy 338.618344 -302.952985) (xy 338.610588 -303.006933) (xy 338.595233 -303.059228) (xy 338.572591 -303.108805)
			(xy 338.543125 -303.154655) (xy 338.507434 -303.195846) (xy 338.466243 -303.231537) (xy 338.420393 -303.261003)
			(xy 338.370816 -303.283645) (xy 338.318521 -303.299) (xy 338.264573 -303.306756) (xy 338.210071 -303.306756)
			(xy 338.156123 -303.299) (xy 338.103828 -303.283645) (xy 338.054251 -303.261003) (xy 338.008401 -303.231537)
			(xy 337.96721 -303.195846) (xy 337.931519 -303.154655) (xy 337.902053 -303.108805) (xy 337.879411 -303.059228)
			(xy 337.864056 -303.006933) (xy 337.8563 -302.952985) (xy 337.855814 -302.925734) (xy 335.19872 -302.925734)
			(xy 335.198234 -302.952985) (xy 335.190478 -303.006933) (xy 335.175123 -303.059228) (xy 335.152481 -303.108805)
			(xy 335.123015 -303.154655) (xy 335.087324 -303.195846) (xy 335.046133 -303.231537) (xy 335.000283 -303.261003)
			(xy 334.950706 -303.283645) (xy 334.898411 -303.299) (xy 334.844463 -303.306756) (xy 334.789961 -303.306756)
			(xy 334.736013 -303.299) (xy 334.683718 -303.283645) (xy 334.634141 -303.261003) (xy 334.588291 -303.231537)
			(xy 334.5471 -303.195846) (xy 334.511409 -303.154655) (xy 334.481943 -303.108805) (xy 334.459301 -303.059228)
			(xy 334.443946 -303.006933) (xy 334.43619 -302.952985) (xy 334.435704 -302.925734) (xy 330.943966 -302.925734)
			(xy 330.943966 -304.157634) (xy 348.984568 -304.157634) (xy 348.988639 -304.102012) (xy 349.000765 -304.047575)
			(xy 349.020688 -303.995484) (xy 349.047984 -303.946849) (xy 349.08207 -303.902706) (xy 349.122219 -303.863997)
			(xy 349.167577 -303.831546) (xy 349.217177 -303.806045) (xy 349.269961 -303.788038) (xy 349.324804 -303.777908)
			(xy 349.380538 -303.775871) (xy 349.435975 -303.781971) (xy 349.489932 -303.796077) (xy 349.541261 -303.817889)
			(xy 349.588867 -303.846943) (xy 349.631735 -303.882618) (xy 349.668952 -303.924155) (xy 349.699725 -303.970668)
			(xy 349.723397 -304.021165) (xy 349.739465 -304.074572) (xy 349.747585 -304.129748) (xy 349.748094 -304.157634)
			(xy 350.127568 -304.157634) (xy 350.131639 -304.102012) (xy 350.143765 -304.047575) (xy 350.163688 -303.995484)
			(xy 350.190984 -303.946849) (xy 350.22507 -303.902706) (xy 350.265219 -303.863997) (xy 350.310577 -303.831546)
			(xy 350.360177 -303.806045) (xy 350.412961 -303.788038) (xy 350.467804 -303.777908) (xy 350.523538 -303.775871)
			(xy 350.578975 -303.781971) (xy 350.632932 -303.796077) (xy 350.684261 -303.817889) (xy 350.731867 -303.846943)
			(xy 350.774735 -303.882618) (xy 350.811952 -303.924155) (xy 350.842725 -303.970668) (xy 350.866397 -304.021165)
			(xy 350.882465 -304.074572) (xy 350.890585 -304.129748) (xy 350.891094 -304.157634) (xy 350.890585 -304.18552)
			(xy 350.882465 -304.240696) (xy 350.866397 -304.294103) (xy 350.842725 -304.3446) (xy 350.811952 -304.391113)
			(xy 350.774735 -304.43265) (xy 350.731867 -304.468325) (xy 350.684261 -304.497379) (xy 350.632932 -304.519191)
			(xy 350.578975 -304.533297) (xy 350.523538 -304.539397) (xy 350.467804 -304.53736) (xy 350.412961 -304.52723)
			(xy 350.360177 -304.509223) (xy 350.310577 -304.483722) (xy 350.265219 -304.451271) (xy 350.22507 -304.412562)
			(xy 350.190984 -304.368419) (xy 350.163688 -304.319784) (xy 350.143765 -304.267693) (xy 350.131639 -304.213256)
			(xy 350.127568 -304.157634) (xy 349.748094 -304.157634) (xy 349.747585 -304.18552) (xy 349.739465 -304.240696)
			(xy 349.723397 -304.294103) (xy 349.699725 -304.3446) (xy 349.668952 -304.391113) (xy 349.631735 -304.43265)
			(xy 349.588867 -304.468325) (xy 349.541261 -304.497379) (xy 349.489932 -304.519191) (xy 349.435975 -304.533297)
			(xy 349.380538 -304.539397) (xy 349.324804 -304.53736) (xy 349.269961 -304.52723) (xy 349.217177 -304.509223)
			(xy 349.167577 -304.483722) (xy 349.122219 -304.451271) (xy 349.08207 -304.412562) (xy 349.047984 -304.368419)
			(xy 349.020688 -304.319784) (xy 349.000765 -304.267693) (xy 348.988639 -304.213256) (xy 348.984568 -304.157634)
			(xy 330.943966 -304.157634) (xy 330.943966 -310.242712) (xy 332.67218 -310.242712) (xy 332.676251 -310.18709)
			(xy 332.688377 -310.132653) (xy 332.7083 -310.080562) (xy 332.735596 -310.031927) (xy 332.769682 -309.987784)
			(xy 332.809831 -309.949075) (xy 332.855189 -309.916624) (xy 332.904789 -309.891123) (xy 332.957573 -309.873116)
			(xy 333.012416 -309.862986) (xy 333.06815 -309.860949) (xy 333.123587 -309.867049) (xy 333.177544 -309.881155)
			(xy 333.228873 -309.902967) (xy 333.276479 -309.932021) (xy 333.319347 -309.967696) (xy 333.356564 -310.009233)
			(xy 333.387337 -310.055746) (xy 333.411009 -310.106243) (xy 333.427077 -310.15965) (xy 333.435197 -310.214826)
			(xy 333.435706 -310.242712) (xy 333.68818 -310.242712) (xy 333.692251 -310.18709) (xy 333.704377 -310.132653)
			(xy 333.7243 -310.080562) (xy 333.751596 -310.031927) (xy 333.785682 -309.987784) (xy 333.825831 -309.949075)
			(xy 333.871189 -309.916624) (xy 333.920789 -309.891123) (xy 333.973573 -309.873116) (xy 334.028416 -309.862986)
			(xy 334.08415 -309.860949) (xy 334.139587 -309.867049) (xy 334.193544 -309.881155) (xy 334.244873 -309.902967)
			(xy 334.292479 -309.932021) (xy 334.335347 -309.967696) (xy 334.372564 -310.009233) (xy 334.403337 -310.055746)
			(xy 334.427009 -310.106243) (xy 334.443077 -310.15965) (xy 334.451197 -310.214826) (xy 334.451706 -310.242712)
			(xy 334.70418 -310.242712) (xy 334.708251 -310.18709) (xy 334.720377 -310.132653) (xy 334.7403 -310.080562)
			(xy 334.767596 -310.031927) (xy 334.801682 -309.987784) (xy 334.841831 -309.949075) (xy 334.887189 -309.916624)
			(xy 334.936789 -309.891123) (xy 334.989573 -309.873116) (xy 335.044416 -309.862986) (xy 335.10015 -309.860949)
			(xy 335.155587 -309.867049) (xy 335.209544 -309.881155) (xy 335.260873 -309.902967) (xy 335.308479 -309.932021)
			(xy 335.351347 -309.967696) (xy 335.388564 -310.009233) (xy 335.419337 -310.055746) (xy 335.443009 -310.106243)
			(xy 335.459077 -310.15965) (xy 335.467197 -310.214826) (xy 335.467706 -310.242712) (xy 335.72018 -310.242712)
			(xy 335.724251 -310.18709) (xy 335.736377 -310.132653) (xy 335.7563 -310.080562) (xy 335.783596 -310.031927)
			(xy 335.817682 -309.987784) (xy 335.857831 -309.949075) (xy 335.903189 -309.916624) (xy 335.952789 -309.891123)
			(xy 336.005573 -309.873116) (xy 336.060416 -309.862986) (xy 336.11615 -309.860949) (xy 336.171587 -309.867049)
			(xy 336.225544 -309.881155) (xy 336.276873 -309.902967) (xy 336.324479 -309.932021) (xy 336.367347 -309.967696)
			(xy 336.404564 -310.009233) (xy 336.435337 -310.055746) (xy 336.459009 -310.106243) (xy 336.475077 -310.15965)
			(xy 336.483197 -310.214826) (xy 336.483706 -310.242712) (xy 336.73618 -310.242712) (xy 336.740251 -310.18709)
			(xy 336.752377 -310.132653) (xy 336.7723 -310.080562) (xy 336.799596 -310.031927) (xy 336.833682 -309.987784)
			(xy 336.873831 -309.949075) (xy 336.919189 -309.916624) (xy 336.968789 -309.891123) (xy 337.021573 -309.873116)
			(xy 337.076416 -309.862986) (xy 337.13215 -309.860949) (xy 337.187587 -309.867049) (xy 337.241544 -309.881155)
			(xy 337.292873 -309.902967) (xy 337.340479 -309.932021) (xy 337.383347 -309.967696) (xy 337.420564 -310.009233)
			(xy 337.451337 -310.055746) (xy 337.475009 -310.106243) (xy 337.491077 -310.15965) (xy 337.499197 -310.214826)
			(xy 337.499706 -310.242712) (xy 337.75218 -310.242712) (xy 337.756251 -310.18709) (xy 337.768377 -310.132653)
			(xy 337.7883 -310.080562) (xy 337.815596 -310.031927) (xy 337.849682 -309.987784) (xy 337.889831 -309.949075)
			(xy 337.935189 -309.916624) (xy 337.984789 -309.891123) (xy 338.037573 -309.873116) (xy 338.092416 -309.862986)
			(xy 338.14815 -309.860949) (xy 338.203587 -309.867049) (xy 338.257544 -309.881155) (xy 338.308873 -309.902967)
			(xy 338.356479 -309.932021) (xy 338.399347 -309.967696) (xy 338.436564 -310.009233) (xy 338.467337 -310.055746)
			(xy 338.491009 -310.106243) (xy 338.507077 -310.15965) (xy 338.515197 -310.214826) (xy 338.515706 -310.242712)
			(xy 338.76818 -310.242712) (xy 338.772251 -310.18709) (xy 338.784377 -310.132653) (xy 338.8043 -310.080562)
			(xy 338.831596 -310.031927) (xy 338.865682 -309.987784) (xy 338.905831 -309.949075) (xy 338.951189 -309.916624)
			(xy 339.000789 -309.891123) (xy 339.053573 -309.873116) (xy 339.108416 -309.862986) (xy 339.16415 -309.860949)
			(xy 339.219587 -309.867049) (xy 339.273544 -309.881155) (xy 339.324873 -309.902967) (xy 339.372479 -309.932021)
			(xy 339.415347 -309.967696) (xy 339.452564 -310.009233) (xy 339.483337 -310.055746) (xy 339.507009 -310.106243)
			(xy 339.523077 -310.15965) (xy 339.531197 -310.214826) (xy 339.531706 -310.242712) (xy 339.78418 -310.242712)
			(xy 339.788251 -310.18709) (xy 339.800377 -310.132653) (xy 339.8203 -310.080562) (xy 339.847596 -310.031927)
			(xy 339.881682 -309.987784) (xy 339.921831 -309.949075) (xy 339.967189 -309.916624) (xy 340.016789 -309.891123)
			(xy 340.069573 -309.873116) (xy 340.124416 -309.862986) (xy 340.18015 -309.860949) (xy 340.235587 -309.867049)
			(xy 340.289544 -309.881155) (xy 340.340873 -309.902967) (xy 340.388479 -309.932021) (xy 340.431347 -309.967696)
			(xy 340.468564 -310.009233) (xy 340.499337 -310.055746) (xy 340.523009 -310.106243) (xy 340.539077 -310.15965)
			(xy 340.547197 -310.214826) (xy 340.547706 -310.242712) (xy 340.80018 -310.242712) (xy 340.804251 -310.18709)
			(xy 340.816377 -310.132653) (xy 340.8363 -310.080562) (xy 340.863596 -310.031927) (xy 340.897682 -309.987784)
			(xy 340.937831 -309.949075) (xy 340.983189 -309.916624) (xy 341.032789 -309.891123) (xy 341.085573 -309.873116)
			(xy 341.140416 -309.862986) (xy 341.19615 -309.860949) (xy 341.251587 -309.867049) (xy 341.305544 -309.881155)
			(xy 341.356873 -309.902967) (xy 341.404479 -309.932021) (xy 341.447347 -309.967696) (xy 341.484564 -310.009233)
			(xy 341.515337 -310.055746) (xy 341.539009 -310.106243) (xy 341.555077 -310.15965) (xy 341.563197 -310.214826)
			(xy 341.563706 -310.242712) (xy 341.81618 -310.242712) (xy 341.820251 -310.18709) (xy 341.832377 -310.132653)
			(xy 341.8523 -310.080562) (xy 341.879596 -310.031927) (xy 341.913682 -309.987784) (xy 341.953831 -309.949075)
			(xy 341.999189 -309.916624) (xy 342.048789 -309.891123) (xy 342.101573 -309.873116) (xy 342.156416 -309.862986)
			(xy 342.21215 -309.860949) (xy 342.267587 -309.867049) (xy 342.321544 -309.881155) (xy 342.372873 -309.902967)
			(xy 342.420479 -309.932021) (xy 342.463347 -309.967696) (xy 342.500564 -310.009233) (xy 342.531337 -310.055746)
			(xy 342.555009 -310.106243) (xy 342.571077 -310.15965) (xy 342.579197 -310.214826) (xy 342.579706 -310.242712)
			(xy 342.579197 -310.270598) (xy 342.571077 -310.325774) (xy 342.555009 -310.379181) (xy 342.531337 -310.429678)
			(xy 342.52631 -310.437276) (xy 357.436926 -310.437276) (xy 357.440997 -310.381654) (xy 357.453123 -310.327217)
			(xy 357.473046 -310.275126) (xy 357.500342 -310.226491) (xy 357.534428 -310.182348) (xy 357.574577 -310.143639)
			(xy 357.619935 -310.111188) (xy 357.669535 -310.085687) (xy 357.722319 -310.06768) (xy 357.777162 -310.05755)
			(xy 357.832896 -310.055513) (xy 357.888333 -310.061613) (xy 357.94229 -310.075719) (xy 357.993619 -310.097531)
			(xy 358.041225 -310.126585) (xy 358.084093 -310.16226) (xy 358.12131 -310.203797) (xy 358.152083 -310.25031)
			(xy 358.175755 -310.300807) (xy 358.191823 -310.354214) (xy 358.199943 -310.40939) (xy 358.200452 -310.437276)
			(xy 358.452926 -310.437276) (xy 358.456997 -310.381654) (xy 358.469123 -310.327217) (xy 358.489046 -310.275126)
			(xy 358.516342 -310.226491) (xy 358.550428 -310.182348) (xy 358.590577 -310.143639) (xy 358.635935 -310.111188)
			(xy 358.685535 -310.085687) (xy 358.738319 -310.06768) (xy 358.793162 -310.05755) (xy 358.848896 -310.055513)
			(xy 358.904333 -310.061613) (xy 358.95829 -310.075719) (xy 359.009619 -310.097531) (xy 359.057225 -310.126585)
			(xy 359.100093 -310.16226) (xy 359.13731 -310.203797) (xy 359.168083 -310.25031) (xy 359.191755 -310.300807)
			(xy 359.207823 -310.354214) (xy 359.215943 -310.40939) (xy 359.216452 -310.437276) (xy 359.468926 -310.437276)
			(xy 359.472997 -310.381654) (xy 359.485123 -310.327217) (xy 359.505046 -310.275126) (xy 359.532342 -310.226491)
			(xy 359.566428 -310.182348) (xy 359.606577 -310.143639) (xy 359.651935 -310.111188) (xy 359.701535 -310.085687)
			(xy 359.754319 -310.06768) (xy 359.809162 -310.05755) (xy 359.864896 -310.055513) (xy 359.920333 -310.061613)
			(xy 359.97429 -310.075719) (xy 360.025619 -310.097531) (xy 360.073225 -310.126585) (xy 360.116093 -310.16226)
			(xy 360.15331 -310.203797) (xy 360.184083 -310.25031) (xy 360.207755 -310.300807) (xy 360.223823 -310.354214)
			(xy 360.231943 -310.40939) (xy 360.232452 -310.437276) (xy 360.484926 -310.437276) (xy 360.488997 -310.381654)
			(xy 360.501123 -310.327217) (xy 360.521046 -310.275126) (xy 360.548342 -310.226491) (xy 360.582428 -310.182348)
			(xy 360.622577 -310.143639) (xy 360.667935 -310.111188) (xy 360.717535 -310.085687) (xy 360.770319 -310.06768)
			(xy 360.825162 -310.05755) (xy 360.880896 -310.055513) (xy 360.936333 -310.061613) (xy 360.99029 -310.075719)
			(xy 361.041619 -310.097531) (xy 361.089225 -310.126585) (xy 361.132093 -310.16226) (xy 361.16931 -310.203797)
			(xy 361.200083 -310.25031) (xy 361.223755 -310.300807) (xy 361.239823 -310.354214) (xy 361.247943 -310.40939)
			(xy 361.248452 -310.437276) (xy 361.500926 -310.437276) (xy 361.504997 -310.381654) (xy 361.517123 -310.327217)
			(xy 361.537046 -310.275126) (xy 361.564342 -310.226491) (xy 361.598428 -310.182348) (xy 361.638577 -310.143639)
			(xy 361.683935 -310.111188) (xy 361.733535 -310.085687) (xy 361.786319 -310.06768) (xy 361.841162 -310.05755)
			(xy 361.896896 -310.055513) (xy 361.952333 -310.061613) (xy 362.00629 -310.075719) (xy 362.057619 -310.097531)
			(xy 362.105225 -310.126585) (xy 362.148093 -310.16226) (xy 362.18531 -310.203797) (xy 362.216083 -310.25031)
			(xy 362.239755 -310.300807) (xy 362.255823 -310.354214) (xy 362.263943 -310.40939) (xy 362.264452 -310.437276)
			(xy 362.516926 -310.437276) (xy 362.520997 -310.381654) (xy 362.533123 -310.327217) (xy 362.553046 -310.275126)
			(xy 362.580342 -310.226491) (xy 362.614428 -310.182348) (xy 362.654577 -310.143639) (xy 362.699935 -310.111188)
			(xy 362.749535 -310.085687) (xy 362.802319 -310.06768) (xy 362.857162 -310.05755) (xy 362.912896 -310.055513)
			(xy 362.968333 -310.061613) (xy 363.02229 -310.075719) (xy 363.073619 -310.097531) (xy 363.121225 -310.126585)
			(xy 363.164093 -310.16226) (xy 363.20131 -310.203797) (xy 363.232083 -310.25031) (xy 363.255755 -310.300807)
			(xy 363.271823 -310.354214) (xy 363.279943 -310.40939) (xy 363.280452 -310.437276) (xy 363.532926 -310.437276)
			(xy 363.536997 -310.381654) (xy 363.549123 -310.327217) (xy 363.569046 -310.275126) (xy 363.596342 -310.226491)
			(xy 363.630428 -310.182348) (xy 363.670577 -310.143639) (xy 363.715935 -310.111188) (xy 363.765535 -310.085687)
			(xy 363.818319 -310.06768) (xy 363.873162 -310.05755) (xy 363.928896 -310.055513) (xy 363.984333 -310.061613)
			(xy 364.03829 -310.075719) (xy 364.089619 -310.097531) (xy 364.137225 -310.126585) (xy 364.180093 -310.16226)
			(xy 364.21731 -310.203797) (xy 364.248083 -310.25031) (xy 364.271755 -310.300807) (xy 364.287823 -310.354214)
			(xy 364.295943 -310.40939) (xy 364.296452 -310.437276) (xy 364.548926 -310.437276) (xy 364.552997 -310.381654)
			(xy 364.565123 -310.327217) (xy 364.585046 -310.275126) (xy 364.612342 -310.226491) (xy 364.646428 -310.182348)
			(xy 364.686577 -310.143639) (xy 364.731935 -310.111188) (xy 364.781535 -310.085687) (xy 364.834319 -310.06768)
			(xy 364.889162 -310.05755) (xy 364.944896 -310.055513) (xy 365.000333 -310.061613) (xy 365.05429 -310.075719)
			(xy 365.105619 -310.097531) (xy 365.153225 -310.126585) (xy 365.196093 -310.16226) (xy 365.23331 -310.203797)
			(xy 365.264083 -310.25031) (xy 365.287755 -310.300807) (xy 365.303823 -310.354214) (xy 365.311943 -310.40939)
			(xy 365.312452 -310.437276) (xy 365.311943 -310.465162) (xy 365.303823 -310.520338) (xy 365.287755 -310.573745)
			(xy 365.264083 -310.624242) (xy 365.23331 -310.670755) (xy 365.196093 -310.712292) (xy 365.153225 -310.747967)
			(xy 365.105619 -310.777021) (xy 365.05429 -310.798833) (xy 365.000333 -310.812939) (xy 364.944896 -310.819039)
			(xy 364.889162 -310.817002) (xy 364.834319 -310.806872) (xy 364.781535 -310.788865) (xy 364.731935 -310.763364)
			(xy 364.686577 -310.730913) (xy 364.646428 -310.692204) (xy 364.612342 -310.648061) (xy 364.585046 -310.599426)
			(xy 364.565123 -310.547335) (xy 364.552997 -310.492898) (xy 364.548926 -310.437276) (xy 364.296452 -310.437276)
			(xy 364.295943 -310.465162) (xy 364.287823 -310.520338) (xy 364.271755 -310.573745) (xy 364.248083 -310.624242)
			(xy 364.21731 -310.670755) (xy 364.180093 -310.712292) (xy 364.137225 -310.747967) (xy 364.089619 -310.777021)
			(xy 364.03829 -310.798833) (xy 363.984333 -310.812939) (xy 363.928896 -310.819039) (xy 363.873162 -310.817002)
			(xy 363.818319 -310.806872) (xy 363.765535 -310.788865) (xy 363.715935 -310.763364) (xy 363.670577 -310.730913)
			(xy 363.630428 -310.692204) (xy 363.596342 -310.648061) (xy 363.569046 -310.599426) (xy 363.549123 -310.547335)
			(xy 363.536997 -310.492898) (xy 363.532926 -310.437276) (xy 363.280452 -310.437276) (xy 363.279943 -310.465162)
			(xy 363.271823 -310.520338) (xy 363.255755 -310.573745) (xy 363.232083 -310.624242) (xy 363.20131 -310.670755)
			(xy 363.164093 -310.712292) (xy 363.121225 -310.747967) (xy 363.073619 -310.777021) (xy 363.02229 -310.798833)
			(xy 362.968333 -310.812939) (xy 362.912896 -310.819039) (xy 362.857162 -310.817002) (xy 362.802319 -310.806872)
			(xy 362.749535 -310.788865) (xy 362.699935 -310.763364) (xy 362.654577 -310.730913) (xy 362.614428 -310.692204)
			(xy 362.580342 -310.648061) (xy 362.553046 -310.599426) (xy 362.533123 -310.547335) (xy 362.520997 -310.492898)
			(xy 362.516926 -310.437276) (xy 362.264452 -310.437276) (xy 362.263943 -310.465162) (xy 362.255823 -310.520338)
			(xy 362.239755 -310.573745) (xy 362.216083 -310.624242) (xy 362.18531 -310.670755) (xy 362.148093 -310.712292)
			(xy 362.105225 -310.747967) (xy 362.057619 -310.777021) (xy 362.00629 -310.798833) (xy 361.952333 -310.812939)
			(xy 361.896896 -310.819039) (xy 361.841162 -310.817002) (xy 361.786319 -310.806872) (xy 361.733535 -310.788865)
			(xy 361.683935 -310.763364) (xy 361.638577 -310.730913) (xy 361.598428 -310.692204) (xy 361.564342 -310.648061)
			(xy 361.537046 -310.599426) (xy 361.517123 -310.547335) (xy 361.504997 -310.492898) (xy 361.500926 -310.437276)
			(xy 361.248452 -310.437276) (xy 361.247943 -310.465162) (xy 361.239823 -310.520338) (xy 361.223755 -310.573745)
			(xy 361.200083 -310.624242) (xy 361.16931 -310.670755) (xy 361.132093 -310.712292) (xy 361.089225 -310.747967)
			(xy 361.041619 -310.777021) (xy 360.99029 -310.798833) (xy 360.936333 -310.812939) (xy 360.880896 -310.819039)
			(xy 360.825162 -310.817002) (xy 360.770319 -310.806872) (xy 360.717535 -310.788865) (xy 360.667935 -310.763364)
			(xy 360.622577 -310.730913) (xy 360.582428 -310.692204) (xy 360.548342 -310.648061) (xy 360.521046 -310.599426)
			(xy 360.501123 -310.547335) (xy 360.488997 -310.492898) (xy 360.484926 -310.437276) (xy 360.232452 -310.437276)
			(xy 360.231943 -310.465162) (xy 360.223823 -310.520338) (xy 360.207755 -310.573745) (xy 360.184083 -310.624242)
			(xy 360.15331 -310.670755) (xy 360.116093 -310.712292) (xy 360.073225 -310.747967) (xy 360.025619 -310.777021)
			(xy 359.97429 -310.798833) (xy 359.920333 -310.812939) (xy 359.864896 -310.819039) (xy 359.809162 -310.817002)
			(xy 359.754319 -310.806872) (xy 359.701535 -310.788865) (xy 359.651935 -310.763364) (xy 359.606577 -310.730913)
			(xy 359.566428 -310.692204) (xy 359.532342 -310.648061) (xy 359.505046 -310.599426) (xy 359.485123 -310.547335)
			(xy 359.472997 -310.492898) (xy 359.468926 -310.437276) (xy 359.216452 -310.437276) (xy 359.215943 -310.465162)
			(xy 359.207823 -310.520338) (xy 359.191755 -310.573745) (xy 359.168083 -310.624242) (xy 359.13731 -310.670755)
			(xy 359.100093 -310.712292) (xy 359.057225 -310.747967) (xy 359.009619 -310.777021) (xy 358.95829 -310.798833)
			(xy 358.904333 -310.812939) (xy 358.848896 -310.819039) (xy 358.793162 -310.817002) (xy 358.738319 -310.806872)
			(xy 358.685535 -310.788865) (xy 358.635935 -310.763364) (xy 358.590577 -310.730913) (xy 358.550428 -310.692204)
			(xy 358.516342 -310.648061) (xy 358.489046 -310.599426) (xy 358.469123 -310.547335) (xy 358.456997 -310.492898)
			(xy 358.452926 -310.437276) (xy 358.200452 -310.437276) (xy 358.199943 -310.465162) (xy 358.191823 -310.520338)
			(xy 358.175755 -310.573745) (xy 358.152083 -310.624242) (xy 358.12131 -310.670755) (xy 358.084093 -310.712292)
			(xy 358.041225 -310.747967) (xy 357.993619 -310.777021) (xy 357.94229 -310.798833) (xy 357.888333 -310.812939)
			(xy 357.832896 -310.819039) (xy 357.777162 -310.817002) (xy 357.722319 -310.806872) (xy 357.669535 -310.788865)
			(xy 357.619935 -310.763364) (xy 357.574577 -310.730913) (xy 357.534428 -310.692204) (xy 357.500342 -310.648061)
			(xy 357.473046 -310.599426) (xy 357.453123 -310.547335) (xy 357.440997 -310.492898) (xy 357.436926 -310.437276)
			(xy 342.52631 -310.437276) (xy 342.500564 -310.476191) (xy 342.463347 -310.517728) (xy 342.420479 -310.553403)
			(xy 342.372873 -310.582457) (xy 342.321544 -310.604269) (xy 342.267587 -310.618375) (xy 342.21215 -310.624475)
			(xy 342.156416 -310.622438) (xy 342.101573 -310.612308) (xy 342.048789 -310.594301) (xy 341.999189 -310.5688)
			(xy 341.953831 -310.536349) (xy 341.913682 -310.49764) (xy 341.879596 -310.453497) (xy 341.8523 -310.404862)
			(xy 341.832377 -310.352771) (xy 341.820251 -310.298334) (xy 341.81618 -310.242712) (xy 341.563706 -310.242712)
			(xy 341.563197 -310.270598) (xy 341.555077 -310.325774) (xy 341.539009 -310.379181) (xy 341.515337 -310.429678)
			(xy 341.484564 -310.476191) (xy 341.447347 -310.517728) (xy 341.404479 -310.553403) (xy 341.356873 -310.582457)
			(xy 341.305544 -310.604269) (xy 341.251587 -310.618375) (xy 341.19615 -310.624475) (xy 341.140416 -310.622438)
			(xy 341.085573 -310.612308) (xy 341.032789 -310.594301) (xy 340.983189 -310.5688) (xy 340.937831 -310.536349)
			(xy 340.897682 -310.49764) (xy 340.863596 -310.453497) (xy 340.8363 -310.404862) (xy 340.816377 -310.352771)
			(xy 340.804251 -310.298334) (xy 340.80018 -310.242712) (xy 340.547706 -310.242712) (xy 340.547197 -310.270598)
			(xy 340.539077 -310.325774) (xy 340.523009 -310.379181) (xy 340.499337 -310.429678) (xy 340.468564 -310.476191)
			(xy 340.431347 -310.517728) (xy 340.388479 -310.553403) (xy 340.340873 -310.582457) (xy 340.289544 -310.604269)
			(xy 340.235587 -310.618375) (xy 340.18015 -310.624475) (xy 340.124416 -310.622438) (xy 340.069573 -310.612308)
			(xy 340.016789 -310.594301) (xy 339.967189 -310.5688) (xy 339.921831 -310.536349) (xy 339.881682 -310.49764)
			(xy 339.847596 -310.453497) (xy 339.8203 -310.404862) (xy 339.800377 -310.352771) (xy 339.788251 -310.298334)
			(xy 339.78418 -310.242712) (xy 339.531706 -310.242712) (xy 339.531197 -310.270598) (xy 339.523077 -310.325774)
			(xy 339.507009 -310.379181) (xy 339.483337 -310.429678) (xy 339.452564 -310.476191) (xy 339.415347 -310.517728)
			(xy 339.372479 -310.553403) (xy 339.324873 -310.582457) (xy 339.273544 -310.604269) (xy 339.219587 -310.618375)
			(xy 339.16415 -310.624475) (xy 339.108416 -310.622438) (xy 339.053573 -310.612308) (xy 339.000789 -310.594301)
			(xy 338.951189 -310.5688) (xy 338.905831 -310.536349) (xy 338.865682 -310.49764) (xy 338.831596 -310.453497)
			(xy 338.8043 -310.404862) (xy 338.784377 -310.352771) (xy 338.772251 -310.298334) (xy 338.76818 -310.242712)
			(xy 338.515706 -310.242712) (xy 338.515197 -310.270598) (xy 338.507077 -310.325774) (xy 338.491009 -310.379181)
			(xy 338.467337 -310.429678) (xy 338.436564 -310.476191) (xy 338.399347 -310.517728) (xy 338.356479 -310.553403)
			(xy 338.308873 -310.582457) (xy 338.257544 -310.604269) (xy 338.203587 -310.618375) (xy 338.14815 -310.624475)
			(xy 338.092416 -310.622438) (xy 338.037573 -310.612308) (xy 337.984789 -310.594301) (xy 337.935189 -310.5688)
			(xy 337.889831 -310.536349) (xy 337.849682 -310.49764) (xy 337.815596 -310.453497) (xy 337.7883 -310.404862)
			(xy 337.768377 -310.352771) (xy 337.756251 -310.298334) (xy 337.75218 -310.242712) (xy 337.499706 -310.242712)
			(xy 337.499197 -310.270598) (xy 337.491077 -310.325774) (xy 337.475009 -310.379181) (xy 337.451337 -310.429678)
			(xy 337.420564 -310.476191) (xy 337.383347 -310.517728) (xy 337.340479 -310.553403) (xy 337.292873 -310.582457)
			(xy 337.241544 -310.604269) (xy 337.187587 -310.618375) (xy 337.13215 -310.624475) (xy 337.076416 -310.622438)
			(xy 337.021573 -310.612308) (xy 336.968789 -310.594301) (xy 336.919189 -310.5688) (xy 336.873831 -310.536349)
			(xy 336.833682 -310.49764) (xy 336.799596 -310.453497) (xy 336.7723 -310.404862) (xy 336.752377 -310.352771)
			(xy 336.740251 -310.298334) (xy 336.73618 -310.242712) (xy 336.483706 -310.242712) (xy 336.483197 -310.270598)
			(xy 336.475077 -310.325774) (xy 336.459009 -310.379181) (xy 336.435337 -310.429678) (xy 336.404564 -310.476191)
			(xy 336.367347 -310.517728) (xy 336.324479 -310.553403) (xy 336.276873 -310.582457) (xy 336.225544 -310.604269)
			(xy 336.171587 -310.618375) (xy 336.11615 -310.624475) (xy 336.060416 -310.622438) (xy 336.005573 -310.612308)
			(xy 335.952789 -310.594301) (xy 335.903189 -310.5688) (xy 335.857831 -310.536349) (xy 335.817682 -310.49764)
			(xy 335.783596 -310.453497) (xy 335.7563 -310.404862) (xy 335.736377 -310.352771) (xy 335.724251 -310.298334)
			(xy 335.72018 -310.242712) (xy 335.467706 -310.242712) (xy 335.467197 -310.270598) (xy 335.459077 -310.325774)
			(xy 335.443009 -310.379181) (xy 335.419337 -310.429678) (xy 335.388564 -310.476191) (xy 335.351347 -310.517728)
			(xy 335.308479 -310.553403) (xy 335.260873 -310.582457) (xy 335.209544 -310.604269) (xy 335.155587 -310.618375)
			(xy 335.10015 -310.624475) (xy 335.044416 -310.622438) (xy 334.989573 -310.612308) (xy 334.936789 -310.594301)
			(xy 334.887189 -310.5688) (xy 334.841831 -310.536349) (xy 334.801682 -310.49764) (xy 334.767596 -310.453497)
			(xy 334.7403 -310.404862) (xy 334.720377 -310.352771) (xy 334.708251 -310.298334) (xy 334.70418 -310.242712)
			(xy 334.451706 -310.242712) (xy 334.451197 -310.270598) (xy 334.443077 -310.325774) (xy 334.427009 -310.379181)
			(xy 334.403337 -310.429678) (xy 334.372564 -310.476191) (xy 334.335347 -310.517728) (xy 334.292479 -310.553403)
			(xy 334.244873 -310.582457) (xy 334.193544 -310.604269) (xy 334.139587 -310.618375) (xy 334.08415 -310.624475)
			(xy 334.028416 -310.622438) (xy 333.973573 -310.612308) (xy 333.920789 -310.594301) (xy 333.871189 -310.5688)
			(xy 333.825831 -310.536349) (xy 333.785682 -310.49764) (xy 333.751596 -310.453497) (xy 333.7243 -310.404862)
			(xy 333.704377 -310.352771) (xy 333.692251 -310.298334) (xy 333.68818 -310.242712) (xy 333.435706 -310.242712)
			(xy 333.435197 -310.270598) (xy 333.427077 -310.325774) (xy 333.411009 -310.379181) (xy 333.387337 -310.429678)
			(xy 333.356564 -310.476191) (xy 333.319347 -310.517728) (xy 333.276479 -310.553403) (xy 333.228873 -310.582457)
			(xy 333.177544 -310.604269) (xy 333.123587 -310.618375) (xy 333.06815 -310.624475) (xy 333.012416 -310.622438)
			(xy 332.957573 -310.612308) (xy 332.904789 -310.594301) (xy 332.855189 -310.5688) (xy 332.809831 -310.536349)
			(xy 332.769682 -310.49764) (xy 332.735596 -310.453497) (xy 332.7083 -310.404862) (xy 332.688377 -310.352771)
			(xy 332.676251 -310.298334) (xy 332.67218 -310.242712) (xy 330.943966 -310.242712) (xy 330.943966 -311.258712)
			(xy 332.67218 -311.258712) (xy 332.676251 -311.20309) (xy 332.688377 -311.148653) (xy 332.7083 -311.096562)
			(xy 332.735596 -311.047927) (xy 332.769682 -311.003784) (xy 332.809831 -310.965075) (xy 332.855189 -310.932624)
			(xy 332.904789 -310.907123) (xy 332.957573 -310.889116) (xy 333.012416 -310.878986) (xy 333.06815 -310.876949)
			(xy 333.123587 -310.883049) (xy 333.177544 -310.897155) (xy 333.228873 -310.918967) (xy 333.276479 -310.948021)
			(xy 333.319347 -310.983696) (xy 333.356564 -311.025233) (xy 333.387337 -311.071746) (xy 333.411009 -311.122243)
			(xy 333.427077 -311.17565) (xy 333.435197 -311.230826) (xy 333.435706 -311.258712) (xy 333.68818 -311.258712)
			(xy 333.692251 -311.20309) (xy 333.704377 -311.148653) (xy 333.7243 -311.096562) (xy 333.751596 -311.047927)
			(xy 333.785682 -311.003784) (xy 333.825831 -310.965075) (xy 333.871189 -310.932624) (xy 333.920789 -310.907123)
			(xy 333.973573 -310.889116) (xy 334.028416 -310.878986) (xy 334.08415 -310.876949) (xy 334.139587 -310.883049)
			(xy 334.193544 -310.897155) (xy 334.244873 -310.918967) (xy 334.292479 -310.948021) (xy 334.335347 -310.983696)
			(xy 334.372564 -311.025233) (xy 334.403337 -311.071746) (xy 334.427009 -311.122243) (xy 334.443077 -311.17565)
			(xy 334.451197 -311.230826) (xy 334.451706 -311.258712) (xy 334.70418 -311.258712) (xy 334.708251 -311.20309)
			(xy 334.720377 -311.148653) (xy 334.7403 -311.096562) (xy 334.767596 -311.047927) (xy 334.801682 -311.003784)
			(xy 334.841831 -310.965075) (xy 334.887189 -310.932624) (xy 334.936789 -310.907123) (xy 334.989573 -310.889116)
			(xy 335.044416 -310.878986) (xy 335.10015 -310.876949) (xy 335.155587 -310.883049) (xy 335.209544 -310.897155)
			(xy 335.260873 -310.918967) (xy 335.308479 -310.948021) (xy 335.351347 -310.983696) (xy 335.388564 -311.025233)
			(xy 335.419337 -311.071746) (xy 335.443009 -311.122243) (xy 335.459077 -311.17565) (xy 335.467197 -311.230826)
			(xy 335.467706 -311.258712) (xy 335.72018 -311.258712) (xy 335.724251 -311.20309) (xy 335.736377 -311.148653)
			(xy 335.7563 -311.096562) (xy 335.783596 -311.047927) (xy 335.817682 -311.003784) (xy 335.857831 -310.965075)
			(xy 335.903189 -310.932624) (xy 335.952789 -310.907123) (xy 336.005573 -310.889116) (xy 336.060416 -310.878986)
			(xy 336.11615 -310.876949) (xy 336.171587 -310.883049) (xy 336.225544 -310.897155) (xy 336.276873 -310.918967)
			(xy 336.324479 -310.948021) (xy 336.367347 -310.983696) (xy 336.404564 -311.025233) (xy 336.435337 -311.071746)
			(xy 336.459009 -311.122243) (xy 336.475077 -311.17565) (xy 336.483197 -311.230826) (xy 336.483706 -311.258712)
			(xy 336.73618 -311.258712) (xy 336.740251 -311.20309) (xy 336.752377 -311.148653) (xy 336.7723 -311.096562)
			(xy 336.799596 -311.047927) (xy 336.833682 -311.003784) (xy 336.873831 -310.965075) (xy 336.919189 -310.932624)
			(xy 336.968789 -310.907123) (xy 337.021573 -310.889116) (xy 337.076416 -310.878986) (xy 337.13215 -310.876949)
			(xy 337.187587 -310.883049) (xy 337.241544 -310.897155) (xy 337.292873 -310.918967) (xy 337.340479 -310.948021)
			(xy 337.383347 -310.983696) (xy 337.420564 -311.025233) (xy 337.451337 -311.071746) (xy 337.475009 -311.122243)
			(xy 337.491077 -311.17565) (xy 337.499197 -311.230826) (xy 337.499706 -311.258712) (xy 337.75218 -311.258712)
			(xy 337.756251 -311.20309) (xy 337.768377 -311.148653) (xy 337.7883 -311.096562) (xy 337.815596 -311.047927)
			(xy 337.849682 -311.003784) (xy 337.889831 -310.965075) (xy 337.935189 -310.932624) (xy 337.984789 -310.907123)
			(xy 338.037573 -310.889116) (xy 338.092416 -310.878986) (xy 338.14815 -310.876949) (xy 338.203587 -310.883049)
			(xy 338.257544 -310.897155) (xy 338.308873 -310.918967) (xy 338.356479 -310.948021) (xy 338.399347 -310.983696)
			(xy 338.436564 -311.025233) (xy 338.467337 -311.071746) (xy 338.491009 -311.122243) (xy 338.507077 -311.17565)
			(xy 338.515197 -311.230826) (xy 338.515706 -311.258712) (xy 338.76818 -311.258712) (xy 338.772251 -311.20309)
			(xy 338.784377 -311.148653) (xy 338.8043 -311.096562) (xy 338.831596 -311.047927) (xy 338.865682 -311.003784)
			(xy 338.905831 -310.965075) (xy 338.951189 -310.932624) (xy 339.000789 -310.907123) (xy 339.053573 -310.889116)
			(xy 339.108416 -310.878986) (xy 339.16415 -310.876949) (xy 339.219587 -310.883049) (xy 339.273544 -310.897155)
			(xy 339.324873 -310.918967) (xy 339.372479 -310.948021) (xy 339.415347 -310.983696) (xy 339.452564 -311.025233)
			(xy 339.483337 -311.071746) (xy 339.507009 -311.122243) (xy 339.523077 -311.17565) (xy 339.531197 -311.230826)
			(xy 339.531706 -311.258712) (xy 339.78418 -311.258712) (xy 339.788251 -311.20309) (xy 339.800377 -311.148653)
			(xy 339.8203 -311.096562) (xy 339.847596 -311.047927) (xy 339.881682 -311.003784) (xy 339.921831 -310.965075)
			(xy 339.967189 -310.932624) (xy 340.016789 -310.907123) (xy 340.069573 -310.889116) (xy 340.124416 -310.878986)
			(xy 340.18015 -310.876949) (xy 340.235587 -310.883049) (xy 340.289544 -310.897155) (xy 340.340873 -310.918967)
			(xy 340.388479 -310.948021) (xy 340.431347 -310.983696) (xy 340.468564 -311.025233) (xy 340.499337 -311.071746)
			(xy 340.523009 -311.122243) (xy 340.539077 -311.17565) (xy 340.547197 -311.230826) (xy 340.547706 -311.258712)
			(xy 340.547197 -311.286598) (xy 340.539077 -311.341774) (xy 340.523009 -311.395181) (xy 340.499337 -311.445678)
			(xy 340.49431 -311.453276) (xy 357.436926 -311.453276) (xy 357.440997 -311.397654) (xy 357.453123 -311.343217)
			(xy 357.473046 -311.291126) (xy 357.500342 -311.242491) (xy 357.534428 -311.198348) (xy 357.574577 -311.159639)
			(xy 357.619935 -311.127188) (xy 357.669535 -311.101687) (xy 357.722319 -311.08368) (xy 357.777162 -311.07355)
			(xy 357.832896 -311.071513) (xy 357.888333 -311.077613) (xy 357.94229 -311.091719) (xy 357.993619 -311.113531)
			(xy 358.041225 -311.142585) (xy 358.084093 -311.17826) (xy 358.12131 -311.219797) (xy 358.152083 -311.26631)
			(xy 358.175755 -311.316807) (xy 358.191823 -311.370214) (xy 358.199943 -311.42539) (xy 358.200452 -311.453276)
			(xy 358.452926 -311.453276) (xy 358.456997 -311.397654) (xy 358.469123 -311.343217) (xy 358.489046 -311.291126)
			(xy 358.516342 -311.242491) (xy 358.550428 -311.198348) (xy 358.590577 -311.159639) (xy 358.635935 -311.127188)
			(xy 358.685535 -311.101687) (xy 358.738319 -311.08368) (xy 358.793162 -311.07355) (xy 358.848896 -311.071513)
			(xy 358.904333 -311.077613) (xy 358.95829 -311.091719) (xy 359.009619 -311.113531) (xy 359.057225 -311.142585)
			(xy 359.100093 -311.17826) (xy 359.13731 -311.219797) (xy 359.168083 -311.26631) (xy 359.191755 -311.316807)
			(xy 359.207823 -311.370214) (xy 359.215943 -311.42539) (xy 359.216452 -311.453276) (xy 359.468926 -311.453276)
			(xy 359.472997 -311.397654) (xy 359.485123 -311.343217) (xy 359.505046 -311.291126) (xy 359.532342 -311.242491)
			(xy 359.566428 -311.198348) (xy 359.606577 -311.159639) (xy 359.651935 -311.127188) (xy 359.701535 -311.101687)
			(xy 359.754319 -311.08368) (xy 359.809162 -311.07355) (xy 359.864896 -311.071513) (xy 359.920333 -311.077613)
			(xy 359.97429 -311.091719) (xy 360.025619 -311.113531) (xy 360.073225 -311.142585) (xy 360.116093 -311.17826)
			(xy 360.15331 -311.219797) (xy 360.184083 -311.26631) (xy 360.207755 -311.316807) (xy 360.223823 -311.370214)
			(xy 360.231943 -311.42539) (xy 360.232452 -311.453276) (xy 360.484926 -311.453276) (xy 360.488997 -311.397654)
			(xy 360.501123 -311.343217) (xy 360.521046 -311.291126) (xy 360.548342 -311.242491) (xy 360.582428 -311.198348)
			(xy 360.622577 -311.159639) (xy 360.667935 -311.127188) (xy 360.717535 -311.101687) (xy 360.770319 -311.08368)
			(xy 360.825162 -311.07355) (xy 360.880896 -311.071513) (xy 360.936333 -311.077613) (xy 360.99029 -311.091719)
			(xy 361.041619 -311.113531) (xy 361.089225 -311.142585) (xy 361.132093 -311.17826) (xy 361.16931 -311.219797)
			(xy 361.200083 -311.26631) (xy 361.223755 -311.316807) (xy 361.239823 -311.370214) (xy 361.247943 -311.42539)
			(xy 361.248452 -311.453276) (xy 361.500926 -311.453276) (xy 361.504997 -311.397654) (xy 361.517123 -311.343217)
			(xy 361.537046 -311.291126) (xy 361.564342 -311.242491) (xy 361.598428 -311.198348) (xy 361.638577 -311.159639)
			(xy 361.683935 -311.127188) (xy 361.733535 -311.101687) (xy 361.786319 -311.08368) (xy 361.841162 -311.07355)
			(xy 361.896896 -311.071513) (xy 361.952333 -311.077613) (xy 362.00629 -311.091719) (xy 362.057619 -311.113531)
			(xy 362.105225 -311.142585) (xy 362.148093 -311.17826) (xy 362.18531 -311.219797) (xy 362.216083 -311.26631)
			(xy 362.239755 -311.316807) (xy 362.255823 -311.370214) (xy 362.263943 -311.42539) (xy 362.264452 -311.453276)
			(xy 362.516926 -311.453276) (xy 362.520997 -311.397654) (xy 362.533123 -311.343217) (xy 362.553046 -311.291126)
			(xy 362.580342 -311.242491) (xy 362.614428 -311.198348) (xy 362.654577 -311.159639) (xy 362.699935 -311.127188)
			(xy 362.749535 -311.101687) (xy 362.802319 -311.08368) (xy 362.857162 -311.07355) (xy 362.912896 -311.071513)
			(xy 362.968333 -311.077613) (xy 363.02229 -311.091719) (xy 363.073619 -311.113531) (xy 363.121225 -311.142585)
			(xy 363.164093 -311.17826) (xy 363.20131 -311.219797) (xy 363.232083 -311.26631) (xy 363.255755 -311.316807)
			(xy 363.271823 -311.370214) (xy 363.279943 -311.42539) (xy 363.280452 -311.453276) (xy 363.532926 -311.453276)
			(xy 363.536997 -311.397654) (xy 363.549123 -311.343217) (xy 363.569046 -311.291126) (xy 363.596342 -311.242491)
			(xy 363.630428 -311.198348) (xy 363.670577 -311.159639) (xy 363.715935 -311.127188) (xy 363.765535 -311.101687)
			(xy 363.818319 -311.08368) (xy 363.873162 -311.07355) (xy 363.928896 -311.071513) (xy 363.984333 -311.077613)
			(xy 364.03829 -311.091719) (xy 364.089619 -311.113531) (xy 364.137225 -311.142585) (xy 364.180093 -311.17826)
			(xy 364.21731 -311.219797) (xy 364.248083 -311.26631) (xy 364.271755 -311.316807) (xy 364.287823 -311.370214)
			(xy 364.295943 -311.42539) (xy 364.296452 -311.453276) (xy 364.548926 -311.453276) (xy 364.552997 -311.397654)
			(xy 364.565123 -311.343217) (xy 364.585046 -311.291126) (xy 364.612342 -311.242491) (xy 364.646428 -311.198348)
			(xy 364.686577 -311.159639) (xy 364.731935 -311.127188) (xy 364.781535 -311.101687) (xy 364.834319 -311.08368)
			(xy 364.889162 -311.07355) (xy 364.944896 -311.071513) (xy 365.000333 -311.077613) (xy 365.05429 -311.091719)
			(xy 365.105619 -311.113531) (xy 365.153225 -311.142585) (xy 365.196093 -311.17826) (xy 365.23331 -311.219797)
			(xy 365.264083 -311.26631) (xy 365.287755 -311.316807) (xy 365.303823 -311.370214) (xy 365.311943 -311.42539)
			(xy 365.312452 -311.453276) (xy 365.311943 -311.481162) (xy 365.303823 -311.536338) (xy 365.287755 -311.589745)
			(xy 365.264083 -311.640242) (xy 365.23331 -311.686755) (xy 365.196093 -311.728292) (xy 365.153225 -311.763967)
			(xy 365.105619 -311.793021) (xy 365.05429 -311.814833) (xy 365.000333 -311.828939) (xy 364.944896 -311.835039)
			(xy 364.889162 -311.833002) (xy 364.834319 -311.822872) (xy 364.781535 -311.804865) (xy 364.731935 -311.779364)
			(xy 364.686577 -311.746913) (xy 364.646428 -311.708204) (xy 364.612342 -311.664061) (xy 364.585046 -311.615426)
			(xy 364.565123 -311.563335) (xy 364.552997 -311.508898) (xy 364.548926 -311.453276) (xy 364.296452 -311.453276)
			(xy 364.295943 -311.481162) (xy 364.287823 -311.536338) (xy 364.271755 -311.589745) (xy 364.248083 -311.640242)
			(xy 364.21731 -311.686755) (xy 364.180093 -311.728292) (xy 364.137225 -311.763967) (xy 364.089619 -311.793021)
			(xy 364.03829 -311.814833) (xy 363.984333 -311.828939) (xy 363.928896 -311.835039) (xy 363.873162 -311.833002)
			(xy 363.818319 -311.822872) (xy 363.765535 -311.804865) (xy 363.715935 -311.779364) (xy 363.670577 -311.746913)
			(xy 363.630428 -311.708204) (xy 363.596342 -311.664061) (xy 363.569046 -311.615426) (xy 363.549123 -311.563335)
			(xy 363.536997 -311.508898) (xy 363.532926 -311.453276) (xy 363.280452 -311.453276) (xy 363.279943 -311.481162)
			(xy 363.271823 -311.536338) (xy 363.255755 -311.589745) (xy 363.232083 -311.640242) (xy 363.20131 -311.686755)
			(xy 363.164093 -311.728292) (xy 363.121225 -311.763967) (xy 363.073619 -311.793021) (xy 363.02229 -311.814833)
			(xy 362.968333 -311.828939) (xy 362.912896 -311.835039) (xy 362.857162 -311.833002) (xy 362.802319 -311.822872)
			(xy 362.749535 -311.804865) (xy 362.699935 -311.779364) (xy 362.654577 -311.746913) (xy 362.614428 -311.708204)
			(xy 362.580342 -311.664061) (xy 362.553046 -311.615426) (xy 362.533123 -311.563335) (xy 362.520997 -311.508898)
			(xy 362.516926 -311.453276) (xy 362.264452 -311.453276) (xy 362.263943 -311.481162) (xy 362.255823 -311.536338)
			(xy 362.239755 -311.589745) (xy 362.216083 -311.640242) (xy 362.18531 -311.686755) (xy 362.148093 -311.728292)
			(xy 362.105225 -311.763967) (xy 362.057619 -311.793021) (xy 362.00629 -311.814833) (xy 361.952333 -311.828939)
			(xy 361.896896 -311.835039) (xy 361.841162 -311.833002) (xy 361.786319 -311.822872) (xy 361.733535 -311.804865)
			(xy 361.683935 -311.779364) (xy 361.638577 -311.746913) (xy 361.598428 -311.708204) (xy 361.564342 -311.664061)
			(xy 361.537046 -311.615426) (xy 361.517123 -311.563335) (xy 361.504997 -311.508898) (xy 361.500926 -311.453276)
			(xy 361.248452 -311.453276) (xy 361.247943 -311.481162) (xy 361.239823 -311.536338) (xy 361.223755 -311.589745)
			(xy 361.200083 -311.640242) (xy 361.16931 -311.686755) (xy 361.132093 -311.728292) (xy 361.089225 -311.763967)
			(xy 361.041619 -311.793021) (xy 360.99029 -311.814833) (xy 360.936333 -311.828939) (xy 360.880896 -311.835039)
			(xy 360.825162 -311.833002) (xy 360.770319 -311.822872) (xy 360.717535 -311.804865) (xy 360.667935 -311.779364)
			(xy 360.622577 -311.746913) (xy 360.582428 -311.708204) (xy 360.548342 -311.664061) (xy 360.521046 -311.615426)
			(xy 360.501123 -311.563335) (xy 360.488997 -311.508898) (xy 360.484926 -311.453276) (xy 360.232452 -311.453276)
			(xy 360.231943 -311.481162) (xy 360.223823 -311.536338) (xy 360.207755 -311.589745) (xy 360.184083 -311.640242)
			(xy 360.15331 -311.686755) (xy 360.116093 -311.728292) (xy 360.073225 -311.763967) (xy 360.025619 -311.793021)
			(xy 359.97429 -311.814833) (xy 359.920333 -311.828939) (xy 359.864896 -311.835039) (xy 359.809162 -311.833002)
			(xy 359.754319 -311.822872) (xy 359.701535 -311.804865) (xy 359.651935 -311.779364) (xy 359.606577 -311.746913)
			(xy 359.566428 -311.708204) (xy 359.532342 -311.664061) (xy 359.505046 -311.615426) (xy 359.485123 -311.563335)
			(xy 359.472997 -311.508898) (xy 359.468926 -311.453276) (xy 359.216452 -311.453276) (xy 359.215943 -311.481162)
			(xy 359.207823 -311.536338) (xy 359.191755 -311.589745) (xy 359.168083 -311.640242) (xy 359.13731 -311.686755)
			(xy 359.100093 -311.728292) (xy 359.057225 -311.763967) (xy 359.009619 -311.793021) (xy 358.95829 -311.814833)
			(xy 358.904333 -311.828939) (xy 358.848896 -311.835039) (xy 358.793162 -311.833002) (xy 358.738319 -311.822872)
			(xy 358.685535 -311.804865) (xy 358.635935 -311.779364) (xy 358.590577 -311.746913) (xy 358.550428 -311.708204)
			(xy 358.516342 -311.664061) (xy 358.489046 -311.615426) (xy 358.469123 -311.563335) (xy 358.456997 -311.508898)
			(xy 358.452926 -311.453276) (xy 358.200452 -311.453276) (xy 358.199943 -311.481162) (xy 358.191823 -311.536338)
			(xy 358.175755 -311.589745) (xy 358.152083 -311.640242) (xy 358.12131 -311.686755) (xy 358.084093 -311.728292)
			(xy 358.041225 -311.763967) (xy 357.993619 -311.793021) (xy 357.94229 -311.814833) (xy 357.888333 -311.828939)
			(xy 357.832896 -311.835039) (xy 357.777162 -311.833002) (xy 357.722319 -311.822872) (xy 357.669535 -311.804865)
			(xy 357.619935 -311.779364) (xy 357.574577 -311.746913) (xy 357.534428 -311.708204) (xy 357.500342 -311.664061)
			(xy 357.473046 -311.615426) (xy 357.453123 -311.563335) (xy 357.440997 -311.508898) (xy 357.436926 -311.453276)
			(xy 340.49431 -311.453276) (xy 340.468564 -311.492191) (xy 340.431347 -311.533728) (xy 340.388479 -311.569403)
			(xy 340.340873 -311.598457) (xy 340.289544 -311.620269) (xy 340.235587 -311.634375) (xy 340.18015 -311.640475)
			(xy 340.124416 -311.638438) (xy 340.069573 -311.628308) (xy 340.016789 -311.610301) (xy 339.967189 -311.5848)
			(xy 339.921831 -311.552349) (xy 339.881682 -311.51364) (xy 339.847596 -311.469497) (xy 339.8203 -311.420862)
			(xy 339.800377 -311.368771) (xy 339.788251 -311.314334) (xy 339.78418 -311.258712) (xy 339.531706 -311.258712)
			(xy 339.531197 -311.286598) (xy 339.523077 -311.341774) (xy 339.507009 -311.395181) (xy 339.483337 -311.445678)
			(xy 339.452564 -311.492191) (xy 339.415347 -311.533728) (xy 339.372479 -311.569403) (xy 339.324873 -311.598457)
			(xy 339.273544 -311.620269) (xy 339.219587 -311.634375) (xy 339.16415 -311.640475) (xy 339.108416 -311.638438)
			(xy 339.053573 -311.628308) (xy 339.000789 -311.610301) (xy 338.951189 -311.5848) (xy 338.905831 -311.552349)
			(xy 338.865682 -311.51364) (xy 338.831596 -311.469497) (xy 338.8043 -311.420862) (xy 338.784377 -311.368771)
			(xy 338.772251 -311.314334) (xy 338.76818 -311.258712) (xy 338.515706 -311.258712) (xy 338.515197 -311.286598)
			(xy 338.507077 -311.341774) (xy 338.491009 -311.395181) (xy 338.467337 -311.445678) (xy 338.436564 -311.492191)
			(xy 338.399347 -311.533728) (xy 338.356479 -311.569403) (xy 338.308873 -311.598457) (xy 338.257544 -311.620269)
			(xy 338.203587 -311.634375) (xy 338.14815 -311.640475) (xy 338.092416 -311.638438) (xy 338.037573 -311.628308)
			(xy 337.984789 -311.610301) (xy 337.935189 -311.5848) (xy 337.889831 -311.552349) (xy 337.849682 -311.51364)
			(xy 337.815596 -311.469497) (xy 337.7883 -311.420862) (xy 337.768377 -311.368771) (xy 337.756251 -311.314334)
			(xy 337.75218 -311.258712) (xy 337.499706 -311.258712) (xy 337.499197 -311.286598) (xy 337.491077 -311.341774)
			(xy 337.475009 -311.395181) (xy 337.451337 -311.445678) (xy 337.420564 -311.492191) (xy 337.383347 -311.533728)
			(xy 337.340479 -311.569403) (xy 337.292873 -311.598457) (xy 337.241544 -311.620269) (xy 337.187587 -311.634375)
			(xy 337.13215 -311.640475) (xy 337.076416 -311.638438) (xy 337.021573 -311.628308) (xy 336.968789 -311.610301)
			(xy 336.919189 -311.5848) (xy 336.873831 -311.552349) (xy 336.833682 -311.51364) (xy 336.799596 -311.469497)
			(xy 336.7723 -311.420862) (xy 336.752377 -311.368771) (xy 336.740251 -311.314334) (xy 336.73618 -311.258712)
			(xy 336.483706 -311.258712) (xy 336.483197 -311.286598) (xy 336.475077 -311.341774) (xy 336.459009 -311.395181)
			(xy 336.435337 -311.445678) (xy 336.404564 -311.492191) (xy 336.367347 -311.533728) (xy 336.324479 -311.569403)
			(xy 336.276873 -311.598457) (xy 336.225544 -311.620269) (xy 336.171587 -311.634375) (xy 336.11615 -311.640475)
			(xy 336.060416 -311.638438) (xy 336.005573 -311.628308) (xy 335.952789 -311.610301) (xy 335.903189 -311.5848)
			(xy 335.857831 -311.552349) (xy 335.817682 -311.51364) (xy 335.783596 -311.469497) (xy 335.7563 -311.420862)
			(xy 335.736377 -311.368771) (xy 335.724251 -311.314334) (xy 335.72018 -311.258712) (xy 335.467706 -311.258712)
			(xy 335.467197 -311.286598) (xy 335.459077 -311.341774) (xy 335.443009 -311.395181) (xy 335.419337 -311.445678)
			(xy 335.388564 -311.492191) (xy 335.351347 -311.533728) (xy 335.308479 -311.569403) (xy 335.260873 -311.598457)
			(xy 335.209544 -311.620269) (xy 335.155587 -311.634375) (xy 335.10015 -311.640475) (xy 335.044416 -311.638438)
			(xy 334.989573 -311.628308) (xy 334.936789 -311.610301) (xy 334.887189 -311.5848) (xy 334.841831 -311.552349)
			(xy 334.801682 -311.51364) (xy 334.767596 -311.469497) (xy 334.7403 -311.420862) (xy 334.720377 -311.368771)
			(xy 334.708251 -311.314334) (xy 334.70418 -311.258712) (xy 334.451706 -311.258712) (xy 334.451197 -311.286598)
			(xy 334.443077 -311.341774) (xy 334.427009 -311.395181) (xy 334.403337 -311.445678) (xy 334.372564 -311.492191)
			(xy 334.335347 -311.533728) (xy 334.292479 -311.569403) (xy 334.244873 -311.598457) (xy 334.193544 -311.620269)
			(xy 334.139587 -311.634375) (xy 334.08415 -311.640475) (xy 334.028416 -311.638438) (xy 333.973573 -311.628308)
			(xy 333.920789 -311.610301) (xy 333.871189 -311.5848) (xy 333.825831 -311.552349) (xy 333.785682 -311.51364)
			(xy 333.751596 -311.469497) (xy 333.7243 -311.420862) (xy 333.704377 -311.368771) (xy 333.692251 -311.314334)
			(xy 333.68818 -311.258712) (xy 333.435706 -311.258712) (xy 333.435197 -311.286598) (xy 333.427077 -311.341774)
			(xy 333.411009 -311.395181) (xy 333.387337 -311.445678) (xy 333.356564 -311.492191) (xy 333.319347 -311.533728)
			(xy 333.276479 -311.569403) (xy 333.228873 -311.598457) (xy 333.177544 -311.620269) (xy 333.123587 -311.634375)
			(xy 333.06815 -311.640475) (xy 333.012416 -311.638438) (xy 332.957573 -311.628308) (xy 332.904789 -311.610301)
			(xy 332.855189 -311.5848) (xy 332.809831 -311.552349) (xy 332.769682 -311.51364) (xy 332.735596 -311.469497)
			(xy 332.7083 -311.420862) (xy 332.688377 -311.368771) (xy 332.676251 -311.314334) (xy 332.67218 -311.258712)
			(xy 330.943966 -311.258712) (xy 330.943966 -312.274712) (xy 332.67218 -312.274712) (xy 332.676251 -312.21909)
			(xy 332.688377 -312.164653) (xy 332.7083 -312.112562) (xy 332.735596 -312.063927) (xy 332.769682 -312.019784)
			(xy 332.809831 -311.981075) (xy 332.855189 -311.948624) (xy 332.904789 -311.923123) (xy 332.957573 -311.905116)
			(xy 333.012416 -311.894986) (xy 333.06815 -311.892949) (xy 333.123587 -311.899049) (xy 333.177544 -311.913155)
			(xy 333.228873 -311.934967) (xy 333.276479 -311.964021) (xy 333.319347 -311.999696) (xy 333.356564 -312.041233)
			(xy 333.387337 -312.087746) (xy 333.411009 -312.138243) (xy 333.427077 -312.19165) (xy 333.435197 -312.246826)
			(xy 333.435706 -312.274712) (xy 333.68818 -312.274712) (xy 333.692251 -312.21909) (xy 333.704377 -312.164653)
			(xy 333.7243 -312.112562) (xy 333.751596 -312.063927) (xy 333.785682 -312.019784) (xy 333.825831 -311.981075)
			(xy 333.871189 -311.948624) (xy 333.920789 -311.923123) (xy 333.973573 -311.905116) (xy 334.028416 -311.894986)
			(xy 334.08415 -311.892949) (xy 334.139587 -311.899049) (xy 334.193544 -311.913155) (xy 334.244873 -311.934967)
			(xy 334.292479 -311.964021) (xy 334.335347 -311.999696) (xy 334.372564 -312.041233) (xy 334.403337 -312.087746)
			(xy 334.427009 -312.138243) (xy 334.443077 -312.19165) (xy 334.451197 -312.246826) (xy 334.451706 -312.274712)
			(xy 334.70418 -312.274712) (xy 334.708251 -312.21909) (xy 334.720377 -312.164653) (xy 334.7403 -312.112562)
			(xy 334.767596 -312.063927) (xy 334.801682 -312.019784) (xy 334.841831 -311.981075) (xy 334.887189 -311.948624)
			(xy 334.936789 -311.923123) (xy 334.989573 -311.905116) (xy 335.044416 -311.894986) (xy 335.10015 -311.892949)
			(xy 335.155587 -311.899049) (xy 335.209544 -311.913155) (xy 335.260873 -311.934967) (xy 335.308479 -311.964021)
			(xy 335.351347 -311.999696) (xy 335.388564 -312.041233) (xy 335.419337 -312.087746) (xy 335.443009 -312.138243)
			(xy 335.459077 -312.19165) (xy 335.467197 -312.246826) (xy 335.467706 -312.274712) (xy 335.72018 -312.274712)
			(xy 335.724251 -312.21909) (xy 335.736377 -312.164653) (xy 335.7563 -312.112562) (xy 335.783596 -312.063927)
			(xy 335.817682 -312.019784) (xy 335.857831 -311.981075) (xy 335.903189 -311.948624) (xy 335.952789 -311.923123)
			(xy 336.005573 -311.905116) (xy 336.060416 -311.894986) (xy 336.11615 -311.892949) (xy 336.171587 -311.899049)
			(xy 336.225544 -311.913155) (xy 336.276873 -311.934967) (xy 336.324479 -311.964021) (xy 336.367347 -311.999696)
			(xy 336.404564 -312.041233) (xy 336.435337 -312.087746) (xy 336.459009 -312.138243) (xy 336.475077 -312.19165)
			(xy 336.483197 -312.246826) (xy 336.483706 -312.274712) (xy 336.73618 -312.274712) (xy 336.740251 -312.21909)
			(xy 336.752377 -312.164653) (xy 336.7723 -312.112562) (xy 336.799596 -312.063927) (xy 336.833682 -312.019784)
			(xy 336.873831 -311.981075) (xy 336.919189 -311.948624) (xy 336.968789 -311.923123) (xy 337.021573 -311.905116)
			(xy 337.076416 -311.894986) (xy 337.13215 -311.892949) (xy 337.187587 -311.899049) (xy 337.241544 -311.913155)
			(xy 337.292873 -311.934967) (xy 337.340479 -311.964021) (xy 337.383347 -311.999696) (xy 337.420564 -312.041233)
			(xy 337.451337 -312.087746) (xy 337.475009 -312.138243) (xy 337.491077 -312.19165) (xy 337.499197 -312.246826)
			(xy 337.499706 -312.274712) (xy 337.75218 -312.274712) (xy 337.756251 -312.21909) (xy 337.768377 -312.164653)
			(xy 337.7883 -312.112562) (xy 337.815596 -312.063927) (xy 337.849682 -312.019784) (xy 337.889831 -311.981075)
			(xy 337.935189 -311.948624) (xy 337.984789 -311.923123) (xy 338.037573 -311.905116) (xy 338.092416 -311.894986)
			(xy 338.14815 -311.892949) (xy 338.203587 -311.899049) (xy 338.257544 -311.913155) (xy 338.308873 -311.934967)
			(xy 338.356479 -311.964021) (xy 338.399347 -311.999696) (xy 338.436564 -312.041233) (xy 338.467337 -312.087746)
			(xy 338.491009 -312.138243) (xy 338.507077 -312.19165) (xy 338.515197 -312.246826) (xy 338.515706 -312.274712)
			(xy 338.76818 -312.274712) (xy 338.772251 -312.21909) (xy 338.784377 -312.164653) (xy 338.8043 -312.112562)
			(xy 338.831596 -312.063927) (xy 338.865682 -312.019784) (xy 338.905831 -311.981075) (xy 338.951189 -311.948624)
			(xy 339.000789 -311.923123) (xy 339.053573 -311.905116) (xy 339.108416 -311.894986) (xy 339.16415 -311.892949)
			(xy 339.219587 -311.899049) (xy 339.273544 -311.913155) (xy 339.324873 -311.934967) (xy 339.372479 -311.964021)
			(xy 339.415347 -311.999696) (xy 339.452564 -312.041233) (xy 339.483337 -312.087746) (xy 339.507009 -312.138243)
			(xy 339.523077 -312.19165) (xy 339.531197 -312.246826) (xy 339.531706 -312.274712) (xy 339.78418 -312.274712)
			(xy 339.788251 -312.21909) (xy 339.800377 -312.164653) (xy 339.8203 -312.112562) (xy 339.847596 -312.063927)
			(xy 339.881682 -312.019784) (xy 339.921831 -311.981075) (xy 339.967189 -311.948624) (xy 340.016789 -311.923123)
			(xy 340.069573 -311.905116) (xy 340.124416 -311.894986) (xy 340.18015 -311.892949) (xy 340.235587 -311.899049)
			(xy 340.289544 -311.913155) (xy 340.340873 -311.934967) (xy 340.388479 -311.964021) (xy 340.431347 -311.999696)
			(xy 340.468564 -312.041233) (xy 340.499337 -312.087746) (xy 340.523009 -312.138243) (xy 340.539077 -312.19165)
			(xy 340.547197 -312.246826) (xy 340.547706 -312.274712) (xy 340.80018 -312.274712) (xy 340.804251 -312.21909)
			(xy 340.816377 -312.164653) (xy 340.8363 -312.112562) (xy 340.863596 -312.063927) (xy 340.897682 -312.019784)
			(xy 340.937831 -311.981075) (xy 340.983189 -311.948624) (xy 341.032789 -311.923123) (xy 341.085573 -311.905116)
			(xy 341.140416 -311.894986) (xy 341.19615 -311.892949) (xy 341.251587 -311.899049) (xy 341.305544 -311.913155)
			(xy 341.356873 -311.934967) (xy 341.404479 -311.964021) (xy 341.447347 -311.999696) (xy 341.484564 -312.041233)
			(xy 341.515337 -312.087746) (xy 341.539009 -312.138243) (xy 341.555077 -312.19165) (xy 341.563197 -312.246826)
			(xy 341.563706 -312.274712) (xy 341.81618 -312.274712) (xy 341.820251 -312.21909) (xy 341.832377 -312.164653)
			(xy 341.8523 -312.112562) (xy 341.879596 -312.063927) (xy 341.913682 -312.019784) (xy 341.953831 -311.981075)
			(xy 341.999189 -311.948624) (xy 342.048789 -311.923123) (xy 342.101573 -311.905116) (xy 342.156416 -311.894986)
			(xy 342.21215 -311.892949) (xy 342.267587 -311.899049) (xy 342.321544 -311.913155) (xy 342.372873 -311.934967)
			(xy 342.420479 -311.964021) (xy 342.463347 -311.999696) (xy 342.500564 -312.041233) (xy 342.531337 -312.087746)
			(xy 342.555009 -312.138243) (xy 342.571077 -312.19165) (xy 342.579197 -312.246826) (xy 342.579706 -312.274712)
			(xy 342.579197 -312.302598) (xy 342.571077 -312.357774) (xy 342.555009 -312.411181) (xy 342.531337 -312.461678)
			(xy 342.52631 -312.469276) (xy 357.436926 -312.469276) (xy 357.440997 -312.413654) (xy 357.453123 -312.359217)
			(xy 357.473046 -312.307126) (xy 357.500342 -312.258491) (xy 357.534428 -312.214348) (xy 357.574577 -312.175639)
			(xy 357.619935 -312.143188) (xy 357.669535 -312.117687) (xy 357.722319 -312.09968) (xy 357.777162 -312.08955)
			(xy 357.832896 -312.087513) (xy 357.888333 -312.093613) (xy 357.94229 -312.107719) (xy 357.993619 -312.129531)
			(xy 358.041225 -312.158585) (xy 358.084093 -312.19426) (xy 358.12131 -312.235797) (xy 358.152083 -312.28231)
			(xy 358.175755 -312.332807) (xy 358.191823 -312.386214) (xy 358.199943 -312.44139) (xy 358.200452 -312.469276)
			(xy 358.452926 -312.469276) (xy 358.456997 -312.413654) (xy 358.469123 -312.359217) (xy 358.489046 -312.307126)
			(xy 358.516342 -312.258491) (xy 358.550428 -312.214348) (xy 358.590577 -312.175639) (xy 358.635935 -312.143188)
			(xy 358.685535 -312.117687) (xy 358.738319 -312.09968) (xy 358.793162 -312.08955) (xy 358.848896 -312.087513)
			(xy 358.904333 -312.093613) (xy 358.95829 -312.107719) (xy 359.009619 -312.129531) (xy 359.057225 -312.158585)
			(xy 359.100093 -312.19426) (xy 359.13731 -312.235797) (xy 359.168083 -312.28231) (xy 359.191755 -312.332807)
			(xy 359.207823 -312.386214) (xy 359.215943 -312.44139) (xy 359.216452 -312.469276) (xy 359.468926 -312.469276)
			(xy 359.472997 -312.413654) (xy 359.485123 -312.359217) (xy 359.505046 -312.307126) (xy 359.532342 -312.258491)
			(xy 359.566428 -312.214348) (xy 359.606577 -312.175639) (xy 359.651935 -312.143188) (xy 359.701535 -312.117687)
			(xy 359.754319 -312.09968) (xy 359.809162 -312.08955) (xy 359.864896 -312.087513) (xy 359.920333 -312.093613)
			(xy 359.97429 -312.107719) (xy 360.025619 -312.129531) (xy 360.073225 -312.158585) (xy 360.116093 -312.19426)
			(xy 360.15331 -312.235797) (xy 360.184083 -312.28231) (xy 360.207755 -312.332807) (xy 360.223823 -312.386214)
			(xy 360.231943 -312.44139) (xy 360.232452 -312.469276) (xy 360.484926 -312.469276) (xy 360.488997 -312.413654)
			(xy 360.501123 -312.359217) (xy 360.521046 -312.307126) (xy 360.548342 -312.258491) (xy 360.582428 -312.214348)
			(xy 360.622577 -312.175639) (xy 360.667935 -312.143188) (xy 360.717535 -312.117687) (xy 360.770319 -312.09968)
			(xy 360.825162 -312.08955) (xy 360.880896 -312.087513) (xy 360.936333 -312.093613) (xy 360.99029 -312.107719)
			(xy 361.041619 -312.129531) (xy 361.089225 -312.158585) (xy 361.132093 -312.19426) (xy 361.16931 -312.235797)
			(xy 361.200083 -312.28231) (xy 361.223755 -312.332807) (xy 361.239823 -312.386214) (xy 361.247943 -312.44139)
			(xy 361.248452 -312.469276) (xy 361.500926 -312.469276) (xy 361.504997 -312.413654) (xy 361.517123 -312.359217)
			(xy 361.537046 -312.307126) (xy 361.564342 -312.258491) (xy 361.598428 -312.214348) (xy 361.638577 -312.175639)
			(xy 361.683935 -312.143188) (xy 361.733535 -312.117687) (xy 361.786319 -312.09968) (xy 361.841162 -312.08955)
			(xy 361.896896 -312.087513) (xy 361.952333 -312.093613) (xy 362.00629 -312.107719) (xy 362.057619 -312.129531)
			(xy 362.105225 -312.158585) (xy 362.148093 -312.19426) (xy 362.18531 -312.235797) (xy 362.216083 -312.28231)
			(xy 362.239755 -312.332807) (xy 362.255823 -312.386214) (xy 362.263943 -312.44139) (xy 362.264452 -312.469276)
			(xy 362.516926 -312.469276) (xy 362.520997 -312.413654) (xy 362.533123 -312.359217) (xy 362.553046 -312.307126)
			(xy 362.580342 -312.258491) (xy 362.614428 -312.214348) (xy 362.654577 -312.175639) (xy 362.699935 -312.143188)
			(xy 362.749535 -312.117687) (xy 362.802319 -312.09968) (xy 362.857162 -312.08955) (xy 362.912896 -312.087513)
			(xy 362.968333 -312.093613) (xy 363.02229 -312.107719) (xy 363.073619 -312.129531) (xy 363.121225 -312.158585)
			(xy 363.164093 -312.19426) (xy 363.20131 -312.235797) (xy 363.232083 -312.28231) (xy 363.255755 -312.332807)
			(xy 363.271823 -312.386214) (xy 363.279943 -312.44139) (xy 363.280452 -312.469276) (xy 363.532926 -312.469276)
			(xy 363.536997 -312.413654) (xy 363.549123 -312.359217) (xy 363.569046 -312.307126) (xy 363.596342 -312.258491)
			(xy 363.630428 -312.214348) (xy 363.670577 -312.175639) (xy 363.715935 -312.143188) (xy 363.765535 -312.117687)
			(xy 363.818319 -312.09968) (xy 363.873162 -312.08955) (xy 363.928896 -312.087513) (xy 363.984333 -312.093613)
			(xy 364.03829 -312.107719) (xy 364.089619 -312.129531) (xy 364.137225 -312.158585) (xy 364.180093 -312.19426)
			(xy 364.21731 -312.235797) (xy 364.248083 -312.28231) (xy 364.271755 -312.332807) (xy 364.287823 -312.386214)
			(xy 364.295943 -312.44139) (xy 364.296452 -312.469276) (xy 364.295943 -312.497162) (xy 364.287823 -312.552338)
			(xy 364.271755 -312.605745) (xy 364.248083 -312.656242) (xy 364.21731 -312.702755) (xy 364.180093 -312.744292)
			(xy 364.137225 -312.779967) (xy 364.089619 -312.809021) (xy 364.03829 -312.830833) (xy 363.984333 -312.844939)
			(xy 363.928896 -312.851039) (xy 363.873162 -312.849002) (xy 363.818319 -312.838872) (xy 363.765535 -312.820865)
			(xy 363.715935 -312.795364) (xy 363.670577 -312.762913) (xy 363.630428 -312.724204) (xy 363.596342 -312.680061)
			(xy 363.569046 -312.631426) (xy 363.549123 -312.579335) (xy 363.536997 -312.524898) (xy 363.532926 -312.469276)
			(xy 363.280452 -312.469276) (xy 363.279943 -312.497162) (xy 363.271823 -312.552338) (xy 363.255755 -312.605745)
			(xy 363.232083 -312.656242) (xy 363.20131 -312.702755) (xy 363.164093 -312.744292) (xy 363.121225 -312.779967)
			(xy 363.073619 -312.809021) (xy 363.02229 -312.830833) (xy 362.968333 -312.844939) (xy 362.912896 -312.851039)
			(xy 362.857162 -312.849002) (xy 362.802319 -312.838872) (xy 362.749535 -312.820865) (xy 362.699935 -312.795364)
			(xy 362.654577 -312.762913) (xy 362.614428 -312.724204) (xy 362.580342 -312.680061) (xy 362.553046 -312.631426)
			(xy 362.533123 -312.579335) (xy 362.520997 -312.524898) (xy 362.516926 -312.469276) (xy 362.264452 -312.469276)
			(xy 362.263943 -312.497162) (xy 362.255823 -312.552338) (xy 362.239755 -312.605745) (xy 362.216083 -312.656242)
			(xy 362.18531 -312.702755) (xy 362.148093 -312.744292) (xy 362.105225 -312.779967) (xy 362.057619 -312.809021)
			(xy 362.00629 -312.830833) (xy 361.952333 -312.844939) (xy 361.896896 -312.851039) (xy 361.841162 -312.849002)
			(xy 361.786319 -312.838872) (xy 361.733535 -312.820865) (xy 361.683935 -312.795364) (xy 361.638577 -312.762913)
			(xy 361.598428 -312.724204) (xy 361.564342 -312.680061) (xy 361.537046 -312.631426) (xy 361.517123 -312.579335)
			(xy 361.504997 -312.524898) (xy 361.500926 -312.469276) (xy 361.248452 -312.469276) (xy 361.247943 -312.497162)
			(xy 361.239823 -312.552338) (xy 361.223755 -312.605745) (xy 361.200083 -312.656242) (xy 361.16931 -312.702755)
			(xy 361.132093 -312.744292) (xy 361.089225 -312.779967) (xy 361.041619 -312.809021) (xy 360.99029 -312.830833)
			(xy 360.936333 -312.844939) (xy 360.880896 -312.851039) (xy 360.825162 -312.849002) (xy 360.770319 -312.838872)
			(xy 360.717535 -312.820865) (xy 360.667935 -312.795364) (xy 360.622577 -312.762913) (xy 360.582428 -312.724204)
			(xy 360.548342 -312.680061) (xy 360.521046 -312.631426) (xy 360.501123 -312.579335) (xy 360.488997 -312.524898)
			(xy 360.484926 -312.469276) (xy 360.232452 -312.469276) (xy 360.231943 -312.497162) (xy 360.223823 -312.552338)
			(xy 360.207755 -312.605745) (xy 360.184083 -312.656242) (xy 360.15331 -312.702755) (xy 360.116093 -312.744292)
			(xy 360.073225 -312.779967) (xy 360.025619 -312.809021) (xy 359.97429 -312.830833) (xy 359.920333 -312.844939)
			(xy 359.864896 -312.851039) (xy 359.809162 -312.849002) (xy 359.754319 -312.838872) (xy 359.701535 -312.820865)
			(xy 359.651935 -312.795364) (xy 359.606577 -312.762913) (xy 359.566428 -312.724204) (xy 359.532342 -312.680061)
			(xy 359.505046 -312.631426) (xy 359.485123 -312.579335) (xy 359.472997 -312.524898) (xy 359.468926 -312.469276)
			(xy 359.216452 -312.469276) (xy 359.215943 -312.497162) (xy 359.207823 -312.552338) (xy 359.191755 -312.605745)
			(xy 359.168083 -312.656242) (xy 359.13731 -312.702755) (xy 359.100093 -312.744292) (xy 359.057225 -312.779967)
			(xy 359.009619 -312.809021) (xy 358.95829 -312.830833) (xy 358.904333 -312.844939) (xy 358.848896 -312.851039)
			(xy 358.793162 -312.849002) (xy 358.738319 -312.838872) (xy 358.685535 -312.820865) (xy 358.635935 -312.795364)
			(xy 358.590577 -312.762913) (xy 358.550428 -312.724204) (xy 358.516342 -312.680061) (xy 358.489046 -312.631426)
			(xy 358.469123 -312.579335) (xy 358.456997 -312.524898) (xy 358.452926 -312.469276) (xy 358.200452 -312.469276)
			(xy 358.199943 -312.497162) (xy 358.191823 -312.552338) (xy 358.175755 -312.605745) (xy 358.152083 -312.656242)
			(xy 358.12131 -312.702755) (xy 358.084093 -312.744292) (xy 358.041225 -312.779967) (xy 357.993619 -312.809021)
			(xy 357.94229 -312.830833) (xy 357.888333 -312.844939) (xy 357.832896 -312.851039) (xy 357.777162 -312.849002)
			(xy 357.722319 -312.838872) (xy 357.669535 -312.820865) (xy 357.619935 -312.795364) (xy 357.574577 -312.762913)
			(xy 357.534428 -312.724204) (xy 357.500342 -312.680061) (xy 357.473046 -312.631426) (xy 357.453123 -312.579335)
			(xy 357.440997 -312.524898) (xy 357.436926 -312.469276) (xy 342.52631 -312.469276) (xy 342.500564 -312.508191)
			(xy 342.463347 -312.549728) (xy 342.420479 -312.585403) (xy 342.372873 -312.614457) (xy 342.321544 -312.636269)
			(xy 342.267587 -312.650375) (xy 342.21215 -312.656475) (xy 342.156416 -312.654438) (xy 342.101573 -312.644308)
			(xy 342.048789 -312.626301) (xy 341.999189 -312.6008) (xy 341.953831 -312.568349) (xy 341.913682 -312.52964)
			(xy 341.879596 -312.485497) (xy 341.8523 -312.436862) (xy 341.832377 -312.384771) (xy 341.820251 -312.330334)
			(xy 341.81618 -312.274712) (xy 341.563706 -312.274712) (xy 341.563197 -312.302598) (xy 341.555077 -312.357774)
			(xy 341.539009 -312.411181) (xy 341.515337 -312.461678) (xy 341.484564 -312.508191) (xy 341.447347 -312.549728)
			(xy 341.404479 -312.585403) (xy 341.356873 -312.614457) (xy 341.305544 -312.636269) (xy 341.251587 -312.650375)
			(xy 341.19615 -312.656475) (xy 341.140416 -312.654438) (xy 341.085573 -312.644308) (xy 341.032789 -312.626301)
			(xy 340.983189 -312.6008) (xy 340.937831 -312.568349) (xy 340.897682 -312.52964) (xy 340.863596 -312.485497)
			(xy 340.8363 -312.436862) (xy 340.816377 -312.384771) (xy 340.804251 -312.330334) (xy 340.80018 -312.274712)
			(xy 340.547706 -312.274712) (xy 340.547197 -312.302598) (xy 340.539077 -312.357774) (xy 340.523009 -312.411181)
			(xy 340.499337 -312.461678) (xy 340.468564 -312.508191) (xy 340.431347 -312.549728) (xy 340.388479 -312.585403)
			(xy 340.340873 -312.614457) (xy 340.289544 -312.636269) (xy 340.235587 -312.650375) (xy 340.18015 -312.656475)
			(xy 340.124416 -312.654438) (xy 340.069573 -312.644308) (xy 340.016789 -312.626301) (xy 339.967189 -312.6008)
			(xy 339.921831 -312.568349) (xy 339.881682 -312.52964) (xy 339.847596 -312.485497) (xy 339.8203 -312.436862)
			(xy 339.800377 -312.384771) (xy 339.788251 -312.330334) (xy 339.78418 -312.274712) (xy 339.531706 -312.274712)
			(xy 339.531197 -312.302598) (xy 339.523077 -312.357774) (xy 339.507009 -312.411181) (xy 339.483337 -312.461678)
			(xy 339.452564 -312.508191) (xy 339.415347 -312.549728) (xy 339.372479 -312.585403) (xy 339.324873 -312.614457)
			(xy 339.273544 -312.636269) (xy 339.219587 -312.650375) (xy 339.16415 -312.656475) (xy 339.108416 -312.654438)
			(xy 339.053573 -312.644308) (xy 339.000789 -312.626301) (xy 338.951189 -312.6008) (xy 338.905831 -312.568349)
			(xy 338.865682 -312.52964) (xy 338.831596 -312.485497) (xy 338.8043 -312.436862) (xy 338.784377 -312.384771)
			(xy 338.772251 -312.330334) (xy 338.76818 -312.274712) (xy 338.515706 -312.274712) (xy 338.515197 -312.302598)
			(xy 338.507077 -312.357774) (xy 338.491009 -312.411181) (xy 338.467337 -312.461678) (xy 338.436564 -312.508191)
			(xy 338.399347 -312.549728) (xy 338.356479 -312.585403) (xy 338.308873 -312.614457) (xy 338.257544 -312.636269)
			(xy 338.203587 -312.650375) (xy 338.14815 -312.656475) (xy 338.092416 -312.654438) (xy 338.037573 -312.644308)
			(xy 337.984789 -312.626301) (xy 337.935189 -312.6008) (xy 337.889831 -312.568349) (xy 337.849682 -312.52964)
			(xy 337.815596 -312.485497) (xy 337.7883 -312.436862) (xy 337.768377 -312.384771) (xy 337.756251 -312.330334)
			(xy 337.75218 -312.274712) (xy 337.499706 -312.274712) (xy 337.499197 -312.302598) (xy 337.491077 -312.357774)
			(xy 337.475009 -312.411181) (xy 337.451337 -312.461678) (xy 337.420564 -312.508191) (xy 337.383347 -312.549728)
			(xy 337.340479 -312.585403) (xy 337.292873 -312.614457) (xy 337.241544 -312.636269) (xy 337.187587 -312.650375)
			(xy 337.13215 -312.656475) (xy 337.076416 -312.654438) (xy 337.021573 -312.644308) (xy 336.968789 -312.626301)
			(xy 336.919189 -312.6008) (xy 336.873831 -312.568349) (xy 336.833682 -312.52964) (xy 336.799596 -312.485497)
			(xy 336.7723 -312.436862) (xy 336.752377 -312.384771) (xy 336.740251 -312.330334) (xy 336.73618 -312.274712)
			(xy 336.483706 -312.274712) (xy 336.483197 -312.302598) (xy 336.475077 -312.357774) (xy 336.459009 -312.411181)
			(xy 336.435337 -312.461678) (xy 336.404564 -312.508191) (xy 336.367347 -312.549728) (xy 336.324479 -312.585403)
			(xy 336.276873 -312.614457) (xy 336.225544 -312.636269) (xy 336.171587 -312.650375) (xy 336.11615 -312.656475)
			(xy 336.060416 -312.654438) (xy 336.005573 -312.644308) (xy 335.952789 -312.626301) (xy 335.903189 -312.6008)
			(xy 335.857831 -312.568349) (xy 335.817682 -312.52964) (xy 335.783596 -312.485497) (xy 335.7563 -312.436862)
			(xy 335.736377 -312.384771) (xy 335.724251 -312.330334) (xy 335.72018 -312.274712) (xy 335.467706 -312.274712)
			(xy 335.467197 -312.302598) (xy 335.459077 -312.357774) (xy 335.443009 -312.411181) (xy 335.419337 -312.461678)
			(xy 335.388564 -312.508191) (xy 335.351347 -312.549728) (xy 335.308479 -312.585403) (xy 335.260873 -312.614457)
			(xy 335.209544 -312.636269) (xy 335.155587 -312.650375) (xy 335.10015 -312.656475) (xy 335.044416 -312.654438)
			(xy 334.989573 -312.644308) (xy 334.936789 -312.626301) (xy 334.887189 -312.6008) (xy 334.841831 -312.568349)
			(xy 334.801682 -312.52964) (xy 334.767596 -312.485497) (xy 334.7403 -312.436862) (xy 334.720377 -312.384771)
			(xy 334.708251 -312.330334) (xy 334.70418 -312.274712) (xy 334.451706 -312.274712) (xy 334.451197 -312.302598)
			(xy 334.443077 -312.357774) (xy 334.427009 -312.411181) (xy 334.403337 -312.461678) (xy 334.372564 -312.508191)
			(xy 334.335347 -312.549728) (xy 334.292479 -312.585403) (xy 334.244873 -312.614457) (xy 334.193544 -312.636269)
			(xy 334.139587 -312.650375) (xy 334.08415 -312.656475) (xy 334.028416 -312.654438) (xy 333.973573 -312.644308)
			(xy 333.920789 -312.626301) (xy 333.871189 -312.6008) (xy 333.825831 -312.568349) (xy 333.785682 -312.52964)
			(xy 333.751596 -312.485497) (xy 333.7243 -312.436862) (xy 333.704377 -312.384771) (xy 333.692251 -312.330334)
			(xy 333.68818 -312.274712) (xy 333.435706 -312.274712) (xy 333.435197 -312.302598) (xy 333.427077 -312.357774)
			(xy 333.411009 -312.411181) (xy 333.387337 -312.461678) (xy 333.356564 -312.508191) (xy 333.319347 -312.549728)
			(xy 333.276479 -312.585403) (xy 333.228873 -312.614457) (xy 333.177544 -312.636269) (xy 333.123587 -312.650375)
			(xy 333.06815 -312.656475) (xy 333.012416 -312.654438) (xy 332.957573 -312.644308) (xy 332.904789 -312.626301)
			(xy 332.855189 -312.6008) (xy 332.809831 -312.568349) (xy 332.769682 -312.52964) (xy 332.735596 -312.485497)
			(xy 332.7083 -312.436862) (xy 332.688377 -312.384771) (xy 332.676251 -312.330334) (xy 332.67218 -312.274712)
			(xy 330.943966 -312.274712) (xy 330.943966 -313.290712) (xy 332.67218 -313.290712) (xy 332.676251 -313.23509)
			(xy 332.688377 -313.180653) (xy 332.7083 -313.128562) (xy 332.735596 -313.079927) (xy 332.769682 -313.035784)
			(xy 332.809831 -312.997075) (xy 332.855189 -312.964624) (xy 332.904789 -312.939123) (xy 332.957573 -312.921116)
			(xy 333.012416 -312.910986) (xy 333.06815 -312.908949) (xy 333.123587 -312.915049) (xy 333.177544 -312.929155)
			(xy 333.228873 -312.950967) (xy 333.276479 -312.980021) (xy 333.319347 -313.015696) (xy 333.356564 -313.057233)
			(xy 333.387337 -313.103746) (xy 333.411009 -313.154243) (xy 333.427077 -313.20765) (xy 333.435197 -313.262826)
			(xy 333.435706 -313.290712) (xy 333.68818 -313.290712) (xy 333.692251 -313.23509) (xy 333.704377 -313.180653)
			(xy 333.7243 -313.128562) (xy 333.751596 -313.079927) (xy 333.785682 -313.035784) (xy 333.825831 -312.997075)
			(xy 333.871189 -312.964624) (xy 333.920789 -312.939123) (xy 333.973573 -312.921116) (xy 334.028416 -312.910986)
			(xy 334.08415 -312.908949) (xy 334.139587 -312.915049) (xy 334.193544 -312.929155) (xy 334.244873 -312.950967)
			(xy 334.292479 -312.980021) (xy 334.335347 -313.015696) (xy 334.372564 -313.057233) (xy 334.403337 -313.103746)
			(xy 334.427009 -313.154243) (xy 334.443077 -313.20765) (xy 334.451197 -313.262826) (xy 334.451706 -313.290712)
			(xy 334.70418 -313.290712) (xy 334.708251 -313.23509) (xy 334.720377 -313.180653) (xy 334.7403 -313.128562)
			(xy 334.767596 -313.079927) (xy 334.801682 -313.035784) (xy 334.841831 -312.997075) (xy 334.887189 -312.964624)
			(xy 334.936789 -312.939123) (xy 334.989573 -312.921116) (xy 335.044416 -312.910986) (xy 335.10015 -312.908949)
			(xy 335.155587 -312.915049) (xy 335.209544 -312.929155) (xy 335.260873 -312.950967) (xy 335.308479 -312.980021)
			(xy 335.351347 -313.015696) (xy 335.388564 -313.057233) (xy 335.419337 -313.103746) (xy 335.443009 -313.154243)
			(xy 335.459077 -313.20765) (xy 335.467197 -313.262826) (xy 335.467706 -313.290712) (xy 335.72018 -313.290712)
			(xy 335.724251 -313.23509) (xy 335.736377 -313.180653) (xy 335.7563 -313.128562) (xy 335.783596 -313.079927)
			(xy 335.817682 -313.035784) (xy 335.857831 -312.997075) (xy 335.903189 -312.964624) (xy 335.952789 -312.939123)
			(xy 336.005573 -312.921116) (xy 336.060416 -312.910986) (xy 336.11615 -312.908949) (xy 336.171587 -312.915049)
			(xy 336.225544 -312.929155) (xy 336.276873 -312.950967) (xy 336.324479 -312.980021) (xy 336.367347 -313.015696)
			(xy 336.404564 -313.057233) (xy 336.435337 -313.103746) (xy 336.459009 -313.154243) (xy 336.475077 -313.20765)
			(xy 336.483197 -313.262826) (xy 336.483706 -313.290712) (xy 336.73618 -313.290712) (xy 336.740251 -313.23509)
			(xy 336.752377 -313.180653) (xy 336.7723 -313.128562) (xy 336.799596 -313.079927) (xy 336.833682 -313.035784)
			(xy 336.873831 -312.997075) (xy 336.919189 -312.964624) (xy 336.968789 -312.939123) (xy 337.021573 -312.921116)
			(xy 337.076416 -312.910986) (xy 337.13215 -312.908949) (xy 337.187587 -312.915049) (xy 337.241544 -312.929155)
			(xy 337.292873 -312.950967) (xy 337.340479 -312.980021) (xy 337.383347 -313.015696) (xy 337.420564 -313.057233)
			(xy 337.451337 -313.103746) (xy 337.475009 -313.154243) (xy 337.491077 -313.20765) (xy 337.499197 -313.262826)
			(xy 337.499706 -313.290712) (xy 337.75218 -313.290712) (xy 337.756251 -313.23509) (xy 337.768377 -313.180653)
			(xy 337.7883 -313.128562) (xy 337.815596 -313.079927) (xy 337.849682 -313.035784) (xy 337.889831 -312.997075)
			(xy 337.935189 -312.964624) (xy 337.984789 -312.939123) (xy 338.037573 -312.921116) (xy 338.092416 -312.910986)
			(xy 338.14815 -312.908949) (xy 338.203587 -312.915049) (xy 338.257544 -312.929155) (xy 338.308873 -312.950967)
			(xy 338.356479 -312.980021) (xy 338.399347 -313.015696) (xy 338.436564 -313.057233) (xy 338.467337 -313.103746)
			(xy 338.491009 -313.154243) (xy 338.507077 -313.20765) (xy 338.515197 -313.262826) (xy 338.515706 -313.290712)
			(xy 338.76818 -313.290712) (xy 338.772251 -313.23509) (xy 338.784377 -313.180653) (xy 338.8043 -313.128562)
			(xy 338.831596 -313.079927) (xy 338.865682 -313.035784) (xy 338.905831 -312.997075) (xy 338.951189 -312.964624)
			(xy 339.000789 -312.939123) (xy 339.053573 -312.921116) (xy 339.108416 -312.910986) (xy 339.16415 -312.908949)
			(xy 339.219587 -312.915049) (xy 339.273544 -312.929155) (xy 339.324873 -312.950967) (xy 339.372479 -312.980021)
			(xy 339.415347 -313.015696) (xy 339.452564 -313.057233) (xy 339.483337 -313.103746) (xy 339.507009 -313.154243)
			(xy 339.523077 -313.20765) (xy 339.531197 -313.262826) (xy 339.531706 -313.290712) (xy 339.78418 -313.290712)
			(xy 339.788251 -313.23509) (xy 339.800377 -313.180653) (xy 339.8203 -313.128562) (xy 339.847596 -313.079927)
			(xy 339.881682 -313.035784) (xy 339.921831 -312.997075) (xy 339.967189 -312.964624) (xy 340.016789 -312.939123)
			(xy 340.069573 -312.921116) (xy 340.124416 -312.910986) (xy 340.18015 -312.908949) (xy 340.235587 -312.915049)
			(xy 340.289544 -312.929155) (xy 340.340873 -312.950967) (xy 340.388479 -312.980021) (xy 340.431347 -313.015696)
			(xy 340.468564 -313.057233) (xy 340.499337 -313.103746) (xy 340.523009 -313.154243) (xy 340.539077 -313.20765)
			(xy 340.547197 -313.262826) (xy 340.547706 -313.290712) (xy 340.80018 -313.290712) (xy 340.804251 -313.23509)
			(xy 340.816377 -313.180653) (xy 340.8363 -313.128562) (xy 340.863596 -313.079927) (xy 340.897682 -313.035784)
			(xy 340.937831 -312.997075) (xy 340.983189 -312.964624) (xy 341.032789 -312.939123) (xy 341.085573 -312.921116)
			(xy 341.140416 -312.910986) (xy 341.19615 -312.908949) (xy 341.251587 -312.915049) (xy 341.305544 -312.929155)
			(xy 341.356873 -312.950967) (xy 341.404479 -312.980021) (xy 341.447347 -313.015696) (xy 341.484564 -313.057233)
			(xy 341.515337 -313.103746) (xy 341.539009 -313.154243) (xy 341.555077 -313.20765) (xy 341.563197 -313.262826)
			(xy 341.563706 -313.290712) (xy 341.81618 -313.290712) (xy 341.820251 -313.23509) (xy 341.832377 -313.180653)
			(xy 341.8523 -313.128562) (xy 341.879596 -313.079927) (xy 341.913682 -313.035784) (xy 341.953831 -312.997075)
			(xy 341.999189 -312.964624) (xy 342.048789 -312.939123) (xy 342.101573 -312.921116) (xy 342.156416 -312.910986)
			(xy 342.21215 -312.908949) (xy 342.267587 -312.915049) (xy 342.321544 -312.929155) (xy 342.372873 -312.950967)
			(xy 342.420479 -312.980021) (xy 342.463347 -313.015696) (xy 342.500564 -313.057233) (xy 342.531337 -313.103746)
			(xy 342.555009 -313.154243) (xy 342.571077 -313.20765) (xy 342.579197 -313.262826) (xy 342.579706 -313.290712)
			(xy 342.579197 -313.318598) (xy 342.571077 -313.373774) (xy 342.555009 -313.427181) (xy 342.531337 -313.477678)
			(xy 342.52631 -313.485276) (xy 357.436926 -313.485276) (xy 357.440997 -313.429654) (xy 357.453123 -313.375217)
			(xy 357.473046 -313.323126) (xy 357.500342 -313.274491) (xy 357.534428 -313.230348) (xy 357.574577 -313.191639)
			(xy 357.619935 -313.159188) (xy 357.669535 -313.133687) (xy 357.722319 -313.11568) (xy 357.777162 -313.10555)
			(xy 357.832896 -313.103513) (xy 357.888333 -313.109613) (xy 357.94229 -313.123719) (xy 357.993619 -313.145531)
			(xy 358.041225 -313.174585) (xy 358.084093 -313.21026) (xy 358.12131 -313.251797) (xy 358.152083 -313.29831)
			(xy 358.175755 -313.348807) (xy 358.191823 -313.402214) (xy 358.199943 -313.45739) (xy 358.200452 -313.485276)
			(xy 358.452926 -313.485276) (xy 358.456997 -313.429654) (xy 358.469123 -313.375217) (xy 358.489046 -313.323126)
			(xy 358.516342 -313.274491) (xy 358.550428 -313.230348) (xy 358.590577 -313.191639) (xy 358.635935 -313.159188)
			(xy 358.685535 -313.133687) (xy 358.738319 -313.11568) (xy 358.793162 -313.10555) (xy 358.848896 -313.103513)
			(xy 358.904333 -313.109613) (xy 358.95829 -313.123719) (xy 359.009619 -313.145531) (xy 359.057225 -313.174585)
			(xy 359.100093 -313.21026) (xy 359.13731 -313.251797) (xy 359.168083 -313.29831) (xy 359.191755 -313.348807)
			(xy 359.207823 -313.402214) (xy 359.215943 -313.45739) (xy 359.216452 -313.485276) (xy 359.468926 -313.485276)
			(xy 359.472997 -313.429654) (xy 359.485123 -313.375217) (xy 359.505046 -313.323126) (xy 359.532342 -313.274491)
			(xy 359.566428 -313.230348) (xy 359.606577 -313.191639) (xy 359.651935 -313.159188) (xy 359.701535 -313.133687)
			(xy 359.754319 -313.11568) (xy 359.809162 -313.10555) (xy 359.864896 -313.103513) (xy 359.920333 -313.109613)
			(xy 359.97429 -313.123719) (xy 360.025619 -313.145531) (xy 360.073225 -313.174585) (xy 360.116093 -313.21026)
			(xy 360.15331 -313.251797) (xy 360.184083 -313.29831) (xy 360.207755 -313.348807) (xy 360.223823 -313.402214)
			(xy 360.231943 -313.45739) (xy 360.232452 -313.485276) (xy 360.484926 -313.485276) (xy 360.488997 -313.429654)
			(xy 360.501123 -313.375217) (xy 360.521046 -313.323126) (xy 360.548342 -313.274491) (xy 360.582428 -313.230348)
			(xy 360.622577 -313.191639) (xy 360.667935 -313.159188) (xy 360.717535 -313.133687) (xy 360.770319 -313.11568)
			(xy 360.825162 -313.10555) (xy 360.880896 -313.103513) (xy 360.936333 -313.109613) (xy 360.99029 -313.123719)
			(xy 361.041619 -313.145531) (xy 361.089225 -313.174585) (xy 361.132093 -313.21026) (xy 361.16931 -313.251797)
			(xy 361.200083 -313.29831) (xy 361.223755 -313.348807) (xy 361.239823 -313.402214) (xy 361.247943 -313.45739)
			(xy 361.248452 -313.485276) (xy 361.500926 -313.485276) (xy 361.504997 -313.429654) (xy 361.517123 -313.375217)
			(xy 361.537046 -313.323126) (xy 361.564342 -313.274491) (xy 361.598428 -313.230348) (xy 361.638577 -313.191639)
			(xy 361.683935 -313.159188) (xy 361.733535 -313.133687) (xy 361.786319 -313.11568) (xy 361.841162 -313.10555)
			(xy 361.896896 -313.103513) (xy 361.952333 -313.109613) (xy 362.00629 -313.123719) (xy 362.057619 -313.145531)
			(xy 362.105225 -313.174585) (xy 362.148093 -313.21026) (xy 362.18531 -313.251797) (xy 362.216083 -313.29831)
			(xy 362.239755 -313.348807) (xy 362.255823 -313.402214) (xy 362.263943 -313.45739) (xy 362.264452 -313.485276)
			(xy 362.516926 -313.485276) (xy 362.520997 -313.429654) (xy 362.533123 -313.375217) (xy 362.553046 -313.323126)
			(xy 362.580342 -313.274491) (xy 362.614428 -313.230348) (xy 362.654577 -313.191639) (xy 362.699935 -313.159188)
			(xy 362.749535 -313.133687) (xy 362.802319 -313.11568) (xy 362.857162 -313.10555) (xy 362.912896 -313.103513)
			(xy 362.968333 -313.109613) (xy 363.02229 -313.123719) (xy 363.073619 -313.145531) (xy 363.121225 -313.174585)
			(xy 363.164093 -313.21026) (xy 363.20131 -313.251797) (xy 363.232083 -313.29831) (xy 363.255755 -313.348807)
			(xy 363.271823 -313.402214) (xy 363.279943 -313.45739) (xy 363.280452 -313.485276) (xy 363.532926 -313.485276)
			(xy 363.536997 -313.429654) (xy 363.549123 -313.375217) (xy 363.569046 -313.323126) (xy 363.596342 -313.274491)
			(xy 363.630428 -313.230348) (xy 363.670577 -313.191639) (xy 363.715935 -313.159188) (xy 363.765535 -313.133687)
			(xy 363.818319 -313.11568) (xy 363.873162 -313.10555) (xy 363.928896 -313.103513) (xy 363.984333 -313.109613)
			(xy 364.03829 -313.123719) (xy 364.089619 -313.145531) (xy 364.137225 -313.174585) (xy 364.180093 -313.21026)
			(xy 364.21731 -313.251797) (xy 364.248083 -313.29831) (xy 364.271755 -313.348807) (xy 364.287823 -313.402214)
			(xy 364.295943 -313.45739) (xy 364.296452 -313.485276) (xy 364.295943 -313.513162) (xy 364.287823 -313.568338)
			(xy 364.271755 -313.621745) (xy 364.248083 -313.672242) (xy 364.21731 -313.718755) (xy 364.180093 -313.760292)
			(xy 364.137225 -313.795967) (xy 364.089619 -313.825021) (xy 364.03829 -313.846833) (xy 363.984333 -313.860939)
			(xy 363.928896 -313.867039) (xy 363.873162 -313.865002) (xy 363.818319 -313.854872) (xy 363.765535 -313.836865)
			(xy 363.715935 -313.811364) (xy 363.670577 -313.778913) (xy 363.630428 -313.740204) (xy 363.596342 -313.696061)
			(xy 363.569046 -313.647426) (xy 363.549123 -313.595335) (xy 363.536997 -313.540898) (xy 363.532926 -313.485276)
			(xy 363.280452 -313.485276) (xy 363.279943 -313.513162) (xy 363.271823 -313.568338) (xy 363.255755 -313.621745)
			(xy 363.232083 -313.672242) (xy 363.20131 -313.718755) (xy 363.164093 -313.760292) (xy 363.121225 -313.795967)
			(xy 363.073619 -313.825021) (xy 363.02229 -313.846833) (xy 362.968333 -313.860939) (xy 362.912896 -313.867039)
			(xy 362.857162 -313.865002) (xy 362.802319 -313.854872) (xy 362.749535 -313.836865) (xy 362.699935 -313.811364)
			(xy 362.654577 -313.778913) (xy 362.614428 -313.740204) (xy 362.580342 -313.696061) (xy 362.553046 -313.647426)
			(xy 362.533123 -313.595335) (xy 362.520997 -313.540898) (xy 362.516926 -313.485276) (xy 362.264452 -313.485276)
			(xy 362.263943 -313.513162) (xy 362.255823 -313.568338) (xy 362.239755 -313.621745) (xy 362.216083 -313.672242)
			(xy 362.18531 -313.718755) (xy 362.148093 -313.760292) (xy 362.105225 -313.795967) (xy 362.057619 -313.825021)
			(xy 362.00629 -313.846833) (xy 361.952333 -313.860939) (xy 361.896896 -313.867039) (xy 361.841162 -313.865002)
			(xy 361.786319 -313.854872) (xy 361.733535 -313.836865) (xy 361.683935 -313.811364) (xy 361.638577 -313.778913)
			(xy 361.598428 -313.740204) (xy 361.564342 -313.696061) (xy 361.537046 -313.647426) (xy 361.517123 -313.595335)
			(xy 361.504997 -313.540898) (xy 361.500926 -313.485276) (xy 361.248452 -313.485276) (xy 361.247943 -313.513162)
			(xy 361.239823 -313.568338) (xy 361.223755 -313.621745) (xy 361.200083 -313.672242) (xy 361.16931 -313.718755)
			(xy 361.132093 -313.760292) (xy 361.089225 -313.795967) (xy 361.041619 -313.825021) (xy 360.99029 -313.846833)
			(xy 360.936333 -313.860939) (xy 360.880896 -313.867039) (xy 360.825162 -313.865002) (xy 360.770319 -313.854872)
			(xy 360.717535 -313.836865) (xy 360.667935 -313.811364) (xy 360.622577 -313.778913) (xy 360.582428 -313.740204)
			(xy 360.548342 -313.696061) (xy 360.521046 -313.647426) (xy 360.501123 -313.595335) (xy 360.488997 -313.540898)
			(xy 360.484926 -313.485276) (xy 360.232452 -313.485276) (xy 360.231943 -313.513162) (xy 360.223823 -313.568338)
			(xy 360.207755 -313.621745) (xy 360.184083 -313.672242) (xy 360.15331 -313.718755) (xy 360.116093 -313.760292)
			(xy 360.073225 -313.795967) (xy 360.025619 -313.825021) (xy 359.97429 -313.846833) (xy 359.920333 -313.860939)
			(xy 359.864896 -313.867039) (xy 359.809162 -313.865002) (xy 359.754319 -313.854872) (xy 359.701535 -313.836865)
			(xy 359.651935 -313.811364) (xy 359.606577 -313.778913) (xy 359.566428 -313.740204) (xy 359.532342 -313.696061)
			(xy 359.505046 -313.647426) (xy 359.485123 -313.595335) (xy 359.472997 -313.540898) (xy 359.468926 -313.485276)
			(xy 359.216452 -313.485276) (xy 359.215943 -313.513162) (xy 359.207823 -313.568338) (xy 359.191755 -313.621745)
			(xy 359.168083 -313.672242) (xy 359.13731 -313.718755) (xy 359.100093 -313.760292) (xy 359.057225 -313.795967)
			(xy 359.009619 -313.825021) (xy 358.95829 -313.846833) (xy 358.904333 -313.860939) (xy 358.848896 -313.867039)
			(xy 358.793162 -313.865002) (xy 358.738319 -313.854872) (xy 358.685535 -313.836865) (xy 358.635935 -313.811364)
			(xy 358.590577 -313.778913) (xy 358.550428 -313.740204) (xy 358.516342 -313.696061) (xy 358.489046 -313.647426)
			(xy 358.469123 -313.595335) (xy 358.456997 -313.540898) (xy 358.452926 -313.485276) (xy 358.200452 -313.485276)
			(xy 358.199943 -313.513162) (xy 358.191823 -313.568338) (xy 358.175755 -313.621745) (xy 358.152083 -313.672242)
			(xy 358.12131 -313.718755) (xy 358.084093 -313.760292) (xy 358.041225 -313.795967) (xy 357.993619 -313.825021)
			(xy 357.94229 -313.846833) (xy 357.888333 -313.860939) (xy 357.832896 -313.867039) (xy 357.777162 -313.865002)
			(xy 357.722319 -313.854872) (xy 357.669535 -313.836865) (xy 357.619935 -313.811364) (xy 357.574577 -313.778913)
			(xy 357.534428 -313.740204) (xy 357.500342 -313.696061) (xy 357.473046 -313.647426) (xy 357.453123 -313.595335)
			(xy 357.440997 -313.540898) (xy 357.436926 -313.485276) (xy 342.52631 -313.485276) (xy 342.500564 -313.524191)
			(xy 342.463347 -313.565728) (xy 342.420479 -313.601403) (xy 342.372873 -313.630457) (xy 342.321544 -313.652269)
			(xy 342.267587 -313.666375) (xy 342.21215 -313.672475) (xy 342.156416 -313.670438) (xy 342.101573 -313.660308)
			(xy 342.048789 -313.642301) (xy 341.999189 -313.6168) (xy 341.953831 -313.584349) (xy 341.913682 -313.54564)
			(xy 341.879596 -313.501497) (xy 341.8523 -313.452862) (xy 341.832377 -313.400771) (xy 341.820251 -313.346334)
			(xy 341.81618 -313.290712) (xy 341.563706 -313.290712) (xy 341.563197 -313.318598) (xy 341.555077 -313.373774)
			(xy 341.539009 -313.427181) (xy 341.515337 -313.477678) (xy 341.484564 -313.524191) (xy 341.447347 -313.565728)
			(xy 341.404479 -313.601403) (xy 341.356873 -313.630457) (xy 341.305544 -313.652269) (xy 341.251587 -313.666375)
			(xy 341.19615 -313.672475) (xy 341.140416 -313.670438) (xy 341.085573 -313.660308) (xy 341.032789 -313.642301)
			(xy 340.983189 -313.6168) (xy 340.937831 -313.584349) (xy 340.897682 -313.54564) (xy 340.863596 -313.501497)
			(xy 340.8363 -313.452862) (xy 340.816377 -313.400771) (xy 340.804251 -313.346334) (xy 340.80018 -313.290712)
			(xy 340.547706 -313.290712) (xy 340.547197 -313.318598) (xy 340.539077 -313.373774) (xy 340.523009 -313.427181)
			(xy 340.499337 -313.477678) (xy 340.468564 -313.524191) (xy 340.431347 -313.565728) (xy 340.388479 -313.601403)
			(xy 340.340873 -313.630457) (xy 340.289544 -313.652269) (xy 340.235587 -313.666375) (xy 340.18015 -313.672475)
			(xy 340.124416 -313.670438) (xy 340.069573 -313.660308) (xy 340.016789 -313.642301) (xy 339.967189 -313.6168)
			(xy 339.921831 -313.584349) (xy 339.881682 -313.54564) (xy 339.847596 -313.501497) (xy 339.8203 -313.452862)
			(xy 339.800377 -313.400771) (xy 339.788251 -313.346334) (xy 339.78418 -313.290712) (xy 339.531706 -313.290712)
			(xy 339.531197 -313.318598) (xy 339.523077 -313.373774) (xy 339.507009 -313.427181) (xy 339.483337 -313.477678)
			(xy 339.452564 -313.524191) (xy 339.415347 -313.565728) (xy 339.372479 -313.601403) (xy 339.324873 -313.630457)
			(xy 339.273544 -313.652269) (xy 339.219587 -313.666375) (xy 339.16415 -313.672475) (xy 339.108416 -313.670438)
			(xy 339.053573 -313.660308) (xy 339.000789 -313.642301) (xy 338.951189 -313.6168) (xy 338.905831 -313.584349)
			(xy 338.865682 -313.54564) (xy 338.831596 -313.501497) (xy 338.8043 -313.452862) (xy 338.784377 -313.400771)
			(xy 338.772251 -313.346334) (xy 338.76818 -313.290712) (xy 338.515706 -313.290712) (xy 338.515197 -313.318598)
			(xy 338.507077 -313.373774) (xy 338.491009 -313.427181) (xy 338.467337 -313.477678) (xy 338.436564 -313.524191)
			(xy 338.399347 -313.565728) (xy 338.356479 -313.601403) (xy 338.308873 -313.630457) (xy 338.257544 -313.652269)
			(xy 338.203587 -313.666375) (xy 338.14815 -313.672475) (xy 338.092416 -313.670438) (xy 338.037573 -313.660308)
			(xy 337.984789 -313.642301) (xy 337.935189 -313.6168) (xy 337.889831 -313.584349) (xy 337.849682 -313.54564)
			(xy 337.815596 -313.501497) (xy 337.7883 -313.452862) (xy 337.768377 -313.400771) (xy 337.756251 -313.346334)
			(xy 337.75218 -313.290712) (xy 337.499706 -313.290712) (xy 337.499197 -313.318598) (xy 337.491077 -313.373774)
			(xy 337.475009 -313.427181) (xy 337.451337 -313.477678) (xy 337.420564 -313.524191) (xy 337.383347 -313.565728)
			(xy 337.340479 -313.601403) (xy 337.292873 -313.630457) (xy 337.241544 -313.652269) (xy 337.187587 -313.666375)
			(xy 337.13215 -313.672475) (xy 337.076416 -313.670438) (xy 337.021573 -313.660308) (xy 336.968789 -313.642301)
			(xy 336.919189 -313.6168) (xy 336.873831 -313.584349) (xy 336.833682 -313.54564) (xy 336.799596 -313.501497)
			(xy 336.7723 -313.452862) (xy 336.752377 -313.400771) (xy 336.740251 -313.346334) (xy 336.73618 -313.290712)
			(xy 336.483706 -313.290712) (xy 336.483197 -313.318598) (xy 336.475077 -313.373774) (xy 336.459009 -313.427181)
			(xy 336.435337 -313.477678) (xy 336.404564 -313.524191) (xy 336.367347 -313.565728) (xy 336.324479 -313.601403)
			(xy 336.276873 -313.630457) (xy 336.225544 -313.652269) (xy 336.171587 -313.666375) (xy 336.11615 -313.672475)
			(xy 336.060416 -313.670438) (xy 336.005573 -313.660308) (xy 335.952789 -313.642301) (xy 335.903189 -313.6168)
			(xy 335.857831 -313.584349) (xy 335.817682 -313.54564) (xy 335.783596 -313.501497) (xy 335.7563 -313.452862)
			(xy 335.736377 -313.400771) (xy 335.724251 -313.346334) (xy 335.72018 -313.290712) (xy 335.467706 -313.290712)
			(xy 335.467197 -313.318598) (xy 335.459077 -313.373774) (xy 335.443009 -313.427181) (xy 335.419337 -313.477678)
			(xy 335.388564 -313.524191) (xy 335.351347 -313.565728) (xy 335.308479 -313.601403) (xy 335.260873 -313.630457)
			(xy 335.209544 -313.652269) (xy 335.155587 -313.666375) (xy 335.10015 -313.672475) (xy 335.044416 -313.670438)
			(xy 334.989573 -313.660308) (xy 334.936789 -313.642301) (xy 334.887189 -313.6168) (xy 334.841831 -313.584349)
			(xy 334.801682 -313.54564) (xy 334.767596 -313.501497) (xy 334.7403 -313.452862) (xy 334.720377 -313.400771)
			(xy 334.708251 -313.346334) (xy 334.70418 -313.290712) (xy 334.451706 -313.290712) (xy 334.451197 -313.318598)
			(xy 334.443077 -313.373774) (xy 334.427009 -313.427181) (xy 334.403337 -313.477678) (xy 334.372564 -313.524191)
			(xy 334.335347 -313.565728) (xy 334.292479 -313.601403) (xy 334.244873 -313.630457) (xy 334.193544 -313.652269)
			(xy 334.139587 -313.666375) (xy 334.08415 -313.672475) (xy 334.028416 -313.670438) (xy 333.973573 -313.660308)
			(xy 333.920789 -313.642301) (xy 333.871189 -313.6168) (xy 333.825831 -313.584349) (xy 333.785682 -313.54564)
			(xy 333.751596 -313.501497) (xy 333.7243 -313.452862) (xy 333.704377 -313.400771) (xy 333.692251 -313.346334)
			(xy 333.68818 -313.290712) (xy 333.435706 -313.290712) (xy 333.435197 -313.318598) (xy 333.427077 -313.373774)
			(xy 333.411009 -313.427181) (xy 333.387337 -313.477678) (xy 333.356564 -313.524191) (xy 333.319347 -313.565728)
			(xy 333.276479 -313.601403) (xy 333.228873 -313.630457) (xy 333.177544 -313.652269) (xy 333.123587 -313.666375)
			(xy 333.06815 -313.672475) (xy 333.012416 -313.670438) (xy 332.957573 -313.660308) (xy 332.904789 -313.642301)
			(xy 332.855189 -313.6168) (xy 332.809831 -313.584349) (xy 332.769682 -313.54564) (xy 332.735596 -313.501497)
			(xy 332.7083 -313.452862) (xy 332.688377 -313.400771) (xy 332.676251 -313.346334) (xy 332.67218 -313.290712)
			(xy 330.943966 -313.290712) (xy 330.943966 -314.168282) (xy 330.944406 -314.178344) (xy 330.952149 -314.196921)
			(xy 330.958952 -314.20435) (xy 331.061262 -314.306712) (xy 333.68818 -314.306712) (xy 333.692251 -314.25109)
			(xy 333.704377 -314.196653) (xy 333.7243 -314.144562) (xy 333.751596 -314.095927) (xy 333.785682 -314.051784)
			(xy 333.825831 -314.013075) (xy 333.871189 -313.980624) (xy 333.920789 -313.955123) (xy 333.973573 -313.937116)
			(xy 334.028416 -313.926986) (xy 334.08415 -313.924949) (xy 334.139587 -313.931049) (xy 334.193544 -313.945155)
			(xy 334.244873 -313.966967) (xy 334.292479 -313.996021) (xy 334.335347 -314.031696) (xy 334.372564 -314.073233)
			(xy 334.403337 -314.119746) (xy 334.427009 -314.170243) (xy 334.443077 -314.22365) (xy 334.451197 -314.278826)
			(xy 334.451706 -314.306712) (xy 334.70418 -314.306712) (xy 334.708251 -314.25109) (xy 334.720377 -314.196653)
			(xy 334.7403 -314.144562) (xy 334.767596 -314.095927) (xy 334.801682 -314.051784) (xy 334.841831 -314.013075)
			(xy 334.887189 -313.980624) (xy 334.936789 -313.955123) (xy 334.989573 -313.937116) (xy 335.044416 -313.926986)
			(xy 335.10015 -313.924949) (xy 335.155587 -313.931049) (xy 335.209544 -313.945155) (xy 335.260873 -313.966967)
			(xy 335.308479 -313.996021) (xy 335.351347 -314.031696) (xy 335.388564 -314.073233) (xy 335.419337 -314.119746)
			(xy 335.443009 -314.170243) (xy 335.459077 -314.22365) (xy 335.467197 -314.278826) (xy 335.467706 -314.306712)
			(xy 335.72018 -314.306712) (xy 335.724251 -314.25109) (xy 335.736377 -314.196653) (xy 335.7563 -314.144562)
			(xy 335.783596 -314.095927) (xy 335.817682 -314.051784) (xy 335.857831 -314.013075) (xy 335.903189 -313.980624)
			(xy 335.952789 -313.955123) (xy 336.005573 -313.937116) (xy 336.060416 -313.926986) (xy 336.11615 -313.924949)
			(xy 336.171587 -313.931049) (xy 336.225544 -313.945155) (xy 336.276873 -313.966967) (xy 336.324479 -313.996021)
			(xy 336.367347 -314.031696) (xy 336.404564 -314.073233) (xy 336.435337 -314.119746) (xy 336.459009 -314.170243)
			(xy 336.475077 -314.22365) (xy 336.483197 -314.278826) (xy 336.483706 -314.306712) (xy 336.73618 -314.306712)
			(xy 336.740251 -314.25109) (xy 336.752377 -314.196653) (xy 336.7723 -314.144562) (xy 336.799596 -314.095927)
			(xy 336.833682 -314.051784) (xy 336.873831 -314.013075) (xy 336.919189 -313.980624) (xy 336.968789 -313.955123)
			(xy 337.021573 -313.937116) (xy 337.076416 -313.926986) (xy 337.13215 -313.924949) (xy 337.187587 -313.931049)
			(xy 337.241544 -313.945155) (xy 337.292873 -313.966967) (xy 337.340479 -313.996021) (xy 337.383347 -314.031696)
			(xy 337.420564 -314.073233) (xy 337.451337 -314.119746) (xy 337.475009 -314.170243) (xy 337.491077 -314.22365)
			(xy 337.499197 -314.278826) (xy 337.499706 -314.306712) (xy 337.75218 -314.306712) (xy 337.756251 -314.25109)
			(xy 337.768377 -314.196653) (xy 337.7883 -314.144562) (xy 337.815596 -314.095927) (xy 337.849682 -314.051784)
			(xy 337.889831 -314.013075) (xy 337.935189 -313.980624) (xy 337.984789 -313.955123) (xy 338.037573 -313.937116)
			(xy 338.092416 -313.926986) (xy 338.14815 -313.924949) (xy 338.203587 -313.931049) (xy 338.257544 -313.945155)
			(xy 338.308873 -313.966967) (xy 338.356479 -313.996021) (xy 338.399347 -314.031696) (xy 338.436564 -314.073233)
			(xy 338.467337 -314.119746) (xy 338.491009 -314.170243) (xy 338.507077 -314.22365) (xy 338.515197 -314.278826)
			(xy 338.515706 -314.306712) (xy 338.76818 -314.306712) (xy 338.772251 -314.25109) (xy 338.784377 -314.196653)
			(xy 338.8043 -314.144562) (xy 338.831596 -314.095927) (xy 338.865682 -314.051784) (xy 338.905831 -314.013075)
			(xy 338.951189 -313.980624) (xy 339.000789 -313.955123) (xy 339.053573 -313.937116) (xy 339.108416 -313.926986)
			(xy 339.16415 -313.924949) (xy 339.219587 -313.931049) (xy 339.273544 -313.945155) (xy 339.324873 -313.966967)
			(xy 339.372479 -313.996021) (xy 339.415347 -314.031696) (xy 339.452564 -314.073233) (xy 339.483337 -314.119746)
			(xy 339.507009 -314.170243) (xy 339.523077 -314.22365) (xy 339.531197 -314.278826) (xy 339.531706 -314.306712)
			(xy 339.78418 -314.306712) (xy 339.788251 -314.25109) (xy 339.800377 -314.196653) (xy 339.8203 -314.144562)
			(xy 339.847596 -314.095927) (xy 339.881682 -314.051784) (xy 339.921831 -314.013075) (xy 339.967189 -313.980624)
			(xy 340.016789 -313.955123) (xy 340.069573 -313.937116) (xy 340.124416 -313.926986) (xy 340.18015 -313.924949)
			(xy 340.235587 -313.931049) (xy 340.289544 -313.945155) (xy 340.340873 -313.966967) (xy 340.388479 -313.996021)
			(xy 340.431347 -314.031696) (xy 340.468564 -314.073233) (xy 340.499337 -314.119746) (xy 340.523009 -314.170243)
			(xy 340.539077 -314.22365) (xy 340.547197 -314.278826) (xy 340.547706 -314.306712) (xy 340.80018 -314.306712)
			(xy 340.804251 -314.25109) (xy 340.816377 -314.196653) (xy 340.8363 -314.144562) (xy 340.863596 -314.095927)
			(xy 340.897682 -314.051784) (xy 340.937831 -314.013075) (xy 340.983189 -313.980624) (xy 341.032789 -313.955123)
			(xy 341.085573 -313.937116) (xy 341.140416 -313.926986) (xy 341.19615 -313.924949) (xy 341.251587 -313.931049)
			(xy 341.305544 -313.945155) (xy 341.356873 -313.966967) (xy 341.404479 -313.996021) (xy 341.447347 -314.031696)
			(xy 341.484564 -314.073233) (xy 341.515337 -314.119746) (xy 341.539009 -314.170243) (xy 341.555077 -314.22365)
			(xy 341.563197 -314.278826) (xy 341.563706 -314.306712) (xy 341.81618 -314.306712) (xy 341.820251 -314.25109)
			(xy 341.832377 -314.196653) (xy 341.8523 -314.144562) (xy 341.879596 -314.095927) (xy 341.913682 -314.051784)
			(xy 341.953831 -314.013075) (xy 341.999189 -313.980624) (xy 342.048789 -313.955123) (xy 342.101573 -313.937116)
			(xy 342.156416 -313.926986) (xy 342.21215 -313.924949) (xy 342.267587 -313.931049) (xy 342.321544 -313.945155)
			(xy 342.372873 -313.966967) (xy 342.420479 -313.996021) (xy 342.463347 -314.031696) (xy 342.500564 -314.073233)
			(xy 342.531337 -314.119746) (xy 342.555009 -314.170243) (xy 342.571077 -314.22365) (xy 342.579197 -314.278826)
			(xy 342.579706 -314.306712) (xy 342.579197 -314.334598) (xy 342.571077 -314.389774) (xy 342.555009 -314.443181)
			(xy 342.531337 -314.493678) (xy 342.52631 -314.501276) (xy 357.436926 -314.501276) (xy 357.440997 -314.445654)
			(xy 357.453123 -314.391217) (xy 357.473046 -314.339126) (xy 357.500342 -314.290491) (xy 357.534428 -314.246348)
			(xy 357.574577 -314.207639) (xy 357.619935 -314.175188) (xy 357.669535 -314.149687) (xy 357.722319 -314.13168)
			(xy 357.777162 -314.12155) (xy 357.832896 -314.119513) (xy 357.888333 -314.125613) (xy 357.94229 -314.139719)
			(xy 357.993619 -314.161531) (xy 358.041225 -314.190585) (xy 358.084093 -314.22626) (xy 358.12131 -314.267797)
			(xy 358.152083 -314.31431) (xy 358.175755 -314.364807) (xy 358.191823 -314.418214) (xy 358.199943 -314.47339)
			(xy 358.200452 -314.501276) (xy 358.452926 -314.501276) (xy 358.456997 -314.445654) (xy 358.469123 -314.391217)
			(xy 358.489046 -314.339126) (xy 358.516342 -314.290491) (xy 358.550428 -314.246348) (xy 358.590577 -314.207639)
			(xy 358.635935 -314.175188) (xy 358.685535 -314.149687) (xy 358.738319 -314.13168) (xy 358.793162 -314.12155)
			(xy 358.848896 -314.119513) (xy 358.904333 -314.125613) (xy 358.95829 -314.139719) (xy 359.009619 -314.161531)
			(xy 359.057225 -314.190585) (xy 359.100093 -314.22626) (xy 359.13731 -314.267797) (xy 359.168083 -314.31431)
			(xy 359.191755 -314.364807) (xy 359.207823 -314.418214) (xy 359.215943 -314.47339) (xy 359.216452 -314.501276)
			(xy 359.468926 -314.501276) (xy 359.472997 -314.445654) (xy 359.485123 -314.391217) (xy 359.505046 -314.339126)
			(xy 359.532342 -314.290491) (xy 359.566428 -314.246348) (xy 359.606577 -314.207639) (xy 359.651935 -314.175188)
			(xy 359.701535 -314.149687) (xy 359.754319 -314.13168) (xy 359.809162 -314.12155) (xy 359.864896 -314.119513)
			(xy 359.920333 -314.125613) (xy 359.97429 -314.139719) (xy 360.025619 -314.161531) (xy 360.073225 -314.190585)
			(xy 360.116093 -314.22626) (xy 360.15331 -314.267797) (xy 360.184083 -314.31431) (xy 360.207755 -314.364807)
			(xy 360.223823 -314.418214) (xy 360.231943 -314.47339) (xy 360.232452 -314.501276) (xy 360.484926 -314.501276)
			(xy 360.488997 -314.445654) (xy 360.501123 -314.391217) (xy 360.521046 -314.339126) (xy 360.548342 -314.290491)
			(xy 360.582428 -314.246348) (xy 360.622577 -314.207639) (xy 360.667935 -314.175188) (xy 360.717535 -314.149687)
			(xy 360.770319 -314.13168) (xy 360.825162 -314.12155) (xy 360.880896 -314.119513) (xy 360.936333 -314.125613)
			(xy 360.99029 -314.139719) (xy 361.041619 -314.161531) (xy 361.089225 -314.190585) (xy 361.132093 -314.22626)
			(xy 361.16931 -314.267797) (xy 361.200083 -314.31431) (xy 361.223755 -314.364807) (xy 361.239823 -314.418214)
			(xy 361.247943 -314.47339) (xy 361.248452 -314.501276) (xy 361.500926 -314.501276) (xy 361.504997 -314.445654)
			(xy 361.517123 -314.391217) (xy 361.537046 -314.339126) (xy 361.564342 -314.290491) (xy 361.598428 -314.246348)
			(xy 361.638577 -314.207639) (xy 361.683935 -314.175188) (xy 361.733535 -314.149687) (xy 361.786319 -314.13168)
			(xy 361.841162 -314.12155) (xy 361.896896 -314.119513) (xy 361.952333 -314.125613) (xy 362.00629 -314.139719)
			(xy 362.057619 -314.161531) (xy 362.105225 -314.190585) (xy 362.148093 -314.22626) (xy 362.18531 -314.267797)
			(xy 362.216083 -314.31431) (xy 362.239755 -314.364807) (xy 362.255823 -314.418214) (xy 362.263943 -314.47339)
			(xy 362.264452 -314.501276) (xy 362.516926 -314.501276) (xy 362.520997 -314.445654) (xy 362.533123 -314.391217)
			(xy 362.553046 -314.339126) (xy 362.580342 -314.290491) (xy 362.614428 -314.246348) (xy 362.654577 -314.207639)
			(xy 362.699935 -314.175188) (xy 362.749535 -314.149687) (xy 362.802319 -314.13168) (xy 362.857162 -314.12155)
			(xy 362.912896 -314.119513) (xy 362.968333 -314.125613) (xy 363.02229 -314.139719) (xy 363.073619 -314.161531)
			(xy 363.121225 -314.190585) (xy 363.164093 -314.22626) (xy 363.20131 -314.267797) (xy 363.232083 -314.31431)
			(xy 363.255755 -314.364807) (xy 363.271823 -314.418214) (xy 363.279943 -314.47339) (xy 363.280452 -314.501276)
			(xy 363.279943 -314.529162) (xy 363.271823 -314.584338) (xy 363.255755 -314.637745) (xy 363.232083 -314.688242)
			(xy 363.20131 -314.734755) (xy 363.164093 -314.776292) (xy 363.121225 -314.811967) (xy 363.073619 -314.841021)
			(xy 363.02229 -314.862833) (xy 362.968333 -314.876939) (xy 362.912896 -314.883039) (xy 362.857162 -314.881002)
			(xy 362.802319 -314.870872) (xy 362.749535 -314.852865) (xy 362.699935 -314.827364) (xy 362.654577 -314.794913)
			(xy 362.614428 -314.756204) (xy 362.580342 -314.712061) (xy 362.553046 -314.663426) (xy 362.533123 -314.611335)
			(xy 362.520997 -314.556898) (xy 362.516926 -314.501276) (xy 362.264452 -314.501276) (xy 362.263943 -314.529162)
			(xy 362.255823 -314.584338) (xy 362.239755 -314.637745) (xy 362.216083 -314.688242) (xy 362.18531 -314.734755)
			(xy 362.148093 -314.776292) (xy 362.105225 -314.811967) (xy 362.057619 -314.841021) (xy 362.00629 -314.862833)
			(xy 361.952333 -314.876939) (xy 361.896896 -314.883039) (xy 361.841162 -314.881002) (xy 361.786319 -314.870872)
			(xy 361.733535 -314.852865) (xy 361.683935 -314.827364) (xy 361.638577 -314.794913) (xy 361.598428 -314.756204)
			(xy 361.564342 -314.712061) (xy 361.537046 -314.663426) (xy 361.517123 -314.611335) (xy 361.504997 -314.556898)
			(xy 361.500926 -314.501276) (xy 361.248452 -314.501276) (xy 361.247943 -314.529162) (xy 361.239823 -314.584338)
			(xy 361.223755 -314.637745) (xy 361.200083 -314.688242) (xy 361.16931 -314.734755) (xy 361.132093 -314.776292)
			(xy 361.089225 -314.811967) (xy 361.041619 -314.841021) (xy 360.99029 -314.862833) (xy 360.936333 -314.876939)
			(xy 360.880896 -314.883039) (xy 360.825162 -314.881002) (xy 360.770319 -314.870872) (xy 360.717535 -314.852865)
			(xy 360.667935 -314.827364) (xy 360.622577 -314.794913) (xy 360.582428 -314.756204) (xy 360.548342 -314.712061)
			(xy 360.521046 -314.663426) (xy 360.501123 -314.611335) (xy 360.488997 -314.556898) (xy 360.484926 -314.501276)
			(xy 360.232452 -314.501276) (xy 360.231943 -314.529162) (xy 360.223823 -314.584338) (xy 360.207755 -314.637745)
			(xy 360.184083 -314.688242) (xy 360.15331 -314.734755) (xy 360.116093 -314.776292) (xy 360.073225 -314.811967)
			(xy 360.025619 -314.841021) (xy 359.97429 -314.862833) (xy 359.920333 -314.876939) (xy 359.864896 -314.883039)
			(xy 359.809162 -314.881002) (xy 359.754319 -314.870872) (xy 359.701535 -314.852865) (xy 359.651935 -314.827364)
			(xy 359.606577 -314.794913) (xy 359.566428 -314.756204) (xy 359.532342 -314.712061) (xy 359.505046 -314.663426)
			(xy 359.485123 -314.611335) (xy 359.472997 -314.556898) (xy 359.468926 -314.501276) (xy 359.216452 -314.501276)
			(xy 359.215943 -314.529162) (xy 359.207823 -314.584338) (xy 359.191755 -314.637745) (xy 359.168083 -314.688242)
			(xy 359.13731 -314.734755) (xy 359.100093 -314.776292) (xy 359.057225 -314.811967) (xy 359.009619 -314.841021)
			(xy 358.95829 -314.862833) (xy 358.904333 -314.876939) (xy 358.848896 -314.883039) (xy 358.793162 -314.881002)
			(xy 358.738319 -314.870872) (xy 358.685535 -314.852865) (xy 358.635935 -314.827364) (xy 358.590577 -314.794913)
			(xy 358.550428 -314.756204) (xy 358.516342 -314.712061) (xy 358.489046 -314.663426) (xy 358.469123 -314.611335)
			(xy 358.456997 -314.556898) (xy 358.452926 -314.501276) (xy 358.200452 -314.501276) (xy 358.199943 -314.529162)
			(xy 358.191823 -314.584338) (xy 358.175755 -314.637745) (xy 358.152083 -314.688242) (xy 358.12131 -314.734755)
			(xy 358.084093 -314.776292) (xy 358.041225 -314.811967) (xy 357.993619 -314.841021) (xy 357.94229 -314.862833)
			(xy 357.888333 -314.876939) (xy 357.832896 -314.883039) (xy 357.777162 -314.881002) (xy 357.722319 -314.870872)
			(xy 357.669535 -314.852865) (xy 357.619935 -314.827364) (xy 357.574577 -314.794913) (xy 357.534428 -314.756204)
			(xy 357.500342 -314.712061) (xy 357.473046 -314.663426) (xy 357.453123 -314.611335) (xy 357.440997 -314.556898)
			(xy 357.436926 -314.501276) (xy 342.52631 -314.501276) (xy 342.500564 -314.540191) (xy 342.463347 -314.581728)
			(xy 342.420479 -314.617403) (xy 342.372873 -314.646457) (xy 342.321544 -314.668269) (xy 342.267587 -314.682375)
			(xy 342.21215 -314.688475) (xy 342.156416 -314.686438) (xy 342.101573 -314.676308) (xy 342.048789 -314.658301)
			(xy 341.999189 -314.6328) (xy 341.953831 -314.600349) (xy 341.913682 -314.56164) (xy 341.879596 -314.517497)
			(xy 341.8523 -314.468862) (xy 341.832377 -314.416771) (xy 341.820251 -314.362334) (xy 341.81618 -314.306712)
			(xy 341.563706 -314.306712) (xy 341.563197 -314.334598) (xy 341.555077 -314.389774) (xy 341.539009 -314.443181)
			(xy 341.515337 -314.493678) (xy 341.484564 -314.540191) (xy 341.447347 -314.581728) (xy 341.404479 -314.617403)
			(xy 341.356873 -314.646457) (xy 341.305544 -314.668269) (xy 341.251587 -314.682375) (xy 341.19615 -314.688475)
			(xy 341.140416 -314.686438) (xy 341.085573 -314.676308) (xy 341.032789 -314.658301) (xy 340.983189 -314.6328)
			(xy 340.937831 -314.600349) (xy 340.897682 -314.56164) (xy 340.863596 -314.517497) (xy 340.8363 -314.468862)
			(xy 340.816377 -314.416771) (xy 340.804251 -314.362334) (xy 340.80018 -314.306712) (xy 340.547706 -314.306712)
			(xy 340.547197 -314.334598) (xy 340.539077 -314.389774) (xy 340.523009 -314.443181) (xy 340.499337 -314.493678)
			(xy 340.468564 -314.540191) (xy 340.431347 -314.581728) (xy 340.388479 -314.617403) (xy 340.340873 -314.646457)
			(xy 340.289544 -314.668269) (xy 340.235587 -314.682375) (xy 340.18015 -314.688475) (xy 340.124416 -314.686438)
			(xy 340.069573 -314.676308) (xy 340.016789 -314.658301) (xy 339.967189 -314.6328) (xy 339.921831 -314.600349)
			(xy 339.881682 -314.56164) (xy 339.847596 -314.517497) (xy 339.8203 -314.468862) (xy 339.800377 -314.416771)
			(xy 339.788251 -314.362334) (xy 339.78418 -314.306712) (xy 339.531706 -314.306712) (xy 339.531197 -314.334598)
			(xy 339.523077 -314.389774) (xy 339.507009 -314.443181) (xy 339.483337 -314.493678) (xy 339.452564 -314.540191)
			(xy 339.415347 -314.581728) (xy 339.372479 -314.617403) (xy 339.324873 -314.646457) (xy 339.273544 -314.668269)
			(xy 339.219587 -314.682375) (xy 339.16415 -314.688475) (xy 339.108416 -314.686438) (xy 339.053573 -314.676308)
			(xy 339.000789 -314.658301) (xy 338.951189 -314.6328) (xy 338.905831 -314.600349) (xy 338.865682 -314.56164)
			(xy 338.831596 -314.517497) (xy 338.8043 -314.468862) (xy 338.784377 -314.416771) (xy 338.772251 -314.362334)
			(xy 338.76818 -314.306712) (xy 338.515706 -314.306712) (xy 338.515197 -314.334598) (xy 338.507077 -314.389774)
			(xy 338.491009 -314.443181) (xy 338.467337 -314.493678) (xy 338.436564 -314.540191) (xy 338.399347 -314.581728)
			(xy 338.356479 -314.617403) (xy 338.308873 -314.646457) (xy 338.257544 -314.668269) (xy 338.203587 -314.682375)
			(xy 338.14815 -314.688475) (xy 338.092416 -314.686438) (xy 338.037573 -314.676308) (xy 337.984789 -314.658301)
			(xy 337.935189 -314.6328) (xy 337.889831 -314.600349) (xy 337.849682 -314.56164) (xy 337.815596 -314.517497)
			(xy 337.7883 -314.468862) (xy 337.768377 -314.416771) (xy 337.756251 -314.362334) (xy 337.75218 -314.306712)
			(xy 337.499706 -314.306712) (xy 337.499197 -314.334598) (xy 337.491077 -314.389774) (xy 337.475009 -314.443181)
			(xy 337.451337 -314.493678) (xy 337.420564 -314.540191) (xy 337.383347 -314.581728) (xy 337.340479 -314.617403)
			(xy 337.292873 -314.646457) (xy 337.241544 -314.668269) (xy 337.187587 -314.682375) (xy 337.13215 -314.688475)
			(xy 337.076416 -314.686438) (xy 337.021573 -314.676308) (xy 336.968789 -314.658301) (xy 336.919189 -314.6328)
			(xy 336.873831 -314.600349) (xy 336.833682 -314.56164) (xy 336.799596 -314.517497) (xy 336.7723 -314.468862)
			(xy 336.752377 -314.416771) (xy 336.740251 -314.362334) (xy 336.73618 -314.306712) (xy 336.483706 -314.306712)
			(xy 336.483197 -314.334598) (xy 336.475077 -314.389774) (xy 336.459009 -314.443181) (xy 336.435337 -314.493678)
			(xy 336.404564 -314.540191) (xy 336.367347 -314.581728) (xy 336.324479 -314.617403) (xy 336.276873 -314.646457)
			(xy 336.225544 -314.668269) (xy 336.171587 -314.682375) (xy 336.11615 -314.688475) (xy 336.060416 -314.686438)
			(xy 336.005573 -314.676308) (xy 335.952789 -314.658301) (xy 335.903189 -314.6328) (xy 335.857831 -314.600349)
			(xy 335.817682 -314.56164) (xy 335.783596 -314.517497) (xy 335.7563 -314.468862) (xy 335.736377 -314.416771)
			(xy 335.724251 -314.362334) (xy 335.72018 -314.306712) (xy 335.467706 -314.306712) (xy 335.467197 -314.334598)
			(xy 335.459077 -314.389774) (xy 335.443009 -314.443181) (xy 335.419337 -314.493678) (xy 335.388564 -314.540191)
			(xy 335.351347 -314.581728) (xy 335.308479 -314.617403) (xy 335.260873 -314.646457) (xy 335.209544 -314.668269)
			(xy 335.155587 -314.682375) (xy 335.10015 -314.688475) (xy 335.044416 -314.686438) (xy 334.989573 -314.676308)
			(xy 334.936789 -314.658301) (xy 334.887189 -314.6328) (xy 334.841831 -314.600349) (xy 334.801682 -314.56164)
			(xy 334.767596 -314.517497) (xy 334.7403 -314.468862) (xy 334.720377 -314.416771) (xy 334.708251 -314.362334)
			(xy 334.70418 -314.306712) (xy 334.451706 -314.306712) (xy 334.451197 -314.334598) (xy 334.443077 -314.389774)
			(xy 334.427009 -314.443181) (xy 334.403337 -314.493678) (xy 334.372564 -314.540191) (xy 334.335347 -314.581728)
			(xy 334.292479 -314.617403) (xy 334.244873 -314.646457) (xy 334.193544 -314.668269) (xy 334.139587 -314.682375)
			(xy 334.08415 -314.688475) (xy 334.028416 -314.686438) (xy 333.973573 -314.676308) (xy 333.920789 -314.658301)
			(xy 333.871189 -314.6328) (xy 333.825831 -314.600349) (xy 333.785682 -314.56164) (xy 333.751596 -314.517497)
			(xy 333.7243 -314.468862) (xy 333.704377 -314.416771) (xy 333.692251 -314.362334) (xy 333.68818 -314.306712)
			(xy 331.061262 -314.306712) (xy 331.456792 -314.702444) (xy 331.491011 -314.737464) (xy 331.553184 -314.813109)
			(xy 331.607648 -314.894481) (xy 331.653878 -314.980798) (xy 331.6732 -315.025786) (xy 331.796183 -315.322712)
			(xy 333.68818 -315.322712) (xy 333.692251 -315.26709) (xy 333.704377 -315.212653) (xy 333.7243 -315.160562)
			(xy 333.751596 -315.111927) (xy 333.785682 -315.067784) (xy 333.825831 -315.029075) (xy 333.871189 -314.996624)
			(xy 333.920789 -314.971123) (xy 333.973573 -314.953116) (xy 334.028416 -314.942986) (xy 334.08415 -314.940949)
			(xy 334.139587 -314.947049) (xy 334.193544 -314.961155) (xy 334.244873 -314.982967) (xy 334.292479 -315.012021)
			(xy 334.335347 -315.047696) (xy 334.372564 -315.089233) (xy 334.403337 -315.135746) (xy 334.427009 -315.186243)
			(xy 334.443077 -315.23965) (xy 334.451197 -315.294826) (xy 334.451706 -315.322712) (xy 334.70418 -315.322712)
			(xy 334.708251 -315.26709) (xy 334.720377 -315.212653) (xy 334.7403 -315.160562) (xy 334.767596 -315.111927)
			(xy 334.801682 -315.067784) (xy 334.841831 -315.029075) (xy 334.887189 -314.996624) (xy 334.936789 -314.971123)
			(xy 334.989573 -314.953116) (xy 335.044416 -314.942986) (xy 335.10015 -314.940949) (xy 335.155587 -314.947049)
			(xy 335.209544 -314.961155) (xy 335.260873 -314.982967) (xy 335.308479 -315.012021) (xy 335.351347 -315.047696)
			(xy 335.388564 -315.089233) (xy 335.419337 -315.135746) (xy 335.443009 -315.186243) (xy 335.459077 -315.23965)
			(xy 335.467197 -315.294826) (xy 335.467706 -315.322712) (xy 335.72018 -315.322712) (xy 335.724251 -315.26709)
			(xy 335.736377 -315.212653) (xy 335.7563 -315.160562) (xy 335.783596 -315.111927) (xy 335.817682 -315.067784)
			(xy 335.857831 -315.029075) (xy 335.903189 -314.996624) (xy 335.952789 -314.971123) (xy 336.005573 -314.953116)
			(xy 336.060416 -314.942986) (xy 336.11615 -314.940949) (xy 336.171587 -314.947049) (xy 336.225544 -314.961155)
			(xy 336.276873 -314.982967) (xy 336.324479 -315.012021) (xy 336.367347 -315.047696) (xy 336.404564 -315.089233)
			(xy 336.435337 -315.135746) (xy 336.459009 -315.186243) (xy 336.475077 -315.23965) (xy 336.483197 -315.294826)
			(xy 336.483706 -315.322712) (xy 336.73618 -315.322712) (xy 336.740251 -315.26709) (xy 336.752377 -315.212653)
			(xy 336.7723 -315.160562) (xy 336.799596 -315.111927) (xy 336.833682 -315.067784) (xy 336.873831 -315.029075)
			(xy 336.919189 -314.996624) (xy 336.968789 -314.971123) (xy 337.021573 -314.953116) (xy 337.076416 -314.942986)
			(xy 337.13215 -314.940949) (xy 337.187587 -314.947049) (xy 337.241544 -314.961155) (xy 337.292873 -314.982967)
			(xy 337.340479 -315.012021) (xy 337.383347 -315.047696) (xy 337.420564 -315.089233) (xy 337.451337 -315.135746)
			(xy 337.475009 -315.186243) (xy 337.491077 -315.23965) (xy 337.499197 -315.294826) (xy 337.499706 -315.322712)
			(xy 337.75218 -315.322712) (xy 337.756251 -315.26709) (xy 337.768377 -315.212653) (xy 337.7883 -315.160562)
			(xy 337.815596 -315.111927) (xy 337.849682 -315.067784) (xy 337.889831 -315.029075) (xy 337.935189 -314.996624)
			(xy 337.984789 -314.971123) (xy 338.037573 -314.953116) (xy 338.092416 -314.942986) (xy 338.14815 -314.940949)
			(xy 338.203587 -314.947049) (xy 338.257544 -314.961155) (xy 338.308873 -314.982967) (xy 338.356479 -315.012021)
			(xy 338.399347 -315.047696) (xy 338.436564 -315.089233) (xy 338.467337 -315.135746) (xy 338.491009 -315.186243)
			(xy 338.507077 -315.23965) (xy 338.515197 -315.294826) (xy 338.515706 -315.322712) (xy 338.76818 -315.322712)
			(xy 338.772251 -315.26709) (xy 338.784377 -315.212653) (xy 338.8043 -315.160562) (xy 338.831596 -315.111927)
			(xy 338.865682 -315.067784) (xy 338.905831 -315.029075) (xy 338.951189 -314.996624) (xy 339.000789 -314.971123)
			(xy 339.053573 -314.953116) (xy 339.108416 -314.942986) (xy 339.16415 -314.940949) (xy 339.219587 -314.947049)
			(xy 339.273544 -314.961155) (xy 339.324873 -314.982967) (xy 339.372479 -315.012021) (xy 339.415347 -315.047696)
			(xy 339.452564 -315.089233) (xy 339.483337 -315.135746) (xy 339.507009 -315.186243) (xy 339.523077 -315.23965)
			(xy 339.531197 -315.294826) (xy 339.531706 -315.322712) (xy 339.78418 -315.322712) (xy 339.788251 -315.26709)
			(xy 339.800377 -315.212653) (xy 339.8203 -315.160562) (xy 339.847596 -315.111927) (xy 339.881682 -315.067784)
			(xy 339.921831 -315.029075) (xy 339.967189 -314.996624) (xy 340.016789 -314.971123) (xy 340.069573 -314.953116)
			(xy 340.124416 -314.942986) (xy 340.18015 -314.940949) (xy 340.235587 -314.947049) (xy 340.289544 -314.961155)
			(xy 340.340873 -314.982967) (xy 340.388479 -315.012021) (xy 340.431347 -315.047696) (xy 340.468564 -315.089233)
			(xy 340.499337 -315.135746) (xy 340.523009 -315.186243) (xy 340.539077 -315.23965) (xy 340.547197 -315.294826)
			(xy 340.547706 -315.322712) (xy 340.80018 -315.322712) (xy 340.804251 -315.26709) (xy 340.816377 -315.212653)
			(xy 340.8363 -315.160562) (xy 340.863596 -315.111927) (xy 340.897682 -315.067784) (xy 340.937831 -315.029075)
			(xy 340.983189 -314.996624) (xy 341.032789 -314.971123) (xy 341.085573 -314.953116) (xy 341.140416 -314.942986)
			(xy 341.19615 -314.940949) (xy 341.251587 -314.947049) (xy 341.305544 -314.961155) (xy 341.356873 -314.982967)
			(xy 341.404479 -315.012021) (xy 341.447347 -315.047696) (xy 341.484564 -315.089233) (xy 341.515337 -315.135746)
			(xy 341.539009 -315.186243) (xy 341.555077 -315.23965) (xy 341.563197 -315.294826) (xy 341.563706 -315.322712)
			(xy 341.81618 -315.322712) (xy 341.820251 -315.26709) (xy 341.832377 -315.212653) (xy 341.8523 -315.160562)
			(xy 341.879596 -315.111927) (xy 341.913682 -315.067784) (xy 341.953831 -315.029075) (xy 341.999189 -314.996624)
			(xy 342.048789 -314.971123) (xy 342.101573 -314.953116) (xy 342.156416 -314.942986) (xy 342.21215 -314.940949)
			(xy 342.267587 -314.947049) (xy 342.321544 -314.961155) (xy 342.372873 -314.982967) (xy 342.420479 -315.012021)
			(xy 342.463347 -315.047696) (xy 342.500564 -315.089233) (xy 342.531337 -315.135746) (xy 342.555009 -315.186243)
			(xy 342.571077 -315.23965) (xy 342.579197 -315.294826) (xy 342.579706 -315.322712) (xy 342.579197 -315.350598)
			(xy 342.571077 -315.405774) (xy 342.555009 -315.459181) (xy 342.531337 -315.509678) (xy 342.52631 -315.517276)
			(xy 357.436926 -315.517276) (xy 357.440997 -315.461654) (xy 357.453123 -315.407217) (xy 357.473046 -315.355126)
			(xy 357.500342 -315.306491) (xy 357.534428 -315.262348) (xy 357.574577 -315.223639) (xy 357.619935 -315.191188)
			(xy 357.669535 -315.165687) (xy 357.722319 -315.14768) (xy 357.777162 -315.13755) (xy 357.832896 -315.135513)
			(xy 357.888333 -315.141613) (xy 357.94229 -315.155719) (xy 357.993619 -315.177531) (xy 358.041225 -315.206585)
			(xy 358.084093 -315.24226) (xy 358.12131 -315.283797) (xy 358.152083 -315.33031) (xy 358.175755 -315.380807)
			(xy 358.191823 -315.434214) (xy 358.199943 -315.48939) (xy 358.200452 -315.517276) (xy 358.452926 -315.517276)
			(xy 358.456997 -315.461654) (xy 358.469123 -315.407217) (xy 358.489046 -315.355126) (xy 358.516342 -315.306491)
			(xy 358.550428 -315.262348) (xy 358.590577 -315.223639) (xy 358.635935 -315.191188) (xy 358.685535 -315.165687)
			(xy 358.738319 -315.14768) (xy 358.793162 -315.13755) (xy 358.848896 -315.135513) (xy 358.904333 -315.141613)
			(xy 358.95829 -315.155719) (xy 359.009619 -315.177531) (xy 359.057225 -315.206585) (xy 359.100093 -315.24226)
			(xy 359.13731 -315.283797) (xy 359.168083 -315.33031) (xy 359.191755 -315.380807) (xy 359.207823 -315.434214)
			(xy 359.215943 -315.48939) (xy 359.216452 -315.517276) (xy 359.468926 -315.517276) (xy 359.472997 -315.461654)
			(xy 359.485123 -315.407217) (xy 359.505046 -315.355126) (xy 359.532342 -315.306491) (xy 359.566428 -315.262348)
			(xy 359.606577 -315.223639) (xy 359.651935 -315.191188) (xy 359.701535 -315.165687) (xy 359.754319 -315.14768)
			(xy 359.809162 -315.13755) (xy 359.864896 -315.135513) (xy 359.920333 -315.141613) (xy 359.97429 -315.155719)
			(xy 360.025619 -315.177531) (xy 360.073225 -315.206585) (xy 360.116093 -315.24226) (xy 360.15331 -315.283797)
			(xy 360.184083 -315.33031) (xy 360.207755 -315.380807) (xy 360.223823 -315.434214) (xy 360.231943 -315.48939)
			(xy 360.232452 -315.517276) (xy 360.484926 -315.517276) (xy 360.488997 -315.461654) (xy 360.501123 -315.407217)
			(xy 360.521046 -315.355126) (xy 360.548342 -315.306491) (xy 360.582428 -315.262348) (xy 360.622577 -315.223639)
			(xy 360.667935 -315.191188) (xy 360.717535 -315.165687) (xy 360.770319 -315.14768) (xy 360.825162 -315.13755)
			(xy 360.880896 -315.135513) (xy 360.936333 -315.141613) (xy 360.99029 -315.155719) (xy 361.041619 -315.177531)
			(xy 361.089225 -315.206585) (xy 361.132093 -315.24226) (xy 361.16931 -315.283797) (xy 361.200083 -315.33031)
			(xy 361.223755 -315.380807) (xy 361.239823 -315.434214) (xy 361.247943 -315.48939) (xy 361.248452 -315.517276)
			(xy 361.500926 -315.517276) (xy 361.504997 -315.461654) (xy 361.517123 -315.407217) (xy 361.537046 -315.355126)
			(xy 361.564342 -315.306491) (xy 361.598428 -315.262348) (xy 361.638577 -315.223639) (xy 361.683935 -315.191188)
			(xy 361.733535 -315.165687) (xy 361.786319 -315.14768) (xy 361.841162 -315.13755) (xy 361.896896 -315.135513)
			(xy 361.952333 -315.141613) (xy 362.00629 -315.155719) (xy 362.057619 -315.177531) (xy 362.105225 -315.206585)
			(xy 362.148093 -315.24226) (xy 362.18531 -315.283797) (xy 362.216083 -315.33031) (xy 362.239755 -315.380807)
			(xy 362.255823 -315.434214) (xy 362.263943 -315.48939) (xy 362.264452 -315.517276) (xy 362.516926 -315.517276)
			(xy 362.520997 -315.461654) (xy 362.533123 -315.407217) (xy 362.553046 -315.355126) (xy 362.580342 -315.306491)
			(xy 362.614428 -315.262348) (xy 362.654577 -315.223639) (xy 362.699935 -315.191188) (xy 362.749535 -315.165687)
			(xy 362.802319 -315.14768) (xy 362.857162 -315.13755) (xy 362.912896 -315.135513) (xy 362.968333 -315.141613)
			(xy 363.02229 -315.155719) (xy 363.073619 -315.177531) (xy 363.121225 -315.206585) (xy 363.164093 -315.24226)
			(xy 363.20131 -315.283797) (xy 363.232083 -315.33031) (xy 363.255755 -315.380807) (xy 363.271823 -315.434214)
			(xy 363.279943 -315.48939) (xy 363.280452 -315.517276) (xy 363.279943 -315.545162) (xy 363.271823 -315.600338)
			(xy 363.255755 -315.653745) (xy 363.232083 -315.704242) (xy 363.20131 -315.750755) (xy 363.164093 -315.792292)
			(xy 363.121225 -315.827967) (xy 363.073619 -315.857021) (xy 363.02229 -315.878833) (xy 362.968333 -315.892939)
			(xy 362.912896 -315.899039) (xy 362.857162 -315.897002) (xy 362.802319 -315.886872) (xy 362.749535 -315.868865)
			(xy 362.699935 -315.843364) (xy 362.654577 -315.810913) (xy 362.614428 -315.772204) (xy 362.580342 -315.728061)
			(xy 362.553046 -315.679426) (xy 362.533123 -315.627335) (xy 362.520997 -315.572898) (xy 362.516926 -315.517276)
			(xy 362.264452 -315.517276) (xy 362.263943 -315.545162) (xy 362.255823 -315.600338) (xy 362.239755 -315.653745)
			(xy 362.216083 -315.704242) (xy 362.18531 -315.750755) (xy 362.148093 -315.792292) (xy 362.105225 -315.827967)
			(xy 362.057619 -315.857021) (xy 362.00629 -315.878833) (xy 361.952333 -315.892939) (xy 361.896896 -315.899039)
			(xy 361.841162 -315.897002) (xy 361.786319 -315.886872) (xy 361.733535 -315.868865) (xy 361.683935 -315.843364)
			(xy 361.638577 -315.810913) (xy 361.598428 -315.772204) (xy 361.564342 -315.728061) (xy 361.537046 -315.679426)
			(xy 361.517123 -315.627335) (xy 361.504997 -315.572898) (xy 361.500926 -315.517276) (xy 361.248452 -315.517276)
			(xy 361.247943 -315.545162) (xy 361.239823 -315.600338) (xy 361.223755 -315.653745) (xy 361.200083 -315.704242)
			(xy 361.16931 -315.750755) (xy 361.132093 -315.792292) (xy 361.089225 -315.827967) (xy 361.041619 -315.857021)
			(xy 360.99029 -315.878833) (xy 360.936333 -315.892939) (xy 360.880896 -315.899039) (xy 360.825162 -315.897002)
			(xy 360.770319 -315.886872) (xy 360.717535 -315.868865) (xy 360.667935 -315.843364) (xy 360.622577 -315.810913)
			(xy 360.582428 -315.772204) (xy 360.548342 -315.728061) (xy 360.521046 -315.679426) (xy 360.501123 -315.627335)
			(xy 360.488997 -315.572898) (xy 360.484926 -315.517276) (xy 360.232452 -315.517276) (xy 360.231943 -315.545162)
			(xy 360.223823 -315.600338) (xy 360.207755 -315.653745) (xy 360.184083 -315.704242) (xy 360.15331 -315.750755)
			(xy 360.116093 -315.792292) (xy 360.073225 -315.827967) (xy 360.025619 -315.857021) (xy 359.97429 -315.878833)
			(xy 359.920333 -315.892939) (xy 359.864896 -315.899039) (xy 359.809162 -315.897002) (xy 359.754319 -315.886872)
			(xy 359.701535 -315.868865) (xy 359.651935 -315.843364) (xy 359.606577 -315.810913) (xy 359.566428 -315.772204)
			(xy 359.532342 -315.728061) (xy 359.505046 -315.679426) (xy 359.485123 -315.627335) (xy 359.472997 -315.572898)
			(xy 359.468926 -315.517276) (xy 359.216452 -315.517276) (xy 359.215943 -315.545162) (xy 359.207823 -315.600338)
			(xy 359.191755 -315.653745) (xy 359.168083 -315.704242) (xy 359.13731 -315.750755) (xy 359.100093 -315.792292)
			(xy 359.057225 -315.827967) (xy 359.009619 -315.857021) (xy 358.95829 -315.878833) (xy 358.904333 -315.892939)
			(xy 358.848896 -315.899039) (xy 358.793162 -315.897002) (xy 358.738319 -315.886872) (xy 358.685535 -315.868865)
			(xy 358.635935 -315.843364) (xy 358.590577 -315.810913) (xy 358.550428 -315.772204) (xy 358.516342 -315.728061)
			(xy 358.489046 -315.679426) (xy 358.469123 -315.627335) (xy 358.456997 -315.572898) (xy 358.452926 -315.517276)
			(xy 358.200452 -315.517276) (xy 358.199943 -315.545162) (xy 358.191823 -315.600338) (xy 358.175755 -315.653745)
			(xy 358.152083 -315.704242) (xy 358.12131 -315.750755) (xy 358.084093 -315.792292) (xy 358.041225 -315.827967)
			(xy 357.993619 -315.857021) (xy 357.94229 -315.878833) (xy 357.888333 -315.892939) (xy 357.832896 -315.899039)
			(xy 357.777162 -315.897002) (xy 357.722319 -315.886872) (xy 357.669535 -315.868865) (xy 357.619935 -315.843364)
			(xy 357.574577 -315.810913) (xy 357.534428 -315.772204) (xy 357.500342 -315.728061) (xy 357.473046 -315.679426)
			(xy 357.453123 -315.627335) (xy 357.440997 -315.572898) (xy 357.436926 -315.517276) (xy 342.52631 -315.517276)
			(xy 342.500564 -315.556191) (xy 342.463347 -315.597728) (xy 342.420479 -315.633403) (xy 342.372873 -315.662457)
			(xy 342.321544 -315.684269) (xy 342.267587 -315.698375) (xy 342.21215 -315.704475) (xy 342.156416 -315.702438)
			(xy 342.101573 -315.692308) (xy 342.048789 -315.674301) (xy 341.999189 -315.6488) (xy 341.953831 -315.616349)
			(xy 341.913682 -315.57764) (xy 341.879596 -315.533497) (xy 341.8523 -315.484862) (xy 341.832377 -315.432771)
			(xy 341.820251 -315.378334) (xy 341.81618 -315.322712) (xy 341.563706 -315.322712) (xy 341.563197 -315.350598)
			(xy 341.555077 -315.405774) (xy 341.539009 -315.459181) (xy 341.515337 -315.509678) (xy 341.484564 -315.556191)
			(xy 341.447347 -315.597728) (xy 341.404479 -315.633403) (xy 341.356873 -315.662457) (xy 341.305544 -315.684269)
			(xy 341.251587 -315.698375) (xy 341.19615 -315.704475) (xy 341.140416 -315.702438) (xy 341.085573 -315.692308)
			(xy 341.032789 -315.674301) (xy 340.983189 -315.6488) (xy 340.937831 -315.616349) (xy 340.897682 -315.57764)
			(xy 340.863596 -315.533497) (xy 340.8363 -315.484862) (xy 340.816377 -315.432771) (xy 340.804251 -315.378334)
			(xy 340.80018 -315.322712) (xy 340.547706 -315.322712) (xy 340.547197 -315.350598) (xy 340.539077 -315.405774)
			(xy 340.523009 -315.459181) (xy 340.499337 -315.509678) (xy 340.468564 -315.556191) (xy 340.431347 -315.597728)
			(xy 340.388479 -315.633403) (xy 340.340873 -315.662457) (xy 340.289544 -315.684269) (xy 340.235587 -315.698375)
			(xy 340.18015 -315.704475) (xy 340.124416 -315.702438) (xy 340.069573 -315.692308) (xy 340.016789 -315.674301)
			(xy 339.967189 -315.6488) (xy 339.921831 -315.616349) (xy 339.881682 -315.57764) (xy 339.847596 -315.533497)
			(xy 339.8203 -315.484862) (xy 339.800377 -315.432771) (xy 339.788251 -315.378334) (xy 339.78418 -315.322712)
			(xy 339.531706 -315.322712) (xy 339.531197 -315.350598) (xy 339.523077 -315.405774) (xy 339.507009 -315.459181)
			(xy 339.483337 -315.509678) (xy 339.452564 -315.556191) (xy 339.415347 -315.597728) (xy 339.372479 -315.633403)
			(xy 339.324873 -315.662457) (xy 339.273544 -315.684269) (xy 339.219587 -315.698375) (xy 339.16415 -315.704475)
			(xy 339.108416 -315.702438) (xy 339.053573 -315.692308) (xy 339.000789 -315.674301) (xy 338.951189 -315.6488)
			(xy 338.905831 -315.616349) (xy 338.865682 -315.57764) (xy 338.831596 -315.533497) (xy 338.8043 -315.484862)
			(xy 338.784377 -315.432771) (xy 338.772251 -315.378334) (xy 338.76818 -315.322712) (xy 338.515706 -315.322712)
			(xy 338.515197 -315.350598) (xy 338.507077 -315.405774) (xy 338.491009 -315.459181) (xy 338.467337 -315.509678)
			(xy 338.436564 -315.556191) (xy 338.399347 -315.597728) (xy 338.356479 -315.633403) (xy 338.308873 -315.662457)
			(xy 338.257544 -315.684269) (xy 338.203587 -315.698375) (xy 338.14815 -315.704475) (xy 338.092416 -315.702438)
			(xy 338.037573 -315.692308) (xy 337.984789 -315.674301) (xy 337.935189 -315.6488) (xy 337.889831 -315.616349)
			(xy 337.849682 -315.57764) (xy 337.815596 -315.533497) (xy 337.7883 -315.484862) (xy 337.768377 -315.432771)
			(xy 337.756251 -315.378334) (xy 337.75218 -315.322712) (xy 337.499706 -315.322712) (xy 337.499197 -315.350598)
			(xy 337.491077 -315.405774) (xy 337.475009 -315.459181) (xy 337.451337 -315.509678) (xy 337.420564 -315.556191)
			(xy 337.383347 -315.597728) (xy 337.340479 -315.633403) (xy 337.292873 -315.662457) (xy 337.241544 -315.684269)
			(xy 337.187587 -315.698375) (xy 337.13215 -315.704475) (xy 337.076416 -315.702438) (xy 337.021573 -315.692308)
			(xy 336.968789 -315.674301) (xy 336.919189 -315.6488) (xy 336.873831 -315.616349) (xy 336.833682 -315.57764)
			(xy 336.799596 -315.533497) (xy 336.7723 -315.484862) (xy 336.752377 -315.432771) (xy 336.740251 -315.378334)
			(xy 336.73618 -315.322712) (xy 336.483706 -315.322712) (xy 336.483197 -315.350598) (xy 336.475077 -315.405774)
			(xy 336.459009 -315.459181) (xy 336.435337 -315.509678) (xy 336.404564 -315.556191) (xy 336.367347 -315.597728)
			(xy 336.324479 -315.633403) (xy 336.276873 -315.662457) (xy 336.225544 -315.684269) (xy 336.171587 -315.698375)
			(xy 336.11615 -315.704475) (xy 336.060416 -315.702438) (xy 336.005573 -315.692308) (xy 335.952789 -315.674301)
			(xy 335.903189 -315.6488) (xy 335.857831 -315.616349) (xy 335.817682 -315.57764) (xy 335.783596 -315.533497)
			(xy 335.7563 -315.484862) (xy 335.736377 -315.432771) (xy 335.724251 -315.378334) (xy 335.72018 -315.322712)
			(xy 335.467706 -315.322712) (xy 335.467197 -315.350598) (xy 335.459077 -315.405774) (xy 335.443009 -315.459181)
			(xy 335.419337 -315.509678) (xy 335.388564 -315.556191) (xy 335.351347 -315.597728) (xy 335.308479 -315.633403)
			(xy 335.260873 -315.662457) (xy 335.209544 -315.684269) (xy 335.155587 -315.698375) (xy 335.10015 -315.704475)
			(xy 335.044416 -315.702438) (xy 334.989573 -315.692308) (xy 334.936789 -315.674301) (xy 334.887189 -315.6488)
			(xy 334.841831 -315.616349) (xy 334.801682 -315.57764) (xy 334.767596 -315.533497) (xy 334.7403 -315.484862)
			(xy 334.720377 -315.432771) (xy 334.708251 -315.378334) (xy 334.70418 -315.322712) (xy 334.451706 -315.322712)
			(xy 334.451197 -315.350598) (xy 334.443077 -315.405774) (xy 334.427009 -315.459181) (xy 334.403337 -315.509678)
			(xy 334.372564 -315.556191) (xy 334.335347 -315.597728) (xy 334.292479 -315.633403) (xy 334.244873 -315.662457)
			(xy 334.193544 -315.684269) (xy 334.139587 -315.698375) (xy 334.08415 -315.704475) (xy 334.028416 -315.702438)
			(xy 333.973573 -315.692308) (xy 333.920789 -315.674301) (xy 333.871189 -315.6488) (xy 333.825831 -315.616349)
			(xy 333.785682 -315.57764) (xy 333.751596 -315.533497) (xy 333.7243 -315.484862) (xy 333.704377 -315.432771)
			(xy 333.692251 -315.378334) (xy 333.68818 -315.322712) (xy 331.796183 -315.322712) (xy 332.0796 -316.006988)
			(xy 332.0847 -316.017718) (xy 332.102579 -316.033319) (xy 332.11389 -316.03696) (xy 332.114144 -316.03696)
			(xy 332.141209 -316.044332) (xy 332.192979 -316.065927) (xy 332.241029 -316.094869) (xy 332.284323 -316.130534)
			(xy 332.321929 -316.172155) (xy 332.353035 -316.218832) (xy 332.376972 -316.269562) (xy 332.393223 -316.323249)
			(xy 332.395513 -316.338712) (xy 335.72018 -316.338712) (xy 335.724251 -316.28309) (xy 335.736377 -316.228653)
			(xy 335.7563 -316.176562) (xy 335.783596 -316.127927) (xy 335.817682 -316.083784) (xy 335.857831 -316.045075)
			(xy 335.903189 -316.012624) (xy 335.952789 -315.987123) (xy 336.005573 -315.969116) (xy 336.060416 -315.958986)
			(xy 336.11615 -315.956949) (xy 336.171587 -315.963049) (xy 336.225544 -315.977155) (xy 336.276873 -315.998967)
			(xy 336.324479 -316.028021) (xy 336.367347 -316.063696) (xy 336.404564 -316.105233) (xy 336.435337 -316.151746)
			(xy 336.459009 -316.202243) (xy 336.475077 -316.25565) (xy 336.483197 -316.310826) (xy 336.483706 -316.338712)
			(xy 336.73618 -316.338712) (xy 336.740251 -316.28309) (xy 336.752377 -316.228653) (xy 336.7723 -316.176562)
			(xy 336.799596 -316.127927) (xy 336.833682 -316.083784) (xy 336.873831 -316.045075) (xy 336.919189 -316.012624)
			(xy 336.968789 -315.987123) (xy 337.021573 -315.969116) (xy 337.076416 -315.958986) (xy 337.13215 -315.956949)
			(xy 337.187587 -315.963049) (xy 337.241544 -315.977155) (xy 337.292873 -315.998967) (xy 337.340479 -316.028021)
			(xy 337.383347 -316.063696) (xy 337.420564 -316.105233) (xy 337.451337 -316.151746) (xy 337.475009 -316.202243)
			(xy 337.491077 -316.25565) (xy 337.499197 -316.310826) (xy 337.499706 -316.338712) (xy 337.75218 -316.338712)
			(xy 337.756251 -316.28309) (xy 337.768377 -316.228653) (xy 337.7883 -316.176562) (xy 337.815596 -316.127927)
			(xy 337.849682 -316.083784) (xy 337.889831 -316.045075) (xy 337.935189 -316.012624) (xy 337.984789 -315.987123)
			(xy 338.037573 -315.969116) (xy 338.092416 -315.958986) (xy 338.14815 -315.956949) (xy 338.203587 -315.963049)
			(xy 338.257544 -315.977155) (xy 338.308873 -315.998967) (xy 338.356479 -316.028021) (xy 338.399347 -316.063696)
			(xy 338.436564 -316.105233) (xy 338.467337 -316.151746) (xy 338.491009 -316.202243) (xy 338.507077 -316.25565)
			(xy 338.515197 -316.310826) (xy 338.515706 -316.338712) (xy 338.76818 -316.338712) (xy 338.772251 -316.28309)
			(xy 338.784377 -316.228653) (xy 338.8043 -316.176562) (xy 338.831596 -316.127927) (xy 338.865682 -316.083784)
			(xy 338.905831 -316.045075) (xy 338.951189 -316.012624) (xy 339.000789 -315.987123) (xy 339.053573 -315.969116)
			(xy 339.108416 -315.958986) (xy 339.16415 -315.956949) (xy 339.219587 -315.963049) (xy 339.273544 -315.977155)
			(xy 339.324873 -315.998967) (xy 339.372479 -316.028021) (xy 339.415347 -316.063696) (xy 339.452564 -316.105233)
			(xy 339.483337 -316.151746) (xy 339.507009 -316.202243) (xy 339.523077 -316.25565) (xy 339.531197 -316.310826)
			(xy 339.531706 -316.338712) (xy 339.78418 -316.338712) (xy 339.788251 -316.28309) (xy 339.800377 -316.228653)
			(xy 339.8203 -316.176562) (xy 339.847596 -316.127927) (xy 339.881682 -316.083784) (xy 339.921831 -316.045075)
			(xy 339.967189 -316.012624) (xy 340.016789 -315.987123) (xy 340.069573 -315.969116) (xy 340.124416 -315.958986)
			(xy 340.18015 -315.956949) (xy 340.235587 -315.963049) (xy 340.289544 -315.977155) (xy 340.340873 -315.998967)
			(xy 340.388479 -316.028021) (xy 340.431347 -316.063696) (xy 340.468564 -316.105233) (xy 340.499337 -316.151746)
			(xy 340.523009 -316.202243) (xy 340.539077 -316.25565) (xy 340.547197 -316.310826) (xy 340.547706 -316.338712)
			(xy 340.80018 -316.338712) (xy 340.804251 -316.28309) (xy 340.816377 -316.228653) (xy 340.8363 -316.176562)
			(xy 340.863596 -316.127927) (xy 340.897682 -316.083784) (xy 340.937831 -316.045075) (xy 340.983189 -316.012624)
			(xy 341.032789 -315.987123) (xy 341.085573 -315.969116) (xy 341.140416 -315.958986) (xy 341.19615 -315.956949)
			(xy 341.251587 -315.963049) (xy 341.305544 -315.977155) (xy 341.356873 -315.998967) (xy 341.404479 -316.028021)
			(xy 341.447347 -316.063696) (xy 341.484564 -316.105233) (xy 341.515337 -316.151746) (xy 341.539009 -316.202243)
			(xy 341.555077 -316.25565) (xy 341.563197 -316.310826) (xy 341.563706 -316.338712) (xy 341.81618 -316.338712)
			(xy 341.820251 -316.28309) (xy 341.832377 -316.228653) (xy 341.8523 -316.176562) (xy 341.879596 -316.127927)
			(xy 341.913682 -316.083784) (xy 341.953831 -316.045075) (xy 341.999189 -316.012624) (xy 342.048789 -315.987123)
			(xy 342.101573 -315.969116) (xy 342.156416 -315.958986) (xy 342.21215 -315.956949) (xy 342.267587 -315.963049)
			(xy 342.321544 -315.977155) (xy 342.372873 -315.998967) (xy 342.420479 -316.028021) (xy 342.463347 -316.063696)
			(xy 342.500564 -316.105233) (xy 342.531337 -316.151746) (xy 342.555009 -316.202243) (xy 342.571077 -316.25565)
			(xy 342.579197 -316.310826) (xy 342.579706 -316.338712) (xy 342.579197 -316.366598) (xy 342.571077 -316.421774)
			(xy 342.555009 -316.475181) (xy 342.531337 -316.525678) (xy 342.52631 -316.533276) (xy 357.436926 -316.533276)
			(xy 357.440997 -316.477654) (xy 357.453123 -316.423217) (xy 357.473046 -316.371126) (xy 357.500342 -316.322491)
			(xy 357.534428 -316.278348) (xy 357.574577 -316.239639) (xy 357.619935 -316.207188) (xy 357.669535 -316.181687)
			(xy 357.722319 -316.16368) (xy 357.777162 -316.15355) (xy 357.832896 -316.151513) (xy 357.888333 -316.157613)
			(xy 357.94229 -316.171719) (xy 357.993619 -316.193531) (xy 358.041225 -316.222585) (xy 358.084093 -316.25826)
			(xy 358.12131 -316.299797) (xy 358.152083 -316.34631) (xy 358.175755 -316.396807) (xy 358.191823 -316.450214)
			(xy 358.199943 -316.50539) (xy 358.200452 -316.533276) (xy 358.452926 -316.533276) (xy 358.456997 -316.477654)
			(xy 358.469123 -316.423217) (xy 358.489046 -316.371126) (xy 358.516342 -316.322491) (xy 358.550428 -316.278348)
			(xy 358.590577 -316.239639) (xy 358.635935 -316.207188) (xy 358.685535 -316.181687) (xy 358.738319 -316.16368)
			(xy 358.793162 -316.15355) (xy 358.848896 -316.151513) (xy 358.904333 -316.157613) (xy 358.95829 -316.171719)
			(xy 359.009619 -316.193531) (xy 359.057225 -316.222585) (xy 359.100093 -316.25826) (xy 359.13731 -316.299797)
			(xy 359.168083 -316.34631) (xy 359.191755 -316.396807) (xy 359.207823 -316.450214) (xy 359.215943 -316.50539)
			(xy 359.216452 -316.533276) (xy 359.468926 -316.533276) (xy 359.472997 -316.477654) (xy 359.485123 -316.423217)
			(xy 359.505046 -316.371126) (xy 359.532342 -316.322491) (xy 359.566428 -316.278348) (xy 359.606577 -316.239639)
			(xy 359.651935 -316.207188) (xy 359.701535 -316.181687) (xy 359.754319 -316.16368) (xy 359.809162 -316.15355)
			(xy 359.864896 -316.151513) (xy 359.920333 -316.157613) (xy 359.97429 -316.171719) (xy 360.025619 -316.193531)
			(xy 360.073225 -316.222585) (xy 360.116093 -316.25826) (xy 360.15331 -316.299797) (xy 360.184083 -316.34631)
			(xy 360.207755 -316.396807) (xy 360.223823 -316.450214) (xy 360.231943 -316.50539) (xy 360.232452 -316.533276)
			(xy 360.484926 -316.533276) (xy 360.488997 -316.477654) (xy 360.501123 -316.423217) (xy 360.521046 -316.371126)
			(xy 360.548342 -316.322491) (xy 360.582428 -316.278348) (xy 360.622577 -316.239639) (xy 360.667935 -316.207188)
			(xy 360.717535 -316.181687) (xy 360.770319 -316.16368) (xy 360.825162 -316.15355) (xy 360.880896 -316.151513)
			(xy 360.936333 -316.157613) (xy 360.99029 -316.171719) (xy 361.041619 -316.193531) (xy 361.089225 -316.222585)
			(xy 361.132093 -316.25826) (xy 361.16931 -316.299797) (xy 361.200083 -316.34631) (xy 361.223755 -316.396807)
			(xy 361.239823 -316.450214) (xy 361.247943 -316.50539) (xy 361.248452 -316.533276) (xy 361.500926 -316.533276)
			(xy 361.504997 -316.477654) (xy 361.517123 -316.423217) (xy 361.537046 -316.371126) (xy 361.564342 -316.322491)
			(xy 361.598428 -316.278348) (xy 361.638577 -316.239639) (xy 361.683935 -316.207188) (xy 361.733535 -316.181687)
			(xy 361.786319 -316.16368) (xy 361.841162 -316.15355) (xy 361.896896 -316.151513) (xy 361.952333 -316.157613)
			(xy 362.00629 -316.171719) (xy 362.057619 -316.193531) (xy 362.105225 -316.222585) (xy 362.148093 -316.25826)
			(xy 362.18531 -316.299797) (xy 362.216083 -316.34631) (xy 362.239755 -316.396807) (xy 362.255823 -316.450214)
			(xy 362.263943 -316.50539) (xy 362.264452 -316.533276) (xy 362.516926 -316.533276) (xy 362.520997 -316.477654)
			(xy 362.533123 -316.423217) (xy 362.553046 -316.371126) (xy 362.580342 -316.322491) (xy 362.614428 -316.278348)
			(xy 362.654577 -316.239639) (xy 362.699935 -316.207188) (xy 362.749535 -316.181687) (xy 362.802319 -316.16368)
			(xy 362.857162 -316.15355) (xy 362.912896 -316.151513) (xy 362.968333 -316.157613) (xy 363.02229 -316.171719)
			(xy 363.073619 -316.193531) (xy 363.121225 -316.222585) (xy 363.164093 -316.25826) (xy 363.20131 -316.299797)
			(xy 363.232083 -316.34631) (xy 363.255755 -316.396807) (xy 363.271823 -316.450214) (xy 363.279943 -316.50539)
			(xy 363.280452 -316.533276) (xy 363.279943 -316.561162) (xy 363.271823 -316.616338) (xy 363.255755 -316.669745)
			(xy 363.232083 -316.720242) (xy 363.20131 -316.766755) (xy 363.164093 -316.808292) (xy 363.121225 -316.843967)
			(xy 363.073619 -316.873021) (xy 363.02229 -316.894833) (xy 362.968333 -316.908939) (xy 362.912896 -316.915039)
			(xy 362.857162 -316.913002) (xy 362.802319 -316.902872) (xy 362.749535 -316.884865) (xy 362.699935 -316.859364)
			(xy 362.654577 -316.826913) (xy 362.614428 -316.788204) (xy 362.580342 -316.744061) (xy 362.553046 -316.695426)
			(xy 362.533123 -316.643335) (xy 362.520997 -316.588898) (xy 362.516926 -316.533276) (xy 362.264452 -316.533276)
			(xy 362.263943 -316.561162) (xy 362.255823 -316.616338) (xy 362.239755 -316.669745) (xy 362.216083 -316.720242)
			(xy 362.18531 -316.766755) (xy 362.148093 -316.808292) (xy 362.105225 -316.843967) (xy 362.057619 -316.873021)
			(xy 362.00629 -316.894833) (xy 361.952333 -316.908939) (xy 361.896896 -316.915039) (xy 361.841162 -316.913002)
			(xy 361.786319 -316.902872) (xy 361.733535 -316.884865) (xy 361.683935 -316.859364) (xy 361.638577 -316.826913)
			(xy 361.598428 -316.788204) (xy 361.564342 -316.744061) (xy 361.537046 -316.695426) (xy 361.517123 -316.643335)
			(xy 361.504997 -316.588898) (xy 361.500926 -316.533276) (xy 361.248452 -316.533276) (xy 361.247943 -316.561162)
			(xy 361.239823 -316.616338) (xy 361.223755 -316.669745) (xy 361.200083 -316.720242) (xy 361.16931 -316.766755)
			(xy 361.132093 -316.808292) (xy 361.089225 -316.843967) (xy 361.041619 -316.873021) (xy 360.99029 -316.894833)
			(xy 360.936333 -316.908939) (xy 360.880896 -316.915039) (xy 360.825162 -316.913002) (xy 360.770319 -316.902872)
			(xy 360.717535 -316.884865) (xy 360.667935 -316.859364) (xy 360.622577 -316.826913) (xy 360.582428 -316.788204)
			(xy 360.548342 -316.744061) (xy 360.521046 -316.695426) (xy 360.501123 -316.643335) (xy 360.488997 -316.588898)
			(xy 360.484926 -316.533276) (xy 360.232452 -316.533276) (xy 360.231943 -316.561162) (xy 360.223823 -316.616338)
			(xy 360.207755 -316.669745) (xy 360.184083 -316.720242) (xy 360.15331 -316.766755) (xy 360.116093 -316.808292)
			(xy 360.073225 -316.843967) (xy 360.025619 -316.873021) (xy 359.97429 -316.894833) (xy 359.920333 -316.908939)
			(xy 359.864896 -316.915039) (xy 359.809162 -316.913002) (xy 359.754319 -316.902872) (xy 359.701535 -316.884865)
			(xy 359.651935 -316.859364) (xy 359.606577 -316.826913) (xy 359.566428 -316.788204) (xy 359.532342 -316.744061)
			(xy 359.505046 -316.695426) (xy 359.485123 -316.643335) (xy 359.472997 -316.588898) (xy 359.468926 -316.533276)
			(xy 359.216452 -316.533276) (xy 359.215943 -316.561162) (xy 359.207823 -316.616338) (xy 359.191755 -316.669745)
			(xy 359.168083 -316.720242) (xy 359.13731 -316.766755) (xy 359.100093 -316.808292) (xy 359.057225 -316.843967)
			(xy 359.009619 -316.873021) (xy 358.95829 -316.894833) (xy 358.904333 -316.908939) (xy 358.848896 -316.915039)
			(xy 358.793162 -316.913002) (xy 358.738319 -316.902872) (xy 358.685535 -316.884865) (xy 358.635935 -316.859364)
			(xy 358.590577 -316.826913) (xy 358.550428 -316.788204) (xy 358.516342 -316.744061) (xy 358.489046 -316.695426)
			(xy 358.469123 -316.643335) (xy 358.456997 -316.588898) (xy 358.452926 -316.533276) (xy 358.200452 -316.533276)
			(xy 358.199943 -316.561162) (xy 358.191823 -316.616338) (xy 358.175755 -316.669745) (xy 358.152083 -316.720242)
			(xy 358.12131 -316.766755) (xy 358.084093 -316.808292) (xy 358.041225 -316.843967) (xy 357.993619 -316.873021)
			(xy 357.94229 -316.894833) (xy 357.888333 -316.908939) (xy 357.832896 -316.915039) (xy 357.777162 -316.913002)
			(xy 357.722319 -316.902872) (xy 357.669535 -316.884865) (xy 357.619935 -316.859364) (xy 357.574577 -316.826913)
			(xy 357.534428 -316.788204) (xy 357.500342 -316.744061) (xy 357.473046 -316.695426) (xy 357.453123 -316.643335)
			(xy 357.440997 -316.588898) (xy 357.436926 -316.533276) (xy 342.52631 -316.533276) (xy 342.500564 -316.572191)
			(xy 342.463347 -316.613728) (xy 342.420479 -316.649403) (xy 342.372873 -316.678457) (xy 342.321544 -316.700269)
			(xy 342.267587 -316.714375) (xy 342.21215 -316.720475) (xy 342.156416 -316.718438) (xy 342.101573 -316.708308)
			(xy 342.048789 -316.690301) (xy 341.999189 -316.6648) (xy 341.953831 -316.632349) (xy 341.913682 -316.59364)
			(xy 341.879596 -316.549497) (xy 341.8523 -316.500862) (xy 341.832377 -316.448771) (xy 341.820251 -316.394334)
			(xy 341.81618 -316.338712) (xy 341.563706 -316.338712) (xy 341.563197 -316.366598) (xy 341.555077 -316.421774)
			(xy 341.539009 -316.475181) (xy 341.515337 -316.525678) (xy 341.484564 -316.572191) (xy 341.447347 -316.613728)
			(xy 341.404479 -316.649403) (xy 341.356873 -316.678457) (xy 341.305544 -316.700269) (xy 341.251587 -316.714375)
			(xy 341.19615 -316.720475) (xy 341.140416 -316.718438) (xy 341.085573 -316.708308) (xy 341.032789 -316.690301)
			(xy 340.983189 -316.6648) (xy 340.937831 -316.632349) (xy 340.897682 -316.59364) (xy 340.863596 -316.549497)
			(xy 340.8363 -316.500862) (xy 340.816377 -316.448771) (xy 340.804251 -316.394334) (xy 340.80018 -316.338712)
			(xy 340.547706 -316.338712) (xy 340.547197 -316.366598) (xy 340.539077 -316.421774) (xy 340.523009 -316.475181)
			(xy 340.499337 -316.525678) (xy 340.468564 -316.572191) (xy 340.431347 -316.613728) (xy 340.388479 -316.649403)
			(xy 340.340873 -316.678457) (xy 340.289544 -316.700269) (xy 340.235587 -316.714375) (xy 340.18015 -316.720475)
			(xy 340.124416 -316.718438) (xy 340.069573 -316.708308) (xy 340.016789 -316.690301) (xy 339.967189 -316.6648)
			(xy 339.921831 -316.632349) (xy 339.881682 -316.59364) (xy 339.847596 -316.549497) (xy 339.8203 -316.500862)
			(xy 339.800377 -316.448771) (xy 339.788251 -316.394334) (xy 339.78418 -316.338712) (xy 339.531706 -316.338712)
			(xy 339.531197 -316.366598) (xy 339.523077 -316.421774) (xy 339.507009 -316.475181) (xy 339.483337 -316.525678)
			(xy 339.452564 -316.572191) (xy 339.415347 -316.613728) (xy 339.372479 -316.649403) (xy 339.324873 -316.678457)
			(xy 339.273544 -316.700269) (xy 339.219587 -316.714375) (xy 339.16415 -316.720475) (xy 339.108416 -316.718438)
			(xy 339.053573 -316.708308) (xy 339.000789 -316.690301) (xy 338.951189 -316.6648) (xy 338.905831 -316.632349)
			(xy 338.865682 -316.59364) (xy 338.831596 -316.549497) (xy 338.8043 -316.500862) (xy 338.784377 -316.448771)
			(xy 338.772251 -316.394334) (xy 338.76818 -316.338712) (xy 338.515706 -316.338712) (xy 338.515197 -316.366598)
			(xy 338.507077 -316.421774) (xy 338.491009 -316.475181) (xy 338.467337 -316.525678) (xy 338.436564 -316.572191)
			(xy 338.399347 -316.613728) (xy 338.356479 -316.649403) (xy 338.308873 -316.678457) (xy 338.257544 -316.700269)
			(xy 338.203587 -316.714375) (xy 338.14815 -316.720475) (xy 338.092416 -316.718438) (xy 338.037573 -316.708308)
			(xy 337.984789 -316.690301) (xy 337.935189 -316.6648) (xy 337.889831 -316.632349) (xy 337.849682 -316.59364)
			(xy 337.815596 -316.549497) (xy 337.7883 -316.500862) (xy 337.768377 -316.448771) (xy 337.756251 -316.394334)
			(xy 337.75218 -316.338712) (xy 337.499706 -316.338712) (xy 337.499197 -316.366598) (xy 337.491077 -316.421774)
			(xy 337.475009 -316.475181) (xy 337.451337 -316.525678) (xy 337.420564 -316.572191) (xy 337.383347 -316.613728)
			(xy 337.340479 -316.649403) (xy 337.292873 -316.678457) (xy 337.241544 -316.700269) (xy 337.187587 -316.714375)
			(xy 337.13215 -316.720475) (xy 337.076416 -316.718438) (xy 337.021573 -316.708308) (xy 336.968789 -316.690301)
			(xy 336.919189 -316.6648) (xy 336.873831 -316.632349) (xy 336.833682 -316.59364) (xy 336.799596 -316.549497)
			(xy 336.7723 -316.500862) (xy 336.752377 -316.448771) (xy 336.740251 -316.394334) (xy 336.73618 -316.338712)
			(xy 336.483706 -316.338712) (xy 336.483197 -316.366598) (xy 336.475077 -316.421774) (xy 336.459009 -316.475181)
			(xy 336.435337 -316.525678) (xy 336.404564 -316.572191) (xy 336.367347 -316.613728) (xy 336.324479 -316.649403)
			(xy 336.276873 -316.678457) (xy 336.225544 -316.700269) (xy 336.171587 -316.714375) (xy 336.11615 -316.720475)
			(xy 336.060416 -316.718438) (xy 336.005573 -316.708308) (xy 335.952789 -316.690301) (xy 335.903189 -316.6648)
			(xy 335.857831 -316.632349) (xy 335.817682 -316.59364) (xy 335.783596 -316.549497) (xy 335.7563 -316.500862)
			(xy 335.736377 -316.448771) (xy 335.724251 -316.394334) (xy 335.72018 -316.338712) (xy 332.395513 -316.338712)
			(xy 332.401439 -316.378737) (xy 332.401926 -316.406784) (xy 332.40151 -316.432429) (xy 332.394633 -316.483257)
			(xy 332.381002 -316.532703) (xy 332.360862 -316.579874) (xy 332.348078 -316.60211) (xy 332.341982 -316.612524)
			(xy 332.340204 -316.636146) (xy 333.107792 -318.489076) (xy 333.125888 -318.534416) (xy 333.154189 -318.627851)
			(xy 333.173238 -318.723602) (xy 333.182855 -318.820755) (xy 333.183484 -318.869568) (xy 333.183484 -320.08064)
			(xy 338.422996 -320.08064) (xy 338.423507 -320.051722) (xy 338.432232 -319.994549) (xy 338.449489 -319.939349)
			(xy 338.474882 -319.887386) (xy 338.507829 -319.839853) (xy 338.547574 -319.797838) (xy 338.570062 -319.77965)
			(xy 338.578847 -319.772022) (xy 338.58904 -319.751137) (xy 338.58962 -319.739518) (xy 338.58962 -319.659762)
			(xy 338.589082 -319.64813) (xy 338.578891 -319.627221) (xy 338.570062 -319.61963) (xy 338.547585 -319.601432)
			(xy 338.507851 -319.559412) (xy 338.474912 -319.511879) (xy 338.449523 -319.459919) (xy 338.432265 -319.404723)
			(xy 338.423533 -319.347555) (xy 338.422996 -319.31864) (xy 338.423493 -319.291388) (xy 338.431244 -319.237438)
			(xy 338.446595 -319.185141) (xy 338.469233 -319.13556) (xy 338.498698 -319.089707) (xy 338.534388 -319.048514)
			(xy 338.575578 -319.012819) (xy 338.621429 -318.983351) (xy 338.671007 -318.960708) (xy 338.723303 -318.945352)
			(xy 338.777252 -318.937595) (xy 338.804504 -318.937132) (xy 338.833422 -318.937635) (xy 338.890594 -318.946366)
			(xy 338.945794 -318.963626) (xy 338.997756 -318.98902) (xy 339.045289 -319.021967) (xy 339.087305 -319.061711)
			(xy 339.105494 -319.084198) (xy 339.113114 -319.092992) (xy 339.134005 -319.103183) (xy 339.145626 -319.103756)
			(xy 339.225382 -319.103756) (xy 339.237013 -319.103207) (xy 339.257924 -319.093027) (xy 339.265514 -319.084198)
			(xy 339.282267 -319.063415) (xy 339.320621 -319.026285) (xy 339.363775 -318.994863) (xy 339.410889 -318.969764)
			(xy 339.461041 -318.951478) (xy 339.513252 -318.940361) (xy 339.566504 -318.936631) (xy 339.619756 -318.940361)
			(xy 339.671967 -318.951478) (xy 339.722119 -318.969764) (xy 339.769233 -318.994863) (xy 339.812387 -319.026285)
			(xy 339.850741 -319.063415) (xy 339.867494 -319.084198) (xy 339.875114 -319.092992) (xy 339.896005 -319.103183)
			(xy 339.907626 -319.103756) (xy 339.987382 -319.103756) (xy 339.999013 -319.103207) (xy 340.019924 -319.093027)
			(xy 340.027514 -319.084198) (xy 340.044267 -319.063415) (xy 340.082621 -319.026285) (xy 340.125775 -318.994863)
			(xy 340.172889 -318.969764) (xy 340.223041 -318.951478) (xy 340.275252 -318.940361) (xy 340.328504 -318.936631)
			(xy 340.381756 -318.940361) (xy 340.433967 -318.951478) (xy 340.484119 -318.969764) (xy 340.531233 -318.994863)
			(xy 340.574387 -319.026285) (xy 340.612741 -319.063415) (xy 340.629494 -319.084198) (xy 340.637114 -319.092992)
			(xy 340.658005 -319.103183) (xy 340.669626 -319.103756) (xy 340.749382 -319.103756) (xy 340.761013 -319.103207)
			(xy 340.781924 -319.093027) (xy 340.789514 -319.084198) (xy 340.806267 -319.063415) (xy 340.844621 -319.026285)
			(xy 340.887775 -318.994863) (xy 340.934889 -318.969764) (xy 340.985041 -318.951478) (xy 341.037252 -318.940361)
			(xy 341.090504 -318.936631) (xy 341.143756 -318.940361) (xy 341.195967 -318.951478) (xy 341.246119 -318.969764)
			(xy 341.293233 -318.994863) (xy 341.336387 -319.026285) (xy 341.374741 -319.063415) (xy 341.391494 -319.084198)
			(xy 341.399114 -319.092992) (xy 341.420005 -319.103183) (xy 341.431626 -319.103756) (xy 341.511382 -319.103756)
			(xy 341.523013 -319.103207) (xy 341.543924 -319.093027) (xy 341.551514 -319.084198) (xy 341.568267 -319.063415)
			(xy 341.606621 -319.026285) (xy 341.649775 -318.994863) (xy 341.696889 -318.969764) (xy 341.747041 -318.951478)
			(xy 341.799252 -318.940361) (xy 341.852504 -318.936631) (xy 341.905756 -318.940361) (xy 341.957967 -318.951478)
			(xy 342.008119 -318.969764) (xy 342.055233 -318.994863) (xy 342.098387 -319.026285) (xy 342.136741 -319.063415)
			(xy 342.153494 -319.084198) (xy 342.161114 -319.092992) (xy 342.182005 -319.103183) (xy 342.193626 -319.103756)
			(xy 342.273382 -319.103756) (xy 342.285013 -319.103207) (xy 342.305924 -319.093027) (xy 342.313514 -319.084198)
			(xy 342.330267 -319.063415) (xy 342.368621 -319.026285) (xy 342.411775 -318.994863) (xy 342.458889 -318.969764)
			(xy 342.509041 -318.951478) (xy 342.561252 -318.940361) (xy 342.614504 -318.936631) (xy 342.667756 -318.940361)
			(xy 342.719967 -318.951478) (xy 342.770119 -318.969764) (xy 342.817233 -318.994863) (xy 342.860387 -319.026285)
			(xy 342.898741 -319.063415) (xy 342.915494 -319.084198) (xy 342.923114 -319.092992) (xy 342.944005 -319.103183)
			(xy 342.955626 -319.103756) (xy 343.035382 -319.103756) (xy 343.047013 -319.103207) (xy 343.067924 -319.093027)
			(xy 343.075514 -319.084198) (xy 343.092267 -319.063415) (xy 343.130621 -319.026285) (xy 343.173775 -318.994863)
			(xy 343.220889 -318.969764) (xy 343.271041 -318.951478) (xy 343.323252 -318.940361) (xy 343.376504 -318.936631)
			(xy 343.429756 -318.940361) (xy 343.481967 -318.951478) (xy 343.532119 -318.969764) (xy 343.579233 -318.994863)
			(xy 343.622387 -319.026285) (xy 343.660741 -319.063415) (xy 343.677494 -319.084198) (xy 343.685114 -319.092992)
			(xy 343.706005 -319.103183) (xy 343.717626 -319.103756) (xy 343.797382 -319.103756) (xy 343.809013 -319.103207)
			(xy 343.829924 -319.093027) (xy 343.837514 -319.084198) (xy 343.854267 -319.063415) (xy 343.892621 -319.026285)
			(xy 343.935775 -318.994863) (xy 343.982889 -318.969764) (xy 344.033041 -318.951478) (xy 344.085252 -318.940361)
			(xy 344.138504 -318.936631) (xy 344.191756 -318.940361) (xy 344.243967 -318.951478) (xy 344.294119 -318.969764)
			(xy 344.341233 -318.994863) (xy 344.384387 -319.026285) (xy 344.422741 -319.063415) (xy 344.439494 -319.084198)
			(xy 344.447114 -319.092992) (xy 344.468005 -319.103183) (xy 344.479626 -319.103756) (xy 344.559382 -319.103756)
			(xy 344.571013 -319.103207) (xy 344.591924 -319.093027) (xy 344.599514 -319.084198) (xy 344.616267 -319.063415)
			(xy 344.654621 -319.026285) (xy 344.697775 -318.994863) (xy 344.744889 -318.969764) (xy 344.795041 -318.951478)
			(xy 344.847252 -318.940361) (xy 344.900504 -318.936631) (xy 344.953756 -318.940361) (xy 345.005967 -318.951478)
			(xy 345.056119 -318.969764) (xy 345.103233 -318.994863) (xy 345.146387 -319.026285) (xy 345.184741 -319.063415)
			(xy 345.201494 -319.084198) (xy 345.209114 -319.092992) (xy 345.230005 -319.103183) (xy 345.241626 -319.103756)
			(xy 345.321382 -319.103756) (xy 345.333013 -319.103207) (xy 345.353924 -319.093027) (xy 345.361514 -319.084198)
			(xy 345.378267 -319.063415) (xy 345.416621 -319.026285) (xy 345.459775 -318.994863) (xy 345.506889 -318.969764)
			(xy 345.557041 -318.951478) (xy 345.609252 -318.940361) (xy 345.662504 -318.936631) (xy 345.715756 -318.940361)
			(xy 345.767967 -318.951478) (xy 345.818119 -318.969764) (xy 345.865233 -318.994863) (xy 345.908387 -319.026285)
			(xy 345.946741 -319.063415) (xy 345.963494 -319.084198) (xy 345.971114 -319.092992) (xy 345.992005 -319.103183)
			(xy 346.003626 -319.103756) (xy 346.083382 -319.103756) (xy 346.095013 -319.103207) (xy 346.115924 -319.093027)
			(xy 346.123514 -319.084198) (xy 346.140267 -319.063415) (xy 346.178621 -319.026285) (xy 346.221775 -318.994863)
			(xy 346.268889 -318.969764) (xy 346.319041 -318.951478) (xy 346.371252 -318.940361) (xy 346.424504 -318.936631)
			(xy 346.477756 -318.940361) (xy 346.529967 -318.951478) (xy 346.580119 -318.969764) (xy 346.627233 -318.994863)
			(xy 346.670387 -319.026285) (xy 346.708741 -319.063415) (xy 346.725494 -319.084198) (xy 346.733114 -319.092992)
			(xy 346.754005 -319.103183) (xy 346.765626 -319.103756) (xy 346.845382 -319.103756) (xy 346.857013 -319.103207)
			(xy 346.877924 -319.093027) (xy 346.885514 -319.084198) (xy 346.903697 -319.061707) (xy 346.945718 -319.021973)
			(xy 346.993255 -318.989035) (xy 347.045218 -318.963647) (xy 347.100417 -318.946393) (xy 347.157588 -318.937666)
			(xy 347.186504 -318.937132) (xy 347.213759 -318.937552) (xy 347.267713 -318.94531) (xy 347.320014 -318.960669)
			(xy 347.369597 -318.983315) (xy 347.415452 -319.012787) (xy 347.456646 -319.048485) (xy 347.49234 -319.089683)
			(xy 347.521806 -319.135541) (xy 347.544447 -319.185127) (xy 347.559799 -319.23743) (xy 347.567551 -319.291385)
			(xy 347.568012 -319.31864) (xy 347.567484 -319.347557) (xy 347.558761 -319.404729) (xy 347.541508 -319.459929)
			(xy 347.516118 -319.511892) (xy 347.483174 -319.559426) (xy 347.443432 -319.601441) (xy 347.420946 -319.61963)
			(xy 347.412126 -319.627224) (xy 347.401951 -319.648135) (xy 347.401388 -319.659762) (xy 347.401388 -319.739518)
			(xy 347.401935 -319.751149) (xy 347.412119 -319.772058) (xy 347.420946 -319.77965) (xy 347.443415 -319.797858)
			(xy 347.483149 -319.839875) (xy 347.516088 -319.887407) (xy 347.541479 -319.939365) (xy 347.558739 -319.994559)
			(xy 347.567474 -320.051725) (xy 347.568012 -320.08064) (xy 351.617026 -320.08064) (xy 351.617563 -320.051724)
			(xy 351.626287 -319.994553) (xy 351.64354 -319.939354) (xy 351.668928 -319.887392) (xy 351.701869 -319.839858)
			(xy 351.741608 -319.79784) (xy 351.764092 -319.77965) (xy 351.772865 -319.77201) (xy 351.783068 -319.751134)
			(xy 351.78365 -319.739518) (xy 351.78365 -319.659762) (xy 351.783136 -319.648126) (xy 351.772931 -319.627216)
			(xy 351.764092 -319.61963) (xy 351.741621 -319.601424) (xy 351.701886 -319.559407) (xy 351.668945 -319.511875)
			(xy 351.643555 -319.459917) (xy 351.626296 -319.404722) (xy 351.617563 -319.347555) (xy 351.617026 -319.31864)
			(xy 351.617493 -319.291387) (xy 351.625245 -319.237434) (xy 351.640598 -319.185134) (xy 351.663238 -319.135552)
			(xy 351.692705 -319.089697) (xy 351.728399 -319.048503) (xy 351.769592 -319.012809) (xy 351.815447 -318.983341)
			(xy 351.865028 -318.9607) (xy 351.917328 -318.945346) (xy 351.971281 -318.937593) (xy 351.998534 -318.937132)
			(xy 352.02745 -318.937685) (xy 352.08462 -318.946405) (xy 352.139819 -318.963656) (xy 352.191781 -318.989041)
			(xy 352.239315 -319.021979) (xy 352.281333 -319.061715) (xy 352.299524 -319.084198) (xy 352.307131 -319.093006)
			(xy 352.328032 -319.103189) (xy 352.339656 -319.103756) (xy 352.419412 -319.103756) (xy 352.431045 -319.103225)
			(xy 352.451956 -319.093032) (xy 352.459544 -319.084198) (xy 352.476297 -319.063415) (xy 352.514651 -319.026285)
			(xy 352.557805 -318.994863) (xy 352.604919 -318.969764) (xy 352.655071 -318.951478) (xy 352.707282 -318.940361)
			(xy 352.760534 -318.936631) (xy 352.813786 -318.940361) (xy 352.865997 -318.951478) (xy 352.916149 -318.969764)
			(xy 352.963263 -318.994863) (xy 353.006417 -319.026285) (xy 353.044771 -319.063415) (xy 353.061524 -319.084198)
			(xy 353.069131 -319.093006) (xy 353.090032 -319.103189) (xy 353.101656 -319.103756) (xy 353.181412 -319.103756)
			(xy 353.193045 -319.103225) (xy 353.213956 -319.093032) (xy 353.221544 -319.084198) (xy 353.238297 -319.063415)
			(xy 353.276651 -319.026285) (xy 353.319805 -318.994863) (xy 353.366919 -318.969764) (xy 353.417071 -318.951478)
			(xy 353.469282 -318.940361) (xy 353.522534 -318.936631) (xy 353.575786 -318.940361) (xy 353.627997 -318.951478)
			(xy 353.678149 -318.969764) (xy 353.725263 -318.994863) (xy 353.768417 -319.026285) (xy 353.806771 -319.063415)
			(xy 353.823524 -319.084198) (xy 353.831131 -319.093006) (xy 353.852032 -319.103189) (xy 353.863656 -319.103756)
			(xy 353.943412 -319.103756) (xy 353.955045 -319.103225) (xy 353.975956 -319.093032) (xy 353.983544 -319.084198)
			(xy 354.000297 -319.063415) (xy 354.038651 -319.026285) (xy 354.081805 -318.994863) (xy 354.128919 -318.969764)
			(xy 354.179071 -318.951478) (xy 354.231282 -318.940361) (xy 354.284534 -318.936631) (xy 354.337786 -318.940361)
			(xy 354.389997 -318.951478) (xy 354.440149 -318.969764) (xy 354.487263 -318.994863) (xy 354.530417 -319.026285)
			(xy 354.568771 -319.063415) (xy 354.585524 -319.084198) (xy 354.593131 -319.093006) (xy 354.614032 -319.103189)
			(xy 354.625656 -319.103756) (xy 354.705412 -319.103756) (xy 354.717045 -319.103225) (xy 354.737956 -319.093032)
			(xy 354.745544 -319.084198) (xy 354.762297 -319.063415) (xy 354.800651 -319.026285) (xy 354.843805 -318.994863)
			(xy 354.890919 -318.969764) (xy 354.941071 -318.951478) (xy 354.993282 -318.940361) (xy 355.046534 -318.936631)
			(xy 355.099786 -318.940361) (xy 355.151997 -318.951478) (xy 355.202149 -318.969764) (xy 355.249263 -318.994863)
			(xy 355.292417 -319.026285) (xy 355.330771 -319.063415) (xy 355.347524 -319.084198) (xy 355.355131 -319.093006)
			(xy 355.376032 -319.103189) (xy 355.387656 -319.103756) (xy 355.467412 -319.103756) (xy 355.479045 -319.103225)
			(xy 355.499956 -319.093032) (xy 355.507544 -319.084198) (xy 355.524297 -319.063415) (xy 355.562651 -319.026285)
			(xy 355.605805 -318.994863) (xy 355.652919 -318.969764) (xy 355.703071 -318.951478) (xy 355.755282 -318.940361)
			(xy 355.808534 -318.936631) (xy 355.861786 -318.940361) (xy 355.913997 -318.951478) (xy 355.964149 -318.969764)
			(xy 356.011263 -318.994863) (xy 356.054417 -319.026285) (xy 356.092771 -319.063415) (xy 356.109524 -319.084198)
			(xy 356.117131 -319.093006) (xy 356.138032 -319.103189) (xy 356.149656 -319.103756) (xy 356.229412 -319.103756)
			(xy 356.241045 -319.103225) (xy 356.261956 -319.093032) (xy 356.269544 -319.084198) (xy 356.286297 -319.063415)
			(xy 356.324651 -319.026285) (xy 356.367805 -318.994863) (xy 356.414919 -318.969764) (xy 356.465071 -318.951478)
			(xy 356.517282 -318.940361) (xy 356.570534 -318.936631) (xy 356.623786 -318.940361) (xy 356.675997 -318.951478)
			(xy 356.726149 -318.969764) (xy 356.773263 -318.994863) (xy 356.816417 -319.026285) (xy 356.854771 -319.063415)
			(xy 356.871524 -319.084198) (xy 356.879131 -319.093006) (xy 356.900032 -319.103189) (xy 356.911656 -319.103756)
			(xy 356.991412 -319.103756) (xy 357.003045 -319.103225) (xy 357.023956 -319.093032) (xy 357.031544 -319.084198)
			(xy 357.048297 -319.063415) (xy 357.086651 -319.026285) (xy 357.129805 -318.994863) (xy 357.176919 -318.969764)
			(xy 357.227071 -318.951478) (xy 357.279282 -318.940361) (xy 357.332534 -318.936631) (xy 357.385786 -318.940361)
			(xy 357.437997 -318.951478) (xy 357.488149 -318.969764) (xy 357.535263 -318.994863) (xy 357.578417 -319.026285)
			(xy 357.616771 -319.063415) (xy 357.633524 -319.084198) (xy 357.641131 -319.093006) (xy 357.662032 -319.103189)
			(xy 357.673656 -319.103756) (xy 357.753412 -319.103756) (xy 357.765045 -319.103225) (xy 357.785956 -319.093032)
			(xy 357.793544 -319.084198) (xy 357.810297 -319.063415) (xy 357.848651 -319.026285) (xy 357.891805 -318.994863)
			(xy 357.938919 -318.969764) (xy 357.989071 -318.951478) (xy 358.041282 -318.940361) (xy 358.094534 -318.936631)
			(xy 358.147786 -318.940361) (xy 358.199997 -318.951478) (xy 358.250149 -318.969764) (xy 358.297263 -318.994863)
			(xy 358.340417 -319.026285) (xy 358.378771 -319.063415) (xy 358.395524 -319.084198) (xy 358.403131 -319.093006)
			(xy 358.424032 -319.103189) (xy 358.435656 -319.103756) (xy 358.515412 -319.103756) (xy 358.527045 -319.103225)
			(xy 358.547956 -319.093032) (xy 358.555544 -319.084198) (xy 358.572297 -319.063415) (xy 358.610651 -319.026285)
			(xy 358.653805 -318.994863) (xy 358.700919 -318.969764) (xy 358.751071 -318.951478) (xy 358.803282 -318.940361)
			(xy 358.856534 -318.936631) (xy 358.909786 -318.940361) (xy 358.961997 -318.951478) (xy 359.012149 -318.969764)
			(xy 359.059263 -318.994863) (xy 359.102417 -319.026285) (xy 359.140771 -319.063415) (xy 359.157524 -319.084198)
			(xy 359.165131 -319.093006) (xy 359.186032 -319.103189) (xy 359.197656 -319.103756) (xy 359.277412 -319.103756)
			(xy 359.289045 -319.103225) (xy 359.309956 -319.093032) (xy 359.317544 -319.084198) (xy 359.334297 -319.063415)
			(xy 359.372651 -319.026285) (xy 359.415805 -318.994863) (xy 359.462919 -318.969764) (xy 359.513071 -318.951478)
			(xy 359.565282 -318.940361) (xy 359.618534 -318.936631) (xy 359.671786 -318.940361) (xy 359.723997 -318.951478)
			(xy 359.774149 -318.969764) (xy 359.821263 -318.994863) (xy 359.864417 -319.026285) (xy 359.902771 -319.063415)
			(xy 359.919524 -319.084198) (xy 359.927131 -319.093006) (xy 359.948032 -319.103189) (xy 359.959656 -319.103756)
			(xy 360.039412 -319.103756) (xy 360.051045 -319.103225) (xy 360.071956 -319.093032) (xy 360.079544 -319.084198)
			(xy 360.096297 -319.063415) (xy 360.134651 -319.026285) (xy 360.177805 -318.994863) (xy 360.224919 -318.969764)
			(xy 360.275071 -318.951478) (xy 360.327282 -318.940361) (xy 360.380534 -318.936631) (xy 360.433786 -318.940361)
			(xy 360.485997 -318.951478) (xy 360.536149 -318.969764) (xy 360.583263 -318.994863) (xy 360.626417 -319.026285)
			(xy 360.664771 -319.063415) (xy 360.681524 -319.084198) (xy 360.689131 -319.093006) (xy 360.710032 -319.103189)
			(xy 360.721656 -319.103756) (xy 360.801412 -319.103756) (xy 360.813045 -319.103225) (xy 360.833956 -319.093032)
			(xy 360.841544 -319.084198) (xy 360.85971 -319.061693) (xy 360.901735 -319.021959) (xy 360.949275 -318.989023)
			(xy 361.001241 -318.963638) (xy 361.056443 -318.946387) (xy 361.113617 -318.937664) (xy 361.142534 -318.937132)
			(xy 361.16979 -318.937523) (xy 361.223745 -318.945286) (xy 361.276047 -318.960648) (xy 361.32563 -318.983298)
			(xy 361.371485 -319.012773) (xy 361.412678 -319.048474) (xy 361.448371 -319.089675) (xy 361.477838 -319.135535)
			(xy 361.500478 -319.185123) (xy 361.51583 -319.237427) (xy 361.523582 -319.291384) (xy 361.524042 -319.31864)
			(xy 361.523502 -319.347556) (xy 361.514781 -319.404728) (xy 361.497528 -319.459927) (xy 361.472141 -319.511889)
			(xy 361.4392 -319.559423) (xy 361.399461 -319.60144) (xy 361.376976 -319.61963) (xy 361.368161 -319.62723)
			(xy 361.357983 -319.648136) (xy 361.357418 -319.659762) (xy 361.357418 -319.739518) (xy 361.357955 -319.75115)
			(xy 361.368145 -319.77206) (xy 361.376976 -319.77965) (xy 361.399431 -319.797875) (xy 361.439169 -319.839887)
			(xy 361.472112 -319.887415) (xy 361.497505 -319.939369) (xy 361.514768 -319.994561) (xy 361.523503 -320.051726)
			(xy 361.524042 -320.08064) (xy 361.52356 -320.107891) (xy 361.515798 -320.161837) (xy 361.50044 -320.214129)
			(xy 361.477797 -320.263705) (xy 361.448329 -320.309553) (xy 361.412638 -320.350742) (xy 361.371448 -320.386433)
			(xy 361.325599 -320.4159) (xy 361.276024 -320.438542) (xy 361.223731 -320.4539) (xy 361.169785 -320.46166)
			(xy 361.142534 -320.462148) (xy 361.113617 -320.461625) (xy 361.056445 -320.4529) (xy 361.001246 -320.435644)
			(xy 360.949283 -320.410253) (xy 360.901749 -320.37731) (xy 360.859733 -320.337568) (xy 360.841544 -320.315082)
			(xy 360.833911 -320.306302) (xy 360.81303 -320.296104) (xy 360.801412 -320.295524) (xy 360.721656 -320.295524)
			(xy 360.710021 -320.296044) (xy 360.689112 -320.306246) (xy 360.681524 -320.315082) (xy 360.664771 -320.335865)
			(xy 360.626417 -320.372995) (xy 360.583263 -320.404417) (xy 360.536149 -320.429516) (xy 360.485997 -320.447802)
			(xy 360.433786 -320.458919) (xy 360.380534 -320.462649) (xy 360.327282 -320.458919) (xy 360.275071 -320.447802)
			(xy 360.224919 -320.429516) (xy 360.177805 -320.404417) (xy 360.134651 -320.372995) (xy 360.096297 -320.335865)
			(xy 360.079544 -320.315082) (xy 360.071911 -320.306302) (xy 360.05103 -320.296104) (xy 360.039412 -320.295524)
			(xy 359.959656 -320.295524) (xy 359.948021 -320.296044) (xy 359.927112 -320.306246) (xy 359.919524 -320.315082)
			(xy 359.902771 -320.335865) (xy 359.864417 -320.372995) (xy 359.821263 -320.404417) (xy 359.774149 -320.429516)
			(xy 359.723997 -320.447802) (xy 359.671786 -320.458919) (xy 359.618534 -320.462649) (xy 359.565282 -320.458919)
			(xy 359.513071 -320.447802) (xy 359.462919 -320.429516) (xy 359.415805 -320.404417) (xy 359.372651 -320.372995)
			(xy 359.334297 -320.335865) (xy 359.317544 -320.315082) (xy 359.309911 -320.306302) (xy 359.28903 -320.296104)
			(xy 359.277412 -320.295524) (xy 359.197656 -320.295524) (xy 359.186021 -320.296044) (xy 359.165112 -320.306246)
			(xy 359.157524 -320.315082) (xy 359.140771 -320.335865) (xy 359.102417 -320.372995) (xy 359.059263 -320.404417)
			(xy 359.012149 -320.429516) (xy 358.961997 -320.447802) (xy 358.909786 -320.458919) (xy 358.856534 -320.462649)
			(xy 358.803282 -320.458919) (xy 358.751071 -320.447802) (xy 358.700919 -320.429516) (xy 358.653805 -320.404417)
			(xy 358.610651 -320.372995) (xy 358.572297 -320.335865) (xy 358.555544 -320.315082) (xy 358.547911 -320.306302)
			(xy 358.52703 -320.296104) (xy 358.515412 -320.295524) (xy 358.435656 -320.295524) (xy 358.424021 -320.296044)
			(xy 358.403112 -320.306246) (xy 358.395524 -320.315082) (xy 358.378771 -320.335865) (xy 358.340417 -320.372995)
			(xy 358.297263 -320.404417) (xy 358.250149 -320.429516) (xy 358.199997 -320.447802) (xy 358.147786 -320.458919)
			(xy 358.094534 -320.462649) (xy 358.041282 -320.458919) (xy 357.989071 -320.447802) (xy 357.938919 -320.429516)
			(xy 357.891805 -320.404417) (xy 357.848651 -320.372995) (xy 357.810297 -320.335865) (xy 357.793544 -320.315082)
			(xy 357.785911 -320.306302) (xy 357.76503 -320.296104) (xy 357.753412 -320.295524) (xy 357.673656 -320.295524)
			(xy 357.662021 -320.296044) (xy 357.641112 -320.306246) (xy 357.633524 -320.315082) (xy 357.616771 -320.335865)
			(xy 357.578417 -320.372995) (xy 357.535263 -320.404417) (xy 357.488149 -320.429516) (xy 357.437997 -320.447802)
			(xy 357.385786 -320.458919) (xy 357.332534 -320.462649) (xy 357.279282 -320.458919) (xy 357.227071 -320.447802)
			(xy 357.176919 -320.429516) (xy 357.129805 -320.404417) (xy 357.086651 -320.372995) (xy 357.048297 -320.335865)
			(xy 357.031544 -320.315082) (xy 357.023911 -320.306302) (xy 357.00303 -320.296104) (xy 356.991412 -320.295524)
			(xy 356.911656 -320.295524) (xy 356.900021 -320.296044) (xy 356.879112 -320.306246) (xy 356.871524 -320.315082)
			(xy 356.854771 -320.335865) (xy 356.816417 -320.372995) (xy 356.773263 -320.404417) (xy 356.726149 -320.429516)
			(xy 356.675997 -320.447802) (xy 356.623786 -320.458919) (xy 356.570534 -320.462649) (xy 356.517282 -320.458919)
			(xy 356.465071 -320.447802) (xy 356.414919 -320.429516) (xy 356.367805 -320.404417) (xy 356.324651 -320.372995)
			(xy 356.286297 -320.335865) (xy 356.269544 -320.315082) (xy 356.261911 -320.306302) (xy 356.24103 -320.296104)
			(xy 356.229412 -320.295524) (xy 356.149656 -320.295524) (xy 356.138021 -320.296044) (xy 356.117112 -320.306246)
			(xy 356.109524 -320.315082) (xy 356.092771 -320.335865) (xy 356.054417 -320.372995) (xy 356.011263 -320.404417)
			(xy 355.964149 -320.429516) (xy 355.913997 -320.447802) (xy 355.861786 -320.458919) (xy 355.808534 -320.462649)
			(xy 355.755282 -320.458919) (xy 355.703071 -320.447802) (xy 355.652919 -320.429516) (xy 355.605805 -320.404417)
			(xy 355.562651 -320.372995) (xy 355.524297 -320.335865) (xy 355.507544 -320.315082) (xy 355.499911 -320.306302)
			(xy 355.47903 -320.296104) (xy 355.467412 -320.295524) (xy 355.387656 -320.295524) (xy 355.376021 -320.296044)
			(xy 355.355112 -320.306246) (xy 355.347524 -320.315082) (xy 355.330771 -320.335865) (xy 355.292417 -320.372995)
			(xy 355.249263 -320.404417) (xy 355.202149 -320.429516) (xy 355.151997 -320.447802) (xy 355.099786 -320.458919)
			(xy 355.046534 -320.462649) (xy 354.993282 -320.458919) (xy 354.941071 -320.447802) (xy 354.890919 -320.429516)
			(xy 354.843805 -320.404417) (xy 354.800651 -320.372995) (xy 354.762297 -320.335865) (xy 354.745544 -320.315082)
			(xy 354.737911 -320.306302) (xy 354.71703 -320.296104) (xy 354.705412 -320.295524) (xy 354.625656 -320.295524)
			(xy 354.614021 -320.296044) (xy 354.593112 -320.306246) (xy 354.585524 -320.315082) (xy 354.568771 -320.335865)
			(xy 354.530417 -320.372995) (xy 354.487263 -320.404417) (xy 354.440149 -320.429516) (xy 354.389997 -320.447802)
			(xy 354.337786 -320.458919) (xy 354.284534 -320.462649) (xy 354.231282 -320.458919) (xy 354.179071 -320.447802)
			(xy 354.128919 -320.429516) (xy 354.081805 -320.404417) (xy 354.038651 -320.372995) (xy 354.000297 -320.335865)
			(xy 353.983544 -320.315082) (xy 353.975911 -320.306302) (xy 353.95503 -320.296104) (xy 353.943412 -320.295524)
			(xy 353.863656 -320.295524) (xy 353.852021 -320.296044) (xy 353.831112 -320.306246) (xy 353.823524 -320.315082)
			(xy 353.806771 -320.335865) (xy 353.768417 -320.372995) (xy 353.725263 -320.404417) (xy 353.678149 -320.429516)
			(xy 353.627997 -320.447802) (xy 353.575786 -320.458919) (xy 353.522534 -320.462649) (xy 353.469282 -320.458919)
			(xy 353.417071 -320.447802) (xy 353.366919 -320.429516) (xy 353.319805 -320.404417) (xy 353.276651 -320.372995)
			(xy 353.238297 -320.335865) (xy 353.221544 -320.315082) (xy 353.213911 -320.306302) (xy 353.19303 -320.296104)
			(xy 353.181412 -320.295524) (xy 353.101656 -320.295524) (xy 353.090021 -320.296044) (xy 353.069112 -320.306246)
			(xy 353.061524 -320.315082) (xy 353.044771 -320.335865) (xy 353.006417 -320.372995) (xy 352.963263 -320.404417)
			(xy 352.916149 -320.429516) (xy 352.865997 -320.447802) (xy 352.813786 -320.458919) (xy 352.760534 -320.462649)
			(xy 352.707282 -320.458919) (xy 352.655071 -320.447802) (xy 352.604919 -320.429516) (xy 352.557805 -320.404417)
			(xy 352.514651 -320.372995) (xy 352.476297 -320.335865) (xy 352.459544 -320.315082) (xy 352.451911 -320.306302)
			(xy 352.43103 -320.296104) (xy 352.419412 -320.295524) (xy 352.339656 -320.295524) (xy 352.328021 -320.296044)
			(xy 352.307112 -320.306246) (xy 352.299524 -320.315082) (xy 352.281315 -320.33755) (xy 352.239299 -320.377287)
			(xy 352.191768 -320.410229) (xy 352.139811 -320.43562) (xy 352.084616 -320.452879) (xy 352.027449 -320.461611)
			(xy 351.998534 -320.462148) (xy 351.971285 -320.46159) (xy 351.917342 -320.453839) (xy 351.865051 -320.438491)
			(xy 351.815477 -320.415856) (xy 351.769629 -320.386397) (xy 351.728439 -320.350713) (xy 351.692747 -320.309531)
			(xy 351.663279 -320.263688) (xy 351.640635 -320.214118) (xy 351.625276 -320.16183) (xy 351.617515 -320.107888)
			(xy 351.617026 -320.08064) (xy 347.568012 -320.08064) (xy 347.567559 -320.107892) (xy 347.559798 -320.161841)
			(xy 347.544438 -320.214136) (xy 347.521792 -320.263713) (xy 347.492322 -320.309563) (xy 347.456627 -320.350753)
			(xy 347.415434 -320.386444) (xy 347.369581 -320.415909) (xy 347.320002 -320.43855) (xy 347.267706 -320.453905)
			(xy 347.213756 -320.461662) (xy 347.186504 -320.462148) (xy 347.157586 -320.461646) (xy 347.100413 -320.452917)
			(xy 347.045213 -320.435657) (xy 346.993251 -320.410262) (xy 346.945718 -320.377315) (xy 346.903703 -320.33757)
			(xy 346.885514 -320.315082) (xy 346.877894 -320.306288) (xy 346.857003 -320.296098) (xy 346.845382 -320.295524)
			(xy 346.765626 -320.295524) (xy 346.753996 -320.296084) (xy 346.733086 -320.306257) (xy 346.725494 -320.315082)
			(xy 346.708741 -320.335865) (xy 346.670387 -320.372995) (xy 346.627233 -320.404417) (xy 346.580119 -320.429516)
			(xy 346.529967 -320.447802) (xy 346.477756 -320.458919) (xy 346.424504 -320.462649) (xy 346.371252 -320.458919)
			(xy 346.319041 -320.447802) (xy 346.268889 -320.429516) (xy 346.221775 -320.404417) (xy 346.178621 -320.372995)
			(xy 346.140267 -320.335865) (xy 346.123514 -320.315082) (xy 346.115894 -320.306288) (xy 346.095003 -320.296098)
			(xy 346.083382 -320.295524) (xy 346.003626 -320.295524) (xy 345.991996 -320.296084) (xy 345.971086 -320.306257)
			(xy 345.963494 -320.315082) (xy 345.946741 -320.335865) (xy 345.908387 -320.372995) (xy 345.865233 -320.404417)
			(xy 345.818119 -320.429516) (xy 345.767967 -320.447802) (xy 345.715756 -320.458919) (xy 345.662504 -320.462649)
			(xy 345.609252 -320.458919) (xy 345.557041 -320.447802) (xy 345.506889 -320.429516) (xy 345.459775 -320.404417)
			(xy 345.416621 -320.372995) (xy 345.378267 -320.335865) (xy 345.361514 -320.315082) (xy 345.353894 -320.306288)
			(xy 345.333003 -320.296098) (xy 345.321382 -320.295524) (xy 345.241626 -320.295524) (xy 345.229996 -320.296084)
			(xy 345.209086 -320.306257) (xy 345.201494 -320.315082) (xy 345.184741 -320.335865) (xy 345.146387 -320.372995)
			(xy 345.103233 -320.404417) (xy 345.056119 -320.429516) (xy 345.005967 -320.447802) (xy 344.953756 -320.458919)
			(xy 344.900504 -320.462649) (xy 344.847252 -320.458919) (xy 344.795041 -320.447802) (xy 344.744889 -320.429516)
			(xy 344.697775 -320.404417) (xy 344.654621 -320.372995) (xy 344.616267 -320.335865) (xy 344.599514 -320.315082)
			(xy 344.591894 -320.306288) (xy 344.571003 -320.296098) (xy 344.559382 -320.295524) (xy 344.479626 -320.295524)
			(xy 344.467996 -320.296084) (xy 344.447086 -320.306257) (xy 344.439494 -320.315082) (xy 344.422741 -320.335865)
			(xy 344.384387 -320.372995) (xy 344.341233 -320.404417) (xy 344.294119 -320.429516) (xy 344.243967 -320.447802)
			(xy 344.191756 -320.458919) (xy 344.138504 -320.462649) (xy 344.085252 -320.458919) (xy 344.033041 -320.447802)
			(xy 343.982889 -320.429516) (xy 343.935775 -320.404417) (xy 343.892621 -320.372995) (xy 343.854267 -320.335865)
			(xy 343.837514 -320.315082) (xy 343.829894 -320.306288) (xy 343.809003 -320.296098) (xy 343.797382 -320.295524)
			(xy 343.717626 -320.295524) (xy 343.705996 -320.296084) (xy 343.685086 -320.306257) (xy 343.677494 -320.315082)
			(xy 343.660741 -320.335865) (xy 343.622387 -320.372995) (xy 343.579233 -320.404417) (xy 343.532119 -320.429516)
			(xy 343.481967 -320.447802) (xy 343.429756 -320.458919) (xy 343.376504 -320.462649) (xy 343.323252 -320.458919)
			(xy 343.271041 -320.447802) (xy 343.220889 -320.429516) (xy 343.173775 -320.404417) (xy 343.130621 -320.372995)
			(xy 343.092267 -320.335865) (xy 343.075514 -320.315082) (xy 343.067894 -320.306288) (xy 343.047003 -320.296098)
			(xy 343.035382 -320.295524) (xy 342.955626 -320.295524) (xy 342.943996 -320.296084) (xy 342.923086 -320.306257)
			(xy 342.915494 -320.315082) (xy 342.898741 -320.335865) (xy 342.860387 -320.372995) (xy 342.817233 -320.404417)
			(xy 342.770119 -320.429516) (xy 342.719967 -320.447802) (xy 342.667756 -320.458919) (xy 342.614504 -320.462649)
			(xy 342.561252 -320.458919) (xy 342.509041 -320.447802) (xy 342.458889 -320.429516) (xy 342.411775 -320.404417)
			(xy 342.368621 -320.372995) (xy 342.330267 -320.335865) (xy 342.313514 -320.315082) (xy 342.305894 -320.306288)
			(xy 342.285003 -320.296098) (xy 342.273382 -320.295524) (xy 342.193626 -320.295524) (xy 342.181996 -320.296084)
			(xy 342.161086 -320.306257) (xy 342.153494 -320.315082) (xy 342.136741 -320.335865) (xy 342.098387 -320.372995)
			(xy 342.055233 -320.404417) (xy 342.008119 -320.429516) (xy 341.957967 -320.447802) (xy 341.905756 -320.458919)
			(xy 341.852504 -320.462649) (xy 341.799252 -320.458919) (xy 341.747041 -320.447802) (xy 341.696889 -320.429516)
			(xy 341.649775 -320.404417) (xy 341.606621 -320.372995) (xy 341.568267 -320.335865) (xy 341.551514 -320.315082)
			(xy 341.543894 -320.306288) (xy 341.523003 -320.296098) (xy 341.511382 -320.295524) (xy 341.431626 -320.295524)
			(xy 341.419996 -320.296084) (xy 341.399086 -320.306257) (xy 341.391494 -320.315082) (xy 341.374741 -320.335865)
			(xy 341.336387 -320.372995) (xy 341.293233 -320.404417) (xy 341.246119 -320.429516) (xy 341.195967 -320.447802)
			(xy 341.143756 -320.458919) (xy 341.090504 -320.462649) (xy 341.037252 -320.458919) (xy 340.985041 -320.447802)
			(xy 340.934889 -320.429516) (xy 340.887775 -320.404417) (xy 340.844621 -320.372995) (xy 340.806267 -320.335865)
			(xy 340.789514 -320.315082) (xy 340.781894 -320.306288) (xy 340.761003 -320.296098) (xy 340.749382 -320.295524)
			(xy 340.669626 -320.295524) (xy 340.657996 -320.296084) (xy 340.637086 -320.306257) (xy 340.629494 -320.315082)
			(xy 340.612741 -320.335865) (xy 340.574387 -320.372995) (xy 340.531233 -320.404417) (xy 340.484119 -320.429516)
			(xy 340.433967 -320.447802) (xy 340.381756 -320.458919) (xy 340.328504 -320.462649) (xy 340.275252 -320.458919)
			(xy 340.223041 -320.447802) (xy 340.172889 -320.429516) (xy 340.125775 -320.404417) (xy 340.082621 -320.372995)
			(xy 340.044267 -320.335865) (xy 340.027514 -320.315082) (xy 340.019894 -320.306288) (xy 339.999003 -320.296098)
			(xy 339.987382 -320.295524) (xy 339.907626 -320.295524) (xy 339.895996 -320.296084) (xy 339.875086 -320.306257)
			(xy 339.867494 -320.315082) (xy 339.850741 -320.335865) (xy 339.812387 -320.372995) (xy 339.769233 -320.404417)
			(xy 339.722119 -320.429516) (xy 339.671967 -320.447802) (xy 339.619756 -320.458919) (xy 339.566504 -320.462649)
			(xy 339.513252 -320.458919) (xy 339.461041 -320.447802) (xy 339.410889 -320.429516) (xy 339.363775 -320.404417)
			(xy 339.320621 -320.372995) (xy 339.282267 -320.335865) (xy 339.265514 -320.315082) (xy 339.257894 -320.306288)
			(xy 339.237003 -320.296098) (xy 339.225382 -320.295524) (xy 339.145626 -320.295524) (xy 339.133996 -320.296084)
			(xy 339.113086 -320.306257) (xy 339.105494 -320.315082) (xy 339.087302 -320.337565) (xy 339.045283 -320.377301)
			(xy 338.997748 -320.41024) (xy 338.945787 -320.435629) (xy 338.89059 -320.452885) (xy 338.83342 -320.461614)
			(xy 338.804504 -320.462148) (xy 338.777255 -320.461619) (xy 338.723311 -320.453864) (xy 338.671019 -320.438511)
			(xy 338.621445 -320.415873) (xy 338.575596 -320.386411) (xy 338.534407 -320.350724) (xy 338.498715 -320.309539)
			(xy 338.469248 -320.263694) (xy 338.446604 -320.214122) (xy 338.431246 -320.161832) (xy 338.423485 -320.107889)
			(xy 338.422996 -320.08064) (xy 333.183484 -320.08064) (xy 333.183484 -323.198236) (xy 333.182929 -323.244292)
			(xy 333.174389 -323.336009) (xy 333.157431 -323.426548) (xy 333.132199 -323.515139) (xy 333.098908 -323.601026)
			(xy 333.078836 -323.642482) (xy 333.02956 -323.74078) (xy 333.025325 -323.750538) (xy 333.024377 -323.771763)
			(xy 333.032076 -323.791566) (xy 333.039212 -323.799454) (xy 334.8482 -325.608442) (xy 334.853629 -325.613425)
			(xy 334.866667 -325.620277) (xy 334.873854 -325.621904) (xy 334.874362 -325.621904) (xy 334.88376 -325.62292)
		)
		(stroke
			(width 0)
			(type solid)
		)
		(fill yes)
		(layer "In11.Cu")
		(net "GND")
	)
	(gr_poly
		(pts
			(xy 113.914682 -325.925434) (xy 113.91519 -325.925434) (xy 113.92235 -325.92373) (xy 113.935378 -325.916899)
			(xy 113.940844 -325.911972) (xy 114.21491 -325.637906) (xy 114.222309 -325.631061) (xy 114.240907 -325.623329)
			(xy 114.250978 -325.62292) (xy 114.716052 -325.62292) (xy 114.726207 -325.62247) (xy 114.744937 -325.61461)
			(xy 114.752374 -325.60768) (xy 114.752882 -325.607172) (xy 114.776126 -325.584581) (xy 114.826814 -325.544175)
			(xy 114.881705 -325.509696) (xy 114.940109 -325.481576) (xy 115.001294 -325.460168) (xy 115.06449 -325.445742)
			(xy 115.128903 -325.438478) (xy 115.161314 -325.438008) (xy 119.096536 -325.438008) (xy 119.128945 -325.438479)
			(xy 119.193352 -325.445764) (xy 119.256542 -325.460203) (xy 119.31772 -325.481617) (xy 119.376121 -325.509736)
			(xy 119.431013 -325.544208) (xy 119.481706 -325.584601) (xy 119.504968 -325.607172) (xy 119.505476 -325.60768)
			(xy 119.5129 -325.614633) (xy 119.531636 -325.622502) (xy 119.541798 -325.62292) (xy 129.87147 -325.62292)
			(xy 129.881535 -325.622485) (xy 129.900123 -325.614755) (xy 129.907538 -325.607934) (xy 129.93497 -325.580502)
			(xy 129.94182 -325.573105) (xy 129.94956 -325.554507) (xy 129.949956 -325.544434) (xy 129.949956 -318.799718)
			(xy 129.950361 -318.767566) (xy 129.957394 -318.70365) (xy 129.971421 -318.640896) (xy 129.992271 -318.580068)
			(xy 130.005582 -318.550798) (xy 130.123946 -318.3001) (xy 130.124962 -318.298068) (xy 130.673602 -316.973458)
			(xy 130.672947 -316.968751) (xy 130.670141 -316.959673) (xy 130.668014 -316.955424) (xy 130.664712 -316.949074)
			(xy 130.656076 -316.932818) (xy 130.653317 -316.927899) (xy 130.64601 -316.919313) (xy 130.641598 -316.9158)
			(xy 130.632708 -316.909196) (xy 130.621532 -316.90691) (xy 130.59325 -316.900517) (xy 130.538895 -316.880331)
			(xy 130.488221 -316.852152) (xy 130.442394 -316.816629) (xy 130.402471 -316.774581) (xy 130.369371 -316.726976)
			(xy 130.343855 -316.67491) (xy 130.326513 -316.619582) (xy 130.317742 -316.562267) (xy 130.31724 -316.533276)
			(xy 130.317705 -316.506026) (xy 130.325465 -316.45208) (xy 130.340824 -316.399788) (xy 130.363468 -316.350213)
			(xy 130.392938 -316.304367) (xy 130.428632 -316.263181) (xy 130.469825 -316.227494) (xy 130.515677 -316.198034)
			(xy 130.565255 -316.175398) (xy 130.61755 -316.16005) (xy 130.671497 -316.1523) (xy 130.698748 -316.151768)
			(xy 130.699256 -316.151768) (xy 130.726098 -316.152237) (xy 130.77925 -316.159788) (xy 130.830816 -316.174719)
			(xy 130.879779 -316.196736) (xy 130.90271 -316.210696) (xy 130.908552 -316.214506) (xy 130.936746 -316.222888)
			(xy 130.946652 -316.221872) (xy 130.976878 -316.212728) (xy 130.980982 -316.211217) (xy 130.988642 -316.207)
			(xy 130.992118 -316.204346) (xy 131.936998 -313.92368) (xy 131.936023 -313.917256) (xy 131.931259 -313.905173)
			(xy 131.9276 -313.899804) (xy 131.923282 -313.894724) (xy 131.91363 -313.884564) (xy 131.888992 -313.858402)
			(xy 131.881557 -313.851782) (xy 131.863124 -313.844321) (xy 131.853178 -313.843924) (xy 131.8387 -313.84621)
			(xy 131.834636 -313.84748) (xy 131.80555 -313.856487) (xy 131.745444 -313.866194) (xy 131.715002 -313.866784)
			(xy 131.714748 -313.866784) (xy 131.687495 -313.866324) (xy 131.633542 -313.858573) (xy 131.581242 -313.843222)
			(xy 131.531659 -313.820584) (xy 131.485802 -313.791119) (xy 131.444606 -313.755428) (xy 131.40891 -313.714236)
			(xy 131.379439 -313.668384) (xy 131.356795 -313.618803) (xy 131.341437 -313.566505) (xy 131.333679 -313.512553)
			(xy 131.333679 -313.458047) (xy 131.341437 -313.404095) (xy 131.356795 -313.351797) (xy 131.379439 -313.302216)
			(xy 131.40891 -313.256364) (xy 131.444606 -313.215172) (xy 131.485802 -313.179481) (xy 131.531659 -313.150016)
			(xy 131.581242 -313.127378) (xy 131.633542 -313.112027) (xy 131.687495 -313.104276) (xy 131.714748 -313.103768)
			(xy 131.742139 -313.104243) (xy 131.796356 -313.112079) (xy 131.848898 -313.127582) (xy 131.898685 -313.150435)
			(xy 131.944694 -313.180169) (xy 131.985983 -313.216172) (xy 132.021702 -313.257706) (xy 132.03682 -313.280552)
			(xy 132.04063 -313.286394) (xy 132.051044 -313.296046) (xy 132.05714 -313.299094) (xy 132.063425 -313.301878)
			(xy 132.076947 -313.304318) (xy 132.08381 -313.30392) (xy 132.17398 -313.2963) (xy 132.181346 -313.295407)
			(xy 132.19515 -313.289986) (xy 132.201158 -313.285632) (xy 132.756656 -311.944512) (xy 132.756015 -311.94007)
			(xy 132.753338 -311.931504) (xy 132.751322 -311.927494) (xy 132.710936 -311.855612) (xy 132.707949 -311.85068)
			(xy 132.700117 -311.842224) (xy 132.695442 -311.838848) (xy 132.686044 -311.832244) (xy 132.68071 -311.831482)
			(xy 132.653546 -311.827401) (xy 132.600691 -311.812454) (xy 132.550526 -311.790081) (xy 132.504088 -311.760744)
			(xy 132.462338 -311.72505) (xy 132.426138 -311.683737) (xy 132.396239 -311.63766) (xy 132.373256 -311.587771)
			(xy 132.357667 -311.535101) (xy 132.349792 -311.48074) (xy 132.34924 -311.453276) (xy 132.349705 -311.426026)
			(xy 132.357465 -311.37208) (xy 132.372824 -311.319788) (xy 132.395468 -311.270213) (xy 132.424938 -311.224367)
			(xy 132.460632 -311.183181) (xy 132.501825 -311.147494) (xy 132.547677 -311.118034) (xy 132.597255 -311.095398)
			(xy 132.64955 -311.08005) (xy 132.703497 -311.0723) (xy 132.730748 -311.071768) (xy 132.757435 -311.072237)
			(xy 132.810289 -311.079671) (xy 132.861594 -311.094389) (xy 132.910351 -311.116103) (xy 132.955613 -311.144391)
			(xy 132.976366 -311.161176) (xy 132.984748 -311.168034) (xy 133.005322 -311.17413) (xy 133.09092 -311.161938)
			(xy 133.101542 -311.159991) (xy 133.11983 -311.148542) (xy 133.126226 -311.13984) (xy 134.781544 -308.662324)
			(xy 134.783068 -308.660292) (xy 135.67537 -307.170836) (xy 136.280652 -306.161186) (xy 136.284716 -306.149756)
			(xy 136.285986 -306.13858) (xy 136.285986 -279.457658) (xy 136.285164 -279.449232) (xy 136.278808 -279.433552)
			(xy 136.27354 -279.426924) (xy 136.249156 -279.40254) (xy 136.245092 -279.398984) (xy 136.242806 -279.39746)
			(xy 136.237343 -279.393953) (xy 136.225124 -279.389579) (xy 136.218676 -279.388824) (xy 136.214866 -279.388824)
			(xy 136.137441 -279.387541) (xy 135.982822 -279.378773) (xy 135.905748 -279.371298) (xy 135.823421 -279.362347)
			(xy 135.659688 -279.3374) (xy 135.497375 -279.304459) (xy 135.336871 -279.263605) (xy 135.178561 -279.214936)
			(xy 135.022826 -279.158569) (xy 134.87004 -279.094638) (xy 134.720571 -279.023298) (xy 134.647432 -278.984456)
			(xy 134.646924 -278.984202) (xy 134.640764 -278.981172) (xy 134.62737 -278.978197) (xy 134.620508 -278.97836)
			(xy 134.606538 -278.979122) (xy 134.556754 -279.013412) (xy 134.517638 -279.040336) (xy 134.512821 -279.044277)
			(xy 134.505104 -279.054036) (xy 134.502398 -279.05964) (xy 134.499604 -279.06599) (xy 134.497572 -279.07869)
			(xy 134.49808 -279.083262) (xy 134.498588 -279.087072) (xy 134.499858 -279.098502) (xy 134.50062 -279.107646)
			(xy 134.50062 -279.108916) (xy 134.501636 -279.135078) (xy 134.501636 -280.148538) (xy 134.501083 -280.17852)
			(xy 134.491708 -280.237746) (xy 134.473179 -280.294776) (xy 134.445953 -280.348202) (xy 134.4107 -280.39671)
			(xy 134.389876 -280.418286) (xy 134.318248 -280.489914) (xy 134.311775 -280.498343) (xy 134.305726 -280.51869)
			(xy 134.306564 -280.529284) (xy 134.319264 -280.58364) (xy 134.319264 -280.584148) (xy 134.328662 -280.622248)
			(xy 134.330406 -280.627473) (xy 134.335786 -280.637081) (xy 134.33933 -280.641298) (xy 134.343394 -280.645616)
			(xy 134.353808 -280.652474) (xy 134.360666 -280.655014) (xy 134.361428 -280.655268) (xy 134.386266 -280.664174)
			(xy 134.433416 -280.687859) (xy 134.476856 -280.71781) (xy 134.51576 -280.753455) (xy 134.549387 -280.794117)
			(xy 134.577097 -280.839021) (xy 134.598361 -280.887311) (xy 134.612775 -280.938069) (xy 134.620064 -280.990328)
			(xy 134.620508 -281.01671) (xy 134.620003 -281.044446) (xy 134.611957 -281.099332) (xy 134.596052 -281.152475)
			(xy 134.572622 -281.202756) (xy 134.54216 -281.249116) (xy 134.505308 -281.290579) (xy 134.462843 -281.32627)
			(xy 134.415659 -281.355439) (xy 134.364749 -281.377471) (xy 134.311187 -281.391901) (xy 134.283704 -281.395678)
			(xy 134.269988 -281.397202) (xy 134.239 -281.398472) (xy 134.210235 -281.397957) (xy 134.153356 -281.389335)
			(xy 134.098415 -281.372273) (xy 134.046658 -281.347156) (xy 133.999258 -281.314554) (xy 133.95729 -281.275206)
			(xy 133.921704 -281.230003) (xy 133.893308 -281.17997) (xy 133.872744 -281.126242) (xy 133.866128 -281.098244)
			(xy 133.863588 -281.086306) (xy 133.857492 -281.077924) (xy 133.854613 -281.074202) (xy 133.847705 -281.067814)
			(xy 133.843776 -281.065224) (xy 133.807962 -281.045158) (xy 133.774434 -281.026616) (xy 133.769634 -281.024074)
			(xy 133.759258 -281.020872) (xy 133.75386 -281.020266) (xy 133.743192 -281.019504) (xy 133.732778 -281.02306)
			(xy 133.701793 -281.033435) (xy 133.637429 -281.044678) (xy 133.604762 -281.045412) (xy 133.434836 -281.045412)
			(xy 133.425111 -281.045887) (xy 133.407076 -281.053186) (xy 133.399784 -281.059636) (xy 133.038088 -281.421586)
			(xy 133.01876 -281.440259) (xy 132.975798 -281.472544) (xy 132.928731 -281.498483) (xy 132.87849 -281.517561)
			(xy 132.82607 -281.529402) (xy 132.799328 -281.532076) (xy 132.782564 -281.533346) (xy 132.768848 -281.533346)
			(xy 132.741605 -281.5329) (xy 132.687663 -281.525227) (xy 132.635361 -281.509958) (xy 132.585763 -281.487404)
			(xy 132.539878 -281.458024) (xy 132.498639 -281.422416) (xy 132.462885 -281.381303) (xy 132.433343 -281.335522)
			(xy 132.410614 -281.286004) (xy 132.395161 -281.233756) (xy 132.387297 -281.179842) (xy 132.386832 -281.1526)
			(xy 132.386832 -281.147012) (xy 132.387959 -281.114148) (xy 132.400098 -281.049525) (xy 132.410962 -281.018488)
			(xy 132.413248 -281.012138) (xy 132.414518 -281.000962) (xy 132.413756 -280.99512) (xy 132.412969 -280.989389)
			(xy 132.409122 -280.978484) (xy 132.406136 -280.97353) (xy 132.39877 -280.9621) (xy 132.359654 -280.901902)
			(xy 132.356526 -280.897904) (xy 132.348978 -280.89112) (xy 132.344668 -280.88844) (xy 132.33527 -280.882852)
			(xy 132.322316 -280.881836) (xy 132.322062 -280.881836) (xy 132.290892 -280.879067) (xy 132.230003 -280.864645)
			(xy 132.200904 -280.853134) (xy 132.190744 -280.848816) (xy 132.18033 -280.84907) (xy 132.175646 -280.849229)
			(xy 132.166446 -280.851022) (xy 132.162042 -280.852626) (xy 132.125212 -280.870152) (xy 132.090922 -280.886662)
			(xy 132.086175 -280.889029) (xy 132.077722 -280.895433) (xy 132.074158 -280.899362) (xy 132.0673 -280.90749)
			(xy 132.064252 -280.918158) (xy 132.056066 -280.944128) (xy 132.033359 -280.993619) (xy 132.003853 -281.039384)
			(xy 131.968147 -281.080494) (xy 131.926965 -281.116117) (xy 131.881141 -281.14553) (xy 131.831604 -281.168137)
			(xy 131.779358 -281.183479) (xy 131.725463 -281.191246) (xy 131.698238 -281.191716) (xy 131.674882 -281.191349)
			(xy 131.628524 -281.185618) (xy 131.605782 -281.180286) (xy 131.59613 -281.178) (xy 131.586986 -281.17927)
			(xy 131.582827 -281.179874) (xy 131.574781 -281.182295) (xy 131.570984 -281.184096) (xy 131.505452 -281.221688)
			(xy 131.499356 -281.22626) (xy 131.492244 -281.233626) (xy 131.486656 -281.240738) (xy 131.483608 -281.250644)
			(xy 131.475537 -281.276737) (xy 131.45297 -281.326475) (xy 131.423545 -281.372489) (xy 131.38786 -281.413838)
			(xy 131.346647 -281.449678) (xy 131.300745 -281.479278) (xy 131.251093 -281.502032) (xy 131.198704 -281.517477)
			(xy 131.144649 -281.525296) (xy 131.11734 -281.525726) (xy 131.090085 -281.525266) (xy 131.036129 -281.517514)
			(xy 130.983825 -281.502161) (xy 130.934238 -281.479521) (xy 130.888379 -281.450055) (xy 130.84718 -281.414361)
			(xy 130.81148 -281.373168) (xy 130.782007 -281.327313) (xy 130.759359 -281.27773) (xy 130.743999 -281.225428)
			(xy 130.736238 -281.171473) (xy 130.735832 -281.144218) (xy 130.73587 -281.133465) (xy 130.737014 -281.111989)
			(xy 130.738118 -281.101292) (xy 130.739134 -281.09164) (xy 130.737102 -281.083258) (xy 130.735989 -281.079237)
			(xy 130.732667 -281.071583) (xy 130.730498 -281.068018) (xy 130.688842 -281.010868) (xy 130.688334 -281.010106)
			(xy 130.685428 -281.006462) (xy 130.678525 -281.000201) (xy 130.674618 -280.99766) (xy 130.666744 -280.992834)
			(xy 130.661156 -280.991564) (xy 130.635447 -280.986079) (xy 130.585735 -280.968985) (xy 130.538842 -280.945227)
			(xy 130.495655 -280.915255) (xy 130.456993 -280.879637) (xy 130.423587 -280.839048) (xy 130.39607 -280.794256)
			(xy 130.374965 -280.746111) (xy 130.36067 -280.695523) (xy 130.353456 -280.643452) (xy 130.353054 -280.617168)
			(xy 130.35354 -280.589917) (xy 130.361296 -280.535969) (xy 130.376651 -280.483674) (xy 130.399293 -280.434097)
			(xy 130.428759 -280.388247) (xy 130.46445 -280.347056) (xy 130.505641 -280.311365) (xy 130.551491 -280.281899)
			(xy 130.601068 -280.259257) (xy 130.653363 -280.243902) (xy 130.707311 -280.236146) (xy 130.761813 -280.236146)
			(xy 130.815761 -280.243902) (xy 130.868056 -280.259257) (xy 130.917633 -280.281899) (xy 130.963483 -280.311365)
			(xy 131.004674 -280.347056) (xy 131.040365 -280.388247) (xy 131.069831 -280.434097) (xy 131.092473 -280.483674)
			(xy 131.107828 -280.535969) (xy 131.115584 -280.589917) (xy 131.11607 -280.617168) (xy 131.116033 -280.627921)
			(xy 131.114889 -280.649397) (xy 131.113784 -280.660094) (xy 131.112768 -280.669746) (xy 131.1148 -280.678128)
			(xy 131.115912 -280.68215) (xy 131.119233 -280.689805) (xy 131.121404 -280.693368) (xy 131.16306 -280.750518)
			(xy 131.163568 -280.75128) (xy 131.166474 -280.754924) (xy 131.173376 -280.761187) (xy 131.177284 -280.763726)
			(xy 131.185158 -280.768552) (xy 131.191762 -280.770076) (xy 131.194302 -280.770584) (xy 131.209796 -280.77414)
			(xy 131.219448 -280.776426) (xy 131.228592 -280.775156) (xy 131.232749 -280.774546) (xy 131.24079 -280.772115)
			(xy 131.244594 -280.77033) (xy 131.310126 -280.732738) (xy 131.316222 -280.728166) (xy 131.323334 -280.7208)
			(xy 131.328922 -280.713688) (xy 131.33197 -280.703782) (xy 131.340237 -280.677108) (xy 131.363482 -280.626331)
			(xy 131.393873 -280.579481) (xy 131.430762 -280.537556) (xy 131.473363 -280.501449) (xy 131.520768 -280.471931)
			(xy 131.571966 -280.44963) (xy 131.625865 -280.435022) (xy 131.653534 -280.43124) (xy 131.66725 -280.429716)
			(xy 131.698238 -280.428446) (xy 131.723503 -280.428854) (xy 131.77359 -280.43553) (xy 131.822354 -280.448771)
			(xy 131.845812 -280.458164) (xy 131.855972 -280.462482) (xy 131.865878 -280.462228) (xy 131.870846 -280.46207)
			(xy 131.880573 -280.460025) (xy 131.885182 -280.458164) (xy 131.920742 -280.440892) (xy 131.92125 -280.440892)
			(xy 131.955286 -280.424636) (xy 131.960032 -280.422268) (xy 131.968485 -280.415863) (xy 131.97205 -280.411936)
			(xy 131.978908 -280.403808) (xy 131.981956 -280.39314) (xy 131.990748 -280.365212) (xy 132.015694 -280.312243)
			(xy 132.048437 -280.263706) (xy 132.088209 -280.220738) (xy 132.134076 -280.18435) (xy 132.184963 -280.155393)
			(xy 132.239676 -280.134548) (xy 132.29693 -280.122304) (xy 132.326126 -280.12009) (xy 132.338572 -280.119328)
			(xy 132.34797 -280.113994) (xy 132.352339 -280.111396) (xy 132.360023 -280.104745) (xy 132.36321 -280.100786)
			(xy 132.387594 -280.066496) (xy 132.411978 -280.031952) (xy 132.414612 -280.027671) (xy 132.418316 -280.01833)
			(xy 132.419344 -280.01341) (xy 132.421122 -280.002742) (xy 132.41782 -279.991058) (xy 132.411122 -279.965548)
			(xy 132.403987 -279.91329) (xy 132.403596 -279.886918) (xy 132.40408 -279.859683) (xy 132.411829 -279.805766)
			(xy 132.427172 -279.753501) (xy 132.449797 -279.703952) (xy 132.479242 -279.658126) (xy 132.514909 -279.616957)
			(xy 132.556072 -279.581283) (xy 132.601892 -279.551829) (xy 132.651438 -279.529196) (xy 132.7037 -279.513844)
			(xy 132.757615 -279.506085) (xy 132.78485 -279.505664) (xy 132.785358 -279.505664) (xy 132.815272 -279.506275)
			(xy 132.87436 -279.515669) (xy 132.931258 -279.534172) (xy 132.984569 -279.561328) (xy 133.032989 -279.596474)
			(xy 133.054598 -279.61717) (xy 133.272784 -279.83561) (xy 133.279683 -279.841244) (xy 133.29621 -279.847852)
			(xy 133.313998 -279.848447) (xy 133.322568 -279.846024) (xy 133.331712 -279.84196) (xy 133.337073 -279.838871)
			(xy 133.346194 -279.830517) (xy 133.349746 -279.82545) (xy 133.353556 -279.819862) (xy 133.355588 -279.81275)
			(xy 133.356539 -279.809271) (xy 133.357562 -279.802132) (xy 133.35762 -279.798526) (xy 133.35762 -279.471628)
			(xy 133.357124 -279.461816) (xy 133.349685 -279.44365) (xy 133.343142 -279.436322) (xy 131.762754 -277.856188)
			(xy 131.735322 -277.828756) (xy 131.717984 -277.810805) (xy 131.687633 -277.771187) (xy 131.662697 -277.727957)
			(xy 131.652772 -277.705058) (xy 131.194048 -276.59711) (xy 130.939794 -275.983192) (xy 130.93954 -275.982684)
			(xy 130.935984 -275.974048) (xy 130.932936 -275.965666) (xy 130.929888 -275.957284) (xy 130.929888 -275.95703)
			(xy 130.927602 -275.949664) (xy 130.919696 -275.922336) (xy 130.911153 -275.866093) (xy 130.910584 -275.83765)
			(xy 130.910584 -268.252956) (xy 130.910074 -268.243053) (xy 130.902506 -268.224746) (xy 130.895852 -268.217396)
			(xy 126.512066 -263.83361) (xy 126.508975 -263.830611) (xy 126.501945 -263.825637) (xy 126.498096 -263.823704)
			(xy 126.496572 -263.823196) (xy 126.495302 -263.822434) (xy 123.295918 -262.497062) (xy 123.291291 -262.495286)
			(xy 123.281569 -262.493362) (xy 123.276614 -262.493252) (xy 122.90044 -262.493252) (xy 122.891156 -262.493648)
			(xy 122.873818 -262.500285) (xy 122.866658 -262.506206) (xy 122.69851 -262.674354) (xy 122.694043 -262.679996)
			(xy 122.688245 -262.69316) (xy 122.68708 -262.700262) (xy 122.686572 -262.70712) (xy 122.686572 -263.18337)
			(xy 122.968764 -263.18337) (xy 122.972835 -263.127748) (xy 122.984961 -263.073311) (xy 123.004884 -263.02122)
			(xy 123.03218 -262.972585) (xy 123.066266 -262.928442) (xy 123.106415 -262.889733) (xy 123.151773 -262.857282)
			(xy 123.201373 -262.831781) (xy 123.254157 -262.813774) (xy 123.309 -262.803644) (xy 123.364734 -262.801607)
			(xy 123.420171 -262.807707) (xy 123.474128 -262.821813) (xy 123.525457 -262.843625) (xy 123.573063 -262.872679)
			(xy 123.615931 -262.908354) (xy 123.653148 -262.949891) (xy 123.683921 -262.996404) (xy 123.707593 -263.046901)
			(xy 123.723661 -263.100308) (xy 123.731781 -263.155484) (xy 123.73229 -263.18337) (xy 123.731781 -263.211256)
			(xy 123.723661 -263.266432) (xy 123.707593 -263.319839) (xy 123.683921 -263.370336) (xy 123.653148 -263.416849)
			(xy 123.615931 -263.458386) (xy 123.573063 -263.494061) (xy 123.525457 -263.523115) (xy 123.474128 -263.544927)
			(xy 123.420171 -263.559033) (xy 123.364734 -263.565133) (xy 123.309 -263.563096) (xy 123.254157 -263.552966)
			(xy 123.201373 -263.534959) (xy 123.151773 -263.509458) (xy 123.106415 -263.477007) (xy 123.066266 -263.438298)
			(xy 123.03218 -263.394155) (xy 123.004884 -263.34552) (xy 122.984961 -263.293429) (xy 122.972835 -263.238992)
			(xy 122.968764 -263.18337) (xy 122.686572 -263.18337) (xy 122.686572 -264.12952) (xy 122.980194 -264.12952)
			(xy 122.984265 -264.073898) (xy 122.996391 -264.019461) (xy 123.016314 -263.96737) (xy 123.04361 -263.918735)
			(xy 123.077696 -263.874592) (xy 123.117845 -263.835883) (xy 123.163203 -263.803432) (xy 123.212803 -263.777931)
			(xy 123.265587 -263.759924) (xy 123.32043 -263.749794) (xy 123.376164 -263.747757) (xy 123.431601 -263.753857)
			(xy 123.485558 -263.767963) (xy 123.536887 -263.789775) (xy 123.584493 -263.818829) (xy 123.627361 -263.854504)
			(xy 123.664578 -263.896041) (xy 123.695351 -263.942554) (xy 123.719023 -263.993051) (xy 123.735091 -264.046458)
			(xy 123.743211 -264.101634) (xy 123.74372 -264.12952) (xy 123.743211 -264.157406) (xy 123.735091 -264.212582)
			(xy 123.719023 -264.265989) (xy 123.695351 -264.316486) (xy 123.664578 -264.362999) (xy 123.627361 -264.404536)
			(xy 123.584493 -264.440211) (xy 123.536887 -264.469265) (xy 123.485558 -264.491077) (xy 123.431601 -264.505183)
			(xy 123.376164 -264.511283) (xy 123.32043 -264.509246) (xy 123.265587 -264.499116) (xy 123.212803 -264.481109)
			(xy 123.163203 -264.455608) (xy 123.117845 -264.423157) (xy 123.077696 -264.384448) (xy 123.04361 -264.340305)
			(xy 123.016314 -264.29167) (xy 122.996391 -264.239579) (xy 122.984265 -264.185142) (xy 122.980194 -264.12952)
			(xy 122.686572 -264.12952) (xy 122.686572 -265.453876) (xy 122.687334 -265.46175) (xy 122.687334 -265.462258)
			(xy 122.689112 -265.469624) (xy 122.691081 -265.475067) (xy 122.697108 -265.484944) (xy 122.70105 -265.489182)
			(xy 123.599194 -266.387326) (xy 123.599194 -266.387834) (xy 123.706382 -266.494768) (xy 123.727118 -266.516344)
			(xy 123.762282 -266.564761) (xy 123.789444 -266.618079) (xy 123.807937 -266.674988) (xy 123.817306 -266.734089)
			(xy 123.817888 -266.764008) (xy 123.817888 -269.417038) (xy 124.88545 -269.417038) (xy 124.885949 -269.388298)
			(xy 124.89458 -269.33147) (xy 124.911636 -269.27658) (xy 124.936733 -269.224869) (xy 124.969302 -269.177507)
			(xy 124.988574 -269.15618) (xy 124.995178 -269.149322) (xy 125.00229 -269.131288) (xy 125.00229 -269.042388)
			(xy 124.995178 -269.024354) (xy 124.988574 -269.017496) (xy 124.969327 -268.996148) (xy 124.936756 -268.948792)
			(xy 124.911659 -268.897086) (xy 124.894602 -268.8422) (xy 124.885974 -268.785376) (xy 124.88545 -268.756638)
			(xy 124.886013 -268.72939) (xy 124.893764 -268.675447) (xy 124.909112 -268.623156) (xy 124.931746 -268.573582)
			(xy 124.961204 -268.527733) (xy 124.996887 -268.486544) (xy 125.038069 -268.450852) (xy 125.083912 -268.421384)
			(xy 125.133481 -268.39874) (xy 125.185769 -268.383381) (xy 125.23971 -268.375619) (xy 125.266958 -268.37513)
			(xy 125.294328 -268.375613) (xy 125.348506 -268.383426) (xy 125.40101 -268.398911) (xy 125.450757 -268.421749)
			(xy 125.496724 -268.45147) (xy 125.517656 -268.46911) (xy 125.51791 -268.469364) (xy 125.524984 -268.474968)
			(xy 125.541911 -268.481203) (xy 125.55093 -268.481556) (xy 125.617986 -268.481556) (xy 125.627003 -268.481202)
			(xy 125.643921 -268.474953) (xy 125.651006 -268.469364) (xy 125.651006 -268.46911) (xy 125.65126 -268.46911)
			(xy 125.672193 -268.451469) (xy 125.718161 -268.421745) (xy 125.767907 -268.398899) (xy 125.820409 -268.383403)
			(xy 125.874587 -268.375574) (xy 125.929329 -268.375574) (xy 125.983507 -268.383403) (xy 126.036009 -268.398899)
			(xy 126.085755 -268.421745) (xy 126.131723 -268.451469) (xy 126.152656 -268.46911) (xy 126.15291 -268.469364)
			(xy 126.159984 -268.474968) (xy 126.176911 -268.481203) (xy 126.18593 -268.481556) (xy 126.252986 -268.481556)
			(xy 126.262003 -268.481202) (xy 126.278921 -268.474953) (xy 126.286006 -268.469364) (xy 126.286006 -268.46911)
			(xy 126.28626 -268.46911) (xy 126.307193 -268.451469) (xy 126.353161 -268.421745) (xy 126.402907 -268.398899)
			(xy 126.455409 -268.383403) (xy 126.509587 -268.375574) (xy 126.564329 -268.375574) (xy 126.618507 -268.383403)
			(xy 126.671009 -268.398899) (xy 126.720755 -268.421745) (xy 126.766723 -268.451469) (xy 126.787656 -268.46911)
			(xy 126.78791 -268.469364) (xy 126.794984 -268.474968) (xy 126.811911 -268.481203) (xy 126.82093 -268.481556)
			(xy 126.887986 -268.481556) (xy 126.897003 -268.481202) (xy 126.913921 -268.474953) (xy 126.921006 -268.469364)
			(xy 126.921006 -268.46911) (xy 126.92126 -268.46911) (xy 126.942193 -268.451469) (xy 126.988161 -268.421745)
			(xy 127.037907 -268.398899) (xy 127.090409 -268.383403) (xy 127.144587 -268.375574) (xy 127.199329 -268.375574)
			(xy 127.253507 -268.383403) (xy 127.306009 -268.398899) (xy 127.355755 -268.421745) (xy 127.401723 -268.451469)
			(xy 127.422656 -268.46911) (xy 127.42291 -268.469364) (xy 127.429984 -268.474968) (xy 127.446911 -268.481203)
			(xy 127.45593 -268.481556) (xy 127.522986 -268.481556) (xy 127.532003 -268.481202) (xy 127.548921 -268.474953)
			(xy 127.556006 -268.469364) (xy 127.556006 -268.46911) (xy 127.55626 -268.46911) (xy 127.577198 -268.451478)
			(xy 127.623169 -268.421765) (xy 127.672915 -268.398927) (xy 127.725414 -268.383434) (xy 127.779589 -268.375605)
			(xy 127.806958 -268.37513) (xy 127.834212 -268.375594) (xy 127.888164 -268.383347) (xy 127.940465 -268.398699)
			(xy 127.990047 -268.42134) (xy 128.035902 -268.450807) (xy 128.077096 -268.486501) (xy 128.112791 -268.527695)
			(xy 128.142258 -268.573549) (xy 128.164899 -268.623132) (xy 128.180252 -268.675432) (xy 128.188005 -268.729384)
			(xy 128.188466 -268.756638) (xy 128.187948 -268.785377) (xy 128.179321 -268.842204) (xy 128.162269 -268.897094)
			(xy 128.137177 -268.948805) (xy 128.104612 -268.996168) (xy 128.085342 -269.017496) (xy 128.078738 -269.024354)
			(xy 128.071626 -269.042388) (xy 128.071626 -269.131288) (xy 128.078738 -269.149322) (xy 128.085342 -269.15618)
			(xy 128.104627 -269.177494) (xy 128.137192 -269.224859) (xy 128.162282 -269.276574) (xy 128.17933 -269.331468)
			(xy 128.187948 -269.388298) (xy 128.188466 -269.417038) (xy 128.18808 -269.444294) (xy 128.180317 -269.49825)
			(xy 128.164954 -269.550552) (xy 128.142304 -269.600135) (xy 128.112828 -269.64599) (xy 128.077126 -269.687183)
			(xy 128.035926 -269.722876) (xy 127.990064 -269.752343) (xy 127.940477 -269.774982) (xy 127.888171 -269.790334)
			(xy 127.834214 -269.798086) (xy 127.806958 -269.798546) (xy 127.779588 -269.798059) (xy 127.72541 -269.790248)
			(xy 127.672906 -269.774765) (xy 127.623159 -269.751927) (xy 127.577192 -269.722206) (xy 127.55626 -269.704566)
			(xy 127.556006 -269.704312) (xy 127.548921 -269.698723) (xy 127.532003 -269.692477) (xy 127.522986 -269.69212)
			(xy 127.45593 -269.69212) (xy 127.446914 -269.692487) (xy 127.429997 -269.698727) (xy 127.42291 -269.704312)
			(xy 127.422656 -269.704566) (xy 127.401723 -269.722207) (xy 127.355755 -269.751931) (xy 127.306009 -269.774777)
			(xy 127.253507 -269.790273) (xy 127.199329 -269.798102) (xy 127.144587 -269.798102) (xy 127.090409 -269.790273)
			(xy 127.037907 -269.774777) (xy 126.988161 -269.751931) (xy 126.942193 -269.722207) (xy 126.92126 -269.704566)
			(xy 126.921006 -269.704312) (xy 126.913921 -269.698723) (xy 126.897003 -269.692477) (xy 126.887986 -269.69212)
			(xy 126.82093 -269.69212) (xy 126.811914 -269.692487) (xy 126.794997 -269.698727) (xy 126.78791 -269.704312)
			(xy 126.78791 -269.704566) (xy 126.787656 -269.704566) (xy 126.766723 -269.722207) (xy 126.720755 -269.751931)
			(xy 126.671009 -269.774777) (xy 126.618507 -269.790273) (xy 126.564329 -269.798102) (xy 126.509587 -269.798102)
			(xy 126.455409 -269.790273) (xy 126.402907 -269.774777) (xy 126.353161 -269.751931) (xy 126.307193 -269.722207)
			(xy 126.28626 -269.704566) (xy 126.286006 -269.704312) (xy 126.278921 -269.698723) (xy 126.262003 -269.692477)
			(xy 126.252986 -269.69212) (xy 126.18593 -269.69212) (xy 126.176914 -269.692487) (xy 126.159997 -269.698727)
			(xy 126.15291 -269.704312) (xy 126.15291 -269.704566) (xy 126.152656 -269.704566) (xy 126.131723 -269.722207)
			(xy 126.085755 -269.751931) (xy 126.036009 -269.774777) (xy 125.983507 -269.790273) (xy 125.929329 -269.798102)
			(xy 125.874587 -269.798102) (xy 125.820409 -269.790273) (xy 125.767907 -269.774777) (xy 125.718161 -269.751931)
			(xy 125.672193 -269.722207) (xy 125.65126 -269.704566) (xy 125.651006 -269.704312) (xy 125.643921 -269.698723)
			(xy 125.627003 -269.692477) (xy 125.617986 -269.69212) (xy 125.55093 -269.69212) (xy 125.541914 -269.692487)
			(xy 125.524997 -269.698727) (xy 125.51791 -269.704312) (xy 125.51791 -269.704566) (xy 125.517656 -269.704566)
			(xy 125.496709 -269.722187) (xy 125.450741 -269.751903) (xy 125.400997 -269.774743) (xy 125.3485 -269.790238)
			(xy 125.294326 -269.79807) (xy 125.266958 -269.798546) (xy 125.239707 -269.798061) (xy 125.185762 -269.7903)
			(xy 125.133469 -269.774942) (xy 125.083894 -269.752298) (xy 125.038046 -269.722831) (xy 124.996857 -269.68714)
			(xy 124.961166 -269.645951) (xy 124.9317 -269.600102) (xy 124.909057 -269.550527) (xy 124.893699 -269.498234)
			(xy 124.885938 -269.444289) (xy 124.88545 -269.417038) (xy 123.817888 -269.417038) (xy 123.817888 -276.046184)
			(xy 124.460254 -276.046184) (xy 124.460698 -276.018813) (xy 124.468519 -275.964632) (xy 124.484012 -275.912128)
			(xy 124.506859 -275.862382) (xy 124.53659 -275.816416) (xy 124.554234 -275.795486) (xy 124.554488 -275.795232)
			(xy 124.560066 -275.788139) (xy 124.566318 -275.771227) (xy 124.56668 -275.762212) (xy 124.56668 -275.695156)
			(xy 124.5663 -275.686141) (xy 124.560069 -275.669224) (xy 124.554488 -275.662136) (xy 124.554234 -275.662136)
			(xy 124.554234 -275.661882) (xy 124.536625 -275.640925) (xy 124.506908 -275.59496) (xy 124.484065 -275.545219)
			(xy 124.468567 -275.492723) (xy 124.460732 -275.438552) (xy 124.460254 -275.411184) (xy 124.460763 -275.383934)
			(xy 124.46852 -275.329989) (xy 124.483876 -275.277697) (xy 124.506516 -275.228122) (xy 124.53598 -275.182274)
			(xy 124.571669 -275.141085) (xy 124.612856 -275.105394) (xy 124.658703 -275.075927) (xy 124.708277 -275.053283)
			(xy 124.760568 -275.037925) (xy 124.814512 -275.030164) (xy 124.841762 -275.029676) (xy 124.869132 -275.030146)
			(xy 124.923312 -275.03796) (xy 124.975816 -275.053447) (xy 125.025563 -275.076288) (xy 125.071529 -275.106014)
			(xy 125.09246 -275.123656) (xy 125.092714 -275.12391) (xy 125.099792 -275.12951) (xy 125.116715 -275.135748)
			(xy 125.125734 -275.136102) (xy 125.19279 -275.136102) (xy 125.201806 -275.13574) (xy 125.218723 -275.129496)
			(xy 125.22581 -275.12391) (xy 125.22581 -275.123656) (xy 125.226064 -275.123656) (xy 125.246997 -275.106015)
			(xy 125.292965 -275.076291) (xy 125.342711 -275.053445) (xy 125.395213 -275.037949) (xy 125.449391 -275.03012)
			(xy 125.504133 -275.03012) (xy 125.558311 -275.037949) (xy 125.610813 -275.053445) (xy 125.660559 -275.076291)
			(xy 125.706527 -275.106015) (xy 125.72746 -275.123656) (xy 125.727714 -275.12391) (xy 125.734792 -275.12951)
			(xy 125.751715 -275.135748) (xy 125.760734 -275.136102) (xy 125.82779 -275.136102) (xy 125.836806 -275.13574)
			(xy 125.853723 -275.129496) (xy 125.86081 -275.12391) (xy 125.86081 -275.123656) (xy 125.861064 -275.123656)
			(xy 125.881997 -275.106015) (xy 125.927965 -275.076291) (xy 125.977711 -275.053445) (xy 126.030213 -275.037949)
			(xy 126.084391 -275.03012) (xy 126.139133 -275.03012) (xy 126.193311 -275.037949) (xy 126.245813 -275.053445)
			(xy 126.295559 -275.076291) (xy 126.341527 -275.106015) (xy 126.36246 -275.123656) (xy 126.362714 -275.12391)
			(xy 126.369792 -275.12951) (xy 126.386715 -275.135748) (xy 126.395734 -275.136102) (xy 126.46279 -275.136102)
			(xy 126.471806 -275.13574) (xy 126.488723 -275.129496) (xy 126.49581 -275.12391) (xy 126.49581 -275.123656)
			(xy 126.496064 -275.123656) (xy 126.516997 -275.106015) (xy 126.562965 -275.076291) (xy 126.612711 -275.053445)
			(xy 126.665213 -275.037949) (xy 126.719391 -275.03012) (xy 126.774133 -275.03012) (xy 126.828311 -275.037949)
			(xy 126.880813 -275.053445) (xy 126.930559 -275.076291) (xy 126.976527 -275.106015) (xy 126.99746 -275.123656)
			(xy 126.997714 -275.12391) (xy 127.004792 -275.12951) (xy 127.021715 -275.135748) (xy 127.030734 -275.136102)
			(xy 127.09779 -275.136102) (xy 127.106806 -275.13574) (xy 127.123723 -275.129496) (xy 127.13081 -275.12391)
			(xy 127.13081 -275.123656) (xy 127.131064 -275.123656) (xy 127.151993 -275.106013) (xy 127.197967 -275.076303)
			(xy 127.247716 -275.053469) (xy 127.300217 -275.037978) (xy 127.354393 -275.03015) (xy 127.381762 -275.029676)
			(xy 127.409013 -275.030191) (xy 127.462961 -275.037942) (xy 127.515257 -275.053292) (xy 127.564836 -275.075929)
			(xy 127.610689 -275.105392) (xy 127.651882 -275.14108) (xy 127.687576 -275.182268) (xy 127.717045 -275.228116)
			(xy 127.739689 -275.277692) (xy 127.755047 -275.329986) (xy 127.762806 -275.383933) (xy 127.76327 -275.411184)
			(xy 127.762802 -275.438554) (xy 127.754986 -275.492734) (xy 127.739497 -275.545237) (xy 127.716656 -275.594984)
			(xy 127.686931 -275.640951) (xy 127.66929 -275.661882) (xy 127.669036 -275.662136) (xy 127.663463 -275.669231)
			(xy 127.65721 -275.686142) (xy 127.656844 -275.695156) (xy 127.656844 -275.762212) (xy 127.657186 -275.771231)
			(xy 127.663443 -275.788148) (xy 127.669036 -275.795232) (xy 127.66929 -275.795232) (xy 127.66929 -275.795486)
			(xy 127.686934 -275.816414) (xy 127.716646 -275.862388) (xy 127.739481 -275.912136) (xy 127.754971 -275.964638)
			(xy 127.762797 -276.018815) (xy 127.76327 -276.046184) (xy 127.76283 -276.073438) (xy 127.755074 -276.127392)
			(xy 127.739718 -276.179693) (xy 127.717075 -276.229275) (xy 127.687605 -276.27513) (xy 127.651908 -276.316324)
			(xy 127.610713 -276.352018) (xy 127.564856 -276.381485) (xy 127.515272 -276.404126) (xy 127.46297 -276.419479)
			(xy 127.409016 -276.427231) (xy 127.381762 -276.427692) (xy 127.354393 -276.427192) (xy 127.300215 -276.419382)
			(xy 127.247712 -276.403901) (xy 127.197965 -276.381067) (xy 127.151997 -276.35135) (xy 127.131064 -276.333712)
			(xy 127.13081 -276.333458) (xy 127.123728 -276.327864) (xy 127.106808 -276.321623) (xy 127.09779 -276.321266)
			(xy 127.030734 -276.321266) (xy 127.02172 -276.321647) (xy 127.004803 -276.327879) (xy 126.997714 -276.333458)
			(xy 126.99746 -276.333712) (xy 126.976527 -276.351353) (xy 126.930559 -276.381077) (xy 126.880813 -276.403923)
			(xy 126.828311 -276.419419) (xy 126.774133 -276.427248) (xy 126.719391 -276.427248) (xy 126.665213 -276.419419)
			(xy 126.612711 -276.403923) (xy 126.562965 -276.381077) (xy 126.516997 -276.351353) (xy 126.496064 -276.333712)
			(xy 126.49581 -276.333458) (xy 126.488728 -276.327864) (xy 126.471808 -276.321623) (xy 126.46279 -276.321266)
			(xy 126.395734 -276.321266) (xy 126.38672 -276.321647) (xy 126.369803 -276.327879) (xy 126.362714 -276.333458)
			(xy 126.362714 -276.333712) (xy 126.36246 -276.333712) (xy 126.341527 -276.351353) (xy 126.295559 -276.381077)
			(xy 126.245813 -276.403923) (xy 126.193311 -276.419419) (xy 126.139133 -276.427248) (xy 126.084391 -276.427248)
			(xy 126.030213 -276.419419) (xy 125.977711 -276.403923) (xy 125.927965 -276.381077) (xy 125.881997 -276.351353)
			(xy 125.861064 -276.333712) (xy 125.86081 -276.333458) (xy 125.853728 -276.327864) (xy 125.836808 -276.321623)
			(xy 125.82779 -276.321266) (xy 125.760734 -276.321266) (xy 125.75172 -276.321647) (xy 125.734803 -276.327879)
			(xy 125.727714 -276.333458) (xy 125.727714 -276.333712) (xy 125.72746 -276.333712) (xy 125.706527 -276.351353)
			(xy 125.660559 -276.381077) (xy 125.610813 -276.403923) (xy 125.558311 -276.419419) (xy 125.504133 -276.427248)
			(xy 125.449391 -276.427248) (xy 125.395213 -276.419419) (xy 125.342711 -276.403923) (xy 125.292965 -276.381077)
			(xy 125.246997 -276.351353) (xy 125.226064 -276.333712) (xy 125.22581 -276.333458) (xy 125.218728 -276.327864)
			(xy 125.201808 -276.321623) (xy 125.19279 -276.321266) (xy 125.125734 -276.321266) (xy 125.11672 -276.321647)
			(xy 125.099803 -276.327879) (xy 125.092714 -276.333458) (xy 125.092714 -276.333712) (xy 125.09246 -276.333712)
			(xy 125.071518 -276.351338) (xy 125.025547 -276.381052) (xy 124.975803 -276.40389) (xy 124.923304 -276.419384)
			(xy 124.86913 -276.427216) (xy 124.841762 -276.427692) (xy 124.814509 -276.427257) (xy 124.760559 -276.419495)
			(xy 124.708262 -276.404135) (xy 124.658684 -276.381488) (xy 124.612833 -276.352016) (xy 124.571642 -276.316319)
			(xy 124.535951 -276.275124) (xy 124.506486 -276.229269) (xy 124.483846 -276.179687) (xy 124.468493 -276.127388)
			(xy 124.460739 -276.073437) (xy 124.460254 -276.046184) (xy 123.817888 -276.046184) (xy 123.817888 -276.291802)
			(xy 123.818311 -276.301872) (xy 123.826025 -276.320477) (xy 123.832874 -276.32787) (xy 124.122688 -276.617684)
			(xy 124.122797 -276.622031) (xy 124.124328 -276.630588) (xy 124.125736 -276.634702) (xy 124.125736 -276.63521)
			(xy 124.131832 -276.647148) (xy 124.135642 -276.651212) (xy 124.136658 -276.652482) (xy 124.138182 -276.65426)
			(xy 125.128274 -277.644352) (xy 127.083566 -277.644352) (xy 127.084012 -277.618037) (xy 127.091253 -277.565908)
			(xy 127.105577 -277.515266) (xy 127.126713 -277.467067) (xy 127.154263 -277.422224) (xy 127.187704 -277.381585)
			(xy 127.206756 -277.363428) (xy 127.214141 -277.355892) (xy 127.222676 -277.336623) (xy 127.223266 -277.32609)
			(xy 127.223266 -277.251414) (xy 127.222753 -277.240862) (xy 127.214208 -277.221566) (xy 127.206756 -277.214076)
			(xy 127.187687 -277.195934) (xy 127.154233 -277.1553) (xy 127.126677 -277.110457) (xy 127.105541 -277.062254)
			(xy 127.091226 -277.011604) (xy 127.084004 -276.959469) (xy 127.083566 -276.933152) (xy 127.084052 -276.905901)
			(xy 127.091808 -276.851953) (xy 127.107163 -276.799658) (xy 127.129805 -276.750081) (xy 127.159271 -276.704231)
			(xy 127.194962 -276.66304) (xy 127.236153 -276.627349) (xy 127.282003 -276.597883) (xy 127.33158 -276.575241)
			(xy 127.383875 -276.559886) (xy 127.437823 -276.55213) (xy 127.492325 -276.55213) (xy 127.546273 -276.559886)
			(xy 127.598568 -276.575241) (xy 127.648145 -276.597883) (xy 127.693995 -276.627349) (xy 127.735186 -276.66304)
			(xy 127.770877 -276.704231) (xy 127.800343 -276.750081) (xy 127.822985 -276.799658) (xy 127.83834 -276.851953)
			(xy 127.846096 -276.905901) (xy 127.846582 -276.933152) (xy 127.846155 -276.959467) (xy 127.838913 -277.011598)
			(xy 127.824586 -277.062242) (xy 127.803446 -277.110441) (xy 127.775893 -277.155283) (xy 127.742447 -277.195921)
			(xy 127.723392 -277.214076) (xy 127.715998 -277.221604) (xy 127.70747 -277.240879) (xy 127.706882 -277.251414)
			(xy 127.706882 -277.32609) (xy 127.707408 -277.33664) (xy 127.715946 -277.355935) (xy 127.723392 -277.363428)
			(xy 127.742453 -277.381579) (xy 127.77591 -277.422209) (xy 127.803468 -277.46705) (xy 127.824606 -277.515252)
			(xy 127.838922 -277.565901) (xy 127.846145 -277.618036) (xy 127.846582 -277.644352) (xy 127.846096 -277.671603)
			(xy 127.83834 -277.725551) (xy 127.822985 -277.777846) (xy 127.800343 -277.827423) (xy 127.770877 -277.873273)
			(xy 127.735186 -277.914464) (xy 127.693995 -277.950155) (xy 127.648145 -277.979621) (xy 127.598568 -278.002263)
			(xy 127.546273 -278.017618) (xy 127.492325 -278.025374) (xy 127.437823 -278.025374) (xy 127.383875 -278.017618)
			(xy 127.33158 -278.002263) (xy 127.282003 -277.979621) (xy 127.236153 -277.950155) (xy 127.194962 -277.914464)
			(xy 127.159271 -277.873273) (xy 127.129805 -277.827423) (xy 127.107163 -277.777846) (xy 127.091808 -277.725551)
			(xy 127.084052 -277.671603) (xy 127.083566 -277.644352) (xy 125.128274 -277.644352) (xy 126.454408 -278.970486)
			(xy 126.475185 -278.992101) (xy 126.51042 -279.040608) (xy 126.537636 -279.094027) (xy 126.556164 -279.151044)
			(xy 126.565549 -279.210258) (xy 126.566168 -279.240234) (xy 126.566168 -280.138886) (xy 126.565611 -280.168867)
			(xy 126.55623 -280.22809) (xy 126.537697 -280.285115) (xy 126.510468 -280.338538) (xy 126.475215 -280.387042)
			(xy 126.454408 -280.408634) (xy 126.31039 -280.552652) (xy 126.307191 -280.55602) (xy 126.301952 -280.563689)
			(xy 126.299976 -280.567892) (xy 126.299976 -280.5684) (xy 126.297749 -280.573839) (xy 126.295565 -280.585384)
			(xy 126.295658 -280.59126) (xy 126.297182 -280.620978) (xy 126.297182 -280.621486) (xy 126.299976 -280.67)
			(xy 126.300585 -280.674364) (xy 126.303133 -280.682799) (xy 126.305056 -280.686764) (xy 126.309628 -280.695654)
			(xy 126.318264 -280.702766) (xy 126.318772 -280.703274) (xy 126.34042 -280.721505) (xy 126.378618 -280.763265)
			(xy 126.410235 -280.810205) (xy 126.434578 -280.861297) (xy 126.451115 -280.915422) (xy 126.459483 -280.971395)
			(xy 126.459996 -280.999692) (xy 126.459533 -281.026945) (xy 126.451777 -281.080896) (xy 126.436422 -281.133194)
			(xy 126.413779 -281.182775) (xy 126.384311 -281.228628) (xy 126.348618 -281.26982) (xy 126.307425 -281.305514)
			(xy 126.261571 -281.334981) (xy 126.21199 -281.357623) (xy 126.159692 -281.372978) (xy 126.105741 -281.380733)
			(xy 126.078488 -281.3812) (xy 126.049952 -281.380666) (xy 125.993519 -281.37216) (xy 125.938982 -281.35534)
			(xy 125.887561 -281.330581) (xy 125.840403 -281.298437) (xy 125.798562 -281.259624) (xy 125.762971 -281.21501)
			(xy 125.734425 -281.165591) (xy 125.713562 -281.11247) (xy 125.706632 -281.084782) (xy 125.705616 -281.08021)
			(xy 125.703 -281.073224) (xy 125.694355 -281.061077) (xy 125.688598 -281.056334) (xy 125.68174 -281.051)
			(xy 125.67412 -281.04846) (xy 125.670063 -281.047085) (xy 125.661637 -281.045547) (xy 125.657356 -281.045412)
			(xy 125.274324 -281.045412) (xy 125.2646 -281.045889) (xy 125.246568 -281.053191) (xy 125.239272 -281.059636)
			(xy 124.877576 -281.421586) (xy 124.85825 -281.440263) (xy 124.81529 -281.472558) (xy 124.768225 -281.498508)
			(xy 124.717985 -281.517598) (xy 124.665563 -281.529451) (xy 124.638816 -281.532076) (xy 124.622052 -281.533346)
			(xy 124.608336 -281.533346) (xy 124.581093 -281.532899) (xy 124.527153 -281.525225) (xy 124.474852 -281.509955)
			(xy 124.425256 -281.4874) (xy 124.379372 -281.45802) (xy 124.338135 -281.422411) (xy 124.302382 -281.381299)
			(xy 124.272841 -281.335518) (xy 124.250113 -281.286001) (xy 124.23466 -281.233755) (xy 124.226797 -281.179841)
			(xy 124.22632 -281.1526) (xy 124.22632 -281.147012) (xy 124.227447 -281.114148) (xy 124.239585 -281.049525)
			(xy 124.25045 -281.018488) (xy 124.252736 -281.012138) (xy 124.254006 -281.000962) (xy 124.253244 -280.99512)
			(xy 124.252457 -280.989389) (xy 124.248609 -280.978485) (xy 124.245624 -280.97353) (xy 124.238258 -280.9621)
			(xy 124.199142 -280.901902) (xy 124.196014 -280.897905) (xy 124.188465 -280.891122) (xy 124.184156 -280.88844)
			(xy 124.174758 -280.882852) (xy 124.161804 -280.881836) (xy 124.16155 -280.881836) (xy 124.13038 -280.879066)
			(xy 124.069492 -280.864642) (xy 124.040392 -280.853134) (xy 124.030232 -280.848816) (xy 124.019818 -280.84907)
			(xy 124.015134 -280.84923) (xy 124.005935 -280.851025) (xy 124.00153 -280.852626) (xy 123.9647 -280.870152)
			(xy 123.93041 -280.886662) (xy 123.925664 -280.88903) (xy 123.917212 -280.895435) (xy 123.913646 -280.899362)
			(xy 123.906788 -280.90749) (xy 123.90374 -280.918158) (xy 123.895553 -280.944128) (xy 123.872846 -280.993618)
			(xy 123.843341 -281.039382) (xy 123.807634 -281.080491) (xy 123.766452 -281.116112) (xy 123.720628 -281.145524)
			(xy 123.671091 -281.168129) (xy 123.618845 -281.18347) (xy 123.564951 -281.191235) (xy 123.537726 -281.191716)
			(xy 123.514371 -281.191348) (xy 123.468012 -281.185616) (xy 123.44527 -281.180286) (xy 123.435618 -281.178)
			(xy 123.426474 -281.17927) (xy 123.422315 -281.179875) (xy 123.41427 -281.182297) (xy 123.410472 -281.184096)
			(xy 123.34494 -281.221688) (xy 123.338844 -281.22626) (xy 123.331732 -281.233626) (xy 123.326144 -281.240738)
			(xy 123.323096 -281.250644) (xy 123.315025 -281.276737) (xy 123.292458 -281.326474) (xy 123.263032 -281.372486)
			(xy 123.227348 -281.413834) (xy 123.186134 -281.449674) (xy 123.140232 -281.479272) (xy 123.09058 -281.502025)
			(xy 123.038191 -281.517468) (xy 122.984136 -281.525286) (xy 122.956828 -281.525726) (xy 122.929573 -281.525265)
			(xy 122.875618 -281.517511) (xy 122.823316 -281.502158) (xy 122.773731 -281.479517) (xy 122.727873 -281.45005)
			(xy 122.686676 -281.414357) (xy 122.650977 -281.373164) (xy 122.621505 -281.327309) (xy 122.598858 -281.277727)
			(xy 122.583498 -281.225427) (xy 122.575738 -281.171473) (xy 122.57532 -281.144218) (xy 122.575358 -281.133465)
			(xy 122.576502 -281.111989) (xy 122.577606 -281.101292) (xy 122.578622 -281.09164) (xy 122.57659 -281.083258)
			(xy 122.575477 -281.079237) (xy 122.572154 -281.071583) (xy 122.569986 -281.068018) (xy 122.52833 -281.010868)
			(xy 122.527822 -281.010106) (xy 122.524915 -281.006463) (xy 122.518012 -281.000203) (xy 122.514106 -280.99766)
			(xy 122.506232 -280.992834) (xy 122.500644 -280.991564) (xy 122.474935 -280.986079) (xy 122.425225 -280.968983)
			(xy 122.378333 -280.945224) (xy 122.335148 -280.915252) (xy 122.296486 -280.879634) (xy 122.263082 -280.839045)
			(xy 122.235566 -280.794254) (xy 122.214462 -280.746109) (xy 122.200167 -280.695522) (xy 122.192954 -280.643452)
			(xy 122.192542 -280.617168) (xy 122.193028 -280.589917) (xy 122.200784 -280.535969) (xy 122.216139 -280.483674)
			(xy 122.238781 -280.434097) (xy 122.268247 -280.388247) (xy 122.303938 -280.347056) (xy 122.345129 -280.311365)
			(xy 122.390979 -280.281899) (xy 122.440556 -280.259257) (xy 122.492851 -280.243902) (xy 122.546799 -280.236146)
			(xy 122.601301 -280.236146) (xy 122.655249 -280.243902) (xy 122.707544 -280.259257) (xy 122.757121 -280.281899)
			(xy 122.802971 -280.311365) (xy 122.844162 -280.347056) (xy 122.879853 -280.388247) (xy 122.909319 -280.434097)
			(xy 122.931961 -280.483674) (xy 122.947316 -280.535969) (xy 122.955072 -280.589917) (xy 122.955558 -280.617168)
			(xy 122.955521 -280.627921) (xy 122.954377 -280.649397) (xy 122.953272 -280.660094) (xy 122.952256 -280.669746)
			(xy 122.954288 -280.678128) (xy 122.9554 -280.68215) (xy 122.95872 -280.689805) (xy 122.960892 -280.693368)
			(xy 123.002548 -280.750518) (xy 123.003056 -280.75128) (xy 123.005961 -280.754925) (xy 123.012862 -280.761188)
			(xy 123.016772 -280.763726) (xy 123.024646 -280.768552) (xy 123.03125 -280.770076) (xy 123.03379 -280.770584)
			(xy 123.049284 -280.77414) (xy 123.058936 -280.776426) (xy 123.06808 -280.775156) (xy 123.072237 -280.774547)
			(xy 123.08028 -280.772118) (xy 123.084082 -280.77033) (xy 123.149614 -280.732738) (xy 123.15571 -280.728166)
			(xy 123.162822 -280.7208) (xy 123.16841 -280.713688) (xy 123.171458 -280.703782) (xy 123.179528 -280.67769)
			(xy 123.202094 -280.627954) (xy 123.23152 -280.581943) (xy 123.267205 -280.540597) (xy 123.30842 -280.50476)
			(xy 123.354322 -280.475166) (xy 123.403975 -280.452418) (xy 123.456364 -280.43698) (xy 123.510418 -280.429169)
			(xy 123.537726 -280.4287) (xy 123.562897 -280.429105) (xy 123.612802 -280.435726) (xy 123.661404 -280.44885)
			(xy 123.684792 -280.458164) (xy 123.694952 -280.462482) (xy 123.705366 -280.462228) (xy 123.710335 -280.462071)
			(xy 123.720062 -280.460028) (xy 123.72467 -280.458164) (xy 123.76023 -280.440892) (xy 123.760738 -280.440892)
			(xy 123.794774 -280.424636) (xy 123.799521 -280.422269) (xy 123.807975 -280.415865) (xy 123.811538 -280.411936)
			(xy 123.818396 -280.403808) (xy 123.821444 -280.39314) (xy 123.830236 -280.365212) (xy 123.855181 -280.312242)
			(xy 123.887924 -280.263703) (xy 123.927695 -280.220735) (xy 123.973563 -280.184345) (xy 124.02445 -280.155387)
			(xy 124.079163 -280.13454) (xy 124.136418 -280.122294) (xy 124.165614 -280.12009) (xy 124.17806 -280.119328)
			(xy 124.187458 -280.113994) (xy 124.191828 -280.111397) (xy 124.199513 -280.104747) (xy 124.202698 -280.100786)
			(xy 124.227082 -280.066496) (xy 124.251466 -280.031952) (xy 124.2541 -280.027672) (xy 124.257805 -280.01833)
			(xy 124.258832 -280.01341) (xy 124.26061 -280.002742) (xy 124.257308 -279.991058) (xy 124.250611 -279.965548)
			(xy 124.243475 -279.91329) (xy 124.243084 -279.886918) (xy 124.243545 -279.859683) (xy 124.251295 -279.805768)
			(xy 124.26664 -279.753505) (xy 124.289267 -279.703958) (xy 124.318716 -279.658136) (xy 124.354386 -279.616972)
			(xy 124.395552 -279.581304) (xy 124.441376 -279.551857) (xy 124.490924 -279.529233) (xy 124.543188 -279.513891)
			(xy 124.597103 -279.506144) (xy 124.624338 -279.505664) (xy 124.624846 -279.505664) (xy 124.654761 -279.506274)
			(xy 124.71385 -279.515667) (xy 124.770748 -279.534168) (xy 124.824061 -279.561323) (xy 124.872482 -279.596468)
			(xy 124.894086 -279.61717) (xy 125.164596 -279.887934) (xy 125.1718 -279.894087) (xy 125.18942 -279.901011)
			(xy 125.198886 -279.901396) (xy 125.278896 -279.901396) (xy 125.288022 -279.900971) (xy 125.305076 -279.894454)
			(xy 125.31217 -279.888696) (xy 125.34265 -279.85847) (xy 125.409198 -279.791668) (xy 125.415067 -279.784476)
			(xy 125.421711 -279.767158) (xy 125.422152 -279.757886) (xy 125.422152 -279.576784) (xy 125.421667 -279.567063)
			(xy 125.414351 -279.549045) (xy 125.407928 -279.541732) (xy 124.384308 -278.518366) (xy 123.090686 -277.224744)
			(xy 123.085098 -277.219156) (xy 123.084844 -277.218902) (xy 123.082812 -277.216616) (xy 122.785886 -276.919944)
			(xy 122.765151 -276.898367) (xy 122.729988 -276.84995) (xy 122.702827 -276.796632) (xy 122.684334 -276.739723)
			(xy 122.674964 -276.680623) (xy 122.67438 -276.650704) (xy 122.67438 -267.102336) (xy 122.673945 -267.092271)
			(xy 122.666212 -267.073686) (xy 122.659394 -267.066268) (xy 121.968768 -266.375642) (xy 121.961886 -266.370609)
			(xy 121.945792 -266.365015) (xy 121.937272 -266.36472) (xy 121.23166 -266.36472) (xy 121.221659 -266.365215)
			(xy 121.203184 -266.372883) (xy 121.189049 -266.387035) (xy 121.181403 -266.405519) (xy 121.18086 -266.41552)
			(xy 121.18086 -267.365226) (xy 121.180308 -267.395209) (xy 121.170935 -267.454436) (xy 121.152408 -267.511468)
			(xy 121.125184 -267.564897) (xy 121.089934 -267.613407) (xy 121.0691 -267.634974) (xy 118.846854 -269.85722)
			(xy 118.841021 -269.864358) (xy 118.834382 -269.881542) (xy 118.8339 -269.890748) (xy 118.8339 -277.634192)
			(xy 120.08485 -277.634192) (xy 120.085348 -277.606122) (xy 120.093588 -277.550589) (xy 120.109875 -277.496862)
			(xy 120.133856 -277.446101) (xy 120.165015 -277.3994) (xy 120.202679 -277.357769) (xy 120.224042 -277.339552)
			(xy 120.232678 -277.33244) (xy 120.24233 -277.312628) (xy 120.24487 -277.213568) (xy 120.23598 -277.193248)
			(xy 120.227852 -277.185882) (xy 120.208519 -277.167737) (xy 120.174597 -277.126988) (xy 120.146643 -277.081936)
			(xy 120.125194 -277.033447) (xy 120.110665 -276.982456) (xy 120.103334 -276.929944) (xy 120.102884 -276.903434)
			(xy 120.103387 -276.876182) (xy 120.111139 -276.822233) (xy 120.12649 -276.769937) (xy 120.149128 -276.720357)
			(xy 120.178592 -276.674504) (xy 120.214282 -276.633311) (xy 120.255471 -276.597617) (xy 120.30132 -276.568148)
			(xy 120.350897 -276.545505) (xy 120.403192 -276.530148) (xy 120.45714 -276.52239) (xy 120.484392 -276.521926)
			(xy 120.510644 -276.52235) (xy 120.562654 -276.529537) (xy 120.613186 -276.543791) (xy 120.661285 -276.564842)
			(xy 120.706042 -276.592292) (xy 120.74661 -276.625622) (xy 120.782223 -276.664202) (xy 120.797574 -276.685502)
			(xy 120.802902 -276.692457) (xy 120.817178 -276.702589) (xy 120.834029 -276.707332) (xy 120.842786 -276.707092)
			(xy 120.94337 -276.69998) (xy 120.965468 -276.685248) (xy 120.971564 -276.67331) (xy 120.983825 -276.650017)
			(xy 121.013792 -276.606742) (xy 121.049423 -276.567996) (xy 121.09004 -276.534514) (xy 121.134873 -276.506933)
			(xy 121.183072 -276.485774) (xy 121.233721 -276.47144) (xy 121.285859 -276.464203) (xy 121.312178 -276.46376)
			(xy 121.345706 -276.465284) (xy 121.355779 -276.465774) (xy 121.374985 -276.459662) (xy 121.390363 -276.446633)
			(xy 121.399547 -276.428692) (xy 121.401125 -276.408599) (xy 121.394855 -276.389444) (xy 121.381699 -276.374175)
			(xy 121.372884 -276.369272) (xy 121.351374 -276.358095) (xy 121.311121 -276.331087) (xy 121.29262 -276.315424)
			(xy 121.292366 -276.31517) (xy 121.285267 -276.309602) (xy 121.26836 -276.303345) (xy 121.259346 -276.302978)
			(xy 121.19229 -276.302978) (xy 121.183273 -276.303335) (xy 121.166357 -276.309583) (xy 121.15927 -276.31517)
			(xy 121.15927 -276.315424) (xy 121.159016 -276.315424) (xy 121.138092 -276.333073) (xy 121.092116 -276.362782)
			(xy 121.042367 -276.385616) (xy 120.989865 -276.401105) (xy 120.935688 -276.408931) (xy 120.908318 -276.409404)
			(xy 120.881065 -276.408928) (xy 120.827115 -276.401173) (xy 120.774817 -276.385819) (xy 120.725237 -276.363179)
			(xy 120.679383 -276.333712) (xy 120.63819 -276.29802) (xy 120.602496 -276.256828) (xy 120.573028 -276.210976)
			(xy 120.550386 -276.161396) (xy 120.53503 -276.109099) (xy 120.527273 -276.055149) (xy 120.52681 -276.027896)
			(xy 120.527271 -276.000526) (xy 120.53509 -275.946346) (xy 120.55058 -275.893843) (xy 120.573423 -275.844096)
			(xy 120.603148 -275.79813) (xy 120.62079 -275.777198) (xy 120.621044 -275.776944) (xy 120.626624 -275.769853)
			(xy 120.632873 -275.752939) (xy 120.633236 -275.743924) (xy 120.633236 -275.676868) (xy 120.632887 -275.667851)
			(xy 120.626633 -275.650934) (xy 120.621044 -275.643848) (xy 120.62079 -275.643848) (xy 120.62079 -275.643594)
			(xy 120.603147 -275.622664) (xy 120.573425 -275.576695) (xy 120.550582 -275.526948) (xy 120.535088 -275.474446)
			(xy 120.52726 -275.420267) (xy 120.527261 -275.365527) (xy 120.535089 -275.311349) (xy 120.550584 -275.258847)
			(xy 120.573428 -275.2091) (xy 120.603151 -275.163131) (xy 120.62079 -275.142198) (xy 120.621044 -275.141944)
			(xy 120.626624 -275.134853) (xy 120.632873 -275.117939) (xy 120.633236 -275.108924) (xy 120.633236 -275.041868)
			(xy 120.632887 -275.032851) (xy 120.626633 -275.015934) (xy 120.621044 -275.008848) (xy 120.62079 -275.008848)
			(xy 120.62079 -275.008594) (xy 120.603133 -274.987676) (xy 120.573424 -274.941699) (xy 120.550592 -274.891948)
			(xy 120.535105 -274.839444) (xy 120.527282 -274.785266) (xy 120.52681 -274.757896) (xy 120.527252 -274.730642)
			(xy 120.53501 -274.67669) (xy 120.550367 -274.62439) (xy 120.573011 -274.574809) (xy 120.602481 -274.528955)
			(xy 120.638177 -274.487762) (xy 120.679373 -274.452068) (xy 120.725228 -274.422601) (xy 120.774811 -274.399959)
			(xy 120.827111 -274.384605) (xy 120.881064 -274.37685) (xy 120.908318 -274.376388) (xy 120.935688 -274.376846)
			(xy 120.989868 -274.384667) (xy 121.042371 -274.400158) (xy 121.092118 -274.423001) (xy 121.138084 -274.452726)
			(xy 121.159016 -274.470368) (xy 121.15927 -274.470622) (xy 121.166359 -274.476205) (xy 121.183274 -274.482453)
			(xy 121.19229 -274.482814) (xy 121.259346 -274.482814) (xy 121.26836 -274.482428) (xy 121.285277 -274.4762)
			(xy 121.292366 -274.470622) (xy 121.292366 -274.470368) (xy 121.29262 -274.470368) (xy 121.313567 -274.452748)
			(xy 121.359536 -274.423034) (xy 121.40928 -274.400195) (xy 121.461777 -274.3847) (xy 121.51595 -274.376865)
			(xy 121.543318 -274.376388) (xy 121.57057 -274.376861) (xy 121.624517 -274.38462) (xy 121.676812 -274.399977)
			(xy 121.726389 -274.42262) (xy 121.772239 -274.452088) (xy 121.813429 -274.487781) (xy 121.849121 -274.528972)
			(xy 121.878587 -274.574823) (xy 121.901228 -274.624401) (xy 121.916583 -274.676696) (xy 121.92434 -274.730644)
			(xy 121.924826 -274.757896) (xy 121.924376 -274.785267) (xy 121.916557 -274.839447) (xy 121.901065 -274.891951)
			(xy 121.878219 -274.941698) (xy 121.84849 -274.987664) (xy 121.830846 -275.008594) (xy 121.830592 -275.008848)
			(xy 121.82502 -275.015945) (xy 121.818765 -275.032854) (xy 121.8184 -275.041868) (xy 121.8184 -275.108924)
			(xy 121.818746 -275.117942) (xy 121.825001 -275.134859) (xy 121.830592 -275.141944) (xy 121.830846 -275.141944)
			(xy 121.830846 -275.142198) (xy 121.848484 -275.163133) (xy 121.878211 -275.2091) (xy 121.901058 -275.258846)
			(xy 121.916556 -275.311348) (xy 121.924385 -275.365526) (xy 121.924386 -275.420268) (xy 121.916557 -275.474447)
			(xy 121.90106 -275.526949) (xy 121.878214 -275.576695) (xy 121.848488 -275.622662) (xy 121.830846 -275.643594)
			(xy 121.830592 -275.643848) (xy 121.82502 -275.650945) (xy 121.818765 -275.667854) (xy 121.8184 -275.676868)
			(xy 121.8184 -275.743924) (xy 121.818746 -275.752942) (xy 121.825001 -275.769859) (xy 121.830592 -275.776944)
			(xy 121.830846 -275.776944) (xy 121.830846 -275.777198) (xy 121.848489 -275.798127) (xy 121.878202 -275.8441)
			(xy 121.901038 -275.893848) (xy 121.916528 -275.94635) (xy 121.924354 -276.000526) (xy 121.924826 -276.027896)
			(xy 121.924387 -276.056524) (xy 121.915839 -276.113137) (xy 121.898921 -276.167835) (xy 121.874013 -276.219388)
			(xy 121.841674 -276.266636) (xy 121.802633 -276.308517) (xy 121.757768 -276.344087) (xy 121.708088 -276.372547)
			(xy 121.654709 -276.393257) (xy 121.626884 -276.400006) (xy 121.62663 -276.400006) (xy 121.617871 -276.402419)
			(xy 121.602755 -276.41248) (xy 121.592088 -276.427174) (xy 121.589292 -276.43582) (xy 121.561098 -276.535388)
			(xy 121.56821 -276.562058) (xy 121.57837 -276.571964) (xy 121.596267 -276.58999) (xy 121.627628 -276.629949)
			(xy 121.653411 -276.673716) (xy 121.673158 -276.720517) (xy 121.686522 -276.769523) (xy 121.693266 -276.81987)
			(xy 121.693686 -276.845268) (xy 121.693215 -276.872521) (xy 121.685462 -276.926473) (xy 121.670109 -276.978772)
			(xy 121.647468 -277.028353) (xy 121.618001 -277.074208) (xy 121.582308 -277.115401) (xy 121.541116 -277.151095)
			(xy 121.495262 -277.180563) (xy 121.445681 -277.203205) (xy 121.393383 -277.21856) (xy 121.339431 -277.226314)
			(xy 121.312178 -277.226776) (xy 121.285925 -277.226374) (xy 121.233915 -277.219182) (xy 121.183382 -277.204925)
			(xy 121.135283 -277.18387) (xy 121.090527 -277.156417) (xy 121.049959 -277.123084) (xy 121.014347 -277.084501)
			(xy 120.998996 -277.0632) (xy 120.993685 -277.05623) (xy 120.979402 -277.046101) (xy 120.962543 -277.041365)
			(xy 120.953784 -277.04161) (xy 120.8532 -277.048722) (xy 120.831102 -277.063454) (xy 120.825006 -277.075392)
			(xy 120.812694 -277.098751) (xy 120.782606 -277.142141) (xy 120.746822 -277.180968) (xy 120.726708 -277.198074)
			(xy 120.718072 -277.205186) (xy 120.70842 -277.224998) (xy 120.70588 -277.324058) (xy 120.71477 -277.344378)
			(xy 120.722898 -277.351744) (xy 120.742185 -277.369935) (xy 120.776113 -277.410673) (xy 120.804075 -277.455716)
			(xy 120.825531 -277.504195) (xy 120.84007 -277.555179) (xy 120.847411 -277.607684) (xy 120.847866 -277.634192)
			(xy 120.84738 -277.661443) (xy 120.839624 -277.715391) (xy 120.834827 -277.731728) (xy 120.970292 -277.731728)
			(xy 120.974363 -277.676106) (xy 120.986489 -277.621669) (xy 121.006412 -277.569578) (xy 121.033708 -277.520943)
			(xy 121.067794 -277.4768) (xy 121.107943 -277.438091) (xy 121.153301 -277.40564) (xy 121.202901 -277.380139)
			(xy 121.255685 -277.362132) (xy 121.310528 -277.352002) (xy 121.366262 -277.349965) (xy 121.421699 -277.356065)
			(xy 121.475656 -277.370171) (xy 121.526985 -277.391983) (xy 121.574591 -277.421037) (xy 121.617459 -277.456712)
			(xy 121.654676 -277.498249) (xy 121.685449 -277.544762) (xy 121.709121 -277.595259) (xy 121.725189 -277.648666)
			(xy 121.733309 -277.703842) (xy 121.733818 -277.731728) (xy 121.733309 -277.759614) (xy 121.725189 -277.81479)
			(xy 121.709121 -277.868197) (xy 121.685449 -277.918694) (xy 121.654676 -277.965207) (xy 121.617459 -278.006744)
			(xy 121.574591 -278.042419) (xy 121.526985 -278.071473) (xy 121.475656 -278.093285) (xy 121.421699 -278.107391)
			(xy 121.366262 -278.113491) (xy 121.310528 -278.111454) (xy 121.255685 -278.101324) (xy 121.202901 -278.083317)
			(xy 121.153301 -278.057816) (xy 121.107943 -278.025365) (xy 121.067794 -277.986656) (xy 121.033708 -277.942513)
			(xy 121.006412 -277.893878) (xy 120.986489 -277.841787) (xy 120.974363 -277.78735) (xy 120.970292 -277.731728)
			(xy 120.834827 -277.731728) (xy 120.824269 -277.767686) (xy 120.801627 -277.817263) (xy 120.772161 -277.863113)
			(xy 120.73647 -277.904304) (xy 120.695279 -277.939995) (xy 120.649429 -277.969461) (xy 120.599852 -277.992103)
			(xy 120.547557 -278.007458) (xy 120.493609 -278.015214) (xy 120.439107 -278.015214) (xy 120.385159 -278.007458)
			(xy 120.332864 -277.992103) (xy 120.283287 -277.969461) (xy 120.237437 -277.939995) (xy 120.196246 -277.904304)
			(xy 120.160555 -277.863113) (xy 120.131089 -277.817263) (xy 120.108447 -277.767686) (xy 120.093092 -277.715391)
			(xy 120.085336 -277.661443) (xy 120.08485 -277.634192) (xy 118.8339 -277.634192) (xy 118.8339 -279.314656)
			(xy 118.834154 -279.326594) (xy 118.834154 -279.328372) (xy 118.833569 -279.358374) (xy 118.824192 -279.417641)
			(xy 118.805666 -279.474714) (xy 118.778445 -279.528189) (xy 118.743199 -279.57675) (xy 118.722394 -279.598374)
			(xy 118.275354 -280.045414) (xy 117.772688 -280.547826) (xy 117.767514 -280.554993) (xy 117.761938 -280.571753)
			(xy 117.761766 -280.580592) (xy 117.766592 -280.630122) (xy 117.770148 -280.665428) (xy 117.771039 -280.67018)
			(xy 117.774366 -280.679257) (xy 117.776752 -280.683462) (xy 117.779546 -280.688288) (xy 117.786912 -280.696162)
			(xy 117.792246 -280.699718) (xy 117.814208 -280.71497) (xy 117.854042 -280.750639) (xy 117.888503 -280.791523)
			(xy 117.916917 -280.836818) (xy 117.938725 -280.885639) (xy 117.9535 -280.937027) (xy 117.960953 -280.989975)
			(xy 117.96141 -281.01671) (xy 117.960924 -281.043961) (xy 117.953166 -281.097908) (xy 117.93781 -281.150201)
			(xy 117.915168 -281.199777) (xy 117.885702 -281.245627) (xy 117.85001 -281.286816) (xy 117.80882 -281.322506)
			(xy 117.76297 -281.351972) (xy 117.713394 -281.374613) (xy 117.6611 -281.389968) (xy 117.607153 -281.397724)
			(xy 117.579902 -281.398218) (xy 117.55187 -281.397717) (xy 117.49641 -281.389501) (xy 117.442748 -281.373262)
			(xy 117.392039 -281.349348) (xy 117.345373 -281.318274) (xy 117.303755 -281.280708) (xy 117.268079 -281.237459)
			(xy 117.239113 -281.189456) (xy 117.217481 -281.137732) (xy 117.210078 -281.11069) (xy 117.208046 -281.102562)
			(xy 117.193568 -281.08021) (xy 117.193314 -281.079702) (xy 117.19052 -281.076654) (xy 117.190266 -281.076146)
			(xy 117.184424 -281.070304) (xy 117.180868 -281.067002) (xy 117.163596 -281.054048) (xy 117.160294 -281.052016)
			(xy 117.159786 -281.051508) (xy 117.154871 -281.048916) (xy 117.144234 -281.045708) (xy 117.138704 -281.045158)
			(xy 117.13337 -281.045412) (xy 117.117114 -281.045666) (xy 117.116606 -281.045666) (xy 117.103144 -281.045412)
			(xy 116.775738 -281.045412) (xy 116.766012 -281.045887) (xy 116.747977 -281.053185) (xy 116.740686 -281.059636)
			(xy 116.37899 -281.421586) (xy 116.357413 -281.442319) (xy 116.308995 -281.477477) (xy 116.255676 -281.504634)
			(xy 116.198767 -281.52312) (xy 116.139668 -281.532483) (xy 116.10975 -281.533092) (xy 116.109242 -281.533092)
			(xy 116.082004 -281.532632) (xy 116.028083 -281.524885) (xy 115.975812 -281.509544) (xy 115.926258 -281.486919)
			(xy 115.880427 -281.457472) (xy 115.839254 -281.421803) (xy 115.803576 -281.380637) (xy 115.774119 -281.334813)
			(xy 115.751484 -281.285263) (xy 115.736132 -281.232996) (xy 115.728374 -281.179076) (xy 115.727988 -281.151838)
			(xy 115.728101 -281.135118) (xy 115.730899 -281.101795) (xy 115.733576 -281.08529) (xy 115.734084 -281.08275)
			(xy 115.734338 -281.081734) (xy 115.7351 -281.077416) (xy 115.7351 -281.077162) (xy 115.735354 -281.075892)
			(xy 115.735354 -281.075384) (xy 115.735862 -281.072844) (xy 115.73637 -281.07132) (xy 115.737132 -281.067256)
			(xy 115.737132 -281.067002) (xy 115.738148 -281.063446) (xy 115.738148 -281.062938) (xy 115.739418 -281.05862)
			(xy 115.739418 -281.058112) (xy 115.746022 -281.035252) (xy 115.751864 -281.018488) (xy 115.75415 -281.012138)
			(xy 115.75542 -281.000962) (xy 115.754658 -280.99512) (xy 115.753872 -280.989389) (xy 115.750024 -280.978484)
			(xy 115.747038 -280.97353) (xy 115.739672 -280.9621) (xy 115.700556 -280.901902) (xy 115.697429 -280.897904)
			(xy 115.689881 -280.89112) (xy 115.68557 -280.88844) (xy 115.676172 -280.882852) (xy 115.663218 -280.881836)
			(xy 115.662964 -280.881836) (xy 115.631794 -280.879067) (xy 115.570905 -280.864645) (xy 115.541806 -280.853134)
			(xy 115.531646 -280.848816) (xy 115.521232 -280.84907) (xy 115.516548 -280.849229) (xy 115.507348 -280.851022)
			(xy 115.502944 -280.852626) (xy 115.466114 -280.870152) (xy 115.431824 -280.886662) (xy 115.427077 -280.889029)
			(xy 115.418623 -280.895433) (xy 115.41506 -280.899362) (xy 115.408202 -280.90749) (xy 115.405154 -280.918158)
			(xy 115.396968 -280.944128) (xy 115.374261 -280.99362) (xy 115.344755 -281.039384) (xy 115.309049 -281.080495)
			(xy 115.267867 -281.116118) (xy 115.222043 -281.145531) (xy 115.172506 -281.168138) (xy 115.12026 -281.18348)
			(xy 115.066366 -281.191247) (xy 115.03914 -281.191716) (xy 115.015784 -281.191349) (xy 114.969426 -281.185619)
			(xy 114.946684 -281.180286) (xy 114.937032 -281.178) (xy 114.927888 -281.17927) (xy 114.923729 -281.179874)
			(xy 114.915682 -281.182294) (xy 114.911886 -281.184096) (xy 114.846354 -281.221688) (xy 114.840258 -281.22626)
			(xy 114.833146 -281.233626) (xy 114.827558 -281.240738) (xy 114.82451 -281.250644) (xy 114.816439 -281.276737)
			(xy 114.793873 -281.326475) (xy 114.764447 -281.372489) (xy 114.728763 -281.413838) (xy 114.687549 -281.449679)
			(xy 114.641647 -281.479279) (xy 114.591995 -281.502034) (xy 114.539606 -281.517479) (xy 114.485551 -281.525298)
			(xy 114.458242 -281.525726) (xy 114.430987 -281.525266) (xy 114.37703 -281.517514) (xy 114.324726 -281.502162)
			(xy 114.27514 -281.479522) (xy 114.22928 -281.450055) (xy 114.188081 -281.414362) (xy 114.152381 -281.373168)
			(xy 114.122907 -281.327313) (xy 114.100259 -281.27773) (xy 114.084899 -281.225429) (xy 114.077138 -281.171473)
			(xy 114.076734 -281.144218) (xy 114.076772 -281.133465) (xy 114.077916 -281.111989) (xy 114.07902 -281.101292)
			(xy 114.080036 -281.09164) (xy 114.078004 -281.083258) (xy 114.076891 -281.079237) (xy 114.073569 -281.071583)
			(xy 114.0714 -281.068018) (xy 114.029744 -281.010868) (xy 114.029236 -281.010106) (xy 114.02633 -281.006462)
			(xy 114.019427 -281.000201) (xy 114.01552 -280.99766) (xy 114.007646 -280.992834) (xy 114.002058 -280.991564)
			(xy 113.976349 -280.986079) (xy 113.926637 -280.968985) (xy 113.879744 -280.945227) (xy 113.836556 -280.915255)
			(xy 113.797894 -280.879637) (xy 113.764487 -280.839048) (xy 113.736971 -280.794257) (xy 113.715865 -280.746111)
			(xy 113.70157 -280.695523) (xy 113.694357 -280.643452) (xy 113.693956 -280.617168) (xy 113.694442 -280.589917)
			(xy 113.702198 -280.535969) (xy 113.717553 -280.483674) (xy 113.740195 -280.434097) (xy 113.769661 -280.388247)
			(xy 113.805352 -280.347056) (xy 113.846543 -280.311365) (xy 113.892393 -280.281899) (xy 113.94197 -280.259257)
			(xy 113.994265 -280.243902) (xy 114.048213 -280.236146) (xy 114.102715 -280.236146) (xy 114.156663 -280.243902)
			(xy 114.208958 -280.259257) (xy 114.258535 -280.281899) (xy 114.304385 -280.311365) (xy 114.345576 -280.347056)
			(xy 114.381267 -280.388247) (xy 114.410733 -280.434097) (xy 114.433375 -280.483674) (xy 114.44873 -280.535969)
			(xy 114.456486 -280.589917) (xy 114.456972 -280.617168) (xy 114.456935 -280.627921) (xy 114.455791 -280.649397)
			(xy 114.454686 -280.660094) (xy 114.45367 -280.669746) (xy 114.455702 -280.678128) (xy 114.456814 -280.68215)
			(xy 114.460135 -280.689804) (xy 114.462306 -280.693368) (xy 114.503962 -280.750518) (xy 114.50447 -280.75128)
			(xy 114.507376 -280.754924) (xy 114.514278 -280.761186) (xy 114.518186 -280.763726) (xy 114.52606 -280.768552)
			(xy 114.532664 -280.770076) (xy 114.535204 -280.770584) (xy 114.550698 -280.77414) (xy 114.56035 -280.776426)
			(xy 114.569494 -280.775156) (xy 114.573651 -280.774546) (xy 114.581692 -280.772115) (xy 114.585496 -280.77033)
			(xy 114.651028 -280.732738) (xy 114.657124 -280.728166) (xy 114.664236 -280.7208) (xy 114.669824 -280.713688)
			(xy 114.672872 -280.703782) (xy 114.681139 -280.677108) (xy 114.704384 -280.626332) (xy 114.734775 -280.579482)
			(xy 114.771665 -280.537557) (xy 114.814266 -280.50145) (xy 114.86167 -280.471932) (xy 114.912868 -280.449631)
			(xy 114.966767 -280.435023) (xy 114.994436 -280.43124) (xy 115.008152 -280.429716) (xy 115.03914 -280.428446)
			(xy 115.064405 -280.428854) (xy 115.114492 -280.43553) (xy 115.163256 -280.448772) (xy 115.186714 -280.458164)
			(xy 115.196874 -280.462482) (xy 115.20678 -280.462228) (xy 115.211748 -280.46207) (xy 115.221474 -280.460024)
			(xy 115.226084 -280.458164) (xy 115.261644 -280.440892) (xy 115.262152 -280.440892) (xy 115.296188 -280.424636)
			(xy 115.300934 -280.422268) (xy 115.309386 -280.415863) (xy 115.312952 -280.411936) (xy 115.31981 -280.403808)
			(xy 115.322858 -280.39314) (xy 115.33165 -280.365212) (xy 115.356596 -280.312243) (xy 115.389339 -280.263706)
			(xy 115.429111 -280.220739) (xy 115.474978 -280.18435) (xy 115.525866 -280.155394) (xy 115.580578 -280.13455)
			(xy 115.637833 -280.122306) (xy 115.667028 -280.12009) (xy 115.679474 -280.119328) (xy 115.688872 -280.113994)
			(xy 115.693241 -280.111396) (xy 115.700925 -280.104745) (xy 115.704112 -280.100786) (xy 115.728496 -280.066496)
			(xy 115.75288 -280.031952) (xy 115.755514 -280.027671) (xy 115.759218 -280.01833) (xy 115.760246 -280.01341)
			(xy 115.762024 -280.002742) (xy 115.758722 -279.991312) (xy 115.752118 -279.96388) (xy 115.752118 -279.963626)
			(xy 115.751102 -279.9588) (xy 115.748562 -279.943814) (xy 115.746555 -279.929675) (xy 115.744394 -279.901198)
			(xy 115.744244 -279.886918) (xy 115.744244 -279.865582) (xy 115.745768 -279.852628) (xy 115.748818 -279.824533)
			(xy 115.76215 -279.769616) (xy 115.783441 -279.717269) (xy 115.812226 -279.668638) (xy 115.847874 -279.624789)
			(xy 115.889603 -279.586681) (xy 115.9365 -279.55515) (xy 115.987538 -279.530887) (xy 116.041598 -279.514423)
			(xy 116.097496 -279.506118) (xy 116.125752 -279.505664) (xy 116.155718 -279.506239) (xy 116.214916 -279.515587)
			(xy 116.271924 -279.534075) (xy 116.325341 -279.561249) (xy 116.373851 -279.596442) (xy 116.3955 -279.61717)
			(xy 116.66601 -279.887934) (xy 116.673215 -279.894085) (xy 116.690835 -279.901003) (xy 116.7003 -279.901396)
			(xy 116.78031 -279.901396) (xy 116.78953 -279.900966) (xy 116.806738 -279.894337) (xy 116.813838 -279.888442)
			(xy 117.675406 -279.027128) (xy 117.681955 -279.019802) (xy 117.689404 -279.001637) (xy 117.689884 -278.991822)
			(xy 117.689884 -269.446502) (xy 117.690442 -269.416522) (xy 117.699826 -269.357301) (xy 117.718362 -269.300278)
			(xy 117.745595 -269.246859) (xy 117.780852 -269.19836) (xy 117.801644 -269.176754) (xy 119.986806 -266.991592)
			(xy 119.991791 -266.986164) (xy 119.998646 -266.973126) (xy 120.000268 -266.965938) (xy 120.000268 -266.96543)
			(xy 120.001284 -266.956032) (xy 120.001284 -266.447524) (xy 120.000915 -266.43949) (xy 119.995858 -266.424233)
			(xy 119.991378 -266.417552) (xy 119.986806 -266.411202) (xy 119.973344 -266.401804) (xy 119.965724 -266.399518)
			(xy 119.937022 -266.38885) (xy 119.927546 -266.384697) (xy 119.909114 -266.375292) (xy 119.900192 -266.370054)
			(xy 119.891048 -266.36472) (xy 119.478806 -266.36472) (xy 119.468838 -266.365194) (xy 119.450397 -266.372765)
			(xy 119.442992 -266.379452) (xy 118.603522 -267.218668) (xy 118.581908 -267.239448) (xy 118.533403 -267.274687)
			(xy 118.479984 -267.301907) (xy 118.422966 -267.320438) (xy 118.363751 -267.329825) (xy 118.333774 -267.330428)
			(xy 117.29212 -267.330428) (xy 117.282906 -267.33087) (xy 117.265715 -267.33752) (xy 117.258592 -267.343382)
			(xy 113.351564 -271.250156) (xy 113.348008 -271.25422) (xy 113.34374 -271.260044) (xy 113.33843 -271.273465)
			(xy 113.337594 -271.280636) (xy 113.33734 -271.285462) (xy 113.33734 -278.49957) (xy 113.336736 -278.529487)
			(xy 113.327354 -278.588582) (xy 113.308861 -278.645488) (xy 113.281713 -278.69881) (xy 113.246573 -278.74724)
			(xy 113.225834 -278.76881) (xy 111.968026 -280.026618) (xy 111.946449 -280.047352) (xy 111.898031 -280.082512)
			(xy 111.844713 -280.109671) (xy 111.787804 -280.128161) (xy 111.728704 -280.137528) (xy 111.698786 -280.138124)
			(xy 110.04169 -280.138124) (xy 110.030768 -280.139394) (xy 110.025926 -280.140682) (xy 110.016846 -280.144912)
			(xy 110.012734 -280.147776) (xy 110.009178 -280.150824) (xy 110.008162 -280.15184) (xy 110.006384 -280.153364)
			(xy 109.6264 -280.533348) (xy 109.618965 -280.541583) (xy 109.61133 -280.56239) (xy 109.611668 -280.57348)
			(xy 109.613954 -280.600404) (xy 109.618526 -280.653236) (xy 109.619305 -280.658171) (xy 109.622511 -280.667631)
			(xy 109.624876 -280.672032) (xy 109.63021 -280.68143) (xy 109.639608 -280.688034) (xy 109.660621 -280.703444)
			(xy 109.69867 -280.739046) (xy 109.731524 -280.779492) (xy 109.758571 -280.824031) (xy 109.779309 -280.871834)
			(xy 109.793353 -280.922014) (xy 109.800441 -280.973638) (xy 109.800898 -280.999692) (xy 109.800419 -281.026866)
			(xy 109.792709 -281.080664) (xy 109.777444 -281.132824) (xy 109.754934 -281.182291) (xy 109.725632 -281.228063)
			(xy 109.690133 -281.269215) (xy 109.649155 -281.304915) (xy 109.603526 -281.334439) (xy 109.55417 -281.357191)
			(xy 109.502085 -281.372709) (xy 109.47527 -281.377136) (xy 109.465568 -281.379027) (xy 109.448587 -281.389106)
			(xy 109.44225 -281.396694) (xy 109.424103 -281.419793) (xy 109.381908 -281.460659) (xy 109.333948 -281.494573)
			(xy 109.281356 -281.520734) (xy 109.225375 -281.538524) (xy 109.167328 -281.547522) (xy 109.137958 -281.548078)
			(xy 109.11071 -281.547589) (xy 109.056768 -281.539827) (xy 109.00448 -281.524468) (xy 108.95491 -281.501824)
			(xy 108.909067 -281.472356) (xy 108.867884 -281.436665) (xy 108.8322 -281.395475) (xy 108.802741 -281.349627)
			(xy 108.780107 -281.300052) (xy 108.764757 -281.247762) (xy 108.757006 -281.193819) (xy 108.75645 -281.16657)
			(xy 108.756704 -281.151076) (xy 108.757212 -281.140662) (xy 108.7501 -281.121358) (xy 108.691934 -281.060906)
			(xy 108.684484 -281.053852) (xy 108.665609 -281.045857) (xy 108.655358 -281.045412) (xy 108.615226 -281.045412)
			(xy 108.60559 -281.045871) (xy 108.587698 -281.053043) (xy 108.580428 -281.059382) (xy 108.218478 -281.421586)
			(xy 108.196901 -281.442319) (xy 108.148483 -281.477475) (xy 108.095163 -281.50463) (xy 108.038255 -281.523114)
			(xy 107.979156 -281.532475) (xy 107.949238 -281.533092) (xy 107.94873 -281.533092) (xy 107.921495 -281.532608)
			(xy 107.867577 -281.524861) (xy 107.815312 -281.509519) (xy 107.765761 -281.486895) (xy 107.719935 -281.45745)
			(xy 107.678766 -281.421783) (xy 107.643091 -281.380619) (xy 107.613638 -281.334798) (xy 107.591005 -281.285252)
			(xy 107.575654 -281.232989) (xy 107.567896 -281.179073) (xy 107.567476 -281.151838) (xy 107.567589 -281.135118)
			(xy 107.570387 -281.101795) (xy 107.573064 -281.08529) (xy 107.573572 -281.08275) (xy 107.573826 -281.081734)
			(xy 107.574588 -281.077416) (xy 107.574588 -281.077162) (xy 107.574842 -281.075892) (xy 107.574842 -281.075384)
			(xy 107.57535 -281.072844) (xy 107.575858 -281.07132) (xy 107.57662 -281.067256) (xy 107.57662 -281.067002)
			(xy 107.577636 -281.063446) (xy 107.577636 -281.062938) (xy 107.578906 -281.05862) (xy 107.578906 -281.058112)
			(xy 107.58551 -281.035252) (xy 107.591352 -281.018488) (xy 107.593638 -281.012138) (xy 107.594908 -281.000962)
			(xy 107.594146 -280.99512) (xy 107.593359 -280.989389) (xy 107.589511 -280.978485) (xy 107.586526 -280.97353)
			(xy 107.57916 -280.9621) (xy 107.540044 -280.901902) (xy 107.536916 -280.897905) (xy 107.529367 -280.891122)
			(xy 107.525058 -280.88844) (xy 107.51566 -280.882852) (xy 107.502706 -280.881836) (xy 107.502452 -280.881836)
			(xy 107.471282 -280.879066) (xy 107.410394 -280.864643) (xy 107.381294 -280.853134) (xy 107.371134 -280.848816)
			(xy 107.36072 -280.84907) (xy 107.356036 -280.84923) (xy 107.346837 -280.851025) (xy 107.342432 -280.852626)
			(xy 107.305602 -280.870152) (xy 107.271312 -280.886662) (xy 107.266566 -280.88903) (xy 107.258113 -280.895435)
			(xy 107.254548 -280.899362) (xy 107.24769 -280.90749) (xy 107.244642 -280.918158) (xy 107.236455 -280.944128)
			(xy 107.213748 -280.993618) (xy 107.184243 -281.039382) (xy 107.148537 -281.080492) (xy 107.107354 -281.116113)
			(xy 107.06153 -281.145525) (xy 107.011993 -281.16813) (xy 106.959748 -281.183471) (xy 106.905853 -281.191237)
			(xy 106.878628 -281.191716) (xy 106.855273 -281.191348) (xy 106.808914 -281.185616) (xy 106.786172 -281.180286)
			(xy 106.77652 -281.178) (xy 106.767376 -281.17927) (xy 106.763217 -281.179874) (xy 106.755172 -281.182297)
			(xy 106.751374 -281.184096) (xy 106.685842 -281.221688) (xy 106.679746 -281.22626) (xy 106.672634 -281.233626)
			(xy 106.667046 -281.240738) (xy 106.663998 -281.250644) (xy 106.655927 -281.276737) (xy 106.63336 -281.326474)
			(xy 106.603934 -281.372487) (xy 106.56825 -281.413835) (xy 106.527036 -281.449674) (xy 106.481134 -281.479273)
			(xy 106.431482 -281.502026) (xy 106.379093 -281.51747) (xy 106.325038 -281.525288) (xy 106.29773 -281.525726)
			(xy 106.270475 -281.525265) (xy 106.21652 -281.517512) (xy 106.164218 -281.502159) (xy 106.114632 -281.479518)
			(xy 106.068774 -281.450051) (xy 106.027576 -281.414358) (xy 105.991878 -281.373164) (xy 105.962405 -281.32731)
			(xy 105.939758 -281.277728) (xy 105.924398 -281.225427) (xy 105.916638 -281.171473) (xy 105.916222 -281.144218)
			(xy 105.91626 -281.133465) (xy 105.917404 -281.111989) (xy 105.918508 -281.101292) (xy 105.919524 -281.09164)
			(xy 105.917492 -281.083258) (xy 105.916379 -281.079237) (xy 105.913056 -281.071583) (xy 105.910888 -281.068018)
			(xy 105.869232 -281.010868) (xy 105.868724 -281.010106) (xy 105.865817 -281.006463) (xy 105.858914 -281.000203)
			(xy 105.855008 -280.99766) (xy 105.847134 -280.992834) (xy 105.841546 -280.991564) (xy 105.815837 -280.986079)
			(xy 105.766127 -280.968983) (xy 105.719235 -280.945225) (xy 105.676049 -280.915252) (xy 105.637387 -280.879634)
			(xy 105.603983 -280.839045) (xy 105.576467 -280.794254) (xy 105.555362 -280.746109) (xy 105.541068 -280.695522)
			(xy 105.533854 -280.643452) (xy 105.533444 -280.617168) (xy 105.53393 -280.589917) (xy 105.541686 -280.535969)
			(xy 105.557041 -280.483674) (xy 105.579683 -280.434097) (xy 105.609149 -280.388247) (xy 105.64484 -280.347056)
			(xy 105.686031 -280.311365) (xy 105.731881 -280.281899) (xy 105.781458 -280.259257) (xy 105.833753 -280.243902)
			(xy 105.887701 -280.236146) (xy 105.942203 -280.236146) (xy 105.996151 -280.243902) (xy 106.048446 -280.259257)
			(xy 106.098023 -280.281899) (xy 106.143873 -280.311365) (xy 106.185064 -280.347056) (xy 106.220755 -280.388247)
			(xy 106.250221 -280.434097) (xy 106.272863 -280.483674) (xy 106.288218 -280.535969) (xy 106.295974 -280.589917)
			(xy 106.29646 -280.617168) (xy 106.296423 -280.627921) (xy 106.295279 -280.649397) (xy 106.294174 -280.660094)
			(xy 106.293158 -280.669746) (xy 106.29519 -280.678128) (xy 106.296302 -280.68215) (xy 106.299622 -280.689805)
			(xy 106.301794 -280.693368) (xy 106.34345 -280.750518) (xy 106.343958 -280.75128) (xy 106.346863 -280.754925)
			(xy 106.353765 -280.761188) (xy 106.357674 -280.763726) (xy 106.365548 -280.768552) (xy 106.372152 -280.770076)
			(xy 106.374692 -280.770584) (xy 106.390186 -280.77414) (xy 106.399838 -280.776426) (xy 106.408982 -280.775156)
			(xy 106.413139 -280.774547) (xy 106.421181 -280.772118) (xy 106.424984 -280.77033) (xy 106.490516 -280.732738)
			(xy 106.496612 -280.728166) (xy 106.503724 -280.7208) (xy 106.509312 -280.713688) (xy 106.51236 -280.703782)
			(xy 106.520627 -280.677107) (xy 106.543872 -280.62633) (xy 106.574263 -280.57948) (xy 106.611151 -280.537553)
			(xy 106.653752 -280.501446) (xy 106.701157 -280.471926) (xy 106.752354 -280.449623) (xy 106.806254 -280.435014)
			(xy 106.833924 -280.43124) (xy 106.84764 -280.429716) (xy 106.878628 -280.428446) (xy 106.903893 -280.428853)
			(xy 106.953981 -280.435528) (xy 107.002745 -280.448768) (xy 107.026202 -280.458164) (xy 107.036362 -280.462482)
			(xy 107.046268 -280.462228) (xy 107.051237 -280.462071) (xy 107.060964 -280.460027) (xy 107.065572 -280.458164)
			(xy 107.101132 -280.440892) (xy 107.10164 -280.440892) (xy 107.135676 -280.424636) (xy 107.140423 -280.422269)
			(xy 107.148877 -280.415865) (xy 107.15244 -280.411936) (xy 107.159298 -280.403808) (xy 107.162346 -280.39314)
			(xy 107.171138 -280.365212) (xy 107.196084 -280.312242) (xy 107.228826 -280.263704) (xy 107.268598 -280.220735)
			(xy 107.314465 -280.184345) (xy 107.365352 -280.155388) (xy 107.420065 -280.134542) (xy 107.47732 -280.122296)
			(xy 107.506516 -280.12009) (xy 107.518962 -280.119328) (xy 107.52836 -280.113994) (xy 107.53273 -280.111397)
			(xy 107.540415 -280.104747) (xy 107.5436 -280.100786) (xy 107.567984 -280.066496) (xy 107.592368 -280.031952)
			(xy 107.595002 -280.027672) (xy 107.598707 -280.01833) (xy 107.599734 -280.01341) (xy 107.601512 -280.002742)
			(xy 107.59821 -279.991312) (xy 107.591606 -279.96388) (xy 107.591606 -279.963626) (xy 107.59059 -279.9588)
			(xy 107.58805 -279.943814) (xy 107.586043 -279.929675) (xy 107.583881 -279.901198) (xy 107.583732 -279.886918)
			(xy 107.583732 -279.865582) (xy 107.585256 -279.852628) (xy 107.588307 -279.824535) (xy 107.601639 -279.769624)
			(xy 107.622932 -279.717283) (xy 107.651718 -279.668659) (xy 107.687368 -279.624817) (xy 107.729098 -279.586718)
			(xy 107.775996 -279.555197) (xy 107.827033 -279.530944) (xy 107.881091 -279.514492) (xy 107.936986 -279.5062)
			(xy 107.96524 -279.505664) (xy 107.995206 -279.506238) (xy 108.054405 -279.515584) (xy 108.111415 -279.534071)
			(xy 108.164832 -279.561244) (xy 108.213345 -279.596436) (xy 108.234988 -279.61717) (xy 108.505498 -279.887934)
			(xy 108.512702 -279.894087) (xy 108.530322 -279.901009) (xy 108.539788 -279.901396) (xy 108.619798 -279.901396)
			(xy 108.629011 -279.900951) (xy 108.646199 -279.8943) (xy 108.653326 -279.888442) (xy 109.435646 -279.106122)
			(xy 109.457222 -279.085385) (xy 109.505637 -279.050218) (xy 109.558956 -279.023052) (xy 109.615865 -279.004555)
			(xy 109.674966 -278.995183) (xy 109.704886 -278.994616) (xy 111.36122 -278.994616) (xy 111.366046 -278.994362)
			(xy 111.373194 -278.993427) (xy 111.386602 -278.988147) (xy 111.392462 -278.983948) (xy 111.39678 -278.980138)
			(xy 112.179354 -278.197564) (xy 112.183164 -278.193246) (xy 112.187423 -278.187418) (xy 112.192716 -278.173996)
			(xy 112.193578 -278.16683) (xy 112.193832 -278.162004) (xy 112.193832 -270.947896) (xy 112.194439 -270.91798)
			(xy 112.203825 -270.858887) (xy 112.22232 -270.801983) (xy 112.24947 -270.748664) (xy 112.28461 -270.700236)
			(xy 112.305338 -270.678656) (xy 116.685822 -266.298172) (xy 116.707437 -266.277392) (xy 116.755942 -266.242151)
			(xy 116.80936 -266.214928) (xy 116.866378 -266.196391) (xy 116.925593 -266.186997) (xy 116.95557 -266.186412)
			(xy 117.945662 -266.186412) (xy 117.94998 -266.186158) (xy 117.957949 -266.184952) (xy 117.972583 -266.178219)
			(xy 117.978682 -266.17295) (xy 118.02872 -266.122658) (xy 118.034812 -266.115201) (xy 118.041429 -266.097134)
			(xy 118.04094 -266.077899) (xy 118.033414 -266.060192) (xy 118.026942 -266.053062) (xy 117.958108 -265.984228)
			(xy 117.955257 -265.981522) (xy 117.948879 -265.976929) (xy 117.945408 -265.975084) (xy 117.93998 -265.972507)
			(xy 117.9283 -265.969695) (xy 117.922294 -265.969496) (xy 116.30152 -265.969496) (xy 116.291456 -265.969058)
			(xy 116.272873 -265.961323) (xy 116.265452 -265.95451) (xy 114.855244 -264.544048) (xy 114.855244 -264.543286)
			(xy 114.836702 -264.524744) (xy 114.833334 -264.521545) (xy 114.825667 -264.516302) (xy 114.821462 -264.51433)
			(xy 114.813588 -264.510774) (xy 114.804444 -264.510012) (xy 114.777241 -264.507638) (xy 114.723871 -264.496094)
			(xy 114.672692 -264.477058) (xy 114.624751 -264.450918) (xy 114.581028 -264.418209) (xy 114.542415 -264.3796)
			(xy 114.509702 -264.335879) (xy 114.483557 -264.287941) (xy 114.464516 -264.236764) (xy 114.452967 -264.183395)
			(xy 114.450622 -264.15619) (xy 114.44986 -264.147046) (xy 114.445542 -264.137394) (xy 114.437668 -264.12571)
			(xy 114.417348 -264.105644) (xy 114.417094 -264.105644) (xy 114.41684 -264.10539) (xy 114.416586 -264.10539)
			(xy 113.073942 -262.763) (xy 113.065367 -262.75745) (xy 113.045453 -262.752979) (xy 113.035334 -262.754364)
			(xy 113.003076 -262.762492) (xy 113.002568 -262.762492) (xy 112.944402 -262.777478) (xy 112.93882 -262.779392)
			(xy 112.92868 -262.785423) (xy 112.924336 -262.789416) (xy 112.919764 -262.79348) (xy 112.91316 -262.80491)
			(xy 112.911128 -262.811514) (xy 112.911128 -262.811768) (xy 112.902933 -262.837725) (xy 112.880211 -262.887187)
			(xy 112.850695 -262.932921) (xy 112.814982 -262.973999) (xy 112.773797 -263.009587) (xy 112.727974 -263.038965)
			(xy 112.678444 -263.061537) (xy 112.626209 -263.076845) (xy 112.57233 -263.084578) (xy 112.545114 -263.085072)
			(xy 112.517861 -263.08461) (xy 112.463911 -263.076854) (xy 112.411613 -263.061499) (xy 112.362034 -263.038857)
			(xy 112.316182 -263.009388) (xy 112.27499 -262.973694) (xy 112.239298 -262.932501) (xy 112.209833 -262.886647)
			(xy 112.187193 -262.837066) (xy 112.171841 -262.784768) (xy 112.164089 -262.730817) (xy 112.163606 -262.703564)
			(xy 112.164153 -262.674515) (xy 112.172962 -262.61709) (xy 112.190373 -262.561663) (xy 112.215983 -262.509514)
			(xy 112.249199 -262.461849) (xy 112.289256 -262.419768) (xy 112.335227 -262.384244) (xy 112.38605 -262.356096)
			(xy 112.440552 -262.335976) (xy 112.468914 -262.329676) (xy 112.47882 -262.327644) (xy 112.48009 -262.32739)
			(xy 112.488726 -262.32104) (xy 112.49311 -262.31765) (xy 112.500415 -262.309319) (xy 112.503204 -262.30453)
			(xy 112.540796 -262.23722) (xy 112.542735 -262.23363) (xy 112.545551 -262.225974) (xy 112.546384 -262.22198)
			(xy 112.547146 -262.21563) (xy 112.547908 -262.205724) (xy 112.54359 -262.194548) (xy 112.533463 -262.166115)
			(xy 112.523352 -262.10662) (xy 112.523524 -262.076438) (xy 112.527334 -261.949692) (xy 112.527334 -261.94766)
			(xy 112.527588 -261.94639) (xy 112.528096 -261.94258) (xy 112.528096 -261.939532) (xy 112.529112 -261.9375)
			(xy 112.529112 -261.936992) (xy 112.52962 -261.93623) (xy 112.530382 -261.934452) (xy 112.53216 -261.92988)
			(xy 112.575086 -261.837678) (xy 112.575086 -261.837424) (xy 112.57534 -261.83717) (xy 112.577118 -261.83336)
			(xy 112.578642 -261.830312) (xy 112.579658 -261.828534) (xy 112.581944 -261.823962) (xy 112.582198 -261.823708)
			(xy 112.58423 -261.822184) (xy 112.586262 -261.819898) (xy 112.589818 -261.816596) (xy 112.629188 -261.782306)
			(xy 112.629696 -261.781798) (xy 112.642532 -261.769513) (xy 112.661423 -261.739441) (xy 112.671275 -261.70532)
			(xy 112.67186 -261.687564) (xy 112.67129 -261.670969) (xy 112.66265 -261.638921) (xy 112.646019 -261.610195)
			(xy 112.622528 -261.586745) (xy 112.593773 -261.570165) (xy 112.56171 -261.561581) (xy 112.545114 -261.561072)
			(xy 112.544606 -261.561072) (xy 112.532759 -261.561364) (xy 112.509492 -261.565847) (xy 112.498378 -261.569962)
			(xy 112.494568 -261.571486) (xy 112.438688 -261.595362) (xy 112.427258 -261.598664) (xy 112.427004 -261.598918)
			(xy 112.427004 -261.598664) (xy 112.423448 -261.599172) (xy 112.413542 -261.599172) (xy 112.29467 -261.58698)
			(xy 112.294162 -261.58698) (xy 112.274858 -261.585202) (xy 112.268762 -261.581138) (xy 112.266984 -261.580122)
			(xy 112.263174 -261.577836) (xy 112.26292 -261.577582) (xy 112.261396 -261.576566) (xy 112.13973 -261.49554)
			(xy 112.119199 -261.481243) (xy 112.082663 -261.447069) (xy 112.052189 -261.407395) (xy 112.028592 -261.363283)
			(xy 112.012505 -261.315913) (xy 112.004357 -261.266554) (xy 112.00384 -261.24154) (xy 112.00384 -260.536182)
			(xy 112.004094 -260.521704) (xy 112.004094 -260.520434) (xy 112.004348 -260.518656) (xy 112.004348 -260.486906)
			(xy 112.004348 -260.486652) (xy 112.004444 -260.481774) (xy 112.006232 -260.472185) (xy 112.007904 -260.467602)
			(xy 112.021112 -260.434836) (xy 112.021112 -260.434328) (xy 112.021366 -260.43382) (xy 112.022636 -260.430264)
			(xy 112.030764 -260.410198) (xy 112.031018 -260.40969) (xy 112.031526 -260.40842) (xy 112.032034 -260.407404)
			(xy 112.032288 -260.40715) (xy 112.032542 -260.406642) (xy 112.046766 -260.371844) (xy 112.04889 -260.367037)
			(xy 112.054785 -260.358339) (xy 112.05845 -260.354572) (xy 112.070134 -260.343142) (xy 112.08004 -260.33349)
			(xy 112.080548 -260.332982) (xy 112.08668 -260.326169) (xy 112.099642 -260.313205) (xy 112.106456 -260.307074)
			(xy 112.108488 -260.305042) (xy 112.256824 -260.156706) (xy 112.264698 -260.149086) (xy 112.26546 -260.148324)
			(xy 112.279938 -260.133338) (xy 112.291368 -260.121654) (xy 112.295105 -260.117953) (xy 112.303814 -260.112061)
			(xy 112.30864 -260.10997) (xy 112.344962 -260.095238) (xy 112.345724 -260.094984) (xy 112.347248 -260.093968)
			(xy 112.37087 -260.08457) (xy 112.371632 -260.084316) (xy 112.404398 -260.071108) (xy 112.40897 -260.069393)
			(xy 112.418566 -260.067594) (xy 112.423448 -260.067552) (xy 112.455452 -260.067552) (xy 112.458754 -260.067298)
			(xy 112.459008 -260.067298) (xy 112.472978 -260.067044) (xy 114.567208 -260.067044) (xy 114.573515 -260.065954)
			(xy 114.585345 -260.06108) (xy 114.590576 -260.057392) (xy 114.650266 -259.997702) (xy 114.656551 -259.988362)
			(xy 114.66105 -259.966333) (xy 114.658902 -259.955284) (xy 114.65179 -259.939028) (xy 114.650012 -259.936488)
			(xy 114.639852 -259.926582) (xy 114.628168 -259.919978) (xy 114.618516 -259.916168) (xy 114.606578 -259.916676)
			(xy 114.589814 -259.91693) (xy 114.589306 -259.91693) (xy 114.562068 -259.916424) (xy 114.508151 -259.908634)
			(xy 114.45589 -259.893253) (xy 114.406348 -259.870596) (xy 114.360533 -259.841122) (xy 114.319376 -259.805431)
			(xy 114.283715 -259.764249) (xy 114.254273 -259.718413) (xy 114.231651 -259.668855) (xy 114.216308 -259.616583)
			(xy 114.208556 -259.56266) (xy 114.208052 -259.535422) (xy 114.208536 -259.508169) (xy 114.21629 -259.454216)
			(xy 114.231643 -259.401917) (xy 114.254282 -259.352334) (xy 114.283747 -259.306478) (xy 114.319438 -259.265282)
			(xy 114.360628 -259.229584) (xy 114.40648 -259.200112) (xy 114.456059 -259.177465) (xy 114.508356 -259.162103)
			(xy 114.562307 -259.154341) (xy 114.58956 -259.153914) (xy 114.618705 -259.154464) (xy 114.676317 -259.163327)
			(xy 114.731909 -259.180854) (xy 114.784187 -259.206637) (xy 114.831932 -259.240074) (xy 114.874034 -259.280387)
			(xy 114.909511 -259.326637) (xy 114.937537 -259.377746) (xy 114.95746 -259.432526) (xy 114.963702 -259.461)
			(xy 114.964718 -259.465572) (xy 114.966469 -259.471103) (xy 114.972115 -259.481235) (xy 114.975894 -259.485638)
			(xy 114.980466 -259.490464) (xy 114.9858 -259.493766) (xy 114.998246 -259.499608) (xy 115.087654 -259.526786)
			(xy 115.098645 -259.528861) (xy 115.120531 -259.524384) (xy 115.129818 -259.51815) (xy 115.288568 -259.3594)
			(xy 115.292256 -259.354169) (xy 115.297134 -259.34234) (xy 115.29822 -259.336032) (xy 115.29822 -259.018024)
			(xy 115.298474 -259.004054) (xy 115.298474 -259.0038) (xy 115.298728 -259.000498) (xy 115.298728 -258.987036)
			(xy 115.30076 -258.973066) (xy 115.302284 -258.967478) (xy 115.302792 -258.965446) (xy 115.306289 -258.946997)
			(xy 115.317244 -258.911079) (xy 115.324636 -258.893818) (xy 115.325906 -258.891024) (xy 115.327176 -258.887214)
			(xy 115.3287 -258.882134) (xy 115.33124 -258.878324) (xy 115.337082 -258.86918) (xy 115.33759 -258.868418)
			(xy 115.337844 -258.86791) (xy 115.348258 -258.850892) (xy 115.355946 -258.838363) (xy 115.365954 -258.810732)
			(xy 115.369357 -258.781542) (xy 115.365974 -258.75235) (xy 115.355984 -258.724712) (xy 115.348258 -258.712208)
			(xy 115.337844 -258.69519) (xy 115.33759 -258.694682) (xy 115.337082 -258.69392) (xy 115.33124 -258.684776)
			(xy 115.3287 -258.680966) (xy 115.327176 -258.675886) (xy 115.325906 -258.672076) (xy 115.324636 -258.669282)
			(xy 115.317275 -258.65201) (xy 115.306326 -258.616094) (xy 115.302792 -258.597654) (xy 115.302284 -258.595622)
			(xy 115.30076 -258.590034) (xy 115.298728 -258.576064) (xy 115.298728 -258.562602) (xy 115.298474 -258.5593)
			(xy 115.298474 -258.559046) (xy 115.29822 -258.545076) (xy 115.29822 -255.617218) (xy 115.298749 -255.591144)
			(xy 115.307604 -255.539754) (xy 115.325061 -255.490615) (xy 115.350611 -255.445155) (xy 115.383513 -255.404696)
			(xy 115.422809 -255.370415) (xy 115.444778 -255.35636) (xy 115.576858 -255.276096) (xy 115.580922 -255.27381)
			(xy 115.582954 -255.272794) (xy 115.587272 -255.270254) (xy 115.587526 -255.270254) (xy 115.59159 -255.27)
			(xy 115.593368 -255.269746) (xy 115.60175 -255.26873) (xy 115.7351 -255.26492) (xy 115.735608 -255.26492)
			(xy 115.742134 -255.264857) (xy 115.754867 -255.267691) (xy 115.760754 -255.270508) (xy 115.824508 -255.304036)
			(xy 115.829334 -255.306068) (xy 115.840798 -255.310371) (xy 115.864843 -255.314983) (xy 115.877086 -255.315212)
			(xy 115.87734 -255.315212) (xy 115.892813 -255.314778) (xy 115.922847 -255.307321) (xy 115.950192 -255.292832)
			(xy 115.973229 -255.272169) (xy 115.982242 -255.259586) (xy 115.99418 -255.243076) (xy 115.994688 -255.242314)
			(xy 115.998244 -255.237488) (xy 116.00053 -255.235456) (xy 116.004086 -255.231138) (xy 116.010436 -255.216152)
			(xy 116.010436 -255.215898) (xy 116.01196 -255.20396) (xy 116.01196 -255.17348) (xy 116.010436 -255.161542)
			(xy 116.010436 -255.161288) (xy 116.004086 -255.146302) (xy 116.00053 -255.141984) (xy 115.998244 -255.139952)
			(xy 115.994688 -255.135126) (xy 115.99418 -255.134364) (xy 115.982242 -255.117854) (xy 115.973197 -255.105296)
			(xy 115.950168 -255.084631) (xy 115.922835 -255.070134) (xy 115.89281 -255.062659) (xy 115.87734 -255.062228)
			(xy 115.877086 -255.062228) (xy 115.863039 -255.062515) (xy 115.835603 -255.068537) (xy 115.82273 -255.074166)
			(xy 115.81892 -255.076198) (xy 115.818666 -255.076452) (xy 115.760754 -255.106932) (xy 115.749832 -255.110996)
			(xy 115.748562 -255.111758) (xy 115.747292 -255.111758) (xy 115.745006 -255.113028) (xy 115.739926 -255.112774)
			(xy 115.739672 -255.112774) (xy 115.737386 -255.11252) (xy 115.735354 -255.11252) (xy 115.677188 -255.110742)
			(xy 115.594384 -255.108456) (xy 115.591336 -255.109472) (xy 115.589304 -255.108202) (xy 115.588288 -255.108202)
			(xy 115.580922 -255.10363) (xy 115.52555 -255.1176) (xy 115.525042 -255.1176) (xy 115.489736 -255.126744)
			(xy 115.485119 -255.12807) (xy 115.476431 -255.132164) (xy 115.472464 -255.134872) (xy 115.465098 -255.140206)
			(xy 115.45951 -255.149604) (xy 115.459002 -255.150112) (xy 115.444173 -255.174188) (xy 115.408531 -255.218082)
			(xy 115.366802 -255.256237) (xy 115.319899 -255.287816) (xy 115.268851 -255.31213) (xy 115.214773 -255.328644)
			(xy 115.158851 -255.336999) (xy 115.13058 -255.337564) (xy 115.125754 -255.337564) (xy 115.11534 -255.337056)
			(xy 115.103922 -255.336504) (xy 115.081173 -255.334218) (xy 115.069874 -255.332484) (xy 115.03864 -255.326837)
			(xy 114.978504 -255.306541) (xy 114.95024 -255.292098) (xy 114.94516 -255.289304) (xy 114.940334 -255.286764)
			(xy 114.933222 -255.286256) (xy 114.927888 -255.286002) (xy 114.922977 -255.285867) (xy 114.913254 -255.287269)
			(xy 114.908584 -255.288796) (xy 114.88801 -255.29667) (xy 114.833146 -255.317498) (xy 114.829094 -255.319457)
			(xy 114.82169 -255.324572) (xy 114.818414 -255.327658) (xy 114.811302 -255.334516) (xy 114.81054 -255.336548)
			(xy 114.806984 -255.345692) (xy 114.806984 -255.345946) (xy 114.796249 -255.372707) (xy 114.767892 -255.422911)
			(xy 114.732309 -255.46828) (xy 114.690307 -255.507783) (xy 114.642844 -255.54052) (xy 114.590997 -255.565748)
			(xy 114.535946 -255.582893) (xy 114.478943 -255.591566) (xy 114.450114 -255.592072) (xy 114.422863 -255.59161)
			(xy 114.368916 -255.583855) (xy 114.316621 -255.568502) (xy 114.267044 -255.545862) (xy 114.221193 -255.516397)
			(xy 114.180003 -255.480707) (xy 114.144311 -255.439518) (xy 114.114845 -255.393668) (xy 114.092203 -255.344092)
			(xy 114.076848 -255.291798) (xy 114.069091 -255.237851) (xy 114.069091 -255.183349) (xy 114.076848 -255.129402)
			(xy 114.092203 -255.077108) (xy 114.114845 -255.027532) (xy 114.144311 -254.981682) (xy 114.180003 -254.940493)
			(xy 114.221193 -254.904803) (xy 114.267044 -254.875338) (xy 114.316621 -254.852698) (xy 114.368916 -254.837345)
			(xy 114.422863 -254.82959) (xy 114.450114 -254.829056) (xy 114.450368 -254.829056) (xy 114.481646 -254.829684)
			(xy 114.543364 -254.839897) (xy 114.602585 -254.860054) (xy 114.630454 -254.874268) (xy 114.635534 -254.877062)
			(xy 114.64036 -254.879602) (xy 114.647472 -254.88011) (xy 114.652806 -254.880364) (xy 114.657718 -254.8805)
			(xy 114.667441 -254.879101) (xy 114.67211 -254.87757) (xy 114.692684 -254.869696) (xy 114.748564 -254.84836)
			(xy 114.752332 -254.846468) (xy 114.759226 -254.841615) (xy 114.76228 -254.838708) (xy 114.769138 -254.832104)
			(xy 114.773456 -254.820674) (xy 114.784165 -254.793862) (xy 114.812493 -254.743556) (xy 114.848075 -254.698091)
			(xy 114.890099 -254.658504) (xy 114.937606 -254.625699) (xy 114.989513 -254.600424) (xy 115.044634 -254.583256)
			(xy 115.101713 -254.574587) (xy 115.13058 -254.57404) (xy 115.137184 -254.57404) (xy 115.1509 -254.574802)
			(xy 115.151154 -254.574802) (xy 115.178332 -254.577088) (xy 115.17884 -254.577088) (xy 115.193115 -254.579074)
			(xy 115.221339 -254.584923) (xy 115.235228 -254.588772) (xy 115.238784 -254.589788) (xy 115.253262 -254.59182)
			(xy 115.258431 -254.591637) (xy 115.268543 -254.589466) (xy 115.273328 -254.587502) (xy 115.281202 -254.583946)
			(xy 115.287298 -254.578104) (xy 115.290245 -254.575111) (xy 115.295215 -254.568342) (xy 115.297204 -254.564642)
			(xy 115.31473 -254.528066) (xy 115.327176 -254.501904) (xy 115.32743 -254.501396) (xy 115.332733 -254.488903)
			(xy 115.338487 -254.462385) (xy 115.33886 -254.448818) (xy 115.338606 -254.448564) (xy 115.33886 -254.44831)
			(xy 115.338507 -254.434741) (xy 115.33274 -254.408224) (xy 115.32743 -254.395732) (xy 115.327176 -254.395224)
			(xy 115.303046 -254.344678) (xy 115.301776 -254.342138) (xy 115.301522 -254.341376) (xy 115.29949 -254.334772)
			(xy 115.298728 -254.33274) (xy 115.298728 -254.3302) (xy 115.29822 -254.32639) (xy 115.29822 -253.137924)
			(xy 115.298474 -253.123446) (xy 115.298474 -253.122176) (xy 115.298728 -253.120398) (xy 115.298728 -253.088648)
			(xy 115.298728 -253.088394) (xy 115.298829 -253.083517) (xy 115.300626 -253.073932) (xy 115.302284 -253.069344)
			(xy 115.315492 -253.036578) (xy 115.315492 -253.036324) (xy 115.315746 -253.035562) (xy 115.317016 -253.032006)
			(xy 115.325144 -253.01194) (xy 115.325398 -253.011432) (xy 115.325906 -253.010162) (xy 115.326414 -253.009146)
			(xy 115.326668 -253.008892) (xy 115.326922 -253.008384) (xy 115.341146 -252.973586) (xy 115.343266 -252.968776)
			(xy 115.349155 -252.960071) (xy 115.35283 -252.956314) (xy 115.364514 -252.944884) (xy 115.37442 -252.935232)
			(xy 115.374928 -252.934724) (xy 115.38106 -252.927911) (xy 115.394023 -252.914949) (xy 115.400836 -252.908816)
			(xy 115.402868 -252.906784) (xy 115.494562 -252.81509) (xy 115.502436 -252.80747) (xy 115.503198 -252.806708)
			(xy 115.517676 -252.791722) (xy 115.529106 -252.780038) (xy 115.532841 -252.776334) (xy 115.541547 -252.770433)
			(xy 115.546378 -252.768354) (xy 115.5827 -252.753622) (xy 115.583462 -252.753368) (xy 115.584986 -252.752352)
			(xy 115.608608 -252.742954) (xy 115.60937 -252.7427) (xy 115.642136 -252.729492) (xy 115.646711 -252.727789)
			(xy 115.656305 -252.725998) (xy 115.661186 -252.725936) (xy 115.69319 -252.725936) (xy 115.696492 -252.725682)
			(xy 115.696746 -252.725682) (xy 115.710716 -252.725428) (xy 117.812312 -252.725428) (xy 117.82679 -252.725682)
			(xy 117.82806 -252.725682) (xy 117.829838 -252.725936) (xy 117.861588 -252.725936) (xy 117.861842 -252.725936)
			(xy 117.86672 -252.726031) (xy 117.87631 -252.727818) (xy 117.880892 -252.729492) (xy 117.913658 -252.7427)
			(xy 117.913912 -252.7427) (xy 117.914674 -252.742954) (xy 117.938296 -252.752352) (xy 117.938804 -252.752606)
			(xy 117.93982 -252.753114) (xy 117.94109 -252.753622) (xy 117.941344 -252.753876) (xy 117.941852 -252.75413)
			(xy 117.97665 -252.768354) (xy 117.981457 -252.770477) (xy 117.990157 -252.77637) (xy 117.993922 -252.780038)
			(xy 118.005352 -252.791722) (xy 118.015004 -252.801628) (xy 118.015512 -252.802136) (xy 118.02618 -252.812042)
			(xy 118.041674 -252.828044) (xy 118.04269 -252.829314) (xy 118.193566 -252.98019) (xy 118.202689 -252.98828)
			(xy 118.225909 -252.995592) (xy 118.238016 -252.99416) (xy 118.245382 -252.99289) (xy 118.322852 -252.978666)
			(xy 118.333509 -252.975495) (xy 118.350888 -252.961664) (xy 118.35638 -252.951996) (xy 118.367961 -252.92697)
			(xy 118.397262 -252.880255) (xy 118.43298 -252.838242) (xy 118.47437 -252.801805) (xy 118.520573 -252.771703)
			(xy 118.570626 -252.748561) (xy 118.623488 -252.732862) (xy 118.678058 -252.724932) (xy 118.70563 -252.724412)
			(xy 118.732879 -252.7249) (xy 118.786823 -252.73266) (xy 118.839113 -252.748018) (xy 118.888685 -252.770661)
			(xy 118.93453 -252.800129) (xy 118.975715 -252.835821) (xy 119.011401 -252.87701) (xy 119.040863 -252.922859)
			(xy 119.063499 -252.972434) (xy 119.07885 -253.024726) (xy 119.086603 -253.078671) (xy 119.087138 -253.10592)
			(xy 119.086673 -253.13286) (xy 119.07909 -253.186204) (xy 119.064078 -253.23795) (xy 119.041935 -253.287069)
			(xy 119.013102 -253.332585) (xy 118.978152 -253.373592) (xy 118.962009 -253.38786) (xy 126.243078 -253.38786)
			(xy 126.247149 -253.332238) (xy 126.259275 -253.277801) (xy 126.279198 -253.22571) (xy 126.306494 -253.177075)
			(xy 126.34058 -253.132932) (xy 126.380729 -253.094223) (xy 126.426087 -253.061772) (xy 126.475687 -253.036271)
			(xy 126.528471 -253.018264) (xy 126.583314 -253.008134) (xy 126.639048 -253.006097) (xy 126.694485 -253.012197)
			(xy 126.748442 -253.026303) (xy 126.799771 -253.048115) (xy 126.847377 -253.077169) (xy 126.890245 -253.112844)
			(xy 126.927462 -253.154381) (xy 126.943461 -253.178564) (xy 128.285746 -253.178564) (xy 128.289817 -253.122942)
			(xy 128.301943 -253.068505) (xy 128.321866 -253.016414) (xy 128.349162 -252.967779) (xy 128.383248 -252.923636)
			(xy 128.423397 -252.884927) (xy 128.468755 -252.852476) (xy 128.518355 -252.826975) (xy 128.571139 -252.808968)
			(xy 128.625982 -252.798838) (xy 128.681716 -252.796801) (xy 128.737153 -252.802901) (xy 128.79111 -252.817007)
			(xy 128.842439 -252.838819) (xy 128.890045 -252.867873) (xy 128.932913 -252.903548) (xy 128.97013 -252.945085)
			(xy 129.000903 -252.991598) (xy 129.024575 -253.042095) (xy 129.040643 -253.095502) (xy 129.048763 -253.150678)
			(xy 129.049272 -253.178564) (xy 130.349242 -253.178564) (xy 130.353313 -253.122942) (xy 130.365439 -253.068505)
			(xy 130.385362 -253.016414) (xy 130.412658 -252.967779) (xy 130.446744 -252.923636) (xy 130.486893 -252.884927)
			(xy 130.532251 -252.852476) (xy 130.581851 -252.826975) (xy 130.634635 -252.808968) (xy 130.689478 -252.798838)
			(xy 130.745212 -252.796801) (xy 130.800649 -252.802901) (xy 130.854606 -252.817007) (xy 130.905935 -252.838819)
			(xy 130.953541 -252.867873) (xy 130.996409 -252.903548) (xy 131.033626 -252.945085) (xy 131.064399 -252.991598)
			(xy 131.088071 -253.042095) (xy 131.104139 -253.095502) (xy 131.112259 -253.150678) (xy 131.112768 -253.178564)
			(xy 131.112259 -253.20645) (xy 131.104139 -253.261626) (xy 131.088071 -253.315033) (xy 131.064399 -253.36553)
			(xy 131.033626 -253.412043) (xy 130.996409 -253.45358) (xy 130.953541 -253.489255) (xy 130.905935 -253.518309)
			(xy 130.854606 -253.540121) (xy 130.800649 -253.554227) (xy 130.745212 -253.560327) (xy 130.689478 -253.55829)
			(xy 130.634635 -253.54816) (xy 130.581851 -253.530153) (xy 130.532251 -253.504652) (xy 130.486893 -253.472201)
			(xy 130.446744 -253.433492) (xy 130.412658 -253.389349) (xy 130.385362 -253.340714) (xy 130.365439 -253.288623)
			(xy 130.353313 -253.234186) (xy 130.349242 -253.178564) (xy 129.049272 -253.178564) (xy 129.048763 -253.20645)
			(xy 129.040643 -253.261626) (xy 129.024575 -253.315033) (xy 129.000903 -253.36553) (xy 128.97013 -253.412043)
			(xy 128.932913 -253.45358) (xy 128.890045 -253.489255) (xy 128.842439 -253.518309) (xy 128.79111 -253.540121)
			(xy 128.737153 -253.554227) (xy 128.681716 -253.560327) (xy 128.625982 -253.55829) (xy 128.571139 -253.54816)
			(xy 128.518355 -253.530153) (xy 128.468755 -253.504652) (xy 128.423397 -253.472201) (xy 128.383248 -253.433492)
			(xy 128.349162 -253.389349) (xy 128.321866 -253.340714) (xy 128.301943 -253.288623) (xy 128.289817 -253.234186)
			(xy 128.285746 -253.178564) (xy 126.943461 -253.178564) (xy 126.958235 -253.200894) (xy 126.981907 -253.251391)
			(xy 126.997975 -253.304798) (xy 127.006095 -253.359974) (xy 127.006604 -253.38786) (xy 127.006095 -253.415746)
			(xy 126.997975 -253.470922) (xy 126.981907 -253.524329) (xy 126.958235 -253.574826) (xy 126.927462 -253.621339)
			(xy 126.890245 -253.662876) (xy 126.847377 -253.698551) (xy 126.799771 -253.727605) (xy 126.748442 -253.749417)
			(xy 126.694485 -253.763523) (xy 126.639048 -253.769623) (xy 126.583314 -253.767586) (xy 126.528471 -253.757456)
			(xy 126.475687 -253.739449) (xy 126.426087 -253.713948) (xy 126.380729 -253.681497) (xy 126.34058 -253.642788)
			(xy 126.306494 -253.598645) (xy 126.279198 -253.55001) (xy 126.259275 -253.497919) (xy 126.247149 -253.443482)
			(xy 126.243078 -253.38786) (xy 118.962009 -253.38786) (xy 118.93778 -253.409274) (xy 118.892791 -253.438921)
			(xy 118.844077 -253.461944) (xy 118.79261 -253.477885) (xy 118.766082 -253.482602) (xy 118.756684 -253.484126)
			(xy 118.749064 -253.488444) (xy 118.745858 -253.490342) (xy 118.73999 -253.49493) (xy 118.73738 -253.497588)
			(xy 118.731792 -253.503938) (xy 118.692676 -253.551436) (xy 118.689768 -253.555048) (xy 118.685171 -253.5631)
			(xy 118.683532 -253.567438) (xy 118.680738 -253.57582) (xy 118.680992 -253.585218) (xy 118.680992 -253.593346)
			(xy 118.680992 -253.593854) (xy 118.680992 -253.985014) (xy 121.718576 -253.985014) (xy 121.722647 -253.929392)
			(xy 121.734773 -253.874955) (xy 121.754696 -253.822864) (xy 121.781992 -253.774229) (xy 121.816078 -253.730086)
			(xy 121.856227 -253.691377) (xy 121.901585 -253.658926) (xy 121.951185 -253.633425) (xy 122.003969 -253.615418)
			(xy 122.058812 -253.605288) (xy 122.114546 -253.603251) (xy 122.169983 -253.609351) (xy 122.22394 -253.623457)
			(xy 122.275269 -253.645269) (xy 122.322875 -253.674323) (xy 122.365743 -253.709998) (xy 122.40296 -253.751535)
			(xy 122.433733 -253.798048) (xy 122.457405 -253.848545) (xy 122.473473 -253.901952) (xy 122.481593 -253.957128)
			(xy 122.482102 -253.985014) (xy 122.481593 -254.0129) (xy 122.473473 -254.068076) (xy 122.457405 -254.121483)
			(xy 122.433733 -254.17198) (xy 122.418791 -254.194564) (xy 130.317746 -254.194564) (xy 130.321817 -254.138942)
			(xy 130.333943 -254.084505) (xy 130.353866 -254.032414) (xy 130.381162 -253.983779) (xy 130.415248 -253.939636)
			(xy 130.455397 -253.900927) (xy 130.500755 -253.868476) (xy 130.550355 -253.842975) (xy 130.603139 -253.824968)
			(xy 130.657982 -253.814838) (xy 130.713716 -253.812801) (xy 130.769153 -253.818901) (xy 130.82311 -253.833007)
			(xy 130.874439 -253.854819) (xy 130.922045 -253.883873) (xy 130.964913 -253.919548) (xy 131.00213 -253.961085)
			(xy 131.032903 -254.007598) (xy 131.056575 -254.058095) (xy 131.072643 -254.111502) (xy 131.080763 -254.166678)
			(xy 131.081272 -254.194564) (xy 131.080763 -254.22245) (xy 131.072643 -254.277626) (xy 131.056575 -254.331033)
			(xy 131.032903 -254.38153) (xy 131.00213 -254.428043) (xy 130.964913 -254.46958) (xy 130.922045 -254.505255)
			(xy 130.874439 -254.534309) (xy 130.82311 -254.556121) (xy 130.769153 -254.570227) (xy 130.713716 -254.576327)
			(xy 130.657982 -254.57429) (xy 130.603139 -254.56416) (xy 130.550355 -254.546153) (xy 130.500755 -254.520652)
			(xy 130.455397 -254.488201) (xy 130.415248 -254.449492) (xy 130.381162 -254.405349) (xy 130.353866 -254.356714)
			(xy 130.333943 -254.304623) (xy 130.321817 -254.250186) (xy 130.317746 -254.194564) (xy 122.418791 -254.194564)
			(xy 122.40296 -254.218493) (xy 122.365743 -254.26003) (xy 122.322875 -254.295705) (xy 122.275269 -254.324759)
			(xy 122.22394 -254.346571) (xy 122.169983 -254.360677) (xy 122.114546 -254.366777) (xy 122.058812 -254.36474)
			(xy 122.003969 -254.35461) (xy 121.951185 -254.336603) (xy 121.901585 -254.311102) (xy 121.856227 -254.278651)
			(xy 121.816078 -254.239942) (xy 121.781992 -254.195799) (xy 121.754696 -254.147164) (xy 121.734773 -254.095073)
			(xy 121.722647 -254.040636) (xy 121.718576 -253.985014) (xy 118.680992 -253.985014) (xy 118.680992 -255.11125)
			(xy 120.99366 -255.11125) (xy 120.997731 -255.055628) (xy 121.009857 -255.001191) (xy 121.02978 -254.9491)
			(xy 121.057076 -254.900465) (xy 121.091162 -254.856322) (xy 121.131311 -254.817613) (xy 121.176669 -254.785162)
			(xy 121.226269 -254.759661) (xy 121.279053 -254.741654) (xy 121.333896 -254.731524) (xy 121.38963 -254.729487)
			(xy 121.445067 -254.735587) (xy 121.499024 -254.749693) (xy 121.550353 -254.771505) (xy 121.597959 -254.800559)
			(xy 121.640827 -254.836234) (xy 121.678044 -254.877771) (xy 121.708817 -254.924284) (xy 121.732489 -254.974781)
			(xy 121.748557 -255.028188) (xy 121.756677 -255.083364) (xy 121.757186 -255.11125) (xy 121.756677 -255.139136)
			(xy 121.748557 -255.194312) (xy 121.743667 -255.210564) (xy 130.349242 -255.210564) (xy 130.353313 -255.154942)
			(xy 130.365439 -255.100505) (xy 130.385362 -255.048414) (xy 130.412658 -254.999779) (xy 130.446744 -254.955636)
			(xy 130.486893 -254.916927) (xy 130.532251 -254.884476) (xy 130.581851 -254.858975) (xy 130.634635 -254.840968)
			(xy 130.689478 -254.830838) (xy 130.745212 -254.828801) (xy 130.800649 -254.834901) (xy 130.854606 -254.849007)
			(xy 130.905935 -254.870819) (xy 130.953541 -254.899873) (xy 130.996409 -254.935548) (xy 131.033626 -254.977085)
			(xy 131.064399 -255.023598) (xy 131.088071 -255.074095) (xy 131.104139 -255.127502) (xy 131.112259 -255.182678)
			(xy 131.112768 -255.210564) (xy 131.112259 -255.23845) (xy 131.104139 -255.293626) (xy 131.088071 -255.347033)
			(xy 131.064399 -255.39753) (xy 131.033626 -255.444043) (xy 130.996409 -255.48558) (xy 130.953541 -255.521255)
			(xy 130.905935 -255.550309) (xy 130.854606 -255.572121) (xy 130.800649 -255.586227) (xy 130.745212 -255.592327)
			(xy 130.689478 -255.59029) (xy 130.634635 -255.58016) (xy 130.581851 -255.562153) (xy 130.532251 -255.536652)
			(xy 130.486893 -255.504201) (xy 130.446744 -255.465492) (xy 130.412658 -255.421349) (xy 130.385362 -255.372714)
			(xy 130.365439 -255.320623) (xy 130.353313 -255.266186) (xy 130.349242 -255.210564) (xy 121.743667 -255.210564)
			(xy 121.732489 -255.247719) (xy 121.708817 -255.298216) (xy 121.678044 -255.344729) (xy 121.640827 -255.386266)
			(xy 121.597959 -255.421941) (xy 121.550353 -255.450995) (xy 121.499024 -255.472807) (xy 121.445067 -255.486913)
			(xy 121.38963 -255.493013) (xy 121.333896 -255.490976) (xy 121.279053 -255.480846) (xy 121.226269 -255.462839)
			(xy 121.176669 -255.437338) (xy 121.131311 -255.404887) (xy 121.091162 -255.366178) (xy 121.057076 -255.322035)
			(xy 121.02978 -255.2734) (xy 121.009857 -255.221309) (xy 120.997731 -255.166872) (xy 120.99366 -255.11125)
			(xy 118.680992 -255.11125) (xy 118.680992 -256.226564) (xy 126.220472 -256.226564) (xy 126.224543 -256.170942)
			(xy 126.236669 -256.116505) (xy 126.256592 -256.064414) (xy 126.283888 -256.015779) (xy 126.317974 -255.971636)
			(xy 126.358123 -255.932927) (xy 126.403481 -255.900476) (xy 126.453081 -255.874975) (xy 126.505865 -255.856968)
			(xy 126.560708 -255.846838) (xy 126.616442 -255.844801) (xy 126.671879 -255.850901) (xy 126.725836 -255.865007)
			(xy 126.777165 -255.886819) (xy 126.824771 -255.915873) (xy 126.867639 -255.951548) (xy 126.904856 -255.993085)
			(xy 126.935629 -256.039598) (xy 126.959301 -256.090095) (xy 126.975369 -256.143502) (xy 126.983489 -256.198678)
			(xy 126.983998 -256.226564) (xy 128.285746 -256.226564) (xy 128.289817 -256.170942) (xy 128.301943 -256.116505)
			(xy 128.321866 -256.064414) (xy 128.349162 -256.015779) (xy 128.383248 -255.971636) (xy 128.423397 -255.932927)
			(xy 128.468755 -255.900476) (xy 128.518355 -255.874975) (xy 128.571139 -255.856968) (xy 128.625982 -255.846838)
			(xy 128.681716 -255.844801) (xy 128.737153 -255.850901) (xy 128.79111 -255.865007) (xy 128.842439 -255.886819)
			(xy 128.890045 -255.915873) (xy 128.932913 -255.951548) (xy 128.97013 -255.993085) (xy 129.000903 -256.039598)
			(xy 129.024575 -256.090095) (xy 129.040643 -256.143502) (xy 129.048763 -256.198678) (xy 129.049272 -256.226564)
			(xy 129.048763 -256.25445) (xy 129.040643 -256.309626) (xy 129.024575 -256.363033) (xy 129.000903 -256.41353)
			(xy 128.97013 -256.460043) (xy 128.932913 -256.50158) (xy 128.890045 -256.537255) (xy 128.842439 -256.566309)
			(xy 128.79111 -256.588121) (xy 128.737153 -256.602227) (xy 128.681716 -256.608327) (xy 128.625982 -256.60629)
			(xy 128.571139 -256.59616) (xy 128.518355 -256.578153) (xy 128.468755 -256.552652) (xy 128.423397 -256.520201)
			(xy 128.383248 -256.481492) (xy 128.349162 -256.437349) (xy 128.321866 -256.388714) (xy 128.301943 -256.336623)
			(xy 128.289817 -256.282186) (xy 128.285746 -256.226564) (xy 126.983998 -256.226564) (xy 126.983489 -256.25445)
			(xy 126.975369 -256.309626) (xy 126.959301 -256.363033) (xy 126.935629 -256.41353) (xy 126.904856 -256.460043)
			(xy 126.867639 -256.50158) (xy 126.824771 -256.537255) (xy 126.777165 -256.566309) (xy 126.725836 -256.588121)
			(xy 126.671879 -256.602227) (xy 126.616442 -256.608327) (xy 126.560708 -256.60629) (xy 126.505865 -256.59616)
			(xy 126.453081 -256.578153) (xy 126.403481 -256.552652) (xy 126.358123 -256.520201) (xy 126.317974 -256.481492)
			(xy 126.283888 -256.437349) (xy 126.256592 -256.388714) (xy 126.236669 -256.336623) (xy 126.224543 -256.282186)
			(xy 126.220472 -256.226564) (xy 118.680992 -256.226564) (xy 118.680992 -257.115564) (xy 128.285746 -257.115564)
			(xy 128.289817 -257.059942) (xy 128.301943 -257.005505) (xy 128.321866 -256.953414) (xy 128.349162 -256.904779)
			(xy 128.383248 -256.860636) (xy 128.423397 -256.821927) (xy 128.468755 -256.789476) (xy 128.518355 -256.763975)
			(xy 128.571139 -256.745968) (xy 128.625982 -256.735838) (xy 128.681716 -256.733801) (xy 128.737153 -256.739901)
			(xy 128.79111 -256.754007) (xy 128.842439 -256.775819) (xy 128.890045 -256.804873) (xy 128.932913 -256.840548)
			(xy 128.97013 -256.882085) (xy 129.000903 -256.928598) (xy 129.024575 -256.979095) (xy 129.040643 -257.032502)
			(xy 129.048763 -257.087678) (xy 129.049272 -257.115564) (xy 129.048763 -257.14345) (xy 129.040643 -257.198626)
			(xy 129.024575 -257.252033) (xy 129.000903 -257.30253) (xy 128.97013 -257.349043) (xy 128.932913 -257.39058)
			(xy 128.890045 -257.426255) (xy 128.842439 -257.455309) (xy 128.79111 -257.477121) (xy 128.737153 -257.491227)
			(xy 128.681716 -257.497327) (xy 128.625982 -257.49529) (xy 128.571139 -257.48516) (xy 128.518355 -257.467153)
			(xy 128.468755 -257.441652) (xy 128.423397 -257.409201) (xy 128.383248 -257.370492) (xy 128.349162 -257.326349)
			(xy 128.321866 -257.277714) (xy 128.301943 -257.225623) (xy 128.289817 -257.171186) (xy 128.285746 -257.115564)
			(xy 118.680992 -257.115564) (xy 118.680992 -258.131564) (xy 126.258572 -258.131564) (xy 126.262643 -258.075942)
			(xy 126.274769 -258.021505) (xy 126.294692 -257.969414) (xy 126.321988 -257.920779) (xy 126.356074 -257.876636)
			(xy 126.396223 -257.837927) (xy 126.441581 -257.805476) (xy 126.491181 -257.779975) (xy 126.543965 -257.761968)
			(xy 126.598808 -257.751838) (xy 126.654542 -257.749801) (xy 126.709979 -257.755901) (xy 126.763936 -257.770007)
			(xy 126.815265 -257.791819) (xy 126.862871 -257.820873) (xy 126.905739 -257.856548) (xy 126.942956 -257.898085)
			(xy 126.973729 -257.944598) (xy 126.997401 -257.995095) (xy 127.013469 -258.048502) (xy 127.021589 -258.103678)
			(xy 127.022098 -258.131564) (xy 130.317746 -258.131564) (xy 130.321817 -258.075942) (xy 130.333943 -258.021505)
			(xy 130.353866 -257.969414) (xy 130.381162 -257.920779) (xy 130.415248 -257.876636) (xy 130.455397 -257.837927)
			(xy 130.500755 -257.805476) (xy 130.550355 -257.779975) (xy 130.603139 -257.761968) (xy 130.657982 -257.751838)
			(xy 130.713716 -257.749801) (xy 130.769153 -257.755901) (xy 130.82311 -257.770007) (xy 130.874439 -257.791819)
			(xy 130.922045 -257.820873) (xy 130.964913 -257.856548) (xy 131.00213 -257.898085) (xy 131.032903 -257.944598)
			(xy 131.056575 -257.995095) (xy 131.072643 -258.048502) (xy 131.080763 -258.103678) (xy 131.081272 -258.131564)
			(xy 131.080763 -258.15945) (xy 131.072643 -258.214626) (xy 131.056575 -258.268033) (xy 131.032903 -258.31853)
			(xy 131.00213 -258.365043) (xy 130.964913 -258.40658) (xy 130.922045 -258.442255) (xy 130.874439 -258.471309)
			(xy 130.82311 -258.493121) (xy 130.769153 -258.507227) (xy 130.713716 -258.513327) (xy 130.657982 -258.51129)
			(xy 130.603139 -258.50116) (xy 130.550355 -258.483153) (xy 130.500755 -258.457652) (xy 130.455397 -258.425201)
			(xy 130.415248 -258.386492) (xy 130.381162 -258.342349) (xy 130.353866 -258.293714) (xy 130.333943 -258.241623)
			(xy 130.321817 -258.187186) (xy 130.317746 -258.131564) (xy 127.022098 -258.131564) (xy 127.021589 -258.15945)
			(xy 127.013469 -258.214626) (xy 126.997401 -258.268033) (xy 126.973729 -258.31853) (xy 126.942956 -258.365043)
			(xy 126.905739 -258.40658) (xy 126.862871 -258.442255) (xy 126.815265 -258.471309) (xy 126.763936 -258.493121)
			(xy 126.709979 -258.507227) (xy 126.654542 -258.513327) (xy 126.598808 -258.51129) (xy 126.543965 -258.50116)
			(xy 126.491181 -258.483153) (xy 126.441581 -258.457652) (xy 126.396223 -258.425201) (xy 126.356074 -258.386492)
			(xy 126.321988 -258.342349) (xy 126.294692 -258.293714) (xy 126.274769 -258.241623) (xy 126.262643 -258.187186)
			(xy 126.258572 -258.131564) (xy 118.680992 -258.131564) (xy 118.680992 -259.19176) (xy 123.580396 -259.19176)
			(xy 123.584467 -259.136138) (xy 123.596593 -259.081701) (xy 123.616516 -259.02961) (xy 123.643812 -258.980975)
			(xy 123.677898 -258.936832) (xy 123.718047 -258.898123) (xy 123.763405 -258.865672) (xy 123.813005 -258.840171)
			(xy 123.865789 -258.822164) (xy 123.920632 -258.812034) (xy 123.976366 -258.809997) (xy 124.031803 -258.816097)
			(xy 124.08576 -258.830203) (xy 124.137089 -258.852015) (xy 124.184695 -258.881069) (xy 124.227563 -258.916744)
			(xy 124.26478 -258.958281) (xy 124.295553 -259.004794) (xy 124.319225 -259.055291) (xy 124.335293 -259.108698)
			(xy 124.341013 -259.147564) (xy 130.338828 -259.147564) (xy 130.342899 -259.091942) (xy 130.355025 -259.037505)
			(xy 130.374948 -258.985414) (xy 130.402244 -258.936779) (xy 130.43633 -258.892636) (xy 130.476479 -258.853927)
			(xy 130.521837 -258.821476) (xy 130.571437 -258.795975) (xy 130.624221 -258.777968) (xy 130.679064 -258.767838)
			(xy 130.734798 -258.765801) (xy 130.790235 -258.771901) (xy 130.844192 -258.786007) (xy 130.895521 -258.807819)
			(xy 130.943127 -258.836873) (xy 130.985995 -258.872548) (xy 131.023212 -258.914085) (xy 131.053985 -258.960598)
			(xy 131.077657 -259.011095) (xy 131.093725 -259.064502) (xy 131.101845 -259.119678) (xy 131.102354 -259.147564)
			(xy 131.101845 -259.17545) (xy 131.093725 -259.230626) (xy 131.077657 -259.284033) (xy 131.053985 -259.33453)
			(xy 131.023212 -259.381043) (xy 130.985995 -259.42258) (xy 130.943127 -259.458255) (xy 130.895521 -259.487309)
			(xy 130.844192 -259.509121) (xy 130.790235 -259.523227) (xy 130.734798 -259.529327) (xy 130.679064 -259.52729)
			(xy 130.624221 -259.51716) (xy 130.571437 -259.499153) (xy 130.521837 -259.473652) (xy 130.476479 -259.441201)
			(xy 130.43633 -259.402492) (xy 130.402244 -259.358349) (xy 130.374948 -259.309714) (xy 130.355025 -259.257623)
			(xy 130.342899 -259.203186) (xy 130.338828 -259.147564) (xy 124.341013 -259.147564) (xy 124.343413 -259.163874)
			(xy 124.343922 -259.19176) (xy 124.343413 -259.219646) (xy 124.335293 -259.274822) (xy 124.319225 -259.328229)
			(xy 124.295553 -259.378726) (xy 124.26478 -259.425239) (xy 124.227563 -259.466776) (xy 124.184695 -259.502451)
			(xy 124.137089 -259.531505) (xy 124.08576 -259.553317) (xy 124.031803 -259.567423) (xy 123.976366 -259.573523)
			(xy 123.920632 -259.571486) (xy 123.865789 -259.561356) (xy 123.813005 -259.543349) (xy 123.763405 -259.517848)
			(xy 123.718047 -259.485397) (xy 123.677898 -259.446688) (xy 123.643812 -259.402545) (xy 123.616516 -259.35391)
			(xy 123.596593 -259.301819) (xy 123.584467 -259.247382) (xy 123.580396 -259.19176) (xy 118.680992 -259.19176)
			(xy 118.680992 -260.471158) (xy 118.682008 -260.480556) (xy 118.682008 -260.481064) (xy 118.68371 -260.488224)
			(xy 118.69054 -260.501253) (xy 118.69547 -260.506718) (xy 119.044974 -260.856222) (xy 119.050406 -260.861198)
			(xy 119.063448 -260.868034) (xy 119.070628 -260.869684) (xy 119.071136 -260.869684) (xy 119.080534 -260.8707)
			(xy 121.847864 -260.8707) (xy 121.857929 -260.871135) (xy 121.876517 -260.878866) (xy 121.883932 -260.885686)
			(xy 122.205822 -261.207758) (xy 131.570982 -261.207758) (xy 131.575053 -261.152136) (xy 131.587179 -261.097699)
			(xy 131.607102 -261.045608) (xy 131.634398 -260.996973) (xy 131.668484 -260.95283) (xy 131.708633 -260.914121)
			(xy 131.753991 -260.88167) (xy 131.803591 -260.856169) (xy 131.856375 -260.838162) (xy 131.911218 -260.828032)
			(xy 131.966952 -260.825995) (xy 132.022389 -260.832095) (xy 132.076346 -260.846201) (xy 132.127675 -260.868013)
			(xy 132.175281 -260.897067) (xy 132.218149 -260.932742) (xy 132.255366 -260.974279) (xy 132.286139 -261.020792)
			(xy 132.309811 -261.071289) (xy 132.325879 -261.124696) (xy 132.333999 -261.179872) (xy 132.334508 -261.207758)
			(xy 132.333999 -261.235644) (xy 132.325879 -261.29082) (xy 132.309811 -261.344227) (xy 132.286139 -261.394724)
			(xy 132.255366 -261.441237) (xy 132.218149 -261.482774) (xy 132.175281 -261.518449) (xy 132.127675 -261.547503)
			(xy 132.076346 -261.569315) (xy 132.022389 -261.583421) (xy 131.966952 -261.589521) (xy 131.911218 -261.587484)
			(xy 131.856375 -261.577354) (xy 131.803591 -261.559347) (xy 131.753991 -261.533846) (xy 131.708633 -261.501395)
			(xy 131.668484 -261.462686) (xy 131.634398 -261.418543) (xy 131.607102 -261.369908) (xy 131.587179 -261.317817)
			(xy 131.575053 -261.26338) (xy 131.570982 -261.207758) (xy 122.205822 -261.207758) (xy 122.333004 -261.335012)
			(xy 122.339522 -261.340768) (xy 122.355363 -261.347913) (xy 122.363992 -261.348982) (xy 122.365008 -261.348982)
			(xy 122.36831 -261.349236) (xy 123.438666 -261.349236) (xy 123.461926 -261.349617) (xy 123.508093 -261.355338)
			(xy 123.553223 -261.366627) (xy 123.575064 -261.374636) (xy 123.575572 -261.374636) (xy 123.584716 -261.378446)
			(xy 124.637655 -261.814564) (xy 130.388104 -261.814564) (xy 130.392175 -261.758942) (xy 130.404301 -261.704505)
			(xy 130.424224 -261.652414) (xy 130.45152 -261.603779) (xy 130.485606 -261.559636) (xy 130.525755 -261.520927)
			(xy 130.571113 -261.488476) (xy 130.620713 -261.462975) (xy 130.673497 -261.444968) (xy 130.72834 -261.434838)
			(xy 130.784074 -261.432801) (xy 130.839511 -261.438901) (xy 130.893468 -261.453007) (xy 130.944797 -261.474819)
			(xy 130.992403 -261.503873) (xy 131.035271 -261.539548) (xy 131.072488 -261.581085) (xy 131.103261 -261.627598)
			(xy 131.126933 -261.678095) (xy 131.143001 -261.731502) (xy 131.151121 -261.786678) (xy 131.15163 -261.814564)
			(xy 131.151121 -261.84245) (xy 131.143001 -261.897626) (xy 131.126933 -261.951033) (xy 131.103261 -262.00153)
			(xy 131.072488 -262.048043) (xy 131.035271 -262.08958) (xy 130.992403 -262.125255) (xy 130.944797 -262.154309)
			(xy 130.893468 -262.176121) (xy 130.839511 -262.190227) (xy 130.784074 -262.196327) (xy 130.72834 -262.19429)
			(xy 130.673497 -262.18416) (xy 130.620713 -262.166153) (xy 130.571113 -262.140652) (xy 130.525755 -262.108201)
			(xy 130.485606 -262.069492) (xy 130.45152 -262.025349) (xy 130.424224 -261.976714) (xy 130.404301 -261.924623)
			(xy 130.392175 -261.870186) (xy 130.388104 -261.814564) (xy 124.637655 -261.814564) (xy 127.082042 -262.827008)
			(xy 127.104956 -262.836903) (xy 127.148197 -262.861831) (xy 127.18781 -262.892195) (xy 127.20574 -262.909558)
			(xy 131.94284 -267.646658) (xy 131.963618 -267.668274) (xy 131.998852 -267.71678) (xy 132.02607 -267.770199)
			(xy 132.044601 -267.827216) (xy 132.053989 -267.88643) (xy 132.0546 -267.916406) (xy 132.0546 -275.675344)
			(xy 132.054723 -275.680298) (xy 132.05665 -275.690016) (xy 132.05841 -275.694648) (xy 132.647944 -277.118064)
			(xy 132.649468 -277.121366) (xy 132.651377 -277.125066) (xy 132.656232 -277.131828) (xy 132.65912 -277.134828)
			(xy 132.980938 -277.456646) (xy 132.98967 -277.464595) (xy 133.012011 -277.472153) (xy 133.035369 -277.46889)
			(xy 133.045454 -277.462742) (xy 133.128004 -277.406862) (xy 133.128258 -277.406608) (xy 133.135261 -277.401367)
			(xy 133.145509 -277.387205) (xy 133.148324 -277.378922) (xy 133.148324 -277.350728) (xy 133.146292 -277.34514)
			(xy 133.146292 -277.344886) (xy 133.115528 -277.272138) (xy 133.060006 -277.12425) (xy 133.035294 -277.04923)
			(xy 133.009985 -276.969283) (xy 132.966365 -276.807342) (xy 132.930829 -276.643438) (xy 132.903464 -276.477973)
			(xy 132.884338 -276.311355) (xy 132.873498 -276.143993) (xy 132.871718 -276.060154) (xy 132.871464 -276.028658)
			(xy 132.871464 -276.02815) (xy 132.87121 -276.01037) (xy 132.87121 -276.009862) (xy 132.871711 -275.927497)
			(xy 132.87975 -275.762965) (xy 132.895797 -275.599019) (xy 132.919814 -275.43605) (xy 132.951744 -275.274445)
			(xy 132.991512 -275.114588) (xy 133.039022 -274.956859) (xy 133.094162 -274.801633) (xy 133.156801 -274.649278)
			(xy 133.226789 -274.500156) (xy 133.303962 -274.354622) (xy 133.388134 -274.213022) (xy 133.479107 -274.075692)
			(xy 133.576664 -273.942958) (xy 133.680573 -273.815135) (xy 133.790588 -273.692528) (xy 133.906447 -273.575428)
			(xy 134.027874 -273.464113) (xy 134.154582 -273.358847) (xy 134.286268 -273.259881) (xy 134.422621 -273.16745)
			(xy 134.563316 -273.081773) (xy 134.70802 -273.003054) (xy 134.856387 -272.93148) (xy 135.008066 -272.867221)
			(xy 135.162696 -272.81043) (xy 135.319909 -272.761241) (xy 135.479333 -272.719772) (xy 135.640589 -272.686121)
			(xy 135.803292 -272.660369) (xy 135.967058 -272.642575) (xy 136.131495 -272.632783) (xy 136.21385 -272.631408)
			(xy 136.218676 -272.631408) (xy 136.22909 -272.629376) (xy 136.235186 -272.62709) (xy 136.244584 -272.621502)
			(xy 136.250172 -272.616676) (xy 136.27354 -272.593308) (xy 136.278885 -272.586726) (xy 136.285244 -272.57102)
			(xy 136.285986 -272.562574) (xy 136.285986 -256.766568) (xy 136.285821 -256.760558) (xy 136.283 -256.748874)
			(xy 136.280398 -256.743454) (xy 136.278557 -256.739981) (xy 136.273961 -256.733605) (xy 136.271254 -256.730754)
			(xy 135.652256 -256.111756) (xy 135.64541 -256.104358) (xy 135.637683 -256.085759) (xy 135.63727 -256.075688)
			(xy 135.63727 -251.516896) (xy 135.637096 -251.510888) (xy 135.63426 -251.499212) (xy 135.631682 -251.493782)
			(xy 135.629842 -251.490308) (xy 135.625247 -251.48393) (xy 135.622538 -251.481082) (xy 134.909052 -250.767596)
			(xy 134.906198 -250.764894) (xy 134.899816 -250.76031) (xy 134.896352 -250.758452) (xy 134.890926 -250.755867)
			(xy 134.879246 -250.753042) (xy 134.873238 -250.752864) (xy 130.293364 -250.752864) (xy 130.290513 -250.750159)
			(xy 130.284133 -250.745567) (xy 130.280664 -250.74372) (xy 130.275238 -250.741135) (xy 130.263558 -250.738309)
			(xy 130.25755 -250.738132) (xy 103.01351 -250.738132) (xy 103.007502 -250.738304) (xy 102.995824 -250.741138)
			(xy 102.990396 -250.74372) (xy 102.986922 -250.745559) (xy 102.980543 -250.750153) (xy 102.977696 -250.752864)
			(xy 102.38486 -251.3457) (xy 123.339096 -251.3457) (xy 123.343167 -251.290078) (xy 123.355293 -251.235641)
			(xy 123.375216 -251.18355) (xy 123.402512 -251.134915) (xy 123.436598 -251.090772) (xy 123.476747 -251.052063)
			(xy 123.522105 -251.019612) (xy 123.571705 -250.994111) (xy 123.624489 -250.976104) (xy 123.679332 -250.965974)
			(xy 123.735066 -250.963937) (xy 123.790503 -250.970037) (xy 123.84446 -250.984143) (xy 123.895789 -251.005955)
			(xy 123.943395 -251.035009) (xy 123.986263 -251.070684) (xy 124.02348 -251.112221) (xy 124.054253 -251.158734)
			(xy 124.077925 -251.209231) (xy 124.093993 -251.262638) (xy 124.102113 -251.317814) (xy 124.102622 -251.3457)
			(xy 124.863096 -251.3457) (xy 124.867167 -251.290078) (xy 124.879293 -251.235641) (xy 124.899216 -251.18355)
			(xy 124.926512 -251.134915) (xy 124.960598 -251.090772) (xy 125.000747 -251.052063) (xy 125.046105 -251.019612)
			(xy 125.095705 -250.994111) (xy 125.148489 -250.976104) (xy 125.203332 -250.965974) (xy 125.259066 -250.963937)
			(xy 125.314503 -250.970037) (xy 125.36846 -250.984143) (xy 125.419789 -251.005955) (xy 125.467395 -251.035009)
			(xy 125.510263 -251.070684) (xy 125.54748 -251.112221) (xy 125.578253 -251.158734) (xy 125.601925 -251.209231)
			(xy 125.617993 -251.262638) (xy 125.626113 -251.317814) (xy 125.626622 -251.3457) (xy 125.626113 -251.373586)
			(xy 125.617993 -251.428762) (xy 125.601925 -251.482169) (xy 125.578253 -251.532666) (xy 125.54748 -251.579179)
			(xy 125.510263 -251.620716) (xy 125.467395 -251.656391) (xy 125.419789 -251.685445) (xy 125.36846 -251.707257)
			(xy 125.314503 -251.721363) (xy 125.259066 -251.727463) (xy 125.203332 -251.725426) (xy 125.148489 -251.715296)
			(xy 125.095705 -251.697289) (xy 125.046105 -251.671788) (xy 125.000747 -251.639337) (xy 124.960598 -251.600628)
			(xy 124.926512 -251.556485) (xy 124.899216 -251.50785) (xy 124.879293 -251.455759) (xy 124.867167 -251.401322)
			(xy 124.863096 -251.3457) (xy 124.102622 -251.3457) (xy 124.102113 -251.373586) (xy 124.093993 -251.428762)
			(xy 124.077925 -251.482169) (xy 124.054253 -251.532666) (xy 124.02348 -251.579179) (xy 123.986263 -251.620716)
			(xy 123.943395 -251.656391) (xy 123.895789 -251.685445) (xy 123.84446 -251.707257) (xy 123.790503 -251.721363)
			(xy 123.735066 -251.727463) (xy 123.679332 -251.725426) (xy 123.624489 -251.715296) (xy 123.571705 -251.697289)
			(xy 123.522105 -251.671788) (xy 123.476747 -251.639337) (xy 123.436598 -251.600628) (xy 123.402512 -251.556485)
			(xy 123.375216 -251.50785) (xy 123.355293 -251.455759) (xy 123.343167 -251.401322) (xy 123.339096 -251.3457)
			(xy 102.38486 -251.3457) (xy 101.618288 -252.112272) (xy 120.272554 -252.112272) (xy 120.276625 -252.05665)
			(xy 120.288751 -252.002213) (xy 120.308674 -251.950122) (xy 120.33597 -251.901487) (xy 120.370056 -251.857344)
			(xy 120.410205 -251.818635) (xy 120.455563 -251.786184) (xy 120.505163 -251.760683) (xy 120.557947 -251.742676)
			(xy 120.61279 -251.732546) (xy 120.668524 -251.730509) (xy 120.723961 -251.736609) (xy 120.777918 -251.750715)
			(xy 120.829247 -251.772527) (xy 120.876853 -251.801581) (xy 120.919721 -251.837256) (xy 120.956938 -251.878793)
			(xy 120.987711 -251.925306) (xy 121.011383 -251.975803) (xy 121.027451 -252.02921) (xy 121.035571 -252.084386)
			(xy 121.03608 -252.112272) (xy 121.035571 -252.140158) (xy 121.028984 -252.184916) (xy 132.344158 -252.184916)
			(xy 132.348229 -252.129294) (xy 132.360355 -252.074857) (xy 132.380278 -252.022766) (xy 132.407574 -251.974131)
			(xy 132.44166 -251.929988) (xy 132.481809 -251.891279) (xy 132.527167 -251.858828) (xy 132.576767 -251.833327)
			(xy 132.629551 -251.81532) (xy 132.684394 -251.80519) (xy 132.740128 -251.803153) (xy 132.795565 -251.809253)
			(xy 132.849522 -251.823359) (xy 132.900851 -251.845171) (xy 132.948457 -251.874225) (xy 132.991325 -251.9099)
			(xy 133.028542 -251.951437) (xy 133.059315 -251.99795) (xy 133.082987 -252.048447) (xy 133.099055 -252.101854)
			(xy 133.107175 -252.15703) (xy 133.107684 -252.184916) (xy 133.107175 -252.212802) (xy 133.099055 -252.267978)
			(xy 133.082987 -252.321385) (xy 133.059315 -252.371882) (xy 133.028542 -252.418395) (xy 132.991325 -252.459932)
			(xy 132.948457 -252.495607) (xy 132.900851 -252.524661) (xy 132.849522 -252.546473) (xy 132.795565 -252.560579)
			(xy 132.740128 -252.566679) (xy 132.684394 -252.564642) (xy 132.629551 -252.554512) (xy 132.576767 -252.536505)
			(xy 132.527167 -252.511004) (xy 132.481809 -252.478553) (xy 132.44166 -252.439844) (xy 132.407574 -252.395701)
			(xy 132.380278 -252.347066) (xy 132.360355 -252.294975) (xy 132.348229 -252.240538) (xy 132.344158 -252.184916)
			(xy 121.028984 -252.184916) (xy 121.027451 -252.195334) (xy 121.011383 -252.248741) (xy 120.987711 -252.299238)
			(xy 120.956938 -252.345751) (xy 120.919721 -252.387288) (xy 120.876853 -252.422963) (xy 120.829247 -252.452017)
			(xy 120.777918 -252.473829) (xy 120.723961 -252.487935) (xy 120.668524 -252.494035) (xy 120.61279 -252.491998)
			(xy 120.557947 -252.481868) (xy 120.505163 -252.463861) (xy 120.455563 -252.43836) (xy 120.410205 -252.405909)
			(xy 120.370056 -252.3672) (xy 120.33597 -252.323057) (xy 120.308674 -252.274422) (xy 120.288751 -252.222331)
			(xy 120.276625 -252.167894) (xy 120.272554 -252.112272) (xy 101.618288 -252.112272) (xy 98.758502 -254.972058)
			(xy 98.755796 -254.974909) (xy 98.751201 -254.981286) (xy 98.749358 -254.984758) (xy 98.746774 -254.990184)
			(xy 98.74395 -255.001864) (xy 98.74377 -255.007872) (xy 98.74377 -258.923536) (xy 108.0897 -258.923536)
			(xy 108.090164 -258.896092) (xy 108.098019 -258.841769) (xy 108.113586 -258.789134) (xy 108.136543 -258.739277)
			(xy 108.166414 -258.693229) (xy 108.202583 -258.651943) (xy 108.2443 -258.616273) (xy 108.267246 -258.60121)
			(xy 108.2675 -258.600956) (xy 108.277812 -258.593587) (xy 108.290076 -258.571443) (xy 108.290868 -258.558792)
			(xy 108.29163 -258.459986) (xy 108.279692 -258.437634) (xy 108.26877 -258.430268) (xy 108.24645 -258.415055)
			(xy 108.205883 -258.379395) (xy 108.170755 -258.338366) (xy 108.141768 -258.292791) (xy 108.119503 -258.243581)
			(xy 108.104405 -258.191721) (xy 108.096776 -258.13825) (xy 108.096304 -258.111244) (xy 108.096796 -258.083992)
			(xy 108.104548 -258.030041) (xy 108.119899 -257.977743) (xy 108.142537 -257.928162) (xy 108.172001 -257.882308)
			(xy 108.207692 -257.841115) (xy 108.248883 -257.805421) (xy 108.294734 -257.775952) (xy 108.344313 -257.75331)
			(xy 108.39661 -257.737954) (xy 108.45056 -257.730199) (xy 108.477812 -257.729736) (xy 108.504127 -257.730184)
			(xy 108.556257 -257.737421) (xy 108.6069 -257.751743) (xy 108.655099 -257.772879) (xy 108.699942 -257.800429)
			(xy 108.74058 -257.833872) (xy 108.758736 -257.852926) (xy 108.766252 -257.860335) (xy 108.785536 -257.868858)
			(xy 108.796074 -257.869436) (xy 108.87075 -257.869436) (xy 108.881297 -257.868883) (xy 108.900591 -257.860363)
			(xy 108.908088 -257.852926) (xy 108.927908 -257.832138) (xy 108.97268 -257.796163) (xy 109.022338 -257.767303)
			(xy 109.07576 -257.74621) (xy 109.131739 -257.733361) (xy 109.189012 -257.729046) (xy 109.246285 -257.733361)
			(xy 109.302264 -257.74621) (xy 109.355686 -257.767303) (xy 109.405344 -257.796163) (xy 109.450116 -257.832138)
			(xy 109.469936 -257.852926) (xy 109.477452 -257.860335) (xy 109.496736 -257.868858) (xy 109.507274 -257.869436)
			(xy 109.58195 -257.869436) (xy 109.592497 -257.868883) (xy 109.611791 -257.860363) (xy 109.619288 -257.852926)
			(xy 109.637462 -257.833888) (xy 109.678087 -257.800428) (xy 109.722923 -257.772866) (xy 109.77112 -257.751725)
			(xy 109.821765 -257.737404) (xy 109.873897 -257.730176) (xy 109.900212 -257.729736) (xy 109.927467 -257.730144)
			(xy 109.981422 -257.737904) (xy 110.033724 -257.753263) (xy 110.083307 -257.775911) (xy 110.129162 -257.805384)
			(xy 110.170356 -257.841083) (xy 110.20605 -257.882282) (xy 110.235516 -257.928142) (xy 110.258156 -257.977728)
			(xy 110.273508 -258.030032) (xy 110.28126 -258.083989) (xy 110.28172 -258.111244) (xy 110.281231 -258.138687)
			(xy 110.273379 -258.193009) (xy 110.257816 -258.245642) (xy 110.234863 -258.295499) (xy 110.204996 -258.341547)
			(xy 110.168831 -258.382834) (xy 110.127118 -258.418506) (xy 110.104174 -258.43357) (xy 110.10392 -258.433824)
			(xy 110.09362 -258.441208) (xy 110.081349 -258.463341) (xy 110.080552 -258.475988) (xy 110.07979 -258.574794)
			(xy 110.091728 -258.597146) (xy 110.10265 -258.604512) (xy 110.124965 -258.619731) (xy 110.165531 -258.655391)
			(xy 110.200659 -258.696419) (xy 110.229646 -258.741994) (xy 110.251912 -258.791202) (xy 110.267012 -258.84306)
			(xy 110.274642 -258.89653) (xy 110.275116 -258.923536) (xy 110.274656 -258.950788) (xy 110.266894 -259.004736)
			(xy 110.262245 -259.020564) (xy 112.290096 -259.020564) (xy 112.294167 -258.964942) (xy 112.306293 -258.910505)
			(xy 112.326216 -258.858414) (xy 112.353512 -258.809779) (xy 112.387598 -258.765636) (xy 112.427747 -258.726927)
			(xy 112.473105 -258.694476) (xy 112.522705 -258.668975) (xy 112.575489 -258.650968) (xy 112.630332 -258.640838)
			(xy 112.686066 -258.638801) (xy 112.741503 -258.644901) (xy 112.79546 -258.659007) (xy 112.846789 -258.680819)
			(xy 112.894395 -258.709873) (xy 112.937263 -258.745548) (xy 112.97448 -258.787085) (xy 113.005253 -258.833598)
			(xy 113.028925 -258.884095) (xy 113.044993 -258.937502) (xy 113.053113 -258.992678) (xy 113.053622 -259.020564)
			(xy 113.179096 -259.020564) (xy 113.183167 -258.964942) (xy 113.195293 -258.910505) (xy 113.215216 -258.858414)
			(xy 113.242512 -258.809779) (xy 113.276598 -258.765636) (xy 113.316747 -258.726927) (xy 113.362105 -258.694476)
			(xy 113.411705 -258.668975) (xy 113.464489 -258.650968) (xy 113.519332 -258.640838) (xy 113.575066 -258.638801)
			(xy 113.630503 -258.644901) (xy 113.68446 -258.659007) (xy 113.735789 -258.680819) (xy 113.783395 -258.709873)
			(xy 113.826263 -258.745548) (xy 113.86348 -258.787085) (xy 113.894253 -258.833598) (xy 113.917925 -258.884095)
			(xy 113.933993 -258.937502) (xy 113.942113 -258.992678) (xy 113.942622 -259.020564) (xy 113.942113 -259.04845)
			(xy 113.933993 -259.103626) (xy 113.917925 -259.157033) (xy 113.894253 -259.20753) (xy 113.86348 -259.254043)
			(xy 113.826263 -259.29558) (xy 113.783395 -259.331255) (xy 113.735789 -259.360309) (xy 113.68446 -259.382121)
			(xy 113.630503 -259.396227) (xy 113.575066 -259.402327) (xy 113.519332 -259.40029) (xy 113.464489 -259.39016)
			(xy 113.411705 -259.372153) (xy 113.362105 -259.346652) (xy 113.316747 -259.314201) (xy 113.276598 -259.275492)
			(xy 113.242512 -259.231349) (xy 113.215216 -259.182714) (xy 113.195293 -259.130623) (xy 113.183167 -259.076186)
			(xy 113.179096 -259.020564) (xy 113.053622 -259.020564) (xy 113.053113 -259.04845) (xy 113.044993 -259.103626)
			(xy 113.028925 -259.157033) (xy 113.005253 -259.20753) (xy 112.97448 -259.254043) (xy 112.937263 -259.29558)
			(xy 112.894395 -259.331255) (xy 112.846789 -259.360309) (xy 112.79546 -259.382121) (xy 112.741503 -259.396227)
			(xy 112.686066 -259.402327) (xy 112.630332 -259.40029) (xy 112.575489 -259.39016) (xy 112.522705 -259.372153)
			(xy 112.473105 -259.346652) (xy 112.427747 -259.314201) (xy 112.387598 -259.275492) (xy 112.353512 -259.231349)
			(xy 112.326216 -259.182714) (xy 112.306293 -259.130623) (xy 112.294167 -259.076186) (xy 112.290096 -259.020564)
			(xy 110.262245 -259.020564) (xy 110.251535 -259.057031) (xy 110.22889 -259.106608) (xy 110.199421 -259.152457)
			(xy 110.163727 -259.193647) (xy 110.122535 -259.229338) (xy 110.076683 -259.258804) (xy 110.027104 -259.281445)
			(xy 109.974809 -259.2968) (xy 109.92086 -259.304558) (xy 109.893608 -259.305044) (xy 109.867293 -259.304589)
			(xy 109.815164 -259.297354) (xy 109.76452 -259.283034) (xy 109.716321 -259.261899) (xy 109.671478 -259.23435)
			(xy 109.630839 -259.200908) (xy 109.612684 -259.181854) (xy 109.605163 -259.174451) (xy 109.585883 -259.165926)
			(xy 109.575346 -259.165344) (xy 109.50067 -259.165344) (xy 109.490121 -259.165884) (xy 109.470825 -259.17441)
			(xy 109.463332 -259.181854) (xy 109.443512 -259.202642) (xy 109.39874 -259.238617) (xy 109.349082 -259.267477)
			(xy 109.29566 -259.28857) (xy 109.239681 -259.301419) (xy 109.182408 -259.305734) (xy 109.125135 -259.301419)
			(xy 109.069156 -259.28857) (xy 109.015734 -259.267477) (xy 108.966076 -259.238617) (xy 108.921304 -259.202642)
			(xy 108.901484 -259.181854) (xy 108.893963 -259.174451) (xy 108.874683 -259.165926) (xy 108.864146 -259.165344)
			(xy 108.78947 -259.165344) (xy 108.778921 -259.165884) (xy 108.759625 -259.17441) (xy 108.752132 -259.181854)
			(xy 108.734013 -259.200946) (xy 108.693374 -259.234398) (xy 108.648526 -259.261951) (xy 108.600318 -259.283082)
			(xy 108.549665 -259.297392) (xy 108.497526 -259.304609) (xy 108.471208 -259.305044) (xy 108.443959 -259.304515)
			(xy 108.390014 -259.29676) (xy 108.337723 -259.281408) (xy 108.288148 -259.258771) (xy 108.242299 -259.229308)
			(xy 108.20111 -259.193622) (xy 108.165418 -259.152436) (xy 108.135951 -259.106591) (xy 108.113307 -259.057019)
			(xy 108.097949 -259.004729) (xy 108.090188 -258.950785) (xy 108.0897 -258.923536) (xy 98.74377 -258.923536)
			(xy 98.74377 -269.417038) (xy 102.50043 -269.417038) (xy 102.500935 -269.388299) (xy 102.509565 -269.331471)
			(xy 102.52662 -269.276581) (xy 102.551716 -269.22487) (xy 102.584283 -269.177507) (xy 102.603554 -269.15618)
			(xy 102.610158 -269.149322) (xy 102.61727 -269.131288) (xy 102.61727 -269.042388) (xy 102.610158 -269.024354)
			(xy 102.603554 -269.017496) (xy 102.584304 -268.996151) (xy 102.551734 -268.948794) (xy 102.526638 -268.897087)
			(xy 102.509582 -268.8422) (xy 102.500954 -268.785376) (xy 102.50043 -268.756638) (xy 102.500891 -268.729384)
			(xy 102.508644 -268.675431) (xy 102.523997 -268.623131) (xy 102.546638 -268.573549) (xy 102.576105 -268.527693)
			(xy 102.611799 -268.486499) (xy 102.652993 -268.450805) (xy 102.698849 -268.421338) (xy 102.748431 -268.398697)
			(xy 102.800731 -268.383344) (xy 102.854684 -268.375591) (xy 102.881938 -268.37513) (xy 102.909307 -268.375625)
			(xy 102.963485 -268.383435) (xy 103.015988 -268.398917) (xy 103.065736 -268.421752) (xy 103.111704 -268.451471)
			(xy 103.132636 -268.46911) (xy 103.13289 -268.469364) (xy 103.13997 -268.47496) (xy 103.156892 -268.481199)
			(xy 103.16591 -268.481556) (xy 103.232966 -268.481556) (xy 103.241982 -268.481192) (xy 103.2589 -268.47495)
			(xy 103.265986 -268.469364) (xy 103.265986 -268.46911) (xy 103.26624 -268.46911) (xy 103.287173 -268.451469)
			(xy 103.333141 -268.421745) (xy 103.382887 -268.398899) (xy 103.435389 -268.383403) (xy 103.489567 -268.375574)
			(xy 103.544309 -268.375574) (xy 103.598487 -268.383403) (xy 103.650989 -268.398899) (xy 103.700735 -268.421745)
			(xy 103.746703 -268.451469) (xy 103.767636 -268.46911) (xy 103.76789 -268.469364) (xy 103.77497 -268.47496)
			(xy 103.791892 -268.481199) (xy 103.80091 -268.481556) (xy 103.867966 -268.481556) (xy 103.876982 -268.481192)
			(xy 103.8939 -268.47495) (xy 103.900986 -268.469364) (xy 103.900986 -268.46911) (xy 103.90124 -268.46911)
			(xy 103.922173 -268.451469) (xy 103.968141 -268.421745) (xy 104.017887 -268.398899) (xy 104.070389 -268.383403)
			(xy 104.124567 -268.375574) (xy 104.179309 -268.375574) (xy 104.233487 -268.383403) (xy 104.285989 -268.398899)
			(xy 104.335735 -268.421745) (xy 104.381703 -268.451469) (xy 104.402636 -268.46911) (xy 104.40289 -268.469364)
			(xy 104.40997 -268.47496) (xy 104.426892 -268.481199) (xy 104.43591 -268.481556) (xy 104.502966 -268.481556)
			(xy 104.511982 -268.481192) (xy 104.5289 -268.47495) (xy 104.535986 -268.469364) (xy 104.535986 -268.46911)
			(xy 104.53624 -268.46911) (xy 104.557173 -268.451469) (xy 104.603141 -268.421745) (xy 104.652887 -268.398899)
			(xy 104.705389 -268.383403) (xy 104.759567 -268.375574) (xy 104.814309 -268.375574) (xy 104.868487 -268.383403)
			(xy 104.920989 -268.398899) (xy 104.970735 -268.421745) (xy 105.016703 -268.451469) (xy 105.037636 -268.46911)
			(xy 105.03789 -268.469364) (xy 105.04497 -268.47496) (xy 105.061892 -268.481199) (xy 105.07091 -268.481556)
			(xy 105.137966 -268.481556) (xy 105.146982 -268.481192) (xy 105.1639 -268.47495) (xy 105.170986 -268.469364)
			(xy 105.170986 -268.46911) (xy 105.17124 -268.46911) (xy 105.192185 -268.451487) (xy 105.238154 -268.421773)
			(xy 105.287898 -268.398933) (xy 105.340396 -268.383438) (xy 105.39457 -268.375606) (xy 105.421938 -268.37513)
			(xy 105.449192 -268.375543) (xy 105.503144 -268.383305) (xy 105.555443 -268.398667) (xy 105.605023 -268.421315)
			(xy 105.650875 -268.450789) (xy 105.692065 -268.486488) (xy 105.727756 -268.527686) (xy 105.757221 -268.573544)
			(xy 105.779859 -268.623129) (xy 105.795211 -268.67543) (xy 105.802963 -268.729384) (xy 105.803446 -268.756638)
			(xy 105.802933 -268.785377) (xy 105.794306 -268.842204) (xy 105.777253 -268.897095) (xy 105.752159 -268.948806)
			(xy 105.719593 -268.996169) (xy 105.700322 -269.017496) (xy 105.693718 -269.024354) (xy 105.686606 -269.042388)
			(xy 105.686606 -269.131288) (xy 105.693718 -269.149322) (xy 105.700322 -269.15618) (xy 105.719604 -269.177497)
			(xy 105.75217 -269.224861) (xy 105.777261 -269.276575) (xy 105.794309 -269.331468) (xy 105.802928 -269.388298)
			(xy 105.803446 -269.417038) (xy 105.802958 -269.444288) (xy 105.795197 -269.498234) (xy 105.779839 -269.550526)
			(xy 105.757196 -269.600101) (xy 105.727729 -269.64595) (xy 105.692038 -269.687138) (xy 105.65085 -269.722829)
			(xy 105.605001 -269.752296) (xy 105.555426 -269.774939) (xy 105.503134 -269.790297) (xy 105.449188 -269.798058)
			(xy 105.421938 -269.798546) (xy 105.394568 -269.798071) (xy 105.340389 -269.790257) (xy 105.287885 -269.774771)
			(xy 105.238138 -269.751931) (xy 105.192171 -269.722207) (xy 105.17124 -269.704566) (xy 105.170986 -269.704312)
			(xy 105.163907 -269.698715) (xy 105.146984 -269.692474) (xy 105.137966 -269.69212) (xy 105.07091 -269.69212)
			(xy 105.061893 -269.692477) (xy 105.044976 -269.698724) (xy 105.03789 -269.704312) (xy 105.037636 -269.704566)
			(xy 105.016703 -269.722207) (xy 104.970735 -269.751931) (xy 104.920989 -269.774777) (xy 104.868487 -269.790273)
			(xy 104.814309 -269.798102) (xy 104.759567 -269.798102) (xy 104.705389 -269.790273) (xy 104.652887 -269.774777)
			(xy 104.603141 -269.751931) (xy 104.557173 -269.722207) (xy 104.53624 -269.704566) (xy 104.535986 -269.704312)
			(xy 104.528907 -269.698715) (xy 104.511984 -269.692474) (xy 104.502966 -269.69212) (xy 104.43591 -269.69212)
			(xy 104.426893 -269.692477) (xy 104.409976 -269.698724) (xy 104.40289 -269.704312) (xy 104.40289 -269.704566)
			(xy 104.402636 -269.704566) (xy 104.381703 -269.722207) (xy 104.335735 -269.751931) (xy 104.285989 -269.774777)
			(xy 104.233487 -269.790273) (xy 104.179309 -269.798102) (xy 104.124567 -269.798102) (xy 104.070389 -269.790273)
			(xy 104.017887 -269.774777) (xy 103.968141 -269.751931) (xy 103.922173 -269.722207) (xy 103.90124 -269.704566)
			(xy 103.900986 -269.704312) (xy 103.893907 -269.698715) (xy 103.876984 -269.692474) (xy 103.867966 -269.69212)
			(xy 103.80091 -269.69212) (xy 103.791893 -269.692477) (xy 103.774976 -269.698724) (xy 103.76789 -269.704312)
			(xy 103.76789 -269.704566) (xy 103.767636 -269.704566) (xy 103.746703 -269.722207) (xy 103.700735 -269.751931)
			(xy 103.650989 -269.774777) (xy 103.598487 -269.790273) (xy 103.544309 -269.798102) (xy 103.489567 -269.798102)
			(xy 103.435389 -269.790273) (xy 103.382887 -269.774777) (xy 103.333141 -269.751931) (xy 103.287173 -269.722207)
			(xy 103.26624 -269.704566) (xy 103.265986 -269.704312) (xy 103.258907 -269.698715) (xy 103.241984 -269.692474)
			(xy 103.232966 -269.69212) (xy 103.16591 -269.69212) (xy 103.156893 -269.692477) (xy 103.139976 -269.698724)
			(xy 103.13289 -269.704312) (xy 103.13289 -269.704566) (xy 103.132636 -269.704566) (xy 103.111697 -269.722196)
			(xy 103.065727 -269.751911) (xy 103.015981 -269.774749) (xy 102.963482 -269.790242) (xy 102.909307 -269.798071)
			(xy 102.881938 -269.798546) (xy 102.854689 -269.797987) (xy 102.800746 -269.790236) (xy 102.748455 -269.774888)
			(xy 102.698881 -269.752254) (xy 102.653032 -269.722795) (xy 102.611843 -269.687111) (xy 102.57615 -269.645929)
			(xy 102.546683 -269.600086) (xy 102.524039 -269.550516) (xy 102.50868 -269.498228) (xy 102.500919 -269.444286)
			(xy 102.50043 -269.417038) (xy 98.74377 -269.417038) (xy 98.74377 -277.864824) (xy 103.46563 -277.864824)
			(xy 103.466154 -277.835907) (xy 103.47488 -277.778736) (xy 103.492136 -277.723537) (xy 103.517527 -277.671575)
			(xy 103.55047 -277.624041) (xy 103.590211 -277.582024) (xy 103.612696 -277.563834) (xy 103.621477 -277.556202)
			(xy 103.631675 -277.53532) (xy 103.632254 -277.523702) (xy 103.632254 -277.443946) (xy 103.631748 -277.43231)
			(xy 103.621537 -277.411399) (xy 103.612696 -277.403814) (xy 103.590218 -277.385616) (xy 103.550483 -277.343598)
			(xy 103.517543 -277.296064) (xy 103.492154 -277.244104) (xy 103.474896 -277.188908) (xy 103.466166 -277.13174)
			(xy 103.46563 -277.102824) (xy 103.466211 -277.073416) (xy 103.475241 -277.015298) (xy 103.493076 -276.959253)
			(xy 103.519295 -276.906604) (xy 103.553276 -276.858599) (xy 103.594217 -276.816372) (xy 103.641148 -276.780922)
			(xy 103.666798 -276.766528) (xy 103.678736 -276.760178) (xy 103.69296 -276.737826) (xy 103.698802 -276.624288)
			(xy 103.686864 -276.600412) (xy 103.675942 -276.593046) (xy 103.654185 -276.577733) (xy 103.614705 -276.54207)
			(xy 103.580561 -276.50127) (xy 103.552414 -276.456123) (xy 103.530809 -276.407504) (xy 103.516166 -276.356357)
			(xy 103.508768 -276.303671) (xy 103.508302 -276.27707) (xy 103.50875 -276.249699) (xy 103.516572 -276.195519)
			(xy 103.532065 -276.143016) (xy 103.554911 -276.093269) (xy 103.584639 -276.047303) (xy 103.602282 -276.026372)
			(xy 103.602536 -276.026118) (xy 103.608125 -276.019033) (xy 103.614369 -276.002115) (xy 103.614728 -275.993098)
			(xy 103.614728 -275.926042) (xy 103.614345 -275.917028) (xy 103.608115 -275.900111) (xy 103.602536 -275.893022)
			(xy 103.602282 -275.893022) (xy 103.602282 -275.892768) (xy 103.584659 -275.871823) (xy 103.554945 -275.825854)
			(xy 103.532106 -275.776109) (xy 103.516611 -275.723612) (xy 103.508779 -275.669438) (xy 103.508302 -275.64207)
			(xy 103.508302 -275.641816) (xy 103.508871 -275.612017) (xy 103.518149 -275.553146) (xy 103.536467 -275.496433)
			(xy 103.563378 -275.443257) (xy 103.598228 -275.394912) (xy 103.618792 -275.373338) (xy 103.626158 -275.365972)
			(xy 103.633778 -275.34743) (xy 103.632762 -275.25472) (xy 103.624888 -275.236178) (xy 103.617522 -275.229066)
			(xy 103.599566 -275.211014) (xy 103.568068 -275.171012) (xy 103.542169 -275.127176) (xy 103.522329 -275.080286)
			(xy 103.508902 -275.031173) (xy 103.502124 -274.980711) (xy 103.501698 -274.955254) (xy 103.502135 -274.928001)
			(xy 103.509898 -274.874052) (xy 103.525259 -274.821756) (xy 103.547906 -274.772178) (xy 103.577378 -274.726327)
			(xy 103.613074 -274.685137) (xy 103.654269 -274.649447) (xy 103.700123 -274.619981) (xy 103.749704 -274.597341)
			(xy 103.802002 -274.581987) (xy 103.855953 -274.574231) (xy 103.883206 -274.573746) (xy 103.912124 -274.574243)
			(xy 103.969297 -274.582974) (xy 104.024497 -274.600235) (xy 104.076459 -274.62563) (xy 104.123992 -274.658579)
			(xy 104.166007 -274.698324) (xy 104.184196 -274.720812) (xy 104.191813 -274.729609) (xy 104.212706 -274.739798)
			(xy 104.224328 -274.74037) (xy 104.304084 -274.74037) (xy 104.315715 -274.739818) (xy 104.336625 -274.729639)
			(xy 104.344216 -274.720812) (xy 104.360969 -274.700029) (xy 104.399323 -274.662899) (xy 104.442477 -274.631477)
			(xy 104.489591 -274.606378) (xy 104.539743 -274.588092) (xy 104.591954 -274.576975) (xy 104.645206 -274.573245)
			(xy 104.698458 -274.576975) (xy 104.750669 -274.588092) (xy 104.800821 -274.606378) (xy 104.847935 -274.631477)
			(xy 104.891089 -274.662899) (xy 104.929443 -274.700029) (xy 104.946196 -274.720812) (xy 104.953813 -274.729609)
			(xy 104.974706 -274.739798) (xy 104.986328 -274.74037) (xy 105.066084 -274.74037) (xy 105.077715 -274.739818)
			(xy 105.098625 -274.729639) (xy 105.106216 -274.720812) (xy 105.124401 -274.698323) (xy 105.166422 -274.658588)
			(xy 105.213958 -274.625649) (xy 105.26592 -274.600262) (xy 105.321119 -274.583007) (xy 105.37829 -274.57428)
			(xy 105.407206 -274.573746) (xy 105.434455 -274.574272) (xy 105.488399 -274.582028) (xy 105.54069 -274.597382)
			(xy 105.590265 -274.62002) (xy 105.636113 -274.649483) (xy 105.677302 -274.68517) (xy 105.712993 -274.726355)
			(xy 105.742461 -274.7722) (xy 105.765104 -274.821772) (xy 105.780463 -274.874062) (xy 105.788225 -274.928005)
			(xy 105.788714 -274.955254) (xy 105.788714 -274.955508) (xy 105.788155 -274.985307) (xy 105.778874 -275.044178)
			(xy 105.760554 -275.100891) (xy 105.733641 -275.154067) (xy 105.698789 -275.202412) (xy 105.678224 -275.223986)
			(xy 105.670858 -275.231352) (xy 105.663238 -275.249894) (xy 105.664254 -275.342604) (xy 105.672128 -275.361146)
			(xy 105.679494 -275.368258) (xy 105.697465 -275.386296) (xy 105.728961 -275.426301) (xy 105.754857 -275.47014)
			(xy 105.774694 -275.517034) (xy 105.788119 -275.566148) (xy 105.794894 -275.616612) (xy 105.795318 -275.64207)
			(xy 105.794809 -275.670988) (xy 105.786083 -275.728161) (xy 105.768825 -275.783361) (xy 105.743432 -275.835324)
			(xy 105.710485 -275.882857) (xy 105.67074 -275.924872) (xy 105.648252 -275.94306) (xy 105.639465 -275.950686)
			(xy 105.629272 -275.971573) (xy 105.628694 -275.983192) (xy 105.628694 -276.051264) (xy 109.061504 -276.051264)
			(xy 109.061948 -276.023893) (xy 109.069771 -275.969713) (xy 109.085265 -275.917209) (xy 109.108112 -275.867463)
			(xy 109.137841 -275.821497) (xy 109.155484 -275.800566) (xy 109.155738 -275.800312) (xy 109.16133 -275.793229)
			(xy 109.167572 -275.776309) (xy 109.16793 -275.767292) (xy 109.16793 -275.700236) (xy 109.167549 -275.691222)
			(xy 109.161317 -275.674305) (xy 109.155738 -275.667216) (xy 109.155484 -275.667216) (xy 109.155484 -275.666962)
			(xy 109.13781 -275.646057) (xy 109.10809 -275.600083) (xy 109.085249 -275.550332) (xy 109.069757 -275.497826)
			(xy 109.061933 -275.443645) (xy 109.061937 -275.388901) (xy 109.069769 -275.334721) (xy 109.085268 -275.282217)
			(xy 109.108116 -275.232469) (xy 109.137843 -275.1865) (xy 109.155484 -275.165566) (xy 109.155738 -275.165312)
			(xy 109.16133 -275.158229) (xy 109.167572 -275.141309) (xy 109.16793 -275.132292) (xy 109.16793 -275.065236)
			(xy 109.167549 -275.056222) (xy 109.161317 -275.039305) (xy 109.155738 -275.032216) (xy 109.155484 -275.032216)
			(xy 109.155484 -275.031962) (xy 109.137858 -275.011019) (xy 109.108145 -274.965049) (xy 109.085307 -274.915304)
			(xy 109.069812 -274.862806) (xy 109.06198 -274.808632) (xy 109.061504 -274.781264) (xy 109.061944 -274.754011)
			(xy 109.069706 -274.700061) (xy 109.085066 -274.647765) (xy 109.107713 -274.598187) (xy 109.137184 -274.552336)
			(xy 109.17288 -274.511146) (xy 109.214075 -274.475455) (xy 109.259929 -274.44599) (xy 109.30951 -274.42335)
			(xy 109.361808 -274.407996) (xy 109.415759 -274.400241) (xy 109.443012 -274.399756) (xy 109.470383 -274.400201)
			(xy 109.524564 -274.408022) (xy 109.577068 -274.423515) (xy 109.626814 -274.446362) (xy 109.67278 -274.476092)
			(xy 109.69371 -274.493736) (xy 109.693964 -274.49399) (xy 109.701058 -274.499567) (xy 109.717969 -274.50582)
			(xy 109.726984 -274.506182) (xy 109.79404 -274.506182) (xy 109.803059 -274.505848) (xy 109.819976 -274.499585)
			(xy 109.82706 -274.49399) (xy 109.82706 -274.493736) (xy 109.827314 -274.493736) (xy 109.848272 -274.476129)
			(xy 109.894237 -274.446411) (xy 109.943978 -274.423569) (xy 109.996473 -274.40807) (xy 110.050645 -274.400234)
			(xy 110.078012 -274.399756) (xy 110.105262 -274.400267) (xy 110.159207 -274.408024) (xy 110.211499 -274.423379)
			(xy 110.261074 -274.446018) (xy 110.306922 -274.475483) (xy 110.348112 -274.511171) (xy 110.383803 -274.552358)
			(xy 110.41327 -274.598205) (xy 110.435913 -274.647779) (xy 110.451271 -274.70007) (xy 110.459032 -274.754014)
			(xy 110.45952 -274.781264) (xy 110.459052 -274.808634) (xy 110.451238 -274.862814) (xy 110.43575 -274.915318)
			(xy 110.412908 -274.965065) (xy 110.383182 -275.011031) (xy 110.36554 -275.031962) (xy 110.365286 -275.032216)
			(xy 110.359685 -275.039293) (xy 110.353447 -275.056217) (xy 110.353094 -275.065236) (xy 110.353094 -275.132292)
			(xy 110.353456 -275.141308) (xy 110.3597 -275.158225) (xy 110.365286 -275.165312) (xy 110.36554 -275.165312)
			(xy 110.36554 -275.165566) (xy 110.383147 -275.186527) (xy 110.412876 -275.232489) (xy 110.435725 -275.28223)
			(xy 110.451226 -275.334728) (xy 110.459058 -275.388904) (xy 110.459062 -275.443642) (xy 110.451237 -275.497819)
			(xy 110.435744 -275.550319) (xy 110.412902 -275.600064) (xy 110.38318 -275.64603) (xy 110.36554 -275.666962)
			(xy 110.365286 -275.667216) (xy 110.359685 -275.674293) (xy 110.353447 -275.691217) (xy 110.353094 -275.700236)
			(xy 110.353094 -275.767292) (xy 110.353456 -275.776308) (xy 110.3597 -275.793225) (xy 110.365286 -275.800312)
			(xy 110.36554 -275.800312) (xy 110.36554 -275.800566) (xy 110.383147 -275.821527) (xy 110.412876 -275.867489)
			(xy 110.435725 -275.91723) (xy 110.451226 -275.969728) (xy 110.459058 -276.023904) (xy 110.459062 -276.078642)
			(xy 110.451237 -276.132819) (xy 110.435744 -276.185319) (xy 110.412902 -276.235064) (xy 110.38318 -276.28103)
			(xy 110.36554 -276.301962) (xy 110.365286 -276.302216) (xy 110.359685 -276.309293) (xy 110.353447 -276.326217)
			(xy 110.353094 -276.335236) (xy 110.353094 -276.402292) (xy 110.353456 -276.411308) (xy 110.3597 -276.428225)
			(xy 110.365286 -276.435312) (xy 110.36554 -276.435312) (xy 110.36554 -276.43582) (xy 110.38169 -276.454875)
			(xy 110.409357 -276.496465) (xy 110.431359 -276.54131) (xy 110.439708 -276.564852) (xy 110.443518 -276.576282)
			(xy 110.460028 -276.593046) (xy 110.547912 -276.622764) (xy 110.559214 -276.626032) (xy 110.582519 -276.622965)
			(xy 110.592616 -276.616922) (xy 110.59287 -276.616668) (xy 110.616626 -276.601325) (xy 110.667684 -276.577015)
			(xy 110.721771 -276.560506) (xy 110.777701 -276.552158) (xy 110.805976 -276.551644) (xy 110.833224 -276.5522)
			(xy 110.887167 -276.559952) (xy 110.939458 -276.575302) (xy 110.989031 -276.597937) (xy 111.03488 -276.627396)
			(xy 111.076069 -276.66308) (xy 111.111761 -276.704263) (xy 111.141229 -276.750105) (xy 111.163873 -276.799675)
			(xy 111.179232 -276.851962) (xy 111.186994 -276.905904) (xy 111.187484 -276.933152) (xy 111.187056 -276.959467)
			(xy 111.179814 -277.011598) (xy 111.165488 -277.062241) (xy 111.144348 -277.11044) (xy 111.116794 -277.155283)
			(xy 111.083349 -277.195921) (xy 111.064294 -277.214076) (xy 111.0569 -277.221604) (xy 111.048372 -277.240879)
			(xy 111.047784 -277.251414) (xy 111.047784 -277.32609) (xy 111.04831 -277.33664) (xy 111.056848 -277.355935)
			(xy 111.064294 -277.363428) (xy 111.083355 -277.381578) (xy 111.116812 -277.422209) (xy 111.14437 -277.46705)
			(xy 111.165508 -277.515252) (xy 111.179824 -277.565901) (xy 111.187047 -277.618036) (xy 111.187484 -277.644352)
			(xy 111.187 -277.671605) (xy 111.179249 -277.725556) (xy 111.163898 -277.777855) (xy 111.141259 -277.827437)
			(xy 111.111794 -277.873291) (xy 111.076102 -277.914485) (xy 111.03491 -277.950179) (xy 110.989058 -277.979648)
			(xy 110.939478 -278.002289) (xy 110.88718 -278.017644) (xy 110.833229 -278.025398) (xy 110.805976 -278.02586)
			(xy 110.779505 -278.025464) (xy 110.72707 -278.018167) (xy 110.676147 -278.003687) (xy 110.627717 -277.982304)
			(xy 110.582709 -277.954428) (xy 110.541989 -277.920596) (xy 110.506339 -277.881457) (xy 110.476445 -277.837763)
			(xy 110.452882 -277.790355) (xy 110.436101 -277.740144) (xy 110.430818 -277.714202) (xy 110.428532 -277.701756)
			(xy 110.413292 -277.682452) (xy 110.31347 -277.638002) (xy 110.288578 -277.63978) (xy 110.27791 -277.646384)
			(xy 110.255311 -277.659729) (xy 110.207243 -277.680797) (xy 110.156742 -277.695082) (xy 110.104761 -277.702314)
			(xy 110.07852 -277.702772) (xy 110.078012 -277.702772) (xy 110.050758 -277.702333) (xy 109.996804 -277.694577)
			(xy 109.944504 -277.679221) (xy 109.894921 -277.656577) (xy 109.849066 -277.627107) (xy 109.807872 -277.591411)
			(xy 109.772179 -277.550215) (xy 109.742711 -277.504358) (xy 109.720071 -277.454774) (xy 109.704718 -277.402472)
			(xy 109.696965 -277.348518) (xy 109.696504 -277.321264) (xy 109.696948 -277.293893) (xy 109.704771 -277.239713)
			(xy 109.720265 -277.187209) (xy 109.743112 -277.137463) (xy 109.772841 -277.091497) (xy 109.790484 -277.070566)
			(xy 109.790738 -277.070312) (xy 109.79633 -277.063229) (xy 109.802572 -277.046309) (xy 109.80293 -277.037292)
			(xy 109.80293 -276.970236) (xy 109.802549 -276.961222) (xy 109.796317 -276.944305) (xy 109.790738 -276.937216)
			(xy 109.790484 -276.937216) (xy 109.790484 -276.936962) (xy 109.772858 -276.916019) (xy 109.743145 -276.870049)
			(xy 109.720307 -276.820304) (xy 109.704812 -276.767806) (xy 109.69698 -276.713632) (xy 109.696504 -276.686264)
			(xy 109.697083 -276.656788) (xy 109.706142 -276.598536) (xy 109.724056 -276.542372) (xy 109.750396 -276.489632)
			(xy 109.784537 -276.441572) (xy 109.804708 -276.420072) (xy 109.811249 -276.412742) (xy 109.81869 -276.394578)
			(xy 109.819186 -276.384766) (xy 109.819186 -276.331426) (xy 109.81182 -276.324568) (xy 109.804477 -276.318045)
			(xy 109.786323 -276.310594) (xy 109.776514 -276.31009) (xy 109.74451 -276.31009) (xy 109.734698 -276.310593)
			(xy 109.716533 -276.318027) (xy 109.709204 -276.324568) (xy 109.687705 -276.344742) (xy 109.639645 -276.378886)
			(xy 109.586906 -276.405232) (xy 109.530741 -276.423153) (xy 109.472489 -276.432223) (xy 109.443012 -276.432772)
			(xy 109.415758 -276.432333) (xy 109.361804 -276.424577) (xy 109.309504 -276.409221) (xy 109.259921 -276.386577)
			(xy 109.214066 -276.357107) (xy 109.172872 -276.321411) (xy 109.137179 -276.280215) (xy 109.107711 -276.234358)
			(xy 109.085071 -276.184774) (xy 109.069718 -276.132472) (xy 109.061965 -276.078518) (xy 109.061504 -276.051264)
			(xy 105.628694 -276.051264) (xy 105.628694 -276.062948) (xy 105.629222 -276.074581) (xy 105.639419 -276.09549)
			(xy 105.648252 -276.10308) (xy 105.670737 -276.121269) (xy 105.710469 -276.163291) (xy 105.743407 -276.210827)
			(xy 105.768794 -276.262788) (xy 105.786051 -276.317985) (xy 105.794782 -276.375154) (xy 105.795318 -276.40407)
			(xy 105.794817 -276.431322) (xy 105.787064 -276.485271) (xy 105.771712 -276.537567) (xy 105.749074 -276.587147)
			(xy 105.71961 -276.632999) (xy 105.68392 -276.674192) (xy 105.642731 -276.709886) (xy 105.596882 -276.739355)
			(xy 105.547305 -276.761998) (xy 105.49501 -276.777356) (xy 105.441062 -276.785114) (xy 105.41381 -276.785578)
			(xy 105.384893 -276.785061) (xy 105.327721 -276.776333) (xy 105.272522 -276.759075) (xy 105.22056 -276.733683)
			(xy 105.173026 -276.700739) (xy 105.13101 -276.660998) (xy 105.11282 -276.638512) (xy 105.105192 -276.629726)
			(xy 105.084307 -276.61953) (xy 105.072688 -276.618954) (xy 104.992932 -276.618954) (xy 104.981301 -276.619507)
			(xy 104.96039 -276.629684) (xy 104.9528 -276.638512) (xy 104.942769 -276.651117) (xy 104.920893 -276.674769)
			(xy 104.909112 -276.685756) (xy 104.900222 -276.693884) (xy 104.891586 -276.715982) (xy 104.900222 -276.808692)
			(xy 104.901916 -276.820318) (xy 104.914226 -276.840299) (xy 104.923844 -276.847046) (xy 104.924098 -276.8473)
			(xy 104.947407 -276.862306) (xy 104.989845 -276.897971) (xy 105.026673 -276.939405) (xy 105.057113 -276.985734)
			(xy 105.080524 -277.035983) (xy 105.096413 -277.089091) (xy 105.104446 -277.143941) (xy 105.104946 -277.171658)
			(xy 105.10446 -277.198909) (xy 105.096704 -277.252857) (xy 105.081349 -277.305152) (xy 105.058707 -277.354729)
			(xy 105.029241 -277.400579) (xy 104.99355 -277.44177) (xy 104.952359 -277.477461) (xy 104.906509 -277.506927)
			(xy 104.856932 -277.529569) (xy 104.804637 -277.544924) (xy 104.750689 -277.55268) (xy 104.696187 -277.55268)
			(xy 104.642239 -277.544924) (xy 104.589944 -277.529569) (xy 104.540367 -277.506927) (xy 104.494517 -277.477461)
			(xy 104.453326 -277.44177) (xy 104.417635 -277.400579) (xy 104.388169 -277.354729) (xy 104.365527 -277.305152)
			(xy 104.350172 -277.252857) (xy 104.342416 -277.198909) (xy 104.34193 -277.171658) (xy 104.342402 -277.14524)
			(xy 104.349686 -277.09291) (xy 104.364122 -277.042085) (xy 104.385435 -276.99374) (xy 104.413216 -276.948798)
			(xy 104.446934 -276.908121) (xy 104.466136 -276.889972) (xy 104.475026 -276.881844) (xy 104.483662 -276.859746)
			(xy 104.475026 -276.767036) (xy 104.473338 -276.755409) (xy 104.461026 -276.735426) (xy 104.451404 -276.728682)
			(xy 104.45115 -276.728428) (xy 104.429535 -276.714589) (xy 104.389877 -276.68201) (xy 104.354959 -276.644394)
			(xy 104.325417 -276.602424) (xy 104.313228 -276.579838) (xy 104.30764 -276.56917) (xy 104.28859 -276.5552)
			(xy 104.196388 -276.539706) (xy 104.184684 -276.53846) (xy 104.162198 -276.54532) (xy 104.153208 -276.552914)
			(xy 104.152954 -276.553168) (xy 104.1341 -276.57061) (xy 104.09256 -276.600817) (xy 104.07015 -276.613366)
			(xy 104.058212 -276.619716) (xy 104.043988 -276.642068) (xy 104.038146 -276.755606) (xy 104.050084 -276.779482)
			(xy 104.061006 -276.786848) (xy 104.082749 -276.802181) (xy 104.122231 -276.837839) (xy 104.156378 -276.878635)
			(xy 104.184528 -276.923778) (xy 104.206135 -276.972394) (xy 104.22078 -277.02354) (xy 104.22818 -277.076224)
			(xy 104.228646 -277.102824) (xy 104.228093 -277.13174) (xy 104.219374 -277.18891) (xy 104.202124 -277.244109)
			(xy 104.176739 -277.296072) (xy 104.143801 -277.343606) (xy 104.104064 -277.385623) (xy 104.08158 -277.403814)
			(xy 104.072773 -277.411421) (xy 104.06259 -277.432322) (xy 104.062022 -277.443946) (xy 104.062022 -277.523702)
			(xy 104.062567 -277.535333) (xy 104.072751 -277.556243) (xy 104.08158 -277.563834) (xy 104.104076 -277.582011)
			(xy 104.143811 -277.624033) (xy 104.176749 -277.671571) (xy 104.202136 -277.723535) (xy 104.219389 -277.778735)
			(xy 104.228114 -277.835907) (xy 104.228646 -277.864824) (xy 104.22816 -277.892075) (xy 104.220404 -277.946023)
			(xy 104.205049 -277.998318) (xy 104.182407 -278.047895) (xy 104.152941 -278.093745) (xy 104.11725 -278.134936)
			(xy 104.076059 -278.170627) (xy 104.030209 -278.200093) (xy 103.980632 -278.222735) (xy 103.928337 -278.23809)
			(xy 103.874389 -278.245846) (xy 103.819887 -278.245846) (xy 103.765939 -278.23809) (xy 103.713644 -278.222735)
			(xy 103.664067 -278.200093) (xy 103.618217 -278.170627) (xy 103.577026 -278.134936) (xy 103.541335 -278.093745)
			(xy 103.511869 -278.047895) (xy 103.489227 -277.998318) (xy 103.473872 -277.946023) (xy 103.466116 -277.892075)
			(xy 103.46563 -277.864824) (xy 98.74377 -277.864824) (xy 98.74377 -282.904438) (xy 101.903022 -282.904438)
			(xy 101.903506 -282.876864) (xy 101.911454 -282.822292) (xy 101.927175 -282.769432) (xy 101.950341 -282.719386)
			(xy 101.980471 -282.673196) (xy 102.016936 -282.631824) (xy 102.037642 -282.613608) (xy 102.045721 -282.606056)
			(xy 102.055071 -282.586042) (xy 102.055676 -282.575) (xy 102.055676 -282.497276) (xy 102.055073 -282.486231)
			(xy 102.045733 -282.466209) (xy 102.037642 -282.458668) (xy 102.016921 -282.440468) (xy 101.980449 -282.399098)
			(xy 101.950317 -282.352906) (xy 101.927153 -282.302856) (xy 101.911439 -282.249991) (xy 101.903504 -282.195414)
			(xy 101.903022 -282.167838) (xy 101.903506 -282.140264) (xy 101.911454 -282.085692) (xy 101.927175 -282.032832)
			(xy 101.950341 -281.982786) (xy 101.980471 -281.936596) (xy 102.016936 -281.895224) (xy 102.037642 -281.877008)
			(xy 102.045721 -281.869456) (xy 102.055071 -281.849442) (xy 102.055676 -281.8384) (xy 102.055676 -281.760676)
			(xy 102.055073 -281.749631) (xy 102.045733 -281.729609) (xy 102.037642 -281.722068) (xy 102.016921 -281.703868)
			(xy 101.980449 -281.662498) (xy 101.950317 -281.616306) (xy 101.927153 -281.566256) (xy 101.911439 -281.513391)
			(xy 101.903504 -281.458814) (xy 101.903022 -281.431238) (xy 101.903491 -281.403985) (xy 101.911243 -281.350032)
			(xy 101.926596 -281.297733) (xy 101.949236 -281.248151) (xy 101.978703 -281.202296) (xy 102.014397 -281.161102)
			(xy 102.05559 -281.125408) (xy 102.101444 -281.09594) (xy 102.151025 -281.073299) (xy 102.203325 -281.057945)
			(xy 102.257277 -281.050191) (xy 102.28453 -281.04973) (xy 102.312387 -281.050204) (xy 102.367506 -281.058332)
			(xy 102.420859 -281.074383) (xy 102.471313 -281.098016) (xy 102.517798 -281.128729) (xy 102.559327 -281.165871)
			(xy 102.595019 -281.208652) (xy 102.624116 -281.256165) (xy 102.646 -281.307402) (xy 102.653592 -281.33421)
			(xy 102.655878 -281.3431) (xy 102.666546 -281.35834) (xy 102.738428 -281.406092) (xy 102.756462 -281.410156)
			(xy 102.765606 -281.408886) (xy 102.778623 -281.407218) (xy 102.804807 -281.405437) (xy 102.81793 -281.40533)
			(xy 102.831053 -281.405425) (xy 102.857239 -281.407203) (xy 102.870254 -281.408886) (xy 102.879398 -281.410156)
			(xy 102.897432 -281.406092) (xy 102.969314 -281.35834) (xy 102.979982 -281.3431) (xy 102.982268 -281.33421)
			(xy 102.989866 -281.307402) (xy 103.011728 -281.256153) (xy 103.040812 -281.208628) (xy 103.076499 -281.165839)
			(xy 103.118029 -281.128694) (xy 103.16452 -281.097985) (xy 103.214983 -281.074364) (xy 103.268345 -281.058334)
			(xy 103.323471 -281.050234) (xy 103.35133 -281.04973) (xy 103.378585 -281.050127) (xy 103.432541 -281.057889)
			(xy 103.484842 -281.073251) (xy 103.534425 -281.0959) (xy 103.58028 -281.125374) (xy 103.621473 -281.161075)
			(xy 103.657166 -281.202275) (xy 103.686633 -281.248135) (xy 103.709273 -281.297722) (xy 103.724625 -281.350026)
			(xy 103.732378 -281.403983) (xy 103.732838 -281.431238) (xy 103.732367 -281.458537) (xy 103.724591 -281.512579)
			(xy 103.709189 -281.564959) (xy 103.686476 -281.614609) (xy 103.656915 -281.660512) (xy 103.639366 -281.681428)
			(xy 103.633016 -281.688794) (xy 103.626666 -281.706574) (xy 103.629968 -281.795728) (xy 103.637842 -281.813508)
			(xy 103.6447 -281.820112) (xy 103.665831 -281.841741) (xy 103.701631 -281.89047) (xy 103.729295 -281.944237)
			(xy 103.735566 -281.963368) (xy 108.281722 -281.963368) (xy 108.285793 -281.907746) (xy 108.297919 -281.853309)
			(xy 108.317842 -281.801218) (xy 108.345138 -281.752583) (xy 108.379224 -281.70844) (xy 108.419373 -281.669731)
			(xy 108.464731 -281.63728) (xy 108.514331 -281.611779) (xy 108.567115 -281.593772) (xy 108.621958 -281.583642)
			(xy 108.677692 -281.581605) (xy 108.733129 -281.587705) (xy 108.787086 -281.601811) (xy 108.838415 -281.623623)
			(xy 108.886021 -281.652677) (xy 108.928889 -281.688352) (xy 108.966106 -281.729889) (xy 108.996879 -281.776402)
			(xy 109.020551 -281.826899) (xy 109.036619 -281.880306) (xy 109.044739 -281.935482) (xy 109.045248 -281.963368)
			(xy 109.044739 -281.991254) (xy 109.036619 -282.04643) (xy 109.020551 -282.099837) (xy 108.996879 -282.150334)
			(xy 108.966106 -282.196847) (xy 108.928889 -282.238384) (xy 108.886021 -282.274059) (xy 108.838415 -282.303113)
			(xy 108.787086 -282.324925) (xy 108.733129 -282.339031) (xy 108.677692 -282.345131) (xy 108.621958 -282.343094)
			(xy 108.567115 -282.332964) (xy 108.514331 -282.314957) (xy 108.464731 -282.289456) (xy 108.419373 -282.257005)
			(xy 108.379224 -282.218296) (xy 108.345138 -282.174153) (xy 108.317842 -282.125518) (xy 108.297919 -282.073427)
			(xy 108.285793 -282.01899) (xy 108.281722 -281.963368) (xy 103.735566 -281.963368) (xy 103.74813 -282.001695)
			(xy 103.757663 -282.061405) (xy 103.758238 -282.091638) (xy 103.757742 -282.119276) (xy 103.74975 -282.173971)
			(xy 103.733952 -282.226942) (xy 103.710681 -282.277081) (xy 103.680421 -282.323338) (xy 103.66248 -282.344368)
			(xy 103.654098 -282.353766) (xy 103.648256 -282.37815) (xy 103.672386 -282.47213) (xy 103.676088 -282.484075)
			(xy 103.692864 -282.502584) (xy 103.70439 -282.507436) (xy 103.731799 -282.517772) (xy 103.783314 -282.545654)
			(xy 103.829959 -282.581086) (xy 103.870637 -282.623235) (xy 103.904391 -282.671108) (xy 103.930427 -282.72358)
			(xy 103.948133 -282.779416) (xy 103.957092 -282.837304) (xy 103.957628 -282.866592) (xy 103.957115 -282.893842)
			(xy 103.957113 -282.893854) (xy 104.287247 -282.893854) (xy 104.287247 -282.839346) (xy 104.295005 -282.785392)
			(xy 104.310362 -282.733091) (xy 104.333007 -282.683509) (xy 104.362477 -282.637654) (xy 104.398174 -282.59646)
			(xy 104.43937 -282.560765) (xy 104.485226 -282.531297) (xy 104.53481 -282.508655) (xy 104.587111 -282.493301)
			(xy 104.641066 -282.485546) (xy 104.66832 -282.485084) (xy 104.695692 -282.485518) (xy 104.749873 -282.49334)
			(xy 104.802377 -282.508836) (xy 104.852124 -282.531685) (xy 104.898088 -282.561418) (xy 104.919018 -282.579064)
			(xy 104.919272 -282.579318) (xy 104.926361 -282.584901) (xy 104.943276 -282.591149) (xy 104.952292 -282.59151)
			(xy 105.019348 -282.59151) (xy 105.028362 -282.591126) (xy 105.045279 -282.584897) (xy 105.052368 -282.579318)
			(xy 105.052368 -282.579064) (xy 105.052622 -282.579064) (xy 105.073568 -282.561442) (xy 105.119538 -282.531729)
			(xy 105.169282 -282.50889) (xy 105.221779 -282.493395) (xy 105.275952 -282.485561) (xy 105.30332 -282.485084)
			(xy 105.33057 -282.485587) (xy 105.384514 -282.493346) (xy 105.436805 -282.508702) (xy 105.486379 -282.531344)
			(xy 105.532226 -282.56081) (xy 105.573413 -282.596501) (xy 105.609102 -282.63769) (xy 105.638565 -282.683538)
			(xy 105.661205 -282.733113) (xy 105.676558 -282.785405) (xy 105.684314 -282.83935) (xy 105.684314 -282.89385)
			(xy 105.682792 -282.904438) (xy 110.063534 -282.904438) (xy 110.064014 -282.876864) (xy 110.071962 -282.822291)
			(xy 110.087683 -282.769431) (xy 110.110851 -282.719385) (xy 110.140981 -282.673195) (xy 110.177447 -282.631824)
			(xy 110.198154 -282.613608) (xy 110.206234 -282.606058) (xy 110.215583 -282.586042) (xy 110.216188 -282.575)
			(xy 110.216188 -282.497276) (xy 110.215581 -282.486231) (xy 110.206244 -282.46621) (xy 110.198154 -282.458668)
			(xy 110.177415 -282.440487) (xy 110.140949 -282.399111) (xy 110.110821 -282.352914) (xy 110.087661 -282.302861)
			(xy 110.07195 -282.249993) (xy 110.064016 -282.195414) (xy 110.063534 -282.167838) (xy 110.064014 -282.140264)
			(xy 110.071962 -282.085691) (xy 110.087683 -282.032831) (xy 110.110851 -281.982785) (xy 110.140981 -281.936595)
			(xy 110.177447 -281.895224) (xy 110.198154 -281.877008) (xy 110.206234 -281.869458) (xy 110.215583 -281.849442)
			(xy 110.216188 -281.8384) (xy 110.216188 -281.760676) (xy 110.215581 -281.749631) (xy 110.206244 -281.72961)
			(xy 110.198154 -281.722068) (xy 110.177415 -281.703887) (xy 110.140949 -281.662511) (xy 110.110821 -281.616314)
			(xy 110.087661 -281.566261) (xy 110.07195 -281.513393) (xy 110.064016 -281.458814) (xy 110.063534 -281.431238)
			(xy 110.063991 -281.403984) (xy 110.071744 -281.350031) (xy 110.087097 -281.29773) (xy 110.109738 -281.248147)
			(xy 110.139206 -281.202292) (xy 110.174901 -281.161098) (xy 110.216095 -281.125404) (xy 110.261951 -281.095936)
			(xy 110.311534 -281.073296) (xy 110.363835 -281.057943) (xy 110.417788 -281.050191) (xy 110.445042 -281.04973)
			(xy 110.4729 -281.050193) (xy 110.528019 -281.058323) (xy 110.581372 -281.074376) (xy 110.631826 -281.09801)
			(xy 110.678311 -281.128725) (xy 110.71984 -281.165867) (xy 110.755531 -281.20865) (xy 110.784628 -281.256164)
			(xy 110.806512 -281.307402) (xy 110.814104 -281.33421) (xy 110.81639 -281.3431) (xy 110.827058 -281.35834)
			(xy 110.89894 -281.406092) (xy 110.916974 -281.410156) (xy 110.926118 -281.408886) (xy 110.939135 -281.407217)
			(xy 110.965319 -281.405437) (xy 110.978442 -281.40533) (xy 110.991565 -281.405424) (xy 111.017751 -281.407203)
			(xy 111.030766 -281.408886) (xy 111.03991 -281.410156) (xy 111.057944 -281.406092) (xy 111.129826 -281.35834)
			(xy 111.140494 -281.3431) (xy 111.14278 -281.33421) (xy 111.150367 -281.307399) (xy 111.17223 -281.256149)
			(xy 111.201315 -281.208623) (xy 111.237003 -281.165834) (xy 111.278535 -281.12869) (xy 111.325028 -281.097981)
			(xy 111.375492 -281.074361) (xy 111.428855 -281.058331) (xy 111.483983 -281.050233) (xy 111.511842 -281.04973)
			(xy 111.539096 -281.050139) (xy 111.593048 -281.057902) (xy 111.645347 -281.073264) (xy 111.694927 -281.095913)
			(xy 111.740779 -281.125387) (xy 111.78197 -281.161087) (xy 111.817661 -281.202285) (xy 111.847125 -281.248143)
			(xy 111.869764 -281.297728) (xy 111.885115 -281.35003) (xy 111.892867 -281.403984) (xy 111.89335 -281.431238)
			(xy 111.892876 -281.458537) (xy 111.8851 -281.512578) (xy 111.869699 -281.564959) (xy 111.846986 -281.614608)
			(xy 111.817427 -281.660512) (xy 111.799878 -281.681428) (xy 111.793528 -281.688794) (xy 111.787178 -281.706574)
			(xy 111.79048 -281.795728) (xy 111.798354 -281.813508) (xy 111.805212 -281.820112) (xy 111.826328 -281.841756)
			(xy 111.862133 -281.890479) (xy 111.889802 -281.944242) (xy 111.896073 -281.963368) (xy 116.442234 -281.963368)
			(xy 116.446305 -281.907746) (xy 116.458431 -281.853309) (xy 116.478354 -281.801218) (xy 116.50565 -281.752583)
			(xy 116.539736 -281.70844) (xy 116.579885 -281.669731) (xy 116.625243 -281.63728) (xy 116.674843 -281.611779)
			(xy 116.727627 -281.593772) (xy 116.78247 -281.583642) (xy 116.838204 -281.581605) (xy 116.893641 -281.587705)
			(xy 116.947598 -281.601811) (xy 116.998927 -281.623623) (xy 117.046533 -281.652677) (xy 117.089401 -281.688352)
			(xy 117.126618 -281.729889) (xy 117.157391 -281.776402) (xy 117.181063 -281.826899) (xy 117.197131 -281.880306)
			(xy 117.205251 -281.935482) (xy 117.20576 -281.963368) (xy 117.205251 -281.991254) (xy 117.197131 -282.04643)
			(xy 117.181063 -282.099837) (xy 117.157391 -282.150334) (xy 117.126618 -282.196847) (xy 117.089401 -282.238384)
			(xy 117.046533 -282.274059) (xy 116.998927 -282.303113) (xy 116.947598 -282.324925) (xy 116.893641 -282.339031)
			(xy 116.838204 -282.345131) (xy 116.78247 -282.343094) (xy 116.727627 -282.332964) (xy 116.674843 -282.314957)
			(xy 116.625243 -282.289456) (xy 116.579885 -282.257005) (xy 116.539736 -282.218296) (xy 116.50565 -282.174153)
			(xy 116.478354 -282.125518) (xy 116.458431 -282.073427) (xy 116.446305 -282.01899) (xy 116.442234 -281.963368)
			(xy 111.896073 -281.963368) (xy 111.90864 -282.001697) (xy 111.918175 -282.061406) (xy 111.91875 -282.091638)
			(xy 111.918251 -282.119276) (xy 111.910259 -282.173971) (xy 111.894462 -282.226942) (xy 111.871191 -282.27708)
			(xy 111.840932 -282.323338) (xy 111.822992 -282.344368) (xy 111.81461 -282.353766) (xy 111.808768 -282.37815)
			(xy 111.832898 -282.47213) (xy 111.836594 -282.484078) (xy 111.853374 -282.502586) (xy 111.864902 -282.507436)
			(xy 111.892314 -282.517765) (xy 111.943828 -282.545649) (xy 111.990473 -282.581082) (xy 112.03115 -282.623232)
			(xy 112.064904 -282.671106) (xy 112.09094 -282.723579) (xy 112.108645 -282.779416) (xy 112.117604 -282.837304)
			(xy 112.11814 -282.866592) (xy 112.117605 -282.893855) (xy 112.447747 -282.893855) (xy 112.447747 -282.839345)
			(xy 112.455505 -282.78539) (xy 112.470863 -282.733089) (xy 112.493509 -282.683505) (xy 112.52298 -282.63765)
			(xy 112.558678 -282.596455) (xy 112.599876 -282.560761) (xy 112.645734 -282.531293) (xy 112.695319 -282.508652)
			(xy 112.747622 -282.493299) (xy 112.801577 -282.485545) (xy 112.828832 -282.485084) (xy 112.856204 -282.485511)
			(xy 112.910385 -282.493335) (xy 112.96289 -282.508832) (xy 113.012636 -282.531683) (xy 113.0586 -282.561418)
			(xy 113.07953 -282.579064) (xy 113.079784 -282.579318) (xy 113.086869 -282.584906) (xy 113.103787 -282.591151)
			(xy 113.112804 -282.59151) (xy 113.17986 -282.59151) (xy 113.188875 -282.591132) (xy 113.205792 -282.584899)
			(xy 113.21288 -282.579318) (xy 113.21288 -282.579064) (xy 113.213134 -282.579064) (xy 113.234076 -282.561437)
			(xy 113.280046 -282.531724) (xy 113.329791 -282.508887) (xy 113.38229 -282.493393) (xy 113.436464 -282.48556)
			(xy 113.463832 -282.485084) (xy 113.491081 -282.485588) (xy 113.545024 -282.493348) (xy 113.597314 -282.508706)
			(xy 113.646886 -282.531348) (xy 113.692732 -282.560815) (xy 113.733917 -282.596505) (xy 113.769605 -282.637694)
			(xy 113.799067 -282.683542) (xy 113.821706 -282.733116) (xy 113.837059 -282.785407) (xy 113.844814 -282.839351)
			(xy 113.844814 -282.893849) (xy 113.843292 -282.904438) (xy 118.56212 -282.904438) (xy 118.562605 -282.876864)
			(xy 118.570552 -282.822292) (xy 118.586273 -282.769432) (xy 118.60944 -282.719386) (xy 118.639569 -282.673196)
			(xy 118.676034 -282.631824) (xy 118.69674 -282.613608) (xy 118.704818 -282.606056) (xy 118.714169 -282.586042)
			(xy 118.714774 -282.575) (xy 118.714774 -282.497276) (xy 118.714172 -282.486231) (xy 118.704832 -282.466209)
			(xy 118.69674 -282.458668) (xy 118.676018 -282.440468) (xy 118.639547 -282.399098) (xy 118.609415 -282.352906)
			(xy 118.586251 -282.302856) (xy 118.570537 -282.249991) (xy 118.562602 -282.195414) (xy 118.56212 -282.167838)
			(xy 118.562605 -282.140264) (xy 118.570552 -282.085692) (xy 118.586273 -282.032832) (xy 118.60944 -281.982786)
			(xy 118.639569 -281.936596) (xy 118.676034 -281.895224) (xy 118.69674 -281.877008) (xy 118.704818 -281.869456)
			(xy 118.714169 -281.849442) (xy 118.714774 -281.8384) (xy 118.714774 -281.760676) (xy 118.714172 -281.749631)
			(xy 118.704832 -281.729609) (xy 118.69674 -281.722068) (xy 118.676018 -281.703868) (xy 118.639547 -281.662498)
			(xy 118.609415 -281.616306) (xy 118.586251 -281.566256) (xy 118.570537 -281.513391) (xy 118.562602 -281.458814)
			(xy 118.56212 -281.431238) (xy 118.562591 -281.403985) (xy 118.570343 -281.350033) (xy 118.585696 -281.297733)
			(xy 118.608336 -281.248151) (xy 118.637803 -281.202297) (xy 118.673496 -281.161103) (xy 118.714689 -281.125409)
			(xy 118.760543 -281.095941) (xy 118.810124 -281.073299) (xy 118.862423 -281.057945) (xy 118.916375 -281.050191)
			(xy 118.943628 -281.04973) (xy 118.971485 -281.050206) (xy 119.026604 -281.058334) (xy 119.079956 -281.074385)
			(xy 119.130411 -281.098017) (xy 119.176896 -281.12873) (xy 119.218425 -281.165871) (xy 119.254117 -281.208652)
			(xy 119.283214 -281.256166) (xy 119.305098 -281.307402) (xy 119.31269 -281.33421) (xy 119.314976 -281.3431)
			(xy 119.325644 -281.35834) (xy 119.397526 -281.406092) (xy 119.41556 -281.410156) (xy 119.424704 -281.408886)
			(xy 119.437721 -281.407218) (xy 119.463905 -281.405438) (xy 119.477028 -281.40533) (xy 119.490151 -281.405425)
			(xy 119.516337 -281.407203) (xy 119.529352 -281.408886) (xy 119.538496 -281.410156) (xy 119.55653 -281.406092)
			(xy 119.628412 -281.35834) (xy 119.63908 -281.3431) (xy 119.641366 -281.33421) (xy 119.648875 -281.307374)
			(xy 119.670745 -281.25612) (xy 119.699839 -281.208591) (xy 119.735536 -281.1658) (xy 119.777078 -281.128657)
			(xy 119.823581 -281.097951) (xy 119.874056 -281.074336) (xy 119.927429 -281.058315) (xy 119.982565 -281.050227)
			(xy 120.010428 -281.04973) (xy 120.037683 -281.050129) (xy 120.091639 -281.057891) (xy 120.14394 -281.073252)
			(xy 120.193523 -281.095901) (xy 120.239378 -281.125375) (xy 120.280571 -281.161076) (xy 120.316264 -281.202275)
			(xy 120.345731 -281.248135) (xy 120.368371 -281.297722) (xy 120.383723 -281.350026) (xy 120.391476 -281.403983)
			(xy 120.391936 -281.431238) (xy 120.391466 -281.458537) (xy 120.383689 -281.512579) (xy 120.368287 -281.564959)
			(xy 120.345574 -281.614609) (xy 120.316013 -281.660512) (xy 120.298464 -281.681428) (xy 120.292114 -281.688794)
			(xy 120.285764 -281.706574) (xy 120.289066 -281.795728) (xy 120.29694 -281.813508) (xy 120.303798 -281.820112)
			(xy 120.324929 -281.841741) (xy 120.360729 -281.89047) (xy 120.388393 -281.944237) (xy 120.394664 -281.963368)
			(xy 124.94082 -281.963368) (xy 124.944891 -281.907746) (xy 124.957017 -281.853309) (xy 124.97694 -281.801218)
			(xy 125.004236 -281.752583) (xy 125.038322 -281.70844) (xy 125.078471 -281.669731) (xy 125.123829 -281.63728)
			(xy 125.173429 -281.611779) (xy 125.226213 -281.593772) (xy 125.281056 -281.583642) (xy 125.33679 -281.581605)
			(xy 125.392227 -281.587705) (xy 125.446184 -281.601811) (xy 125.497513 -281.623623) (xy 125.545119 -281.652677)
			(xy 125.587987 -281.688352) (xy 125.625204 -281.729889) (xy 125.655977 -281.776402) (xy 125.679649 -281.826899)
			(xy 125.695717 -281.880306) (xy 125.703837 -281.935482) (xy 125.704346 -281.963368) (xy 125.703837 -281.991254)
			(xy 125.695717 -282.04643) (xy 125.679649 -282.099837) (xy 125.655977 -282.150334) (xy 125.625204 -282.196847)
			(xy 125.587987 -282.238384) (xy 125.545119 -282.274059) (xy 125.497513 -282.303113) (xy 125.446184 -282.324925)
			(xy 125.392227 -282.339031) (xy 125.33679 -282.345131) (xy 125.281056 -282.343094) (xy 125.226213 -282.332964)
			(xy 125.173429 -282.314957) (xy 125.123829 -282.289456) (xy 125.078471 -282.257005) (xy 125.038322 -282.218296)
			(xy 125.004236 -282.174153) (xy 124.97694 -282.125518) (xy 124.957017 -282.073427) (xy 124.944891 -282.01899)
			(xy 124.94082 -281.963368) (xy 120.394664 -281.963368) (xy 120.407228 -282.001695) (xy 120.416761 -282.061405)
			(xy 120.417336 -282.091638) (xy 120.41684 -282.119276) (xy 120.408848 -282.173971) (xy 120.393051 -282.226942)
			(xy 120.369779 -282.277081) (xy 120.339519 -282.323339) (xy 120.321578 -282.344368) (xy 120.313196 -282.353766)
			(xy 120.307354 -282.37815) (xy 120.331484 -282.47213) (xy 120.335187 -282.484075) (xy 120.351962 -282.502584)
			(xy 120.363488 -282.507436) (xy 120.390896 -282.517773) (xy 120.442411 -282.545655) (xy 120.489057 -282.581087)
			(xy 120.529735 -282.623235) (xy 120.563489 -282.671108) (xy 120.589525 -282.72358) (xy 120.607231 -282.779417)
			(xy 120.61619 -282.837304) (xy 120.616726 -282.866592) (xy 120.616192 -282.893854) (xy 120.946347 -282.893854)
			(xy 120.946347 -282.839346) (xy 120.954105 -282.785392) (xy 120.969462 -282.733092) (xy 120.992107 -282.683509)
			(xy 121.021577 -282.637654) (xy 121.057273 -282.59646) (xy 121.098469 -282.560766) (xy 121.144325 -282.531298)
			(xy 121.193909 -282.508656) (xy 121.24621 -282.493301) (xy 121.300164 -282.485546) (xy 121.327418 -282.485084)
			(xy 121.35479 -282.485519) (xy 121.408971 -282.493341) (xy 121.461475 -282.508836) (xy 121.511222 -282.531686)
			(xy 121.557186 -282.561418) (xy 121.578116 -282.579064) (xy 121.57837 -282.579318) (xy 121.58546 -282.5849)
			(xy 121.602374 -282.591149) (xy 121.61139 -282.59151) (xy 121.678446 -282.59151) (xy 121.68746 -282.591125)
			(xy 121.704377 -282.584897) (xy 121.711466 -282.579318) (xy 121.711466 -282.579064) (xy 121.71172 -282.579064)
			(xy 121.732667 -282.561443) (xy 121.778636 -282.53173) (xy 121.82838 -282.508891) (xy 121.880877 -282.493396)
			(xy 121.93505 -282.485561) (xy 121.962418 -282.485084) (xy 121.989668 -282.485587) (xy 122.043612 -282.493345)
			(xy 122.095904 -282.508702) (xy 122.145478 -282.531343) (xy 122.191325 -282.56081) (xy 122.232512 -282.5965)
			(xy 122.268201 -282.637689) (xy 122.297665 -282.683538) (xy 122.320305 -282.733113) (xy 122.335658 -282.785405)
			(xy 122.343414 -282.83935) (xy 122.343414 -282.89385) (xy 122.341892 -282.904438) (xy 126.722632 -282.904438)
			(xy 126.723113 -282.876864) (xy 126.731061 -282.822291) (xy 126.746782 -282.769431) (xy 126.769949 -282.719385)
			(xy 126.800079 -282.673195) (xy 126.836545 -282.631824) (xy 126.857252 -282.613608) (xy 126.865332 -282.606058)
			(xy 126.874681 -282.586042) (xy 126.875286 -282.575) (xy 126.875286 -282.497276) (xy 126.87468 -282.486231)
			(xy 126.865342 -282.46621) (xy 126.857252 -282.458668) (xy 126.836513 -282.440488) (xy 126.800046 -282.399111)
			(xy 126.769919 -282.352915) (xy 126.746759 -282.302861) (xy 126.731048 -282.249993) (xy 126.723114 -282.195414)
			(xy 126.722632 -282.167838) (xy 126.723113 -282.140264) (xy 126.731061 -282.085691) (xy 126.746782 -282.032831)
			(xy 126.769949 -281.982785) (xy 126.800079 -281.936595) (xy 126.836545 -281.895224) (xy 126.857252 -281.877008)
			(xy 126.865332 -281.869458) (xy 126.874681 -281.849442) (xy 126.875286 -281.8384) (xy 126.875286 -281.760676)
			(xy 126.87468 -281.749631) (xy 126.865342 -281.72961) (xy 126.857252 -281.722068) (xy 126.836513 -281.703888)
			(xy 126.800046 -281.662511) (xy 126.769919 -281.616315) (xy 126.746759 -281.566261) (xy 126.731048 -281.513393)
			(xy 126.723114 -281.458814) (xy 126.722632 -281.431238) (xy 126.723091 -281.403984) (xy 126.730844 -281.350031)
			(xy 126.746197 -281.297731) (xy 126.768838 -281.248148) (xy 126.798306 -281.202293) (xy 126.834 -281.161099)
			(xy 126.875194 -281.125404) (xy 126.92105 -281.095937) (xy 126.970633 -281.073296) (xy 127.022933 -281.057943)
			(xy 127.076886 -281.050191) (xy 127.10414 -281.04973) (xy 127.131997 -281.050195) (xy 127.187117 -281.058325)
			(xy 127.240469 -281.074377) (xy 127.290924 -281.098011) (xy 127.337409 -281.128725) (xy 127.378938 -281.165868)
			(xy 127.414629 -281.20865) (xy 127.443726 -281.256164) (xy 127.46561 -281.307402) (xy 127.473202 -281.33421)
			(xy 127.475488 -281.3431) (xy 127.486156 -281.35834) (xy 127.558038 -281.406092) (xy 127.576072 -281.410156)
			(xy 127.585216 -281.408886) (xy 127.598233 -281.407217) (xy 127.624417 -281.405437) (xy 127.63754 -281.40533)
			(xy 127.650663 -281.405424) (xy 127.676849 -281.407203) (xy 127.689864 -281.408886) (xy 127.699008 -281.410156)
			(xy 127.717042 -281.406092) (xy 127.788924 -281.35834) (xy 127.799592 -281.3431) (xy 127.801878 -281.33421)
			(xy 127.809467 -281.307399) (xy 127.83133 -281.256149) (xy 127.860415 -281.208624) (xy 127.896103 -281.165835)
			(xy 127.937634 -281.12869) (xy 127.984126 -281.097982) (xy 128.034591 -281.074361) (xy 128.087954 -281.058332)
			(xy 128.143081 -281.050234) (xy 128.17094 -281.04973) (xy 128.198194 -281.050141) (xy 128.252146 -281.057904)
			(xy 128.304445 -281.073266) (xy 128.354025 -281.095914) (xy 128.399877 -281.125388) (xy 128.441068 -281.161088)
			(xy 128.476758 -281.202286) (xy 128.506223 -281.248144) (xy 128.528862 -281.297728) (xy 128.544213 -281.35003)
			(xy 128.551965 -281.403984) (xy 128.552448 -281.431238) (xy 128.551975 -281.458537) (xy 128.544199 -281.512578)
			(xy 128.528797 -281.564959) (xy 128.506085 -281.614608) (xy 128.476525 -281.660512) (xy 128.458976 -281.681428)
			(xy 128.452626 -281.688794) (xy 128.446276 -281.706574) (xy 128.449578 -281.795728) (xy 128.457452 -281.813508)
			(xy 128.46431 -281.820112) (xy 128.485426 -281.841756) (xy 128.521231 -281.890479) (xy 128.5489 -281.944242)
			(xy 128.555171 -281.963368) (xy 133.101332 -281.963368) (xy 133.105403 -281.907746) (xy 133.117529 -281.853309)
			(xy 133.137452 -281.801218) (xy 133.164748 -281.752583) (xy 133.198834 -281.70844) (xy 133.238983 -281.669731)
			(xy 133.284341 -281.63728) (xy 133.333941 -281.611779) (xy 133.386725 -281.593772) (xy 133.441568 -281.583642)
			(xy 133.497302 -281.581605) (xy 133.552739 -281.587705) (xy 133.606696 -281.601811) (xy 133.658025 -281.623623)
			(xy 133.705631 -281.652677) (xy 133.748499 -281.688352) (xy 133.785716 -281.729889) (xy 133.816489 -281.776402)
			(xy 133.840161 -281.826899) (xy 133.856229 -281.880306) (xy 133.864349 -281.935482) (xy 133.864858 -281.963368)
			(xy 133.864349 -281.991254) (xy 133.856229 -282.04643) (xy 133.840161 -282.099837) (xy 133.816489 -282.150334)
			(xy 133.785716 -282.196847) (xy 133.748499 -282.238384) (xy 133.705631 -282.274059) (xy 133.658025 -282.303113)
			(xy 133.606696 -282.324925) (xy 133.552739 -282.339031) (xy 133.497302 -282.345131) (xy 133.441568 -282.343094)
			(xy 133.386725 -282.332964) (xy 133.333941 -282.314957) (xy 133.284341 -282.289456) (xy 133.238983 -282.257005)
			(xy 133.198834 -282.218296) (xy 133.164748 -282.174153) (xy 133.137452 -282.125518) (xy 133.117529 -282.073427)
			(xy 133.105403 -282.01899) (xy 133.101332 -281.963368) (xy 128.555171 -281.963368) (xy 128.567738 -282.001697)
			(xy 128.577273 -282.061406) (xy 128.577848 -282.091638) (xy 128.577349 -282.119276) (xy 128.569357 -282.173971)
			(xy 128.553561 -282.226942) (xy 128.530289 -282.27708) (xy 128.50003 -282.323338) (xy 128.48209 -282.344368)
			(xy 128.473708 -282.353766) (xy 128.467866 -282.37815) (xy 128.491996 -282.47213) (xy 128.495693 -282.484077)
			(xy 128.512472 -282.502586) (xy 128.524 -282.507436) (xy 128.551411 -282.517766) (xy 128.602926 -282.54565)
			(xy 128.64957 -282.581083) (xy 128.690248 -282.623232) (xy 128.724002 -282.671106) (xy 128.750038 -282.723579)
			(xy 128.767743 -282.779416) (xy 128.776702 -282.837304) (xy 128.777238 -282.866592) (xy 128.776703 -282.893855)
			(xy 129.106847 -282.893855) (xy 129.106847 -282.839345) (xy 129.114605 -282.785391) (xy 129.129963 -282.733089)
			(xy 129.152608 -282.683506) (xy 129.18208 -282.637651) (xy 129.217777 -282.596456) (xy 129.258975 -282.560762)
			(xy 129.304832 -282.531294) (xy 129.354417 -282.508653) (xy 129.40672 -282.493299) (xy 129.460675 -282.485545)
			(xy 129.48793 -282.485084) (xy 129.515302 -282.485512) (xy 129.569483 -282.493336) (xy 129.621988 -282.508833)
			(xy 129.671734 -282.531683) (xy 129.717698 -282.561418) (xy 129.738628 -282.579064) (xy 129.738882 -282.579318)
			(xy 129.745968 -282.584905) (xy 129.762885 -282.591151) (xy 129.771902 -282.59151) (xy 129.838958 -282.59151)
			(xy 129.847973 -282.591131) (xy 129.86489 -282.584898) (xy 129.871978 -282.579318) (xy 129.871978 -282.579064)
			(xy 129.872232 -282.579064) (xy 129.893174 -282.561438) (xy 129.939145 -282.531725) (xy 129.98889 -282.508887)
			(xy 130.041388 -282.493393) (xy 130.095562 -282.485561) (xy 130.12293 -282.485084) (xy 130.150179 -282.485588)
			(xy 130.204123 -282.493348) (xy 130.256413 -282.508705) (xy 130.305985 -282.531347) (xy 130.351831 -282.560814)
			(xy 130.393017 -282.596505) (xy 130.428704 -282.637693) (xy 130.458167 -282.683541) (xy 130.480805 -282.733115)
			(xy 130.496159 -282.785407) (xy 130.503914 -282.839351) (xy 130.503914 -282.893849) (xy 130.496159 -282.947793)
			(xy 130.480805 -283.000085) (xy 130.458167 -283.049659) (xy 130.428704 -283.095507) (xy 130.393017 -283.136695)
			(xy 130.351831 -283.172386) (xy 130.305985 -283.201853) (xy 130.256413 -283.224495) (xy 130.204123 -283.239852)
			(xy 130.150179 -283.247612) (xy 130.12293 -283.2481) (xy 130.09556 -283.247616) (xy 130.041382 -283.239803)
			(xy 129.988879 -283.224318) (xy 129.939132 -283.20148) (xy 129.893164 -283.171759) (xy 129.872232 -283.15412)
			(xy 129.871978 -283.153866) (xy 129.864905 -283.14826) (xy 129.847978 -283.142026) (xy 129.838958 -283.141674)
			(xy 129.771902 -283.141674) (xy 129.762886 -283.142038) (xy 129.745969 -283.148281) (xy 129.738882 -283.153866)
			(xy 129.738882 -283.15412) (xy 129.738628 -283.15412) (xy 129.717699 -283.171763) (xy 129.671725 -283.201473)
			(xy 129.621977 -283.224308) (xy 129.569475 -283.239798) (xy 129.515299 -283.247626) (xy 129.48793 -283.2481)
			(xy 129.460675 -283.247655) (xy 129.40672 -283.239901) (xy 129.354417 -283.224547) (xy 129.304832 -283.201906)
			(xy 129.258975 -283.172438) (xy 129.217777 -283.136744) (xy 129.18208 -283.095549) (xy 129.152608 -283.049694)
			(xy 129.129963 -283.000111) (xy 129.114605 -282.947809) (xy 129.106847 -282.893855) (xy 128.776703 -282.893855)
			(xy 128.776652 -282.89643) (xy 128.767344 -282.955376) (xy 128.758696 -282.98394) (xy 128.755394 -282.994354)
			(xy 128.75768 -283.015944) (xy 128.807972 -283.100526) (xy 128.825244 -283.112972) (xy 128.836166 -283.115004)
			(xy 128.861983 -283.120344) (xy 128.911899 -283.137313) (xy 128.959003 -283.160993) (xy 129.002398 -283.190934)
			(xy 129.041256 -283.226565) (xy 129.074838 -283.267208) (xy 129.102503 -283.312087) (xy 129.123725 -283.360349)
			(xy 129.138099 -283.411073) (xy 129.145351 -283.463293) (xy 129.145792 -283.489654) (xy 129.145209 -283.519777)
			(xy 129.135733 -283.579274) (xy 129.117026 -283.636542) (xy 129.089553 -283.690159) (xy 129.053995 -283.738793)
			(xy 129.033016 -283.760418) (xy 129.026178 -283.76782) (xy 129.018456 -283.786418) (xy 129.01803 -283.796486)
			(xy 129.01803 -283.868622) (xy 129.018436 -283.878694) (xy 129.02617 -283.897292) (xy 129.033016 -283.90469)
			(xy 129.054019 -283.926293) (xy 129.089584 -283.974928) (xy 129.117059 -284.02855) (xy 129.131438 -284.072584)
			(xy 134.033006 -284.072584) (xy 134.033461 -284.045213) (xy 134.041281 -283.991034) (xy 134.056773 -283.93853)
			(xy 134.079617 -283.888784) (xy 134.109344 -283.842817) (xy 134.126986 -283.821886) (xy 134.12724 -283.821632)
			(xy 134.132824 -283.814544) (xy 134.139071 -283.797628) (xy 134.139432 -283.788612) (xy 134.139432 -283.721556)
			(xy 134.139041 -283.712543) (xy 134.132816 -283.695626) (xy 134.12724 -283.688536) (xy 134.126986 -283.688536)
			(xy 134.126986 -283.688282) (xy 134.10937 -283.667332) (xy 134.079655 -283.621364) (xy 134.056815 -283.571621)
			(xy 134.041318 -283.519124) (xy 134.033484 -283.464952) (xy 134.033006 -283.437584) (xy 134.033492 -283.410333)
			(xy 134.041248 -283.356385) (xy 134.056603 -283.30409) (xy 134.079245 -283.254513) (xy 134.108711 -283.208663)
			(xy 134.144402 -283.167472) (xy 134.185593 -283.131781) (xy 134.231443 -283.102315) (xy 134.28102 -283.079673)
			(xy 134.333315 -283.064318) (xy 134.387263 -283.056562) (xy 134.441765 -283.056562) (xy 134.495713 -283.064318)
			(xy 134.548008 -283.079673) (xy 134.597585 -283.102315) (xy 134.643435 -283.131781) (xy 134.684626 -283.167472)
			(xy 134.720317 -283.208663) (xy 134.749783 -283.254513) (xy 134.772425 -283.30409) (xy 134.78778 -283.356385)
			(xy 134.795536 -283.410333) (xy 134.796022 -283.437584) (xy 134.795566 -283.464955) (xy 134.787748 -283.519135)
			(xy 134.772258 -283.571639) (xy 134.749414 -283.621386) (xy 134.719685 -283.667351) (xy 134.702042 -283.688282)
			(xy 134.701788 -283.688536) (xy 134.696221 -283.695636) (xy 134.689963 -283.712542) (xy 134.689596 -283.721556)
			(xy 134.689596 -283.788612) (xy 134.689948 -283.797629) (xy 134.696199 -283.814546) (xy 134.701788 -283.821632)
			(xy 134.702042 -283.821632) (xy 134.702042 -283.821886) (xy 134.719695 -283.842807) (xy 134.749403 -283.888783)
			(xy 134.772236 -283.938534) (xy 134.787724 -283.991037) (xy 134.79555 -284.045214) (xy 134.796022 -284.072584)
			(xy 134.795536 -284.099835) (xy 134.78778 -284.153783) (xy 134.772425 -284.206078) (xy 134.749783 -284.255655)
			(xy 134.720317 -284.301505) (xy 134.684626 -284.342696) (xy 134.643435 -284.378387) (xy 134.597585 -284.407853)
			(xy 134.548008 -284.430495) (xy 134.495713 -284.44585) (xy 134.441765 -284.453606) (xy 134.387263 -284.453606)
			(xy 134.333315 -284.44585) (xy 134.28102 -284.430495) (xy 134.231443 -284.407853) (xy 134.185593 -284.378387)
			(xy 134.144402 -284.342696) (xy 134.108711 -284.301505) (xy 134.079245 -284.255655) (xy 134.056603 -284.206078)
			(xy 134.041248 -284.153783) (xy 134.033492 -284.099835) (xy 134.033006 -284.072584) (xy 129.131438 -284.072584)
			(xy 129.135762 -284.085825) (xy 129.145227 -284.145328) (xy 129.145792 -284.175454) (xy 129.145306 -284.202705)
			(xy 129.13755 -284.256653) (xy 129.122195 -284.308948) (xy 129.099553 -284.358525) (xy 129.070087 -284.404375)
			(xy 129.034396 -284.445566) (xy 128.993205 -284.481257) (xy 128.947355 -284.510723) (xy 128.897778 -284.533365)
			(xy 128.845483 -284.54872) (xy 128.791535 -284.556476) (xy 128.737033 -284.556476) (xy 128.683085 -284.54872)
			(xy 128.63079 -284.533365) (xy 128.581213 -284.510723) (xy 128.535363 -284.481257) (xy 128.494172 -284.445566)
			(xy 128.458481 -284.404375) (xy 128.429015 -284.358525) (xy 128.406373 -284.308948) (xy 128.391018 -284.256653)
			(xy 128.383262 -284.202705) (xy 128.382776 -284.175454) (xy 128.383374 -284.145332) (xy 128.392847 -284.085836)
			(xy 128.411551 -284.028568) (xy 128.439021 -283.974951) (xy 128.474575 -283.926316) (xy 128.495552 -283.90469)
			(xy 128.502382 -283.897282) (xy 128.510109 -283.878689) (xy 128.510538 -283.868622) (xy 128.510538 -283.796486)
			(xy 128.510136 -283.786414) (xy 128.502401 -283.767815) (xy 128.495552 -283.760418) (xy 128.474564 -283.7388)
			(xy 128.438995 -283.69017) (xy 128.411515 -283.636552) (xy 128.392809 -283.57928) (xy 128.383342 -283.519779)
			(xy 128.382776 -283.489654) (xy 128.383349 -283.459815) (xy 128.392666 -283.400869) (xy 128.401318 -283.372306)
			(xy 128.40462 -283.361892) (xy 128.402334 -283.340302) (xy 128.352042 -283.25572) (xy 128.33477 -283.243274)
			(xy 128.323848 -283.241242) (xy 128.295998 -283.235391) (xy 128.242335 -283.216454) (xy 128.192078 -283.18976)
			(xy 128.146341 -283.155899) (xy 128.106139 -283.115622) (xy 128.072363 -283.069823) (xy 128.045761 -283.019516)
			(xy 128.026924 -282.965818) (xy 128.02108 -282.937966) (xy 128.01854 -282.92552) (xy 128.0033 -282.906216)
			(xy 127.902208 -282.862528) (xy 127.87757 -282.864306) (xy 127.866902 -282.871164) (xy 127.843932 -282.885202)
			(xy 127.794858 -282.907333) (xy 127.743156 -282.922329) (xy 127.689857 -282.929892) (xy 127.66294 -282.930346)
			(xy 127.644921 -282.930129) (xy 127.609046 -282.926692) (xy 127.591312 -282.923488) (xy 127.58166 -282.92171)
			(xy 127.56261 -282.925266) (xy 127.48768 -282.973272) (xy 127.47625 -282.98902) (xy 127.473964 -282.998418)
			(xy 127.466566 -283.025463) (xy 127.444939 -283.07719) (xy 127.415976 -283.125197) (xy 127.380301 -283.16845)
			(xy 127.338682 -283.206018) (xy 127.292014 -283.237092) (xy 127.241301 -283.261004) (xy 127.187636 -283.27724)
			(xy 127.132173 -283.285449) (xy 127.10414 -283.285946) (xy 127.07689 -283.285408) (xy 127.022944 -283.277657)
			(xy 126.970649 -283.262308) (xy 126.921072 -283.239673) (xy 126.875221 -283.210213) (xy 126.834028 -283.174527)
			(xy 126.798334 -283.133342) (xy 126.768864 -283.087497) (xy 126.746219 -283.037924) (xy 126.73086 -282.985633)
			(xy 126.723098 -282.931688) (xy 126.722632 -282.904438) (xy 122.341892 -282.904438) (xy 122.335658 -282.947795)
			(xy 122.320305 -283.000087) (xy 122.297665 -283.049662) (xy 122.268201 -283.095511) (xy 122.232512 -283.1367)
			(xy 122.191325 -283.17239) (xy 122.145478 -283.201857) (xy 122.095904 -283.224498) (xy 122.043612 -283.239855)
			(xy 121.989668 -283.247613) (xy 121.962418 -283.2481) (xy 121.935048 -283.247623) (xy 121.88087 -283.239808)
			(xy 121.828367 -283.224321) (xy 121.778619 -283.201482) (xy 121.732652 -283.17176) (xy 121.71172 -283.15412)
			(xy 121.711466 -283.153866) (xy 121.704367 -283.148297) (xy 121.68746 -283.142041) (xy 121.678446 -283.141674)
			(xy 121.61139 -283.141674) (xy 121.602373 -283.142032) (xy 121.585457 -283.14828) (xy 121.57837 -283.153866)
			(xy 121.57837 -283.15412) (xy 121.578116 -283.15412) (xy 121.557191 -283.171768) (xy 121.511216 -283.201478)
			(xy 121.461467 -283.224312) (xy 121.408965 -283.239801) (xy 121.354788 -283.247627) (xy 121.327418 -283.2481)
			(xy 121.300164 -283.247654) (xy 121.24621 -283.239899) (xy 121.193909 -283.224544) (xy 121.144325 -283.201902)
			(xy 121.098469 -283.172434) (xy 121.057273 -283.13674) (xy 121.021577 -283.095546) (xy 120.992107 -283.049691)
			(xy 120.969462 -283.000108) (xy 120.954105 -282.947808) (xy 120.946347 -282.893854) (xy 120.616192 -282.893854)
			(xy 120.616141 -282.89643) (xy 120.606832 -282.955376) (xy 120.598184 -282.98394) (xy 120.594882 -282.994354)
			(xy 120.597168 -283.015944) (xy 120.64746 -283.100526) (xy 120.664732 -283.112972) (xy 120.675654 -283.115004)
			(xy 120.701469 -283.120353) (xy 120.751385 -283.13732) (xy 120.798489 -283.160999) (xy 120.841884 -283.190938)
			(xy 120.880743 -283.226569) (xy 120.914325 -283.26721) (xy 120.94199 -283.312089) (xy 120.963212 -283.36035)
			(xy 120.977587 -283.411074) (xy 120.984839 -283.463293) (xy 120.98528 -283.489654) (xy 120.984672 -283.519776)
			(xy 120.975198 -283.57927) (xy 120.956496 -283.636537) (xy 120.929029 -283.690155) (xy 120.893479 -283.738791)
			(xy 120.872504 -283.760418) (xy 120.865664 -283.767818) (xy 120.857944 -283.786417) (xy 120.857518 -283.796486)
			(xy 120.857518 -283.868622) (xy 120.857927 -283.878693) (xy 120.865659 -283.897291) (xy 120.872504 -283.90469)
			(xy 120.893505 -283.926295) (xy 120.929071 -283.97493) (xy 120.956547 -284.028551) (xy 120.970926 -284.072584)
			(xy 125.872494 -284.072584) (xy 125.872952 -284.045214) (xy 125.880772 -283.991034) (xy 125.896263 -283.938531)
			(xy 125.919107 -283.888784) (xy 125.948832 -283.842818) (xy 125.966474 -283.821886) (xy 125.966728 -283.821632)
			(xy 125.97231 -283.814543) (xy 125.978559 -283.797628) (xy 125.97892 -283.788612) (xy 125.97892 -283.721556)
			(xy 125.978532 -283.712542) (xy 125.972306 -283.695625) (xy 125.966728 -283.688536) (xy 125.966474 -283.688536)
			(xy 125.966474 -283.688282) (xy 125.948856 -283.667333) (xy 125.919142 -283.621365) (xy 125.896302 -283.571621)
			(xy 125.880806 -283.519124) (xy 125.872972 -283.464952) (xy 125.872494 -283.437584) (xy 125.87298 -283.410333)
			(xy 125.880736 -283.356385) (xy 125.896091 -283.30409) (xy 125.918733 -283.254513) (xy 125.948199 -283.208663)
			(xy 125.98389 -283.167472) (xy 126.025081 -283.131781) (xy 126.070931 -283.102315) (xy 126.120508 -283.079673)
			(xy 126.172803 -283.064318) (xy 126.226751 -283.056562) (xy 126.281253 -283.056562) (xy 126.335201 -283.064318)
			(xy 126.387496 -283.079673) (xy 126.437073 -283.102315) (xy 126.482923 -283.131781) (xy 126.524114 -283.167472)
			(xy 126.559805 -283.208663) (xy 126.589271 -283.254513) (xy 126.611913 -283.30409) (xy 126.627268 -283.356385)
			(xy 126.635024 -283.410333) (xy 126.63551 -283.437584) (xy 126.635032 -283.464954) (xy 126.627217 -283.519132)
			(xy 126.61173 -283.571635) (xy 126.588891 -283.621382) (xy 126.55917 -283.66735) (xy 126.54153 -283.688282)
			(xy 126.541276 -283.688536) (xy 126.535707 -283.695635) (xy 126.529451 -283.712542) (xy 126.529084 -283.721556)
			(xy 126.529084 -283.788612) (xy 126.529439 -283.797629) (xy 126.535688 -283.814546) (xy 126.541276 -283.821632)
			(xy 126.54153 -283.821632) (xy 126.54153 -283.821886) (xy 126.559181 -283.842809) (xy 126.58889 -283.888785)
			(xy 126.611723 -283.938534) (xy 126.627211 -283.991037) (xy 126.635037 -284.045214) (xy 126.63551 -284.072584)
			(xy 126.635024 -284.099835) (xy 126.627268 -284.153783) (xy 126.611913 -284.206078) (xy 126.589271 -284.255655)
			(xy 126.559805 -284.301505) (xy 126.524114 -284.342696) (xy 126.482923 -284.378387) (xy 126.437073 -284.407853)
			(xy 126.387496 -284.430495) (xy 126.335201 -284.44585) (xy 126.281253 -284.453606) (xy 126.226751 -284.453606)
			(xy 126.172803 -284.44585) (xy 126.120508 -284.430495) (xy 126.070931 -284.407853) (xy 126.025081 -284.378387)
			(xy 125.98389 -284.342696) (xy 125.948199 -284.301505) (xy 125.918733 -284.255655) (xy 125.896091 -284.206078)
			(xy 125.880736 -284.153783) (xy 125.87298 -284.099835) (xy 125.872494 -284.072584) (xy 120.970926 -284.072584)
			(xy 120.97525 -284.085825) (xy 120.984715 -284.145328) (xy 120.98528 -284.175454) (xy 120.984794 -284.202705)
			(xy 120.977038 -284.256653) (xy 120.961683 -284.308948) (xy 120.939041 -284.358525) (xy 120.909575 -284.404375)
			(xy 120.873884 -284.445566) (xy 120.832693 -284.481257) (xy 120.786843 -284.510723) (xy 120.737266 -284.533365)
			(xy 120.684971 -284.54872) (xy 120.631023 -284.556476) (xy 120.576521 -284.556476) (xy 120.522573 -284.54872)
			(xy 120.470278 -284.533365) (xy 120.420701 -284.510723) (xy 120.374851 -284.481257) (xy 120.33366 -284.445566)
			(xy 120.297969 -284.404375) (xy 120.268503 -284.358525) (xy 120.245861 -284.308948) (xy 120.230506 -284.256653)
			(xy 120.22275 -284.202705) (xy 120.222264 -284.175454) (xy 120.222865 -284.145332) (xy 120.232338 -284.085837)
			(xy 120.251042 -284.028569) (xy 120.278511 -283.974951) (xy 120.314064 -283.926316) (xy 120.33504 -283.90469)
			(xy 120.341883 -283.897292) (xy 120.3496 -283.878691) (xy 120.350026 -283.868622) (xy 120.350026 -283.796486)
			(xy 120.349627 -283.786413) (xy 120.34189 -283.767815) (xy 120.33504 -283.760418) (xy 120.31405 -283.738802)
			(xy 120.278482 -283.690171) (xy 120.251003 -283.636553) (xy 120.232297 -283.57928) (xy 120.22283 -283.519779)
			(xy 120.222264 -283.489654) (xy 120.222837 -283.459815) (xy 120.232154 -283.400869) (xy 120.240806 -283.372306)
			(xy 120.244108 -283.361892) (xy 120.241822 -283.340302) (xy 120.19153 -283.25572) (xy 120.174258 -283.243274)
			(xy 120.163336 -283.241242) (xy 120.135485 -283.2354) (xy 120.081821 -283.216461) (xy 120.031564 -283.189765)
			(xy 119.985828 -283.155903) (xy 119.945626 -283.115625) (xy 119.91185 -283.069825) (xy 119.885249 -283.019517)
			(xy 119.866412 -282.965818) (xy 119.860568 -282.937966) (xy 119.858028 -282.92552) (xy 119.842788 -282.906216)
			(xy 119.741696 -282.862528) (xy 119.717058 -282.864306) (xy 119.70639 -282.871164) (xy 119.683423 -282.885207)
			(xy 119.634348 -282.907337) (xy 119.582645 -282.922332) (xy 119.529345 -282.929892) (xy 119.502428 -282.930346)
			(xy 119.484408 -282.93013) (xy 119.448534 -282.926693) (xy 119.4308 -282.923488) (xy 119.421148 -282.92171)
			(xy 119.402098 -282.925266) (xy 119.327168 -282.973272) (xy 119.315738 -282.98902) (xy 119.313452 -282.998418)
			(xy 119.306065 -283.025466) (xy 119.284437 -283.077194) (xy 119.255473 -283.125202) (xy 119.219797 -283.168455)
			(xy 119.178176 -283.206023) (xy 119.131506 -283.237097) (xy 119.080793 -283.261008) (xy 119.027126 -283.277242)
			(xy 118.971662 -283.285449) (xy 118.943628 -283.285946) (xy 118.916379 -283.285396) (xy 118.862436 -283.277644)
			(xy 118.810145 -283.262294) (xy 118.76057 -283.239659) (xy 118.714721 -283.2102) (xy 118.673532 -283.174515)
			(xy 118.63784 -283.133331) (xy 118.608372 -283.087488) (xy 118.585729 -283.037917) (xy 118.57037 -282.985629)
			(xy 118.562609 -282.931687) (xy 118.56212 -282.904438) (xy 113.843292 -282.904438) (xy 113.837059 -282.947793)
			(xy 113.821706 -283.000084) (xy 113.799067 -283.049658) (xy 113.769605 -283.095506) (xy 113.733917 -283.136695)
			(xy 113.692732 -283.172385) (xy 113.646886 -283.201852) (xy 113.597314 -283.224494) (xy 113.545024 -283.239852)
			(xy 113.491081 -283.247612) (xy 113.463832 -283.2481) (xy 113.436462 -283.247615) (xy 113.382284 -283.239802)
			(xy 113.329781 -283.224317) (xy 113.280034 -283.20148) (xy 113.234066 -283.171759) (xy 113.213134 -283.15412)
			(xy 113.21288 -283.153866) (xy 113.205806 -283.148261) (xy 113.188879 -283.142027) (xy 113.17986 -283.141674)
			(xy 113.112804 -283.141674) (xy 113.103788 -283.142039) (xy 113.086871 -283.148282) (xy 113.079784 -283.153866)
			(xy 113.079784 -283.15412) (xy 113.07953 -283.15412) (xy 113.0586 -283.171762) (xy 113.012626 -283.201472)
			(xy 112.962878 -283.224308) (xy 112.910377 -283.239798) (xy 112.856201 -283.247626) (xy 112.828832 -283.2481)
			(xy 112.801577 -283.247655) (xy 112.747622 -283.239901) (xy 112.695319 -283.224548) (xy 112.645734 -283.201907)
			(xy 112.599876 -283.172439) (xy 112.558678 -283.136745) (xy 112.52298 -283.09555) (xy 112.493509 -283.049695)
			(xy 112.470863 -283.000111) (xy 112.455505 -282.94781) (xy 112.447747 -282.893855) (xy 112.117605 -282.893855)
			(xy 112.117554 -282.89643) (xy 112.108246 -282.955376) (xy 112.099598 -282.98394) (xy 112.096296 -282.994354)
			(xy 112.098582 -283.015944) (xy 112.148874 -283.100526) (xy 112.166146 -283.112972) (xy 112.177068 -283.115004)
			(xy 112.202885 -283.120343) (xy 112.252801 -283.137311) (xy 112.299905 -283.160992) (xy 112.3433 -283.190933)
			(xy 112.382158 -283.226565) (xy 112.41574 -283.267207) (xy 112.443405 -283.312087) (xy 112.464627 -283.360349)
			(xy 112.479001 -283.411073) (xy 112.486253 -283.463293) (xy 112.486694 -283.489654) (xy 112.48611 -283.519777)
			(xy 112.476635 -283.579274) (xy 112.457928 -283.636542) (xy 112.430454 -283.690159) (xy 112.394897 -283.738793)
			(xy 112.373918 -283.760418) (xy 112.36708 -283.76782) (xy 112.359358 -283.786418) (xy 112.358932 -283.796486)
			(xy 112.358932 -283.868622) (xy 112.359338 -283.878694) (xy 112.367071 -283.897292) (xy 112.373918 -283.90469)
			(xy 112.394922 -283.926293) (xy 112.430486 -283.974928) (xy 112.457962 -284.02855) (xy 112.47234 -284.072584)
			(xy 117.373908 -284.072584) (xy 117.374363 -284.045213) (xy 117.382183 -283.991034) (xy 117.397675 -283.93853)
			(xy 117.420519 -283.888784) (xy 117.450246 -283.842817) (xy 117.467888 -283.821886) (xy 117.468142 -283.821632)
			(xy 117.473726 -283.814544) (xy 117.479973 -283.797628) (xy 117.480334 -283.788612) (xy 117.480334 -283.721556)
			(xy 117.479943 -283.712543) (xy 117.473718 -283.695626) (xy 117.468142 -283.688536) (xy 117.467888 -283.688536)
			(xy 117.467888 -283.688282) (xy 117.450272 -283.667331) (xy 117.420557 -283.621363) (xy 117.397717 -283.571621)
			(xy 117.38222 -283.519124) (xy 117.374386 -283.464952) (xy 117.373908 -283.437584) (xy 117.374394 -283.410333)
			(xy 117.38215 -283.356385) (xy 117.397505 -283.30409) (xy 117.420147 -283.254513) (xy 117.449613 -283.208663)
			(xy 117.485304 -283.167472) (xy 117.526495 -283.131781) (xy 117.572345 -283.102315) (xy 117.621922 -283.079673)
			(xy 117.674217 -283.064318) (xy 117.728165 -283.056562) (xy 117.782667 -283.056562) (xy 117.836615 -283.064318)
			(xy 117.88891 -283.079673) (xy 117.938487 -283.102315) (xy 117.984337 -283.131781) (xy 118.025528 -283.167472)
			(xy 118.061219 -283.208663) (xy 118.090685 -283.254513) (xy 118.113327 -283.30409) (xy 118.128682 -283.356385)
			(xy 118.136438 -283.410333) (xy 118.136924 -283.437584) (xy 118.136467 -283.464955) (xy 118.12865 -283.519135)
			(xy 118.11316 -283.571639) (xy 118.090315 -283.621386) (xy 118.060587 -283.667351) (xy 118.042944 -283.688282)
			(xy 118.04269 -283.688536) (xy 118.037123 -283.695636) (xy 118.030865 -283.712542) (xy 118.030498 -283.721556)
			(xy 118.030498 -283.788612) (xy 118.03085 -283.797629) (xy 118.037101 -283.814546) (xy 118.04269 -283.821632)
			(xy 118.042944 -283.821632) (xy 118.042944 -283.821886) (xy 118.060597 -283.842807) (xy 118.090306 -283.888783)
			(xy 118.113138 -283.938534) (xy 118.128626 -283.991037) (xy 118.136452 -284.045214) (xy 118.136924 -284.072584)
			(xy 118.136438 -284.099835) (xy 118.128682 -284.153783) (xy 118.113327 -284.206078) (xy 118.090685 -284.255655)
			(xy 118.061219 -284.301505) (xy 118.025528 -284.342696) (xy 117.984337 -284.378387) (xy 117.938487 -284.407853)
			(xy 117.88891 -284.430495) (xy 117.836615 -284.44585) (xy 117.782667 -284.453606) (xy 117.728165 -284.453606)
			(xy 117.674217 -284.44585) (xy 117.621922 -284.430495) (xy 117.572345 -284.407853) (xy 117.526495 -284.378387)
			(xy 117.485304 -284.342696) (xy 117.449613 -284.301505) (xy 117.420147 -284.255655) (xy 117.397505 -284.206078)
			(xy 117.38215 -284.153783) (xy 117.374394 -284.099835) (xy 117.373908 -284.072584) (xy 112.47234 -284.072584)
			(xy 112.476664 -284.085825) (xy 112.486129 -284.145328) (xy 112.486694 -284.175454) (xy 112.486208 -284.202705)
			(xy 112.478452 -284.256653) (xy 112.463097 -284.308948) (xy 112.440455 -284.358525) (xy 112.410989 -284.404375)
			(xy 112.375298 -284.445566) (xy 112.334107 -284.481257) (xy 112.288257 -284.510723) (xy 112.23868 -284.533365)
			(xy 112.186385 -284.54872) (xy 112.132437 -284.556476) (xy 112.077935 -284.556476) (xy 112.023987 -284.54872)
			(xy 111.971692 -284.533365) (xy 111.922115 -284.510723) (xy 111.876265 -284.481257) (xy 111.835074 -284.445566)
			(xy 111.799383 -284.404375) (xy 111.769917 -284.358525) (xy 111.747275 -284.308948) (xy 111.73192 -284.256653)
			(xy 111.724164 -284.202705) (xy 111.723678 -284.175454) (xy 111.724275 -284.145332) (xy 111.733748 -284.085836)
			(xy 111.752453 -284.028568) (xy 111.779923 -283.974951) (xy 111.815477 -283.926316) (xy 111.836454 -283.90469)
			(xy 111.843285 -283.897282) (xy 111.851011 -283.878689) (xy 111.85144 -283.868622) (xy 111.85144 -283.796486)
			(xy 111.851038 -283.786414) (xy 111.843303 -283.767815) (xy 111.836454 -283.760418) (xy 111.815467 -283.738799)
			(xy 111.779897 -283.69017) (xy 111.752417 -283.636552) (xy 111.733711 -283.57928) (xy 111.724244 -283.519779)
			(xy 111.723678 -283.489654) (xy 111.72425 -283.459815) (xy 111.733568 -283.400869) (xy 111.74222 -283.372306)
			(xy 111.745522 -283.361892) (xy 111.743236 -283.340302) (xy 111.692944 -283.25572) (xy 111.675672 -283.243274)
			(xy 111.66475 -283.241242) (xy 111.636901 -283.23539) (xy 111.583237 -283.216453) (xy 111.53298 -283.189759)
			(xy 111.487243 -283.155898) (xy 111.447041 -283.115622) (xy 111.413265 -283.069823) (xy 111.386664 -283.019516)
			(xy 111.367826 -282.965818) (xy 111.361982 -282.937966) (xy 111.359442 -282.92552) (xy 111.344202 -282.906216)
			(xy 111.24311 -282.862528) (xy 111.218472 -282.864306) (xy 111.207804 -282.871164) (xy 111.184833 -282.885201)
			(xy 111.13576 -282.907332) (xy 111.084058 -282.922329) (xy 111.030759 -282.929892) (xy 111.003842 -282.930346)
			(xy 110.985823 -282.930129) (xy 110.949948 -282.926692) (xy 110.932214 -282.923488) (xy 110.922562 -282.92171)
			(xy 110.903512 -282.925266) (xy 110.828582 -282.973272) (xy 110.817152 -282.98902) (xy 110.814866 -282.998418)
			(xy 110.807467 -283.025462) (xy 110.785839 -283.07719) (xy 110.756877 -283.125197) (xy 110.721202 -283.168449)
			(xy 110.679583 -283.206017) (xy 110.632915 -283.237092) (xy 110.582203 -283.261004) (xy 110.528538 -283.277239)
			(xy 110.473075 -283.285448) (xy 110.445042 -283.285946) (xy 110.417792 -283.285406) (xy 110.363846 -283.277655)
			(xy 110.311552 -283.262307) (xy 110.261974 -283.239672) (xy 110.216123 -283.210212) (xy 110.17493 -283.174526)
			(xy 110.139236 -283.133341) (xy 110.109767 -283.087496) (xy 110.087121 -283.037923) (xy 110.071762 -282.985633)
			(xy 110.064 -282.931688) (xy 110.063534 -282.904438) (xy 105.682792 -282.904438) (xy 105.676558 -282.947795)
			(xy 105.661205 -283.000087) (xy 105.638565 -283.049662) (xy 105.609102 -283.09551) (xy 105.573413 -283.136699)
			(xy 105.532226 -283.17239) (xy 105.486379 -283.201856) (xy 105.436805 -283.224498) (xy 105.384514 -283.239854)
			(xy 105.33057 -283.247613) (xy 105.30332 -283.2481) (xy 105.27595 -283.247622) (xy 105.221772 -283.239807)
			(xy 105.169269 -283.224321) (xy 105.119522 -283.201482) (xy 105.073554 -283.17176) (xy 105.052622 -283.15412)
			(xy 105.052368 -283.153866) (xy 105.045269 -283.148298) (xy 105.028362 -283.142041) (xy 105.019348 -283.141674)
			(xy 104.952292 -283.141674) (xy 104.943275 -283.142033) (xy 104.926359 -283.14828) (xy 104.919272 -283.153866)
			(xy 104.919272 -283.15412) (xy 104.919018 -283.15412) (xy 104.898093 -283.171767) (xy 104.852118 -283.201477)
			(xy 104.802368 -283.224311) (xy 104.749866 -283.2398) (xy 104.69569 -283.247627) (xy 104.66832 -283.2481)
			(xy 104.641066 -283.247654) (xy 104.587111 -283.239899) (xy 104.53481 -283.224545) (xy 104.485226 -283.201903)
			(xy 104.43937 -283.172435) (xy 104.398174 -283.13674) (xy 104.362477 -283.095546) (xy 104.333007 -283.049691)
			(xy 104.310362 -283.000109) (xy 104.295005 -282.947808) (xy 104.287247 -282.893854) (xy 103.957113 -282.893854)
			(xy 103.94936 -282.947788) (xy 103.934007 -283.000081) (xy 103.911368 -283.049657) (xy 103.881904 -283.095506)
			(xy 103.846216 -283.136696) (xy 103.805029 -283.172388) (xy 103.759181 -283.201855) (xy 103.709607 -283.224497)
			(xy 103.657315 -283.239854) (xy 103.60337 -283.247613) (xy 103.57612 -283.2481) (xy 103.549739 -283.247582)
			(xy 103.497478 -283.240334) (xy 103.446716 -283.225947) (xy 103.398425 -283.204695) (xy 103.353526 -283.176985)
			(xy 103.312879 -283.143347) (xy 103.27726 -283.104423) (xy 103.247351 -283.060959) (xy 103.223723 -283.013784)
			(xy 103.206829 -282.9638) (xy 103.20147 -282.937966) (xy 103.19893 -282.92552) (xy 103.18369 -282.906216)
			(xy 103.082598 -282.862528) (xy 103.05796 -282.864306) (xy 103.047292 -282.871164) (xy 103.024324 -282.885206)
			(xy 102.97525 -282.907336) (xy 102.923547 -282.922331) (xy 102.870247 -282.929892) (xy 102.84333 -282.930346)
			(xy 102.825311 -282.93013) (xy 102.789436 -282.926693) (xy 102.771702 -282.923488) (xy 102.76205 -282.92171)
			(xy 102.743 -282.925266) (xy 102.66807 -282.973272) (xy 102.65664 -282.98902) (xy 102.654354 -282.998418)
			(xy 102.646966 -283.025465) (xy 102.625337 -283.077194) (xy 102.596373 -283.125201) (xy 102.560697 -283.168454)
			(xy 102.519077 -283.206022) (xy 102.472407 -283.237096) (xy 102.421694 -283.261007) (xy 102.368028 -283.277242)
			(xy 102.312564 -283.285449) (xy 102.28453 -283.285946) (xy 102.257281 -283.285394) (xy 102.203338 -283.277643)
			(xy 102.151047 -283.262293) (xy 102.101472 -283.239658) (xy 102.055624 -283.210199) (xy 102.014434 -283.174514)
			(xy 101.978742 -283.133331) (xy 101.949274 -283.087487) (xy 101.926631 -283.037917) (xy 101.911272 -282.985629)
			(xy 101.903511 -282.931687) (xy 101.903022 -282.904438) (xy 98.74377 -282.904438) (xy 98.74377 -284.175454)
			(xy 103.562656 -284.175454) (xy 103.566727 -284.119832) (xy 103.578853 -284.065395) (xy 103.598776 -284.013304)
			(xy 103.626072 -283.964669) (xy 103.660158 -283.920526) (xy 103.700307 -283.881817) (xy 103.745665 -283.849366)
			(xy 103.795265 -283.823865) (xy 103.848049 -283.805858) (xy 103.902892 -283.795728) (xy 103.958626 -283.793691)
			(xy 104.014063 -283.799791) (xy 104.06802 -283.813897) (xy 104.119349 -283.835709) (xy 104.166955 -283.864763)
			(xy 104.209823 -283.900438) (xy 104.24704 -283.941975) (xy 104.277813 -283.988488) (xy 104.301485 -284.038985)
			(xy 104.311594 -284.072584) (xy 109.213396 -284.072584) (xy 109.213854 -284.045213) (xy 109.221674 -283.991034)
			(xy 109.237165 -283.938531) (xy 109.260008 -283.888784) (xy 109.289734 -283.842818) (xy 109.307376 -283.821886)
			(xy 109.30763 -283.821632) (xy 109.313213 -283.814543) (xy 109.319461 -283.797628) (xy 109.319822 -283.788612)
			(xy 109.319822 -283.721556) (xy 109.319434 -283.712542) (xy 109.313207 -283.695625) (xy 109.30763 -283.688536)
			(xy 109.307376 -283.688536) (xy 109.307376 -283.688282) (xy 109.289758 -283.667333) (xy 109.260044 -283.621364)
			(xy 109.237204 -283.571621) (xy 109.221708 -283.519124) (xy 109.213874 -283.464952) (xy 109.213396 -283.437584)
			(xy 109.213882 -283.410333) (xy 109.221638 -283.356385) (xy 109.236993 -283.30409) (xy 109.259635 -283.254513)
			(xy 109.289101 -283.208663) (xy 109.324792 -283.167472) (xy 109.365983 -283.131781) (xy 109.411833 -283.102315)
			(xy 109.46141 -283.079673) (xy 109.513705 -283.064318) (xy 109.567653 -283.056562) (xy 109.622155 -283.056562)
			(xy 109.676103 -283.064318) (xy 109.728398 -283.079673) (xy 109.777975 -283.102315) (xy 109.823825 -283.131781)
			(xy 109.865016 -283.167472) (xy 109.900707 -283.208663) (xy 109.930173 -283.254513) (xy 109.952815 -283.30409)
			(xy 109.96817 -283.356385) (xy 109.975926 -283.410333) (xy 109.976412 -283.437584) (xy 109.975934 -283.464954)
			(xy 109.968118 -283.519132) (xy 109.952632 -283.571635) (xy 109.929793 -283.621382) (xy 109.900072 -283.66735)
			(xy 109.882432 -283.688282) (xy 109.882178 -283.688536) (xy 109.87661 -283.695635) (xy 109.870353 -283.712542)
			(xy 109.869986 -283.721556) (xy 109.869986 -283.788612) (xy 109.87034 -283.797629) (xy 109.87659 -283.814546)
			(xy 109.882178 -283.821632) (xy 109.882432 -283.821632) (xy 109.882432 -283.821886) (xy 109.900083 -283.842808)
			(xy 109.929792 -283.888784) (xy 109.952625 -283.938534) (xy 109.968113 -283.991037) (xy 109.975939 -284.045214)
			(xy 109.976412 -284.072584) (xy 109.975926 -284.099835) (xy 109.96817 -284.153783) (xy 109.952815 -284.206078)
			(xy 109.930173 -284.255655) (xy 109.900707 -284.301505) (xy 109.865016 -284.342696) (xy 109.823825 -284.378387)
			(xy 109.777975 -284.407853) (xy 109.728398 -284.430495) (xy 109.676103 -284.44585) (xy 109.622155 -284.453606)
			(xy 109.567653 -284.453606) (xy 109.513705 -284.44585) (xy 109.46141 -284.430495) (xy 109.411833 -284.407853)
			(xy 109.365983 -284.378387) (xy 109.324792 -284.342696) (xy 109.289101 -284.301505) (xy 109.259635 -284.255655)
			(xy 109.236993 -284.206078) (xy 109.221638 -284.153783) (xy 109.213882 -284.099835) (xy 109.213396 -284.072584)
			(xy 104.311594 -284.072584) (xy 104.317553 -284.092392) (xy 104.325673 -284.147568) (xy 104.326182 -284.175454)
			(xy 104.325673 -284.20334) (xy 104.317553 -284.258516) (xy 104.301485 -284.311923) (xy 104.277813 -284.36242)
			(xy 104.24704 -284.408933) (xy 104.209823 -284.45047) (xy 104.166955 -284.486145) (xy 104.119349 -284.515199)
			(xy 104.06802 -284.537011) (xy 104.014063 -284.551117) (xy 103.958626 -284.557217) (xy 103.902892 -284.55518)
			(xy 103.848049 -284.54505) (xy 103.795265 -284.527043) (xy 103.745665 -284.501542) (xy 103.700307 -284.469091)
			(xy 103.660158 -284.430382) (xy 103.626072 -284.386239) (xy 103.598776 -284.337604) (xy 103.578853 -284.285513)
			(xy 103.566727 -284.231076) (xy 103.562656 -284.175454) (xy 98.74377 -284.175454) (xy 98.74377 -286.35325)
			(xy 98.744262 -286.363064) (xy 98.751694 -286.381236) (xy 98.758248 -286.388556) (xy 98.815652 -286.441388)
			(xy 98.819576 -286.444841) (xy 98.82854 -286.450213) (xy 98.833432 -286.452056) (xy 98.843338 -286.455358)
			(xy 98.85426 -286.454342) (xy 98.928023 -286.448266) (xy 99.075904 -286.441786) (xy 99.149916 -286.441388)
			(xy 99.150932 -286.441388) (xy 99.233846 -286.441922) (xy 99.399472 -286.450107) (xy 99.564497 -286.466409)
			(xy 99.728523 -286.490786) (xy 99.891156 -286.523181) (xy 100.052004 -286.563515) (xy 100.21068 -286.611692)
			(xy 100.366801 -286.667595) (xy 100.519992 -286.73109) (xy 100.643141 -286.789368) (xy 108.672374 -286.789368)
			(xy 108.676445 -286.733746) (xy 108.688571 -286.679309) (xy 108.708494 -286.627218) (xy 108.73579 -286.578583)
			(xy 108.769876 -286.53444) (xy 108.810025 -286.495731) (xy 108.855383 -286.46328) (xy 108.904983 -286.437779)
			(xy 108.957767 -286.419772) (xy 109.01261 -286.409642) (xy 109.068344 -286.407605) (xy 109.123781 -286.413705)
			(xy 109.177738 -286.427811) (xy 109.229067 -286.449623) (xy 109.276673 -286.478677) (xy 109.319541 -286.514352)
			(xy 109.356758 -286.555889) (xy 109.387531 -286.602402) (xy 109.411203 -286.652899) (xy 109.427271 -286.706306)
			(xy 109.429365 -286.720534) (xy 109.558834 -286.720534) (xy 109.562905 -286.664912) (xy 109.575031 -286.610475)
			(xy 109.594954 -286.558384) (xy 109.62225 -286.509749) (xy 109.656336 -286.465606) (xy 109.696485 -286.426897)
			(xy 109.741843 -286.394446) (xy 109.791443 -286.368945) (xy 109.844227 -286.350938) (xy 109.89907 -286.340808)
			(xy 109.954804 -286.338771) (xy 110.010241 -286.344871) (xy 110.064198 -286.358977) (xy 110.115527 -286.380789)
			(xy 110.163133 -286.409843) (xy 110.206001 -286.445518) (xy 110.243218 -286.487055) (xy 110.273991 -286.533568)
			(xy 110.297663 -286.584065) (xy 110.313731 -286.637472) (xy 110.321851 -286.692648) (xy 110.32236 -286.720534)
			(xy 110.321851 -286.74842) (xy 110.31575 -286.789876) (xy 125.407926 -286.789876) (xy 125.411997 -286.734254)
			(xy 125.424123 -286.679817) (xy 125.444046 -286.627726) (xy 125.471342 -286.579091) (xy 125.505428 -286.534948)
			(xy 125.545577 -286.496239) (xy 125.590935 -286.463788) (xy 125.640535 -286.438287) (xy 125.693319 -286.42028)
			(xy 125.748162 -286.41015) (xy 125.803896 -286.408113) (xy 125.859333 -286.414213) (xy 125.91329 -286.428319)
			(xy 125.964619 -286.450131) (xy 126.012225 -286.479185) (xy 126.055093 -286.51486) (xy 126.09231 -286.556397)
			(xy 126.123083 -286.60291) (xy 126.146755 -286.653407) (xy 126.162213 -286.704786) (xy 126.29464 -286.704786)
			(xy 126.298711 -286.649164) (xy 126.310837 -286.594727) (xy 126.33076 -286.542636) (xy 126.358056 -286.494001)
			(xy 126.392142 -286.449858) (xy 126.432291 -286.411149) (xy 126.477649 -286.378698) (xy 126.527249 -286.353197)
			(xy 126.580033 -286.33519) (xy 126.634876 -286.32506) (xy 126.69061 -286.323023) (xy 126.746047 -286.329123)
			(xy 126.800004 -286.343229) (xy 126.851333 -286.365041) (xy 126.898939 -286.394095) (xy 126.941807 -286.42977)
			(xy 126.979024 -286.471307) (xy 127.009797 -286.51782) (xy 127.033469 -286.568317) (xy 127.049537 -286.621724)
			(xy 127.057657 -286.6769) (xy 127.058166 -286.704786) (xy 127.057657 -286.732672) (xy 127.049537 -286.787848)
			(xy 127.033469 -286.841255) (xy 127.009797 -286.891752) (xy 126.979024 -286.938265) (xy 126.941807 -286.979802)
			(xy 126.898939 -287.015477) (xy 126.851333 -287.044531) (xy 126.800004 -287.066343) (xy 126.746047 -287.080449)
			(xy 126.69061 -287.086549) (xy 126.634876 -287.084512) (xy 126.580033 -287.074382) (xy 126.527249 -287.056375)
			(xy 126.477649 -287.030874) (xy 126.432291 -286.998423) (xy 126.392142 -286.959714) (xy 126.358056 -286.915571)
			(xy 126.33076 -286.866936) (xy 126.310837 -286.814845) (xy 126.298711 -286.760408) (xy 126.29464 -286.704786)
			(xy 126.162213 -286.704786) (xy 126.162823 -286.706814) (xy 126.170943 -286.76199) (xy 126.171452 -286.789876)
			(xy 126.170943 -286.817762) (xy 126.162823 -286.872938) (xy 126.146755 -286.926345) (xy 126.123083 -286.976842)
			(xy 126.09231 -287.023355) (xy 126.055093 -287.064892) (xy 126.012225 -287.100567) (xy 125.964619 -287.129621)
			(xy 125.91329 -287.151433) (xy 125.859333 -287.165539) (xy 125.803896 -287.171639) (xy 125.748162 -287.169602)
			(xy 125.693319 -287.159472) (xy 125.640535 -287.141465) (xy 125.590935 -287.115964) (xy 125.545577 -287.083513)
			(xy 125.505428 -287.044804) (xy 125.471342 -287.000661) (xy 125.444046 -286.952026) (xy 125.424123 -286.899935)
			(xy 125.411997 -286.845498) (xy 125.407926 -286.789876) (xy 110.31575 -286.789876) (xy 110.313731 -286.803596)
			(xy 110.297663 -286.857003) (xy 110.273991 -286.9075) (xy 110.243218 -286.954013) (xy 110.206001 -286.99555)
			(xy 110.163133 -287.031225) (xy 110.115527 -287.060279) (xy 110.064198 -287.082091) (xy 110.010241 -287.096197)
			(xy 109.954804 -287.102297) (xy 109.89907 -287.10026) (xy 109.844227 -287.09013) (xy 109.791443 -287.072123)
			(xy 109.741843 -287.046622) (xy 109.696485 -287.014171) (xy 109.656336 -286.975462) (xy 109.62225 -286.931319)
			(xy 109.594954 -286.882684) (xy 109.575031 -286.830593) (xy 109.562905 -286.776156) (xy 109.558834 -286.720534)
			(xy 109.429365 -286.720534) (xy 109.435391 -286.761482) (xy 109.4359 -286.789368) (xy 109.435391 -286.817254)
			(xy 109.427271 -286.87243) (xy 109.411203 -286.925837) (xy 109.387531 -286.976334) (xy 109.356758 -287.022847)
			(xy 109.319541 -287.064384) (xy 109.276673 -287.100059) (xy 109.229067 -287.129113) (xy 109.177738 -287.150925)
			(xy 109.123781 -287.165031) (xy 109.068344 -287.171131) (xy 109.01261 -287.169094) (xy 108.957767 -287.158964)
			(xy 108.904983 -287.140957) (xy 108.855383 -287.115456) (xy 108.810025 -287.083005) (xy 108.769876 -287.044296)
			(xy 108.73579 -287.000153) (xy 108.708494 -286.951518) (xy 108.688571 -286.899427) (xy 108.676445 -286.84499)
			(xy 108.672374 -286.789368) (xy 100.643141 -286.789368) (xy 100.669883 -286.802023) (xy 100.816114 -286.880225)
			(xy 100.958333 -286.965506) (xy 101.096196 -287.057661) (xy 101.229373 -287.156469) (xy 101.357542 -287.261691)
			(xy 101.480394 -287.373075) (xy 101.597634 -287.490351) (xy 101.70898 -287.613237) (xy 101.814163 -287.741438)
			(xy 101.912931 -287.874644) (xy 102.005044 -288.012536) (xy 102.090282 -288.15478) (xy 102.168439 -288.301035)
			(xy 102.239327 -288.450948) (xy 102.302775 -288.604158) (xy 102.35863 -288.760296) (xy 102.406759 -288.918986)
			(xy 102.447044 -289.079847) (xy 102.47939 -289.24249) (xy 102.503717 -289.406524) (xy 102.519968 -289.571554)
			(xy 102.528104 -289.737182) (xy 102.528624 -289.820096) (xy 102.528115 -289.903026) (xy 102.519977 -290.068687)
			(xy 102.50372 -290.233749) (xy 102.479384 -290.397815) (xy 102.447026 -290.560489) (xy 102.406726 -290.721379)
			(xy 102.358579 -290.880098) (xy 102.302703 -291.036263) (xy 102.239231 -291.189498) (xy 102.168316 -291.339435)
			(xy 102.090131 -291.485711) (xy 102.004861 -291.627975) (xy 101.912715 -291.765883) (xy 101.813912 -291.899104)
			(xy 101.708691 -292.027316) (xy 101.597306 -292.150211) (xy 101.480026 -292.267493) (xy 101.357131 -292.378878)
			(xy 101.22892 -292.4841) (xy 101.095699 -292.582903) (xy 100.957791 -292.675051) (xy 100.815528 -292.760321)
			(xy 100.669253 -292.838507) (xy 100.519317 -292.909423) (xy 100.366081 -292.972895) (xy 100.209917 -293.028773)
			(xy 100.051198 -293.07692) (xy 99.890308 -293.117222) (xy 99.727635 -293.14958) (xy 99.563569 -293.173918)
			(xy 99.398507 -293.190176) (xy 99.232846 -293.198315) (xy 99.149916 -293.198804) (xy 99.149662 -293.198804)
			(xy 99.075714 -293.198396) (xy 98.92796 -293.191916) (xy 98.85426 -293.18585) (xy 98.843338 -293.184834)
			(xy 98.833432 -293.188136) (xy 98.828544 -293.189984) (xy 98.819588 -293.195365) (xy 98.815652 -293.198804)
			(xy 98.76028 -293.249604) (xy 98.752841 -293.2571) (xy 98.744317 -293.276395) (xy 98.74377 -293.286942)
			(xy 98.74377 -294.199564) (xy 110.64951 -294.199564) (xy 110.653581 -294.143942) (xy 110.665707 -294.089505)
			(xy 110.68563 -294.037414) (xy 110.712926 -293.988779) (xy 110.747012 -293.944636) (xy 110.787161 -293.905927)
			(xy 110.832519 -293.873476) (xy 110.882119 -293.847975) (xy 110.934903 -293.829968) (xy 110.989746 -293.819838)
			(xy 111.04548 -293.817801) (xy 111.100917 -293.823901) (xy 111.154874 -293.838007) (xy 111.206203 -293.859819)
			(xy 111.253809 -293.888873) (xy 111.296677 -293.924548) (xy 111.333894 -293.966085) (xy 111.364667 -294.012598)
			(xy 111.388339 -294.063095) (xy 111.404407 -294.116502) (xy 111.412527 -294.171678) (xy 111.41273 -294.1828)
			(xy 127.26873 -294.1828) (xy 127.272801 -294.127178) (xy 127.284927 -294.072741) (xy 127.30485 -294.02065)
			(xy 127.332146 -293.972015) (xy 127.366232 -293.927872) (xy 127.406381 -293.889163) (xy 127.451739 -293.856712)
			(xy 127.501339 -293.831211) (xy 127.554123 -293.813204) (xy 127.608966 -293.803074) (xy 127.6647 -293.801037)
			(xy 127.720137 -293.807137) (xy 127.774094 -293.821243) (xy 127.825423 -293.843055) (xy 127.873029 -293.872109)
			(xy 127.915897 -293.907784) (xy 127.953114 -293.949321) (xy 127.983887 -293.995834) (xy 128.007559 -294.046331)
			(xy 128.023627 -294.099738) (xy 128.031747 -294.154914) (xy 128.032256 -294.1828) (xy 128.031747 -294.210686)
			(xy 128.023627 -294.265862) (xy 128.007559 -294.319269) (xy 127.983887 -294.369766) (xy 127.953114 -294.416279)
			(xy 127.915897 -294.457816) (xy 127.873029 -294.493491) (xy 127.825423 -294.522545) (xy 127.774094 -294.544357)
			(xy 127.720137 -294.558463) (xy 127.6647 -294.564563) (xy 127.608966 -294.562526) (xy 127.554123 -294.552396)
			(xy 127.501339 -294.534389) (xy 127.451739 -294.508888) (xy 127.406381 -294.476437) (xy 127.366232 -294.437728)
			(xy 127.332146 -294.393585) (xy 127.30485 -294.34495) (xy 127.284927 -294.292859) (xy 127.272801 -294.238422)
			(xy 127.26873 -294.1828) (xy 111.41273 -294.1828) (xy 111.413036 -294.199564) (xy 111.412527 -294.22745)
			(xy 111.404407 -294.282626) (xy 111.388339 -294.336033) (xy 111.364667 -294.38653) (xy 111.333894 -294.433043)
			(xy 111.296677 -294.47458) (xy 111.253809 -294.510255) (xy 111.206203 -294.539309) (xy 111.154874 -294.561121)
			(xy 111.100917 -294.575227) (xy 111.04548 -294.581327) (xy 110.989746 -294.57929) (xy 110.934903 -294.56916)
			(xy 110.882119 -294.551153) (xy 110.832519 -294.525652) (xy 110.787161 -294.493201) (xy 110.747012 -294.454492)
			(xy 110.712926 -294.410349) (xy 110.68563 -294.361714) (xy 110.665707 -294.309623) (xy 110.653581 -294.255186)
			(xy 110.64951 -294.199564) (xy 98.74377 -294.199564) (xy 98.74377 -294.851836) (xy 102.046784 -294.851836)
			(xy 102.050855 -294.796214) (xy 102.062981 -294.741777) (xy 102.082904 -294.689686) (xy 102.1102 -294.641051)
			(xy 102.144286 -294.596908) (xy 102.184435 -294.558199) (xy 102.229793 -294.525748) (xy 102.279393 -294.500247)
			(xy 102.332177 -294.48224) (xy 102.38702 -294.47211) (xy 102.442754 -294.470073) (xy 102.498191 -294.476173)
			(xy 102.552148 -294.490279) (xy 102.603477 -294.512091) (xy 102.651083 -294.541145) (xy 102.693951 -294.57682)
			(xy 102.731168 -294.618357) (xy 102.761941 -294.66487) (xy 102.785613 -294.715367) (xy 102.801681 -294.768774)
			(xy 102.809801 -294.82395) (xy 102.81031 -294.851836) (xy 117.14048 -294.851836) (xy 117.144551 -294.796214)
			(xy 117.156677 -294.741777) (xy 117.1766 -294.689686) (xy 117.203896 -294.641051) (xy 117.237982 -294.596908)
			(xy 117.278131 -294.558199) (xy 117.323489 -294.525748) (xy 117.373089 -294.500247) (xy 117.425873 -294.48224)
			(xy 117.480716 -294.47211) (xy 117.53645 -294.470073) (xy 117.591887 -294.476173) (xy 117.645844 -294.490279)
			(xy 117.697173 -294.512091) (xy 117.744779 -294.541145) (xy 117.787647 -294.57682) (xy 117.824864 -294.618357)
			(xy 117.855637 -294.66487) (xy 117.879309 -294.715367) (xy 117.895377 -294.768774) (xy 117.903497 -294.82395)
			(xy 117.904006 -294.851836) (xy 118.705882 -294.851836) (xy 118.709953 -294.796214) (xy 118.722079 -294.741777)
			(xy 118.742002 -294.689686) (xy 118.769298 -294.641051) (xy 118.803384 -294.596908) (xy 118.843533 -294.558199)
			(xy 118.888891 -294.525748) (xy 118.938491 -294.500247) (xy 118.991275 -294.48224) (xy 119.046118 -294.47211)
			(xy 119.101852 -294.470073) (xy 119.157289 -294.476173) (xy 119.211246 -294.490279) (xy 119.262575 -294.512091)
			(xy 119.310181 -294.541145) (xy 119.353049 -294.57682) (xy 119.390266 -294.618357) (xy 119.421039 -294.66487)
			(xy 119.444711 -294.715367) (xy 119.460779 -294.768774) (xy 119.468899 -294.82395) (xy 119.469408 -294.851836)
			(xy 133.799578 -294.851836) (xy 133.803649 -294.796214) (xy 133.815775 -294.741777) (xy 133.835698 -294.689686)
			(xy 133.862994 -294.641051) (xy 133.89708 -294.596908) (xy 133.937229 -294.558199) (xy 133.982587 -294.525748)
			(xy 134.032187 -294.500247) (xy 134.084971 -294.48224) (xy 134.139814 -294.47211) (xy 134.195548 -294.470073)
			(xy 134.250985 -294.476173) (xy 134.304942 -294.490279) (xy 134.356271 -294.512091) (xy 134.403877 -294.541145)
			(xy 134.446745 -294.57682) (xy 134.483962 -294.618357) (xy 134.514735 -294.66487) (xy 134.538407 -294.715367)
			(xy 134.554475 -294.768774) (xy 134.562595 -294.82395) (xy 134.563104 -294.851836) (xy 134.562595 -294.879722)
			(xy 134.554475 -294.934898) (xy 134.538407 -294.988305) (xy 134.514735 -295.038802) (xy 134.483962 -295.085315)
			(xy 134.446745 -295.126852) (xy 134.403877 -295.162527) (xy 134.356271 -295.191581) (xy 134.304942 -295.213393)
			(xy 134.250985 -295.227499) (xy 134.195548 -295.233599) (xy 134.139814 -295.231562) (xy 134.084971 -295.221432)
			(xy 134.032187 -295.203425) (xy 133.982587 -295.177924) (xy 133.937229 -295.145473) (xy 133.89708 -295.106764)
			(xy 133.862994 -295.062621) (xy 133.835698 -295.013986) (xy 133.815775 -294.961895) (xy 133.803649 -294.907458)
			(xy 133.799578 -294.851836) (xy 119.469408 -294.851836) (xy 119.468899 -294.879722) (xy 119.460779 -294.934898)
			(xy 119.444711 -294.988305) (xy 119.421039 -295.038802) (xy 119.390266 -295.085315) (xy 119.353049 -295.126852)
			(xy 119.310181 -295.162527) (xy 119.262575 -295.191581) (xy 119.211246 -295.213393) (xy 119.157289 -295.227499)
			(xy 119.101852 -295.233599) (xy 119.046118 -295.231562) (xy 118.991275 -295.221432) (xy 118.938491 -295.203425)
			(xy 118.888891 -295.177924) (xy 118.843533 -295.145473) (xy 118.803384 -295.106764) (xy 118.769298 -295.062621)
			(xy 118.742002 -295.013986) (xy 118.722079 -294.961895) (xy 118.709953 -294.907458) (xy 118.705882 -294.851836)
			(xy 117.904006 -294.851836) (xy 117.903497 -294.879722) (xy 117.895377 -294.934898) (xy 117.879309 -294.988305)
			(xy 117.855637 -295.038802) (xy 117.824864 -295.085315) (xy 117.787647 -295.126852) (xy 117.744779 -295.162527)
			(xy 117.697173 -295.191581) (xy 117.645844 -295.213393) (xy 117.591887 -295.227499) (xy 117.53645 -295.233599)
			(xy 117.480716 -295.231562) (xy 117.425873 -295.221432) (xy 117.373089 -295.203425) (xy 117.323489 -295.177924)
			(xy 117.278131 -295.145473) (xy 117.237982 -295.106764) (xy 117.203896 -295.062621) (xy 117.1766 -295.013986)
			(xy 117.156677 -294.961895) (xy 117.144551 -294.907458) (xy 117.14048 -294.851836) (xy 102.81031 -294.851836)
			(xy 102.809801 -294.879722) (xy 102.801681 -294.934898) (xy 102.785613 -294.988305) (xy 102.761941 -295.038802)
			(xy 102.731168 -295.085315) (xy 102.693951 -295.126852) (xy 102.651083 -295.162527) (xy 102.603477 -295.191581)
			(xy 102.552148 -295.213393) (xy 102.498191 -295.227499) (xy 102.442754 -295.233599) (xy 102.38702 -295.231562)
			(xy 102.332177 -295.221432) (xy 102.279393 -295.203425) (xy 102.229793 -295.177924) (xy 102.184435 -295.145473)
			(xy 102.144286 -295.106764) (xy 102.1102 -295.062621) (xy 102.082904 -295.013986) (xy 102.062981 -294.961895)
			(xy 102.050855 -294.907458) (xy 102.046784 -294.851836) (xy 98.74377 -294.851836) (xy 98.74377 -298.420536)
			(xy 103.494586 -298.420536) (xy 103.495077 -298.393167) (xy 103.502889 -298.338989) (xy 103.518373 -298.286486)
			(xy 103.541209 -298.236739) (xy 103.570928 -298.190771) (xy 103.588566 -298.169838) (xy 103.58882 -298.169584)
			(xy 103.594422 -298.162508) (xy 103.600659 -298.145583) (xy 103.601012 -298.136564) (xy 103.601012 -298.069508)
			(xy 103.600649 -298.060492) (xy 103.594405 -298.043575) (xy 103.58882 -298.036488) (xy 103.588566 -298.036488)
			(xy 103.588566 -298.036234) (xy 103.570959 -298.015273) (xy 103.54123 -297.969311) (xy 103.51838 -297.91957)
			(xy 103.502879 -297.867072) (xy 103.495046 -297.812896) (xy 103.495042 -297.758158) (xy 103.502868 -297.703981)
			(xy 103.518361 -297.651481) (xy 103.541204 -297.601736) (xy 103.570926 -297.55577) (xy 103.588566 -297.534838)
			(xy 103.58882 -297.534584) (xy 103.594422 -297.527508) (xy 103.600659 -297.510583) (xy 103.601012 -297.501564)
			(xy 103.601012 -297.434508) (xy 103.600649 -297.425492) (xy 103.594405 -297.408575) (xy 103.58882 -297.401488)
			(xy 103.588566 -297.401488) (xy 103.588566 -297.401234) (xy 103.570959 -297.380273) (xy 103.54123 -297.334311)
			(xy 103.51838 -297.28457) (xy 103.502879 -297.232072) (xy 103.495046 -297.177896) (xy 103.495042 -297.123158)
			(xy 103.502868 -297.068981) (xy 103.518361 -297.016481) (xy 103.541204 -296.966736) (xy 103.570926 -296.92077)
			(xy 103.588566 -296.899838) (xy 103.58882 -296.899584) (xy 103.594422 -296.892508) (xy 103.600659 -296.875583)
			(xy 103.601012 -296.866564) (xy 103.601012 -296.799508) (xy 103.600649 -296.790492) (xy 103.594405 -296.773575)
			(xy 103.58882 -296.766488) (xy 103.588566 -296.766488) (xy 103.588566 -296.766234) (xy 103.570959 -296.745273)
			(xy 103.54123 -296.699311) (xy 103.51838 -296.64957) (xy 103.502879 -296.597072) (xy 103.495046 -296.542896)
			(xy 103.495042 -296.488158) (xy 103.502868 -296.433981) (xy 103.518361 -296.381481) (xy 103.541204 -296.331736)
			(xy 103.570926 -296.28577) (xy 103.588566 -296.264838) (xy 103.58882 -296.264584) (xy 103.594422 -296.257508)
			(xy 103.600659 -296.240583) (xy 103.601012 -296.231564) (xy 103.601012 -296.164508) (xy 103.600649 -296.155492)
			(xy 103.594405 -296.138575) (xy 103.58882 -296.131488) (xy 103.588566 -296.131488) (xy 103.588566 -296.131234)
			(xy 103.570959 -296.110273) (xy 103.54123 -296.064311) (xy 103.51838 -296.01457) (xy 103.502879 -295.962072)
			(xy 103.495046 -295.907896) (xy 103.495042 -295.853158) (xy 103.502868 -295.798981) (xy 103.518361 -295.746481)
			(xy 103.541204 -295.696736) (xy 103.570926 -295.65077) (xy 103.588566 -295.629838) (xy 103.58882 -295.629584)
			(xy 103.594422 -295.622508) (xy 103.600659 -295.605583) (xy 103.601012 -295.596564) (xy 103.601012 -295.529508)
			(xy 103.600649 -295.520492) (xy 103.594405 -295.503575) (xy 103.58882 -295.496488) (xy 103.588566 -295.496488)
			(xy 103.588566 -295.496234) (xy 103.570924 -295.475304) (xy 103.541214 -295.42933) (xy 103.518379 -295.379582)
			(xy 103.502888 -295.327081) (xy 103.49506 -295.272905) (xy 103.494586 -295.245536) (xy 103.495089 -295.218284)
			(xy 103.502841 -295.164335) (xy 103.518192 -295.112038) (xy 103.54083 -295.062459) (xy 103.570293 -295.016606)
			(xy 103.605983 -294.975413) (xy 103.647172 -294.939719) (xy 103.693022 -294.91025) (xy 103.742599 -294.887607)
			(xy 103.794894 -294.87225) (xy 103.848842 -294.864492) (xy 103.876094 -294.864028) (xy 103.903464 -294.864491)
			(xy 103.957644 -294.872308) (xy 104.010147 -294.887798) (xy 104.059894 -294.91064) (xy 104.105861 -294.940366)
			(xy 104.126792 -294.958008) (xy 104.127046 -294.958262) (xy 104.134139 -294.963839) (xy 104.151051 -294.97009)
			(xy 104.160066 -294.970454) (xy 104.227122 -294.970454) (xy 104.236141 -294.970118) (xy 104.253059 -294.963857)
			(xy 104.260142 -294.958262) (xy 104.260142 -294.958008) (xy 104.260396 -294.958008) (xy 104.28132 -294.940359)
			(xy 104.327295 -294.910648) (xy 104.377044 -294.887814) (xy 104.429547 -294.872325) (xy 104.483724 -294.8645)
			(xy 104.511094 -294.864028) (xy 104.538348 -294.864461) (xy 104.592302 -294.872218) (xy 104.644603 -294.887575)
			(xy 104.694185 -294.91022) (xy 104.74004 -294.93969) (xy 104.781234 -294.975387) (xy 104.816928 -295.016584)
			(xy 104.846395 -295.062441) (xy 104.869035 -295.112025) (xy 104.884388 -295.164327) (xy 104.892141 -295.218282)
			(xy 104.892602 -295.245536) (xy 104.892157 -295.272907) (xy 104.884334 -295.327087) (xy 104.86884 -295.37959)
			(xy 104.845993 -295.429337) (xy 104.816265 -295.475303) (xy 104.798622 -295.496234) (xy 104.798368 -295.496488)
			(xy 104.792777 -295.503571) (xy 104.786534 -295.520491) (xy 104.786176 -295.529508) (xy 104.786176 -295.596564)
			(xy 104.786555 -295.605578) (xy 104.792788 -295.622495) (xy 104.798368 -295.629584) (xy 104.798622 -295.629584)
			(xy 104.798622 -295.629838) (xy 104.816296 -295.650743) (xy 104.846016 -295.696717) (xy 104.868856 -295.746468)
			(xy 104.884347 -295.798974) (xy 104.892171 -295.853155) (xy 104.892167 -295.907899) (xy 104.884336 -295.962079)
			(xy 104.868837 -296.014583) (xy 104.845989 -296.064331) (xy 104.816263 -296.1103) (xy 104.798622 -296.131234)
			(xy 104.798368 -296.131488) (xy 104.792777 -296.138571) (xy 104.786534 -296.155491) (xy 104.786176 -296.164508)
			(xy 104.786176 -296.231564) (xy 104.786555 -296.240578) (xy 104.792788 -296.257495) (xy 104.798368 -296.264584)
			(xy 104.798622 -296.264584) (xy 104.798622 -296.264838) (xy 104.816296 -296.285743) (xy 104.846016 -296.331717)
			(xy 104.868856 -296.381468) (xy 104.884347 -296.433974) (xy 104.892171 -296.488155) (xy 104.892167 -296.542899)
			(xy 104.884336 -296.597079) (xy 104.868837 -296.649583) (xy 104.845989 -296.699331) (xy 104.816263 -296.7453)
			(xy 104.798622 -296.766234) (xy 104.798368 -296.766488) (xy 104.792777 -296.773571) (xy 104.786534 -296.790491)
			(xy 104.786176 -296.799508) (xy 104.786176 -296.866564) (xy 104.786555 -296.875578) (xy 104.792788 -296.892495)
			(xy 104.798368 -296.899584) (xy 104.798622 -296.899584) (xy 104.798622 -296.899838) (xy 104.816296 -296.920743)
			(xy 104.846016 -296.966717) (xy 104.868856 -297.016468) (xy 104.884347 -297.068974) (xy 104.892171 -297.123155)
			(xy 104.892167 -297.177899) (xy 104.884336 -297.232079) (xy 104.868837 -297.284583) (xy 104.845989 -297.334331)
			(xy 104.816263 -297.3803) (xy 104.798622 -297.401234) (xy 104.798368 -297.401488) (xy 104.792777 -297.408571)
			(xy 104.786534 -297.425491) (xy 104.786176 -297.434508) (xy 104.786176 -297.501564) (xy 104.786555 -297.510578)
			(xy 104.792788 -297.527495) (xy 104.798368 -297.534584) (xy 104.798622 -297.534584) (xy 104.798622 -297.534838)
			(xy 104.816296 -297.555743) (xy 104.846016 -297.601717) (xy 104.868856 -297.651468) (xy 104.884347 -297.703974)
			(xy 104.892171 -297.758155) (xy 104.892167 -297.812899) (xy 104.884336 -297.867079) (xy 104.868837 -297.919583)
			(xy 104.845989 -297.969331) (xy 104.816263 -298.0153) (xy 104.798622 -298.036234) (xy 104.798368 -298.036488)
			(xy 104.792777 -298.043571) (xy 104.786534 -298.060491) (xy 104.786176 -298.069508) (xy 104.786176 -298.136564)
			(xy 104.786555 -298.145578) (xy 104.792788 -298.162495) (xy 104.798368 -298.169584) (xy 104.798622 -298.169584)
			(xy 104.798622 -298.169838) (xy 104.816249 -298.19078) (xy 104.845962 -298.23675) (xy 104.8688 -298.286495)
			(xy 104.884294 -298.338994) (xy 104.892126 -298.393168) (xy 104.892602 -298.420536) (xy 108.135166 -298.420536)
			(xy 108.135637 -298.393166) (xy 108.143451 -298.338986) (xy 108.158938 -298.286483) (xy 108.181779 -298.236736)
			(xy 108.211504 -298.190769) (xy 108.229146 -298.169838) (xy 108.2294 -298.169584) (xy 108.234999 -298.162506)
			(xy 108.241238 -298.145583) (xy 108.241592 -298.136564) (xy 108.241592 -298.069508) (xy 108.241233 -298.060491)
			(xy 108.234987 -298.043574) (xy 108.2294 -298.036488) (xy 108.229146 -298.036488) (xy 108.229146 -298.036234)
			(xy 108.21154 -298.015273) (xy 108.181812 -297.969311) (xy 108.158963 -297.919569) (xy 108.143464 -297.867071)
			(xy 108.135631 -297.812896) (xy 108.135627 -297.758158) (xy 108.143452 -297.703982) (xy 108.158944 -297.651482)
			(xy 108.181786 -297.601737) (xy 108.211507 -297.55577) (xy 108.229146 -297.534838) (xy 108.2294 -297.534584)
			(xy 108.234999 -297.527506) (xy 108.241238 -297.510583) (xy 108.241592 -297.501564) (xy 108.241592 -297.434508)
			(xy 108.241233 -297.425491) (xy 108.234987 -297.408574) (xy 108.2294 -297.401488) (xy 108.229146 -297.401488)
			(xy 108.229146 -297.401234) (xy 108.21154 -297.380273) (xy 108.181812 -297.334311) (xy 108.158963 -297.284569)
			(xy 108.143464 -297.232071) (xy 108.135631 -297.177896) (xy 108.135627 -297.123158) (xy 108.143452 -297.068982)
			(xy 108.158944 -297.016482) (xy 108.181786 -296.966737) (xy 108.211507 -296.92077) (xy 108.229146 -296.899838)
			(xy 108.2294 -296.899584) (xy 108.234999 -296.892506) (xy 108.241238 -296.875583) (xy 108.241592 -296.866564)
			(xy 108.241592 -296.799508) (xy 108.241233 -296.790491) (xy 108.234987 -296.773574) (xy 108.2294 -296.766488)
			(xy 108.229146 -296.766488) (xy 108.229146 -296.766234) (xy 108.21154 -296.745273) (xy 108.181812 -296.699311)
			(xy 108.158963 -296.649569) (xy 108.143464 -296.597071) (xy 108.135631 -296.542896) (xy 108.135627 -296.488158)
			(xy 108.143452 -296.433982) (xy 108.158944 -296.381482) (xy 108.181786 -296.331737) (xy 108.211507 -296.28577)
			(xy 108.229146 -296.264838) (xy 108.2294 -296.264584) (xy 108.234999 -296.257506) (xy 108.241238 -296.240583)
			(xy 108.241592 -296.231564) (xy 108.241592 -296.164508) (xy 108.241233 -296.155491) (xy 108.234987 -296.138574)
			(xy 108.2294 -296.131488) (xy 108.229146 -296.131488) (xy 108.229146 -296.131234) (xy 108.21154 -296.110273)
			(xy 108.181812 -296.064311) (xy 108.158963 -296.014569) (xy 108.143464 -295.962071) (xy 108.135631 -295.907896)
			(xy 108.135627 -295.853158) (xy 108.143452 -295.798982) (xy 108.158944 -295.746482) (xy 108.181786 -295.696737)
			(xy 108.211507 -295.65077) (xy 108.229146 -295.629838) (xy 108.2294 -295.629584) (xy 108.234999 -295.622506)
			(xy 108.241238 -295.605583) (xy 108.241592 -295.596564) (xy 108.241592 -295.529508) (xy 108.241233 -295.520491)
			(xy 108.234987 -295.503574) (xy 108.2294 -295.496488) (xy 108.229146 -295.496488) (xy 108.229146 -295.496234)
			(xy 108.211517 -295.475294) (xy 108.181802 -295.429324) (xy 108.158963 -295.379579) (xy 108.14347 -295.327079)
			(xy 108.13564 -295.272905) (xy 108.135166 -295.245536) (xy 108.135689 -295.218285) (xy 108.14344 -295.164338)
			(xy 108.15879 -295.112043) (xy 108.181427 -295.062464) (xy 108.210889 -295.016612) (xy 108.246576 -294.97542)
			(xy 108.287763 -294.939726) (xy 108.33361 -294.910256) (xy 108.383184 -294.887612) (xy 108.435477 -294.872253)
			(xy 108.489423 -294.864493) (xy 108.516674 -294.864028) (xy 108.544044 -294.864502) (xy 108.598223 -294.872317)
			(xy 108.650726 -294.887804) (xy 108.700473 -294.910644) (xy 108.74644 -294.940367) (xy 108.767372 -294.958008)
			(xy 108.767626 -294.958262) (xy 108.774724 -294.963831) (xy 108.791632 -294.970087) (xy 108.800646 -294.970454)
			(xy 108.867702 -294.970454) (xy 108.87672 -294.970108) (xy 108.893637 -294.963854) (xy 108.900722 -294.958262)
			(xy 108.900722 -294.958008) (xy 108.900976 -294.958008) (xy 108.921907 -294.940368) (xy 108.96788 -294.910656)
			(xy 109.017628 -294.88782) (xy 109.070129 -294.872329) (xy 109.124305 -294.864502) (xy 109.151674 -294.864028)
			(xy 109.178928 -294.86448) (xy 109.232881 -294.872234) (xy 109.285181 -294.887589) (xy 109.334764 -294.910231)
			(xy 109.380619 -294.939699) (xy 109.421813 -294.975394) (xy 109.457507 -295.016589) (xy 109.486974 -295.062445)
			(xy 109.509615 -295.112028) (xy 109.524968 -295.164329) (xy 109.532721 -295.218282) (xy 109.533182 -295.245536)
			(xy 109.532741 -295.272907) (xy 109.524918 -295.327088) (xy 109.509423 -295.379591) (xy 109.486576 -295.429338)
			(xy 109.456846 -295.475303) (xy 109.439202 -295.496234) (xy 109.438948 -295.496488) (xy 109.433354 -295.503569)
			(xy 109.427113 -295.52049) (xy 109.426756 -295.529508) (xy 109.426756 -295.596564) (xy 109.427118 -295.605581)
			(xy 109.433361 -295.622498) (xy 109.438948 -295.629584) (xy 109.439202 -295.629584) (xy 109.439202 -295.629838)
			(xy 109.456877 -295.650743) (xy 109.486598 -295.696716) (xy 109.509439 -295.746467) (xy 109.524932 -295.798973)
			(xy 109.532756 -295.853155) (xy 109.532752 -295.907899) (xy 109.52492 -295.96208) (xy 109.50942 -296.014584)
			(xy 109.486572 -296.064331) (xy 109.456844 -296.110301) (xy 109.439202 -296.131234) (xy 109.438948 -296.131488)
			(xy 109.433354 -296.138569) (xy 109.427113 -296.15549) (xy 109.426756 -296.164508) (xy 109.426756 -296.231564)
			(xy 109.427118 -296.240581) (xy 109.433361 -296.257498) (xy 109.438948 -296.264584) (xy 109.439202 -296.264584)
			(xy 109.439202 -296.264838) (xy 109.456877 -296.285743) (xy 109.486598 -296.331716) (xy 109.509439 -296.381467)
			(xy 109.524932 -296.433973) (xy 109.532756 -296.488155) (xy 109.532752 -296.542899) (xy 109.52492 -296.59708)
			(xy 109.50942 -296.649584) (xy 109.486572 -296.699331) (xy 109.456844 -296.745301) (xy 109.439202 -296.766234)
			(xy 109.438948 -296.766488) (xy 109.433354 -296.773569) (xy 109.427113 -296.79049) (xy 109.426756 -296.799508)
			(xy 109.426756 -296.866564) (xy 109.427118 -296.875581) (xy 109.433361 -296.892498) (xy 109.438948 -296.899584)
			(xy 109.439202 -296.899584) (xy 109.439202 -296.899838) (xy 109.456877 -296.920743) (xy 109.486598 -296.966716)
			(xy 109.509439 -297.016467) (xy 109.524932 -297.068973) (xy 109.532756 -297.123155) (xy 109.532752 -297.177899)
			(xy 109.52492 -297.23208) (xy 109.50942 -297.284584) (xy 109.486572 -297.334331) (xy 109.456844 -297.380301)
			(xy 109.439202 -297.401234) (xy 109.438948 -297.401488) (xy 109.433354 -297.408569) (xy 109.427113 -297.42549)
			(xy 109.426756 -297.434508) (xy 109.426756 -297.501564) (xy 109.427118 -297.510581) (xy 109.433361 -297.527498)
			(xy 109.438948 -297.534584) (xy 109.439202 -297.534584) (xy 109.439202 -297.534838) (xy 109.456877 -297.555743)
			(xy 109.486598 -297.601716) (xy 109.509439 -297.651467) (xy 109.524932 -297.703973) (xy 109.532756 -297.758155)
			(xy 109.532752 -297.812899) (xy 109.52492 -297.86708) (xy 109.50942 -297.919584) (xy 109.486572 -297.969331)
			(xy 109.456844 -298.015301) (xy 109.439202 -298.036234) (xy 109.438948 -298.036488) (xy 109.433354 -298.043569)
			(xy 109.427113 -298.06049) (xy 109.426756 -298.069508) (xy 109.426756 -298.136564) (xy 109.427118 -298.145581)
			(xy 109.433361 -298.162498) (xy 109.438948 -298.169584) (xy 109.439202 -298.169584) (xy 109.439202 -298.169838)
			(xy 109.456826 -298.190782) (xy 109.48654 -298.236752) (xy 109.509379 -298.286496) (xy 109.524873 -298.338994)
			(xy 109.532706 -298.393168) (xy 109.533182 -298.420536) (xy 110.562898 -298.420536) (xy 110.563386 -298.393167)
			(xy 110.571198 -298.338988) (xy 110.586682 -298.286486) (xy 110.609519 -298.236738) (xy 110.639239 -298.19077)
			(xy 110.656878 -298.169838) (xy 110.657132 -298.169584) (xy 110.662735 -298.162509) (xy 110.668971 -298.145583)
			(xy 110.669324 -298.136564) (xy 110.669324 -298.069508) (xy 110.668958 -298.060492) (xy 110.662716 -298.043575)
			(xy 110.657132 -298.036488) (xy 110.656878 -298.036488) (xy 110.656878 -298.036234) (xy 110.639275 -298.015272)
			(xy 110.609552 -297.969308) (xy 110.586708 -297.919566) (xy 110.571211 -297.867069) (xy 110.56338 -297.812895)
			(xy 110.563376 -297.758159) (xy 110.571199 -297.703984) (xy 110.586689 -297.651485) (xy 110.609526 -297.60174)
			(xy 110.639242 -297.555772) (xy 110.656878 -297.534838) (xy 110.657132 -297.534584) (xy 110.662735 -297.527509)
			(xy 110.668971 -297.510583) (xy 110.669324 -297.501564) (xy 110.669324 -297.434508) (xy 110.668958 -297.425492)
			(xy 110.662716 -297.408575) (xy 110.657132 -297.401488) (xy 110.656878 -297.401488) (xy 110.656878 -297.401234)
			(xy 110.639275 -297.380272) (xy 110.609552 -297.334308) (xy 110.586708 -297.284566) (xy 110.571211 -297.232069)
			(xy 110.56338 -297.177895) (xy 110.563376 -297.123159) (xy 110.571199 -297.068984) (xy 110.586689 -297.016485)
			(xy 110.609526 -296.96674) (xy 110.639242 -296.920772) (xy 110.656878 -296.899838) (xy 110.657132 -296.899584)
			(xy 110.662735 -296.892509) (xy 110.668971 -296.875583) (xy 110.669324 -296.866564) (xy 110.669324 -296.799508)
			(xy 110.668958 -296.790492) (xy 110.662716 -296.773575) (xy 110.657132 -296.766488) (xy 110.656878 -296.766488)
			(xy 110.656878 -296.766234) (xy 110.639275 -296.745272) (xy 110.609552 -296.699308) (xy 110.586708 -296.649566)
			(xy 110.571211 -296.597069) (xy 110.56338 -296.542895) (xy 110.563376 -296.488159) (xy 110.571199 -296.433984)
			(xy 110.586689 -296.381485) (xy 110.609526 -296.33174) (xy 110.639242 -296.285772) (xy 110.656878 -296.264838)
			(xy 110.657132 -296.264584) (xy 110.662735 -296.257509) (xy 110.668971 -296.240583) (xy 110.669324 -296.231564)
			(xy 110.669324 -296.164508) (xy 110.668958 -296.155492) (xy 110.662716 -296.138575) (xy 110.657132 -296.131488)
			(xy 110.656878 -296.131488) (xy 110.656878 -296.131234) (xy 110.639275 -296.110272) (xy 110.609552 -296.064308)
			(xy 110.586708 -296.014566) (xy 110.571211 -295.962069) (xy 110.56338 -295.907895) (xy 110.563376 -295.853159)
			(xy 110.571199 -295.798984) (xy 110.586689 -295.746485) (xy 110.609526 -295.69674) (xy 110.639242 -295.650772)
			(xy 110.656878 -295.629838) (xy 110.657132 -295.629584) (xy 110.662735 -295.622509) (xy 110.668971 -295.605583)
			(xy 110.669324 -295.596564) (xy 110.669324 -295.529508) (xy 110.668958 -295.520492) (xy 110.662716 -295.503575)
			(xy 110.657132 -295.496488) (xy 110.656878 -295.496488) (xy 110.656878 -295.496234) (xy 110.639238 -295.475303)
			(xy 110.609527 -295.429329) (xy 110.586692 -295.379582) (xy 110.571201 -295.327081) (xy 110.563372 -295.272905)
			(xy 110.562898 -295.245536) (xy 110.563389 -295.218284) (xy 110.571141 -295.164334) (xy 110.586493 -295.112036)
			(xy 110.609132 -295.062455) (xy 110.638596 -295.016602) (xy 110.674287 -294.975409) (xy 110.715478 -294.939714)
			(xy 110.761329 -294.910246) (xy 110.810908 -294.887603) (xy 110.863204 -294.872247) (xy 110.917154 -294.864491)
			(xy 110.944406 -294.864028) (xy 110.971777 -294.864484) (xy 111.025956 -294.872303) (xy 111.07846 -294.887794)
			(xy 111.128207 -294.910638) (xy 111.174173 -294.940365) (xy 111.195104 -294.958008) (xy 111.195358 -294.958262)
			(xy 111.202447 -294.963844) (xy 111.219362 -294.970092) (xy 111.228378 -294.970454) (xy 111.295434 -294.970454)
			(xy 111.304454 -294.970123) (xy 111.321371 -294.963859) (xy 111.328454 -294.958262) (xy 111.328454 -294.958008)
			(xy 111.328708 -294.958008) (xy 111.349627 -294.940353) (xy 111.395603 -294.910643) (xy 111.445354 -294.88781)
			(xy 111.497858 -294.872323) (xy 111.552036 -294.864499) (xy 111.579406 -294.864028) (xy 111.606661 -294.86445)
			(xy 111.660615 -294.872209) (xy 111.712916 -294.887567) (xy 111.762498 -294.910213) (xy 111.808353 -294.939685)
			(xy 111.849547 -294.975383) (xy 111.88524 -295.016581) (xy 111.914707 -295.062439) (xy 111.937347 -295.112024)
			(xy 111.9527 -295.164326) (xy 111.960453 -295.218281) (xy 111.960914 -295.245536) (xy 111.960466 -295.272907)
			(xy 111.952643 -295.327087) (xy 111.93715 -295.37959) (xy 111.914304 -295.429336) (xy 111.884576 -295.475303)
			(xy 111.866934 -295.496234) (xy 111.86668 -295.496488) (xy 111.86109 -295.503572) (xy 111.854846 -295.520491)
			(xy 111.854488 -295.529508) (xy 111.854488 -295.596564) (xy 111.854865 -295.605579) (xy 111.861099 -295.622496)
			(xy 111.86668 -295.629584) (xy 111.866934 -295.629584) (xy 111.866934 -295.629838) (xy 111.884612 -295.650741)
			(xy 111.914338 -295.696713) (xy 111.937184 -295.746464) (xy 111.952679 -295.798971) (xy 111.960505 -295.853154)
			(xy 111.960501 -295.9079) (xy 111.952667 -295.962082) (xy 111.937164 -296.014587) (xy 111.914312 -296.064334)
			(xy 111.884579 -296.110302) (xy 111.866934 -296.131234) (xy 111.86668 -296.131488) (xy 111.86109 -296.138572)
			(xy 111.854846 -296.155491) (xy 111.854488 -296.164508) (xy 111.854488 -296.231564) (xy 111.854865 -296.240579)
			(xy 111.861099 -296.257496) (xy 111.86668 -296.264584) (xy 111.866934 -296.264584) (xy 111.866934 -296.264838)
			(xy 111.884612 -296.285741) (xy 111.914338 -296.331713) (xy 111.937184 -296.381464) (xy 111.952679 -296.433971)
			(xy 111.960505 -296.488154) (xy 111.960501 -296.5429) (xy 111.952667 -296.597082) (xy 111.937164 -296.649587)
			(xy 111.914312 -296.699334) (xy 111.884579 -296.745302) (xy 111.866934 -296.766234) (xy 111.86668 -296.766488)
			(xy 111.86109 -296.773572) (xy 111.854846 -296.790491) (xy 111.854488 -296.799508) (xy 111.854488 -296.866564)
			(xy 111.854865 -296.875579) (xy 111.861099 -296.892496) (xy 111.86668 -296.899584) (xy 111.866934 -296.899584)
			(xy 111.866934 -296.899838) (xy 111.884612 -296.920741) (xy 111.914338 -296.966713) (xy 111.937184 -297.016464)
			(xy 111.952679 -297.068971) (xy 111.960505 -297.123154) (xy 111.960501 -297.1779) (xy 111.952667 -297.232082)
			(xy 111.937164 -297.284587) (xy 111.914312 -297.334334) (xy 111.884579 -297.380302) (xy 111.866934 -297.401234)
			(xy 111.86668 -297.401488) (xy 111.86109 -297.408572) (xy 111.854846 -297.425491) (xy 111.854488 -297.434508)
			(xy 111.854488 -297.501564) (xy 111.854865 -297.510579) (xy 111.861099 -297.527496) (xy 111.86668 -297.534584)
			(xy 111.866934 -297.534584) (xy 111.866934 -297.534838) (xy 111.884612 -297.555741) (xy 111.914338 -297.601713)
			(xy 111.937184 -297.651464) (xy 111.952679 -297.703971) (xy 111.960505 -297.758154) (xy 111.960501 -297.8129)
			(xy 111.952667 -297.867082) (xy 111.937164 -297.919587) (xy 111.914312 -297.969334) (xy 111.884579 -298.015302)
			(xy 111.866934 -298.036234) (xy 111.86668 -298.036488) (xy 111.86109 -298.043572) (xy 111.854846 -298.060491)
			(xy 111.854488 -298.069508) (xy 111.854488 -298.136564) (xy 111.854865 -298.145579) (xy 111.861099 -298.162496)
			(xy 111.86668 -298.169584) (xy 111.866934 -298.169584) (xy 111.866934 -298.169838) (xy 111.884563 -298.190778)
			(xy 111.914275 -298.236749) (xy 111.937112 -298.286495) (xy 111.952606 -298.338993) (xy 111.960438 -298.393167)
			(xy 111.960914 -298.420536) (xy 115.203478 -298.420536) (xy 115.203946 -298.393166) (xy 115.211761 -298.338986)
			(xy 115.227248 -298.286482) (xy 115.25009 -298.236735) (xy 115.279816 -298.190769) (xy 115.297458 -298.169838)
			(xy 115.297712 -298.169584) (xy 115.303313 -298.162507) (xy 115.309551 -298.145583) (xy 115.309904 -298.136564)
			(xy 115.309904 -298.069508) (xy 115.309542 -298.060492) (xy 115.303298 -298.043575) (xy 115.297712 -298.036488)
			(xy 115.297458 -298.036488) (xy 115.297458 -298.036234) (xy 115.279851 -298.015273) (xy 115.250123 -297.969311)
			(xy 115.227273 -297.91957) (xy 115.211773 -297.867072) (xy 115.20394 -297.812896) (xy 115.203936 -297.758158)
			(xy 115.211761 -297.703981) (xy 115.227254 -297.651481) (xy 115.250097 -297.601736) (xy 115.279819 -297.55577)
			(xy 115.297458 -297.534838) (xy 115.297712 -297.534584) (xy 115.303313 -297.527507) (xy 115.309551 -297.510583)
			(xy 115.309904 -297.501564) (xy 115.309904 -297.434508) (xy 115.309542 -297.425492) (xy 115.303298 -297.408575)
			(xy 115.297712 -297.401488) (xy 115.297458 -297.401488) (xy 115.297458 -297.401234) (xy 115.279851 -297.380273)
			(xy 115.250123 -297.334311) (xy 115.227273 -297.28457) (xy 115.211773 -297.232072) (xy 115.20394 -297.177896)
			(xy 115.203936 -297.123158) (xy 115.211761 -297.068981) (xy 115.227254 -297.016481) (xy 115.250097 -296.966736)
			(xy 115.279819 -296.92077) (xy 115.297458 -296.899838) (xy 115.297712 -296.899584) (xy 115.303313 -296.892507)
			(xy 115.309551 -296.875583) (xy 115.309904 -296.866564) (xy 115.309904 -296.799508) (xy 115.309542 -296.790492)
			(xy 115.303298 -296.773575) (xy 115.297712 -296.766488) (xy 115.297458 -296.766488) (xy 115.297458 -296.766234)
			(xy 115.279851 -296.745273) (xy 115.250123 -296.699311) (xy 115.227273 -296.64957) (xy 115.211773 -296.597072)
			(xy 115.20394 -296.542896) (xy 115.203936 -296.488158) (xy 115.211761 -296.433981) (xy 115.227254 -296.381481)
			(xy 115.250097 -296.331736) (xy 115.279819 -296.28577) (xy 115.297458 -296.264838) (xy 115.297712 -296.264584)
			(xy 115.303313 -296.257507) (xy 115.309551 -296.240583) (xy 115.309904 -296.231564) (xy 115.309904 -296.164508)
			(xy 115.309542 -296.155492) (xy 115.303298 -296.138575) (xy 115.297712 -296.131488) (xy 115.297458 -296.131488)
			(xy 115.297458 -296.131234) (xy 115.279851 -296.110273) (xy 115.250123 -296.064311) (xy 115.227273 -296.01457)
			(xy 115.211773 -295.962072) (xy 115.20394 -295.907896) (xy 115.203936 -295.853158) (xy 115.211761 -295.798981)
			(xy 115.227254 -295.746481) (xy 115.250097 -295.696736) (xy 115.279819 -295.65077) (xy 115.297458 -295.629838)
			(xy 115.297712 -295.629584) (xy 115.303313 -295.622507) (xy 115.309551 -295.605583) (xy 115.309904 -295.596564)
			(xy 115.309904 -295.529508) (xy 115.309542 -295.520492) (xy 115.303298 -295.503575) (xy 115.297712 -295.496488)
			(xy 115.297458 -295.496488) (xy 115.297458 -295.496234) (xy 115.279814 -295.475306) (xy 115.250105 -295.429331)
			(xy 115.22727 -295.379583) (xy 115.21178 -295.327081) (xy 115.203952 -295.272905) (xy 115.203478 -295.245536)
			(xy 115.203989 -295.218285) (xy 115.21174 -295.164336) (xy 115.227091 -295.11204) (xy 115.249729 -295.062461)
			(xy 115.279191 -295.016608) (xy 115.31488 -294.975416) (xy 115.356068 -294.939721) (xy 115.401917 -294.910253)
			(xy 115.451493 -294.887609) (xy 115.503787 -294.872251) (xy 115.557735 -294.864492) (xy 115.584986 -294.864028)
			(xy 115.612356 -294.864495) (xy 115.666536 -294.872312) (xy 115.719039 -294.8878) (xy 115.768786 -294.910642)
			(xy 115.814752 -294.940367) (xy 115.835684 -294.958008) (xy 115.835938 -294.958262) (xy 115.843033 -294.963836)
			(xy 115.859944 -294.970089) (xy 115.868958 -294.970454) (xy 115.936014 -294.970454) (xy 115.945033 -294.970114)
			(xy 115.96195 -294.963856) (xy 115.969034 -294.958262) (xy 115.969034 -294.958008) (xy 115.969288 -294.958008)
			(xy 115.990215 -294.940362) (xy 116.036189 -294.910651) (xy 116.085938 -294.887816) (xy 116.13844 -294.872327)
			(xy 116.192616 -294.864501) (xy 116.219986 -294.864028) (xy 116.24724 -294.864468) (xy 116.301194 -294.872224)
			(xy 116.353494 -294.887581) (xy 116.403077 -294.910224) (xy 116.448932 -294.939694) (xy 116.490125 -294.97539)
			(xy 116.525819 -295.016586) (xy 116.555287 -295.062443) (xy 116.577927 -295.112026) (xy 116.59328 -295.164328)
			(xy 116.601033 -295.218282) (xy 116.601494 -295.245536) (xy 116.60105 -295.272907) (xy 116.593227 -295.327087)
			(xy 116.577733 -295.379591) (xy 116.554886 -295.429337) (xy 116.525157 -295.475303) (xy 116.507514 -295.496234)
			(xy 116.50726 -295.496488) (xy 116.501667 -295.50357) (xy 116.495425 -295.52049) (xy 116.495068 -295.529508)
			(xy 116.495068 -295.596564) (xy 116.495449 -295.605578) (xy 116.501681 -295.622495) (xy 116.50726 -295.629584)
			(xy 116.507514 -295.629584) (xy 116.507514 -295.629838) (xy 116.525188 -295.650743) (xy 116.554908 -295.696717)
			(xy 116.577749 -295.746468) (xy 116.593241 -295.798974) (xy 116.601065 -295.853155) (xy 116.601061 -295.907899)
			(xy 116.593229 -295.962079) (xy 116.57773 -296.014583) (xy 116.554882 -296.064331) (xy 116.525156 -296.1103)
			(xy 116.507514 -296.131234) (xy 116.50726 -296.131488) (xy 116.501667 -296.13857) (xy 116.495425 -296.15549)
			(xy 116.495068 -296.164508) (xy 116.495068 -296.231564) (xy 116.495449 -296.240578) (xy 116.501681 -296.257495)
			(xy 116.50726 -296.264584) (xy 116.507514 -296.264584) (xy 116.507514 -296.264838) (xy 116.525188 -296.285743)
			(xy 116.554908 -296.331717) (xy 116.577749 -296.381468) (xy 116.593241 -296.433974) (xy 116.601065 -296.488155)
			(xy 116.601061 -296.542899) (xy 116.593229 -296.597079) (xy 116.57773 -296.649583) (xy 116.554882 -296.699331)
			(xy 116.525156 -296.7453) (xy 116.507514 -296.766234) (xy 116.50726 -296.766488) (xy 116.501667 -296.77357)
			(xy 116.495425 -296.79049) (xy 116.495068 -296.799508) (xy 116.495068 -296.866564) (xy 116.495449 -296.875578)
			(xy 116.501681 -296.892495) (xy 116.50726 -296.899584) (xy 116.507514 -296.899584) (xy 116.507514 -296.899838)
			(xy 116.525188 -296.920743) (xy 116.554908 -296.966717) (xy 116.577749 -297.016468) (xy 116.593241 -297.068974)
			(xy 116.601065 -297.123155) (xy 116.601061 -297.177899) (xy 116.593229 -297.232079) (xy 116.57773 -297.284583)
			(xy 116.554882 -297.334331) (xy 116.525156 -297.3803) (xy 116.507514 -297.401234) (xy 116.50726 -297.401488)
			(xy 116.501667 -297.40857) (xy 116.495425 -297.42549) (xy 116.495068 -297.434508) (xy 116.495068 -297.501564)
			(xy 116.495449 -297.510578) (xy 116.501681 -297.527495) (xy 116.50726 -297.534584) (xy 116.507514 -297.534584)
			(xy 116.507514 -297.534838) (xy 116.525188 -297.555743) (xy 116.554908 -297.601717) (xy 116.577749 -297.651468)
			(xy 116.593241 -297.703974) (xy 116.601065 -297.758155) (xy 116.601061 -297.812899) (xy 116.593229 -297.867079)
			(xy 116.57773 -297.919583) (xy 116.554882 -297.969331) (xy 116.525156 -298.0153) (xy 116.507514 -298.036234)
			(xy 116.50726 -298.036488) (xy 116.501667 -298.04357) (xy 116.495425 -298.06049) (xy 116.495068 -298.069508)
			(xy 116.495068 -298.136564) (xy 116.495449 -298.145578) (xy 116.501681 -298.162495) (xy 116.50726 -298.169584)
			(xy 116.507514 -298.169584) (xy 116.507514 -298.169838) (xy 116.52514 -298.190781) (xy 116.554853 -298.236751)
			(xy 116.577691 -298.286496) (xy 116.593186 -298.338994) (xy 116.601018 -298.393168) (xy 116.601494 -298.420536)
			(xy 120.153684 -298.420536) (xy 120.154151 -298.393166) (xy 120.161965 -298.338986) (xy 120.177453 -298.286482)
			(xy 120.200295 -298.236735) (xy 120.230021 -298.190769) (xy 120.247664 -298.169838) (xy 120.247918 -298.169584)
			(xy 120.253519 -298.162508) (xy 120.259757 -298.145583) (xy 120.26011 -298.136564) (xy 120.26011 -298.069508)
			(xy 120.259747 -298.060492) (xy 120.253503 -298.043575) (xy 120.247918 -298.036488) (xy 120.247664 -298.036488)
			(xy 120.247664 -298.036234) (xy 120.230057 -298.015273) (xy 120.200328 -297.969311) (xy 120.177478 -297.91957)
			(xy 120.161978 -297.867072) (xy 120.154145 -297.812896) (xy 120.154141 -297.758158) (xy 120.161966 -297.703981)
			(xy 120.177459 -297.651481) (xy 120.200302 -297.601736) (xy 120.230024 -297.55577) (xy 120.247664 -297.534838)
			(xy 120.247918 -297.534584) (xy 120.253519 -297.527508) (xy 120.259757 -297.510583) (xy 120.26011 -297.501564)
			(xy 120.26011 -297.434508) (xy 120.259747 -297.425492) (xy 120.253503 -297.408575) (xy 120.247918 -297.401488)
			(xy 120.247664 -297.401488) (xy 120.247664 -297.401234) (xy 120.230057 -297.380273) (xy 120.200328 -297.334311)
			(xy 120.177478 -297.28457) (xy 120.161978 -297.232072) (xy 120.154145 -297.177896) (xy 120.154141 -297.123158)
			(xy 120.161966 -297.068981) (xy 120.177459 -297.016481) (xy 120.200302 -296.966736) (xy 120.230024 -296.92077)
			(xy 120.247664 -296.899838) (xy 120.247918 -296.899584) (xy 120.253519 -296.892508) (xy 120.259757 -296.875583)
			(xy 120.26011 -296.866564) (xy 120.26011 -296.799508) (xy 120.259747 -296.790492) (xy 120.253503 -296.773575)
			(xy 120.247918 -296.766488) (xy 120.247664 -296.766488) (xy 120.247664 -296.766234) (xy 120.230057 -296.745273)
			(xy 120.200328 -296.699311) (xy 120.177478 -296.64957) (xy 120.161978 -296.597072) (xy 120.154145 -296.542896)
			(xy 120.154141 -296.488158) (xy 120.161966 -296.433981) (xy 120.177459 -296.381481) (xy 120.200302 -296.331736)
			(xy 120.230024 -296.28577) (xy 120.247664 -296.264838) (xy 120.247918 -296.264584) (xy 120.253519 -296.257508)
			(xy 120.259757 -296.240583) (xy 120.26011 -296.231564) (xy 120.26011 -296.164508) (xy 120.259747 -296.155492)
			(xy 120.253503 -296.138575) (xy 120.247918 -296.131488) (xy 120.247664 -296.131488) (xy 120.247664 -296.131234)
			(xy 120.230057 -296.110273) (xy 120.200328 -296.064311) (xy 120.177478 -296.01457) (xy 120.161978 -295.962072)
			(xy 120.154145 -295.907896) (xy 120.154141 -295.853158) (xy 120.161966 -295.798981) (xy 120.177459 -295.746481)
			(xy 120.200302 -295.696736) (xy 120.230024 -295.65077) (xy 120.247664 -295.629838) (xy 120.247918 -295.629584)
			(xy 120.253519 -295.622508) (xy 120.259757 -295.605583) (xy 120.26011 -295.596564) (xy 120.26011 -295.529508)
			(xy 120.259747 -295.520492) (xy 120.253503 -295.503575) (xy 120.247918 -295.496488) (xy 120.247664 -295.496488)
			(xy 120.247664 -295.496234) (xy 120.230022 -295.475305) (xy 120.200312 -295.42933) (xy 120.177477 -295.379582)
			(xy 120.161986 -295.327081) (xy 120.154158 -295.272905) (xy 120.153684 -295.245536) (xy 120.154189 -295.218284)
			(xy 120.161941 -295.164335) (xy 120.177292 -295.112039) (xy 120.199929 -295.062459) (xy 120.229393 -295.016606)
			(xy 120.265082 -294.975414) (xy 120.306271 -294.939719) (xy 120.352121 -294.910251) (xy 120.401697 -294.887607)
			(xy 120.453992 -294.87225) (xy 120.50794 -294.864492) (xy 120.535192 -294.864028) (xy 120.562562 -294.864492)
			(xy 120.616742 -294.872309) (xy 120.669245 -294.887798) (xy 120.718992 -294.910641) (xy 120.764959 -294.940366)
			(xy 120.78589 -294.958008) (xy 120.786144 -294.958262) (xy 120.793237 -294.963839) (xy 120.810149 -294.97009)
			(xy 120.819164 -294.970454) (xy 120.88622 -294.970454) (xy 120.895239 -294.970117) (xy 120.912156 -294.963857)
			(xy 120.91924 -294.958262) (xy 120.91924 -294.958008) (xy 120.919494 -294.958008) (xy 120.940419 -294.94036)
			(xy 120.986393 -294.910649) (xy 121.036143 -294.887815) (xy 121.088645 -294.872326) (xy 121.142822 -294.8645)
			(xy 121.170192 -294.864028) (xy 121.197446 -294.864463) (xy 121.2514 -294.87222) (xy 121.303701 -294.887577)
			(xy 121.353283 -294.910221) (xy 121.399138 -294.939691) (xy 121.440332 -294.975388) (xy 121.476026 -295.016584)
			(xy 121.505493 -295.062441) (xy 121.528133 -295.112026) (xy 121.543486 -295.164327) (xy 121.551239 -295.218282)
			(xy 121.5517 -295.245536) (xy 121.551255 -295.272907) (xy 121.543432 -295.327087) (xy 121.527938 -295.37959)
			(xy 121.505092 -295.429337) (xy 121.475363 -295.475303) (xy 121.45772 -295.496234) (xy 121.457466 -295.496488)
			(xy 121.451875 -295.503571) (xy 121.445632 -295.520491) (xy 121.445274 -295.529508) (xy 121.445274 -295.596564)
			(xy 121.445654 -295.605578) (xy 121.451886 -295.622495) (xy 121.457466 -295.629584) (xy 121.45772 -295.629584)
			(xy 121.45772 -295.629838) (xy 121.475394 -295.650743) (xy 121.505114 -295.696717) (xy 121.527954 -295.746468)
			(xy 121.543446 -295.798974) (xy 121.55127 -295.853155) (xy 121.551266 -295.907899) (xy 121.543434 -295.962079)
			(xy 121.527935 -296.014583) (xy 121.505088 -296.064331) (xy 121.475361 -296.1103) (xy 121.45772 -296.131234)
			(xy 121.457466 -296.131488) (xy 121.451875 -296.138571) (xy 121.445632 -296.155491) (xy 121.445274 -296.164508)
			(xy 121.445274 -296.231564) (xy 121.445654 -296.240578) (xy 121.451886 -296.257495) (xy 121.457466 -296.264584)
			(xy 121.45772 -296.264584) (xy 121.45772 -296.264838) (xy 121.475394 -296.285743) (xy 121.505114 -296.331717)
			(xy 121.527954 -296.381468) (xy 121.543446 -296.433974) (xy 121.55127 -296.488155) (xy 121.551266 -296.542899)
			(xy 121.543434 -296.597079) (xy 121.527935 -296.649583) (xy 121.505088 -296.699331) (xy 121.475361 -296.7453)
			(xy 121.45772 -296.766234) (xy 121.457466 -296.766488) (xy 121.451875 -296.773571) (xy 121.445632 -296.790491)
			(xy 121.445274 -296.799508) (xy 121.445274 -296.866564) (xy 121.445654 -296.875578) (xy 121.451886 -296.892495)
			(xy 121.457466 -296.899584) (xy 121.45772 -296.899584) (xy 121.45772 -296.899838) (xy 121.475394 -296.920743)
			(xy 121.505114 -296.966717) (xy 121.527954 -297.016468) (xy 121.543446 -297.068974) (xy 121.55127 -297.123155)
			(xy 121.551266 -297.177899) (xy 121.543434 -297.232079) (xy 121.527935 -297.284583) (xy 121.505088 -297.334331)
			(xy 121.475361 -297.3803) (xy 121.45772 -297.401234) (xy 121.457466 -297.401488) (xy 121.451875 -297.408571)
			(xy 121.445632 -297.425491) (xy 121.445274 -297.434508) (xy 121.445274 -297.501564) (xy 121.445654 -297.510578)
			(xy 121.451886 -297.527495) (xy 121.457466 -297.534584) (xy 121.45772 -297.534584) (xy 121.45772 -297.534838)
			(xy 121.475394 -297.555743) (xy 121.505114 -297.601717) (xy 121.527954 -297.651468) (xy 121.543446 -297.703974)
			(xy 121.55127 -297.758155) (xy 121.551266 -297.812899) (xy 121.543434 -297.867079) (xy 121.527935 -297.919583)
			(xy 121.505088 -297.969331) (xy 121.475361 -298.0153) (xy 121.45772 -298.036234) (xy 121.457466 -298.036488)
			(xy 121.451875 -298.043571) (xy 121.445632 -298.060491) (xy 121.445274 -298.069508) (xy 121.445274 -298.136564)
			(xy 121.445654 -298.145578) (xy 121.451886 -298.162495) (xy 121.457466 -298.169584) (xy 121.45772 -298.169584)
			(xy 121.45772 -298.169838) (xy 121.475347 -298.19078) (xy 121.50506 -298.23675) (xy 121.527898 -298.286495)
			(xy 121.543392 -298.338994) (xy 121.551224 -298.393168) (xy 121.5517 -298.420536) (xy 124.794264 -298.420536)
			(xy 124.794736 -298.393166) (xy 124.80255 -298.338986) (xy 124.818037 -298.286483) (xy 124.840878 -298.236736)
			(xy 124.870602 -298.190769) (xy 124.888244 -298.169838) (xy 124.888498 -298.169584) (xy 124.894097 -298.162506)
			(xy 124.900336 -298.145583) (xy 124.90069 -298.136564) (xy 124.90069 -298.069508) (xy 124.900331 -298.060491)
			(xy 124.894085 -298.043574) (xy 124.888498 -298.036488) (xy 124.888244 -298.036488) (xy 124.888244 -298.036234)
			(xy 124.870638 -298.015273) (xy 124.84091 -297.969311) (xy 124.818062 -297.919569) (xy 124.802562 -297.867071)
			(xy 124.79473 -297.812896) (xy 124.794726 -297.758158) (xy 124.80255 -297.703982) (xy 124.818043 -297.651482)
			(xy 124.840884 -297.601737) (xy 124.870605 -297.55577) (xy 124.888244 -297.534838) (xy 124.888498 -297.534584)
			(xy 124.894097 -297.527506) (xy 124.900336 -297.510583) (xy 124.90069 -297.501564) (xy 124.90069 -297.434508)
			(xy 124.900331 -297.425491) (xy 124.894085 -297.408574) (xy 124.888498 -297.401488) (xy 124.888244 -297.401488)
			(xy 124.888244 -297.401234) (xy 124.870638 -297.380273) (xy 124.84091 -297.334311) (xy 124.818062 -297.284569)
			(xy 124.802562 -297.232071) (xy 124.79473 -297.177896) (xy 124.794726 -297.123158) (xy 124.80255 -297.068982)
			(xy 124.818043 -297.016482) (xy 124.840884 -296.966737) (xy 124.870605 -296.92077) (xy 124.888244 -296.899838)
			(xy 124.888498 -296.899584) (xy 124.894097 -296.892506) (xy 124.900336 -296.875583) (xy 124.90069 -296.866564)
			(xy 124.90069 -296.799508) (xy 124.900331 -296.790491) (xy 124.894085 -296.773574) (xy 124.888498 -296.766488)
			(xy 124.888244 -296.766488) (xy 124.888244 -296.766234) (xy 124.870638 -296.745273) (xy 124.84091 -296.699311)
			(xy 124.818062 -296.649569) (xy 124.802562 -296.597071) (xy 124.79473 -296.542896) (xy 124.794726 -296.488158)
			(xy 124.80255 -296.433982) (xy 124.818043 -296.381482) (xy 124.840884 -296.331737) (xy 124.870605 -296.28577)
			(xy 124.888244 -296.264838) (xy 124.888498 -296.264584) (xy 124.894097 -296.257506) (xy 124.900336 -296.240583)
			(xy 124.90069 -296.231564) (xy 124.90069 -296.164508) (xy 124.900331 -296.155491) (xy 124.894085 -296.138574)
			(xy 124.888498 -296.131488) (xy 124.888244 -296.131488) (xy 124.888244 -296.131234) (xy 124.870638 -296.110273)
			(xy 124.84091 -296.064311) (xy 124.818062 -296.014569) (xy 124.802562 -295.962071) (xy 124.79473 -295.907896)
			(xy 124.794726 -295.853158) (xy 124.80255 -295.798982) (xy 124.818043 -295.746482) (xy 124.840884 -295.696737)
			(xy 124.870605 -295.65077) (xy 124.888244 -295.629838) (xy 124.888498 -295.629584) (xy 124.894097 -295.622506)
			(xy 124.900336 -295.605583) (xy 124.90069 -295.596564) (xy 124.90069 -295.529508) (xy 124.900331 -295.520491)
			(xy 124.894085 -295.503574) (xy 124.888498 -295.496488) (xy 124.888244 -295.496488) (xy 124.888244 -295.496234)
			(xy 124.870614 -295.475294) (xy 124.840899 -295.429324) (xy 124.818061 -295.379579) (xy 124.802568 -295.32708)
			(xy 124.794738 -295.272905) (xy 124.794264 -295.245536) (xy 124.794789 -295.218285) (xy 124.80254 -295.164338)
			(xy 124.81789 -295.112043) (xy 124.840526 -295.062465) (xy 124.869988 -295.016613) (xy 124.905675 -294.975421)
			(xy 124.946862 -294.939726) (xy 124.992709 -294.910257) (xy 125.042283 -294.887613) (xy 125.094575 -294.872254)
			(xy 125.148521 -294.864493) (xy 125.175772 -294.864028) (xy 125.203142 -294.864504) (xy 125.257321 -294.872318)
			(xy 125.309824 -294.887805) (xy 125.359571 -294.910644) (xy 125.405538 -294.940367) (xy 125.42647 -294.958008)
			(xy 125.426724 -294.958262) (xy 125.433794 -294.963872) (xy 125.450724 -294.970103) (xy 125.459744 -294.970454)
			(xy 125.5268 -294.970454) (xy 125.535818 -294.970107) (xy 125.552735 -294.963853) (xy 125.55982 -294.958262)
			(xy 125.55982 -294.958008) (xy 125.560074 -294.958008) (xy 125.581006 -294.940369) (xy 125.626979 -294.910657)
			(xy 125.676726 -294.887821) (xy 125.729227 -294.87233) (xy 125.783403 -294.864502) (xy 125.810772 -294.864028)
			(xy 125.838026 -294.864481) (xy 125.891979 -294.872236) (xy 125.944279 -294.88759) (xy 125.993862 -294.910232)
			(xy 126.039717 -294.9397) (xy 126.080911 -294.975395) (xy 126.116605 -295.01659) (xy 126.146072 -295.062445)
			(xy 126.168713 -295.112028) (xy 126.184066 -295.164329) (xy 126.191819 -295.218282) (xy 126.19228 -295.245536)
			(xy 126.19184 -295.272907) (xy 126.184017 -295.327088) (xy 126.168522 -295.379591) (xy 126.145674 -295.429338)
			(xy 126.115944 -295.475303) (xy 126.0983 -295.496234) (xy 126.098046 -295.496488) (xy 126.092452 -295.503569)
			(xy 126.086211 -295.52049) (xy 126.085854 -295.529508) (xy 126.085854 -295.596564) (xy 126.086217 -295.605581)
			(xy 126.092459 -295.622498) (xy 126.098046 -295.629584) (xy 126.0983 -295.629584) (xy 126.0983 -295.629838)
			(xy 126.115975 -295.650743) (xy 126.145696 -295.696716) (xy 126.168538 -295.746467) (xy 126.18403 -295.798973)
			(xy 126.191855 -295.853155) (xy 126.191851 -295.907899) (xy 126.184018 -295.96208) (xy 126.168519 -296.014584)
			(xy 126.14567 -296.064332) (xy 126.115942 -296.110301) (xy 126.0983 -296.131234) (xy 126.098046 -296.131488)
			(xy 126.092452 -296.138569) (xy 126.086211 -296.15549) (xy 126.085854 -296.164508) (xy 126.085854 -296.231564)
			(xy 126.086217 -296.240581) (xy 126.092459 -296.257498) (xy 126.098046 -296.264584) (xy 126.0983 -296.264584)
			(xy 126.0983 -296.264838) (xy 126.115975 -296.285743) (xy 126.145696 -296.331716) (xy 126.168538 -296.381467)
			(xy 126.18403 -296.433973) (xy 126.191855 -296.488155) (xy 126.191851 -296.542899) (xy 126.184018 -296.59708)
			(xy 126.168519 -296.649584) (xy 126.14567 -296.699332) (xy 126.115942 -296.745301) (xy 126.0983 -296.766234)
			(xy 126.098046 -296.766488) (xy 126.092452 -296.773569) (xy 126.086211 -296.79049) (xy 126.085854 -296.799508)
			(xy 126.085854 -296.866564) (xy 126.086217 -296.875581) (xy 126.092459 -296.892498) (xy 126.098046 -296.899584)
			(xy 126.0983 -296.899584) (xy 126.0983 -296.899838) (xy 126.115975 -296.920743) (xy 126.145696 -296.966716)
			(xy 126.168538 -297.016467) (xy 126.18403 -297.068973) (xy 126.191855 -297.123155) (xy 126.191851 -297.177899)
			(xy 126.184018 -297.23208) (xy 126.168519 -297.284584) (xy 126.14567 -297.334332) (xy 126.115942 -297.380301)
			(xy 126.0983 -297.401234) (xy 126.098046 -297.401488) (xy 126.092452 -297.408569) (xy 126.086211 -297.42549)
			(xy 126.085854 -297.434508) (xy 126.085854 -297.501564) (xy 126.086217 -297.510581) (xy 126.092459 -297.527498)
			(xy 126.098046 -297.534584) (xy 126.0983 -297.534584) (xy 126.0983 -297.534838) (xy 126.115975 -297.555743)
			(xy 126.145696 -297.601716) (xy 126.168538 -297.651467) (xy 126.18403 -297.703973) (xy 126.191855 -297.758155)
			(xy 126.191851 -297.812899) (xy 126.184018 -297.86708) (xy 126.168519 -297.919584) (xy 126.14567 -297.969332)
			(xy 126.115942 -298.015301) (xy 126.0983 -298.036234) (xy 126.098046 -298.036488) (xy 126.092452 -298.043569)
			(xy 126.086211 -298.06049) (xy 126.085854 -298.069508) (xy 126.085854 -298.136564) (xy 126.086217 -298.145581)
			(xy 126.092459 -298.162498) (xy 126.098046 -298.169584) (xy 126.0983 -298.169584) (xy 126.0983 -298.169838)
			(xy 126.115923 -298.190783) (xy 126.145638 -298.236752) (xy 126.168477 -298.286496) (xy 126.183971 -298.338994)
			(xy 126.191804 -298.393168) (xy 126.19228 -298.420536) (xy 127.221996 -298.420536) (xy 127.222484 -298.393167)
			(xy 127.230297 -298.338988) (xy 127.245781 -298.286486) (xy 127.268618 -298.236738) (xy 127.298337 -298.190771)
			(xy 127.315976 -298.169838) (xy 127.31623 -298.169584) (xy 127.321833 -298.162509) (xy 127.328069 -298.145583)
			(xy 127.328422 -298.136564) (xy 127.328422 -298.069508) (xy 127.328056 -298.060492) (xy 127.321814 -298.043575)
			(xy 127.31623 -298.036488) (xy 127.315976 -298.036488) (xy 127.315976 -298.036234) (xy 127.298369 -298.015274)
			(xy 127.268639 -297.969312) (xy 127.245788 -297.91957) (xy 127.230287 -297.867072) (xy 127.222454 -297.812897)
			(xy 127.22245 -297.758158) (xy 127.230275 -297.703981) (xy 127.245769 -297.65148) (xy 127.268612 -297.601736)
			(xy 127.298336 -297.55577) (xy 127.315976 -297.534838) (xy 127.31623 -297.534584) (xy 127.321833 -297.527509)
			(xy 127.328069 -297.510583) (xy 127.328422 -297.501564) (xy 127.328422 -297.434508) (xy 127.328056 -297.425492)
			(xy 127.321814 -297.408575) (xy 127.31623 -297.401488) (xy 127.315976 -297.401488) (xy 127.315976 -297.401234)
			(xy 127.298369 -297.380274) (xy 127.268639 -297.334312) (xy 127.245788 -297.28457) (xy 127.230287 -297.232072)
			(xy 127.222454 -297.177897) (xy 127.22245 -297.123158) (xy 127.230275 -297.068981) (xy 127.245769 -297.01648)
			(xy 127.268612 -296.966736) (xy 127.298336 -296.92077) (xy 127.315976 -296.899838) (xy 127.31623 -296.899584)
			(xy 127.321833 -296.892509) (xy 127.328069 -296.875583) (xy 127.328422 -296.866564) (xy 127.328422 -296.799508)
			(xy 127.328056 -296.790492) (xy 127.321814 -296.773575) (xy 127.31623 -296.766488) (xy 127.315976 -296.766488)
			(xy 127.315976 -296.766234) (xy 127.298369 -296.745274) (xy 127.268639 -296.699312) (xy 127.245788 -296.64957)
			(xy 127.230287 -296.597072) (xy 127.222454 -296.542897) (xy 127.22245 -296.488158) (xy 127.230275 -296.433981)
			(xy 127.245769 -296.38148) (xy 127.268612 -296.331736) (xy 127.298336 -296.28577) (xy 127.315976 -296.264838)
			(xy 127.31623 -296.264584) (xy 127.321833 -296.257509) (xy 127.328069 -296.240583) (xy 127.328422 -296.231564)
			(xy 127.328422 -296.164508) (xy 127.328056 -296.155492) (xy 127.321814 -296.138575) (xy 127.31623 -296.131488)
			(xy 127.315976 -296.131488) (xy 127.315976 -296.131234) (xy 127.298369 -296.110274) (xy 127.268639 -296.064312)
			(xy 127.245788 -296.01457) (xy 127.230287 -295.962072) (xy 127.222454 -295.907897) (xy 127.22245 -295.853158)
			(xy 127.230275 -295.798981) (xy 127.245769 -295.74648) (xy 127.268612 -295.696736) (xy 127.298336 -295.65077)
			(xy 127.315976 -295.629838) (xy 127.31623 -295.629584) (xy 127.321833 -295.622509) (xy 127.328069 -295.605583)
			(xy 127.328422 -295.596564) (xy 127.328422 -295.529508) (xy 127.328056 -295.520492) (xy 127.321814 -295.503575)
			(xy 127.31623 -295.496488) (xy 127.315976 -295.496488) (xy 127.315976 -295.496234) (xy 127.298336 -295.475303)
			(xy 127.268625 -295.42933) (xy 127.24579 -295.379582) (xy 127.230299 -295.327081) (xy 127.22247 -295.272905)
			(xy 127.221996 -295.245536) (xy 127.222489 -295.218284) (xy 127.230241 -295.164334) (xy 127.245593 -295.112036)
			(xy 127.268231 -295.062456) (xy 127.297696 -295.016602) (xy 127.333387 -294.975409) (xy 127.374577 -294.939715)
			(xy 127.420428 -294.910247) (xy 127.470006 -294.887604) (xy 127.522302 -294.872248) (xy 127.576252 -294.864491)
			(xy 127.603504 -294.864028) (xy 127.630875 -294.864485) (xy 127.685054 -294.872304) (xy 127.737558 -294.887795)
			(xy 127.787305 -294.910639) (xy 127.833271 -294.940366) (xy 127.854202 -294.958008) (xy 127.854456 -294.958262)
			(xy 127.861546 -294.963844) (xy 127.87846 -294.970092) (xy 127.887476 -294.970454) (xy 127.954532 -294.970454)
			(xy 127.963552 -294.970122) (xy 127.980469 -294.963858) (xy 127.987552 -294.958262) (xy 127.987552 -294.958008)
			(xy 127.987806 -294.958008) (xy 128.008726 -294.940354) (xy 128.054702 -294.910644) (xy 128.104453 -294.887811)
			(xy 128.156956 -294.872323) (xy 128.211134 -294.8645) (xy 128.238504 -294.864028) (xy 128.265759 -294.864452)
			(xy 128.319713 -294.87221) (xy 128.372014 -294.887569) (xy 128.421596 -294.910214) (xy 128.467451 -294.939686)
			(xy 128.508645 -294.975384) (xy 128.544338 -295.016581) (xy 128.573805 -295.062439) (xy 128.596445 -295.112024)
			(xy 128.611798 -295.164326) (xy 128.619551 -295.218281) (xy 128.620012 -295.245536) (xy 128.619564 -295.272907)
			(xy 128.611741 -295.327087) (xy 128.596248 -295.37959) (xy 128.573402 -295.429336) (xy 128.543675 -295.475303)
			(xy 128.526032 -295.496234) (xy 128.525778 -295.496488) (xy 128.520188 -295.503572) (xy 128.513944 -295.520491)
			(xy 128.513586 -295.529508) (xy 128.513586 -295.596564) (xy 128.513963 -295.605579) (xy 128.520197 -295.622496)
			(xy 128.525778 -295.629584) (xy 128.526032 -295.629584) (xy 128.526032 -295.629838) (xy 128.54371 -295.650741)
			(xy 128.573436 -295.696713) (xy 128.596282 -295.746464) (xy 128.611777 -295.798971) (xy 128.619603 -295.853154)
			(xy 128.619599 -295.9079) (xy 128.611766 -295.962082) (xy 128.596263 -296.014587) (xy 128.57341 -296.064334)
			(xy 128.543677 -296.110302) (xy 128.526032 -296.131234) (xy 128.525778 -296.131488) (xy 128.520188 -296.138572)
			(xy 128.513944 -296.155491) (xy 128.513586 -296.164508) (xy 128.513586 -296.231564) (xy 128.513963 -296.240579)
			(xy 128.520197 -296.257496) (xy 128.525778 -296.264584) (xy 128.526032 -296.264584) (xy 128.526032 -296.264838)
			(xy 128.54371 -296.285741) (xy 128.573436 -296.331713) (xy 128.596282 -296.381464) (xy 128.611777 -296.433971)
			(xy 128.619603 -296.488154) (xy 128.619599 -296.5429) (xy 128.611766 -296.597082) (xy 128.596263 -296.649587)
			(xy 128.57341 -296.699334) (xy 128.543677 -296.745302) (xy 128.526032 -296.766234) (xy 128.525778 -296.766488)
			(xy 128.520188 -296.773572) (xy 128.513944 -296.790491) (xy 128.513586 -296.799508) (xy 128.513586 -296.866564)
			(xy 128.513963 -296.875579) (xy 128.520197 -296.892496) (xy 128.525778 -296.899584) (xy 128.526032 -296.899584)
			(xy 128.526032 -296.899838) (xy 128.54371 -296.920741) (xy 128.573436 -296.966713) (xy 128.596282 -297.016464)
			(xy 128.611777 -297.068971) (xy 128.619603 -297.123154) (xy 128.619599 -297.1779) (xy 128.611766 -297.232082)
			(xy 128.596263 -297.284587) (xy 128.57341 -297.334334) (xy 128.543677 -297.380302) (xy 128.526032 -297.401234)
			(xy 128.525778 -297.401488) (xy 128.520188 -297.408572) (xy 128.513944 -297.425491) (xy 128.513586 -297.434508)
			(xy 128.513586 -297.501564) (xy 128.513963 -297.510579) (xy 128.520197 -297.527496) (xy 128.525778 -297.534584)
			(xy 128.526032 -297.534584) (xy 128.526032 -297.534838) (xy 128.54371 -297.555741) (xy 128.573436 -297.601713)
			(xy 128.596282 -297.651464) (xy 128.611777 -297.703971) (xy 128.619603 -297.758154) (xy 128.619599 -297.8129)
			(xy 128.611766 -297.867082) (xy 128.596263 -297.919587) (xy 128.57341 -297.969334) (xy 128.543677 -298.015302)
			(xy 128.526032 -298.036234) (xy 128.525778 -298.036488) (xy 128.520188 -298.043572) (xy 128.513944 -298.060491)
			(xy 128.513586 -298.069508) (xy 128.513586 -298.136564) (xy 128.513963 -298.145579) (xy 128.520197 -298.162496)
			(xy 128.525778 -298.169584) (xy 128.526032 -298.169584) (xy 128.526032 -298.169838) (xy 128.54366 -298.190779)
			(xy 128.573373 -298.23675) (xy 128.59621 -298.286495) (xy 128.611704 -298.338994) (xy 128.619536 -298.393167)
			(xy 128.620012 -298.420536) (xy 131.862576 -298.420536) (xy 131.863045 -298.393166) (xy 131.870859 -298.338986)
			(xy 131.886346 -298.286482) (xy 131.909188 -298.236735) (xy 131.938914 -298.190769) (xy 131.956556 -298.169838)
			(xy 131.95681 -298.169584) (xy 131.962411 -298.162507) (xy 131.968649 -298.145583) (xy 131.969002 -298.136564)
			(xy 131.969002 -298.069508) (xy 131.968641 -298.060492) (xy 131.962396 -298.043575) (xy 131.95681 -298.036488)
			(xy 131.956556 -298.036488) (xy 131.956556 -298.036234) (xy 131.938949 -298.015273) (xy 131.909221 -297.969311)
			(xy 131.886372 -297.91957) (xy 131.870871 -297.867072) (xy 131.863039 -297.812896) (xy 131.863035 -297.758158)
			(xy 131.87086 -297.703982) (xy 131.886353 -297.651481) (xy 131.909195 -297.601737) (xy 131.938917 -297.55577)
			(xy 131.956556 -297.534838) (xy 131.95681 -297.534584) (xy 131.962411 -297.527507) (xy 131.968649 -297.510583)
			(xy 131.969002 -297.501564) (xy 131.969002 -297.434508) (xy 131.968641 -297.425492) (xy 131.962396 -297.408575)
			(xy 131.95681 -297.401488) (xy 131.956556 -297.401488) (xy 131.956556 -297.401234) (xy 131.938949 -297.380273)
			(xy 131.909221 -297.334311) (xy 131.886372 -297.28457) (xy 131.870871 -297.232072) (xy 131.863039 -297.177896)
			(xy 131.863035 -297.123158) (xy 131.87086 -297.068982) (xy 131.886353 -297.016481) (xy 131.909195 -296.966737)
			(xy 131.938917 -296.92077) (xy 131.956556 -296.899838) (xy 131.95681 -296.899584) (xy 131.962411 -296.892507)
			(xy 131.968649 -296.875583) (xy 131.969002 -296.866564) (xy 131.969002 -296.799508) (xy 131.968641 -296.790492)
			(xy 131.962396 -296.773575) (xy 131.95681 -296.766488) (xy 131.956556 -296.766488) (xy 131.956556 -296.766234)
			(xy 131.938949 -296.745273) (xy 131.909221 -296.699311) (xy 131.886372 -296.64957) (xy 131.870871 -296.597072)
			(xy 131.863039 -296.542896) (xy 131.863035 -296.488158) (xy 131.87086 -296.433982) (xy 131.886353 -296.381481)
			(xy 131.909195 -296.331737) (xy 131.938917 -296.28577) (xy 131.956556 -296.264838) (xy 131.95681 -296.264584)
			(xy 131.962411 -296.257507) (xy 131.968649 -296.240583) (xy 131.969002 -296.231564) (xy 131.969002 -296.164508)
			(xy 131.968641 -296.155492) (xy 131.962396 -296.138575) (xy 131.95681 -296.131488) (xy 131.956556 -296.131488)
			(xy 131.956556 -296.131234) (xy 131.938949 -296.110273) (xy 131.909221 -296.064311) (xy 131.886372 -296.01457)
			(xy 131.870871 -295.962072) (xy 131.863039 -295.907896) (xy 131.863035 -295.853158) (xy 131.87086 -295.798982)
			(xy 131.886353 -295.746481) (xy 131.909195 -295.696737) (xy 131.938917 -295.65077) (xy 131.956556 -295.629838)
			(xy 131.95681 -295.629584) (xy 131.962411 -295.622507) (xy 131.968649 -295.605583) (xy 131.969002 -295.596564)
			(xy 131.969002 -295.529508) (xy 131.968641 -295.520492) (xy 131.962396 -295.503575) (xy 131.95681 -295.496488)
			(xy 131.956556 -295.496488) (xy 131.956556 -295.496234) (xy 131.938912 -295.475306) (xy 131.909202 -295.429331)
			(xy 131.886368 -295.379583) (xy 131.870878 -295.327081) (xy 131.86305 -295.272905) (xy 131.862576 -295.245536)
			(xy 131.863089 -295.218285) (xy 131.87084 -295.164336) (xy 131.886191 -295.11204) (xy 131.908828 -295.062462)
			(xy 131.938291 -295.016609) (xy 131.97398 -294.975416) (xy 132.015167 -294.939722) (xy 132.061016 -294.910253)
			(xy 132.110592 -294.887609) (xy 132.162886 -294.872251) (xy 132.216833 -294.864492) (xy 132.244084 -294.864028)
			(xy 132.271454 -294.864497) (xy 132.325633 -294.872313) (xy 132.378137 -294.887801) (xy 132.427884 -294.910642)
			(xy 132.47385 -294.940367) (xy 132.494782 -294.958008) (xy 132.495036 -294.958262) (xy 132.502131 -294.963835)
			(xy 132.519042 -294.970088) (xy 132.528056 -294.970454) (xy 132.595112 -294.970454) (xy 132.604131 -294.970113)
			(xy 132.621048 -294.963856) (xy 132.628132 -294.958262) (xy 132.628132 -294.958008) (xy 132.628386 -294.958008)
			(xy 132.649314 -294.940363) (xy 132.695287 -294.910652) (xy 132.745036 -294.887817) (xy 132.797538 -294.872327)
			(xy 132.851714 -294.864501) (xy 132.879084 -294.864028) (xy 132.906338 -294.86447) (xy 132.960292 -294.872226)
			(xy 133.012592 -294.887582) (xy 133.062175 -294.910225) (xy 133.108029 -294.939695) (xy 133.149223 -294.975391)
			(xy 133.184917 -295.016587) (xy 133.214384 -295.062443) (xy 133.237025 -295.112027) (xy 133.252378 -295.164328)
			(xy 133.260131 -295.218282) (xy 133.260592 -295.245536) (xy 133.260149 -295.272907) (xy 133.252326 -295.327087)
			(xy 133.236832 -295.379591) (xy 133.213985 -295.429337) (xy 133.184255 -295.475303) (xy 133.166612 -295.496234)
			(xy 133.166358 -295.496488) (xy 133.160765 -295.50357) (xy 133.154523 -295.52049) (xy 133.154166 -295.529508)
			(xy 133.154166 -295.596564) (xy 133.154548 -295.605578) (xy 133.160779 -295.622495) (xy 133.166358 -295.629584)
			(xy 133.166612 -295.629584) (xy 133.166612 -295.629838) (xy 133.184286 -295.650743) (xy 133.214007 -295.696717)
			(xy 133.236848 -295.746468) (xy 133.252339 -295.798974) (xy 133.260164 -295.853155) (xy 133.26016 -295.907899)
			(xy 133.252328 -295.962079) (xy 133.236828 -296.014583) (xy 133.213981 -296.064331) (xy 133.184254 -296.1103)
			(xy 133.166612 -296.131234) (xy 133.166358 -296.131488) (xy 133.160765 -296.13857) (xy 133.154523 -296.15549)
			(xy 133.154166 -296.164508) (xy 133.154166 -296.231564) (xy 133.154548 -296.240578) (xy 133.160779 -296.257495)
			(xy 133.166358 -296.264584) (xy 133.166612 -296.264584) (xy 133.166612 -296.264838) (xy 133.184286 -296.285743)
			(xy 133.214007 -296.331717) (xy 133.236848 -296.381468) (xy 133.252339 -296.433974) (xy 133.260164 -296.488155)
			(xy 133.26016 -296.542899) (xy 133.252328 -296.597079) (xy 133.236828 -296.649583) (xy 133.213981 -296.699331)
			(xy 133.184254 -296.7453) (xy 133.166612 -296.766234) (xy 133.166358 -296.766488) (xy 133.160765 -296.77357)
			(xy 133.154523 -296.79049) (xy 133.154166 -296.799508) (xy 133.154166 -296.866564) (xy 133.154548 -296.875578)
			(xy 133.160779 -296.892495) (xy 133.166358 -296.899584) (xy 133.166612 -296.899584) (xy 133.166612 -296.899838)
			(xy 133.184286 -296.920743) (xy 133.214007 -296.966717) (xy 133.236848 -297.016468) (xy 133.252339 -297.068974)
			(xy 133.260164 -297.123155) (xy 133.26016 -297.177899) (xy 133.252328 -297.232079) (xy 133.236828 -297.284583)
			(xy 133.213981 -297.334331) (xy 133.184254 -297.3803) (xy 133.166612 -297.401234) (xy 133.166358 -297.401488)
			(xy 133.160765 -297.40857) (xy 133.154523 -297.42549) (xy 133.154166 -297.434508) (xy 133.154166 -297.501564)
			(xy 133.154548 -297.510578) (xy 133.160779 -297.527495) (xy 133.166358 -297.534584) (xy 133.166612 -297.534584)
			(xy 133.166612 -297.534838) (xy 133.184286 -297.555743) (xy 133.214007 -297.601717) (xy 133.236848 -297.651468)
			(xy 133.252339 -297.703974) (xy 133.260164 -297.758155) (xy 133.26016 -297.812899) (xy 133.252328 -297.867079)
			(xy 133.236828 -297.919583) (xy 133.213981 -297.969331) (xy 133.184254 -298.0153) (xy 133.166612 -298.036234)
			(xy 133.166358 -298.036488) (xy 133.160765 -298.04357) (xy 133.154523 -298.06049) (xy 133.154166 -298.069508)
			(xy 133.154166 -298.136564) (xy 133.154548 -298.145578) (xy 133.160779 -298.162495) (xy 133.166358 -298.169584)
			(xy 133.166612 -298.169584) (xy 133.166612 -298.169838) (xy 133.184237 -298.190781) (xy 133.213951 -298.236751)
			(xy 133.236789 -298.286496) (xy 133.252284 -298.338994) (xy 133.260116 -298.393168) (xy 133.260592 -298.420536)
			(xy 133.260156 -298.447789) (xy 133.252394 -298.501739) (xy 133.237033 -298.554036) (xy 133.214387 -298.603614)
			(xy 133.184915 -298.649465) (xy 133.149219 -298.690655) (xy 133.108024 -298.726346) (xy 133.062169 -298.755812)
			(xy 133.012587 -298.778451) (xy 132.960288 -298.793805) (xy 132.906337 -298.801559) (xy 132.879084 -298.802044)
			(xy 132.851713 -298.801601) (xy 132.797532 -298.79378) (xy 132.745028 -298.778286) (xy 132.695282 -298.755439)
			(xy 132.649316 -298.725708) (xy 132.628386 -298.708064) (xy 132.628132 -298.70781) (xy 132.62104 -298.702232)
			(xy 132.604127 -298.69598) (xy 132.595112 -298.695618) (xy 132.528056 -298.695618) (xy 132.519041 -298.695998)
			(xy 132.502124 -298.702229) (xy 132.495036 -298.70781) (xy 132.495036 -298.708064) (xy 132.494782 -298.708064)
			(xy 132.473825 -298.725673) (xy 132.42786 -298.75539) (xy 132.378119 -298.778233) (xy 132.325623 -298.793731)
			(xy 132.271452 -298.801566) (xy 132.244084 -298.802044) (xy 132.216834 -298.801537) (xy 132.162889 -298.793779)
			(xy 132.110597 -298.778424) (xy 132.061022 -298.755784) (xy 132.015173 -298.726319) (xy 131.973984 -298.69063)
			(xy 131.938293 -298.649443) (xy 131.908826 -298.603596) (xy 131.886183 -298.554022) (xy 131.870825 -298.501731)
			(xy 131.863064 -298.447786) (xy 131.862576 -298.420536) (xy 128.620012 -298.420536) (xy 128.619556 -298.447788)
			(xy 128.611794 -298.501737) (xy 128.596435 -298.554032) (xy 128.57379 -298.603609) (xy 128.54432 -298.649459)
			(xy 128.508626 -298.690648) (xy 128.467433 -298.726339) (xy 128.421581 -298.755805) (xy 128.372002 -298.778446)
			(xy 128.319705 -298.793801) (xy 128.265756 -298.801558) (xy 128.238504 -298.802044) (xy 128.211133 -298.801589)
			(xy 128.156953 -298.793771) (xy 128.104449 -298.77828) (xy 128.054703 -298.755435) (xy 128.008737 -298.725707)
			(xy 127.987806 -298.708064) (xy 127.987552 -298.70781) (xy 127.980454 -298.70224) (xy 127.963546 -298.695983)
			(xy 127.954532 -298.695618) (xy 127.887476 -298.695618) (xy 127.878457 -298.69596) (xy 127.86154 -298.702217)
			(xy 127.854456 -298.70781) (xy 127.854456 -298.708064) (xy 127.854202 -298.708064) (xy 127.833275 -298.72571)
			(xy 127.787302 -298.755422) (xy 127.737553 -298.778257) (xy 127.685051 -298.793747) (xy 127.630874 -298.801572)
			(xy 127.603504 -298.802044) (xy 127.576254 -298.801519) (xy 127.52231 -298.793764) (xy 127.470018 -298.778411)
			(xy 127.420443 -298.755773) (xy 127.374595 -298.72631) (xy 127.333405 -298.690623) (xy 127.297714 -298.649437)
			(xy 127.268246 -298.603592) (xy 127.245603 -298.554019) (xy 127.230245 -298.501729) (xy 127.222484 -298.447785)
			(xy 127.221996 -298.420536) (xy 126.19228 -298.420536) (xy 126.191856 -298.447789) (xy 126.184093 -298.501741)
			(xy 126.168732 -298.554038) (xy 126.146085 -298.603618) (xy 126.116612 -298.649469) (xy 126.080914 -298.69066)
			(xy 126.039718 -298.726351) (xy 125.993861 -298.755816) (xy 125.944278 -298.778455) (xy 125.891978 -298.793807)
			(xy 125.838025 -298.80156) (xy 125.810772 -298.802044) (xy 125.783401 -298.801608) (xy 125.72922 -298.793785)
			(xy 125.676716 -298.77829) (xy 125.626969 -298.755441) (xy 125.581004 -298.725709) (xy 125.560074 -298.708064)
			(xy 125.55982 -298.70781) (xy 125.552731 -298.702227) (xy 125.535816 -298.695978) (xy 125.5268 -298.695618)
			(xy 125.459744 -298.695618) (xy 125.450729 -298.695992) (xy 125.433812 -298.702228) (xy 125.426724 -298.70781)
			(xy 125.426724 -298.708064) (xy 125.42647 -298.708064) (xy 125.405518 -298.725678) (xy 125.359551 -298.755395)
			(xy 125.309809 -298.778236) (xy 125.257312 -298.793733) (xy 125.20314 -298.801567) (xy 125.175772 -298.802044)
			(xy 125.148522 -298.801548) (xy 125.094576 -298.793789) (xy 125.042284 -298.778432) (xy 124.992709 -298.75579)
			(xy 124.94686 -298.726324) (xy 124.905671 -298.690634) (xy 124.86998 -298.649446) (xy 124.840514 -298.603598)
			(xy 124.817871 -298.554024) (xy 124.802513 -298.501732) (xy 124.794752 -298.447786) (xy 124.794264 -298.420536)
			(xy 121.5517 -298.420536) (xy 121.551256 -298.447789) (xy 121.543494 -298.501738) (xy 121.528134 -298.554034)
			(xy 121.505488 -298.603612) (xy 121.476017 -298.649463) (xy 121.440321 -298.690653) (xy 121.399127 -298.726344)
			(xy 121.353273 -298.755809) (xy 121.303693 -298.778449) (xy 121.251395 -298.793803) (xy 121.197445 -298.801559)
			(xy 121.170192 -298.802044) (xy 121.142821 -298.801596) (xy 121.088641 -298.793776) (xy 121.036137 -298.778284)
			(xy 120.98639 -298.755437) (xy 120.940425 -298.725708) (xy 120.919494 -298.708064) (xy 120.91924 -298.70781)
			(xy 120.912145 -298.702235) (xy 120.895235 -298.695981) (xy 120.88622 -298.695618) (xy 120.819164 -298.695618)
			(xy 120.810145 -298.695954) (xy 120.793228 -298.702216) (xy 120.786144 -298.70781) (xy 120.786144 -298.708064)
			(xy 120.78589 -298.708064) (xy 120.764968 -298.725716) (xy 120.718993 -298.755427) (xy 120.669243 -298.778261)
			(xy 120.61674 -298.793749) (xy 120.562562 -298.801573) (xy 120.535192 -298.802044) (xy 120.507942 -298.80153)
			(xy 120.453997 -298.793773) (xy 120.401705 -298.778419) (xy 120.35213 -298.755779) (xy 120.306282 -298.726316)
			(xy 120.265093 -298.690627) (xy 120.229401 -298.649441) (xy 120.199934 -298.603594) (xy 120.177291 -298.554021)
			(xy 120.161933 -298.50173) (xy 120.154172 -298.447786) (xy 120.153684 -298.420536) (xy 116.601494 -298.420536)
			(xy 116.601056 -298.447789) (xy 116.593294 -298.501739) (xy 116.577933 -298.554035) (xy 116.555287 -298.603614)
			(xy 116.525816 -298.649465) (xy 116.490119 -298.690655) (xy 116.448925 -298.726346) (xy 116.40307 -298.755811)
			(xy 116.353488 -298.778451) (xy 116.30119 -298.793805) (xy 116.247239 -298.801559) (xy 116.219986 -298.802044)
			(xy 116.192615 -298.8016) (xy 116.138434 -298.793779) (xy 116.08593 -298.778285) (xy 116.036184 -298.755438)
			(xy 115.990218 -298.725708) (xy 115.969288 -298.708064) (xy 115.969034 -298.70781) (xy 115.961941 -298.702233)
			(xy 115.945029 -298.69598) (xy 115.936014 -298.695618) (xy 115.868958 -298.695618) (xy 115.859943 -298.695999)
			(xy 115.843026 -298.70223) (xy 115.835938 -298.70781) (xy 115.835938 -298.708064) (xy 115.835684 -298.708064)
			(xy 115.814726 -298.725672) (xy 115.768761 -298.755389) (xy 115.71902 -298.778232) (xy 115.666525 -298.79373)
			(xy 115.612354 -298.801566) (xy 115.584986 -298.802044) (xy 115.557736 -298.801535) (xy 115.503791 -298.793778)
			(xy 115.451499 -298.778423) (xy 115.401924 -298.755783) (xy 115.356075 -298.726318) (xy 115.314886 -298.690629)
			(xy 115.279195 -298.649442) (xy 115.249728 -298.603595) (xy 115.227085 -298.554022) (xy 115.211727 -298.501731)
			(xy 115.203966 -298.447786) (xy 115.203478 -298.420536) (xy 111.960914 -298.420536) (xy 111.960456 -298.447788)
			(xy 111.952694 -298.501736) (xy 111.937335 -298.554031) (xy 111.91469 -298.603608) (xy 111.885221 -298.649458)
			(xy 111.849526 -298.690648) (xy 111.808334 -298.726339) (xy 111.762482 -298.755805) (xy 111.712903 -298.778446)
			(xy 111.660607 -298.793801) (xy 111.606658 -298.801558) (xy 111.579406 -298.802044) (xy 111.552035 -298.801588)
			(xy 111.497855 -298.79377) (xy 111.445351 -298.778279) (xy 111.395605 -298.755435) (xy 111.349639 -298.725707)
			(xy 111.328708 -298.708064) (xy 111.328454 -298.70781) (xy 111.321355 -298.702241) (xy 111.304448 -298.695983)
			(xy 111.295434 -298.695618) (xy 111.228378 -298.695618) (xy 111.21936 -298.695961) (xy 111.202443 -298.702218)
			(xy 111.195358 -298.70781) (xy 111.195358 -298.708064) (xy 111.195104 -298.708064) (xy 111.174177 -298.725709)
			(xy 111.128203 -298.755421) (xy 111.078454 -298.778257) (xy 111.025953 -298.793746) (xy 110.971776 -298.801572)
			(xy 110.944406 -298.802044) (xy 110.917157 -298.801517) (xy 110.863212 -298.793762) (xy 110.81092 -298.778409)
			(xy 110.761346 -298.755772) (xy 110.715497 -298.726309) (xy 110.674308 -298.690622) (xy 110.638616 -298.649437)
			(xy 110.609149 -298.603591) (xy 110.586505 -298.554019) (xy 110.571147 -298.501729) (xy 110.563386 -298.447785)
			(xy 110.562898 -298.420536) (xy 109.533182 -298.420536) (xy 109.532756 -298.447789) (xy 109.524994 -298.501741)
			(xy 109.509633 -298.554038) (xy 109.486985 -298.603617) (xy 109.457513 -298.649469) (xy 109.421815 -298.690659)
			(xy 109.380619 -298.72635) (xy 109.334763 -298.755815) (xy 109.28518 -298.778454) (xy 109.23288 -298.793807)
			(xy 109.178927 -298.80156) (xy 109.151674 -298.802044) (xy 109.124303 -298.801607) (xy 109.070122 -298.793784)
			(xy 109.017618 -298.778289) (xy 108.967871 -298.755441) (xy 108.921906 -298.725709) (xy 108.900976 -298.708064)
			(xy 108.900722 -298.70781) (xy 108.893632 -298.702228) (xy 108.876718 -298.695978) (xy 108.867702 -298.695618)
			(xy 108.800646 -298.695618) (xy 108.791631 -298.695993) (xy 108.774714 -298.702228) (xy 108.767626 -298.70781)
			(xy 108.767626 -298.708064) (xy 108.767372 -298.708064) (xy 108.746419 -298.725677) (xy 108.700452 -298.755394)
			(xy 108.65071 -298.778236) (xy 108.598214 -298.793733) (xy 108.544042 -298.801567) (xy 108.516674 -298.802044)
			(xy 108.489424 -298.801546) (xy 108.435478 -298.793787) (xy 108.383186 -298.778431) (xy 108.333611 -298.755789)
			(xy 108.287763 -298.726324) (xy 108.246574 -298.690634) (xy 108.210882 -298.649445) (xy 108.181416 -298.603598)
			(xy 108.158773 -298.554023) (xy 108.143415 -298.501731) (xy 108.135654 -298.447786) (xy 108.135166 -298.420536)
			(xy 104.892602 -298.420536) (xy 104.892156 -298.447788) (xy 104.884394 -298.501738) (xy 104.869034 -298.554034)
			(xy 104.846388 -298.603611) (xy 104.816918 -298.649462) (xy 104.781222 -298.690652) (xy 104.740028 -298.726343)
			(xy 104.694175 -298.755808) (xy 104.644594 -298.778449) (xy 104.592297 -298.793803) (xy 104.538346 -298.801559)
			(xy 104.511094 -298.802044) (xy 104.483723 -298.801595) (xy 104.429543 -298.793775) (xy 104.377039 -298.778283)
			(xy 104.327292 -298.755437) (xy 104.281327 -298.725708) (xy 104.260396 -298.708064) (xy 104.260142 -298.70781)
			(xy 104.253047 -298.702236) (xy 104.236137 -298.695981) (xy 104.227122 -298.695618) (xy 104.160066 -298.695618)
			(xy 104.151047 -298.695955) (xy 104.13413 -298.702216) (xy 104.127046 -298.70781) (xy 104.127046 -298.708064)
			(xy 104.126792 -298.708064) (xy 104.105869 -298.725715) (xy 104.059894 -298.755426) (xy 104.010145 -298.77826)
			(xy 103.957642 -298.793749) (xy 103.903464 -298.801573) (xy 103.876094 -298.802044) (xy 103.848844 -298.801528)
			(xy 103.794899 -298.793772) (xy 103.742607 -298.778417) (xy 103.693033 -298.755778) (xy 103.647184 -298.726315)
			(xy 103.605995 -298.690626) (xy 103.570303 -298.64944) (xy 103.540836 -298.603594) (xy 103.518193 -298.554021)
			(xy 103.502835 -298.50173) (xy 103.495074 -298.447786) (xy 103.494586 -298.420536) (xy 98.74377 -298.420536)
			(xy 98.74377 -301.424086) (xy 102.823518 -301.424086) (xy 102.823971 -301.396715) (xy 102.831792 -301.342535)
			(xy 102.847283 -301.290032) (xy 102.870128 -301.240285) (xy 102.899855 -301.194319) (xy 102.917498 -301.173388)
			(xy 102.917752 -301.173134) (xy 102.923337 -301.166046) (xy 102.929583 -301.14913) (xy 102.929944 -301.140114)
			(xy 102.929944 -301.073058) (xy 102.929572 -301.064042) (xy 102.923336 -301.047125) (xy 102.917752 -301.040038)
			(xy 102.917498 -301.040038) (xy 102.917498 -301.039784) (xy 102.899845 -301.018862) (xy 102.870123 -300.972891)
			(xy 102.84728 -300.923143) (xy 102.831786 -300.87064) (xy 102.823959 -300.81646) (xy 102.823961 -300.761719)
			(xy 102.831791 -300.707539) (xy 102.847287 -300.655037) (xy 102.870133 -300.60529) (xy 102.899858 -300.559321)
			(xy 102.917498 -300.538388) (xy 102.917752 -300.538134) (xy 102.923337 -300.531046) (xy 102.929583 -300.51413)
			(xy 102.929944 -300.505114) (xy 102.929944 -300.438058) (xy 102.929572 -300.429042) (xy 102.923336 -300.412125)
			(xy 102.917752 -300.405038) (xy 102.917498 -300.405038) (xy 102.917498 -300.404784) (xy 102.899845 -300.383862)
			(xy 102.870123 -300.337891) (xy 102.84728 -300.288143) (xy 102.831786 -300.23564) (xy 102.823959 -300.18146)
			(xy 102.823961 -300.126719) (xy 102.831791 -300.072539) (xy 102.847287 -300.020037) (xy 102.870133 -299.97029)
			(xy 102.899858 -299.924321) (xy 102.917498 -299.903388) (xy 102.917752 -299.903134) (xy 102.923337 -299.896046)
			(xy 102.929583 -299.87913) (xy 102.929944 -299.870114) (xy 102.929944 -299.803058) (xy 102.929572 -299.794042)
			(xy 102.923336 -299.777125) (xy 102.917752 -299.770038) (xy 102.917498 -299.770038) (xy 102.917498 -299.769784)
			(xy 102.899885 -299.748831) (xy 102.870169 -299.702864) (xy 102.847328 -299.653122) (xy 102.831831 -299.600626)
			(xy 102.823996 -299.546454) (xy 102.823518 -299.519086) (xy 102.824004 -299.491835) (xy 102.83176 -299.437887)
			(xy 102.847115 -299.385592) (xy 102.869757 -299.336015) (xy 102.899223 -299.290165) (xy 102.934914 -299.248974)
			(xy 102.976105 -299.213283) (xy 103.021955 -299.183817) (xy 103.071532 -299.161175) (xy 103.123827 -299.14582)
			(xy 103.177775 -299.138064) (xy 103.232277 -299.138064) (xy 103.286225 -299.14582) (xy 103.33852 -299.161175)
			(xy 103.388097 -299.183817) (xy 103.433947 -299.213283) (xy 103.475138 -299.248974) (xy 103.510829 -299.290165)
			(xy 103.540295 -299.336015) (xy 103.562937 -299.385592) (xy 103.578292 -299.437887) (xy 103.586048 -299.491835)
			(xy 103.586534 -299.519086) (xy 103.586076 -299.546457) (xy 103.578259 -299.600637) (xy 103.562769 -299.653141)
			(xy 103.539925 -299.702887) (xy 103.510197 -299.748853) (xy 103.492554 -299.769784) (xy 103.4923 -299.770038)
			(xy 103.486733 -299.777138) (xy 103.480475 -299.794045) (xy 103.480108 -299.803058) (xy 103.480108 -299.870114)
			(xy 103.480457 -299.879132) (xy 103.48671 -299.896049) (xy 103.4923 -299.903134) (xy 103.492554 -299.903134)
			(xy 103.492554 -299.903388) (xy 103.510182 -299.924331) (xy 103.539909 -299.970297) (xy 103.562756 -300.020041)
			(xy 103.578254 -300.072542) (xy 103.586084 -300.126719) (xy 103.586086 -300.18146) (xy 103.578259 -300.235637)
			(xy 103.562763 -300.288139) (xy 103.539919 -300.337885) (xy 103.510194 -300.383852) (xy 103.492554 -300.404784)
			(xy 103.4923 -300.405038) (xy 103.486733 -300.412138) (xy 103.480475 -300.429045) (xy 103.480108 -300.438058)
			(xy 103.480108 -300.505114) (xy 103.480457 -300.514132) (xy 103.48671 -300.531049) (xy 103.4923 -300.538134)
			(xy 103.492554 -300.538134) (xy 103.492554 -300.538388) (xy 103.510182 -300.559331) (xy 103.539909 -300.605297)
			(xy 103.562756 -300.655041) (xy 103.578254 -300.707542) (xy 103.586084 -300.761719) (xy 103.586086 -300.81646)
			(xy 103.578259 -300.870637) (xy 103.562763 -300.923139) (xy 103.539919 -300.972885) (xy 103.510194 -301.018852)
			(xy 103.492554 -301.039784) (xy 103.4923 -301.040038) (xy 103.486733 -301.047138) (xy 103.480475 -301.064045)
			(xy 103.480108 -301.073058) (xy 103.480108 -301.140114) (xy 103.480457 -301.149132) (xy 103.48671 -301.166049)
			(xy 103.4923 -301.173134) (xy 103.492554 -301.173134) (xy 103.492554 -301.173388) (xy 103.510194 -301.19432)
			(xy 103.539907 -301.240292) (xy 103.562744 -301.290039) (xy 103.578234 -301.34254) (xy 103.586061 -301.396717)
			(xy 103.586534 -301.424086) (xy 103.586048 -301.451337) (xy 103.582224 -301.477934) (xy 106.455718 -301.477934)
			(xy 106.4562 -301.450564) (xy 106.464013 -301.396386) (xy 106.479498 -301.343883) (xy 106.502337 -301.294135)
			(xy 106.532058 -301.248168) (xy 106.549698 -301.227236) (xy 106.549952 -301.226982) (xy 106.555558 -301.219909)
			(xy 106.561792 -301.202982) (xy 106.562144 -301.193962) (xy 106.562144 -301.126906) (xy 106.561796 -301.117888)
			(xy 106.555543 -301.10097) (xy 106.549952 -301.093886) (xy 106.549698 -301.093886) (xy 106.549698 -301.093632)
			(xy 106.532092 -301.072672) (xy 106.502368 -301.026708) (xy 106.479522 -300.976966) (xy 106.464025 -300.924469)
			(xy 106.456193 -300.870294) (xy 106.45619 -300.815557) (xy 106.464014 -300.761382) (xy 106.479504 -300.708882)
			(xy 106.502343 -300.659137) (xy 106.532061 -300.613169) (xy 106.549698 -300.592236) (xy 106.549952 -300.591982)
			(xy 106.555558 -300.584909) (xy 106.561792 -300.567982) (xy 106.562144 -300.558962) (xy 106.562144 -300.491906)
			(xy 106.561796 -300.482888) (xy 106.555543 -300.46597) (xy 106.549952 -300.458886) (xy 106.549698 -300.458886)
			(xy 106.549698 -300.458632) (xy 106.532092 -300.437672) (xy 106.502368 -300.391708) (xy 106.479522 -300.341966)
			(xy 106.464025 -300.289469) (xy 106.456193 -300.235294) (xy 106.45619 -300.180557) (xy 106.464014 -300.126382)
			(xy 106.479504 -300.073882) (xy 106.502343 -300.024137) (xy 106.532061 -299.978169) (xy 106.549698 -299.957236)
			(xy 106.549952 -299.956982) (xy 106.555558 -299.949909) (xy 106.561792 -299.932982) (xy 106.562144 -299.923962)
			(xy 106.562144 -299.856906) (xy 106.561796 -299.847888) (xy 106.555543 -299.83097) (xy 106.549952 -299.823886)
			(xy 106.549698 -299.823886) (xy 106.549698 -299.823632) (xy 106.53206 -299.802699) (xy 106.502348 -299.756726)
			(xy 106.479512 -299.706979) (xy 106.464021 -299.654479) (xy 106.456192 -299.600303) (xy 106.455718 -299.572934)
			(xy 106.456204 -299.545683) (xy 106.46396 -299.491735) (xy 106.479315 -299.43944) (xy 106.501957 -299.389863)
			(xy 106.531423 -299.344013) (xy 106.567114 -299.302822) (xy 106.608305 -299.267131) (xy 106.654155 -299.237665)
			(xy 106.703732 -299.215023) (xy 106.756027 -299.199668) (xy 106.809975 -299.191912) (xy 106.864477 -299.191912)
			(xy 106.918425 -299.199668) (xy 106.97072 -299.215023) (xy 107.020297 -299.237665) (xy 107.066147 -299.267131)
			(xy 107.107338 -299.302822) (xy 107.143029 -299.344013) (xy 107.172495 -299.389863) (xy 107.195137 -299.43944)
			(xy 107.210492 -299.491735) (xy 107.218248 -299.545683) (xy 107.218734 -299.572934) (xy 107.218304 -299.600306)
			(xy 107.21048 -299.654487) (xy 107.194983 -299.706991) (xy 107.172133 -299.756737) (xy 107.1424 -299.802702)
			(xy 107.124754 -299.823632) (xy 107.1245 -299.823886) (xy 107.118913 -299.830972) (xy 107.112667 -299.847889)
			(xy 107.112308 -299.856906) (xy 107.112308 -299.923962) (xy 107.112682 -299.932977) (xy 107.118918 -299.949894)
			(xy 107.1245 -299.956982) (xy 107.124754 -299.956982) (xy 107.124754 -299.957236) (xy 107.142429 -299.978141)
			(xy 107.172154 -300.024113) (xy 107.194998 -300.073864) (xy 107.210493 -300.126371) (xy 107.218318 -300.180553)
			(xy 107.218315 -300.235298) (xy 107.210482 -300.28948) (xy 107.19498 -300.341984) (xy 107.172129 -300.391732)
			(xy 107.142398 -300.4377) (xy 107.124754 -300.458632) (xy 107.1245 -300.458886) (xy 107.118913 -300.465972)
			(xy 107.112667 -300.482889) (xy 107.112308 -300.491906) (xy 107.112308 -300.558962) (xy 107.112682 -300.567977)
			(xy 107.118918 -300.584894) (xy 107.1245 -300.591982) (xy 107.124754 -300.591982) (xy 107.124754 -300.592236)
			(xy 107.142429 -300.613141) (xy 107.172154 -300.659113) (xy 107.194998 -300.708864) (xy 107.210493 -300.761371)
			(xy 107.218318 -300.815553) (xy 107.218315 -300.870298) (xy 107.210482 -300.92448) (xy 107.19498 -300.976984)
			(xy 107.172129 -301.026732) (xy 107.142398 -301.0727) (xy 107.124754 -301.093632) (xy 107.1245 -301.093886)
			(xy 107.118913 -301.100972) (xy 107.112667 -301.117889) (xy 107.112308 -301.126906) (xy 107.112308 -301.193962)
			(xy 107.112682 -301.202977) (xy 107.118918 -301.219894) (xy 107.1245 -301.226982) (xy 107.124754 -301.226982)
			(xy 107.124754 -301.227236) (xy 107.142369 -301.248187) (xy 107.172086 -301.294154) (xy 107.194928 -301.343897)
			(xy 107.210424 -301.396393) (xy 107.214428 -301.424086) (xy 109.663738 -301.424086) (xy 109.664187 -301.396715)
			(xy 109.672007 -301.342535) (xy 109.6875 -301.290031) (xy 109.710346 -301.240285) (xy 109.740075 -301.194319)
			(xy 109.757718 -301.173388) (xy 109.757972 -301.173134) (xy 109.763559 -301.166048) (xy 109.769803 -301.149131)
			(xy 109.770164 -301.140114) (xy 109.770164 -301.073058) (xy 109.769787 -301.064043) (xy 109.763554 -301.047125)
			(xy 109.757972 -301.040038) (xy 109.757718 -301.040038) (xy 109.757718 -301.039784) (xy 109.740064 -301.018862)
			(xy 109.71034 -300.972892) (xy 109.687496 -300.923144) (xy 109.672002 -300.870641) (xy 109.664175 -300.816461)
			(xy 109.664176 -300.761718) (xy 109.672006 -300.707539) (xy 109.687504 -300.655036) (xy 109.710351 -300.605289)
			(xy 109.740077 -300.559321) (xy 109.757718 -300.538388) (xy 109.757972 -300.538134) (xy 109.763559 -300.531048)
			(xy 109.769803 -300.514131) (xy 109.770164 -300.505114) (xy 109.770164 -300.438058) (xy 109.769787 -300.429043)
			(xy 109.763554 -300.412125) (xy 109.757972 -300.405038) (xy 109.757718 -300.405038) (xy 109.757718 -300.404784)
			(xy 109.740064 -300.383862) (xy 109.71034 -300.337892) (xy 109.687496 -300.288144) (xy 109.672002 -300.235641)
			(xy 109.664175 -300.181461) (xy 109.664176 -300.126718) (xy 109.672006 -300.072539) (xy 109.687504 -300.020036)
			(xy 109.710351 -299.970289) (xy 109.740077 -299.924321) (xy 109.757718 -299.903388) (xy 109.757972 -299.903134)
			(xy 109.763559 -299.896048) (xy 109.769803 -299.879131) (xy 109.770164 -299.870114) (xy 109.770164 -299.803058)
			(xy 109.769787 -299.794043) (xy 109.763554 -299.777125) (xy 109.757972 -299.770038) (xy 109.757718 -299.770038)
			(xy 109.757718 -299.769784) (xy 109.740108 -299.748829) (xy 109.710391 -299.702863) (xy 109.687549 -299.653121)
			(xy 109.672051 -299.600625) (xy 109.664216 -299.546454) (xy 109.663738 -299.519086) (xy 109.664224 -299.491835)
			(xy 109.67198 -299.437887) (xy 109.687335 -299.385592) (xy 109.709977 -299.336015) (xy 109.739443 -299.290165)
			(xy 109.775134 -299.248974) (xy 109.816325 -299.213283) (xy 109.862175 -299.183817) (xy 109.911752 -299.161175)
			(xy 109.964047 -299.14582) (xy 110.017995 -299.138064) (xy 110.072497 -299.138064) (xy 110.126445 -299.14582)
			(xy 110.17874 -299.161175) (xy 110.228317 -299.183817) (xy 110.274167 -299.213283) (xy 110.315358 -299.248974)
			(xy 110.351049 -299.290165) (xy 110.380515 -299.336015) (xy 110.403157 -299.385592) (xy 110.418512 -299.437887)
			(xy 110.426268 -299.491835) (xy 110.426754 -299.519086) (xy 110.426291 -299.546456) (xy 110.418474 -299.600636)
			(xy 110.402985 -299.65314) (xy 110.380142 -299.702887) (xy 110.350416 -299.748853) (xy 110.332774 -299.769784)
			(xy 110.33252 -299.770038) (xy 110.326944 -299.777131) (xy 110.320693 -299.794043) (xy 110.320328 -299.803058)
			(xy 110.320328 -299.870114) (xy 110.320672 -299.879132) (xy 110.326928 -299.89605) (xy 110.33252 -299.903134)
			(xy 110.332774 -299.903134) (xy 110.332774 -299.903388) (xy 110.350401 -299.924332) (xy 110.380126 -299.970298)
			(xy 110.402972 -300.020042) (xy 110.41847 -300.072543) (xy 110.4263 -300.12672) (xy 110.426301 -300.181459)
			(xy 110.418474 -300.235637) (xy 110.40298 -300.288138) (xy 110.380136 -300.337884) (xy 110.350414 -300.383851)
			(xy 110.332774 -300.404784) (xy 110.33252 -300.405038) (xy 110.326944 -300.412131) (xy 110.320693 -300.429043)
			(xy 110.320328 -300.438058) (xy 110.320328 -300.505114) (xy 110.320672 -300.514132) (xy 110.326928 -300.53105)
			(xy 110.33252 -300.538134) (xy 110.332774 -300.538134) (xy 110.332774 -300.538388) (xy 110.350401 -300.559332)
			(xy 110.380126 -300.605298) (xy 110.402972 -300.655042) (xy 110.41847 -300.707543) (xy 110.4263 -300.76172)
			(xy 110.426301 -300.816459) (xy 110.418474 -300.870637) (xy 110.40298 -300.923138) (xy 110.380136 -300.972884)
			(xy 110.350414 -301.018851) (xy 110.332774 -301.039784) (xy 110.33252 -301.040038) (xy 110.326944 -301.047131)
			(xy 110.320693 -301.064043) (xy 110.320328 -301.073058) (xy 110.320328 -301.140114) (xy 110.320672 -301.149132)
			(xy 110.326928 -301.16605) (xy 110.33252 -301.173134) (xy 110.332774 -301.173134) (xy 110.332774 -301.173388)
			(xy 110.350417 -301.194317) (xy 110.380129 -301.24029) (xy 110.402965 -301.290039) (xy 110.418455 -301.34254)
			(xy 110.426281 -301.396717) (xy 110.426754 -301.424086) (xy 110.426268 -301.451337) (xy 110.422444 -301.477934)
			(xy 113.295938 -301.477934) (xy 113.296415 -301.450564) (xy 113.304229 -301.396385) (xy 113.319715 -301.343882)
			(xy 113.342554 -301.294135) (xy 113.372277 -301.248168) (xy 113.389918 -301.227236) (xy 113.390172 -301.226982)
			(xy 113.395781 -301.219911) (xy 113.402012 -301.202982) (xy 113.402364 -301.193962) (xy 113.402364 -301.126906)
			(xy 113.402012 -301.117889) (xy 113.395762 -301.100971) (xy 113.390172 -301.093886) (xy 113.389918 -301.093886)
			(xy 113.389918 -301.093632) (xy 113.372311 -301.072672) (xy 113.342586 -301.026709) (xy 113.319739 -300.976967)
			(xy 113.30424 -300.924469) (xy 113.296409 -300.870294) (xy 113.296405 -300.815557) (xy 113.304229 -300.761381)
			(xy 113.319721 -300.708881) (xy 113.342561 -300.659136) (xy 113.37228 -300.613169) (xy 113.389918 -300.592236)
			(xy 113.390172 -300.591982) (xy 113.395781 -300.584911) (xy 113.402012 -300.567982) (xy 113.402364 -300.558962)
			(xy 113.402364 -300.491906) (xy 113.402012 -300.482889) (xy 113.395762 -300.465971) (xy 113.390172 -300.458886)
			(xy 113.389918 -300.458886) (xy 113.389918 -300.458632) (xy 113.372311 -300.437672) (xy 113.342586 -300.391709)
			(xy 113.319739 -300.341967) (xy 113.30424 -300.289469) (xy 113.296409 -300.235294) (xy 113.296405 -300.180557)
			(xy 113.304229 -300.126381) (xy 113.319721 -300.073881) (xy 113.342561 -300.024136) (xy 113.37228 -299.978169)
			(xy 113.389918 -299.957236) (xy 113.390172 -299.956982) (xy 113.395781 -299.949911) (xy 113.402012 -299.932982)
			(xy 113.402364 -299.923962) (xy 113.402364 -299.856906) (xy 113.402012 -299.847889) (xy 113.395762 -299.830971)
			(xy 113.390172 -299.823886) (xy 113.389918 -299.823886) (xy 113.389918 -299.823632) (xy 113.372283 -299.802696)
			(xy 113.34257 -299.756725) (xy 113.319733 -299.706978) (xy 113.304241 -299.654478) (xy 113.296412 -299.600303)
			(xy 113.295938 -299.572934) (xy 113.296424 -299.545683) (xy 113.30418 -299.491735) (xy 113.319535 -299.43944)
			(xy 113.342177 -299.389863) (xy 113.371643 -299.344013) (xy 113.407334 -299.302822) (xy 113.448525 -299.267131)
			(xy 113.494375 -299.237665) (xy 113.543952 -299.215023) (xy 113.596247 -299.199668) (xy 113.650195 -299.191912)
			(xy 113.704697 -299.191912) (xy 113.758645 -299.199668) (xy 113.81094 -299.215023) (xy 113.860517 -299.237665)
			(xy 113.906367 -299.267131) (xy 113.947558 -299.302822) (xy 113.983249 -299.344013) (xy 114.012715 -299.389863)
			(xy 114.035357 -299.43944) (xy 114.050712 -299.491735) (xy 114.058468 -299.545683) (xy 114.058954 -299.572934)
			(xy 114.058519 -299.600305) (xy 114.050695 -299.654486) (xy 114.0352 -299.70699) (xy 114.012351 -299.756737)
			(xy 113.982619 -299.802702) (xy 113.964974 -299.823632) (xy 113.96472 -299.823886) (xy 113.959124 -299.830966)
			(xy 113.952885 -299.847888) (xy 113.952528 -299.856906) (xy 113.952528 -299.923962) (xy 113.952897 -299.932978)
			(xy 113.959136 -299.949895) (xy 113.96472 -299.956982) (xy 113.964974 -299.956982) (xy 113.964974 -299.957236)
			(xy 113.982648 -299.978142) (xy 114.012371 -300.024114) (xy 114.035215 -300.073865) (xy 114.050708 -300.126371)
			(xy 114.058534 -300.180553) (xy 114.05853 -300.235298) (xy 114.050697 -300.289479) (xy 114.035197 -300.341983)
			(xy 114.012347 -300.391731) (xy 113.982617 -300.437699) (xy 113.964974 -300.458632) (xy 113.96472 -300.458886)
			(xy 113.959124 -300.465966) (xy 113.952885 -300.482888) (xy 113.952528 -300.491906) (xy 113.952528 -300.558962)
			(xy 113.952897 -300.567978) (xy 113.959136 -300.584895) (xy 113.96472 -300.591982) (xy 113.964974 -300.591982)
			(xy 113.964974 -300.592236) (xy 113.982648 -300.613142) (xy 114.012371 -300.659114) (xy 114.035215 -300.708865)
			(xy 114.050708 -300.761371) (xy 114.058534 -300.815553) (xy 114.05853 -300.870298) (xy 114.050697 -300.924479)
			(xy 114.035197 -300.976983) (xy 114.012347 -301.026731) (xy 113.982617 -301.072699) (xy 113.964974 -301.093632)
			(xy 113.96472 -301.093886) (xy 113.959124 -301.100966) (xy 113.952885 -301.117888) (xy 113.952528 -301.126906)
			(xy 113.952528 -301.193962) (xy 113.952897 -301.202978) (xy 113.959136 -301.219895) (xy 113.96472 -301.226982)
			(xy 113.964974 -301.226982) (xy 113.964974 -301.227236) (xy 113.982593 -301.248185) (xy 114.012308 -301.294153)
			(xy 114.035149 -301.343896) (xy 114.050644 -301.396393) (xy 114.054649 -301.424086) (xy 121.416826 -301.424086)
			(xy 121.417278 -301.396715) (xy 121.425098 -301.342535) (xy 121.44059 -301.290032) (xy 121.463435 -301.240285)
			(xy 121.493163 -301.194319) (xy 121.510806 -301.173388) (xy 121.51106 -301.173134) (xy 121.516646 -301.166047)
			(xy 121.522891 -301.14913) (xy 121.523252 -301.140114) (xy 121.523252 -301.073058) (xy 121.522878 -301.064043)
			(xy 121.516643 -301.047125) (xy 121.51106 -301.040038) (xy 121.510806 -301.040038) (xy 121.510806 -301.039784)
			(xy 121.493152 -301.018862) (xy 121.46343 -300.972892) (xy 121.440587 -300.923144) (xy 121.425092 -300.87064)
			(xy 121.417265 -300.81646) (xy 121.417267 -300.761718) (xy 121.425097 -300.707539) (xy 121.440594 -300.655037)
			(xy 121.46344 -300.60529) (xy 121.493165 -300.559321) (xy 121.510806 -300.538388) (xy 121.51106 -300.538134)
			(xy 121.516646 -300.531047) (xy 121.522891 -300.51413) (xy 121.523252 -300.505114) (xy 121.523252 -300.438058)
			(xy 121.522878 -300.429043) (xy 121.516643 -300.412125) (xy 121.51106 -300.405038) (xy 121.510806 -300.405038)
			(xy 121.510806 -300.404784) (xy 121.493152 -300.383862) (xy 121.46343 -300.337892) (xy 121.440587 -300.288144)
			(xy 121.425092 -300.23564) (xy 121.417265 -300.18146) (xy 121.417267 -300.126718) (xy 121.425097 -300.072539)
			(xy 121.440594 -300.020037) (xy 121.46344 -299.97029) (xy 121.493165 -299.924321) (xy 121.510806 -299.903388)
			(xy 121.51106 -299.903134) (xy 121.516646 -299.896047) (xy 121.522891 -299.87913) (xy 121.523252 -299.870114)
			(xy 121.523252 -299.803058) (xy 121.522878 -299.794043) (xy 121.516643 -299.777125) (xy 121.51106 -299.770038)
			(xy 121.510806 -299.770038) (xy 121.510806 -299.769784) (xy 121.493194 -299.74883) (xy 121.463478 -299.702864)
			(xy 121.440636 -299.653122) (xy 121.425139 -299.600626) (xy 121.417304 -299.546454) (xy 121.416826 -299.519086)
			(xy 121.417312 -299.491835) (xy 121.425068 -299.437887) (xy 121.440423 -299.385592) (xy 121.463065 -299.336015)
			(xy 121.492531 -299.290165) (xy 121.528222 -299.248974) (xy 121.569413 -299.213283) (xy 121.615263 -299.183817)
			(xy 121.66484 -299.161175) (xy 121.717135 -299.14582) (xy 121.771083 -299.138064) (xy 121.825585 -299.138064)
			(xy 121.879533 -299.14582) (xy 121.931828 -299.161175) (xy 121.981405 -299.183817) (xy 122.027255 -299.213283)
			(xy 122.068446 -299.248974) (xy 122.104137 -299.290165) (xy 122.133603 -299.336015) (xy 122.156245 -299.385592)
			(xy 122.1716 -299.437887) (xy 122.179356 -299.491835) (xy 122.179842 -299.519086) (xy 122.179382 -299.546457)
			(xy 122.171565 -299.600637) (xy 122.156075 -299.65314) (xy 122.133232 -299.702887) (xy 122.103505 -299.748853)
			(xy 122.085862 -299.769784) (xy 122.085608 -299.770038) (xy 122.080042 -299.777139) (xy 122.073783 -299.794045)
			(xy 122.073416 -299.803058) (xy 122.073416 -299.870114) (xy 122.073763 -299.879132) (xy 122.080017 -299.896049)
			(xy 122.085608 -299.903134) (xy 122.085862 -299.903134) (xy 122.085862 -299.903388) (xy 122.103489 -299.924332)
			(xy 122.133216 -299.970297) (xy 122.156062 -300.020042) (xy 122.17156 -300.072542) (xy 122.17939 -300.126719)
			(xy 122.179392 -300.18146) (xy 122.171565 -300.235637) (xy 122.15607 -300.288139) (xy 122.133226 -300.337884)
			(xy 122.103502 -300.383852) (xy 122.085862 -300.404784) (xy 122.085608 -300.405038) (xy 122.080042 -300.412139)
			(xy 122.073783 -300.429045) (xy 122.073416 -300.438058) (xy 122.073416 -300.505114) (xy 122.073763 -300.514132)
			(xy 122.080017 -300.531049) (xy 122.085608 -300.538134) (xy 122.085862 -300.538134) (xy 122.085862 -300.538388)
			(xy 122.103489 -300.559332) (xy 122.133216 -300.605297) (xy 122.156062 -300.655042) (xy 122.17156 -300.707542)
			(xy 122.17939 -300.761719) (xy 122.179392 -300.81646) (xy 122.171565 -300.870637) (xy 122.15607 -300.923139)
			(xy 122.133226 -300.972884) (xy 122.103502 -301.018852) (xy 122.085862 -301.039784) (xy 122.085608 -301.040038)
			(xy 122.080042 -301.047139) (xy 122.073783 -301.064045) (xy 122.073416 -301.073058) (xy 122.073416 -301.140114)
			(xy 122.073763 -301.149132) (xy 122.080017 -301.166049) (xy 122.085608 -301.173134) (xy 122.085862 -301.173134)
			(xy 122.085862 -301.173388) (xy 122.103503 -301.194319) (xy 122.133216 -301.240291) (xy 122.156052 -301.290039)
			(xy 122.171543 -301.34254) (xy 122.179369 -301.396717) (xy 122.179842 -301.424086) (xy 122.179356 -301.451337)
			(xy 122.175532 -301.477934) (xy 125.049026 -301.477934) (xy 125.049506 -301.450564) (xy 125.057319 -301.396385)
			(xy 125.072805 -301.343882) (xy 125.095644 -301.294135) (xy 125.125366 -301.248168) (xy 125.143006 -301.227236)
			(xy 125.14326 -301.226982) (xy 125.148867 -301.21991) (xy 125.1551 -301.202982) (xy 125.155452 -301.193962)
			(xy 125.155452 -301.126906) (xy 125.155102 -301.117888) (xy 125.148851 -301.100971) (xy 125.14326 -301.093886)
			(xy 125.143006 -301.093886) (xy 125.143006 -301.093632) (xy 125.125399 -301.072672) (xy 125.095675 -301.026708)
			(xy 125.072829 -300.976966) (xy 125.057331 -300.924469) (xy 125.0495 -300.870294) (xy 125.049496 -300.815557)
			(xy 125.05732 -300.761381) (xy 125.072811 -300.708882) (xy 125.09565 -300.659137) (xy 125.125369 -300.613169)
			(xy 125.143006 -300.592236) (xy 125.14326 -300.591982) (xy 125.148867 -300.58491) (xy 125.1551 -300.567982)
			(xy 125.155452 -300.558962) (xy 125.155452 -300.491906) (xy 125.155102 -300.482888) (xy 125.148851 -300.465971)
			(xy 125.14326 -300.458886) (xy 125.143006 -300.458886) (xy 125.143006 -300.458632) (xy 125.125399 -300.437672)
			(xy 125.095675 -300.391708) (xy 125.072829 -300.341966) (xy 125.057331 -300.289469) (xy 125.0495 -300.235294)
			(xy 125.049496 -300.180557) (xy 125.05732 -300.126381) (xy 125.072811 -300.073882) (xy 125.09565 -300.024137)
			(xy 125.125369 -299.978169) (xy 125.143006 -299.957236) (xy 125.14326 -299.956982) (xy 125.148867 -299.94991)
			(xy 125.1551 -299.932982) (xy 125.155452 -299.923962) (xy 125.155452 -299.856906) (xy 125.155102 -299.847888)
			(xy 125.148851 -299.830971) (xy 125.14326 -299.823886) (xy 125.143006 -299.823886) (xy 125.143006 -299.823632)
			(xy 125.125369 -299.802698) (xy 125.095657 -299.756726) (xy 125.07282 -299.706979) (xy 125.057329 -299.654479)
			(xy 125.0495 -299.600303) (xy 125.049026 -299.572934) (xy 125.049512 -299.545683) (xy 125.057268 -299.491735)
			(xy 125.072623 -299.43944) (xy 125.095265 -299.389863) (xy 125.124731 -299.344013) (xy 125.160422 -299.302822)
			(xy 125.201613 -299.267131) (xy 125.247463 -299.237665) (xy 125.29704 -299.215023) (xy 125.349335 -299.199668)
			(xy 125.403283 -299.191912) (xy 125.457785 -299.191912) (xy 125.511733 -299.199668) (xy 125.564028 -299.215023)
			(xy 125.613605 -299.237665) (xy 125.659455 -299.267131) (xy 125.700646 -299.302822) (xy 125.736337 -299.344013)
			(xy 125.765803 -299.389863) (xy 125.788445 -299.43944) (xy 125.8038 -299.491735) (xy 125.811556 -299.545683)
			(xy 125.812042 -299.572934) (xy 125.81161 -299.600306) (xy 125.803786 -299.654487) (xy 125.78829 -299.706991)
			(xy 125.76544 -299.756737) (xy 125.735707 -299.802702) (xy 125.718062 -299.823632) (xy 125.717808 -299.823886)
			(xy 125.712222 -299.830973) (xy 125.705975 -299.847889) (xy 125.705616 -299.856906) (xy 125.705616 -299.923962)
			(xy 125.705988 -299.932977) (xy 125.712225 -299.949895) (xy 125.717808 -299.956982) (xy 125.718062 -299.956982)
			(xy 125.718062 -299.957236) (xy 125.735736 -299.978142) (xy 125.765461 -300.024114) (xy 125.788305 -300.073864)
			(xy 125.803799 -300.126371) (xy 125.811625 -300.180553) (xy 125.811621 -300.235298) (xy 125.803788 -300.289479)
			(xy 125.788287 -300.341984) (xy 125.765436 -300.391731) (xy 125.735706 -300.437699) (xy 125.718062 -300.458632)
			(xy 125.717808 -300.458886) (xy 125.712222 -300.465973) (xy 125.705975 -300.482889) (xy 125.705616 -300.491906)
			(xy 125.705616 -300.558962) (xy 125.705988 -300.567977) (xy 125.712225 -300.584895) (xy 125.717808 -300.591982)
			(xy 125.718062 -300.591982) (xy 125.718062 -300.592236) (xy 125.735736 -300.613142) (xy 125.765461 -300.659114)
			(xy 125.788305 -300.708864) (xy 125.803799 -300.761371) (xy 125.811625 -300.815553) (xy 125.811621 -300.870298)
			(xy 125.803788 -300.924479) (xy 125.788287 -300.976984) (xy 125.765436 -301.026731) (xy 125.735706 -301.072699)
			(xy 125.718062 -301.093632) (xy 125.717808 -301.093886) (xy 125.712222 -301.100973) (xy 125.705975 -301.117889)
			(xy 125.705616 -301.126906) (xy 125.705616 -301.193962) (xy 125.705988 -301.202977) (xy 125.712225 -301.219895)
			(xy 125.717808 -301.226982) (xy 125.718062 -301.226982) (xy 125.718062 -301.227236) (xy 125.735679 -301.248186)
			(xy 125.765395 -301.294153) (xy 125.788236 -301.343896) (xy 125.803732 -301.396393) (xy 125.807736 -301.424086)
			(xy 128.257046 -301.424086) (xy 128.257493 -301.396715) (xy 128.265313 -301.342535) (xy 128.280806 -301.290031)
			(xy 128.303653 -301.240284) (xy 128.333382 -301.194319) (xy 128.351026 -301.173388) (xy 128.35128 -301.173134)
			(xy 128.356868 -301.166049) (xy 128.363112 -301.149131) (xy 128.363472 -301.140114) (xy 128.363472 -301.073058)
			(xy 128.363093 -301.064043) (xy 128.356861 -301.047126) (xy 128.35128 -301.040038) (xy 128.351026 -301.040038)
			(xy 128.351026 -301.039784) (xy 128.333372 -301.018862) (xy 128.303647 -300.972893) (xy 128.280803 -300.923145)
			(xy 128.265308 -300.870641) (xy 128.257481 -300.816461) (xy 128.257482 -300.761718) (xy 128.265312 -300.707539)
			(xy 128.28081 -300.655036) (xy 128.303658 -300.605289) (xy 128.333384 -300.559321) (xy 128.351026 -300.538388)
			(xy 128.35128 -300.538134) (xy 128.356868 -300.531049) (xy 128.363112 -300.514131) (xy 128.363472 -300.505114)
			(xy 128.363472 -300.438058) (xy 128.363093 -300.429043) (xy 128.356861 -300.412126) (xy 128.35128 -300.405038)
			(xy 128.351026 -300.405038) (xy 128.351026 -300.404784) (xy 128.333372 -300.383862) (xy 128.303647 -300.337893)
			(xy 128.280803 -300.288145) (xy 128.265308 -300.235641) (xy 128.257481 -300.181461) (xy 128.257482 -300.126718)
			(xy 128.265312 -300.072539) (xy 128.28081 -300.020036) (xy 128.303658 -299.970289) (xy 128.333384 -299.924321)
			(xy 128.351026 -299.903388) (xy 128.35128 -299.903134) (xy 128.356868 -299.896049) (xy 128.363112 -299.879131)
			(xy 128.363472 -299.870114) (xy 128.363472 -299.803058) (xy 128.363093 -299.794043) (xy 128.356861 -299.777126)
			(xy 128.35128 -299.770038) (xy 128.351026 -299.770038) (xy 128.351026 -299.769784) (xy 128.333417 -299.748828)
			(xy 128.3037 -299.702862) (xy 128.280858 -299.653121) (xy 128.26536 -299.600625) (xy 128.257524 -299.546454)
			(xy 128.257046 -299.519086) (xy 128.257532 -299.491835) (xy 128.265288 -299.437887) (xy 128.280643 -299.385592)
			(xy 128.303285 -299.336015) (xy 128.332751 -299.290165) (xy 128.368442 -299.248974) (xy 128.409633 -299.213283)
			(xy 128.455483 -299.183817) (xy 128.50506 -299.161175) (xy 128.557355 -299.14582) (xy 128.611303 -299.138064)
			(xy 128.665805 -299.138064) (xy 128.719753 -299.14582) (xy 128.772048 -299.161175) (xy 128.821625 -299.183817)
			(xy 128.867475 -299.213283) (xy 128.908666 -299.248974) (xy 128.944357 -299.290165) (xy 128.973823 -299.336015)
			(xy 128.996465 -299.385592) (xy 129.01182 -299.437887) (xy 129.019576 -299.491835) (xy 129.020062 -299.519086)
			(xy 129.019597 -299.546456) (xy 129.01178 -299.600636) (xy 128.996292 -299.653139) (xy 128.973449 -299.702886)
			(xy 128.943724 -299.748853) (xy 128.926082 -299.769784) (xy 128.925828 -299.770038) (xy 128.920253 -299.777132)
			(xy 128.914001 -299.794043) (xy 128.913636 -299.803058) (xy 128.913636 -299.870114) (xy 128.913978 -299.879133)
			(xy 128.920235 -299.89605) (xy 128.925828 -299.903134) (xy 128.926082 -299.903134) (xy 128.926082 -299.903388)
			(xy 128.943709 -299.924332) (xy 128.973433 -299.970298) (xy 128.996279 -300.020043) (xy 129.011776 -300.072543)
			(xy 129.019606 -300.12672) (xy 129.019607 -300.181459) (xy 129.01178 -300.235637) (xy 128.996286 -300.288138)
			(xy 128.973443 -300.337883) (xy 128.943721 -300.383851) (xy 128.926082 -300.404784) (xy 128.925828 -300.405038)
			(xy 128.920253 -300.412132) (xy 128.914001 -300.429043) (xy 128.913636 -300.438058) (xy 128.913636 -300.505114)
			(xy 128.913978 -300.514133) (xy 128.920235 -300.53105) (xy 128.925828 -300.538134) (xy 128.926082 -300.538134)
			(xy 128.926082 -300.538388) (xy 128.943709 -300.559332) (xy 128.973433 -300.605298) (xy 128.996279 -300.655043)
			(xy 129.011776 -300.707543) (xy 129.019606 -300.76172) (xy 129.019607 -300.816459) (xy 129.01178 -300.870637)
			(xy 128.996286 -300.923138) (xy 128.973443 -300.972883) (xy 128.943721 -301.018851) (xy 128.926082 -301.039784)
			(xy 128.925828 -301.040038) (xy 128.920253 -301.047132) (xy 128.914001 -301.064043) (xy 128.913636 -301.073058)
			(xy 128.913636 -301.140114) (xy 128.913978 -301.149133) (xy 128.920235 -301.16605) (xy 128.925828 -301.173134)
			(xy 128.926082 -301.173134) (xy 128.926082 -301.173388) (xy 128.943726 -301.194316) (xy 128.973438 -301.24029)
			(xy 128.996273 -301.290038) (xy 129.011763 -301.34254) (xy 129.019589 -301.396717) (xy 129.020062 -301.424086)
			(xy 129.019576 -301.451337) (xy 129.015752 -301.477934) (xy 131.889246 -301.477934) (xy 131.889721 -301.450564)
			(xy 131.897535 -301.396385) (xy 131.913021 -301.343881) (xy 131.935861 -301.294134) (xy 131.965585 -301.248168)
			(xy 131.983226 -301.227236) (xy 131.98348 -301.226982) (xy 131.98909 -301.219912) (xy 131.99532 -301.202982)
			(xy 131.995672 -301.193962) (xy 131.995672 -301.126906) (xy 131.995318 -301.117889) (xy 131.989069 -301.100971)
			(xy 131.98348 -301.093886) (xy 131.983226 -301.093886) (xy 131.983226 -301.093632) (xy 131.965619 -301.072672)
			(xy 131.935893 -301.026709) (xy 131.913045 -300.976967) (xy 131.897546 -300.924469) (xy 131.889715 -300.870295)
			(xy 131.889711 -300.815557) (xy 131.897535 -300.761381) (xy 131.913027 -300.708881) (xy 131.935868 -300.659136)
			(xy 131.965588 -300.613169) (xy 131.983226 -300.592236) (xy 131.98348 -300.591982) (xy 131.98909 -300.584912)
			(xy 131.99532 -300.567982) (xy 131.995672 -300.558962) (xy 131.995672 -300.491906) (xy 131.995318 -300.482889)
			(xy 131.989069 -300.465971) (xy 131.98348 -300.458886) (xy 131.983226 -300.458886) (xy 131.983226 -300.458632)
			(xy 131.965619 -300.437672) (xy 131.935893 -300.391709) (xy 131.913045 -300.341967) (xy 131.897546 -300.289469)
			(xy 131.889715 -300.235295) (xy 131.889711 -300.180557) (xy 131.897535 -300.126381) (xy 131.913027 -300.073881)
			(xy 131.935868 -300.024136) (xy 131.965588 -299.978169) (xy 131.983226 -299.957236) (xy 131.98348 -299.956982)
			(xy 131.98909 -299.949912) (xy 131.99532 -299.932982) (xy 131.995672 -299.923962) (xy 131.995672 -299.856906)
			(xy 131.995318 -299.847889) (xy 131.989069 -299.830971) (xy 131.98348 -299.823886) (xy 131.983226 -299.823886)
			(xy 131.983226 -299.823632) (xy 131.965592 -299.802695) (xy 131.935879 -299.756724) (xy 131.913041 -299.706978)
			(xy 131.897549 -299.654478) (xy 131.88972 -299.600303) (xy 131.889246 -299.572934) (xy 131.889732 -299.545683)
			(xy 131.897488 -299.491735) (xy 131.912843 -299.43944) (xy 131.935485 -299.389863) (xy 131.964951 -299.344013)
			(xy 132.000642 -299.302822) (xy 132.041833 -299.267131) (xy 132.087683 -299.237665) (xy 132.13726 -299.215023)
			(xy 132.189555 -299.199668) (xy 132.243503 -299.191912) (xy 132.298005 -299.191912) (xy 132.351953 -299.199668)
			(xy 132.404248 -299.215023) (xy 132.453825 -299.237665) (xy 132.499675 -299.267131) (xy 132.540866 -299.302822)
			(xy 132.576557 -299.344013) (xy 132.606023 -299.389863) (xy 132.628665 -299.43944) (xy 132.64402 -299.491735)
			(xy 132.651776 -299.545683) (xy 132.652262 -299.572934) (xy 132.651825 -299.600305) (xy 132.644002 -299.654486)
			(xy 132.628506 -299.70699) (xy 132.605658 -299.756736) (xy 132.575927 -299.802702) (xy 132.558282 -299.823632)
			(xy 132.558028 -299.823886) (xy 132.552433 -299.830966) (xy 132.546193 -299.847888) (xy 132.545836 -299.856906)
			(xy 132.545836 -299.923962) (xy 132.546203 -299.932978) (xy 132.552443 -299.949895) (xy 132.558028 -299.956982)
			(xy 132.558282 -299.956982) (xy 132.558282 -299.957236) (xy 132.575956 -299.978142) (xy 132.605678 -300.024115)
			(xy 132.628521 -300.073865) (xy 132.644014 -300.126371) (xy 132.65184 -300.180553) (xy 132.651836 -300.235298)
			(xy 132.644003 -300.289479) (xy 132.628503 -300.341983) (xy 132.605654 -300.39173) (xy 132.575925 -300.437699)
			(xy 132.558282 -300.458632) (xy 132.558028 -300.458886) (xy 132.552433 -300.465966) (xy 132.546193 -300.482888)
			(xy 132.545836 -300.491906) (xy 132.545836 -300.558962) (xy 132.546203 -300.567978) (xy 132.552443 -300.584895)
			(xy 132.558028 -300.591982) (xy 132.558282 -300.591982) (xy 132.558282 -300.592236) (xy 132.575956 -300.613142)
			(xy 132.605678 -300.659115) (xy 132.628521 -300.708865) (xy 132.644014 -300.761371) (xy 132.65184 -300.815553)
			(xy 132.651836 -300.870298) (xy 132.644003 -300.924479) (xy 132.628503 -300.976983) (xy 132.605654 -301.02673)
			(xy 132.575925 -301.072699) (xy 132.558282 -301.093632) (xy 132.558028 -301.093886) (xy 132.552433 -301.100966)
			(xy 132.546193 -301.117888) (xy 132.545836 -301.126906) (xy 132.545836 -301.193962) (xy 132.546203 -301.202978)
			(xy 132.552443 -301.219895) (xy 132.558028 -301.226982) (xy 132.558282 -301.226982) (xy 132.558282 -301.227236)
			(xy 132.575902 -301.248184) (xy 132.605617 -301.294152) (xy 132.628457 -301.343895) (xy 132.643953 -301.396393)
			(xy 132.651786 -301.450566) (xy 132.652262 -301.477934) (xy 132.651776 -301.505185) (xy 132.64402 -301.559133)
			(xy 132.628665 -301.611428) (xy 132.606023 -301.661005) (xy 132.576557 -301.706855) (xy 132.540866 -301.748046)
			(xy 132.499675 -301.783737) (xy 132.453825 -301.813203) (xy 132.404248 -301.835845) (xy 132.351953 -301.8512)
			(xy 132.298005 -301.858956) (xy 132.243503 -301.858956) (xy 132.189555 -301.8512) (xy 132.13726 -301.835845)
			(xy 132.087683 -301.813203) (xy 132.041833 -301.783737) (xy 132.000642 -301.748046) (xy 131.964951 -301.706855)
			(xy 131.935485 -301.661005) (xy 131.912843 -301.611428) (xy 131.897488 -301.559133) (xy 131.889732 -301.505185)
			(xy 131.889246 -301.477934) (xy 129.015752 -301.477934) (xy 129.01182 -301.505285) (xy 128.996465 -301.55758)
			(xy 128.973823 -301.607157) (xy 128.944357 -301.653007) (xy 128.908666 -301.694198) (xy 128.867475 -301.729889)
			(xy 128.821625 -301.759355) (xy 128.772048 -301.781997) (xy 128.719753 -301.797352) (xy 128.665805 -301.805108)
			(xy 128.611303 -301.805108) (xy 128.557355 -301.797352) (xy 128.50506 -301.781997) (xy 128.455483 -301.759355)
			(xy 128.409633 -301.729889) (xy 128.368442 -301.694198) (xy 128.332751 -301.653007) (xy 128.303285 -301.607157)
			(xy 128.280643 -301.55758) (xy 128.265288 -301.505285) (xy 128.257532 -301.451337) (xy 128.257046 -301.424086)
			(xy 125.807736 -301.424086) (xy 125.811565 -301.450566) (xy 125.812042 -301.477934) (xy 125.811556 -301.505185)
			(xy 125.8038 -301.559133) (xy 125.788445 -301.611428) (xy 125.765803 -301.661005) (xy 125.736337 -301.706855)
			(xy 125.700646 -301.748046) (xy 125.659455 -301.783737) (xy 125.613605 -301.813203) (xy 125.564028 -301.835845)
			(xy 125.511733 -301.8512) (xy 125.457785 -301.858956) (xy 125.403283 -301.858956) (xy 125.349335 -301.8512)
			(xy 125.29704 -301.835845) (xy 125.247463 -301.813203) (xy 125.201613 -301.783737) (xy 125.160422 -301.748046)
			(xy 125.124731 -301.706855) (xy 125.095265 -301.661005) (xy 125.072623 -301.611428) (xy 125.057268 -301.559133)
			(xy 125.049512 -301.505185) (xy 125.049026 -301.477934) (xy 122.175532 -301.477934) (xy 122.1716 -301.505285)
			(xy 122.156245 -301.55758) (xy 122.133603 -301.607157) (xy 122.104137 -301.653007) (xy 122.068446 -301.694198)
			(xy 122.027255 -301.729889) (xy 121.981405 -301.759355) (xy 121.931828 -301.781997) (xy 121.879533 -301.797352)
			(xy 121.825585 -301.805108) (xy 121.771083 -301.805108) (xy 121.717135 -301.797352) (xy 121.66484 -301.781997)
			(xy 121.615263 -301.759355) (xy 121.569413 -301.729889) (xy 121.528222 -301.694198) (xy 121.492531 -301.653007)
			(xy 121.463065 -301.607157) (xy 121.440423 -301.55758) (xy 121.425068 -301.505285) (xy 121.417312 -301.451337)
			(xy 121.416826 -301.424086) (xy 114.054649 -301.424086) (xy 114.058478 -301.450566) (xy 114.058954 -301.477934)
			(xy 114.058468 -301.505185) (xy 114.050712 -301.559133) (xy 114.035357 -301.611428) (xy 114.012715 -301.661005)
			(xy 113.983249 -301.706855) (xy 113.947558 -301.748046) (xy 113.906367 -301.783737) (xy 113.860517 -301.813203)
			(xy 113.81094 -301.835845) (xy 113.758645 -301.8512) (xy 113.704697 -301.858956) (xy 113.650195 -301.858956)
			(xy 113.596247 -301.8512) (xy 113.543952 -301.835845) (xy 113.494375 -301.813203) (xy 113.448525 -301.783737)
			(xy 113.407334 -301.748046) (xy 113.371643 -301.706855) (xy 113.342177 -301.661005) (xy 113.319535 -301.611428)
			(xy 113.30418 -301.559133) (xy 113.296424 -301.505185) (xy 113.295938 -301.477934) (xy 110.422444 -301.477934)
			(xy 110.418512 -301.505285) (xy 110.403157 -301.55758) (xy 110.380515 -301.607157) (xy 110.351049 -301.653007)
			(xy 110.315358 -301.694198) (xy 110.274167 -301.729889) (xy 110.228317 -301.759355) (xy 110.17874 -301.781997)
			(xy 110.126445 -301.797352) (xy 110.072497 -301.805108) (xy 110.017995 -301.805108) (xy 109.964047 -301.797352)
			(xy 109.911752 -301.781997) (xy 109.862175 -301.759355) (xy 109.816325 -301.729889) (xy 109.775134 -301.694198)
			(xy 109.739443 -301.653007) (xy 109.709977 -301.607157) (xy 109.687335 -301.55758) (xy 109.67198 -301.505285)
			(xy 109.664224 -301.451337) (xy 109.663738 -301.424086) (xy 107.214428 -301.424086) (xy 107.218257 -301.450566)
			(xy 107.218734 -301.477934) (xy 107.218248 -301.505185) (xy 107.210492 -301.559133) (xy 107.195137 -301.611428)
			(xy 107.172495 -301.661005) (xy 107.143029 -301.706855) (xy 107.107338 -301.748046) (xy 107.066147 -301.783737)
			(xy 107.020297 -301.813203) (xy 106.97072 -301.835845) (xy 106.918425 -301.8512) (xy 106.864477 -301.858956)
			(xy 106.809975 -301.858956) (xy 106.756027 -301.8512) (xy 106.703732 -301.835845) (xy 106.654155 -301.813203)
			(xy 106.608305 -301.783737) (xy 106.567114 -301.748046) (xy 106.531423 -301.706855) (xy 106.501957 -301.661005)
			(xy 106.479315 -301.611428) (xy 106.46396 -301.559133) (xy 106.456204 -301.505185) (xy 106.455718 -301.477934)
			(xy 103.582224 -301.477934) (xy 103.578292 -301.505285) (xy 103.562937 -301.55758) (xy 103.540295 -301.607157)
			(xy 103.510829 -301.653007) (xy 103.475138 -301.694198) (xy 103.433947 -301.729889) (xy 103.388097 -301.759355)
			(xy 103.33852 -301.781997) (xy 103.286225 -301.797352) (xy 103.232277 -301.805108) (xy 103.177775 -301.805108)
			(xy 103.123827 -301.797352) (xy 103.071532 -301.781997) (xy 103.021955 -301.759355) (xy 102.976105 -301.729889)
			(xy 102.934914 -301.694198) (xy 102.899223 -301.653007) (xy 102.869757 -301.607157) (xy 102.847115 -301.55758)
			(xy 102.83176 -301.505285) (xy 102.824004 -301.451337) (xy 102.823518 -301.424086) (xy 98.74377 -301.424086)
			(xy 98.74377 -302.925734) (xy 102.235508 -302.925734) (xy 102.235992 -302.898364) (xy 102.243805 -302.844186)
			(xy 102.25929 -302.791683) (xy 102.282128 -302.741936) (xy 102.311849 -302.695968) (xy 102.329488 -302.675036)
			(xy 102.329742 -302.674782) (xy 102.335347 -302.667708) (xy 102.341582 -302.650782) (xy 102.341934 -302.641762)
			(xy 102.341934 -302.574706) (xy 102.341567 -302.56569) (xy 102.335325 -302.548774) (xy 102.329742 -302.541686)
			(xy 102.329488 -302.541686) (xy 102.329488 -302.541432) (xy 102.311849 -302.5205) (xy 102.282137 -302.474527)
			(xy 102.259302 -302.42478) (xy 102.24381 -302.372279) (xy 102.235982 -302.318103) (xy 102.235508 -302.290734)
			(xy 102.235994 -302.263483) (xy 102.24375 -302.209535) (xy 102.259105 -302.15724) (xy 102.281747 -302.107663)
			(xy 102.311213 -302.061813) (xy 102.346904 -302.020622) (xy 102.388095 -301.984931) (xy 102.433945 -301.955465)
			(xy 102.483522 -301.932823) (xy 102.535817 -301.917468) (xy 102.589765 -301.909712) (xy 102.644267 -301.909712)
			(xy 102.698215 -301.917468) (xy 102.75051 -301.932823) (xy 102.800087 -301.955465) (xy 102.845937 -301.984931)
			(xy 102.887128 -302.020622) (xy 102.922819 -302.061813) (xy 102.952285 -302.107663) (xy 102.974927 -302.15724)
			(xy 102.990282 -302.209535) (xy 102.998038 -302.263483) (xy 102.998524 -302.290734) (xy 102.998096 -302.318106)
			(xy 102.990272 -302.372287) (xy 102.974775 -302.424792) (xy 102.951924 -302.474538) (xy 102.92219 -302.520502)
			(xy 102.904544 -302.541432) (xy 102.90429 -302.541686) (xy 102.898702 -302.548772) (xy 102.892456 -302.565689)
			(xy 102.892098 -302.574706) (xy 102.892098 -302.641762) (xy 102.892473 -302.650777) (xy 102.898708 -302.667694)
			(xy 102.90429 -302.674782) (xy 102.904544 -302.674782) (xy 102.904544 -302.675036) (xy 102.922174 -302.695975)
			(xy 102.951886 -302.741947) (xy 102.974723 -302.791693) (xy 102.990216 -302.844191) (xy 102.998048 -302.898365)
			(xy 102.998524 -302.925734) (xy 105.655618 -302.925734) (xy 105.6561 -302.898364) (xy 105.663913 -302.844186)
			(xy 105.679398 -302.791683) (xy 105.702237 -302.741935) (xy 105.731958 -302.695968) (xy 105.749598 -302.675036)
			(xy 105.749852 -302.674782) (xy 105.755458 -302.667709) (xy 105.761692 -302.650782) (xy 105.762044 -302.641762)
			(xy 105.762044 -302.574706) (xy 105.761696 -302.565688) (xy 105.755443 -302.54877) (xy 105.749852 -302.541686)
			(xy 105.749598 -302.541686) (xy 105.749598 -302.541432) (xy 105.73196 -302.520499) (xy 105.702248 -302.474526)
			(xy 105.679412 -302.424779) (xy 105.663921 -302.372279) (xy 105.656092 -302.318103) (xy 105.655618 -302.290734)
			(xy 105.656104 -302.263483) (xy 105.66386 -302.209535) (xy 105.679215 -302.15724) (xy 105.701857 -302.107663)
			(xy 105.731323 -302.061813) (xy 105.767014 -302.020622) (xy 105.808205 -301.984931) (xy 105.854055 -301.955465)
			(xy 105.903632 -301.932823) (xy 105.955927 -301.917468) (xy 106.009875 -301.909712) (xy 106.064377 -301.909712)
			(xy 106.118325 -301.917468) (xy 106.17062 -301.932823) (xy 106.220197 -301.955465) (xy 106.266047 -301.984931)
			(xy 106.307238 -302.020622) (xy 106.342929 -302.061813) (xy 106.372395 -302.107663) (xy 106.395037 -302.15724)
			(xy 106.410392 -302.209535) (xy 106.418148 -302.263483) (xy 106.418634 -302.290734) (xy 106.418204 -302.318106)
			(xy 106.41038 -302.372287) (xy 106.394883 -302.424791) (xy 106.372033 -302.474537) (xy 106.3423 -302.520502)
			(xy 106.324654 -302.541432) (xy 106.3244 -302.541686) (xy 106.318813 -302.548772) (xy 106.312567 -302.565689)
			(xy 106.312208 -302.574706) (xy 106.312208 -302.641762) (xy 106.312582 -302.650777) (xy 106.318818 -302.667694)
			(xy 106.3244 -302.674782) (xy 106.324654 -302.674782) (xy 106.324654 -302.675036) (xy 106.342269 -302.695987)
			(xy 106.371986 -302.741954) (xy 106.394828 -302.791697) (xy 106.410324 -302.844193) (xy 106.418157 -302.898366)
			(xy 106.418634 -302.925734) (xy 107.043728 -302.925734) (xy 107.044207 -302.898364) (xy 107.052021 -302.844185)
			(xy 107.067506 -302.791682) (xy 107.090345 -302.741935) (xy 107.120068 -302.695968) (xy 107.137708 -302.675036)
			(xy 107.137962 -302.674782) (xy 107.14357 -302.66771) (xy 107.149802 -302.650782) (xy 107.150154 -302.641762)
			(xy 107.150154 -302.574706) (xy 107.149804 -302.565688) (xy 107.143553 -302.548771) (xy 107.137962 -302.541686)
			(xy 107.137708 -302.541686) (xy 107.137708 -302.541432) (xy 107.120072 -302.520498) (xy 107.090359 -302.474526)
			(xy 107.067523 -302.424779) (xy 107.052031 -302.372278) (xy 107.044202 -302.318103) (xy 107.043728 -302.290734)
			(xy 107.044214 -302.263483) (xy 107.05197 -302.209535) (xy 107.067325 -302.15724) (xy 107.089967 -302.107663)
			(xy 107.119433 -302.061813) (xy 107.155124 -302.020622) (xy 107.196315 -301.984931) (xy 107.242165 -301.955465)
			(xy 107.291742 -301.932823) (xy 107.344037 -301.917468) (xy 107.397985 -301.909712) (xy 107.452487 -301.909712)
			(xy 107.506435 -301.917468) (xy 107.55873 -301.932823) (xy 107.608307 -301.955465) (xy 107.654157 -301.984931)
			(xy 107.695348 -302.020622) (xy 107.731039 -302.061813) (xy 107.760505 -302.107663) (xy 107.783147 -302.15724)
			(xy 107.798502 -302.209535) (xy 107.806258 -302.263483) (xy 107.806744 -302.290734) (xy 107.806312 -302.318106)
			(xy 107.798488 -302.372287) (xy 107.782992 -302.424791) (xy 107.760142 -302.474537) (xy 107.730409 -302.520502)
			(xy 107.712764 -302.541432) (xy 107.71251 -302.541686) (xy 107.706924 -302.548773) (xy 107.700677 -302.565689)
			(xy 107.700318 -302.574706) (xy 107.700318 -302.641762) (xy 107.700689 -302.650777) (xy 107.706927 -302.667695)
			(xy 107.71251 -302.674782) (xy 107.712764 -302.674782) (xy 107.712764 -302.675036) (xy 107.730381 -302.695986)
			(xy 107.760097 -302.741953) (xy 107.782938 -302.791696) (xy 107.798434 -302.844193) (xy 107.806267 -302.898366)
			(xy 107.806744 -302.925734) (xy 109.075728 -302.925734) (xy 109.076207 -302.898364) (xy 109.084021 -302.844185)
			(xy 109.099506 -302.791682) (xy 109.122345 -302.741935) (xy 109.152068 -302.695968) (xy 109.169708 -302.675036)
			(xy 109.169962 -302.674782) (xy 109.17557 -302.66771) (xy 109.181802 -302.650782) (xy 109.182154 -302.641762)
			(xy 109.182154 -302.574706) (xy 109.181804 -302.565688) (xy 109.175553 -302.548771) (xy 109.169962 -302.541686)
			(xy 109.169708 -302.541686) (xy 109.169708 -302.541432) (xy 109.152072 -302.520498) (xy 109.122359 -302.474526)
			(xy 109.099523 -302.424779) (xy 109.084031 -302.372278) (xy 109.076202 -302.318103) (xy 109.075728 -302.290734)
			(xy 109.076214 -302.263483) (xy 109.08397 -302.209535) (xy 109.099325 -302.15724) (xy 109.121967 -302.107663)
			(xy 109.151433 -302.061813) (xy 109.187124 -302.020622) (xy 109.228315 -301.984931) (xy 109.274165 -301.955465)
			(xy 109.323742 -301.932823) (xy 109.376037 -301.917468) (xy 109.429985 -301.909712) (xy 109.484487 -301.909712)
			(xy 109.538435 -301.917468) (xy 109.59073 -301.932823) (xy 109.640307 -301.955465) (xy 109.686157 -301.984931)
			(xy 109.727348 -302.020622) (xy 109.763039 -302.061813) (xy 109.792505 -302.107663) (xy 109.815147 -302.15724)
			(xy 109.830502 -302.209535) (xy 109.838258 -302.263483) (xy 109.838744 -302.290734) (xy 109.838312 -302.318106)
			(xy 109.830488 -302.372287) (xy 109.814992 -302.424791) (xy 109.792142 -302.474537) (xy 109.762409 -302.520502)
			(xy 109.744764 -302.541432) (xy 109.74451 -302.541686) (xy 109.738924 -302.548773) (xy 109.732677 -302.565689)
			(xy 109.732318 -302.574706) (xy 109.732318 -302.641762) (xy 109.732689 -302.650777) (xy 109.738927 -302.667695)
			(xy 109.74451 -302.674782) (xy 109.744764 -302.674782) (xy 109.744764 -302.675036) (xy 109.762381 -302.695986)
			(xy 109.792097 -302.741953) (xy 109.814938 -302.791696) (xy 109.830434 -302.844193) (xy 109.838267 -302.898366)
			(xy 109.838744 -302.925734) (xy 113.883948 -302.925734) (xy 113.884422 -302.898364) (xy 113.892236 -302.844185)
			(xy 113.907723 -302.791681) (xy 113.930563 -302.741934) (xy 113.960287 -302.695967) (xy 113.977928 -302.675036)
			(xy 113.978182 -302.674782) (xy 113.98378 -302.667703) (xy 113.99002 -302.65078) (xy 113.990374 -302.641762)
			(xy 113.990374 -302.574706) (xy 113.99002 -302.565689) (xy 113.983771 -302.548771) (xy 113.978182 -302.541686)
			(xy 113.977928 -302.541686) (xy 113.977928 -302.541432) (xy 113.960295 -302.520495) (xy 113.930581 -302.474524)
			(xy 113.907744 -302.424778) (xy 113.892251 -302.372278) (xy 113.884422 -302.318103) (xy 113.883948 -302.290734)
			(xy 113.884434 -302.263483) (xy 113.89219 -302.209535) (xy 113.907545 -302.15724) (xy 113.930187 -302.107663)
			(xy 113.959653 -302.061813) (xy 113.995344 -302.020622) (xy 114.036535 -301.984931) (xy 114.082385 -301.955465)
			(xy 114.131962 -301.932823) (xy 114.184257 -301.917468) (xy 114.238205 -301.909712) (xy 114.292707 -301.909712)
			(xy 114.346655 -301.917468) (xy 114.39895 -301.932823) (xy 114.448527 -301.955465) (xy 114.494377 -301.984931)
			(xy 114.535568 -302.020622) (xy 114.571259 -302.061813) (xy 114.600725 -302.107663) (xy 114.623367 -302.15724)
			(xy 114.638722 -302.209535) (xy 114.646478 -302.263483) (xy 114.646964 -302.290734) (xy 114.646527 -302.318105)
			(xy 114.638703 -302.372286) (xy 114.623208 -302.42479) (xy 114.60036 -302.474536) (xy 114.570628 -302.520502)
			(xy 114.552984 -302.541432) (xy 114.55273 -302.541686) (xy 114.547135 -302.548766) (xy 114.540895 -302.565688)
			(xy 114.540538 -302.574706) (xy 114.540538 -302.641762) (xy 114.540905 -302.650778) (xy 114.547145 -302.667695)
			(xy 114.55273 -302.674782) (xy 114.552984 -302.674782) (xy 114.552984 -302.675036) (xy 114.570604 -302.695983)
			(xy 114.600319 -302.741952) (xy 114.623159 -302.791695) (xy 114.638655 -302.844193) (xy 114.646488 -302.898366)
			(xy 114.646964 -302.925734) (xy 114.646478 -302.952985) (xy 114.638722 -303.006933) (xy 114.623367 -303.059228)
			(xy 114.600725 -303.108805) (xy 114.579627 -303.141634) (xy 116.784372 -303.141634) (xy 116.788443 -303.086012)
			(xy 116.800569 -303.031575) (xy 116.820492 -302.979484) (xy 116.847788 -302.930849) (xy 116.881874 -302.886706)
			(xy 116.922023 -302.847997) (xy 116.967381 -302.815546) (xy 117.016981 -302.790045) (xy 117.069765 -302.772038)
			(xy 117.124608 -302.761908) (xy 117.180342 -302.759871) (xy 117.235779 -302.765971) (xy 117.289736 -302.780077)
			(xy 117.341065 -302.801889) (xy 117.388671 -302.830943) (xy 117.431539 -302.866618) (xy 117.468756 -302.908155)
			(xy 117.499529 -302.954668) (xy 117.523201 -303.005165) (xy 117.539269 -303.058572) (xy 117.547389 -303.113748)
			(xy 117.547898 -303.141634) (xy 117.927372 -303.141634) (xy 117.931443 -303.086012) (xy 117.943569 -303.031575)
			(xy 117.963492 -302.979484) (xy 117.990788 -302.930849) (xy 118.024874 -302.886706) (xy 118.065023 -302.847997)
			(xy 118.110381 -302.815546) (xy 118.159981 -302.790045) (xy 118.212765 -302.772038) (xy 118.267608 -302.761908)
			(xy 118.323342 -302.759871) (xy 118.378779 -302.765971) (xy 118.432736 -302.780077) (xy 118.484065 -302.801889)
			(xy 118.531671 -302.830943) (xy 118.574539 -302.866618) (xy 118.611756 -302.908155) (xy 118.623386 -302.925734)
			(xy 120.828816 -302.925734) (xy 120.829298 -302.898364) (xy 120.837111 -302.844186) (xy 120.852597 -302.791683)
			(xy 120.875435 -302.741936) (xy 120.905156 -302.695968) (xy 120.922796 -302.675036) (xy 120.92305 -302.674782)
			(xy 120.928656 -302.667709) (xy 120.93489 -302.650782) (xy 120.935242 -302.641762) (xy 120.935242 -302.574706)
			(xy 120.934895 -302.565688) (xy 120.928642 -302.54877) (xy 120.92305 -302.541686) (xy 120.922796 -302.541686)
			(xy 120.922796 -302.541432) (xy 120.905158 -302.520499) (xy 120.875446 -302.474527) (xy 120.85261 -302.424779)
			(xy 120.837119 -302.372279) (xy 120.82929 -302.318103) (xy 120.828816 -302.290734) (xy 120.829302 -302.263483)
			(xy 120.837058 -302.209535) (xy 120.852413 -302.15724) (xy 120.875055 -302.107663) (xy 120.904521 -302.061813)
			(xy 120.940212 -302.020622) (xy 120.981403 -301.984931) (xy 121.027253 -301.955465) (xy 121.07683 -301.932823)
			(xy 121.129125 -301.917468) (xy 121.183073 -301.909712) (xy 121.237575 -301.909712) (xy 121.291523 -301.917468)
			(xy 121.343818 -301.932823) (xy 121.393395 -301.955465) (xy 121.439245 -301.984931) (xy 121.480436 -302.020622)
			(xy 121.516127 -302.061813) (xy 121.545593 -302.107663) (xy 121.568235 -302.15724) (xy 121.58359 -302.209535)
			(xy 121.591346 -302.263483) (xy 121.591832 -302.290734) (xy 121.591402 -302.318106) (xy 121.583578 -302.372287)
			(xy 121.568082 -302.424791) (xy 121.545231 -302.474538) (xy 121.515498 -302.520502) (xy 121.497852 -302.541432)
			(xy 121.497598 -302.541686) (xy 121.492011 -302.548772) (xy 121.485765 -302.565689) (xy 121.485406 -302.574706)
			(xy 121.485406 -302.641762) (xy 121.48578 -302.650777) (xy 121.492016 -302.667694) (xy 121.497598 -302.674782)
			(xy 121.497852 -302.674782) (xy 121.497852 -302.675036) (xy 121.515467 -302.695988) (xy 121.545184 -302.741954)
			(xy 121.568026 -302.791697) (xy 121.583522 -302.844193) (xy 121.591355 -302.898366) (xy 121.591832 -302.925734)
			(xy 124.248926 -302.925734) (xy 124.249406 -302.898364) (xy 124.257219 -302.844185) (xy 124.272705 -302.791682)
			(xy 124.295544 -302.741935) (xy 124.325266 -302.695968) (xy 124.342906 -302.675036) (xy 124.34316 -302.674782)
			(xy 124.348767 -302.66771) (xy 124.355 -302.650782) (xy 124.355352 -302.641762) (xy 124.355352 -302.574706)
			(xy 124.355002 -302.565688) (xy 124.348751 -302.548771) (xy 124.34316 -302.541686) (xy 124.342906 -302.541686)
			(xy 124.342906 -302.541432) (xy 124.325269 -302.520498) (xy 124.295557 -302.474526) (xy 124.27272 -302.424779)
			(xy 124.257229 -302.372279) (xy 124.2494 -302.318103) (xy 124.248926 -302.290734) (xy 124.249412 -302.263483)
			(xy 124.257168 -302.209535) (xy 124.272523 -302.15724) (xy 124.295165 -302.107663) (xy 124.324631 -302.061813)
			(xy 124.360322 -302.020622) (xy 124.401513 -301.984931) (xy 124.447363 -301.955465) (xy 124.49694 -301.932823)
			(xy 124.549235 -301.917468) (xy 124.603183 -301.909712) (xy 124.657685 -301.909712) (xy 124.711633 -301.917468)
			(xy 124.763928 -301.932823) (xy 124.813505 -301.955465) (xy 124.859355 -301.984931) (xy 124.900546 -302.020622)
			(xy 124.936237 -302.061813) (xy 124.965703 -302.107663) (xy 124.988345 -302.15724) (xy 125.0037 -302.209535)
			(xy 125.011456 -302.263483) (xy 125.011942 -302.290734) (xy 125.01151 -302.318106) (xy 125.003686 -302.372287)
			(xy 124.98819 -302.424791) (xy 124.96534 -302.474537) (xy 124.935607 -302.520502) (xy 124.917962 -302.541432)
			(xy 124.917708 -302.541686) (xy 124.912122 -302.548773) (xy 124.905875 -302.565689) (xy 124.905516 -302.574706)
			(xy 124.905516 -302.641762) (xy 124.905888 -302.650777) (xy 124.912125 -302.667695) (xy 124.917708 -302.674782)
			(xy 124.917962 -302.674782) (xy 124.917962 -302.675036) (xy 124.935579 -302.695986) (xy 124.965295 -302.741953)
			(xy 124.988136 -302.791696) (xy 125.003632 -302.844193) (xy 125.011465 -302.898366) (xy 125.011942 -302.925734)
			(xy 125.637036 -302.925734) (xy 125.637513 -302.898364) (xy 125.645327 -302.844185) (xy 125.660813 -302.791682)
			(xy 125.683652 -302.741935) (xy 125.713375 -302.695968) (xy 125.731016 -302.675036) (xy 125.73127 -302.674782)
			(xy 125.736878 -302.667711) (xy 125.74311 -302.650782) (xy 125.743462 -302.641762) (xy 125.743462 -302.574706)
			(xy 125.74311 -302.565688) (xy 125.73686 -302.548771) (xy 125.73127 -302.541686) (xy 125.731016 -302.541686)
			(xy 125.731016 -302.541432) (xy 125.713381 -302.520497) (xy 125.683668 -302.474525) (xy 125.660831 -302.424778)
			(xy 125.645339 -302.372278) (xy 125.63751 -302.318103) (xy 125.637036 -302.290734) (xy 125.637522 -302.263483)
			(xy 125.645278 -302.209535) (xy 125.660633 -302.15724) (xy 125.683275 -302.107663) (xy 125.712741 -302.061813)
			(xy 125.748432 -302.020622) (xy 125.789623 -301.984931) (xy 125.835473 -301.955465) (xy 125.88505 -301.932823)
			(xy 125.937345 -301.917468) (xy 125.991293 -301.909712) (xy 126.045795 -301.909712) (xy 126.099743 -301.917468)
			(xy 126.152038 -301.932823) (xy 126.201615 -301.955465) (xy 126.247465 -301.984931) (xy 126.288656 -302.020622)
			(xy 126.324347 -302.061813) (xy 126.353813 -302.107663) (xy 126.376455 -302.15724) (xy 126.39181 -302.209535)
			(xy 126.399566 -302.263483) (xy 126.400052 -302.290734) (xy 126.399618 -302.318106) (xy 126.391794 -302.372286)
			(xy 126.376298 -302.42479) (xy 126.353449 -302.474537) (xy 126.323717 -302.520502) (xy 126.306072 -302.541432)
			(xy 126.305818 -302.541686) (xy 126.300234 -302.548774) (xy 126.293985 -302.56569) (xy 126.293626 -302.574706)
			(xy 126.293626 -302.641762) (xy 126.293996 -302.650778) (xy 126.300234 -302.667695) (xy 126.305818 -302.674782)
			(xy 126.306072 -302.674782) (xy 126.306072 -302.675036) (xy 126.32369 -302.695985) (xy 126.353406 -302.741953)
			(xy 126.376247 -302.791696) (xy 126.391742 -302.844193) (xy 126.399576 -302.898366) (xy 126.400052 -302.925734)
			(xy 127.669036 -302.925734) (xy 127.669513 -302.898364) (xy 127.677327 -302.844185) (xy 127.692813 -302.791682)
			(xy 127.715652 -302.741935) (xy 127.745375 -302.695968) (xy 127.763016 -302.675036) (xy 127.76327 -302.674782)
			(xy 127.768878 -302.667711) (xy 127.77511 -302.650782) (xy 127.775462 -302.641762) (xy 127.775462 -302.574706)
			(xy 127.77511 -302.565688) (xy 127.76886 -302.548771) (xy 127.76327 -302.541686) (xy 127.763016 -302.541686)
			(xy 127.763016 -302.541432) (xy 127.745381 -302.520497) (xy 127.715668 -302.474525) (xy 127.692831 -302.424778)
			(xy 127.677339 -302.372278) (xy 127.66951 -302.318103) (xy 127.669036 -302.290734) (xy 127.669522 -302.263483)
			(xy 127.677278 -302.209535) (xy 127.692633 -302.15724) (xy 127.715275 -302.107663) (xy 127.744741 -302.061813)
			(xy 127.780432 -302.020622) (xy 127.821623 -301.984931) (xy 127.867473 -301.955465) (xy 127.91705 -301.932823)
			(xy 127.969345 -301.917468) (xy 128.023293 -301.909712) (xy 128.077795 -301.909712) (xy 128.131743 -301.917468)
			(xy 128.184038 -301.932823) (xy 128.233615 -301.955465) (xy 128.279465 -301.984931) (xy 128.320656 -302.020622)
			(xy 128.356347 -302.061813) (xy 128.385813 -302.107663) (xy 128.408455 -302.15724) (xy 128.42381 -302.209535)
			(xy 128.431566 -302.263483) (xy 128.432052 -302.290734) (xy 128.431618 -302.318106) (xy 128.423794 -302.372286)
			(xy 128.408298 -302.42479) (xy 128.385449 -302.474537) (xy 128.355717 -302.520502) (xy 128.338072 -302.541432)
			(xy 128.337818 -302.541686) (xy 128.332234 -302.548774) (xy 128.325985 -302.56569) (xy 128.325626 -302.574706)
			(xy 128.325626 -302.641762) (xy 128.325996 -302.650778) (xy 128.332234 -302.667695) (xy 128.337818 -302.674782)
			(xy 128.338072 -302.674782) (xy 128.338072 -302.675036) (xy 128.35569 -302.695985) (xy 128.385406 -302.741953)
			(xy 128.408247 -302.791696) (xy 128.423742 -302.844193) (xy 128.431576 -302.898366) (xy 128.432052 -302.925734)
			(xy 132.477256 -302.925734) (xy 132.477728 -302.898364) (xy 132.485543 -302.844184) (xy 132.501029 -302.791681)
			(xy 132.52387 -302.741934) (xy 132.553595 -302.695967) (xy 132.571236 -302.675036) (xy 132.57149 -302.674782)
			(xy 132.577089 -302.667704) (xy 132.583329 -302.650781) (xy 132.583682 -302.641762) (xy 132.583682 -302.574706)
			(xy 132.583326 -302.565689) (xy 132.577078 -302.548772) (xy 132.57149 -302.541686) (xy 132.571236 -302.541686)
			(xy 132.571236 -302.541432) (xy 132.553604 -302.520494) (xy 132.52389 -302.474523) (xy 132.501052 -302.424777)
			(xy 132.485559 -302.372278) (xy 132.47773 -302.318103) (xy 132.477256 -302.290734) (xy 132.477742 -302.263483)
			(xy 132.485498 -302.209535) (xy 132.500853 -302.15724) (xy 132.523495 -302.107663) (xy 132.552961 -302.061813)
			(xy 132.588652 -302.020622) (xy 132.629843 -301.984931) (xy 132.675693 -301.955465) (xy 132.72527 -301.932823)
			(xy 132.777565 -301.917468) (xy 132.831513 -301.909712) (xy 132.886015 -301.909712) (xy 132.939963 -301.917468)
			(xy 132.992258 -301.932823) (xy 133.041835 -301.955465) (xy 133.087685 -301.984931) (xy 133.128876 -302.020622)
			(xy 133.164567 -302.061813) (xy 133.194033 -302.107663) (xy 133.216675 -302.15724) (xy 133.23203 -302.209535)
			(xy 133.239786 -302.263483) (xy 133.240272 -302.290734) (xy 133.239833 -302.318105) (xy 133.232009 -302.372286)
			(xy 133.216514 -302.424789) (xy 133.193667 -302.474536) (xy 133.163936 -302.520501) (xy 133.146292 -302.541432)
			(xy 133.146038 -302.541686) (xy 133.140444 -302.548767) (xy 133.134203 -302.565688) (xy 133.133846 -302.574706)
			(xy 133.133846 -302.641762) (xy 133.134211 -302.650778) (xy 133.140452 -302.667696) (xy 133.146038 -302.674782)
			(xy 133.146292 -302.674782) (xy 133.146292 -302.675036) (xy 133.163913 -302.695982) (xy 133.193628 -302.741951)
			(xy 133.216468 -302.791695) (xy 133.231963 -302.844193) (xy 133.239796 -302.898366) (xy 133.240272 -302.925734)
			(xy 133.239786 -302.952985) (xy 133.23203 -303.006933) (xy 133.216675 -303.059228) (xy 133.194033 -303.108805)
			(xy 133.164567 -303.154655) (xy 133.128876 -303.195846) (xy 133.087685 -303.231537) (xy 133.041835 -303.261003)
			(xy 132.992258 -303.283645) (xy 132.939963 -303.299) (xy 132.886015 -303.306756) (xy 132.831513 -303.306756)
			(xy 132.777565 -303.299) (xy 132.72527 -303.283645) (xy 132.675693 -303.261003) (xy 132.629843 -303.231537)
			(xy 132.588652 -303.195846) (xy 132.552961 -303.154655) (xy 132.523495 -303.108805) (xy 132.500853 -303.059228)
			(xy 132.485498 -303.006933) (xy 132.477742 -302.952985) (xy 132.477256 -302.925734) (xy 128.432052 -302.925734)
			(xy 128.431566 -302.952985) (xy 128.42381 -303.006933) (xy 128.408455 -303.059228) (xy 128.385813 -303.108805)
			(xy 128.356347 -303.154655) (xy 128.320656 -303.195846) (xy 128.279465 -303.231537) (xy 128.233615 -303.261003)
			(xy 128.184038 -303.283645) (xy 128.131743 -303.299) (xy 128.077795 -303.306756) (xy 128.023293 -303.306756)
			(xy 127.969345 -303.299) (xy 127.91705 -303.283645) (xy 127.867473 -303.261003) (xy 127.821623 -303.231537)
			(xy 127.780432 -303.195846) (xy 127.744741 -303.154655) (xy 127.715275 -303.108805) (xy 127.692633 -303.059228)
			(xy 127.677278 -303.006933) (xy 127.669522 -302.952985) (xy 127.669036 -302.925734) (xy 126.400052 -302.925734)
			(xy 126.399566 -302.952985) (xy 126.39181 -303.006933) (xy 126.376455 -303.059228) (xy 126.353813 -303.108805)
			(xy 126.324347 -303.154655) (xy 126.288656 -303.195846) (xy 126.247465 -303.231537) (xy 126.201615 -303.261003)
			(xy 126.152038 -303.283645) (xy 126.099743 -303.299) (xy 126.045795 -303.306756) (xy 125.991293 -303.306756)
			(xy 125.937345 -303.299) (xy 125.88505 -303.283645) (xy 125.835473 -303.261003) (xy 125.789623 -303.231537)
			(xy 125.748432 -303.195846) (xy 125.712741 -303.154655) (xy 125.683275 -303.108805) (xy 125.660633 -303.059228)
			(xy 125.645278 -303.006933) (xy 125.637522 -302.952985) (xy 125.637036 -302.925734) (xy 125.011942 -302.925734)
			(xy 125.011456 -302.952985) (xy 125.0037 -303.006933) (xy 124.988345 -303.059228) (xy 124.965703 -303.108805)
			(xy 124.936237 -303.154655) (xy 124.900546 -303.195846) (xy 124.859355 -303.231537) (xy 124.813505 -303.261003)
			(xy 124.763928 -303.283645) (xy 124.711633 -303.299) (xy 124.657685 -303.306756) (xy 124.603183 -303.306756)
			(xy 124.549235 -303.299) (xy 124.49694 -303.283645) (xy 124.447363 -303.261003) (xy 124.401513 -303.231537)
			(xy 124.360322 -303.195846) (xy 124.324631 -303.154655) (xy 124.295165 -303.108805) (xy 124.272523 -303.059228)
			(xy 124.257168 -303.006933) (xy 124.249412 -302.952985) (xy 124.248926 -302.925734) (xy 121.591832 -302.925734)
			(xy 121.591346 -302.952985) (xy 121.58359 -303.006933) (xy 121.568235 -303.059228) (xy 121.545593 -303.108805)
			(xy 121.516127 -303.154655) (xy 121.480436 -303.195846) (xy 121.439245 -303.231537) (xy 121.393395 -303.261003)
			(xy 121.343818 -303.283645) (xy 121.291523 -303.299) (xy 121.237575 -303.306756) (xy 121.183073 -303.306756)
			(xy 121.129125 -303.299) (xy 121.07683 -303.283645) (xy 121.027253 -303.261003) (xy 120.981403 -303.231537)
			(xy 120.940212 -303.195846) (xy 120.904521 -303.154655) (xy 120.875055 -303.108805) (xy 120.852413 -303.059228)
			(xy 120.837058 -303.006933) (xy 120.829302 -302.952985) (xy 120.828816 -302.925734) (xy 118.623386 -302.925734)
			(xy 118.642529 -302.954668) (xy 118.666201 -303.005165) (xy 118.682269 -303.058572) (xy 118.690389 -303.113748)
			(xy 118.690898 -303.141634) (xy 118.690389 -303.16952) (xy 118.682269 -303.224696) (xy 118.666201 -303.278103)
			(xy 118.642529 -303.3286) (xy 118.611756 -303.375113) (xy 118.574539 -303.41665) (xy 118.531671 -303.452325)
			(xy 118.484065 -303.481379) (xy 118.432736 -303.503191) (xy 118.378779 -303.517297) (xy 118.323342 -303.523397)
			(xy 118.267608 -303.52136) (xy 118.212765 -303.51123) (xy 118.159981 -303.493223) (xy 118.110381 -303.467722)
			(xy 118.065023 -303.435271) (xy 118.024874 -303.396562) (xy 117.990788 -303.352419) (xy 117.963492 -303.303784)
			(xy 117.943569 -303.251693) (xy 117.931443 -303.197256) (xy 117.927372 -303.141634) (xy 117.547898 -303.141634)
			(xy 117.547389 -303.16952) (xy 117.539269 -303.224696) (xy 117.523201 -303.278103) (xy 117.499529 -303.3286)
			(xy 117.468756 -303.375113) (xy 117.431539 -303.41665) (xy 117.388671 -303.452325) (xy 117.341065 -303.481379)
			(xy 117.289736 -303.503191) (xy 117.235779 -303.517297) (xy 117.180342 -303.523397) (xy 117.124608 -303.52136)
			(xy 117.069765 -303.51123) (xy 117.016981 -303.493223) (xy 116.967381 -303.467722) (xy 116.922023 -303.435271)
			(xy 116.881874 -303.396562) (xy 116.847788 -303.352419) (xy 116.820492 -303.303784) (xy 116.800569 -303.251693)
			(xy 116.788443 -303.197256) (xy 116.784372 -303.141634) (xy 114.579627 -303.141634) (xy 114.571259 -303.154655)
			(xy 114.535568 -303.195846) (xy 114.494377 -303.231537) (xy 114.448527 -303.261003) (xy 114.39895 -303.283645)
			(xy 114.346655 -303.299) (xy 114.292707 -303.306756) (xy 114.238205 -303.306756) (xy 114.184257 -303.299)
			(xy 114.131962 -303.283645) (xy 114.082385 -303.261003) (xy 114.036535 -303.231537) (xy 113.995344 -303.195846)
			(xy 113.959653 -303.154655) (xy 113.930187 -303.108805) (xy 113.907545 -303.059228) (xy 113.89219 -303.006933)
			(xy 113.884434 -302.952985) (xy 113.883948 -302.925734) (xy 109.838744 -302.925734) (xy 109.838258 -302.952985)
			(xy 109.830502 -303.006933) (xy 109.815147 -303.059228) (xy 109.792505 -303.108805) (xy 109.763039 -303.154655)
			(xy 109.727348 -303.195846) (xy 109.686157 -303.231537) (xy 109.640307 -303.261003) (xy 109.59073 -303.283645)
			(xy 109.538435 -303.299) (xy 109.484487 -303.306756) (xy 109.429985 -303.306756) (xy 109.376037 -303.299)
			(xy 109.323742 -303.283645) (xy 109.274165 -303.261003) (xy 109.228315 -303.231537) (xy 109.187124 -303.195846)
			(xy 109.151433 -303.154655) (xy 109.121967 -303.108805) (xy 109.099325 -303.059228) (xy 109.08397 -303.006933)
			(xy 109.076214 -302.952985) (xy 109.075728 -302.925734) (xy 107.806744 -302.925734) (xy 107.806258 -302.952985)
			(xy 107.798502 -303.006933) (xy 107.783147 -303.059228) (xy 107.760505 -303.108805) (xy 107.731039 -303.154655)
			(xy 107.695348 -303.195846) (xy 107.654157 -303.231537) (xy 107.608307 -303.261003) (xy 107.55873 -303.283645)
			(xy 107.506435 -303.299) (xy 107.452487 -303.306756) (xy 107.397985 -303.306756) (xy 107.344037 -303.299)
			(xy 107.291742 -303.283645) (xy 107.242165 -303.261003) (xy 107.196315 -303.231537) (xy 107.155124 -303.195846)
			(xy 107.119433 -303.154655) (xy 107.089967 -303.108805) (xy 107.067325 -303.059228) (xy 107.05197 -303.006933)
			(xy 107.044214 -302.952985) (xy 107.043728 -302.925734) (xy 106.418634 -302.925734) (xy 106.418148 -302.952985)
			(xy 106.410392 -303.006933) (xy 106.395037 -303.059228) (xy 106.372395 -303.108805) (xy 106.342929 -303.154655)
			(xy 106.307238 -303.195846) (xy 106.266047 -303.231537) (xy 106.220197 -303.261003) (xy 106.17062 -303.283645)
			(xy 106.118325 -303.299) (xy 106.064377 -303.306756) (xy 106.009875 -303.306756) (xy 105.955927 -303.299)
			(xy 105.903632 -303.283645) (xy 105.854055 -303.261003) (xy 105.808205 -303.231537) (xy 105.767014 -303.195846)
			(xy 105.731323 -303.154655) (xy 105.701857 -303.108805) (xy 105.679215 -303.059228) (xy 105.66386 -303.006933)
			(xy 105.656104 -302.952985) (xy 105.655618 -302.925734) (xy 102.998524 -302.925734) (xy 102.998038 -302.952985)
			(xy 102.990282 -303.006933) (xy 102.974927 -303.059228) (xy 102.952285 -303.108805) (xy 102.922819 -303.154655)
			(xy 102.887128 -303.195846) (xy 102.845937 -303.231537) (xy 102.800087 -303.261003) (xy 102.75051 -303.283645)
			(xy 102.698215 -303.299) (xy 102.644267 -303.306756) (xy 102.589765 -303.306756) (xy 102.535817 -303.299)
			(xy 102.483522 -303.283645) (xy 102.433945 -303.261003) (xy 102.388095 -303.231537) (xy 102.346904 -303.195846)
			(xy 102.311213 -303.154655) (xy 102.281747 -303.108805) (xy 102.259105 -303.059228) (xy 102.24375 -303.006933)
			(xy 102.235994 -302.952985) (xy 102.235508 -302.925734) (xy 98.74377 -302.925734) (xy 98.74377 -304.157634)
			(xy 116.784372 -304.157634) (xy 116.788443 -304.102012) (xy 116.800569 -304.047575) (xy 116.820492 -303.995484)
			(xy 116.847788 -303.946849) (xy 116.881874 -303.902706) (xy 116.922023 -303.863997) (xy 116.967381 -303.831546)
			(xy 117.016981 -303.806045) (xy 117.069765 -303.788038) (xy 117.124608 -303.777908) (xy 117.180342 -303.775871)
			(xy 117.235779 -303.781971) (xy 117.289736 -303.796077) (xy 117.341065 -303.817889) (xy 117.388671 -303.846943)
			(xy 117.431539 -303.882618) (xy 117.468756 -303.924155) (xy 117.499529 -303.970668) (xy 117.523201 -304.021165)
			(xy 117.539269 -304.074572) (xy 117.547389 -304.129748) (xy 117.547898 -304.157634) (xy 117.927372 -304.157634)
			(xy 117.931443 -304.102012) (xy 117.943569 -304.047575) (xy 117.963492 -303.995484) (xy 117.990788 -303.946849)
			(xy 118.024874 -303.902706) (xy 118.065023 -303.863997) (xy 118.110381 -303.831546) (xy 118.159981 -303.806045)
			(xy 118.212765 -303.788038) (xy 118.267608 -303.777908) (xy 118.323342 -303.775871) (xy 118.378779 -303.781971)
			(xy 118.432736 -303.796077) (xy 118.484065 -303.817889) (xy 118.531671 -303.846943) (xy 118.574539 -303.882618)
			(xy 118.611756 -303.924155) (xy 118.642529 -303.970668) (xy 118.666201 -304.021165) (xy 118.682269 -304.074572)
			(xy 118.690389 -304.129748) (xy 118.690898 -304.157634) (xy 118.690389 -304.18552) (xy 118.682269 -304.240696)
			(xy 118.666201 -304.294103) (xy 118.642529 -304.3446) (xy 118.611756 -304.391113) (xy 118.574539 -304.43265)
			(xy 118.531671 -304.468325) (xy 118.484065 -304.497379) (xy 118.432736 -304.519191) (xy 118.378779 -304.533297)
			(xy 118.323342 -304.539397) (xy 118.267608 -304.53736) (xy 118.212765 -304.52723) (xy 118.159981 -304.509223)
			(xy 118.110381 -304.483722) (xy 118.065023 -304.451271) (xy 118.024874 -304.412562) (xy 117.990788 -304.368419)
			(xy 117.963492 -304.319784) (xy 117.943569 -304.267693) (xy 117.931443 -304.213256) (xy 117.927372 -304.157634)
			(xy 117.547898 -304.157634) (xy 117.547389 -304.18552) (xy 117.539269 -304.240696) (xy 117.523201 -304.294103)
			(xy 117.499529 -304.3446) (xy 117.468756 -304.391113) (xy 117.431539 -304.43265) (xy 117.388671 -304.468325)
			(xy 117.341065 -304.497379) (xy 117.289736 -304.519191) (xy 117.235779 -304.533297) (xy 117.180342 -304.539397)
			(xy 117.124608 -304.53736) (xy 117.069765 -304.52723) (xy 117.016981 -304.509223) (xy 116.967381 -304.483722)
			(xy 116.922023 -304.451271) (xy 116.881874 -304.412562) (xy 116.847788 -304.368419) (xy 116.820492 -304.319784)
			(xy 116.800569 -304.267693) (xy 116.788443 -304.213256) (xy 116.784372 -304.157634) (xy 98.74377 -304.157634)
			(xy 98.74377 -310.242712) (xy 100.471984 -310.242712) (xy 100.476055 -310.18709) (xy 100.488181 -310.132653)
			(xy 100.508104 -310.080562) (xy 100.5354 -310.031927) (xy 100.569486 -309.987784) (xy 100.609635 -309.949075)
			(xy 100.654993 -309.916624) (xy 100.704593 -309.891123) (xy 100.757377 -309.873116) (xy 100.81222 -309.862986)
			(xy 100.867954 -309.860949) (xy 100.923391 -309.867049) (xy 100.977348 -309.881155) (xy 101.028677 -309.902967)
			(xy 101.076283 -309.932021) (xy 101.119151 -309.967696) (xy 101.156368 -310.009233) (xy 101.187141 -310.055746)
			(xy 101.210813 -310.106243) (xy 101.226881 -310.15965) (xy 101.235001 -310.214826) (xy 101.23551 -310.242712)
			(xy 101.487984 -310.242712) (xy 101.492055 -310.18709) (xy 101.504181 -310.132653) (xy 101.524104 -310.080562)
			(xy 101.5514 -310.031927) (xy 101.585486 -309.987784) (xy 101.625635 -309.949075) (xy 101.670993 -309.916624)
			(xy 101.720593 -309.891123) (xy 101.773377 -309.873116) (xy 101.82822 -309.862986) (xy 101.883954 -309.860949)
			(xy 101.939391 -309.867049) (xy 101.993348 -309.881155) (xy 102.044677 -309.902967) (xy 102.092283 -309.932021)
			(xy 102.135151 -309.967696) (xy 102.172368 -310.009233) (xy 102.203141 -310.055746) (xy 102.226813 -310.106243)
			(xy 102.242881 -310.15965) (xy 102.251001 -310.214826) (xy 102.25151 -310.242712) (xy 102.503984 -310.242712)
			(xy 102.508055 -310.18709) (xy 102.520181 -310.132653) (xy 102.540104 -310.080562) (xy 102.5674 -310.031927)
			(xy 102.601486 -309.987784) (xy 102.641635 -309.949075) (xy 102.686993 -309.916624) (xy 102.736593 -309.891123)
			(xy 102.789377 -309.873116) (xy 102.84422 -309.862986) (xy 102.899954 -309.860949) (xy 102.955391 -309.867049)
			(xy 103.009348 -309.881155) (xy 103.060677 -309.902967) (xy 103.108283 -309.932021) (xy 103.151151 -309.967696)
			(xy 103.188368 -310.009233) (xy 103.219141 -310.055746) (xy 103.242813 -310.106243) (xy 103.258881 -310.15965)
			(xy 103.267001 -310.214826) (xy 103.26751 -310.242712) (xy 103.519984 -310.242712) (xy 103.524055 -310.18709)
			(xy 103.536181 -310.132653) (xy 103.556104 -310.080562) (xy 103.5834 -310.031927) (xy 103.617486 -309.987784)
			(xy 103.657635 -309.949075) (xy 103.702993 -309.916624) (xy 103.752593 -309.891123) (xy 103.805377 -309.873116)
			(xy 103.86022 -309.862986) (xy 103.915954 -309.860949) (xy 103.971391 -309.867049) (xy 104.025348 -309.881155)
			(xy 104.076677 -309.902967) (xy 104.124283 -309.932021) (xy 104.167151 -309.967696) (xy 104.204368 -310.009233)
			(xy 104.235141 -310.055746) (xy 104.258813 -310.106243) (xy 104.274881 -310.15965) (xy 104.283001 -310.214826)
			(xy 104.28351 -310.242712) (xy 104.535984 -310.242712) (xy 104.540055 -310.18709) (xy 104.552181 -310.132653)
			(xy 104.572104 -310.080562) (xy 104.5994 -310.031927) (xy 104.633486 -309.987784) (xy 104.673635 -309.949075)
			(xy 104.718993 -309.916624) (xy 104.768593 -309.891123) (xy 104.821377 -309.873116) (xy 104.87622 -309.862986)
			(xy 104.931954 -309.860949) (xy 104.987391 -309.867049) (xy 105.041348 -309.881155) (xy 105.092677 -309.902967)
			(xy 105.140283 -309.932021) (xy 105.183151 -309.967696) (xy 105.220368 -310.009233) (xy 105.251141 -310.055746)
			(xy 105.274813 -310.106243) (xy 105.290881 -310.15965) (xy 105.299001 -310.214826) (xy 105.29951 -310.242712)
			(xy 105.551984 -310.242712) (xy 105.556055 -310.18709) (xy 105.568181 -310.132653) (xy 105.588104 -310.080562)
			(xy 105.6154 -310.031927) (xy 105.649486 -309.987784) (xy 105.689635 -309.949075) (xy 105.734993 -309.916624)
			(xy 105.784593 -309.891123) (xy 105.837377 -309.873116) (xy 105.89222 -309.862986) (xy 105.947954 -309.860949)
			(xy 106.003391 -309.867049) (xy 106.057348 -309.881155) (xy 106.108677 -309.902967) (xy 106.156283 -309.932021)
			(xy 106.199151 -309.967696) (xy 106.236368 -310.009233) (xy 106.267141 -310.055746) (xy 106.290813 -310.106243)
			(xy 106.306881 -310.15965) (xy 106.315001 -310.214826) (xy 106.31551 -310.242712) (xy 106.567984 -310.242712)
			(xy 106.572055 -310.18709) (xy 106.584181 -310.132653) (xy 106.604104 -310.080562) (xy 106.6314 -310.031927)
			(xy 106.665486 -309.987784) (xy 106.705635 -309.949075) (xy 106.750993 -309.916624) (xy 106.800593 -309.891123)
			(xy 106.853377 -309.873116) (xy 106.90822 -309.862986) (xy 106.963954 -309.860949) (xy 107.019391 -309.867049)
			(xy 107.073348 -309.881155) (xy 107.124677 -309.902967) (xy 107.172283 -309.932021) (xy 107.215151 -309.967696)
			(xy 107.252368 -310.009233) (xy 107.283141 -310.055746) (xy 107.306813 -310.106243) (xy 107.322881 -310.15965)
			(xy 107.331001 -310.214826) (xy 107.33151 -310.242712) (xy 107.583984 -310.242712) (xy 107.588055 -310.18709)
			(xy 107.600181 -310.132653) (xy 107.620104 -310.080562) (xy 107.6474 -310.031927) (xy 107.681486 -309.987784)
			(xy 107.721635 -309.949075) (xy 107.766993 -309.916624) (xy 107.816593 -309.891123) (xy 107.869377 -309.873116)
			(xy 107.92422 -309.862986) (xy 107.979954 -309.860949) (xy 108.035391 -309.867049) (xy 108.089348 -309.881155)
			(xy 108.140677 -309.902967) (xy 108.188283 -309.932021) (xy 108.231151 -309.967696) (xy 108.268368 -310.009233)
			(xy 108.299141 -310.055746) (xy 108.322813 -310.106243) (xy 108.338881 -310.15965) (xy 108.347001 -310.214826)
			(xy 108.34751 -310.242712) (xy 108.599984 -310.242712) (xy 108.604055 -310.18709) (xy 108.616181 -310.132653)
			(xy 108.636104 -310.080562) (xy 108.6634 -310.031927) (xy 108.697486 -309.987784) (xy 108.737635 -309.949075)
			(xy 108.782993 -309.916624) (xy 108.832593 -309.891123) (xy 108.885377 -309.873116) (xy 108.94022 -309.862986)
			(xy 108.995954 -309.860949) (xy 109.051391 -309.867049) (xy 109.105348 -309.881155) (xy 109.156677 -309.902967)
			(xy 109.204283 -309.932021) (xy 109.247151 -309.967696) (xy 109.284368 -310.009233) (xy 109.315141 -310.055746)
			(xy 109.338813 -310.106243) (xy 109.354881 -310.15965) (xy 109.363001 -310.214826) (xy 109.36351 -310.242712)
			(xy 109.615984 -310.242712) (xy 109.620055 -310.18709) (xy 109.632181 -310.132653) (xy 109.652104 -310.080562)
			(xy 109.6794 -310.031927) (xy 109.713486 -309.987784) (xy 109.753635 -309.949075) (xy 109.798993 -309.916624)
			(xy 109.848593 -309.891123) (xy 109.901377 -309.873116) (xy 109.95622 -309.862986) (xy 110.011954 -309.860949)
			(xy 110.067391 -309.867049) (xy 110.121348 -309.881155) (xy 110.172677 -309.902967) (xy 110.220283 -309.932021)
			(xy 110.263151 -309.967696) (xy 110.300368 -310.009233) (xy 110.331141 -310.055746) (xy 110.354813 -310.106243)
			(xy 110.370881 -310.15965) (xy 110.379001 -310.214826) (xy 110.37951 -310.242712) (xy 110.379001 -310.270598)
			(xy 110.370881 -310.325774) (xy 110.354813 -310.379181) (xy 110.331141 -310.429678) (xy 110.326114 -310.437276)
			(xy 125.23673 -310.437276) (xy 125.240801 -310.381654) (xy 125.252927 -310.327217) (xy 125.27285 -310.275126)
			(xy 125.300146 -310.226491) (xy 125.334232 -310.182348) (xy 125.374381 -310.143639) (xy 125.419739 -310.111188)
			(xy 125.469339 -310.085687) (xy 125.522123 -310.06768) (xy 125.576966 -310.05755) (xy 125.6327 -310.055513)
			(xy 125.688137 -310.061613) (xy 125.742094 -310.075719) (xy 125.793423 -310.097531) (xy 125.841029 -310.126585)
			(xy 125.883897 -310.16226) (xy 125.921114 -310.203797) (xy 125.951887 -310.25031) (xy 125.975559 -310.300807)
			(xy 125.991627 -310.354214) (xy 125.999747 -310.40939) (xy 126.000256 -310.437276) (xy 126.25273 -310.437276)
			(xy 126.256801 -310.381654) (xy 126.268927 -310.327217) (xy 126.28885 -310.275126) (xy 126.316146 -310.226491)
			(xy 126.350232 -310.182348) (xy 126.390381 -310.143639) (xy 126.435739 -310.111188) (xy 126.485339 -310.085687)
			(xy 126.538123 -310.06768) (xy 126.592966 -310.05755) (xy 126.6487 -310.055513) (xy 126.704137 -310.061613)
			(xy 126.758094 -310.075719) (xy 126.809423 -310.097531) (xy 126.857029 -310.126585) (xy 126.899897 -310.16226)
			(xy 126.937114 -310.203797) (xy 126.967887 -310.25031) (xy 126.991559 -310.300807) (xy 127.007627 -310.354214)
			(xy 127.015747 -310.40939) (xy 127.016256 -310.437276) (xy 127.26873 -310.437276) (xy 127.272801 -310.381654)
			(xy 127.284927 -310.327217) (xy 127.30485 -310.275126) (xy 127.332146 -310.226491) (xy 127.366232 -310.182348)
			(xy 127.406381 -310.143639) (xy 127.451739 -310.111188) (xy 127.501339 -310.085687) (xy 127.554123 -310.06768)
			(xy 127.608966 -310.05755) (xy 127.6647 -310.055513) (xy 127.720137 -310.061613) (xy 127.774094 -310.075719)
			(xy 127.825423 -310.097531) (xy 127.873029 -310.126585) (xy 127.915897 -310.16226) (xy 127.953114 -310.203797)
			(xy 127.983887 -310.25031) (xy 128.007559 -310.300807) (xy 128.023627 -310.354214) (xy 128.031747 -310.40939)
			(xy 128.032256 -310.437276) (xy 128.28473 -310.437276) (xy 128.288801 -310.381654) (xy 128.300927 -310.327217)
			(xy 128.32085 -310.275126) (xy 128.348146 -310.226491) (xy 128.382232 -310.182348) (xy 128.422381 -310.143639)
			(xy 128.467739 -310.111188) (xy 128.517339 -310.085687) (xy 128.570123 -310.06768) (xy 128.624966 -310.05755)
			(xy 128.6807 -310.055513) (xy 128.736137 -310.061613) (xy 128.790094 -310.075719) (xy 128.841423 -310.097531)
			(xy 128.889029 -310.126585) (xy 128.931897 -310.16226) (xy 128.969114 -310.203797) (xy 128.999887 -310.25031)
			(xy 129.023559 -310.300807) (xy 129.039627 -310.354214) (xy 129.047747 -310.40939) (xy 129.048256 -310.437276)
			(xy 129.30073 -310.437276) (xy 129.304801 -310.381654) (xy 129.316927 -310.327217) (xy 129.33685 -310.275126)
			(xy 129.364146 -310.226491) (xy 129.398232 -310.182348) (xy 129.438381 -310.143639) (xy 129.483739 -310.111188)
			(xy 129.533339 -310.085687) (xy 129.586123 -310.06768) (xy 129.640966 -310.05755) (xy 129.6967 -310.055513)
			(xy 129.752137 -310.061613) (xy 129.806094 -310.075719) (xy 129.857423 -310.097531) (xy 129.905029 -310.126585)
			(xy 129.947897 -310.16226) (xy 129.985114 -310.203797) (xy 130.015887 -310.25031) (xy 130.039559 -310.300807)
			(xy 130.055627 -310.354214) (xy 130.063747 -310.40939) (xy 130.064256 -310.437276) (xy 130.31673 -310.437276)
			(xy 130.320801 -310.381654) (xy 130.332927 -310.327217) (xy 130.35285 -310.275126) (xy 130.380146 -310.226491)
			(xy 130.414232 -310.182348) (xy 130.454381 -310.143639) (xy 130.499739 -310.111188) (xy 130.549339 -310.085687)
			(xy 130.602123 -310.06768) (xy 130.656966 -310.05755) (xy 130.7127 -310.055513) (xy 130.768137 -310.061613)
			(xy 130.822094 -310.075719) (xy 130.873423 -310.097531) (xy 130.921029 -310.126585) (xy 130.963897 -310.16226)
			(xy 131.001114 -310.203797) (xy 131.031887 -310.25031) (xy 131.055559 -310.300807) (xy 131.071627 -310.354214)
			(xy 131.079747 -310.40939) (xy 131.080256 -310.437276) (xy 131.33273 -310.437276) (xy 131.336801 -310.381654)
			(xy 131.348927 -310.327217) (xy 131.36885 -310.275126) (xy 131.396146 -310.226491) (xy 131.430232 -310.182348)
			(xy 131.470381 -310.143639) (xy 131.515739 -310.111188) (xy 131.565339 -310.085687) (xy 131.618123 -310.06768)
			(xy 131.672966 -310.05755) (xy 131.7287 -310.055513) (xy 131.784137 -310.061613) (xy 131.838094 -310.075719)
			(xy 131.889423 -310.097531) (xy 131.937029 -310.126585) (xy 131.979897 -310.16226) (xy 132.017114 -310.203797)
			(xy 132.047887 -310.25031) (xy 132.071559 -310.300807) (xy 132.087627 -310.354214) (xy 132.095747 -310.40939)
			(xy 132.096256 -310.437276) (xy 132.34873 -310.437276) (xy 132.352801 -310.381654) (xy 132.364927 -310.327217)
			(xy 132.38485 -310.275126) (xy 132.412146 -310.226491) (xy 132.446232 -310.182348) (xy 132.486381 -310.143639)
			(xy 132.531739 -310.111188) (xy 132.581339 -310.085687) (xy 132.634123 -310.06768) (xy 132.688966 -310.05755)
			(xy 132.7447 -310.055513) (xy 132.800137 -310.061613) (xy 132.854094 -310.075719) (xy 132.905423 -310.097531)
			(xy 132.953029 -310.126585) (xy 132.995897 -310.16226) (xy 133.033114 -310.203797) (xy 133.063887 -310.25031)
			(xy 133.087559 -310.300807) (xy 133.103627 -310.354214) (xy 133.111747 -310.40939) (xy 133.112256 -310.437276)
			(xy 133.111747 -310.465162) (xy 133.103627 -310.520338) (xy 133.087559 -310.573745) (xy 133.063887 -310.624242)
			(xy 133.033114 -310.670755) (xy 132.995897 -310.712292) (xy 132.953029 -310.747967) (xy 132.905423 -310.777021)
			(xy 132.854094 -310.798833) (xy 132.800137 -310.812939) (xy 132.7447 -310.819039) (xy 132.688966 -310.817002)
			(xy 132.634123 -310.806872) (xy 132.581339 -310.788865) (xy 132.531739 -310.763364) (xy 132.486381 -310.730913)
			(xy 132.446232 -310.692204) (xy 132.412146 -310.648061) (xy 132.38485 -310.599426) (xy 132.364927 -310.547335)
			(xy 132.352801 -310.492898) (xy 132.34873 -310.437276) (xy 132.096256 -310.437276) (xy 132.095747 -310.465162)
			(xy 132.087627 -310.520338) (xy 132.071559 -310.573745) (xy 132.047887 -310.624242) (xy 132.017114 -310.670755)
			(xy 131.979897 -310.712292) (xy 131.937029 -310.747967) (xy 131.889423 -310.777021) (xy 131.838094 -310.798833)
			(xy 131.784137 -310.812939) (xy 131.7287 -310.819039) (xy 131.672966 -310.817002) (xy 131.618123 -310.806872)
			(xy 131.565339 -310.788865) (xy 131.515739 -310.763364) (xy 131.470381 -310.730913) (xy 131.430232 -310.692204)
			(xy 131.396146 -310.648061) (xy 131.36885 -310.599426) (xy 131.348927 -310.547335) (xy 131.336801 -310.492898)
			(xy 131.33273 -310.437276) (xy 131.080256 -310.437276) (xy 131.079747 -310.465162) (xy 131.071627 -310.520338)
			(xy 131.055559 -310.573745) (xy 131.031887 -310.624242) (xy 131.001114 -310.670755) (xy 130.963897 -310.712292)
			(xy 130.921029 -310.747967) (xy 130.873423 -310.777021) (xy 130.822094 -310.798833) (xy 130.768137 -310.812939)
			(xy 130.7127 -310.819039) (xy 130.656966 -310.817002) (xy 130.602123 -310.806872) (xy 130.549339 -310.788865)
			(xy 130.499739 -310.763364) (xy 130.454381 -310.730913) (xy 130.414232 -310.692204) (xy 130.380146 -310.648061)
			(xy 130.35285 -310.599426) (xy 130.332927 -310.547335) (xy 130.320801 -310.492898) (xy 130.31673 -310.437276)
			(xy 130.064256 -310.437276) (xy 130.063747 -310.465162) (xy 130.055627 -310.520338) (xy 130.039559 -310.573745)
			(xy 130.015887 -310.624242) (xy 129.985114 -310.670755) (xy 129.947897 -310.712292) (xy 129.905029 -310.747967)
			(xy 129.857423 -310.777021) (xy 129.806094 -310.798833) (xy 129.752137 -310.812939) (xy 129.6967 -310.819039)
			(xy 129.640966 -310.817002) (xy 129.586123 -310.806872) (xy 129.533339 -310.788865) (xy 129.483739 -310.763364)
			(xy 129.438381 -310.730913) (xy 129.398232 -310.692204) (xy 129.364146 -310.648061) (xy 129.33685 -310.599426)
			(xy 129.316927 -310.547335) (xy 129.304801 -310.492898) (xy 129.30073 -310.437276) (xy 129.048256 -310.437276)
			(xy 129.047747 -310.465162) (xy 129.039627 -310.520338) (xy 129.023559 -310.573745) (xy 128.999887 -310.624242)
			(xy 128.969114 -310.670755) (xy 128.931897 -310.712292) (xy 128.889029 -310.747967) (xy 128.841423 -310.777021)
			(xy 128.790094 -310.798833) (xy 128.736137 -310.812939) (xy 128.6807 -310.819039) (xy 128.624966 -310.817002)
			(xy 128.570123 -310.806872) (xy 128.517339 -310.788865) (xy 128.467739 -310.763364) (xy 128.422381 -310.730913)
			(xy 128.382232 -310.692204) (xy 128.348146 -310.648061) (xy 128.32085 -310.599426) (xy 128.300927 -310.547335)
			(xy 128.288801 -310.492898) (xy 128.28473 -310.437276) (xy 128.032256 -310.437276) (xy 128.031747 -310.465162)
			(xy 128.023627 -310.520338) (xy 128.007559 -310.573745) (xy 127.983887 -310.624242) (xy 127.953114 -310.670755)
			(xy 127.915897 -310.712292) (xy 127.873029 -310.747967) (xy 127.825423 -310.777021) (xy 127.774094 -310.798833)
			(xy 127.720137 -310.812939) (xy 127.6647 -310.819039) (xy 127.608966 -310.817002) (xy 127.554123 -310.806872)
			(xy 127.501339 -310.788865) (xy 127.451739 -310.763364) (xy 127.406381 -310.730913) (xy 127.366232 -310.692204)
			(xy 127.332146 -310.648061) (xy 127.30485 -310.599426) (xy 127.284927 -310.547335) (xy 127.272801 -310.492898)
			(xy 127.26873 -310.437276) (xy 127.016256 -310.437276) (xy 127.015747 -310.465162) (xy 127.007627 -310.520338)
			(xy 126.991559 -310.573745) (xy 126.967887 -310.624242) (xy 126.937114 -310.670755) (xy 126.899897 -310.712292)
			(xy 126.857029 -310.747967) (xy 126.809423 -310.777021) (xy 126.758094 -310.798833) (xy 126.704137 -310.812939)
			(xy 126.6487 -310.819039) (xy 126.592966 -310.817002) (xy 126.538123 -310.806872) (xy 126.485339 -310.788865)
			(xy 126.435739 -310.763364) (xy 126.390381 -310.730913) (xy 126.350232 -310.692204) (xy 126.316146 -310.648061)
			(xy 126.28885 -310.599426) (xy 126.268927 -310.547335) (xy 126.256801 -310.492898) (xy 126.25273 -310.437276)
			(xy 126.000256 -310.437276) (xy 125.999747 -310.465162) (xy 125.991627 -310.520338) (xy 125.975559 -310.573745)
			(xy 125.951887 -310.624242) (xy 125.921114 -310.670755) (xy 125.883897 -310.712292) (xy 125.841029 -310.747967)
			(xy 125.793423 -310.777021) (xy 125.742094 -310.798833) (xy 125.688137 -310.812939) (xy 125.6327 -310.819039)
			(xy 125.576966 -310.817002) (xy 125.522123 -310.806872) (xy 125.469339 -310.788865) (xy 125.419739 -310.763364)
			(xy 125.374381 -310.730913) (xy 125.334232 -310.692204) (xy 125.300146 -310.648061) (xy 125.27285 -310.599426)
			(xy 125.252927 -310.547335) (xy 125.240801 -310.492898) (xy 125.23673 -310.437276) (xy 110.326114 -310.437276)
			(xy 110.300368 -310.476191) (xy 110.263151 -310.517728) (xy 110.220283 -310.553403) (xy 110.172677 -310.582457)
			(xy 110.121348 -310.604269) (xy 110.067391 -310.618375) (xy 110.011954 -310.624475) (xy 109.95622 -310.622438)
			(xy 109.901377 -310.612308) (xy 109.848593 -310.594301) (xy 109.798993 -310.5688) (xy 109.753635 -310.536349)
			(xy 109.713486 -310.49764) (xy 109.6794 -310.453497) (xy 109.652104 -310.404862) (xy 109.632181 -310.352771)
			(xy 109.620055 -310.298334) (xy 109.615984 -310.242712) (xy 109.36351 -310.242712) (xy 109.363001 -310.270598)
			(xy 109.354881 -310.325774) (xy 109.338813 -310.379181) (xy 109.315141 -310.429678) (xy 109.284368 -310.476191)
			(xy 109.247151 -310.517728) (xy 109.204283 -310.553403) (xy 109.156677 -310.582457) (xy 109.105348 -310.604269)
			(xy 109.051391 -310.618375) (xy 108.995954 -310.624475) (xy 108.94022 -310.622438) (xy 108.885377 -310.612308)
			(xy 108.832593 -310.594301) (xy 108.782993 -310.5688) (xy 108.737635 -310.536349) (xy 108.697486 -310.49764)
			(xy 108.6634 -310.453497) (xy 108.636104 -310.404862) (xy 108.616181 -310.352771) (xy 108.604055 -310.298334)
			(xy 108.599984 -310.242712) (xy 108.34751 -310.242712) (xy 108.347001 -310.270598) (xy 108.338881 -310.325774)
			(xy 108.322813 -310.379181) (xy 108.299141 -310.429678) (xy 108.268368 -310.476191) (xy 108.231151 -310.517728)
			(xy 108.188283 -310.553403) (xy 108.140677 -310.582457) (xy 108.089348 -310.604269) (xy 108.035391 -310.618375)
			(xy 107.979954 -310.624475) (xy 107.92422 -310.622438) (xy 107.869377 -310.612308) (xy 107.816593 -310.594301)
			(xy 107.766993 -310.5688) (xy 107.721635 -310.536349) (xy 107.681486 -310.49764) (xy 107.6474 -310.453497)
			(xy 107.620104 -310.404862) (xy 107.600181 -310.352771) (xy 107.588055 -310.298334) (xy 107.583984 -310.242712)
			(xy 107.33151 -310.242712) (xy 107.331001 -310.270598) (xy 107.322881 -310.325774) (xy 107.306813 -310.379181)
			(xy 107.283141 -310.429678) (xy 107.252368 -310.476191) (xy 107.215151 -310.517728) (xy 107.172283 -310.553403)
			(xy 107.124677 -310.582457) (xy 107.073348 -310.604269) (xy 107.019391 -310.618375) (xy 106.963954 -310.624475)
			(xy 106.90822 -310.622438) (xy 106.853377 -310.612308) (xy 106.800593 -310.594301) (xy 106.750993 -310.5688)
			(xy 106.705635 -310.536349) (xy 106.665486 -310.49764) (xy 106.6314 -310.453497) (xy 106.604104 -310.404862)
			(xy 106.584181 -310.352771) (xy 106.572055 -310.298334) (xy 106.567984 -310.242712) (xy 106.31551 -310.242712)
			(xy 106.315001 -310.270598) (xy 106.306881 -310.325774) (xy 106.290813 -310.379181) (xy 106.267141 -310.429678)
			(xy 106.236368 -310.476191) (xy 106.199151 -310.517728) (xy 106.156283 -310.553403) (xy 106.108677 -310.582457)
			(xy 106.057348 -310.604269) (xy 106.003391 -310.618375) (xy 105.947954 -310.624475) (xy 105.89222 -310.622438)
			(xy 105.837377 -310.612308) (xy 105.784593 -310.594301) (xy 105.734993 -310.5688) (xy 105.689635 -310.536349)
			(xy 105.649486 -310.49764) (xy 105.6154 -310.453497) (xy 105.588104 -310.404862) (xy 105.568181 -310.352771)
			(xy 105.556055 -310.298334) (xy 105.551984 -310.242712) (xy 105.29951 -310.242712) (xy 105.299001 -310.270598)
			(xy 105.290881 -310.325774) (xy 105.274813 -310.379181) (xy 105.251141 -310.429678) (xy 105.220368 -310.476191)
			(xy 105.183151 -310.517728) (xy 105.140283 -310.553403) (xy 105.092677 -310.582457) (xy 105.041348 -310.604269)
			(xy 104.987391 -310.618375) (xy 104.931954 -310.624475) (xy 104.87622 -310.622438) (xy 104.821377 -310.612308)
			(xy 104.768593 -310.594301) (xy 104.718993 -310.5688) (xy 104.673635 -310.536349) (xy 104.633486 -310.49764)
			(xy 104.5994 -310.453497) (xy 104.572104 -310.404862) (xy 104.552181 -310.352771) (xy 104.540055 -310.298334)
			(xy 104.535984 -310.242712) (xy 104.28351 -310.242712) (xy 104.283001 -310.270598) (xy 104.274881 -310.325774)
			(xy 104.258813 -310.379181) (xy 104.235141 -310.429678) (xy 104.204368 -310.476191) (xy 104.167151 -310.517728)
			(xy 104.124283 -310.553403) (xy 104.076677 -310.582457) (xy 104.025348 -310.604269) (xy 103.971391 -310.618375)
			(xy 103.915954 -310.624475) (xy 103.86022 -310.622438) (xy 103.805377 -310.612308) (xy 103.752593 -310.594301)
			(xy 103.702993 -310.5688) (xy 103.657635 -310.536349) (xy 103.617486 -310.49764) (xy 103.5834 -310.453497)
			(xy 103.556104 -310.404862) (xy 103.536181 -310.352771) (xy 103.524055 -310.298334) (xy 103.519984 -310.242712)
			(xy 103.26751 -310.242712) (xy 103.267001 -310.270598) (xy 103.258881 -310.325774) (xy 103.242813 -310.379181)
			(xy 103.219141 -310.429678) (xy 103.188368 -310.476191) (xy 103.151151 -310.517728) (xy 103.108283 -310.553403)
			(xy 103.060677 -310.582457) (xy 103.009348 -310.604269) (xy 102.955391 -310.618375) (xy 102.899954 -310.624475)
			(xy 102.84422 -310.622438) (xy 102.789377 -310.612308) (xy 102.736593 -310.594301) (xy 102.686993 -310.5688)
			(xy 102.641635 -310.536349) (xy 102.601486 -310.49764) (xy 102.5674 -310.453497) (xy 102.540104 -310.404862)
			(xy 102.520181 -310.352771) (xy 102.508055 -310.298334) (xy 102.503984 -310.242712) (xy 102.25151 -310.242712)
			(xy 102.251001 -310.270598) (xy 102.242881 -310.325774) (xy 102.226813 -310.379181) (xy 102.203141 -310.429678)
			(xy 102.172368 -310.476191) (xy 102.135151 -310.517728) (xy 102.092283 -310.553403) (xy 102.044677 -310.582457)
			(xy 101.993348 -310.604269) (xy 101.939391 -310.618375) (xy 101.883954 -310.624475) (xy 101.82822 -310.622438)
			(xy 101.773377 -310.612308) (xy 101.720593 -310.594301) (xy 101.670993 -310.5688) (xy 101.625635 -310.536349)
			(xy 101.585486 -310.49764) (xy 101.5514 -310.453497) (xy 101.524104 -310.404862) (xy 101.504181 -310.352771)
			(xy 101.492055 -310.298334) (xy 101.487984 -310.242712) (xy 101.23551 -310.242712) (xy 101.235001 -310.270598)
			(xy 101.226881 -310.325774) (xy 101.210813 -310.379181) (xy 101.187141 -310.429678) (xy 101.156368 -310.476191)
			(xy 101.119151 -310.517728) (xy 101.076283 -310.553403) (xy 101.028677 -310.582457) (xy 100.977348 -310.604269)
			(xy 100.923391 -310.618375) (xy 100.867954 -310.624475) (xy 100.81222 -310.622438) (xy 100.757377 -310.612308)
			(xy 100.704593 -310.594301) (xy 100.654993 -310.5688) (xy 100.609635 -310.536349) (xy 100.569486 -310.49764)
			(xy 100.5354 -310.453497) (xy 100.508104 -310.404862) (xy 100.488181 -310.352771) (xy 100.476055 -310.298334)
			(xy 100.471984 -310.242712) (xy 98.74377 -310.242712) (xy 98.74377 -311.258712) (xy 100.471984 -311.258712)
			(xy 100.476055 -311.20309) (xy 100.488181 -311.148653) (xy 100.508104 -311.096562) (xy 100.5354 -311.047927)
			(xy 100.569486 -311.003784) (xy 100.609635 -310.965075) (xy 100.654993 -310.932624) (xy 100.704593 -310.907123)
			(xy 100.757377 -310.889116) (xy 100.81222 -310.878986) (xy 100.867954 -310.876949) (xy 100.923391 -310.883049)
			(xy 100.977348 -310.897155) (xy 101.028677 -310.918967) (xy 101.076283 -310.948021) (xy 101.119151 -310.983696)
			(xy 101.156368 -311.025233) (xy 101.187141 -311.071746) (xy 101.210813 -311.122243) (xy 101.226881 -311.17565)
			(xy 101.235001 -311.230826) (xy 101.23551 -311.258712) (xy 101.487984 -311.258712) (xy 101.492055 -311.20309)
			(xy 101.504181 -311.148653) (xy 101.524104 -311.096562) (xy 101.5514 -311.047927) (xy 101.585486 -311.003784)
			(xy 101.625635 -310.965075) (xy 101.670993 -310.932624) (xy 101.720593 -310.907123) (xy 101.773377 -310.889116)
			(xy 101.82822 -310.878986) (xy 101.883954 -310.876949) (xy 101.939391 -310.883049) (xy 101.993348 -310.897155)
			(xy 102.044677 -310.918967) (xy 102.092283 -310.948021) (xy 102.135151 -310.983696) (xy 102.172368 -311.025233)
			(xy 102.203141 -311.071746) (xy 102.226813 -311.122243) (xy 102.242881 -311.17565) (xy 102.251001 -311.230826)
			(xy 102.25151 -311.258712) (xy 102.503984 -311.258712) (xy 102.508055 -311.20309) (xy 102.520181 -311.148653)
			(xy 102.540104 -311.096562) (xy 102.5674 -311.047927) (xy 102.601486 -311.003784) (xy 102.641635 -310.965075)
			(xy 102.686993 -310.932624) (xy 102.736593 -310.907123) (xy 102.789377 -310.889116) (xy 102.84422 -310.878986)
			(xy 102.899954 -310.876949) (xy 102.955391 -310.883049) (xy 103.009348 -310.897155) (xy 103.060677 -310.918967)
			(xy 103.108283 -310.948021) (xy 103.151151 -310.983696) (xy 103.188368 -311.025233) (xy 103.219141 -311.071746)
			(xy 103.242813 -311.122243) (xy 103.258881 -311.17565) (xy 103.267001 -311.230826) (xy 103.26751 -311.258712)
			(xy 103.519984 -311.258712) (xy 103.524055 -311.20309) (xy 103.536181 -311.148653) (xy 103.556104 -311.096562)
			(xy 103.5834 -311.047927) (xy 103.617486 -311.003784) (xy 103.657635 -310.965075) (xy 103.702993 -310.932624)
			(xy 103.752593 -310.907123) (xy 103.805377 -310.889116) (xy 103.86022 -310.878986) (xy 103.915954 -310.876949)
			(xy 103.971391 -310.883049) (xy 104.025348 -310.897155) (xy 104.076677 -310.918967) (xy 104.124283 -310.948021)
			(xy 104.167151 -310.983696) (xy 104.204368 -311.025233) (xy 104.235141 -311.071746) (xy 104.258813 -311.122243)
			(xy 104.274881 -311.17565) (xy 104.283001 -311.230826) (xy 104.28351 -311.258712) (xy 104.535984 -311.258712)
			(xy 104.540055 -311.20309) (xy 104.552181 -311.148653) (xy 104.572104 -311.096562) (xy 104.5994 -311.047927)
			(xy 104.633486 -311.003784) (xy 104.673635 -310.965075) (xy 104.718993 -310.932624) (xy 104.768593 -310.907123)
			(xy 104.821377 -310.889116) (xy 104.87622 -310.878986) (xy 104.931954 -310.876949) (xy 104.987391 -310.883049)
			(xy 105.041348 -310.897155) (xy 105.092677 -310.918967) (xy 105.140283 -310.948021) (xy 105.183151 -310.983696)
			(xy 105.220368 -311.025233) (xy 105.251141 -311.071746) (xy 105.274813 -311.122243) (xy 105.290881 -311.17565)
			(xy 105.299001 -311.230826) (xy 105.29951 -311.258712) (xy 105.551984 -311.258712) (xy 105.556055 -311.20309)
			(xy 105.568181 -311.148653) (xy 105.588104 -311.096562) (xy 105.6154 -311.047927) (xy 105.649486 -311.003784)
			(xy 105.689635 -310.965075) (xy 105.734993 -310.932624) (xy 105.784593 -310.907123) (xy 105.837377 -310.889116)
			(xy 105.89222 -310.878986) (xy 105.947954 -310.876949) (xy 106.003391 -310.883049) (xy 106.057348 -310.897155)
			(xy 106.108677 -310.918967) (xy 106.156283 -310.948021) (xy 106.199151 -310.983696) (xy 106.236368 -311.025233)
			(xy 106.267141 -311.071746) (xy 106.290813 -311.122243) (xy 106.306881 -311.17565) (xy 106.315001 -311.230826)
			(xy 106.31551 -311.258712) (xy 106.567984 -311.258712) (xy 106.572055 -311.20309) (xy 106.584181 -311.148653)
			(xy 106.604104 -311.096562) (xy 106.6314 -311.047927) (xy 106.665486 -311.003784) (xy 106.705635 -310.965075)
			(xy 106.750993 -310.932624) (xy 106.800593 -310.907123) (xy 106.853377 -310.889116) (xy 106.90822 -310.878986)
			(xy 106.963954 -310.876949) (xy 107.019391 -310.883049) (xy 107.073348 -310.897155) (xy 107.124677 -310.918967)
			(xy 107.172283 -310.948021) (xy 107.215151 -310.983696) (xy 107.252368 -311.025233) (xy 107.283141 -311.071746)
			(xy 107.306813 -311.122243) (xy 107.322881 -311.17565) (xy 107.331001 -311.230826) (xy 107.33151 -311.258712)
			(xy 107.583984 -311.258712) (xy 107.588055 -311.20309) (xy 107.600181 -311.148653) (xy 107.620104 -311.096562)
			(xy 107.6474 -311.047927) (xy 107.681486 -311.003784) (xy 107.721635 -310.965075) (xy 107.766993 -310.932624)
			(xy 107.816593 -310.907123) (xy 107.869377 -310.889116) (xy 107.92422 -310.878986) (xy 107.979954 -310.876949)
			(xy 108.035391 -310.883049) (xy 108.089348 -310.897155) (xy 108.140677 -310.918967) (xy 108.188283 -310.948021)
			(xy 108.231151 -310.983696) (xy 108.268368 -311.025233) (xy 108.299141 -311.071746) (xy 108.322813 -311.122243)
			(xy 108.338881 -311.17565) (xy 108.347001 -311.230826) (xy 108.34751 -311.258712) (xy 108.599984 -311.258712)
			(xy 108.604055 -311.20309) (xy 108.616181 -311.148653) (xy 108.636104 -311.096562) (xy 108.6634 -311.047927)
			(xy 108.697486 -311.003784) (xy 108.737635 -310.965075) (xy 108.782993 -310.932624) (xy 108.832593 -310.907123)
			(xy 108.885377 -310.889116) (xy 108.94022 -310.878986) (xy 108.995954 -310.876949) (xy 109.051391 -310.883049)
			(xy 109.105348 -310.897155) (xy 109.156677 -310.918967) (xy 109.204283 -310.948021) (xy 109.247151 -310.983696)
			(xy 109.284368 -311.025233) (xy 109.315141 -311.071746) (xy 109.338813 -311.122243) (xy 109.354881 -311.17565)
			(xy 109.363001 -311.230826) (xy 109.36351 -311.258712) (xy 109.615984 -311.258712) (xy 109.620055 -311.20309)
			(xy 109.632181 -311.148653) (xy 109.652104 -311.096562) (xy 109.6794 -311.047927) (xy 109.713486 -311.003784)
			(xy 109.753635 -310.965075) (xy 109.798993 -310.932624) (xy 109.848593 -310.907123) (xy 109.901377 -310.889116)
			(xy 109.95622 -310.878986) (xy 110.011954 -310.876949) (xy 110.067391 -310.883049) (xy 110.121348 -310.897155)
			(xy 110.172677 -310.918967) (xy 110.220283 -310.948021) (xy 110.263151 -310.983696) (xy 110.300368 -311.025233)
			(xy 110.331141 -311.071746) (xy 110.354813 -311.122243) (xy 110.370881 -311.17565) (xy 110.379001 -311.230826)
			(xy 110.37951 -311.258712) (xy 110.379001 -311.286598) (xy 110.370881 -311.341774) (xy 110.354813 -311.395181)
			(xy 110.331141 -311.445678) (xy 110.326114 -311.453276) (xy 125.23673 -311.453276) (xy 125.240801 -311.397654)
			(xy 125.252927 -311.343217) (xy 125.27285 -311.291126) (xy 125.300146 -311.242491) (xy 125.334232 -311.198348)
			(xy 125.374381 -311.159639) (xy 125.419739 -311.127188) (xy 125.469339 -311.101687) (xy 125.522123 -311.08368)
			(xy 125.576966 -311.07355) (xy 125.6327 -311.071513) (xy 125.688137 -311.077613) (xy 125.742094 -311.091719)
			(xy 125.793423 -311.113531) (xy 125.841029 -311.142585) (xy 125.883897 -311.17826) (xy 125.921114 -311.219797)
			(xy 125.951887 -311.26631) (xy 125.975559 -311.316807) (xy 125.991627 -311.370214) (xy 125.999747 -311.42539)
			(xy 126.000256 -311.453276) (xy 126.25273 -311.453276) (xy 126.256801 -311.397654) (xy 126.268927 -311.343217)
			(xy 126.28885 -311.291126) (xy 126.316146 -311.242491) (xy 126.350232 -311.198348) (xy 126.390381 -311.159639)
			(xy 126.435739 -311.127188) (xy 126.485339 -311.101687) (xy 126.538123 -311.08368) (xy 126.592966 -311.07355)
			(xy 126.6487 -311.071513) (xy 126.704137 -311.077613) (xy 126.758094 -311.091719) (xy 126.809423 -311.113531)
			(xy 126.857029 -311.142585) (xy 126.899897 -311.17826) (xy 126.937114 -311.219797) (xy 126.967887 -311.26631)
			(xy 126.991559 -311.316807) (xy 127.007627 -311.370214) (xy 127.015747 -311.42539) (xy 127.016256 -311.453276)
			(xy 127.26873 -311.453276) (xy 127.272801 -311.397654) (xy 127.284927 -311.343217) (xy 127.30485 -311.291126)
			(xy 127.332146 -311.242491) (xy 127.366232 -311.198348) (xy 127.406381 -311.159639) (xy 127.451739 -311.127188)
			(xy 127.501339 -311.101687) (xy 127.554123 -311.08368) (xy 127.608966 -311.07355) (xy 127.6647 -311.071513)
			(xy 127.720137 -311.077613) (xy 127.774094 -311.091719) (xy 127.825423 -311.113531) (xy 127.873029 -311.142585)
			(xy 127.915897 -311.17826) (xy 127.953114 -311.219797) (xy 127.983887 -311.26631) (xy 128.007559 -311.316807)
			(xy 128.023627 -311.370214) (xy 128.031747 -311.42539) (xy 128.032256 -311.453276) (xy 128.28473 -311.453276)
			(xy 128.288801 -311.397654) (xy 128.300927 -311.343217) (xy 128.32085 -311.291126) (xy 128.348146 -311.242491)
			(xy 128.382232 -311.198348) (xy 128.422381 -311.159639) (xy 128.467739 -311.127188) (xy 128.517339 -311.101687)
			(xy 128.570123 -311.08368) (xy 128.624966 -311.07355) (xy 128.6807 -311.071513) (xy 128.736137 -311.077613)
			(xy 128.790094 -311.091719) (xy 128.841423 -311.113531) (xy 128.889029 -311.142585) (xy 128.931897 -311.17826)
			(xy 128.969114 -311.219797) (xy 128.999887 -311.26631) (xy 129.023559 -311.316807) (xy 129.039627 -311.370214)
			(xy 129.047747 -311.42539) (xy 129.048256 -311.453276) (xy 129.30073 -311.453276) (xy 129.304801 -311.397654)
			(xy 129.316927 -311.343217) (xy 129.33685 -311.291126) (xy 129.364146 -311.242491) (xy 129.398232 -311.198348)
			(xy 129.438381 -311.159639) (xy 129.483739 -311.127188) (xy 129.533339 -311.101687) (xy 129.586123 -311.08368)
			(xy 129.640966 -311.07355) (xy 129.6967 -311.071513) (xy 129.752137 -311.077613) (xy 129.806094 -311.091719)
			(xy 129.857423 -311.113531) (xy 129.905029 -311.142585) (xy 129.947897 -311.17826) (xy 129.985114 -311.219797)
			(xy 130.015887 -311.26631) (xy 130.039559 -311.316807) (xy 130.055627 -311.370214) (xy 130.063747 -311.42539)
			(xy 130.064256 -311.453276) (xy 130.31673 -311.453276) (xy 130.320801 -311.397654) (xy 130.332927 -311.343217)
			(xy 130.35285 -311.291126) (xy 130.380146 -311.242491) (xy 130.414232 -311.198348) (xy 130.454381 -311.159639)
			(xy 130.499739 -311.127188) (xy 130.549339 -311.101687) (xy 130.602123 -311.08368) (xy 130.656966 -311.07355)
			(xy 130.7127 -311.071513) (xy 130.768137 -311.077613) (xy 130.822094 -311.091719) (xy 130.873423 -311.113531)
			(xy 130.921029 -311.142585) (xy 130.963897 -311.17826) (xy 131.001114 -311.219797) (xy 131.031887 -311.26631)
			(xy 131.055559 -311.316807) (xy 131.071627 -311.370214) (xy 131.079747 -311.42539) (xy 131.080256 -311.453276)
			(xy 131.33273 -311.453276) (xy 131.336801 -311.397654) (xy 131.348927 -311.343217) (xy 131.36885 -311.291126)
			(xy 131.396146 -311.242491) (xy 131.430232 -311.198348) (xy 131.470381 -311.159639) (xy 131.515739 -311.127188)
			(xy 131.565339 -311.101687) (xy 131.618123 -311.08368) (xy 131.672966 -311.07355) (xy 131.7287 -311.071513)
			(xy 131.784137 -311.077613) (xy 131.838094 -311.091719) (xy 131.889423 -311.113531) (xy 131.937029 -311.142585)
			(xy 131.979897 -311.17826) (xy 132.017114 -311.219797) (xy 132.047887 -311.26631) (xy 132.071559 -311.316807)
			(xy 132.087627 -311.370214) (xy 132.095747 -311.42539) (xy 132.096256 -311.453276) (xy 132.095747 -311.481162)
			(xy 132.087627 -311.536338) (xy 132.071559 -311.589745) (xy 132.047887 -311.640242) (xy 132.017114 -311.686755)
			(xy 131.979897 -311.728292) (xy 131.937029 -311.763967) (xy 131.889423 -311.793021) (xy 131.838094 -311.814833)
			(xy 131.784137 -311.828939) (xy 131.7287 -311.835039) (xy 131.672966 -311.833002) (xy 131.618123 -311.822872)
			(xy 131.565339 -311.804865) (xy 131.515739 -311.779364) (xy 131.470381 -311.746913) (xy 131.430232 -311.708204)
			(xy 131.396146 -311.664061) (xy 131.36885 -311.615426) (xy 131.348927 -311.563335) (xy 131.336801 -311.508898)
			(xy 131.33273 -311.453276) (xy 131.080256 -311.453276) (xy 131.079747 -311.481162) (xy 131.071627 -311.536338)
			(xy 131.055559 -311.589745) (xy 131.031887 -311.640242) (xy 131.001114 -311.686755) (xy 130.963897 -311.728292)
			(xy 130.921029 -311.763967) (xy 130.873423 -311.793021) (xy 130.822094 -311.814833) (xy 130.768137 -311.828939)
			(xy 130.7127 -311.835039) (xy 130.656966 -311.833002) (xy 130.602123 -311.822872) (xy 130.549339 -311.804865)
			(xy 130.499739 -311.779364) (xy 130.454381 -311.746913) (xy 130.414232 -311.708204) (xy 130.380146 -311.664061)
			(xy 130.35285 -311.615426) (xy 130.332927 -311.563335) (xy 130.320801 -311.508898) (xy 130.31673 -311.453276)
			(xy 130.064256 -311.453276) (xy 130.063747 -311.481162) (xy 130.055627 -311.536338) (xy 130.039559 -311.589745)
			(xy 130.015887 -311.640242) (xy 129.985114 -311.686755) (xy 129.947897 -311.728292) (xy 129.905029 -311.763967)
			(xy 129.857423 -311.793021) (xy 129.806094 -311.814833) (xy 129.752137 -311.828939) (xy 129.6967 -311.835039)
			(xy 129.640966 -311.833002) (xy 129.586123 -311.822872) (xy 129.533339 -311.804865) (xy 129.483739 -311.779364)
			(xy 129.438381 -311.746913) (xy 129.398232 -311.708204) (xy 129.364146 -311.664061) (xy 129.33685 -311.615426)
			(xy 129.316927 -311.563335) (xy 129.304801 -311.508898) (xy 129.30073 -311.453276) (xy 129.048256 -311.453276)
			(xy 129.047747 -311.481162) (xy 129.039627 -311.536338) (xy 129.023559 -311.589745) (xy 128.999887 -311.640242)
			(xy 128.969114 -311.686755) (xy 128.931897 -311.728292) (xy 128.889029 -311.763967) (xy 128.841423 -311.793021)
			(xy 128.790094 -311.814833) (xy 128.736137 -311.828939) (xy 128.6807 -311.835039) (xy 128.624966 -311.833002)
			(xy 128.570123 -311.822872) (xy 128.517339 -311.804865) (xy 128.467739 -311.779364) (xy 128.422381 -311.746913)
			(xy 128.382232 -311.708204) (xy 128.348146 -311.664061) (xy 128.32085 -311.615426) (xy 128.300927 -311.563335)
			(xy 128.288801 -311.508898) (xy 128.28473 -311.453276) (xy 128.032256 -311.453276) (xy 128.031747 -311.481162)
			(xy 128.023627 -311.536338) (xy 128.007559 -311.589745) (xy 127.983887 -311.640242) (xy 127.953114 -311.686755)
			(xy 127.915897 -311.728292) (xy 127.873029 -311.763967) (xy 127.825423 -311.793021) (xy 127.774094 -311.814833)
			(xy 127.720137 -311.828939) (xy 127.6647 -311.835039) (xy 127.608966 -311.833002) (xy 127.554123 -311.822872)
			(xy 127.501339 -311.804865) (xy 127.451739 -311.779364) (xy 127.406381 -311.746913) (xy 127.366232 -311.708204)
			(xy 127.332146 -311.664061) (xy 127.30485 -311.615426) (xy 127.284927 -311.563335) (xy 127.272801 -311.508898)
			(xy 127.26873 -311.453276) (xy 127.016256 -311.453276) (xy 127.015747 -311.481162) (xy 127.007627 -311.536338)
			(xy 126.991559 -311.589745) (xy 126.967887 -311.640242) (xy 126.937114 -311.686755) (xy 126.899897 -311.728292)
			(xy 126.857029 -311.763967) (xy 126.809423 -311.793021) (xy 126.758094 -311.814833) (xy 126.704137 -311.828939)
			(xy 126.6487 -311.835039) (xy 126.592966 -311.833002) (xy 126.538123 -311.822872) (xy 126.485339 -311.804865)
			(xy 126.435739 -311.779364) (xy 126.390381 -311.746913) (xy 126.350232 -311.708204) (xy 126.316146 -311.664061)
			(xy 126.28885 -311.615426) (xy 126.268927 -311.563335) (xy 126.256801 -311.508898) (xy 126.25273 -311.453276)
			(xy 126.000256 -311.453276) (xy 125.999747 -311.481162) (xy 125.991627 -311.536338) (xy 125.975559 -311.589745)
			(xy 125.951887 -311.640242) (xy 125.921114 -311.686755) (xy 125.883897 -311.728292) (xy 125.841029 -311.763967)
			(xy 125.793423 -311.793021) (xy 125.742094 -311.814833) (xy 125.688137 -311.828939) (xy 125.6327 -311.835039)
			(xy 125.576966 -311.833002) (xy 125.522123 -311.822872) (xy 125.469339 -311.804865) (xy 125.419739 -311.779364)
			(xy 125.374381 -311.746913) (xy 125.334232 -311.708204) (xy 125.300146 -311.664061) (xy 125.27285 -311.615426)
			(xy 125.252927 -311.563335) (xy 125.240801 -311.508898) (xy 125.23673 -311.453276) (xy 110.326114 -311.453276)
			(xy 110.300368 -311.492191) (xy 110.263151 -311.533728) (xy 110.220283 -311.569403) (xy 110.172677 -311.598457)
			(xy 110.121348 -311.620269) (xy 110.067391 -311.634375) (xy 110.011954 -311.640475) (xy 109.95622 -311.638438)
			(xy 109.901377 -311.628308) (xy 109.848593 -311.610301) (xy 109.798993 -311.5848) (xy 109.753635 -311.552349)
			(xy 109.713486 -311.51364) (xy 109.6794 -311.469497) (xy 109.652104 -311.420862) (xy 109.632181 -311.368771)
			(xy 109.620055 -311.314334) (xy 109.615984 -311.258712) (xy 109.36351 -311.258712) (xy 109.363001 -311.286598)
			(xy 109.354881 -311.341774) (xy 109.338813 -311.395181) (xy 109.315141 -311.445678) (xy 109.284368 -311.492191)
			(xy 109.247151 -311.533728) (xy 109.204283 -311.569403) (xy 109.156677 -311.598457) (xy 109.105348 -311.620269)
			(xy 109.051391 -311.634375) (xy 108.995954 -311.640475) (xy 108.94022 -311.638438) (xy 108.885377 -311.628308)
			(xy 108.832593 -311.610301) (xy 108.782993 -311.5848) (xy 108.737635 -311.552349) (xy 108.697486 -311.51364)
			(xy 108.6634 -311.469497) (xy 108.636104 -311.420862) (xy 108.616181 -311.368771) (xy 108.604055 -311.314334)
			(xy 108.599984 -311.258712) (xy 108.34751 -311.258712) (xy 108.347001 -311.286598) (xy 108.338881 -311.341774)
			(xy 108.322813 -311.395181) (xy 108.299141 -311.445678) (xy 108.268368 -311.492191) (xy 108.231151 -311.533728)
			(xy 108.188283 -311.569403) (xy 108.140677 -311.598457) (xy 108.089348 -311.620269) (xy 108.035391 -311.634375)
			(xy 107.979954 -311.640475) (xy 107.92422 -311.638438) (xy 107.869377 -311.628308) (xy 107.816593 -311.610301)
			(xy 107.766993 -311.5848) (xy 107.721635 -311.552349) (xy 107.681486 -311.51364) (xy 107.6474 -311.469497)
			(xy 107.620104 -311.420862) (xy 107.600181 -311.368771) (xy 107.588055 -311.314334) (xy 107.583984 -311.258712)
			(xy 107.33151 -311.258712) (xy 107.331001 -311.286598) (xy 107.322881 -311.341774) (xy 107.306813 -311.395181)
			(xy 107.283141 -311.445678) (xy 107.252368 -311.492191) (xy 107.215151 -311.533728) (xy 107.172283 -311.569403)
			(xy 107.124677 -311.598457) (xy 107.073348 -311.620269) (xy 107.019391 -311.634375) (xy 106.963954 -311.640475)
			(xy 106.90822 -311.638438) (xy 106.853377 -311.628308) (xy 106.800593 -311.610301) (xy 106.750993 -311.5848)
			(xy 106.705635 -311.552349) (xy 106.665486 -311.51364) (xy 106.6314 -311.469497) (xy 106.604104 -311.420862)
			(xy 106.584181 -311.368771) (xy 106.572055 -311.314334) (xy 106.567984 -311.258712) (xy 106.31551 -311.258712)
			(xy 106.315001 -311.286598) (xy 106.306881 -311.341774) (xy 106.290813 -311.395181) (xy 106.267141 -311.445678)
			(xy 106.236368 -311.492191) (xy 106.199151 -311.533728) (xy 106.156283 -311.569403) (xy 106.108677 -311.598457)
			(xy 106.057348 -311.620269) (xy 106.003391 -311.634375) (xy 105.947954 -311.640475) (xy 105.89222 -311.638438)
			(xy 105.837377 -311.628308) (xy 105.784593 -311.610301) (xy 105.734993 -311.5848) (xy 105.689635 -311.552349)
			(xy 105.649486 -311.51364) (xy 105.6154 -311.469497) (xy 105.588104 -311.420862) (xy 105.568181 -311.368771)
			(xy 105.556055 -311.314334) (xy 105.551984 -311.258712) (xy 105.29951 -311.258712) (xy 105.299001 -311.286598)
			(xy 105.290881 -311.341774) (xy 105.274813 -311.395181) (xy 105.251141 -311.445678) (xy 105.220368 -311.492191)
			(xy 105.183151 -311.533728) (xy 105.140283 -311.569403) (xy 105.092677 -311.598457) (xy 105.041348 -311.620269)
			(xy 104.987391 -311.634375) (xy 104.931954 -311.640475) (xy 104.87622 -311.638438) (xy 104.821377 -311.628308)
			(xy 104.768593 -311.610301) (xy 104.718993 -311.5848) (xy 104.673635 -311.552349) (xy 104.633486 -311.51364)
			(xy 104.5994 -311.469497) (xy 104.572104 -311.420862) (xy 104.552181 -311.368771) (xy 104.540055 -311.314334)
			(xy 104.535984 -311.258712) (xy 104.28351 -311.258712) (xy 104.283001 -311.286598) (xy 104.274881 -311.341774)
			(xy 104.258813 -311.395181) (xy 104.235141 -311.445678) (xy 104.204368 -311.492191) (xy 104.167151 -311.533728)
			(xy 104.124283 -311.569403) (xy 104.076677 -311.598457) (xy 104.025348 -311.620269) (xy 103.971391 -311.634375)
			(xy 103.915954 -311.640475) (xy 103.86022 -311.638438) (xy 103.805377 -311.628308) (xy 103.752593 -311.610301)
			(xy 103.702993 -311.5848) (xy 103.657635 -311.552349) (xy 103.617486 -311.51364) (xy 103.5834 -311.469497)
			(xy 103.556104 -311.420862) (xy 103.536181 -311.368771) (xy 103.524055 -311.314334) (xy 103.519984 -311.258712)
			(xy 103.26751 -311.258712) (xy 103.267001 -311.286598) (xy 103.258881 -311.341774) (xy 103.242813 -311.395181)
			(xy 103.219141 -311.445678) (xy 103.188368 -311.492191) (xy 103.151151 -311.533728) (xy 103.108283 -311.569403)
			(xy 103.060677 -311.598457) (xy 103.009348 -311.620269) (xy 102.955391 -311.634375) (xy 102.899954 -311.640475)
			(xy 102.84422 -311.638438) (xy 102.789377 -311.628308) (xy 102.736593 -311.610301) (xy 102.686993 -311.5848)
			(xy 102.641635 -311.552349) (xy 102.601486 -311.51364) (xy 102.5674 -311.469497) (xy 102.540104 -311.420862)
			(xy 102.520181 -311.368771) (xy 102.508055 -311.314334) (xy 102.503984 -311.258712) (xy 102.25151 -311.258712)
			(xy 102.251001 -311.286598) (xy 102.242881 -311.341774) (xy 102.226813 -311.395181) (xy 102.203141 -311.445678)
			(xy 102.172368 -311.492191) (xy 102.135151 -311.533728) (xy 102.092283 -311.569403) (xy 102.044677 -311.598457)
			(xy 101.993348 -311.620269) (xy 101.939391 -311.634375) (xy 101.883954 -311.640475) (xy 101.82822 -311.638438)
			(xy 101.773377 -311.628308) (xy 101.720593 -311.610301) (xy 101.670993 -311.5848) (xy 101.625635 -311.552349)
			(xy 101.585486 -311.51364) (xy 101.5514 -311.469497) (xy 101.524104 -311.420862) (xy 101.504181 -311.368771)
			(xy 101.492055 -311.314334) (xy 101.487984 -311.258712) (xy 101.23551 -311.258712) (xy 101.235001 -311.286598)
			(xy 101.226881 -311.341774) (xy 101.210813 -311.395181) (xy 101.187141 -311.445678) (xy 101.156368 -311.492191)
			(xy 101.119151 -311.533728) (xy 101.076283 -311.569403) (xy 101.028677 -311.598457) (xy 100.977348 -311.620269)
			(xy 100.923391 -311.634375) (xy 100.867954 -311.640475) (xy 100.81222 -311.638438) (xy 100.757377 -311.628308)
			(xy 100.704593 -311.610301) (xy 100.654993 -311.5848) (xy 100.609635 -311.552349) (xy 100.569486 -311.51364)
			(xy 100.5354 -311.469497) (xy 100.508104 -311.420862) (xy 100.488181 -311.368771) (xy 100.476055 -311.314334)
			(xy 100.471984 -311.258712) (xy 98.74377 -311.258712) (xy 98.74377 -311.689242) (xy 98.7442 -311.699309)
			(xy 98.751922 -311.717906) (xy 98.758756 -311.72531) (xy 99.308158 -312.274712) (xy 100.471984 -312.274712)
			(xy 100.476055 -312.21909) (xy 100.488181 -312.164653) (xy 100.508104 -312.112562) (xy 100.5354 -312.063927)
			(xy 100.569486 -312.019784) (xy 100.609635 -311.981075) (xy 100.654993 -311.948624) (xy 100.704593 -311.923123)
			(xy 100.757377 -311.905116) (xy 100.81222 -311.894986) (xy 100.867954 -311.892949) (xy 100.923391 -311.899049)
			(xy 100.977348 -311.913155) (xy 101.028677 -311.934967) (xy 101.076283 -311.964021) (xy 101.119151 -311.999696)
			(xy 101.156368 -312.041233) (xy 101.187141 -312.087746) (xy 101.210813 -312.138243) (xy 101.226881 -312.19165)
			(xy 101.235001 -312.246826) (xy 101.23551 -312.274712) (xy 101.487984 -312.274712) (xy 101.492055 -312.21909)
			(xy 101.504181 -312.164653) (xy 101.524104 -312.112562) (xy 101.5514 -312.063927) (xy 101.585486 -312.019784)
			(xy 101.625635 -311.981075) (xy 101.670993 -311.948624) (xy 101.720593 -311.923123) (xy 101.773377 -311.905116)
			(xy 101.82822 -311.894986) (xy 101.883954 -311.892949) (xy 101.939391 -311.899049) (xy 101.993348 -311.913155)
			(xy 102.044677 -311.934967) (xy 102.092283 -311.964021) (xy 102.135151 -311.999696) (xy 102.172368 -312.041233)
			(xy 102.203141 -312.087746) (xy 102.226813 -312.138243) (xy 102.242881 -312.19165) (xy 102.251001 -312.246826)
			(xy 102.25151 -312.274712) (xy 102.503984 -312.274712) (xy 102.508055 -312.21909) (xy 102.520181 -312.164653)
			(xy 102.540104 -312.112562) (xy 102.5674 -312.063927) (xy 102.601486 -312.019784) (xy 102.641635 -311.981075)
			(xy 102.686993 -311.948624) (xy 102.736593 -311.923123) (xy 102.789377 -311.905116) (xy 102.84422 -311.894986)
			(xy 102.899954 -311.892949) (xy 102.955391 -311.899049) (xy 103.009348 -311.913155) (xy 103.060677 -311.934967)
			(xy 103.108283 -311.964021) (xy 103.151151 -311.999696) (xy 103.188368 -312.041233) (xy 103.219141 -312.087746)
			(xy 103.242813 -312.138243) (xy 103.258881 -312.19165) (xy 103.267001 -312.246826) (xy 103.26751 -312.274712)
			(xy 103.519984 -312.274712) (xy 103.524055 -312.21909) (xy 103.536181 -312.164653) (xy 103.556104 -312.112562)
			(xy 103.5834 -312.063927) (xy 103.617486 -312.019784) (xy 103.657635 -311.981075) (xy 103.702993 -311.948624)
			(xy 103.752593 -311.923123) (xy 103.805377 -311.905116) (xy 103.86022 -311.894986) (xy 103.915954 -311.892949)
			(xy 103.971391 -311.899049) (xy 104.025348 -311.913155) (xy 104.076677 -311.934967) (xy 104.124283 -311.964021)
			(xy 104.167151 -311.999696) (xy 104.204368 -312.041233) (xy 104.235141 -312.087746) (xy 104.258813 -312.138243)
			(xy 104.274881 -312.19165) (xy 104.283001 -312.246826) (xy 104.28351 -312.274712) (xy 104.535984 -312.274712)
			(xy 104.540055 -312.21909) (xy 104.552181 -312.164653) (xy 104.572104 -312.112562) (xy 104.5994 -312.063927)
			(xy 104.633486 -312.019784) (xy 104.673635 -311.981075) (xy 104.718993 -311.948624) (xy 104.768593 -311.923123)
			(xy 104.821377 -311.905116) (xy 104.87622 -311.894986) (xy 104.931954 -311.892949) (xy 104.987391 -311.899049)
			(xy 105.041348 -311.913155) (xy 105.092677 -311.934967) (xy 105.140283 -311.964021) (xy 105.183151 -311.999696)
			(xy 105.220368 -312.041233) (xy 105.251141 -312.087746) (xy 105.274813 -312.138243) (xy 105.290881 -312.19165)
			(xy 105.299001 -312.246826) (xy 105.29951 -312.274712) (xy 105.551984 -312.274712) (xy 105.556055 -312.21909)
			(xy 105.568181 -312.164653) (xy 105.588104 -312.112562) (xy 105.6154 -312.063927) (xy 105.649486 -312.019784)
			(xy 105.689635 -311.981075) (xy 105.734993 -311.948624) (xy 105.784593 -311.923123) (xy 105.837377 -311.905116)
			(xy 105.89222 -311.894986) (xy 105.947954 -311.892949) (xy 106.003391 -311.899049) (xy 106.057348 -311.913155)
			(xy 106.108677 -311.934967) (xy 106.156283 -311.964021) (xy 106.199151 -311.999696) (xy 106.236368 -312.041233)
			(xy 106.267141 -312.087746) (xy 106.290813 -312.138243) (xy 106.306881 -312.19165) (xy 106.315001 -312.246826)
			(xy 106.31551 -312.274712) (xy 106.567984 -312.274712) (xy 106.572055 -312.21909) (xy 106.584181 -312.164653)
			(xy 106.604104 -312.112562) (xy 106.6314 -312.063927) (xy 106.665486 -312.019784) (xy 106.705635 -311.981075)
			(xy 106.750993 -311.948624) (xy 106.800593 -311.923123) (xy 106.853377 -311.905116) (xy 106.90822 -311.894986)
			(xy 106.963954 -311.892949) (xy 107.019391 -311.899049) (xy 107.073348 -311.913155) (xy 107.124677 -311.934967)
			(xy 107.172283 -311.964021) (xy 107.215151 -311.999696) (xy 107.252368 -312.041233) (xy 107.283141 -312.087746)
			(xy 107.306813 -312.138243) (xy 107.322881 -312.19165) (xy 107.331001 -312.246826) (xy 107.33151 -312.274712)
			(xy 107.583984 -312.274712) (xy 107.588055 -312.21909) (xy 107.600181 -312.164653) (xy 107.620104 -312.112562)
			(xy 107.6474 -312.063927) (xy 107.681486 -312.019784) (xy 107.721635 -311.981075) (xy 107.766993 -311.948624)
			(xy 107.816593 -311.923123) (xy 107.869377 -311.905116) (xy 107.92422 -311.894986) (xy 107.979954 -311.892949)
			(xy 108.035391 -311.899049) (xy 108.089348 -311.913155) (xy 108.140677 -311.934967) (xy 108.188283 -311.964021)
			(xy 108.231151 -311.999696) (xy 108.268368 -312.041233) (xy 108.299141 -312.087746) (xy 108.322813 -312.138243)
			(xy 108.338881 -312.19165) (xy 108.347001 -312.246826) (xy 108.34751 -312.274712) (xy 108.599984 -312.274712)
			(xy 108.604055 -312.21909) (xy 108.616181 -312.164653) (xy 108.636104 -312.112562) (xy 108.6634 -312.063927)
			(xy 108.697486 -312.019784) (xy 108.737635 -311.981075) (xy 108.782993 -311.948624) (xy 108.832593 -311.923123)
			(xy 108.885377 -311.905116) (xy 108.94022 -311.894986) (xy 108.995954 -311.892949) (xy 109.051391 -311.899049)
			(xy 109.105348 -311.913155) (xy 109.156677 -311.934967) (xy 109.204283 -311.964021) (xy 109.247151 -311.999696)
			(xy 109.284368 -312.041233) (xy 109.315141 -312.087746) (xy 109.338813 -312.138243) (xy 109.354881 -312.19165)
			(xy 109.363001 -312.246826) (xy 109.36351 -312.274712) (xy 109.615984 -312.274712) (xy 109.620055 -312.21909)
			(xy 109.632181 -312.164653) (xy 109.652104 -312.112562) (xy 109.6794 -312.063927) (xy 109.713486 -312.019784)
			(xy 109.753635 -311.981075) (xy 109.798993 -311.948624) (xy 109.848593 -311.923123) (xy 109.901377 -311.905116)
			(xy 109.95622 -311.894986) (xy 110.011954 -311.892949) (xy 110.067391 -311.899049) (xy 110.121348 -311.913155)
			(xy 110.172677 -311.934967) (xy 110.220283 -311.964021) (xy 110.263151 -311.999696) (xy 110.300368 -312.041233)
			(xy 110.331141 -312.087746) (xy 110.354813 -312.138243) (xy 110.370881 -312.19165) (xy 110.379001 -312.246826)
			(xy 110.37951 -312.274712) (xy 110.379001 -312.302598) (xy 110.370881 -312.357774) (xy 110.354813 -312.411181)
			(xy 110.331141 -312.461678) (xy 110.326114 -312.469276) (xy 125.23673 -312.469276) (xy 125.240801 -312.413654)
			(xy 125.252927 -312.359217) (xy 125.27285 -312.307126) (xy 125.300146 -312.258491) (xy 125.334232 -312.214348)
			(xy 125.374381 -312.175639) (xy 125.419739 -312.143188) (xy 125.469339 -312.117687) (xy 125.522123 -312.09968)
			(xy 125.576966 -312.08955) (xy 125.6327 -312.087513) (xy 125.688137 -312.093613) (xy 125.742094 -312.107719)
			(xy 125.793423 -312.129531) (xy 125.841029 -312.158585) (xy 125.883897 -312.19426) (xy 125.921114 -312.235797)
			(xy 125.951887 -312.28231) (xy 125.975559 -312.332807) (xy 125.991627 -312.386214) (xy 125.999747 -312.44139)
			(xy 126.000256 -312.469276) (xy 126.25273 -312.469276) (xy 126.256801 -312.413654) (xy 126.268927 -312.359217)
			(xy 126.28885 -312.307126) (xy 126.316146 -312.258491) (xy 126.350232 -312.214348) (xy 126.390381 -312.175639)
			(xy 126.435739 -312.143188) (xy 126.485339 -312.117687) (xy 126.538123 -312.09968) (xy 126.592966 -312.08955)
			(xy 126.6487 -312.087513) (xy 126.704137 -312.093613) (xy 126.758094 -312.107719) (xy 126.809423 -312.129531)
			(xy 126.857029 -312.158585) (xy 126.899897 -312.19426) (xy 126.937114 -312.235797) (xy 126.967887 -312.28231)
			(xy 126.991559 -312.332807) (xy 127.007627 -312.386214) (xy 127.015747 -312.44139) (xy 127.016256 -312.469276)
			(xy 127.26873 -312.469276) (xy 127.272801 -312.413654) (xy 127.284927 -312.359217) (xy 127.30485 -312.307126)
			(xy 127.332146 -312.258491) (xy 127.366232 -312.214348) (xy 127.406381 -312.175639) (xy 127.451739 -312.143188)
			(xy 127.501339 -312.117687) (xy 127.554123 -312.09968) (xy 127.608966 -312.08955) (xy 127.6647 -312.087513)
			(xy 127.720137 -312.093613) (xy 127.774094 -312.107719) (xy 127.825423 -312.129531) (xy 127.873029 -312.158585)
			(xy 127.915897 -312.19426) (xy 127.953114 -312.235797) (xy 127.983887 -312.28231) (xy 128.007559 -312.332807)
			(xy 128.023627 -312.386214) (xy 128.031747 -312.44139) (xy 128.032256 -312.469276) (xy 128.28473 -312.469276)
			(xy 128.288801 -312.413654) (xy 128.300927 -312.359217) (xy 128.32085 -312.307126) (xy 128.348146 -312.258491)
			(xy 128.382232 -312.214348) (xy 128.422381 -312.175639) (xy 128.467739 -312.143188) (xy 128.517339 -312.117687)
			(xy 128.570123 -312.09968) (xy 128.624966 -312.08955) (xy 128.6807 -312.087513) (xy 128.736137 -312.093613)
			(xy 128.790094 -312.107719) (xy 128.841423 -312.129531) (xy 128.889029 -312.158585) (xy 128.931897 -312.19426)
			(xy 128.969114 -312.235797) (xy 128.999887 -312.28231) (xy 129.023559 -312.332807) (xy 129.039627 -312.386214)
			(xy 129.047747 -312.44139) (xy 129.048256 -312.469276) (xy 129.30073 -312.469276) (xy 129.304801 -312.413654)
			(xy 129.316927 -312.359217) (xy 129.33685 -312.307126) (xy 129.364146 -312.258491) (xy 129.398232 -312.214348)
			(xy 129.438381 -312.175639) (xy 129.483739 -312.143188) (xy 129.533339 -312.117687) (xy 129.586123 -312.09968)
			(xy 129.640966 -312.08955) (xy 129.6967 -312.087513) (xy 129.752137 -312.093613) (xy 129.806094 -312.107719)
			(xy 129.857423 -312.129531) (xy 129.905029 -312.158585) (xy 129.947897 -312.19426) (xy 129.985114 -312.235797)
			(xy 130.015887 -312.28231) (xy 130.039559 -312.332807) (xy 130.055627 -312.386214) (xy 130.063747 -312.44139)
			(xy 130.064256 -312.469276) (xy 130.31673 -312.469276) (xy 130.320801 -312.413654) (xy 130.332927 -312.359217)
			(xy 130.35285 -312.307126) (xy 130.380146 -312.258491) (xy 130.414232 -312.214348) (xy 130.454381 -312.175639)
			(xy 130.499739 -312.143188) (xy 130.549339 -312.117687) (xy 130.602123 -312.09968) (xy 130.656966 -312.08955)
			(xy 130.7127 -312.087513) (xy 130.768137 -312.093613) (xy 130.822094 -312.107719) (xy 130.873423 -312.129531)
			(xy 130.921029 -312.158585) (xy 130.963897 -312.19426) (xy 131.001114 -312.235797) (xy 131.031887 -312.28231)
			(xy 131.055559 -312.332807) (xy 131.071627 -312.386214) (xy 131.079747 -312.44139) (xy 131.080256 -312.469276)
			(xy 131.33273 -312.469276) (xy 131.336801 -312.413654) (xy 131.348927 -312.359217) (xy 131.36885 -312.307126)
			(xy 131.396146 -312.258491) (xy 131.430232 -312.214348) (xy 131.470381 -312.175639) (xy 131.515739 -312.143188)
			(xy 131.565339 -312.117687) (xy 131.618123 -312.09968) (xy 131.672966 -312.08955) (xy 131.7287 -312.087513)
			(xy 131.784137 -312.093613) (xy 131.838094 -312.107719) (xy 131.889423 -312.129531) (xy 131.937029 -312.158585)
			(xy 131.979897 -312.19426) (xy 132.017114 -312.235797) (xy 132.047887 -312.28231) (xy 132.071559 -312.332807)
			(xy 132.087627 -312.386214) (xy 132.095747 -312.44139) (xy 132.096256 -312.469276) (xy 132.095747 -312.497162)
			(xy 132.087627 -312.552338) (xy 132.071559 -312.605745) (xy 132.047887 -312.656242) (xy 132.017114 -312.702755)
			(xy 131.979897 -312.744292) (xy 131.937029 -312.779967) (xy 131.889423 -312.809021) (xy 131.838094 -312.830833)
			(xy 131.784137 -312.844939) (xy 131.7287 -312.851039) (xy 131.672966 -312.849002) (xy 131.618123 -312.838872)
			(xy 131.565339 -312.820865) (xy 131.515739 -312.795364) (xy 131.470381 -312.762913) (xy 131.430232 -312.724204)
			(xy 131.396146 -312.680061) (xy 131.36885 -312.631426) (xy 131.348927 -312.579335) (xy 131.336801 -312.524898)
			(xy 131.33273 -312.469276) (xy 131.080256 -312.469276) (xy 131.079747 -312.497162) (xy 131.071627 -312.552338)
			(xy 131.055559 -312.605745) (xy 131.031887 -312.656242) (xy 131.001114 -312.702755) (xy 130.963897 -312.744292)
			(xy 130.921029 -312.779967) (xy 130.873423 -312.809021) (xy 130.822094 -312.830833) (xy 130.768137 -312.844939)
			(xy 130.7127 -312.851039) (xy 130.656966 -312.849002) (xy 130.602123 -312.838872) (xy 130.549339 -312.820865)
			(xy 130.499739 -312.795364) (xy 130.454381 -312.762913) (xy 130.414232 -312.724204) (xy 130.380146 -312.680061)
			(xy 130.35285 -312.631426) (xy 130.332927 -312.579335) (xy 130.320801 -312.524898) (xy 130.31673 -312.469276)
			(xy 130.064256 -312.469276) (xy 130.063747 -312.497162) (xy 130.055627 -312.552338) (xy 130.039559 -312.605745)
			(xy 130.015887 -312.656242) (xy 129.985114 -312.702755) (xy 129.947897 -312.744292) (xy 129.905029 -312.779967)
			(xy 129.857423 -312.809021) (xy 129.806094 -312.830833) (xy 129.752137 -312.844939) (xy 129.6967 -312.851039)
			(xy 129.640966 -312.849002) (xy 129.586123 -312.838872) (xy 129.533339 -312.820865) (xy 129.483739 -312.795364)
			(xy 129.438381 -312.762913) (xy 129.398232 -312.724204) (xy 129.364146 -312.680061) (xy 129.33685 -312.631426)
			(xy 129.316927 -312.579335) (xy 129.304801 -312.524898) (xy 129.30073 -312.469276) (xy 129.048256 -312.469276)
			(xy 129.047747 -312.497162) (xy 129.039627 -312.552338) (xy 129.023559 -312.605745) (xy 128.999887 -312.656242)
			(xy 128.969114 -312.702755) (xy 128.931897 -312.744292) (xy 128.889029 -312.779967) (xy 128.841423 -312.809021)
			(xy 128.790094 -312.830833) (xy 128.736137 -312.844939) (xy 128.6807 -312.851039) (xy 128.624966 -312.849002)
			(xy 128.570123 -312.838872) (xy 128.517339 -312.820865) (xy 128.467739 -312.795364) (xy 128.422381 -312.762913)
			(xy 128.382232 -312.724204) (xy 128.348146 -312.680061) (xy 128.32085 -312.631426) (xy 128.300927 -312.579335)
			(xy 128.288801 -312.524898) (xy 128.28473 -312.469276) (xy 128.032256 -312.469276) (xy 128.031747 -312.497162)
			(xy 128.023627 -312.552338) (xy 128.007559 -312.605745) (xy 127.983887 -312.656242) (xy 127.953114 -312.702755)
			(xy 127.915897 -312.744292) (xy 127.873029 -312.779967) (xy 127.825423 -312.809021) (xy 127.774094 -312.830833)
			(xy 127.720137 -312.844939) (xy 127.6647 -312.851039) (xy 127.608966 -312.849002) (xy 127.554123 -312.838872)
			(xy 127.501339 -312.820865) (xy 127.451739 -312.795364) (xy 127.406381 -312.762913) (xy 127.366232 -312.724204)
			(xy 127.332146 -312.680061) (xy 127.30485 -312.631426) (xy 127.284927 -312.579335) (xy 127.272801 -312.524898)
			(xy 127.26873 -312.469276) (xy 127.016256 -312.469276) (xy 127.015747 -312.497162) (xy 127.007627 -312.552338)
			(xy 126.991559 -312.605745) (xy 126.967887 -312.656242) (xy 126.937114 -312.702755) (xy 126.899897 -312.744292)
			(xy 126.857029 -312.779967) (xy 126.809423 -312.809021) (xy 126.758094 -312.830833) (xy 126.704137 -312.844939)
			(xy 126.6487 -312.851039) (xy 126.592966 -312.849002) (xy 126.538123 -312.838872) (xy 126.485339 -312.820865)
			(xy 126.435739 -312.795364) (xy 126.390381 -312.762913) (xy 126.350232 -312.724204) (xy 126.316146 -312.680061)
			(xy 126.28885 -312.631426) (xy 126.268927 -312.579335) (xy 126.256801 -312.524898) (xy 126.25273 -312.469276)
			(xy 126.000256 -312.469276) (xy 125.999747 -312.497162) (xy 125.991627 -312.552338) (xy 125.975559 -312.605745)
			(xy 125.951887 -312.656242) (xy 125.921114 -312.702755) (xy 125.883897 -312.744292) (xy 125.841029 -312.779967)
			(xy 125.793423 -312.809021) (xy 125.742094 -312.830833) (xy 125.688137 -312.844939) (xy 125.6327 -312.851039)
			(xy 125.576966 -312.849002) (xy 125.522123 -312.838872) (xy 125.469339 -312.820865) (xy 125.419739 -312.795364)
			(xy 125.374381 -312.762913) (xy 125.334232 -312.724204) (xy 125.300146 -312.680061) (xy 125.27285 -312.631426)
			(xy 125.252927 -312.579335) (xy 125.240801 -312.524898) (xy 125.23673 -312.469276) (xy 110.326114 -312.469276)
			(xy 110.300368 -312.508191) (xy 110.263151 -312.549728) (xy 110.220283 -312.585403) (xy 110.172677 -312.614457)
			(xy 110.121348 -312.636269) (xy 110.067391 -312.650375) (xy 110.011954 -312.656475) (xy 109.95622 -312.654438)
			(xy 109.901377 -312.644308) (xy 109.848593 -312.626301) (xy 109.798993 -312.6008) (xy 109.753635 -312.568349)
			(xy 109.713486 -312.52964) (xy 109.6794 -312.485497) (xy 109.652104 -312.436862) (xy 109.632181 -312.384771)
			(xy 109.620055 -312.330334) (xy 109.615984 -312.274712) (xy 109.36351 -312.274712) (xy 109.363001 -312.302598)
			(xy 109.354881 -312.357774) (xy 109.338813 -312.411181) (xy 109.315141 -312.461678) (xy 109.284368 -312.508191)
			(xy 109.247151 -312.549728) (xy 109.204283 -312.585403) (xy 109.156677 -312.614457) (xy 109.105348 -312.636269)
			(xy 109.051391 -312.650375) (xy 108.995954 -312.656475) (xy 108.94022 -312.654438) (xy 108.885377 -312.644308)
			(xy 108.832593 -312.626301) (xy 108.782993 -312.6008) (xy 108.737635 -312.568349) (xy 108.697486 -312.52964)
			(xy 108.6634 -312.485497) (xy 108.636104 -312.436862) (xy 108.616181 -312.384771) (xy 108.604055 -312.330334)
			(xy 108.599984 -312.274712) (xy 108.34751 -312.274712) (xy 108.347001 -312.302598) (xy 108.338881 -312.357774)
			(xy 108.322813 -312.411181) (xy 108.299141 -312.461678) (xy 108.268368 -312.508191) (xy 108.231151 -312.549728)
			(xy 108.188283 -312.585403) (xy 108.140677 -312.614457) (xy 108.089348 -312.636269) (xy 108.035391 -312.650375)
			(xy 107.979954 -312.656475) (xy 107.92422 -312.654438) (xy 107.869377 -312.644308) (xy 107.816593 -312.626301)
			(xy 107.766993 -312.6008) (xy 107.721635 -312.568349) (xy 107.681486 -312.52964) (xy 107.6474 -312.485497)
			(xy 107.620104 -312.436862) (xy 107.600181 -312.384771) (xy 107.588055 -312.330334) (xy 107.583984 -312.274712)
			(xy 107.33151 -312.274712) (xy 107.331001 -312.302598) (xy 107.322881 -312.357774) (xy 107.306813 -312.411181)
			(xy 107.283141 -312.461678) (xy 107.252368 -312.508191) (xy 107.215151 -312.549728) (xy 107.172283 -312.585403)
			(xy 107.124677 -312.614457) (xy 107.073348 -312.636269) (xy 107.019391 -312.650375) (xy 106.963954 -312.656475)
			(xy 106.90822 -312.654438) (xy 106.853377 -312.644308) (xy 106.800593 -312.626301) (xy 106.750993 -312.6008)
			(xy 106.705635 -312.568349) (xy 106.665486 -312.52964) (xy 106.6314 -312.485497) (xy 106.604104 -312.436862)
			(xy 106.584181 -312.384771) (xy 106.572055 -312.330334) (xy 106.567984 -312.274712) (xy 106.31551 -312.274712)
			(xy 106.315001 -312.302598) (xy 106.306881 -312.357774) (xy 106.290813 -312.411181) (xy 106.267141 -312.461678)
			(xy 106.236368 -312.508191) (xy 106.199151 -312.549728) (xy 106.156283 -312.585403) (xy 106.108677 -312.614457)
			(xy 106.057348 -312.636269) (xy 106.003391 -312.650375) (xy 105.947954 -312.656475) (xy 105.89222 -312.654438)
			(xy 105.837377 -312.644308) (xy 105.784593 -312.626301) (xy 105.734993 -312.6008) (xy 105.689635 -312.568349)
			(xy 105.649486 -312.52964) (xy 105.6154 -312.485497) (xy 105.588104 -312.436862) (xy 105.568181 -312.384771)
			(xy 105.556055 -312.330334) (xy 105.551984 -312.274712) (xy 105.29951 -312.274712) (xy 105.299001 -312.302598)
			(xy 105.290881 -312.357774) (xy 105.274813 -312.411181) (xy 105.251141 -312.461678) (xy 105.220368 -312.508191)
			(xy 105.183151 -312.549728) (xy 105.140283 -312.585403) (xy 105.092677 -312.614457) (xy 105.041348 -312.636269)
			(xy 104.987391 -312.650375) (xy 104.931954 -312.656475) (xy 104.87622 -312.654438) (xy 104.821377 -312.644308)
			(xy 104.768593 -312.626301) (xy 104.718993 -312.6008) (xy 104.673635 -312.568349) (xy 104.633486 -312.52964)
			(xy 104.5994 -312.485497) (xy 104.572104 -312.436862) (xy 104.552181 -312.384771) (xy 104.540055 -312.330334)
			(xy 104.535984 -312.274712) (xy 104.28351 -312.274712) (xy 104.283001 -312.302598) (xy 104.274881 -312.357774)
			(xy 104.258813 -312.411181) (xy 104.235141 -312.461678) (xy 104.204368 -312.508191) (xy 104.167151 -312.549728)
			(xy 104.124283 -312.585403) (xy 104.076677 -312.614457) (xy 104.025348 -312.636269) (xy 103.971391 -312.650375)
			(xy 103.915954 -312.656475) (xy 103.86022 -312.654438) (xy 103.805377 -312.644308) (xy 103.752593 -312.626301)
			(xy 103.702993 -312.6008) (xy 103.657635 -312.568349) (xy 103.617486 -312.52964) (xy 103.5834 -312.485497)
			(xy 103.556104 -312.436862) (xy 103.536181 -312.384771) (xy 103.524055 -312.330334) (xy 103.519984 -312.274712)
			(xy 103.26751 -312.274712) (xy 103.267001 -312.302598) (xy 103.258881 -312.357774) (xy 103.242813 -312.411181)
			(xy 103.219141 -312.461678) (xy 103.188368 -312.508191) (xy 103.151151 -312.549728) (xy 103.108283 -312.585403)
			(xy 103.060677 -312.614457) (xy 103.009348 -312.636269) (xy 102.955391 -312.650375) (xy 102.899954 -312.656475)
			(xy 102.84422 -312.654438) (xy 102.789377 -312.644308) (xy 102.736593 -312.626301) (xy 102.686993 -312.6008)
			(xy 102.641635 -312.568349) (xy 102.601486 -312.52964) (xy 102.5674 -312.485497) (xy 102.540104 -312.436862)
			(xy 102.520181 -312.384771) (xy 102.508055 -312.330334) (xy 102.503984 -312.274712) (xy 102.25151 -312.274712)
			(xy 102.251001 -312.302598) (xy 102.242881 -312.357774) (xy 102.226813 -312.411181) (xy 102.203141 -312.461678)
			(xy 102.172368 -312.508191) (xy 102.135151 -312.549728) (xy 102.092283 -312.585403) (xy 102.044677 -312.614457)
			(xy 101.993348 -312.636269) (xy 101.939391 -312.650375) (xy 101.883954 -312.656475) (xy 101.82822 -312.654438)
			(xy 101.773377 -312.644308) (xy 101.720593 -312.626301) (xy 101.670993 -312.6008) (xy 101.625635 -312.568349)
			(xy 101.585486 -312.52964) (xy 101.5514 -312.485497) (xy 101.524104 -312.436862) (xy 101.504181 -312.384771)
			(xy 101.492055 -312.330334) (xy 101.487984 -312.274712) (xy 101.23551 -312.274712) (xy 101.235001 -312.302598)
			(xy 101.226881 -312.357774) (xy 101.210813 -312.411181) (xy 101.187141 -312.461678) (xy 101.156368 -312.508191)
			(xy 101.119151 -312.549728) (xy 101.076283 -312.585403) (xy 101.028677 -312.614457) (xy 100.977348 -312.636269)
			(xy 100.923391 -312.650375) (xy 100.867954 -312.656475) (xy 100.81222 -312.654438) (xy 100.757377 -312.644308)
			(xy 100.704593 -312.626301) (xy 100.654993 -312.6008) (xy 100.609635 -312.568349) (xy 100.569486 -312.52964)
			(xy 100.5354 -312.485497) (xy 100.508104 -312.436862) (xy 100.488181 -312.384771) (xy 100.476055 -312.330334)
			(xy 100.471984 -312.274712) (xy 99.308158 -312.274712) (xy 100.307394 -313.273948) (xy 100.314189 -313.280142)
			(xy 100.33096 -313.287643) (xy 100.3493 -313.288729) (xy 100.358194 -313.286394) (xy 100.457762 -313.25566)
			(xy 100.476304 -313.234832) (xy 100.477828 -313.227466) (xy 100.482722 -313.201119) (xy 100.498923 -313.150039)
			(xy 100.522112 -313.101728) (xy 100.551832 -313.057137) (xy 100.587499 -313.017143) (xy 100.628411 -312.982533)
			(xy 100.673764 -312.953987) (xy 100.722664 -312.932068) (xy 100.774149 -312.917207) (xy 100.827208 -312.909695)
			(xy 100.854002 -312.909204) (xy 100.881252 -312.90969) (xy 100.935198 -312.917447) (xy 100.987491 -312.932802)
			(xy 101.037066 -312.955442) (xy 101.082915 -312.984908) (xy 101.124103 -313.020598) (xy 101.159794 -313.061787)
			(xy 101.189259 -313.107636) (xy 101.211899 -313.157211) (xy 101.227254 -313.209504) (xy 101.23501 -313.26345)
			(xy 101.23501 -313.290712) (xy 101.487984 -313.290712) (xy 101.492055 -313.23509) (xy 101.504181 -313.180653)
			(xy 101.524104 -313.128562) (xy 101.5514 -313.079927) (xy 101.585486 -313.035784) (xy 101.625635 -312.997075)
			(xy 101.670993 -312.964624) (xy 101.720593 -312.939123) (xy 101.773377 -312.921116) (xy 101.82822 -312.910986)
			(xy 101.883954 -312.908949) (xy 101.939391 -312.915049) (xy 101.993348 -312.929155) (xy 102.044677 -312.950967)
			(xy 102.092283 -312.980021) (xy 102.135151 -313.015696) (xy 102.172368 -313.057233) (xy 102.203141 -313.103746)
			(xy 102.226813 -313.154243) (xy 102.242881 -313.20765) (xy 102.251001 -313.262826) (xy 102.25151 -313.290712)
			(xy 102.503984 -313.290712) (xy 102.508055 -313.23509) (xy 102.520181 -313.180653) (xy 102.540104 -313.128562)
			(xy 102.5674 -313.079927) (xy 102.601486 -313.035784) (xy 102.641635 -312.997075) (xy 102.686993 -312.964624)
			(xy 102.736593 -312.939123) (xy 102.789377 -312.921116) (xy 102.84422 -312.910986) (xy 102.899954 -312.908949)
			(xy 102.955391 -312.915049) (xy 103.009348 -312.929155) (xy 103.060677 -312.950967) (xy 103.108283 -312.980021)
			(xy 103.151151 -313.015696) (xy 103.188368 -313.057233) (xy 103.219141 -313.103746) (xy 103.242813 -313.154243)
			(xy 103.258881 -313.20765) (xy 103.267001 -313.262826) (xy 103.26751 -313.290712) (xy 103.519984 -313.290712)
			(xy 103.524055 -313.23509) (xy 103.536181 -313.180653) (xy 103.556104 -313.128562) (xy 103.5834 -313.079927)
			(xy 103.617486 -313.035784) (xy 103.657635 -312.997075) (xy 103.702993 -312.964624) (xy 103.752593 -312.939123)
			(xy 103.805377 -312.921116) (xy 103.86022 -312.910986) (xy 103.915954 -312.908949) (xy 103.971391 -312.915049)
			(xy 104.025348 -312.929155) (xy 104.076677 -312.950967) (xy 104.124283 -312.980021) (xy 104.167151 -313.015696)
			(xy 104.204368 -313.057233) (xy 104.235141 -313.103746) (xy 104.258813 -313.154243) (xy 104.274881 -313.20765)
			(xy 104.283001 -313.262826) (xy 104.28351 -313.290712) (xy 104.535984 -313.290712) (xy 104.540055 -313.23509)
			(xy 104.552181 -313.180653) (xy 104.572104 -313.128562) (xy 104.5994 -313.079927) (xy 104.633486 -313.035784)
			(xy 104.673635 -312.997075) (xy 104.718993 -312.964624) (xy 104.768593 -312.939123) (xy 104.821377 -312.921116)
			(xy 104.87622 -312.910986) (xy 104.931954 -312.908949) (xy 104.987391 -312.915049) (xy 105.041348 -312.929155)
			(xy 105.092677 -312.950967) (xy 105.140283 -312.980021) (xy 105.183151 -313.015696) (xy 105.220368 -313.057233)
			(xy 105.251141 -313.103746) (xy 105.274813 -313.154243) (xy 105.290881 -313.20765) (xy 105.299001 -313.262826)
			(xy 105.29951 -313.290712) (xy 105.551984 -313.290712) (xy 105.556055 -313.23509) (xy 105.568181 -313.180653)
			(xy 105.588104 -313.128562) (xy 105.6154 -313.079927) (xy 105.649486 -313.035784) (xy 105.689635 -312.997075)
			(xy 105.734993 -312.964624) (xy 105.784593 -312.939123) (xy 105.837377 -312.921116) (xy 105.89222 -312.910986)
			(xy 105.947954 -312.908949) (xy 106.003391 -312.915049) (xy 106.057348 -312.929155) (xy 106.108677 -312.950967)
			(xy 106.156283 -312.980021) (xy 106.199151 -313.015696) (xy 106.236368 -313.057233) (xy 106.267141 -313.103746)
			(xy 106.290813 -313.154243) (xy 106.306881 -313.20765) (xy 106.315001 -313.262826) (xy 106.31551 -313.290712)
			(xy 106.567984 -313.290712) (xy 106.572055 -313.23509) (xy 106.584181 -313.180653) (xy 106.604104 -313.128562)
			(xy 106.6314 -313.079927) (xy 106.665486 -313.035784) (xy 106.705635 -312.997075) (xy 106.750993 -312.964624)
			(xy 106.800593 -312.939123) (xy 106.853377 -312.921116) (xy 106.90822 -312.910986) (xy 106.963954 -312.908949)
			(xy 107.019391 -312.915049) (xy 107.073348 -312.929155) (xy 107.124677 -312.950967) (xy 107.172283 -312.980021)
			(xy 107.215151 -313.015696) (xy 107.252368 -313.057233) (xy 107.283141 -313.103746) (xy 107.306813 -313.154243)
			(xy 107.322881 -313.20765) (xy 107.331001 -313.262826) (xy 107.33151 -313.290712) (xy 107.583984 -313.290712)
			(xy 107.588055 -313.23509) (xy 107.600181 -313.180653) (xy 107.620104 -313.128562) (xy 107.6474 -313.079927)
			(xy 107.681486 -313.035784) (xy 107.721635 -312.997075) (xy 107.766993 -312.964624) (xy 107.816593 -312.939123)
			(xy 107.869377 -312.921116) (xy 107.92422 -312.910986) (xy 107.979954 -312.908949) (xy 108.035391 -312.915049)
			(xy 108.089348 -312.929155) (xy 108.140677 -312.950967) (xy 108.188283 -312.980021) (xy 108.231151 -313.015696)
			(xy 108.268368 -313.057233) (xy 108.299141 -313.103746) (xy 108.322813 -313.154243) (xy 108.338881 -313.20765)
			(xy 108.347001 -313.262826) (xy 108.34751 -313.290712) (xy 108.599984 -313.290712) (xy 108.604055 -313.23509)
			(xy 108.616181 -313.180653) (xy 108.636104 -313.128562) (xy 108.6634 -313.079927) (xy 108.697486 -313.035784)
			(xy 108.737635 -312.997075) (xy 108.782993 -312.964624) (xy 108.832593 -312.939123) (xy 108.885377 -312.921116)
			(xy 108.94022 -312.910986) (xy 108.995954 -312.908949) (xy 109.051391 -312.915049) (xy 109.105348 -312.929155)
			(xy 109.156677 -312.950967) (xy 109.204283 -312.980021) (xy 109.247151 -313.015696) (xy 109.284368 -313.057233)
			(xy 109.315141 -313.103746) (xy 109.338813 -313.154243) (xy 109.354881 -313.20765) (xy 109.363001 -313.262826)
			(xy 109.36351 -313.290712) (xy 109.615984 -313.290712) (xy 109.620055 -313.23509) (xy 109.632181 -313.180653)
			(xy 109.652104 -313.128562) (xy 109.6794 -313.079927) (xy 109.713486 -313.035784) (xy 109.753635 -312.997075)
			(xy 109.798993 -312.964624) (xy 109.848593 -312.939123) (xy 109.901377 -312.921116) (xy 109.95622 -312.910986)
			(xy 110.011954 -312.908949) (xy 110.067391 -312.915049) (xy 110.121348 -312.929155) (xy 110.172677 -312.950967)
			(xy 110.220283 -312.980021) (xy 110.263151 -313.015696) (xy 110.300368 -313.057233) (xy 110.331141 -313.103746)
			(xy 110.354813 -313.154243) (xy 110.370881 -313.20765) (xy 110.379001 -313.262826) (xy 110.37951 -313.290712)
			(xy 110.379001 -313.318598) (xy 110.370881 -313.373774) (xy 110.354813 -313.427181) (xy 110.331141 -313.477678)
			(xy 110.326114 -313.485276) (xy 125.23673 -313.485276) (xy 125.240801 -313.429654) (xy 125.252927 -313.375217)
			(xy 125.27285 -313.323126) (xy 125.300146 -313.274491) (xy 125.334232 -313.230348) (xy 125.374381 -313.191639)
			(xy 125.419739 -313.159188) (xy 125.469339 -313.133687) (xy 125.522123 -313.11568) (xy 125.576966 -313.10555)
			(xy 125.6327 -313.103513) (xy 125.688137 -313.109613) (xy 125.742094 -313.123719) (xy 125.793423 -313.145531)
			(xy 125.841029 -313.174585) (xy 125.883897 -313.21026) (xy 125.921114 -313.251797) (xy 125.951887 -313.29831)
			(xy 125.975559 -313.348807) (xy 125.991627 -313.402214) (xy 125.999747 -313.45739) (xy 126.000256 -313.485276)
			(xy 126.25273 -313.485276) (xy 126.256801 -313.429654) (xy 126.268927 -313.375217) (xy 126.28885 -313.323126)
			(xy 126.316146 -313.274491) (xy 126.350232 -313.230348) (xy 126.390381 -313.191639) (xy 126.435739 -313.159188)
			(xy 126.485339 -313.133687) (xy 126.538123 -313.11568) (xy 126.592966 -313.10555) (xy 126.6487 -313.103513)
			(xy 126.704137 -313.109613) (xy 126.758094 -313.123719) (xy 126.809423 -313.145531) (xy 126.857029 -313.174585)
			(xy 126.899897 -313.21026) (xy 126.937114 -313.251797) (xy 126.967887 -313.29831) (xy 126.991559 -313.348807)
			(xy 127.007627 -313.402214) (xy 127.015747 -313.45739) (xy 127.016256 -313.485276) (xy 127.26873 -313.485276)
			(xy 127.272801 -313.429654) (xy 127.284927 -313.375217) (xy 127.30485 -313.323126) (xy 127.332146 -313.274491)
			(xy 127.366232 -313.230348) (xy 127.406381 -313.191639) (xy 127.451739 -313.159188) (xy 127.501339 -313.133687)
			(xy 127.554123 -313.11568) (xy 127.608966 -313.10555) (xy 127.6647 -313.103513) (xy 127.720137 -313.109613)
			(xy 127.774094 -313.123719) (xy 127.825423 -313.145531) (xy 127.873029 -313.174585) (xy 127.915897 -313.21026)
			(xy 127.953114 -313.251797) (xy 127.983887 -313.29831) (xy 128.007559 -313.348807) (xy 128.023627 -313.402214)
			(xy 128.031747 -313.45739) (xy 128.032256 -313.485276) (xy 128.28473 -313.485276) (xy 128.288801 -313.429654)
			(xy 128.300927 -313.375217) (xy 128.32085 -313.323126) (xy 128.348146 -313.274491) (xy 128.382232 -313.230348)
			(xy 128.422381 -313.191639) (xy 128.467739 -313.159188) (xy 128.517339 -313.133687) (xy 128.570123 -313.11568)
			(xy 128.624966 -313.10555) (xy 128.6807 -313.103513) (xy 128.736137 -313.109613) (xy 128.790094 -313.123719)
			(xy 128.841423 -313.145531) (xy 128.889029 -313.174585) (xy 128.931897 -313.21026) (xy 128.969114 -313.251797)
			(xy 128.999887 -313.29831) (xy 129.023559 -313.348807) (xy 129.039627 -313.402214) (xy 129.047747 -313.45739)
			(xy 129.048256 -313.485276) (xy 129.30073 -313.485276) (xy 129.304801 -313.429654) (xy 129.316927 -313.375217)
			(xy 129.33685 -313.323126) (xy 129.364146 -313.274491) (xy 129.398232 -313.230348) (xy 129.438381 -313.191639)
			(xy 129.483739 -313.159188) (xy 129.533339 -313.133687) (xy 129.586123 -313.11568) (xy 129.640966 -313.10555)
			(xy 129.6967 -313.103513) (xy 129.752137 -313.109613) (xy 129.806094 -313.123719) (xy 129.857423 -313.145531)
			(xy 129.905029 -313.174585) (xy 129.947897 -313.21026) (xy 129.985114 -313.251797) (xy 130.015887 -313.29831)
			(xy 130.039559 -313.348807) (xy 130.055627 -313.402214) (xy 130.063747 -313.45739) (xy 130.064256 -313.485276)
			(xy 130.31673 -313.485276) (xy 130.320801 -313.429654) (xy 130.332927 -313.375217) (xy 130.35285 -313.323126)
			(xy 130.380146 -313.274491) (xy 130.414232 -313.230348) (xy 130.454381 -313.191639) (xy 130.499739 -313.159188)
			(xy 130.549339 -313.133687) (xy 130.602123 -313.11568) (xy 130.656966 -313.10555) (xy 130.7127 -313.103513)
			(xy 130.768137 -313.109613) (xy 130.822094 -313.123719) (xy 130.873423 -313.145531) (xy 130.921029 -313.174585)
			(xy 130.963897 -313.21026) (xy 131.001114 -313.251797) (xy 131.031887 -313.29831) (xy 131.055559 -313.348807)
			(xy 131.071627 -313.402214) (xy 131.079747 -313.45739) (xy 131.080256 -313.485276) (xy 131.079747 -313.513162)
			(xy 131.071627 -313.568338) (xy 131.055559 -313.621745) (xy 131.031887 -313.672242) (xy 131.001114 -313.718755)
			(xy 130.963897 -313.760292) (xy 130.921029 -313.795967) (xy 130.873423 -313.825021) (xy 130.822094 -313.846833)
			(xy 130.768137 -313.860939) (xy 130.7127 -313.867039) (xy 130.656966 -313.865002) (xy 130.602123 -313.854872)
			(xy 130.549339 -313.836865) (xy 130.499739 -313.811364) (xy 130.454381 -313.778913) (xy 130.414232 -313.740204)
			(xy 130.380146 -313.696061) (xy 130.35285 -313.647426) (xy 130.332927 -313.595335) (xy 130.320801 -313.540898)
			(xy 130.31673 -313.485276) (xy 130.064256 -313.485276) (xy 130.063747 -313.513162) (xy 130.055627 -313.568338)
			(xy 130.039559 -313.621745) (xy 130.015887 -313.672242) (xy 129.985114 -313.718755) (xy 129.947897 -313.760292)
			(xy 129.905029 -313.795967) (xy 129.857423 -313.825021) (xy 129.806094 -313.846833) (xy 129.752137 -313.860939)
			(xy 129.6967 -313.867039) (xy 129.640966 -313.865002) (xy 129.586123 -313.854872) (xy 129.533339 -313.836865)
			(xy 129.483739 -313.811364) (xy 129.438381 -313.778913) (xy 129.398232 -313.740204) (xy 129.364146 -313.696061)
			(xy 129.33685 -313.647426) (xy 129.316927 -313.595335) (xy 129.304801 -313.540898) (xy 129.30073 -313.485276)
			(xy 129.048256 -313.485276) (xy 129.047747 -313.513162) (xy 129.039627 -313.568338) (xy 129.023559 -313.621745)
			(xy 128.999887 -313.672242) (xy 128.969114 -313.718755) (xy 128.931897 -313.760292) (xy 128.889029 -313.795967)
			(xy 128.841423 -313.825021) (xy 128.790094 -313.846833) (xy 128.736137 -313.860939) (xy 128.6807 -313.867039)
			(xy 128.624966 -313.865002) (xy 128.570123 -313.854872) (xy 128.517339 -313.836865) (xy 128.467739 -313.811364)
			(xy 128.422381 -313.778913) (xy 128.382232 -313.740204) (xy 128.348146 -313.696061) (xy 128.32085 -313.647426)
			(xy 128.300927 -313.595335) (xy 128.288801 -313.540898) (xy 128.28473 -313.485276) (xy 128.032256 -313.485276)
			(xy 128.031747 -313.513162) (xy 128.023627 -313.568338) (xy 128.007559 -313.621745) (xy 127.983887 -313.672242)
			(xy 127.953114 -313.718755) (xy 127.915897 -313.760292) (xy 127.873029 -313.795967) (xy 127.825423 -313.825021)
			(xy 127.774094 -313.846833) (xy 127.720137 -313.860939) (xy 127.6647 -313.867039) (xy 127.608966 -313.865002)
			(xy 127.554123 -313.854872) (xy 127.501339 -313.836865) (xy 127.451739 -313.811364) (xy 127.406381 -313.778913)
			(xy 127.366232 -313.740204) (xy 127.332146 -313.696061) (xy 127.30485 -313.647426) (xy 127.284927 -313.595335)
			(xy 127.272801 -313.540898) (xy 127.26873 -313.485276) (xy 127.016256 -313.485276) (xy 127.015747 -313.513162)
			(xy 127.007627 -313.568338) (xy 126.991559 -313.621745) (xy 126.967887 -313.672242) (xy 126.937114 -313.718755)
			(xy 126.899897 -313.760292) (xy 126.857029 -313.795967) (xy 126.809423 -313.825021) (xy 126.758094 -313.846833)
			(xy 126.704137 -313.860939) (xy 126.6487 -313.867039) (xy 126.592966 -313.865002) (xy 126.538123 -313.854872)
			(xy 126.485339 -313.836865) (xy 126.435739 -313.811364) (xy 126.390381 -313.778913) (xy 126.350232 -313.740204)
			(xy 126.316146 -313.696061) (xy 126.28885 -313.647426) (xy 126.268927 -313.595335) (xy 126.256801 -313.540898)
			(xy 126.25273 -313.485276) (xy 126.000256 -313.485276) (xy 125.999747 -313.513162) (xy 125.991627 -313.568338)
			(xy 125.975559 -313.621745) (xy 125.951887 -313.672242) (xy 125.921114 -313.718755) (xy 125.883897 -313.760292)
			(xy 125.841029 -313.795967) (xy 125.793423 -313.825021) (xy 125.742094 -313.846833) (xy 125.688137 -313.860939)
			(xy 125.6327 -313.867039) (xy 125.576966 -313.865002) (xy 125.522123 -313.854872) (xy 125.469339 -313.836865)
			(xy 125.419739 -313.811364) (xy 125.374381 -313.778913) (xy 125.334232 -313.740204) (xy 125.300146 -313.696061)
			(xy 125.27285 -313.647426) (xy 125.252927 -313.595335) (xy 125.240801 -313.540898) (xy 125.23673 -313.485276)
			(xy 110.326114 -313.485276) (xy 110.300368 -313.524191) (xy 110.263151 -313.565728) (xy 110.220283 -313.601403)
			(xy 110.172677 -313.630457) (xy 110.121348 -313.652269) (xy 110.067391 -313.666375) (xy 110.011954 -313.672475)
			(xy 109.95622 -313.670438) (xy 109.901377 -313.660308) (xy 109.848593 -313.642301) (xy 109.798993 -313.6168)
			(xy 109.753635 -313.584349) (xy 109.713486 -313.54564) (xy 109.6794 -313.501497) (xy 109.652104 -313.452862)
			(xy 109.632181 -313.400771) (xy 109.620055 -313.346334) (xy 109.615984 -313.290712) (xy 109.36351 -313.290712)
			(xy 109.363001 -313.318598) (xy 109.354881 -313.373774) (xy 109.338813 -313.427181) (xy 109.315141 -313.477678)
			(xy 109.284368 -313.524191) (xy 109.247151 -313.565728) (xy 109.204283 -313.601403) (xy 109.156677 -313.630457)
			(xy 109.105348 -313.652269) (xy 109.051391 -313.666375) (xy 108.995954 -313.672475) (xy 108.94022 -313.670438)
			(xy 108.885377 -313.660308) (xy 108.832593 -313.642301) (xy 108.782993 -313.6168) (xy 108.737635 -313.584349)
			(xy 108.697486 -313.54564) (xy 108.6634 -313.501497) (xy 108.636104 -313.452862) (xy 108.616181 -313.400771)
			(xy 108.604055 -313.346334) (xy 108.599984 -313.290712) (xy 108.34751 -313.290712) (xy 108.347001 -313.318598)
			(xy 108.338881 -313.373774) (xy 108.322813 -313.427181) (xy 108.299141 -313.477678) (xy 108.268368 -313.524191)
			(xy 108.231151 -313.565728) (xy 108.188283 -313.601403) (xy 108.140677 -313.630457) (xy 108.089348 -313.652269)
			(xy 108.035391 -313.666375) (xy 107.979954 -313.672475) (xy 107.92422 -313.670438) (xy 107.869377 -313.660308)
			(xy 107.816593 -313.642301) (xy 107.766993 -313.6168) (xy 107.721635 -313.584349) (xy 107.681486 -313.54564)
			(xy 107.6474 -313.501497) (xy 107.620104 -313.452862) (xy 107.600181 -313.400771) (xy 107.588055 -313.346334)
			(xy 107.583984 -313.290712) (xy 107.33151 -313.290712) (xy 107.331001 -313.318598) (xy 107.322881 -313.373774)
			(xy 107.306813 -313.427181) (xy 107.283141 -313.477678) (xy 107.252368 -313.524191) (xy 107.215151 -313.565728)
			(xy 107.172283 -313.601403) (xy 107.124677 -313.630457) (xy 107.073348 -313.652269) (xy 107.019391 -313.666375)
			(xy 106.963954 -313.672475) (xy 106.90822 -313.670438) (xy 106.853377 -313.660308) (xy 106.800593 -313.642301)
			(xy 106.750993 -313.6168) (xy 106.705635 -313.584349) (xy 106.665486 -313.54564) (xy 106.6314 -313.501497)
			(xy 106.604104 -313.452862) (xy 106.584181 -313.400771) (xy 106.572055 -313.346334) (xy 106.567984 -313.290712)
			(xy 106.31551 -313.290712) (xy 106.315001 -313.318598) (xy 106.306881 -313.373774) (xy 106.290813 -313.427181)
			(xy 106.267141 -313.477678) (xy 106.236368 -313.524191) (xy 106.199151 -313.565728) (xy 106.156283 -313.601403)
			(xy 106.108677 -313.630457) (xy 106.057348 -313.652269) (xy 106.003391 -313.666375) (xy 105.947954 -313.672475)
			(xy 105.89222 -313.670438) (xy 105.837377 -313.660308) (xy 105.784593 -313.642301) (xy 105.734993 -313.6168)
			(xy 105.689635 -313.584349) (xy 105.649486 -313.54564) (xy 105.6154 -313.501497) (xy 105.588104 -313.452862)
			(xy 105.568181 -313.400771) (xy 105.556055 -313.346334) (xy 105.551984 -313.290712) (xy 105.29951 -313.290712)
			(xy 105.299001 -313.318598) (xy 105.290881 -313.373774) (xy 105.274813 -313.427181) (xy 105.251141 -313.477678)
			(xy 105.220368 -313.524191) (xy 105.183151 -313.565728) (xy 105.140283 -313.601403) (xy 105.092677 -313.630457)
			(xy 105.041348 -313.652269) (xy 104.987391 -313.666375) (xy 104.931954 -313.672475) (xy 104.87622 -313.670438)
			(xy 104.821377 -313.660308) (xy 104.768593 -313.642301) (xy 104.718993 -313.6168) (xy 104.673635 -313.584349)
			(xy 104.633486 -313.54564) (xy 104.5994 -313.501497) (xy 104.572104 -313.452862) (xy 104.552181 -313.400771)
			(xy 104.540055 -313.346334) (xy 104.535984 -313.290712) (xy 104.28351 -313.290712) (xy 104.283001 -313.318598)
			(xy 104.274881 -313.373774) (xy 104.258813 -313.427181) (xy 104.235141 -313.477678) (xy 104.204368 -313.524191)
			(xy 104.167151 -313.565728) (xy 104.124283 -313.601403) (xy 104.076677 -313.630457) (xy 104.025348 -313.652269)
			(xy 103.971391 -313.666375) (xy 103.915954 -313.672475) (xy 103.86022 -313.670438) (xy 103.805377 -313.660308)
			(xy 103.752593 -313.642301) (xy 103.702993 -313.6168) (xy 103.657635 -313.584349) (xy 103.617486 -313.54564)
			(xy 103.5834 -313.501497) (xy 103.556104 -313.452862) (xy 103.536181 -313.400771) (xy 103.524055 -313.346334)
			(xy 103.519984 -313.290712) (xy 103.26751 -313.290712) (xy 103.267001 -313.318598) (xy 103.258881 -313.373774)
			(xy 103.242813 -313.427181) (xy 103.219141 -313.477678) (xy 103.188368 -313.524191) (xy 103.151151 -313.565728)
			(xy 103.108283 -313.601403) (xy 103.060677 -313.630457) (xy 103.009348 -313.652269) (xy 102.955391 -313.666375)
			(xy 102.899954 -313.672475) (xy 102.84422 -313.670438) (xy 102.789377 -313.660308) (xy 102.736593 -313.642301)
			(xy 102.686993 -313.6168) (xy 102.641635 -313.584349) (xy 102.601486 -313.54564) (xy 102.5674 -313.501497)
			(xy 102.540104 -313.452862) (xy 102.520181 -313.400771) (xy 102.508055 -313.346334) (xy 102.503984 -313.290712)
			(xy 102.25151 -313.290712) (xy 102.251001 -313.318598) (xy 102.242881 -313.373774) (xy 102.226813 -313.427181)
			(xy 102.203141 -313.477678) (xy 102.172368 -313.524191) (xy 102.135151 -313.565728) (xy 102.092283 -313.601403)
			(xy 102.044677 -313.630457) (xy 101.993348 -313.652269) (xy 101.939391 -313.666375) (xy 101.883954 -313.672475)
			(xy 101.82822 -313.670438) (xy 101.773377 -313.660308) (xy 101.720593 -313.642301) (xy 101.670993 -313.6168)
			(xy 101.625635 -313.584349) (xy 101.585486 -313.54564) (xy 101.5514 -313.501497) (xy 101.524104 -313.452862)
			(xy 101.504181 -313.400771) (xy 101.492055 -313.346334) (xy 101.487984 -313.290712) (xy 101.23501 -313.290712)
			(xy 101.23501 -313.31795) (xy 101.227254 -313.371896) (xy 101.211899 -313.424189) (xy 101.189259 -313.473764)
			(xy 101.159794 -313.519613) (xy 101.124103 -313.560802) (xy 101.082915 -313.596492) (xy 101.037066 -313.625958)
			(xy 100.987491 -313.648598) (xy 100.935198 -313.663953) (xy 100.881252 -313.67171) (xy 100.854002 -313.67222)
			(xy 100.818188 -313.670442) (xy 100.809099 -313.669904) (xy 100.791502 -313.67453) (xy 100.776638 -313.685024)
			(xy 100.766387 -313.700056) (xy 100.763832 -313.708796) (xy 100.761915 -313.718236) (xy 100.764519 -313.737307)
			(xy 100.768912 -313.74588) (xy 100.770182 -313.748166) (xy 100.777732 -313.760352) (xy 100.790963 -313.785785)
			(xy 100.796598 -313.798966) (xy 101.006941 -314.306712) (xy 101.487984 -314.306712) (xy 101.492055 -314.25109)
			(xy 101.504181 -314.196653) (xy 101.524104 -314.144562) (xy 101.5514 -314.095927) (xy 101.585486 -314.051784)
			(xy 101.625635 -314.013075) (xy 101.670993 -313.980624) (xy 101.720593 -313.955123) (xy 101.773377 -313.937116)
			(xy 101.82822 -313.926986) (xy 101.883954 -313.924949) (xy 101.939391 -313.931049) (xy 101.993348 -313.945155)
			(xy 102.044677 -313.966967) (xy 102.092283 -313.996021) (xy 102.135151 -314.031696) (xy 102.172368 -314.073233)
			(xy 102.203141 -314.119746) (xy 102.226813 -314.170243) (xy 102.242881 -314.22365) (xy 102.251001 -314.278826)
			(xy 102.25151 -314.306712) (xy 102.503984 -314.306712) (xy 102.508055 -314.25109) (xy 102.520181 -314.196653)
			(xy 102.540104 -314.144562) (xy 102.5674 -314.095927) (xy 102.601486 -314.051784) (xy 102.641635 -314.013075)
			(xy 102.686993 -313.980624) (xy 102.736593 -313.955123) (xy 102.789377 -313.937116) (xy 102.84422 -313.926986)
			(xy 102.899954 -313.924949) (xy 102.955391 -313.931049) (xy 103.009348 -313.945155) (xy 103.060677 -313.966967)
			(xy 103.108283 -313.996021) (xy 103.151151 -314.031696) (xy 103.188368 -314.073233) (xy 103.219141 -314.119746)
			(xy 103.242813 -314.170243) (xy 103.258881 -314.22365) (xy 103.267001 -314.278826) (xy 103.26751 -314.306712)
			(xy 103.519984 -314.306712) (xy 103.524055 -314.25109) (xy 103.536181 -314.196653) (xy 103.556104 -314.144562)
			(xy 103.5834 -314.095927) (xy 103.617486 -314.051784) (xy 103.657635 -314.013075) (xy 103.702993 -313.980624)
			(xy 103.752593 -313.955123) (xy 103.805377 -313.937116) (xy 103.86022 -313.926986) (xy 103.915954 -313.924949)
			(xy 103.971391 -313.931049) (xy 104.025348 -313.945155) (xy 104.076677 -313.966967) (xy 104.124283 -313.996021)
			(xy 104.167151 -314.031696) (xy 104.204368 -314.073233) (xy 104.235141 -314.119746) (xy 104.258813 -314.170243)
			(xy 104.274881 -314.22365) (xy 104.283001 -314.278826) (xy 104.28351 -314.306712) (xy 104.535984 -314.306712)
			(xy 104.540055 -314.25109) (xy 104.552181 -314.196653) (xy 104.572104 -314.144562) (xy 104.5994 -314.095927)
			(xy 104.633486 -314.051784) (xy 104.673635 -314.013075) (xy 104.718993 -313.980624) (xy 104.768593 -313.955123)
			(xy 104.821377 -313.937116) (xy 104.87622 -313.926986) (xy 104.931954 -313.924949) (xy 104.987391 -313.931049)
			(xy 105.041348 -313.945155) (xy 105.092677 -313.966967) (xy 105.140283 -313.996021) (xy 105.183151 -314.031696)
			(xy 105.220368 -314.073233) (xy 105.251141 -314.119746) (xy 105.274813 -314.170243) (xy 105.290881 -314.22365)
			(xy 105.299001 -314.278826) (xy 105.29951 -314.306712) (xy 105.551984 -314.306712) (xy 105.556055 -314.25109)
			(xy 105.568181 -314.196653) (xy 105.588104 -314.144562) (xy 105.6154 -314.095927) (xy 105.649486 -314.051784)
			(xy 105.689635 -314.013075) (xy 105.734993 -313.980624) (xy 105.784593 -313.955123) (xy 105.837377 -313.937116)
			(xy 105.89222 -313.926986) (xy 105.947954 -313.924949) (xy 106.003391 -313.931049) (xy 106.057348 -313.945155)
			(xy 106.108677 -313.966967) (xy 106.156283 -313.996021) (xy 106.199151 -314.031696) (xy 106.236368 -314.073233)
			(xy 106.267141 -314.119746) (xy 106.290813 -314.170243) (xy 106.306881 -314.22365) (xy 106.315001 -314.278826)
			(xy 106.31551 -314.306712) (xy 106.567984 -314.306712) (xy 106.572055 -314.25109) (xy 106.584181 -314.196653)
			(xy 106.604104 -314.144562) (xy 106.6314 -314.095927) (xy 106.665486 -314.051784) (xy 106.705635 -314.013075)
			(xy 106.750993 -313.980624) (xy 106.800593 -313.955123) (xy 106.853377 -313.937116) (xy 106.90822 -313.926986)
			(xy 106.963954 -313.924949) (xy 107.019391 -313.931049) (xy 107.073348 -313.945155) (xy 107.124677 -313.966967)
			(xy 107.172283 -313.996021) (xy 107.215151 -314.031696) (xy 107.252368 -314.073233) (xy 107.283141 -314.119746)
			(xy 107.306813 -314.170243) (xy 107.322881 -314.22365) (xy 107.331001 -314.278826) (xy 107.33151 -314.306712)
			(xy 107.583984 -314.306712) (xy 107.588055 -314.25109) (xy 107.600181 -314.196653) (xy 107.620104 -314.144562)
			(xy 107.6474 -314.095927) (xy 107.681486 -314.051784) (xy 107.721635 -314.013075) (xy 107.766993 -313.980624)
			(xy 107.816593 -313.955123) (xy 107.869377 -313.937116) (xy 107.92422 -313.926986) (xy 107.979954 -313.924949)
			(xy 108.035391 -313.931049) (xy 108.089348 -313.945155) (xy 108.140677 -313.966967) (xy 108.188283 -313.996021)
			(xy 108.231151 -314.031696) (xy 108.268368 -314.073233) (xy 108.299141 -314.119746) (xy 108.322813 -314.170243)
			(xy 108.338881 -314.22365) (xy 108.347001 -314.278826) (xy 108.34751 -314.306712) (xy 108.599984 -314.306712)
			(xy 108.604055 -314.25109) (xy 108.616181 -314.196653) (xy 108.636104 -314.144562) (xy 108.6634 -314.095927)
			(xy 108.697486 -314.051784) (xy 108.737635 -314.013075) (xy 108.782993 -313.980624) (xy 108.832593 -313.955123)
			(xy 108.885377 -313.937116) (xy 108.94022 -313.926986) (xy 108.995954 -313.924949) (xy 109.051391 -313.931049)
			(xy 109.105348 -313.945155) (xy 109.156677 -313.966967) (xy 109.204283 -313.996021) (xy 109.247151 -314.031696)
			(xy 109.284368 -314.073233) (xy 109.315141 -314.119746) (xy 109.338813 -314.170243) (xy 109.354881 -314.22365)
			(xy 109.363001 -314.278826) (xy 109.36351 -314.306712) (xy 109.615984 -314.306712) (xy 109.620055 -314.25109)
			(xy 109.632181 -314.196653) (xy 109.652104 -314.144562) (xy 109.6794 -314.095927) (xy 109.713486 -314.051784)
			(xy 109.753635 -314.013075) (xy 109.798993 -313.980624) (xy 109.848593 -313.955123) (xy 109.901377 -313.937116)
			(xy 109.95622 -313.926986) (xy 110.011954 -313.924949) (xy 110.067391 -313.931049) (xy 110.121348 -313.945155)
			(xy 110.172677 -313.966967) (xy 110.220283 -313.996021) (xy 110.263151 -314.031696) (xy 110.300368 -314.073233)
			(xy 110.331141 -314.119746) (xy 110.354813 -314.170243) (xy 110.370881 -314.22365) (xy 110.379001 -314.278826)
			(xy 110.37951 -314.306712) (xy 110.379001 -314.334598) (xy 110.370881 -314.389774) (xy 110.354813 -314.443181)
			(xy 110.331141 -314.493678) (xy 110.326114 -314.501276) (xy 125.23673 -314.501276) (xy 125.240801 -314.445654)
			(xy 125.252927 -314.391217) (xy 125.27285 -314.339126) (xy 125.300146 -314.290491) (xy 125.334232 -314.246348)
			(xy 125.374381 -314.207639) (xy 125.419739 -314.175188) (xy 125.469339 -314.149687) (xy 125.522123 -314.13168)
			(xy 125.576966 -314.12155) (xy 125.6327 -314.119513) (xy 125.688137 -314.125613) (xy 125.742094 -314.139719)
			(xy 125.793423 -314.161531) (xy 125.841029 -314.190585) (xy 125.883897 -314.22626) (xy 125.921114 -314.267797)
			(xy 125.951887 -314.31431) (xy 125.975559 -314.364807) (xy 125.991627 -314.418214) (xy 125.999747 -314.47339)
			(xy 126.000256 -314.501276) (xy 126.25273 -314.501276) (xy 126.256801 -314.445654) (xy 126.268927 -314.391217)
			(xy 126.28885 -314.339126) (xy 126.316146 -314.290491) (xy 126.350232 -314.246348) (xy 126.390381 -314.207639)
			(xy 126.435739 -314.175188) (xy 126.485339 -314.149687) (xy 126.538123 -314.13168) (xy 126.592966 -314.12155)
			(xy 126.6487 -314.119513) (xy 126.704137 -314.125613) (xy 126.758094 -314.139719) (xy 126.809423 -314.161531)
			(xy 126.857029 -314.190585) (xy 126.899897 -314.22626) (xy 126.937114 -314.267797) (xy 126.967887 -314.31431)
			(xy 126.991559 -314.364807) (xy 127.007627 -314.418214) (xy 127.015747 -314.47339) (xy 127.016256 -314.501276)
			(xy 127.26873 -314.501276) (xy 127.272801 -314.445654) (xy 127.284927 -314.391217) (xy 127.30485 -314.339126)
			(xy 127.332146 -314.290491) (xy 127.366232 -314.246348) (xy 127.406381 -314.207639) (xy 127.451739 -314.175188)
			(xy 127.501339 -314.149687) (xy 127.554123 -314.13168) (xy 127.608966 -314.12155) (xy 127.6647 -314.119513)
			(xy 127.720137 -314.125613) (xy 127.774094 -314.139719) (xy 127.825423 -314.161531) (xy 127.873029 -314.190585)
			(xy 127.915897 -314.22626) (xy 127.953114 -314.267797) (xy 127.983887 -314.31431) (xy 128.007559 -314.364807)
			(xy 128.023627 -314.418214) (xy 128.031747 -314.47339) (xy 128.032256 -314.501276) (xy 128.28473 -314.501276)
			(xy 128.288801 -314.445654) (xy 128.300927 -314.391217) (xy 128.32085 -314.339126) (xy 128.348146 -314.290491)
			(xy 128.382232 -314.246348) (xy 128.422381 -314.207639) (xy 128.467739 -314.175188) (xy 128.517339 -314.149687)
			(xy 128.570123 -314.13168) (xy 128.624966 -314.12155) (xy 128.6807 -314.119513) (xy 128.736137 -314.125613)
			(xy 128.790094 -314.139719) (xy 128.841423 -314.161531) (xy 128.889029 -314.190585) (xy 128.931897 -314.22626)
			(xy 128.969114 -314.267797) (xy 128.999887 -314.31431) (xy 129.023559 -314.364807) (xy 129.039627 -314.418214)
			(xy 129.047747 -314.47339) (xy 129.048256 -314.501276) (xy 129.30073 -314.501276) (xy 129.304801 -314.445654)
			(xy 129.316927 -314.391217) (xy 129.33685 -314.339126) (xy 129.364146 -314.290491) (xy 129.398232 -314.246348)
			(xy 129.438381 -314.207639) (xy 129.483739 -314.175188) (xy 129.533339 -314.149687) (xy 129.586123 -314.13168)
			(xy 129.640966 -314.12155) (xy 129.6967 -314.119513) (xy 129.752137 -314.125613) (xy 129.806094 -314.139719)
			(xy 129.857423 -314.161531) (xy 129.905029 -314.190585) (xy 129.947897 -314.22626) (xy 129.985114 -314.267797)
			(xy 130.015887 -314.31431) (xy 130.039559 -314.364807) (xy 130.055627 -314.418214) (xy 130.063747 -314.47339)
			(xy 130.064256 -314.501276) (xy 130.31673 -314.501276) (xy 130.320801 -314.445654) (xy 130.332927 -314.391217)
			(xy 130.35285 -314.339126) (xy 130.380146 -314.290491) (xy 130.414232 -314.246348) (xy 130.454381 -314.207639)
			(xy 130.499739 -314.175188) (xy 130.549339 -314.149687) (xy 130.602123 -314.13168) (xy 130.656966 -314.12155)
			(xy 130.7127 -314.119513) (xy 130.768137 -314.125613) (xy 130.822094 -314.139719) (xy 130.873423 -314.161531)
			(xy 130.921029 -314.190585) (xy 130.963897 -314.22626) (xy 131.001114 -314.267797) (xy 131.031887 -314.31431)
			(xy 131.055559 -314.364807) (xy 131.071627 -314.418214) (xy 131.079747 -314.47339) (xy 131.080256 -314.501276)
			(xy 131.079747 -314.529162) (xy 131.071627 -314.584338) (xy 131.055559 -314.637745) (xy 131.031887 -314.688242)
			(xy 131.001114 -314.734755) (xy 130.963897 -314.776292) (xy 130.921029 -314.811967) (xy 130.873423 -314.841021)
			(xy 130.822094 -314.862833) (xy 130.768137 -314.876939) (xy 130.7127 -314.883039) (xy 130.656966 -314.881002)
			(xy 130.602123 -314.870872) (xy 130.549339 -314.852865) (xy 130.499739 -314.827364) (xy 130.454381 -314.794913)
			(xy 130.414232 -314.756204) (xy 130.380146 -314.712061) (xy 130.35285 -314.663426) (xy 130.332927 -314.611335)
			(xy 130.320801 -314.556898) (xy 130.31673 -314.501276) (xy 130.064256 -314.501276) (xy 130.063747 -314.529162)
			(xy 130.055627 -314.584338) (xy 130.039559 -314.637745) (xy 130.015887 -314.688242) (xy 129.985114 -314.734755)
			(xy 129.947897 -314.776292) (xy 129.905029 -314.811967) (xy 129.857423 -314.841021) (xy 129.806094 -314.862833)
			(xy 129.752137 -314.876939) (xy 129.6967 -314.883039) (xy 129.640966 -314.881002) (xy 129.586123 -314.870872)
			(xy 129.533339 -314.852865) (xy 129.483739 -314.827364) (xy 129.438381 -314.794913) (xy 129.398232 -314.756204)
			(xy 129.364146 -314.712061) (xy 129.33685 -314.663426) (xy 129.316927 -314.611335) (xy 129.304801 -314.556898)
			(xy 129.30073 -314.501276) (xy 129.048256 -314.501276) (xy 129.047747 -314.529162) (xy 129.039627 -314.584338)
			(xy 129.023559 -314.637745) (xy 128.999887 -314.688242) (xy 128.969114 -314.734755) (xy 128.931897 -314.776292)
			(xy 128.889029 -314.811967) (xy 128.841423 -314.841021) (xy 128.790094 -314.862833) (xy 128.736137 -314.876939)
			(xy 128.6807 -314.883039) (xy 128.624966 -314.881002) (xy 128.570123 -314.870872) (xy 128.517339 -314.852865)
			(xy 128.467739 -314.827364) (xy 128.422381 -314.794913) (xy 128.382232 -314.756204) (xy 128.348146 -314.712061)
			(xy 128.32085 -314.663426) (xy 128.300927 -314.611335) (xy 128.288801 -314.556898) (xy 128.28473 -314.501276)
			(xy 128.032256 -314.501276) (xy 128.031747 -314.529162) (xy 128.023627 -314.584338) (xy 128.007559 -314.637745)
			(xy 127.983887 -314.688242) (xy 127.953114 -314.734755) (xy 127.915897 -314.776292) (xy 127.873029 -314.811967)
			(xy 127.825423 -314.841021) (xy 127.774094 -314.862833) (xy 127.720137 -314.876939) (xy 127.6647 -314.883039)
			(xy 127.608966 -314.881002) (xy 127.554123 -314.870872) (xy 127.501339 -314.852865) (xy 127.451739 -314.827364)
			(xy 127.406381 -314.794913) (xy 127.366232 -314.756204) (xy 127.332146 -314.712061) (xy 127.30485 -314.663426)
			(xy 127.284927 -314.611335) (xy 127.272801 -314.556898) (xy 127.26873 -314.501276) (xy 127.016256 -314.501276)
			(xy 127.015747 -314.529162) (xy 127.007627 -314.584338) (xy 126.991559 -314.637745) (xy 126.967887 -314.688242)
			(xy 126.937114 -314.734755) (xy 126.899897 -314.776292) (xy 126.857029 -314.811967) (xy 126.809423 -314.841021)
			(xy 126.758094 -314.862833) (xy 126.704137 -314.876939) (xy 126.6487 -314.883039) (xy 126.592966 -314.881002)
			(xy 126.538123 -314.870872) (xy 126.485339 -314.852865) (xy 126.435739 -314.827364) (xy 126.390381 -314.794913)
			(xy 126.350232 -314.756204) (xy 126.316146 -314.712061) (xy 126.28885 -314.663426) (xy 126.268927 -314.611335)
			(xy 126.256801 -314.556898) (xy 126.25273 -314.501276) (xy 126.000256 -314.501276) (xy 125.999747 -314.529162)
			(xy 125.991627 -314.584338) (xy 125.975559 -314.637745) (xy 125.951887 -314.688242) (xy 125.921114 -314.734755)
			(xy 125.883897 -314.776292) (xy 125.841029 -314.811967) (xy 125.793423 -314.841021) (xy 125.742094 -314.862833)
			(xy 125.688137 -314.876939) (xy 125.6327 -314.883039) (xy 125.576966 -314.881002) (xy 125.522123 -314.870872)
			(xy 125.469339 -314.852865) (xy 125.419739 -314.827364) (xy 125.374381 -314.794913) (xy 125.334232 -314.756204)
			(xy 125.300146 -314.712061) (xy 125.27285 -314.663426) (xy 125.252927 -314.611335) (xy 125.240801 -314.556898)
			(xy 125.23673 -314.501276) (xy 110.326114 -314.501276) (xy 110.300368 -314.540191) (xy 110.263151 -314.581728)
			(xy 110.220283 -314.617403) (xy 110.172677 -314.646457) (xy 110.121348 -314.668269) (xy 110.067391 -314.682375)
			(xy 110.011954 -314.688475) (xy 109.95622 -314.686438) (xy 109.901377 -314.676308) (xy 109.848593 -314.658301)
			(xy 109.798993 -314.6328) (xy 109.753635 -314.600349) (xy 109.713486 -314.56164) (xy 109.6794 -314.517497)
			(xy 109.652104 -314.468862) (xy 109.632181 -314.416771) (xy 109.620055 -314.362334) (xy 109.615984 -314.306712)
			(xy 109.36351 -314.306712) (xy 109.363001 -314.334598) (xy 109.354881 -314.389774) (xy 109.338813 -314.443181)
			(xy 109.315141 -314.493678) (xy 109.284368 -314.540191) (xy 109.247151 -314.581728) (xy 109.204283 -314.617403)
			(xy 109.156677 -314.646457) (xy 109.105348 -314.668269) (xy 109.051391 -314.682375) (xy 108.995954 -314.688475)
			(xy 108.94022 -314.686438) (xy 108.885377 -314.676308) (xy 108.832593 -314.658301) (xy 108.782993 -314.6328)
			(xy 108.737635 -314.600349) (xy 108.697486 -314.56164) (xy 108.6634 -314.517497) (xy 108.636104 -314.468862)
			(xy 108.616181 -314.416771) (xy 108.604055 -314.362334) (xy 108.599984 -314.306712) (xy 108.34751 -314.306712)
			(xy 108.347001 -314.334598) (xy 108.338881 -314.389774) (xy 108.322813 -314.443181) (xy 108.299141 -314.493678)
			(xy 108.268368 -314.540191) (xy 108.231151 -314.581728) (xy 108.188283 -314.617403) (xy 108.140677 -314.646457)
			(xy 108.089348 -314.668269) (xy 108.035391 -314.682375) (xy 107.979954 -314.688475) (xy 107.92422 -314.686438)
			(xy 107.869377 -314.676308) (xy 107.816593 -314.658301) (xy 107.766993 -314.6328) (xy 107.721635 -314.600349)
			(xy 107.681486 -314.56164) (xy 107.6474 -314.517497) (xy 107.620104 -314.468862) (xy 107.600181 -314.416771)
			(xy 107.588055 -314.362334) (xy 107.583984 -314.306712) (xy 107.33151 -314.306712) (xy 107.331001 -314.334598)
			(xy 107.322881 -314.389774) (xy 107.306813 -314.443181) (xy 107.283141 -314.493678) (xy 107.252368 -314.540191)
			(xy 107.215151 -314.581728) (xy 107.172283 -314.617403) (xy 107.124677 -314.646457) (xy 107.073348 -314.668269)
			(xy 107.019391 -314.682375) (xy 106.963954 -314.688475) (xy 106.90822 -314.686438) (xy 106.853377 -314.676308)
			(xy 106.800593 -314.658301) (xy 106.750993 -314.6328) (xy 106.705635 -314.600349) (xy 106.665486 -314.56164)
			(xy 106.6314 -314.517497) (xy 106.604104 -314.468862) (xy 106.584181 -314.416771) (xy 106.572055 -314.362334)
			(xy 106.567984 -314.306712) (xy 106.31551 -314.306712) (xy 106.315001 -314.334598) (xy 106.306881 -314.389774)
			(xy 106.290813 -314.443181) (xy 106.267141 -314.493678) (xy 106.236368 -314.540191) (xy 106.199151 -314.581728)
			(xy 106.156283 -314.617403) (xy 106.108677 -314.646457) (xy 106.057348 -314.668269) (xy 106.003391 -314.682375)
			(xy 105.947954 -314.688475) (xy 105.89222 -314.686438) (xy 105.837377 -314.676308) (xy 105.784593 -314.658301)
			(xy 105.734993 -314.6328) (xy 105.689635 -314.600349) (xy 105.649486 -314.56164) (xy 105.6154 -314.517497)
			(xy 105.588104 -314.468862) (xy 105.568181 -314.416771) (xy 105.556055 -314.362334) (xy 105.551984 -314.306712)
			(xy 105.29951 -314.306712) (xy 105.299001 -314.334598) (xy 105.290881 -314.389774) (xy 105.274813 -314.443181)
			(xy 105.251141 -314.493678) (xy 105.220368 -314.540191) (xy 105.183151 -314.581728) (xy 105.140283 -314.617403)
			(xy 105.092677 -314.646457) (xy 105.041348 -314.668269) (xy 104.987391 -314.682375) (xy 104.931954 -314.688475)
			(xy 104.87622 -314.686438) (xy 104.821377 -314.676308) (xy 104.768593 -314.658301) (xy 104.718993 -314.6328)
			(xy 104.673635 -314.600349) (xy 104.633486 -314.56164) (xy 104.5994 -314.517497) (xy 104.572104 -314.468862)
			(xy 104.552181 -314.416771) (xy 104.540055 -314.362334) (xy 104.535984 -314.306712) (xy 104.28351 -314.306712)
			(xy 104.283001 -314.334598) (xy 104.274881 -314.389774) (xy 104.258813 -314.443181) (xy 104.235141 -314.493678)
			(xy 104.204368 -314.540191) (xy 104.167151 -314.581728) (xy 104.124283 -314.617403) (xy 104.076677 -314.646457)
			(xy 104.025348 -314.668269) (xy 103.971391 -314.682375) (xy 103.915954 -314.688475) (xy 103.86022 -314.686438)
			(xy 103.805377 -314.676308) (xy 103.752593 -314.658301) (xy 103.702993 -314.6328) (xy 103.657635 -314.600349)
			(xy 103.617486 -314.56164) (xy 103.5834 -314.517497) (xy 103.556104 -314.468862) (xy 103.536181 -314.416771)
			(xy 103.524055 -314.362334) (xy 103.519984 -314.306712) (xy 103.26751 -314.306712) (xy 103.267001 -314.334598)
			(xy 103.258881 -314.389774) (xy 103.242813 -314.443181) (xy 103.219141 -314.493678) (xy 103.188368 -314.540191)
			(xy 103.151151 -314.581728) (xy 103.108283 -314.617403) (xy 103.060677 -314.646457) (xy 103.009348 -314.668269)
			(xy 102.955391 -314.682375) (xy 102.899954 -314.688475) (xy 102.84422 -314.686438) (xy 102.789377 -314.676308)
			(xy 102.736593 -314.658301) (xy 102.686993 -314.6328) (xy 102.641635 -314.600349) (xy 102.601486 -314.56164)
			(xy 102.5674 -314.517497) (xy 102.540104 -314.468862) (xy 102.520181 -314.416771) (xy 102.508055 -314.362334)
			(xy 102.503984 -314.306712) (xy 102.25151 -314.306712) (xy 102.251001 -314.334598) (xy 102.242881 -314.389774)
			(xy 102.226813 -314.443181) (xy 102.203141 -314.493678) (xy 102.172368 -314.540191) (xy 102.135151 -314.581728)
			(xy 102.092283 -314.617403) (xy 102.044677 -314.646457) (xy 101.993348 -314.668269) (xy 101.939391 -314.682375)
			(xy 101.883954 -314.688475) (xy 101.82822 -314.686438) (xy 101.773377 -314.676308) (xy 101.720593 -314.658301)
			(xy 101.670993 -314.6328) (xy 101.625635 -314.600349) (xy 101.585486 -314.56164) (xy 101.5514 -314.517497)
			(xy 101.524104 -314.468862) (xy 101.504181 -314.416771) (xy 101.492055 -314.362334) (xy 101.487984 -314.306712)
			(xy 101.006941 -314.306712) (xy 101.37775 -315.201808) (xy 101.382098 -315.211087) (xy 101.396709 -315.225428)
			(xy 101.415766 -315.232911) (xy 101.42601 -315.23305) (xy 101.449378 -315.232542) (xy 101.454712 -315.23178)
			(xy 101.460327 -315.230565) (xy 101.470844 -315.225945) (xy 101.47554 -315.222636) (xy 101.491542 -315.210952)
			(xy 101.494391 -315.20874) (xy 101.499494 -315.203644) (xy 101.501702 -315.200792) (xy 101.514148 -315.184536)
			(xy 101.516688 -315.178186) (xy 101.527853 -315.152266) (xy 101.5567 -315.103761) (xy 101.592377 -315.060033)
			(xy 101.634106 -315.022037) (xy 101.680976 -314.990602) (xy 101.731964 -314.966414) (xy 101.78596 -314.949999)
			(xy 101.841784 -314.941716) (xy 101.870002 -314.941204) (xy 101.897252 -314.94169) (xy 101.951198 -314.949447)
			(xy 102.003491 -314.964802) (xy 102.053066 -314.987442) (xy 102.098915 -315.016908) (xy 102.140103 -315.052598)
			(xy 102.175794 -315.093787) (xy 102.205259 -315.139636) (xy 102.227899 -315.189211) (xy 102.243254 -315.241504)
			(xy 102.25101 -315.29545) (xy 102.25101 -315.322712) (xy 102.503984 -315.322712) (xy 102.508055 -315.26709)
			(xy 102.520181 -315.212653) (xy 102.540104 -315.160562) (xy 102.5674 -315.111927) (xy 102.601486 -315.067784)
			(xy 102.641635 -315.029075) (xy 102.686993 -314.996624) (xy 102.736593 -314.971123) (xy 102.789377 -314.953116)
			(xy 102.84422 -314.942986) (xy 102.899954 -314.940949) (xy 102.955391 -314.947049) (xy 103.009348 -314.961155)
			(xy 103.060677 -314.982967) (xy 103.108283 -315.012021) (xy 103.151151 -315.047696) (xy 103.188368 -315.089233)
			(xy 103.219141 -315.135746) (xy 103.242813 -315.186243) (xy 103.258881 -315.23965) (xy 103.267001 -315.294826)
			(xy 103.26751 -315.322712) (xy 103.519984 -315.322712) (xy 103.524055 -315.26709) (xy 103.536181 -315.212653)
			(xy 103.556104 -315.160562) (xy 103.5834 -315.111927) (xy 103.617486 -315.067784) (xy 103.657635 -315.029075)
			(xy 103.702993 -314.996624) (xy 103.752593 -314.971123) (xy 103.805377 -314.953116) (xy 103.86022 -314.942986)
			(xy 103.915954 -314.940949) (xy 103.971391 -314.947049) (xy 104.025348 -314.961155) (xy 104.076677 -314.982967)
			(xy 104.124283 -315.012021) (xy 104.167151 -315.047696) (xy 104.204368 -315.089233) (xy 104.235141 -315.135746)
			(xy 104.258813 -315.186243) (xy 104.274881 -315.23965) (xy 104.283001 -315.294826) (xy 104.28351 -315.322712)
			(xy 104.535984 -315.322712) (xy 104.540055 -315.26709) (xy 104.552181 -315.212653) (xy 104.572104 -315.160562)
			(xy 104.5994 -315.111927) (xy 104.633486 -315.067784) (xy 104.673635 -315.029075) (xy 104.718993 -314.996624)
			(xy 104.768593 -314.971123) (xy 104.821377 -314.953116) (xy 104.87622 -314.942986) (xy 104.931954 -314.940949)
			(xy 104.987391 -314.947049) (xy 105.041348 -314.961155) (xy 105.092677 -314.982967) (xy 105.140283 -315.012021)
			(xy 105.183151 -315.047696) (xy 105.220368 -315.089233) (xy 105.251141 -315.135746) (xy 105.274813 -315.186243)
			(xy 105.290881 -315.23965) (xy 105.299001 -315.294826) (xy 105.29951 -315.322712) (xy 105.551984 -315.322712)
			(xy 105.556055 -315.26709) (xy 105.568181 -315.212653) (xy 105.588104 -315.160562) (xy 105.6154 -315.111927)
			(xy 105.649486 -315.067784) (xy 105.689635 -315.029075) (xy 105.734993 -314.996624) (xy 105.784593 -314.971123)
			(xy 105.837377 -314.953116) (xy 105.89222 -314.942986) (xy 105.947954 -314.940949) (xy 106.003391 -314.947049)
			(xy 106.057348 -314.961155) (xy 106.108677 -314.982967) (xy 106.156283 -315.012021) (xy 106.199151 -315.047696)
			(xy 106.236368 -315.089233) (xy 106.267141 -315.135746) (xy 106.290813 -315.186243) (xy 106.306881 -315.23965)
			(xy 106.315001 -315.294826) (xy 106.31551 -315.322712) (xy 106.567984 -315.322712) (xy 106.572055 -315.26709)
			(xy 106.584181 -315.212653) (xy 106.604104 -315.160562) (xy 106.6314 -315.111927) (xy 106.665486 -315.067784)
			(xy 106.705635 -315.029075) (xy 106.750993 -314.996624) (xy 106.800593 -314.971123) (xy 106.853377 -314.953116)
			(xy 106.90822 -314.942986) (xy 106.963954 -314.940949) (xy 107.019391 -314.947049) (xy 107.073348 -314.961155)
			(xy 107.124677 -314.982967) (xy 107.172283 -315.012021) (xy 107.215151 -315.047696) (xy 107.252368 -315.089233)
			(xy 107.283141 -315.135746) (xy 107.306813 -315.186243) (xy 107.322881 -315.23965) (xy 107.331001 -315.294826)
			(xy 107.33151 -315.322712) (xy 107.583984 -315.322712) (xy 107.588055 -315.26709) (xy 107.600181 -315.212653)
			(xy 107.620104 -315.160562) (xy 107.6474 -315.111927) (xy 107.681486 -315.067784) (xy 107.721635 -315.029075)
			(xy 107.766993 -314.996624) (xy 107.816593 -314.971123) (xy 107.869377 -314.953116) (xy 107.92422 -314.942986)
			(xy 107.979954 -314.940949) (xy 108.035391 -314.947049) (xy 108.089348 -314.961155) (xy 108.140677 -314.982967)
			(xy 108.188283 -315.012021) (xy 108.231151 -315.047696) (xy 108.268368 -315.089233) (xy 108.299141 -315.135746)
			(xy 108.322813 -315.186243) (xy 108.338881 -315.23965) (xy 108.347001 -315.294826) (xy 108.34751 -315.322712)
			(xy 108.599984 -315.322712) (xy 108.604055 -315.26709) (xy 108.616181 -315.212653) (xy 108.636104 -315.160562)
			(xy 108.6634 -315.111927) (xy 108.697486 -315.067784) (xy 108.737635 -315.029075) (xy 108.782993 -314.996624)
			(xy 108.832593 -314.971123) (xy 108.885377 -314.953116) (xy 108.94022 -314.942986) (xy 108.995954 -314.940949)
			(xy 109.051391 -314.947049) (xy 109.105348 -314.961155) (xy 109.156677 -314.982967) (xy 109.204283 -315.012021)
			(xy 109.247151 -315.047696) (xy 109.284368 -315.089233) (xy 109.315141 -315.135746) (xy 109.338813 -315.186243)
			(xy 109.354881 -315.23965) (xy 109.363001 -315.294826) (xy 109.36351 -315.322712) (xy 109.615984 -315.322712)
			(xy 109.620055 -315.26709) (xy 109.632181 -315.212653) (xy 109.652104 -315.160562) (xy 109.6794 -315.111927)
			(xy 109.713486 -315.067784) (xy 109.753635 -315.029075) (xy 109.798993 -314.996624) (xy 109.848593 -314.971123)
			(xy 109.901377 -314.953116) (xy 109.95622 -314.942986) (xy 110.011954 -314.940949) (xy 110.067391 -314.947049)
			(xy 110.121348 -314.961155) (xy 110.172677 -314.982967) (xy 110.220283 -315.012021) (xy 110.263151 -315.047696)
			(xy 110.300368 -315.089233) (xy 110.331141 -315.135746) (xy 110.354813 -315.186243) (xy 110.370881 -315.23965)
			(xy 110.379001 -315.294826) (xy 110.37951 -315.322712) (xy 110.379001 -315.350598) (xy 110.370881 -315.405774)
			(xy 110.354813 -315.459181) (xy 110.331141 -315.509678) (xy 110.326114 -315.517276) (xy 125.23673 -315.517276)
			(xy 125.240801 -315.461654) (xy 125.252927 -315.407217) (xy 125.27285 -315.355126) (xy 125.300146 -315.306491)
			(xy 125.334232 -315.262348) (xy 125.374381 -315.223639) (xy 125.419739 -315.191188) (xy 125.469339 -315.165687)
			(xy 125.522123 -315.14768) (xy 125.576966 -315.13755) (xy 125.6327 -315.135513) (xy 125.688137 -315.141613)
			(xy 125.742094 -315.155719) (xy 125.793423 -315.177531) (xy 125.841029 -315.206585) (xy 125.883897 -315.24226)
			(xy 125.921114 -315.283797) (xy 125.951887 -315.33031) (xy 125.975559 -315.380807) (xy 125.991627 -315.434214)
			(xy 125.999747 -315.48939) (xy 126.000256 -315.517276) (xy 126.25273 -315.517276) (xy 126.256801 -315.461654)
			(xy 126.268927 -315.407217) (xy 126.28885 -315.355126) (xy 126.316146 -315.306491) (xy 126.350232 -315.262348)
			(xy 126.390381 -315.223639) (xy 126.435739 -315.191188) (xy 126.485339 -315.165687) (xy 126.538123 -315.14768)
			(xy 126.592966 -315.13755) (xy 126.6487 -315.135513) (xy 126.704137 -315.141613) (xy 126.758094 -315.155719)
			(xy 126.809423 -315.177531) (xy 126.857029 -315.206585) (xy 126.899897 -315.24226) (xy 126.937114 -315.283797)
			(xy 126.967887 -315.33031) (xy 126.991559 -315.380807) (xy 127.007627 -315.434214) (xy 127.015747 -315.48939)
			(xy 127.016256 -315.517276) (xy 127.26873 -315.517276) (xy 127.272801 -315.461654) (xy 127.284927 -315.407217)
			(xy 127.30485 -315.355126) (xy 127.332146 -315.306491) (xy 127.366232 -315.262348) (xy 127.406381 -315.223639)
			(xy 127.451739 -315.191188) (xy 127.501339 -315.165687) (xy 127.554123 -315.14768) (xy 127.608966 -315.13755)
			(xy 127.6647 -315.135513) (xy 127.720137 -315.141613) (xy 127.774094 -315.155719) (xy 127.825423 -315.177531)
			(xy 127.873029 -315.206585) (xy 127.915897 -315.24226) (xy 127.953114 -315.283797) (xy 127.983887 -315.33031)
			(xy 128.007559 -315.380807) (xy 128.023627 -315.434214) (xy 128.031747 -315.48939) (xy 128.032256 -315.517276)
			(xy 128.28473 -315.517276) (xy 128.288801 -315.461654) (xy 128.300927 -315.407217) (xy 128.32085 -315.355126)
			(xy 128.348146 -315.306491) (xy 128.382232 -315.262348) (xy 128.422381 -315.223639) (xy 128.467739 -315.191188)
			(xy 128.517339 -315.165687) (xy 128.570123 -315.14768) (xy 128.624966 -315.13755) (xy 128.6807 -315.135513)
			(xy 128.736137 -315.141613) (xy 128.790094 -315.155719) (xy 128.841423 -315.177531) (xy 128.889029 -315.206585)
			(xy 128.931897 -315.24226) (xy 128.969114 -315.283797) (xy 128.999887 -315.33031) (xy 129.023559 -315.380807)
			(xy 129.039627 -315.434214) (xy 129.047747 -315.48939) (xy 129.048256 -315.517276) (xy 129.30073 -315.517276)
			(xy 129.304801 -315.461654) (xy 129.316927 -315.407217) (xy 129.33685 -315.355126) (xy 129.364146 -315.306491)
			(xy 129.398232 -315.262348) (xy 129.438381 -315.223639) (xy 129.483739 -315.191188) (xy 129.533339 -315.165687)
			(xy 129.586123 -315.14768) (xy 129.640966 -315.13755) (xy 129.6967 -315.135513) (xy 129.752137 -315.141613)
			(xy 129.806094 -315.155719) (xy 129.857423 -315.177531) (xy 129.905029 -315.206585) (xy 129.947897 -315.24226)
			(xy 129.985114 -315.283797) (xy 130.015887 -315.33031) (xy 130.039559 -315.380807) (xy 130.055627 -315.434214)
			(xy 130.063747 -315.48939) (xy 130.064256 -315.517276) (xy 130.31673 -315.517276) (xy 130.320801 -315.461654)
			(xy 130.332927 -315.407217) (xy 130.35285 -315.355126) (xy 130.380146 -315.306491) (xy 130.414232 -315.262348)
			(xy 130.454381 -315.223639) (xy 130.499739 -315.191188) (xy 130.549339 -315.165687) (xy 130.602123 -315.14768)
			(xy 130.656966 -315.13755) (xy 130.7127 -315.135513) (xy 130.768137 -315.141613) (xy 130.822094 -315.155719)
			(xy 130.873423 -315.177531) (xy 130.921029 -315.206585) (xy 130.963897 -315.24226) (xy 131.001114 -315.283797)
			(xy 131.031887 -315.33031) (xy 131.055559 -315.380807) (xy 131.071627 -315.434214) (xy 131.079747 -315.48939)
			(xy 131.080256 -315.517276) (xy 131.079747 -315.545162) (xy 131.071627 -315.600338) (xy 131.055559 -315.653745)
			(xy 131.031887 -315.704242) (xy 131.001114 -315.750755) (xy 130.963897 -315.792292) (xy 130.921029 -315.827967)
			(xy 130.873423 -315.857021) (xy 130.822094 -315.878833) (xy 130.768137 -315.892939) (xy 130.7127 -315.899039)
			(xy 130.656966 -315.897002) (xy 130.602123 -315.886872) (xy 130.549339 -315.868865) (xy 130.499739 -315.843364)
			(xy 130.454381 -315.810913) (xy 130.414232 -315.772204) (xy 130.380146 -315.728061) (xy 130.35285 -315.679426)
			(xy 130.332927 -315.627335) (xy 130.320801 -315.572898) (xy 130.31673 -315.517276) (xy 130.064256 -315.517276)
			(xy 130.063747 -315.545162) (xy 130.055627 -315.600338) (xy 130.039559 -315.653745) (xy 130.015887 -315.704242)
			(xy 129.985114 -315.750755) (xy 129.947897 -315.792292) (xy 129.905029 -315.827967) (xy 129.857423 -315.857021)
			(xy 129.806094 -315.878833) (xy 129.752137 -315.892939) (xy 129.6967 -315.899039) (xy 129.640966 -315.897002)
			(xy 129.586123 -315.886872) (xy 129.533339 -315.868865) (xy 129.483739 -315.843364) (xy 129.438381 -315.810913)
			(xy 129.398232 -315.772204) (xy 129.364146 -315.728061) (xy 129.33685 -315.679426) (xy 129.316927 -315.627335)
			(xy 129.304801 -315.572898) (xy 129.30073 -315.517276) (xy 129.048256 -315.517276) (xy 129.047747 -315.545162)
			(xy 129.039627 -315.600338) (xy 129.023559 -315.653745) (xy 128.999887 -315.704242) (xy 128.969114 -315.750755)
			(xy 128.931897 -315.792292) (xy 128.889029 -315.827967) (xy 128.841423 -315.857021) (xy 128.790094 -315.878833)
			(xy 128.736137 -315.892939) (xy 128.6807 -315.899039) (xy 128.624966 -315.897002) (xy 128.570123 -315.886872)
			(xy 128.517339 -315.868865) (xy 128.467739 -315.843364) (xy 128.422381 -315.810913) (xy 128.382232 -315.772204)
			(xy 128.348146 -315.728061) (xy 128.32085 -315.679426) (xy 128.300927 -315.627335) (xy 128.288801 -315.572898)
			(xy 128.28473 -315.517276) (xy 128.032256 -315.517276) (xy 128.031747 -315.545162) (xy 128.023627 -315.600338)
			(xy 128.007559 -315.653745) (xy 127.983887 -315.704242) (xy 127.953114 -315.750755) (xy 127.915897 -315.792292)
			(xy 127.873029 -315.827967) (xy 127.825423 -315.857021) (xy 127.774094 -315.878833) (xy 127.720137 -315.892939)
			(xy 127.6647 -315.899039) (xy 127.608966 -315.897002) (xy 127.554123 -315.886872) (xy 127.501339 -315.868865)
			(xy 127.451739 -315.843364) (xy 127.406381 -315.810913) (xy 127.366232 -315.772204) (xy 127.332146 -315.728061)
			(xy 127.30485 -315.679426) (xy 127.284927 -315.627335) (xy 127.272801 -315.572898) (xy 127.26873 -315.517276)
			(xy 127.016256 -315.517276) (xy 127.015747 -315.545162) (xy 127.007627 -315.600338) (xy 126.991559 -315.653745)
			(xy 126.967887 -315.704242) (xy 126.937114 -315.750755) (xy 126.899897 -315.792292) (xy 126.857029 -315.827967)
			(xy 126.809423 -315.857021) (xy 126.758094 -315.878833) (xy 126.704137 -315.892939) (xy 126.6487 -315.899039)
			(xy 126.592966 -315.897002) (xy 126.538123 -315.886872) (xy 126.485339 -315.868865) (xy 126.435739 -315.843364)
			(xy 126.390381 -315.810913) (xy 126.350232 -315.772204) (xy 126.316146 -315.728061) (xy 126.28885 -315.679426)
			(xy 126.268927 -315.627335) (xy 126.256801 -315.572898) (xy 126.25273 -315.517276) (xy 126.000256 -315.517276)
			(xy 125.999747 -315.545162) (xy 125.991627 -315.600338) (xy 125.975559 -315.653745) (xy 125.951887 -315.704242)
			(xy 125.921114 -315.750755) (xy 125.883897 -315.792292) (xy 125.841029 -315.827967) (xy 125.793423 -315.857021)
			(xy 125.742094 -315.878833) (xy 125.688137 -315.892939) (xy 125.6327 -315.899039) (xy 125.576966 -315.897002)
			(xy 125.522123 -315.886872) (xy 125.469339 -315.868865) (xy 125.419739 -315.843364) (xy 125.374381 -315.810913)
			(xy 125.334232 -315.772204) (xy 125.300146 -315.728061) (xy 125.27285 -315.679426) (xy 125.252927 -315.627335)
			(xy 125.240801 -315.572898) (xy 125.23673 -315.517276) (xy 110.326114 -315.517276) (xy 110.300368 -315.556191)
			(xy 110.263151 -315.597728) (xy 110.220283 -315.633403) (xy 110.172677 -315.662457) (xy 110.121348 -315.684269)
			(xy 110.067391 -315.698375) (xy 110.011954 -315.704475) (xy 109.95622 -315.702438) (xy 109.901377 -315.692308)
			(xy 109.848593 -315.674301) (xy 109.798993 -315.6488) (xy 109.753635 -315.616349) (xy 109.713486 -315.57764)
			(xy 109.6794 -315.533497) (xy 109.652104 -315.484862) (xy 109.632181 -315.432771) (xy 109.620055 -315.378334)
			(xy 109.615984 -315.322712) (xy 109.36351 -315.322712) (xy 109.363001 -315.350598) (xy 109.354881 -315.405774)
			(xy 109.338813 -315.459181) (xy 109.315141 -315.509678) (xy 109.284368 -315.556191) (xy 109.247151 -315.597728)
			(xy 109.204283 -315.633403) (xy 109.156677 -315.662457) (xy 109.105348 -315.684269) (xy 109.051391 -315.698375)
			(xy 108.995954 -315.704475) (xy 108.94022 -315.702438) (xy 108.885377 -315.692308) (xy 108.832593 -315.674301)
			(xy 108.782993 -315.6488) (xy 108.737635 -315.616349) (xy 108.697486 -315.57764) (xy 108.6634 -315.533497)
			(xy 108.636104 -315.484862) (xy 108.616181 -315.432771) (xy 108.604055 -315.378334) (xy 108.599984 -315.322712)
			(xy 108.34751 -315.322712) (xy 108.347001 -315.350598) (xy 108.338881 -315.405774) (xy 108.322813 -315.459181)
			(xy 108.299141 -315.509678) (xy 108.268368 -315.556191) (xy 108.231151 -315.597728) (xy 108.188283 -315.633403)
			(xy 108.140677 -315.662457) (xy 108.089348 -315.684269) (xy 108.035391 -315.698375) (xy 107.979954 -315.704475)
			(xy 107.92422 -315.702438) (xy 107.869377 -315.692308) (xy 107.816593 -315.674301) (xy 107.766993 -315.6488)
			(xy 107.721635 -315.616349) (xy 107.681486 -315.57764) (xy 107.6474 -315.533497) (xy 107.620104 -315.484862)
			(xy 107.600181 -315.432771) (xy 107.588055 -315.378334) (xy 107.583984 -315.322712) (xy 107.33151 -315.322712)
			(xy 107.331001 -315.350598) (xy 107.322881 -315.405774) (xy 107.306813 -315.459181) (xy 107.283141 -315.509678)
			(xy 107.252368 -315.556191) (xy 107.215151 -315.597728) (xy 107.172283 -315.633403) (xy 107.124677 -315.662457)
			(xy 107.073348 -315.684269) (xy 107.019391 -315.698375) (xy 106.963954 -315.704475) (xy 106.90822 -315.702438)
			(xy 106.853377 -315.692308) (xy 106.800593 -315.674301) (xy 106.750993 -315.6488) (xy 106.705635 -315.616349)
			(xy 106.665486 -315.57764) (xy 106.6314 -315.533497) (xy 106.604104 -315.484862) (xy 106.584181 -315.432771)
			(xy 106.572055 -315.378334) (xy 106.567984 -315.322712) (xy 106.31551 -315.322712) (xy 106.315001 -315.350598)
			(xy 106.306881 -315.405774) (xy 106.290813 -315.459181) (xy 106.267141 -315.509678) (xy 106.236368 -315.556191)
			(xy 106.199151 -315.597728) (xy 106.156283 -315.633403) (xy 106.108677 -315.662457) (xy 106.057348 -315.684269)
			(xy 106.003391 -315.698375) (xy 105.947954 -315.704475) (xy 105.89222 -315.702438) (xy 105.837377 -315.692308)
			(xy 105.784593 -315.674301) (xy 105.734993 -315.6488) (xy 105.689635 -315.616349) (xy 105.649486 -315.57764)
			(xy 105.6154 -315.533497) (xy 105.588104 -315.484862) (xy 105.568181 -315.432771) (xy 105.556055 -315.378334)
			(xy 105.551984 -315.322712) (xy 105.29951 -315.322712) (xy 105.299001 -315.350598) (xy 105.290881 -315.405774)
			(xy 105.274813 -315.459181) (xy 105.251141 -315.509678) (xy 105.220368 -315.556191) (xy 105.183151 -315.597728)
			(xy 105.140283 -315.633403) (xy 105.092677 -315.662457) (xy 105.041348 -315.684269) (xy 104.987391 -315.698375)
			(xy 104.931954 -315.704475) (xy 104.87622 -315.702438) (xy 104.821377 -315.692308) (xy 104.768593 -315.674301)
			(xy 104.718993 -315.6488) (xy 104.673635 -315.616349) (xy 104.633486 -315.57764) (xy 104.5994 -315.533497)
			(xy 104.572104 -315.484862) (xy 104.552181 -315.432771) (xy 104.540055 -315.378334) (xy 104.535984 -315.322712)
			(xy 104.28351 -315.322712) (xy 104.283001 -315.350598) (xy 104.274881 -315.405774) (xy 104.258813 -315.459181)
			(xy 104.235141 -315.509678) (xy 104.204368 -315.556191) (xy 104.167151 -315.597728) (xy 104.124283 -315.633403)
			(xy 104.076677 -315.662457) (xy 104.025348 -315.684269) (xy 103.971391 -315.698375) (xy 103.915954 -315.704475)
			(xy 103.86022 -315.702438) (xy 103.805377 -315.692308) (xy 103.752593 -315.674301) (xy 103.702993 -315.6488)
			(xy 103.657635 -315.616349) (xy 103.617486 -315.57764) (xy 103.5834 -315.533497) (xy 103.556104 -315.484862)
			(xy 103.536181 -315.432771) (xy 103.524055 -315.378334) (xy 103.519984 -315.322712) (xy 103.26751 -315.322712)
			(xy 103.267001 -315.350598) (xy 103.258881 -315.405774) (xy 103.242813 -315.459181) (xy 103.219141 -315.509678)
			(xy 103.188368 -315.556191) (xy 103.151151 -315.597728) (xy 103.108283 -315.633403) (xy 103.060677 -315.662457)
			(xy 103.009348 -315.684269) (xy 102.955391 -315.698375) (xy 102.899954 -315.704475) (xy 102.84422 -315.702438)
			(xy 102.789377 -315.692308) (xy 102.736593 -315.674301) (xy 102.686993 -315.6488) (xy 102.641635 -315.616349)
			(xy 102.601486 -315.57764) (xy 102.5674 -315.533497) (xy 102.540104 -315.484862) (xy 102.520181 -315.432771)
			(xy 102.508055 -315.378334) (xy 102.503984 -315.322712) (xy 102.25101 -315.322712) (xy 102.25101 -315.34995)
			(xy 102.243254 -315.403896) (xy 102.227899 -315.456189) (xy 102.205259 -315.505764) (xy 102.175794 -315.551613)
			(xy 102.140103 -315.592802) (xy 102.098915 -315.628492) (xy 102.053066 -315.657958) (xy 102.003491 -315.680598)
			(xy 101.951198 -315.695953) (xy 101.897252 -315.70371) (xy 101.870002 -315.70422) (xy 101.841245 -315.703702)
			(xy 101.784383 -315.695066) (xy 101.729466 -315.677975) (xy 101.703378 -315.665866) (xy 101.703124 -315.665866)
			(xy 101.696178 -315.662827) (xy 101.681202 -315.660513) (xy 101.67366 -315.661294) (xy 101.66604 -315.66231)
			(xy 101.658928 -315.665866) (xy 101.655691 -315.667577) (xy 101.649699 -315.671785) (xy 101.64699 -315.674248)
			(xy 101.619812 -315.699648) (xy 101.612616 -315.707056) (xy 101.604321 -315.725948) (xy 101.604102 -315.746581)
			(xy 101.60762 -315.75629) (xy 101.848934 -316.338712) (xy 102.503984 -316.338712) (xy 102.508055 -316.28309)
			(xy 102.520181 -316.228653) (xy 102.540104 -316.176562) (xy 102.5674 -316.127927) (xy 102.601486 -316.083784)
			(xy 102.641635 -316.045075) (xy 102.686993 -316.012624) (xy 102.736593 -315.987123) (xy 102.789377 -315.969116)
			(xy 102.84422 -315.958986) (xy 102.899954 -315.956949) (xy 102.955391 -315.963049) (xy 103.009348 -315.977155)
			(xy 103.060677 -315.998967) (xy 103.108283 -316.028021) (xy 103.151151 -316.063696) (xy 103.188368 -316.105233)
			(xy 103.219141 -316.151746) (xy 103.242813 -316.202243) (xy 103.258881 -316.25565) (xy 103.267001 -316.310826)
			(xy 103.26751 -316.338712) (xy 103.519984 -316.338712) (xy 103.524055 -316.28309) (xy 103.536181 -316.228653)
			(xy 103.556104 -316.176562) (xy 103.5834 -316.127927) (xy 103.617486 -316.083784) (xy 103.657635 -316.045075)
			(xy 103.702993 -316.012624) (xy 103.752593 -315.987123) (xy 103.805377 -315.969116) (xy 103.86022 -315.958986)
			(xy 103.915954 -315.956949) (xy 103.971391 -315.963049) (xy 104.025348 -315.977155) (xy 104.076677 -315.998967)
			(xy 104.124283 -316.028021) (xy 104.167151 -316.063696) (xy 104.204368 -316.105233) (xy 104.235141 -316.151746)
			(xy 104.258813 -316.202243) (xy 104.274881 -316.25565) (xy 104.283001 -316.310826) (xy 104.28351 -316.338712)
			(xy 104.535984 -316.338712) (xy 104.540055 -316.28309) (xy 104.552181 -316.228653) (xy 104.572104 -316.176562)
			(xy 104.5994 -316.127927) (xy 104.633486 -316.083784) (xy 104.673635 -316.045075) (xy 104.718993 -316.012624)
			(xy 104.768593 -315.987123) (xy 104.821377 -315.969116) (xy 104.87622 -315.958986) (xy 104.931954 -315.956949)
			(xy 104.987391 -315.963049) (xy 105.041348 -315.977155) (xy 105.092677 -315.998967) (xy 105.140283 -316.028021)
			(xy 105.183151 -316.063696) (xy 105.220368 -316.105233) (xy 105.251141 -316.151746) (xy 105.274813 -316.202243)
			(xy 105.290881 -316.25565) (xy 105.299001 -316.310826) (xy 105.29951 -316.338712) (xy 105.551984 -316.338712)
			(xy 105.556055 -316.28309) (xy 105.568181 -316.228653) (xy 105.588104 -316.176562) (xy 105.6154 -316.127927)
			(xy 105.649486 -316.083784) (xy 105.689635 -316.045075) (xy 105.734993 -316.012624) (xy 105.784593 -315.987123)
			(xy 105.837377 -315.969116) (xy 105.89222 -315.958986) (xy 105.947954 -315.956949) (xy 106.003391 -315.963049)
			(xy 106.057348 -315.977155) (xy 106.108677 -315.998967) (xy 106.156283 -316.028021) (xy 106.199151 -316.063696)
			(xy 106.236368 -316.105233) (xy 106.267141 -316.151746) (xy 106.290813 -316.202243) (xy 106.306881 -316.25565)
			(xy 106.315001 -316.310826) (xy 106.31551 -316.338712) (xy 106.567984 -316.338712) (xy 106.572055 -316.28309)
			(xy 106.584181 -316.228653) (xy 106.604104 -316.176562) (xy 106.6314 -316.127927) (xy 106.665486 -316.083784)
			(xy 106.705635 -316.045075) (xy 106.750993 -316.012624) (xy 106.800593 -315.987123) (xy 106.853377 -315.969116)
			(xy 106.90822 -315.958986) (xy 106.963954 -315.956949) (xy 107.019391 -315.963049) (xy 107.073348 -315.977155)
			(xy 107.124677 -315.998967) (xy 107.172283 -316.028021) (xy 107.215151 -316.063696) (xy 107.252368 -316.105233)
			(xy 107.283141 -316.151746) (xy 107.306813 -316.202243) (xy 107.322881 -316.25565) (xy 107.331001 -316.310826)
			(xy 107.33151 -316.338712) (xy 107.583984 -316.338712) (xy 107.588055 -316.28309) (xy 107.600181 -316.228653)
			(xy 107.620104 -316.176562) (xy 107.6474 -316.127927) (xy 107.681486 -316.083784) (xy 107.721635 -316.045075)
			(xy 107.766993 -316.012624) (xy 107.816593 -315.987123) (xy 107.869377 -315.969116) (xy 107.92422 -315.958986)
			(xy 107.979954 -315.956949) (xy 108.035391 -315.963049) (xy 108.089348 -315.977155) (xy 108.140677 -315.998967)
			(xy 108.188283 -316.028021) (xy 108.231151 -316.063696) (xy 108.268368 -316.105233) (xy 108.299141 -316.151746)
			(xy 108.322813 -316.202243) (xy 108.338881 -316.25565) (xy 108.347001 -316.310826) (xy 108.34751 -316.338712)
			(xy 108.599984 -316.338712) (xy 108.604055 -316.28309) (xy 108.616181 -316.228653) (xy 108.636104 -316.176562)
			(xy 108.6634 -316.127927) (xy 108.697486 -316.083784) (xy 108.737635 -316.045075) (xy 108.782993 -316.012624)
			(xy 108.832593 -315.987123) (xy 108.885377 -315.969116) (xy 108.94022 -315.958986) (xy 108.995954 -315.956949)
			(xy 109.051391 -315.963049) (xy 109.105348 -315.977155) (xy 109.156677 -315.998967) (xy 109.204283 -316.028021)
			(xy 109.247151 -316.063696) (xy 109.284368 -316.105233) (xy 109.315141 -316.151746) (xy 109.338813 -316.202243)
			(xy 109.354881 -316.25565) (xy 109.363001 -316.310826) (xy 109.36351 -316.338712) (xy 109.615984 -316.338712)
			(xy 109.620055 -316.28309) (xy 109.632181 -316.228653) (xy 109.652104 -316.176562) (xy 109.6794 -316.127927)
			(xy 109.713486 -316.083784) (xy 109.753635 -316.045075) (xy 109.798993 -316.012624) (xy 109.848593 -315.987123)
			(xy 109.901377 -315.969116) (xy 109.95622 -315.958986) (xy 110.011954 -315.956949) (xy 110.067391 -315.963049)
			(xy 110.121348 -315.977155) (xy 110.172677 -315.998967) (xy 110.220283 -316.028021) (xy 110.263151 -316.063696)
			(xy 110.300368 -316.105233) (xy 110.331141 -316.151746) (xy 110.354813 -316.202243) (xy 110.370881 -316.25565)
			(xy 110.379001 -316.310826) (xy 110.37951 -316.338712) (xy 110.379001 -316.366598) (xy 110.370881 -316.421774)
			(xy 110.354813 -316.475181) (xy 110.331141 -316.525678) (xy 110.326114 -316.533276) (xy 125.23673 -316.533276)
			(xy 125.240801 -316.477654) (xy 125.252927 -316.423217) (xy 125.27285 -316.371126) (xy 125.300146 -316.322491)
			(xy 125.334232 -316.278348) (xy 125.374381 -316.239639) (xy 125.419739 -316.207188) (xy 125.469339 -316.181687)
			(xy 125.522123 -316.16368) (xy 125.576966 -316.15355) (xy 125.6327 -316.151513) (xy 125.688137 -316.157613)
			(xy 125.742094 -316.171719) (xy 125.793423 -316.193531) (xy 125.841029 -316.222585) (xy 125.883897 -316.25826)
			(xy 125.921114 -316.299797) (xy 125.951887 -316.34631) (xy 125.975559 -316.396807) (xy 125.991627 -316.450214)
			(xy 125.999747 -316.50539) (xy 126.000256 -316.533276) (xy 126.25273 -316.533276) (xy 126.256801 -316.477654)
			(xy 126.268927 -316.423217) (xy 126.28885 -316.371126) (xy 126.316146 -316.322491) (xy 126.350232 -316.278348)
			(xy 126.390381 -316.239639) (xy 126.435739 -316.207188) (xy 126.485339 -316.181687) (xy 126.538123 -316.16368)
			(xy 126.592966 -316.15355) (xy 126.6487 -316.151513) (xy 126.704137 -316.157613) (xy 126.758094 -316.171719)
			(xy 126.809423 -316.193531) (xy 126.857029 -316.222585) (xy 126.899897 -316.25826) (xy 126.937114 -316.299797)
			(xy 126.967887 -316.34631) (xy 126.991559 -316.396807) (xy 127.007627 -316.450214) (xy 127.015747 -316.50539)
			(xy 127.016256 -316.533276) (xy 127.26873 -316.533276) (xy 127.272801 -316.477654) (xy 127.284927 -316.423217)
			(xy 127.30485 -316.371126) (xy 127.332146 -316.322491) (xy 127.366232 -316.278348) (xy 127.406381 -316.239639)
			(xy 127.451739 -316.207188) (xy 127.501339 -316.181687) (xy 127.554123 -316.16368) (xy 127.608966 -316.15355)
			(xy 127.6647 -316.151513) (xy 127.720137 -316.157613) (xy 127.774094 -316.171719) (xy 127.825423 -316.193531)
			(xy 127.873029 -316.222585) (xy 127.915897 -316.25826) (xy 127.953114 -316.299797) (xy 127.983887 -316.34631)
			(xy 128.007559 -316.396807) (xy 128.023627 -316.450214) (xy 128.031747 -316.50539) (xy 128.032256 -316.533276)
			(xy 128.28473 -316.533276) (xy 128.288801 -316.477654) (xy 128.300927 -316.423217) (xy 128.32085 -316.371126)
			(xy 128.348146 -316.322491) (xy 128.382232 -316.278348) (xy 128.422381 -316.239639) (xy 128.467739 -316.207188)
			(xy 128.517339 -316.181687) (xy 128.570123 -316.16368) (xy 128.624966 -316.15355) (xy 128.6807 -316.151513)
			(xy 128.736137 -316.157613) (xy 128.790094 -316.171719) (xy 128.841423 -316.193531) (xy 128.889029 -316.222585)
			(xy 128.931897 -316.25826) (xy 128.969114 -316.299797) (xy 128.999887 -316.34631) (xy 129.023559 -316.396807)
			(xy 129.039627 -316.450214) (xy 129.047747 -316.50539) (xy 129.048256 -316.533276) (xy 129.30073 -316.533276)
			(xy 129.304801 -316.477654) (xy 129.316927 -316.423217) (xy 129.33685 -316.371126) (xy 129.364146 -316.322491)
			(xy 129.398232 -316.278348) (xy 129.438381 -316.239639) (xy 129.483739 -316.207188) (xy 129.533339 -316.181687)
			(xy 129.586123 -316.16368) (xy 129.640966 -316.15355) (xy 129.6967 -316.151513) (xy 129.752137 -316.157613)
			(xy 129.806094 -316.171719) (xy 129.857423 -316.193531) (xy 129.905029 -316.222585) (xy 129.947897 -316.25826)
			(xy 129.985114 -316.299797) (xy 130.015887 -316.34631) (xy 130.039559 -316.396807) (xy 130.055627 -316.450214)
			(xy 130.063747 -316.50539) (xy 130.064256 -316.533276) (xy 130.063747 -316.561162) (xy 130.055627 -316.616338)
			(xy 130.039559 -316.669745) (xy 130.015887 -316.720242) (xy 129.985114 -316.766755) (xy 129.947897 -316.808292)
			(xy 129.905029 -316.843967) (xy 129.857423 -316.873021) (xy 129.806094 -316.894833) (xy 129.752137 -316.908939)
			(xy 129.6967 -316.915039) (xy 129.640966 -316.913002) (xy 129.586123 -316.902872) (xy 129.533339 -316.884865)
			(xy 129.483739 -316.859364) (xy 129.438381 -316.826913) (xy 129.398232 -316.788204) (xy 129.364146 -316.744061)
			(xy 129.33685 -316.695426) (xy 129.316927 -316.643335) (xy 129.304801 -316.588898) (xy 129.30073 -316.533276)
			(xy 129.048256 -316.533276) (xy 129.047747 -316.561162) (xy 129.039627 -316.616338) (xy 129.023559 -316.669745)
			(xy 128.999887 -316.720242) (xy 128.969114 -316.766755) (xy 128.931897 -316.808292) (xy 128.889029 -316.843967)
			(xy 128.841423 -316.873021) (xy 128.790094 -316.894833) (xy 128.736137 -316.908939) (xy 128.6807 -316.915039)
			(xy 128.624966 -316.913002) (xy 128.570123 -316.902872) (xy 128.517339 -316.884865) (xy 128.467739 -316.859364)
			(xy 128.422381 -316.826913) (xy 128.382232 -316.788204) (xy 128.348146 -316.744061) (xy 128.32085 -316.695426)
			(xy 128.300927 -316.643335) (xy 128.288801 -316.588898) (xy 128.28473 -316.533276) (xy 128.032256 -316.533276)
			(xy 128.031747 -316.561162) (xy 128.023627 -316.616338) (xy 128.007559 -316.669745) (xy 127.983887 -316.720242)
			(xy 127.953114 -316.766755) (xy 127.915897 -316.808292) (xy 127.873029 -316.843967) (xy 127.825423 -316.873021)
			(xy 127.774094 -316.894833) (xy 127.720137 -316.908939) (xy 127.6647 -316.915039) (xy 127.608966 -316.913002)
			(xy 127.554123 -316.902872) (xy 127.501339 -316.884865) (xy 127.451739 -316.859364) (xy 127.406381 -316.826913)
			(xy 127.366232 -316.788204) (xy 127.332146 -316.744061) (xy 127.30485 -316.695426) (xy 127.284927 -316.643335)
			(xy 127.272801 -316.588898) (xy 127.26873 -316.533276) (xy 127.016256 -316.533276) (xy 127.015747 -316.561162)
			(xy 127.007627 -316.616338) (xy 126.991559 -316.669745) (xy 126.967887 -316.720242) (xy 126.937114 -316.766755)
			(xy 126.899897 -316.808292) (xy 126.857029 -316.843967) (xy 126.809423 -316.873021) (xy 126.758094 -316.894833)
			(xy 126.704137 -316.908939) (xy 126.6487 -316.915039) (xy 126.592966 -316.913002) (xy 126.538123 -316.902872)
			(xy 126.485339 -316.884865) (xy 126.435739 -316.859364) (xy 126.390381 -316.826913) (xy 126.350232 -316.788204)
			(xy 126.316146 -316.744061) (xy 126.28885 -316.695426) (xy 126.268927 -316.643335) (xy 126.256801 -316.588898)
			(xy 126.25273 -316.533276) (xy 126.000256 -316.533276) (xy 125.999747 -316.561162) (xy 125.991627 -316.616338)
			(xy 125.975559 -316.669745) (xy 125.951887 -316.720242) (xy 125.921114 -316.766755) (xy 125.883897 -316.808292)
			(xy 125.841029 -316.843967) (xy 125.793423 -316.873021) (xy 125.742094 -316.894833) (xy 125.688137 -316.908939)
			(xy 125.6327 -316.915039) (xy 125.576966 -316.913002) (xy 125.522123 -316.902872) (xy 125.469339 -316.884865)
			(xy 125.419739 -316.859364) (xy 125.374381 -316.826913) (xy 125.334232 -316.788204) (xy 125.300146 -316.744061)
			(xy 125.27285 -316.695426) (xy 125.252927 -316.643335) (xy 125.240801 -316.588898) (xy 125.23673 -316.533276)
			(xy 110.326114 -316.533276) (xy 110.300368 -316.572191) (xy 110.263151 -316.613728) (xy 110.220283 -316.649403)
			(xy 110.172677 -316.678457) (xy 110.121348 -316.700269) (xy 110.067391 -316.714375) (xy 110.011954 -316.720475)
			(xy 109.95622 -316.718438) (xy 109.901377 -316.708308) (xy 109.848593 -316.690301) (xy 109.798993 -316.6648)
			(xy 109.753635 -316.632349) (xy 109.713486 -316.59364) (xy 109.6794 -316.549497) (xy 109.652104 -316.500862)
			(xy 109.632181 -316.448771) (xy 109.620055 -316.394334) (xy 109.615984 -316.338712) (xy 109.36351 -316.338712)
			(xy 109.363001 -316.366598) (xy 109.354881 -316.421774) (xy 109.338813 -316.475181) (xy 109.315141 -316.525678)
			(xy 109.284368 -316.572191) (xy 109.247151 -316.613728) (xy 109.204283 -316.649403) (xy 109.156677 -316.678457)
			(xy 109.105348 -316.700269) (xy 109.051391 -316.714375) (xy 108.995954 -316.720475) (xy 108.94022 -316.718438)
			(xy 108.885377 -316.708308) (xy 108.832593 -316.690301) (xy 108.782993 -316.6648) (xy 108.737635 -316.632349)
			(xy 108.697486 -316.59364) (xy 108.6634 -316.549497) (xy 108.636104 -316.500862) (xy 108.616181 -316.448771)
			(xy 108.604055 -316.394334) (xy 108.599984 -316.338712) (xy 108.34751 -316.338712) (xy 108.347001 -316.366598)
			(xy 108.338881 -316.421774) (xy 108.322813 -316.475181) (xy 108.299141 -316.525678) (xy 108.268368 -316.572191)
			(xy 108.231151 -316.613728) (xy 108.188283 -316.649403) (xy 108.140677 -316.678457) (xy 108.089348 -316.700269)
			(xy 108.035391 -316.714375) (xy 107.979954 -316.720475) (xy 107.92422 -316.718438) (xy 107.869377 -316.708308)
			(xy 107.816593 -316.690301) (xy 107.766993 -316.6648) (xy 107.721635 -316.632349) (xy 107.681486 -316.59364)
			(xy 107.6474 -316.549497) (xy 107.620104 -316.500862) (xy 107.600181 -316.448771) (xy 107.588055 -316.394334)
			(xy 107.583984 -316.338712) (xy 107.33151 -316.338712) (xy 107.331001 -316.366598) (xy 107.322881 -316.421774)
			(xy 107.306813 -316.475181) (xy 107.283141 -316.525678) (xy 107.252368 -316.572191) (xy 107.215151 -316.613728)
			(xy 107.172283 -316.649403) (xy 107.124677 -316.678457) (xy 107.073348 -316.700269) (xy 107.019391 -316.714375)
			(xy 106.963954 -316.720475) (xy 106.90822 -316.718438) (xy 106.853377 -316.708308) (xy 106.800593 -316.690301)
			(xy 106.750993 -316.6648) (xy 106.705635 -316.632349) (xy 106.665486 -316.59364) (xy 106.6314 -316.549497)
			(xy 106.604104 -316.500862) (xy 106.584181 -316.448771) (xy 106.572055 -316.394334) (xy 106.567984 -316.338712)
			(xy 106.31551 -316.338712) (xy 106.315001 -316.366598) (xy 106.306881 -316.421774) (xy 106.290813 -316.475181)
			(xy 106.267141 -316.525678) (xy 106.236368 -316.572191) (xy 106.199151 -316.613728) (xy 106.156283 -316.649403)
			(xy 106.108677 -316.678457) (xy 106.057348 -316.700269) (xy 106.003391 -316.714375) (xy 105.947954 -316.720475)
			(xy 105.89222 -316.718438) (xy 105.837377 -316.708308) (xy 105.784593 -316.690301) (xy 105.734993 -316.6648)
			(xy 105.689635 -316.632349) (xy 105.649486 -316.59364) (xy 105.6154 -316.549497) (xy 105.588104 -316.500862)
			(xy 105.568181 -316.448771) (xy 105.556055 -316.394334) (xy 105.551984 -316.338712) (xy 105.29951 -316.338712)
			(xy 105.299001 -316.366598) (xy 105.290881 -316.421774) (xy 105.274813 -316.475181) (xy 105.251141 -316.525678)
			(xy 105.220368 -316.572191) (xy 105.183151 -316.613728) (xy 105.140283 -316.649403) (xy 105.092677 -316.678457)
			(xy 105.041348 -316.700269) (xy 104.987391 -316.714375) (xy 104.931954 -316.720475) (xy 104.87622 -316.718438)
			(xy 104.821377 -316.708308) (xy 104.768593 -316.690301) (xy 104.718993 -316.6648) (xy 104.673635 -316.632349)
			(xy 104.633486 -316.59364) (xy 104.5994 -316.549497) (xy 104.572104 -316.500862) (xy 104.552181 -316.448771)
			(xy 104.540055 -316.394334) (xy 104.535984 -316.338712) (xy 104.28351 -316.338712) (xy 104.283001 -316.366598)
			(xy 104.274881 -316.421774) (xy 104.258813 -316.475181) (xy 104.235141 -316.525678) (xy 104.204368 -316.572191)
			(xy 104.167151 -316.613728) (xy 104.124283 -316.649403) (xy 104.076677 -316.678457) (xy 104.025348 -316.700269)
			(xy 103.971391 -316.714375) (xy 103.915954 -316.720475) (xy 103.86022 -316.718438) (xy 103.805377 -316.708308)
			(xy 103.752593 -316.690301) (xy 103.702993 -316.6648) (xy 103.657635 -316.632349) (xy 103.617486 -316.59364)
			(xy 103.5834 -316.549497) (xy 103.556104 -316.500862) (xy 103.536181 -316.448771) (xy 103.524055 -316.394334)
			(xy 103.519984 -316.338712) (xy 103.26751 -316.338712) (xy 103.267001 -316.366598) (xy 103.258881 -316.421774)
			(xy 103.242813 -316.475181) (xy 103.219141 -316.525678) (xy 103.188368 -316.572191) (xy 103.151151 -316.613728)
			(xy 103.108283 -316.649403) (xy 103.060677 -316.678457) (xy 103.009348 -316.700269) (xy 102.955391 -316.714375)
			(xy 102.899954 -316.720475) (xy 102.84422 -316.718438) (xy 102.789377 -316.708308) (xy 102.736593 -316.690301)
			(xy 102.686993 -316.6648) (xy 102.641635 -316.632349) (xy 102.601486 -316.59364) (xy 102.5674 -316.549497)
			(xy 102.540104 -316.500862) (xy 102.520181 -316.448771) (xy 102.508055 -316.394334) (xy 102.503984 -316.338712)
			(xy 101.848934 -316.338712) (xy 102.211378 -317.213488) (xy 102.219325 -317.23362) (xy 102.230519 -317.275429)
			(xy 102.236172 -317.318339) (xy 102.236524 -317.33998) (xy 102.236524 -320.08064) (xy 106.2228 -320.08064)
			(xy 106.223347 -320.051724) (xy 106.23207 -319.994554) (xy 106.249322 -319.939356) (xy 106.274709 -319.887394)
			(xy 106.307647 -319.83986) (xy 106.347383 -319.797841) (xy 106.369866 -319.77965) (xy 106.378652 -319.772023)
			(xy 106.388844 -319.751137) (xy 106.389424 -319.739518) (xy 106.389424 -319.659762) (xy 106.388919 -319.648125)
			(xy 106.378709 -319.627214) (xy 106.369866 -319.61963) (xy 106.34739 -319.601431) (xy 106.307656 -319.559412)
			(xy 106.274717 -319.511878) (xy 106.249328 -319.459919) (xy 106.232069 -319.404723) (xy 106.223337 -319.347555)
			(xy 106.2228 -319.31864) (xy 106.223293 -319.291388) (xy 106.231044 -319.237437) (xy 106.246396 -319.18514)
			(xy 106.269034 -319.135559) (xy 106.298499 -319.089705) (xy 106.334189 -319.048512) (xy 106.37538 -319.012818)
			(xy 106.421231 -318.983349) (xy 106.47081 -318.960707) (xy 106.523106 -318.945351) (xy 106.577056 -318.937595)
			(xy 106.604308 -318.937132) (xy 106.633223 -318.937704) (xy 106.690392 -318.946421) (xy 106.74559 -318.963667)
			(xy 106.797553 -318.989048) (xy 106.845088 -319.021983) (xy 106.887106 -319.061716) (xy 106.905298 -319.084198)
			(xy 106.912916 -319.092994) (xy 106.933808 -319.103184) (xy 106.94543 -319.103756) (xy 107.025186 -319.103756)
			(xy 107.036817 -319.10321) (xy 107.057728 -319.093028) (xy 107.065318 -319.084198) (xy 107.082071 -319.063415)
			(xy 107.120425 -319.026285) (xy 107.163579 -318.994863) (xy 107.210693 -318.969764) (xy 107.260845 -318.951478)
			(xy 107.313056 -318.940361) (xy 107.366308 -318.936631) (xy 107.41956 -318.940361) (xy 107.471771 -318.951478)
			(xy 107.521923 -318.969764) (xy 107.569037 -318.994863) (xy 107.612191 -319.026285) (xy 107.650545 -319.063415)
			(xy 107.667298 -319.084198) (xy 107.674916 -319.092994) (xy 107.695808 -319.103184) (xy 107.70743 -319.103756)
			(xy 107.787186 -319.103756) (xy 107.798817 -319.10321) (xy 107.819728 -319.093028) (xy 107.827318 -319.084198)
			(xy 107.844071 -319.063415) (xy 107.882425 -319.026285) (xy 107.925579 -318.994863) (xy 107.972693 -318.969764)
			(xy 108.022845 -318.951478) (xy 108.075056 -318.940361) (xy 108.128308 -318.936631) (xy 108.18156 -318.940361)
			(xy 108.233771 -318.951478) (xy 108.283923 -318.969764) (xy 108.331037 -318.994863) (xy 108.374191 -319.026285)
			(xy 108.412545 -319.063415) (xy 108.429298 -319.084198) (xy 108.436916 -319.092994) (xy 108.457808 -319.103184)
			(xy 108.46943 -319.103756) (xy 108.549186 -319.103756) (xy 108.560817 -319.10321) (xy 108.581728 -319.093028)
			(xy 108.589318 -319.084198) (xy 108.606071 -319.063415) (xy 108.644425 -319.026285) (xy 108.687579 -318.994863)
			(xy 108.734693 -318.969764) (xy 108.784845 -318.951478) (xy 108.837056 -318.940361) (xy 108.890308 -318.936631)
			(xy 108.94356 -318.940361) (xy 108.995771 -318.951478) (xy 109.045923 -318.969764) (xy 109.093037 -318.994863)
			(xy 109.136191 -319.026285) (xy 109.174545 -319.063415) (xy 109.191298 -319.084198) (xy 109.198916 -319.092994)
			(xy 109.219808 -319.103184) (xy 109.23143 -319.103756) (xy 109.311186 -319.103756) (xy 109.322817 -319.10321)
			(xy 109.343728 -319.093028) (xy 109.351318 -319.084198) (xy 109.368071 -319.063415) (xy 109.406425 -319.026285)
			(xy 109.449579 -318.994863) (xy 109.496693 -318.969764) (xy 109.546845 -318.951478) (xy 109.599056 -318.940361)
			(xy 109.652308 -318.936631) (xy 109.70556 -318.940361) (xy 109.757771 -318.951478) (xy 109.807923 -318.969764)
			(xy 109.855037 -318.994863) (xy 109.898191 -319.026285) (xy 109.936545 -319.063415) (xy 109.953298 -319.084198)
			(xy 109.960916 -319.092994) (xy 109.981808 -319.103184) (xy 109.99343 -319.103756) (xy 110.073186 -319.103756)
			(xy 110.084817 -319.10321) (xy 110.105728 -319.093028) (xy 110.113318 -319.084198) (xy 110.130071 -319.063415)
			(xy 110.168425 -319.026285) (xy 110.211579 -318.994863) (xy 110.258693 -318.969764) (xy 110.308845 -318.951478)
			(xy 110.361056 -318.940361) (xy 110.414308 -318.936631) (xy 110.46756 -318.940361) (xy 110.519771 -318.951478)
			(xy 110.569923 -318.969764) (xy 110.617037 -318.994863) (xy 110.660191 -319.026285) (xy 110.698545 -319.063415)
			(xy 110.715298 -319.084198) (xy 110.722916 -319.092994) (xy 110.743808 -319.103184) (xy 110.75543 -319.103756)
			(xy 110.835186 -319.103756) (xy 110.846817 -319.10321) (xy 110.867728 -319.093028) (xy 110.875318 -319.084198)
			(xy 110.892071 -319.063415) (xy 110.930425 -319.026285) (xy 110.973579 -318.994863) (xy 111.020693 -318.969764)
			(xy 111.070845 -318.951478) (xy 111.123056 -318.940361) (xy 111.176308 -318.936631) (xy 111.22956 -318.940361)
			(xy 111.281771 -318.951478) (xy 111.331923 -318.969764) (xy 111.379037 -318.994863) (xy 111.422191 -319.026285)
			(xy 111.460545 -319.063415) (xy 111.477298 -319.084198) (xy 111.484916 -319.092994) (xy 111.505808 -319.103184)
			(xy 111.51743 -319.103756) (xy 111.597186 -319.103756) (xy 111.608817 -319.10321) (xy 111.629728 -319.093028)
			(xy 111.637318 -319.084198) (xy 111.654071 -319.063415) (xy 111.692425 -319.026285) (xy 111.735579 -318.994863)
			(xy 111.782693 -318.969764) (xy 111.832845 -318.951478) (xy 111.885056 -318.940361) (xy 111.938308 -318.936631)
			(xy 111.99156 -318.940361) (xy 112.043771 -318.951478) (xy 112.093923 -318.969764) (xy 112.141037 -318.994863)
			(xy 112.184191 -319.026285) (xy 112.222545 -319.063415) (xy 112.239298 -319.084198) (xy 112.246916 -319.092994)
			(xy 112.267808 -319.103184) (xy 112.27943 -319.103756) (xy 112.359186 -319.103756) (xy 112.370817 -319.10321)
			(xy 112.391728 -319.093028) (xy 112.399318 -319.084198) (xy 112.416071 -319.063415) (xy 112.454425 -319.026285)
			(xy 112.497579 -318.994863) (xy 112.544693 -318.969764) (xy 112.594845 -318.951478) (xy 112.647056 -318.940361)
			(xy 112.700308 -318.936631) (xy 112.75356 -318.940361) (xy 112.805771 -318.951478) (xy 112.855923 -318.969764)
			(xy 112.903037 -318.994863) (xy 112.946191 -319.026285) (xy 112.984545 -319.063415) (xy 113.001298 -319.084198)
			(xy 113.008916 -319.092994) (xy 113.029808 -319.103184) (xy 113.04143 -319.103756) (xy 113.121186 -319.103756)
			(xy 113.132817 -319.10321) (xy 113.153728 -319.093028) (xy 113.161318 -319.084198) (xy 113.178071 -319.063415)
			(xy 113.216425 -319.026285) (xy 113.259579 -318.994863) (xy 113.306693 -318.969764) (xy 113.356845 -318.951478)
			(xy 113.409056 -318.940361) (xy 113.462308 -318.936631) (xy 113.51556 -318.940361) (xy 113.567771 -318.951478)
			(xy 113.617923 -318.969764) (xy 113.665037 -318.994863) (xy 113.708191 -319.026285) (xy 113.746545 -319.063415)
			(xy 113.763298 -319.084198) (xy 113.770916 -319.092994) (xy 113.791808 -319.103184) (xy 113.80343 -319.103756)
			(xy 113.883186 -319.103756) (xy 113.894817 -319.10321) (xy 113.915728 -319.093028) (xy 113.923318 -319.084198)
			(xy 113.941498 -319.061705) (xy 113.98352 -319.021971) (xy 114.031058 -318.989033) (xy 114.083021 -318.963646)
			(xy 114.13822 -318.946392) (xy 114.195391 -318.937666) (xy 114.224308 -318.937132) (xy 114.251563 -318.937548)
			(xy 114.305518 -318.945307) (xy 114.357819 -318.960666) (xy 114.407402 -318.983313) (xy 114.453257 -319.012785)
			(xy 114.49445 -319.048484) (xy 114.530144 -319.089682) (xy 114.559611 -319.135541) (xy 114.582251 -319.185126)
			(xy 114.597603 -319.237429) (xy 114.605355 -319.291385) (xy 114.605816 -319.31864) (xy 114.605286 -319.347557)
			(xy 114.596564 -319.404729) (xy 114.57931 -319.459929) (xy 114.553921 -319.511891) (xy 114.520978 -319.559425)
			(xy 114.481236 -319.601441) (xy 114.45875 -319.61963) (xy 114.449931 -319.627225) (xy 114.439756 -319.648135)
			(xy 114.439192 -319.659762) (xy 114.439192 -319.739518) (xy 114.439738 -319.751149) (xy 114.449922 -319.772058)
			(xy 114.45875 -319.77965) (xy 114.48122 -319.797857) (xy 114.520954 -319.839875) (xy 114.553893 -319.887407)
			(xy 114.579283 -319.939365) (xy 114.596543 -319.994559) (xy 114.605278 -320.051725) (xy 114.605816 -320.08064)
			(xy 119.41683 -320.08064) (xy 119.417366 -320.051724) (xy 119.426089 -319.994553) (xy 119.443343 -319.939354)
			(xy 119.468732 -319.887392) (xy 119.501673 -319.839857) (xy 119.541411 -319.79784) (xy 119.563896 -319.77965)
			(xy 119.57267 -319.772011) (xy 119.582872 -319.751134) (xy 119.583454 -319.739518) (xy 119.583454 -319.659762)
			(xy 119.582939 -319.648127) (xy 119.572735 -319.627216) (xy 119.563896 -319.61963) (xy 119.541426 -319.601423)
			(xy 119.50169 -319.559407) (xy 119.46875 -319.511875) (xy 119.443359 -319.459917) (xy 119.4261 -319.404722)
			(xy 119.417367 -319.347555) (xy 119.41683 -319.31864) (xy 119.417293 -319.291386) (xy 119.425045 -319.237433)
			(xy 119.440398 -319.185133) (xy 119.463039 -319.135551) (xy 119.492506 -319.089696) (xy 119.5282 -319.048501)
			(xy 119.569394 -319.012807) (xy 119.615249 -318.98334) (xy 119.664831 -318.960699) (xy 119.717132 -318.945346)
			(xy 119.771084 -318.937593) (xy 119.798338 -318.937132) (xy 119.827254 -318.937683) (xy 119.884424 -318.946403)
			(xy 119.939623 -318.963654) (xy 119.991585 -318.989039) (xy 120.03912 -319.021978) (xy 120.081137 -319.061714)
			(xy 120.099328 -319.084198) (xy 120.106933 -319.093008) (xy 120.127835 -319.10319) (xy 120.13946 -319.103756)
			(xy 120.219216 -319.103756) (xy 120.23085 -319.103227) (xy 120.25176 -319.093033) (xy 120.259348 -319.084198)
			(xy 120.276101 -319.063415) (xy 120.314455 -319.026285) (xy 120.357609 -318.994863) (xy 120.404723 -318.969764)
			(xy 120.454875 -318.951478) (xy 120.507086 -318.940361) (xy 120.560338 -318.936631) (xy 120.61359 -318.940361)
			(xy 120.665801 -318.951478) (xy 120.715953 -318.969764) (xy 120.763067 -318.994863) (xy 120.806221 -319.026285)
			(xy 120.844575 -319.063415) (xy 120.861328 -319.084198) (xy 120.868933 -319.093008) (xy 120.889835 -319.10319)
			(xy 120.90146 -319.103756) (xy 120.981216 -319.103756) (xy 120.99285 -319.103227) (xy 121.01376 -319.093033)
			(xy 121.021348 -319.084198) (xy 121.038101 -319.063415) (xy 121.076455 -319.026285) (xy 121.119609 -318.994863)
			(xy 121.166723 -318.969764) (xy 121.216875 -318.951478) (xy 121.269086 -318.940361) (xy 121.322338 -318.936631)
			(xy 121.37559 -318.940361) (xy 121.427801 -318.951478) (xy 121.477953 -318.969764) (xy 121.525067 -318.994863)
			(xy 121.568221 -319.026285) (xy 121.606575 -319.063415) (xy 121.623328 -319.084198) (xy 121.630933 -319.093008)
			(xy 121.651835 -319.10319) (xy 121.66346 -319.103756) (xy 121.743216 -319.103756) (xy 121.75485 -319.103227)
			(xy 121.77576 -319.093033) (xy 121.783348 -319.084198) (xy 121.800101 -319.063415) (xy 121.838455 -319.026285)
			(xy 121.881609 -318.994863) (xy 121.928723 -318.969764) (xy 121.978875 -318.951478) (xy 122.031086 -318.940361)
			(xy 122.084338 -318.936631) (xy 122.13759 -318.940361) (xy 122.189801 -318.951478) (xy 122.239953 -318.969764)
			(xy 122.287067 -318.994863) (xy 122.330221 -319.026285) (xy 122.368575 -319.063415) (xy 122.385328 -319.084198)
			(xy 122.392933 -319.093008) (xy 122.413835 -319.10319) (xy 122.42546 -319.103756) (xy 122.505216 -319.103756)
			(xy 122.51685 -319.103227) (xy 122.53776 -319.093033) (xy 122.545348 -319.084198) (xy 122.562101 -319.063415)
			(xy 122.600455 -319.026285) (xy 122.643609 -318.994863) (xy 122.690723 -318.969764) (xy 122.740875 -318.951478)
			(xy 122.793086 -318.940361) (xy 122.846338 -318.936631) (xy 122.89959 -318.940361) (xy 122.951801 -318.951478)
			(xy 123.001953 -318.969764) (xy 123.049067 -318.994863) (xy 123.092221 -319.026285) (xy 123.130575 -319.063415)
			(xy 123.147328 -319.084198) (xy 123.154933 -319.093008) (xy 123.175835 -319.10319) (xy 123.18746 -319.103756)
			(xy 123.267216 -319.103756) (xy 123.27885 -319.103227) (xy 123.29976 -319.093033) (xy 123.307348 -319.084198)
			(xy 123.324101 -319.063415) (xy 123.362455 -319.026285) (xy 123.405609 -318.994863) (xy 123.452723 -318.969764)
			(xy 123.502875 -318.951478) (xy 123.555086 -318.940361) (xy 123.608338 -318.936631) (xy 123.66159 -318.940361)
			(xy 123.713801 -318.951478) (xy 123.763953 -318.969764) (xy 123.811067 -318.994863) (xy 123.854221 -319.026285)
			(xy 123.892575 -319.063415) (xy 123.909328 -319.084198) (xy 123.916933 -319.093008) (xy 123.937835 -319.10319)
			(xy 123.94946 -319.103756) (xy 124.029216 -319.103756) (xy 124.04085 -319.103227) (xy 124.06176 -319.093033)
			(xy 124.069348 -319.084198) (xy 124.086101 -319.063415) (xy 124.124455 -319.026285) (xy 124.167609 -318.994863)
			(xy 124.214723 -318.969764) (xy 124.264875 -318.951478) (xy 124.317086 -318.940361) (xy 124.370338 -318.936631)
			(xy 124.42359 -318.940361) (xy 124.475801 -318.951478) (xy 124.525953 -318.969764) (xy 124.573067 -318.994863)
			(xy 124.616221 -319.026285) (xy 124.654575 -319.063415) (xy 124.671328 -319.084198) (xy 124.678933 -319.093008)
			(xy 124.699835 -319.10319) (xy 124.71146 -319.103756) (xy 124.791216 -319.103756) (xy 124.80285 -319.103227)
			(xy 124.82376 -319.093033) (xy 124.831348 -319.084198) (xy 124.848101 -319.063415) (xy 124.886455 -319.026285)
			(xy 124.929609 -318.994863) (xy 124.976723 -318.969764) (xy 125.026875 -318.951478) (xy 125.079086 -318.940361)
			(xy 125.132338 -318.936631) (xy 125.18559 -318.940361) (xy 125.237801 -318.951478) (xy 125.287953 -318.969764)
			(xy 125.335067 -318.994863) (xy 125.378221 -319.026285) (xy 125.416575 -319.063415) (xy 125.433328 -319.084198)
			(xy 125.440933 -319.093008) (xy 125.461835 -319.10319) (xy 125.47346 -319.103756) (xy 125.553216 -319.103756)
			(xy 125.56485 -319.103227) (xy 125.58576 -319.093033) (xy 125.593348 -319.084198) (xy 125.610101 -319.063415)
			(xy 125.648455 -319.026285) (xy 125.691609 -318.994863) (xy 125.738723 -318.969764) (xy 125.788875 -318.951478)
			(xy 125.841086 -318.940361) (xy 125.894338 -318.936631) (xy 125.94759 -318.940361) (xy 125.999801 -318.951478)
			(xy 126.049953 -318.969764) (xy 126.097067 -318.994863) (xy 126.140221 -319.026285) (xy 126.178575 -319.063415)
			(xy 126.195328 -319.084198) (xy 126.202933 -319.093008) (xy 126.223835 -319.10319) (xy 126.23546 -319.103756)
			(xy 126.315216 -319.103756) (xy 126.32685 -319.103227) (xy 126.34776 -319.093033) (xy 126.355348 -319.084198)
			(xy 126.372101 -319.063415) (xy 126.410455 -319.026285) (xy 126.453609 -318.994863) (xy 126.500723 -318.969764)
			(xy 126.550875 -318.951478) (xy 126.603086 -318.940361) (xy 126.656338 -318.936631) (xy 126.70959 -318.940361)
			(xy 126.761801 -318.951478) (xy 126.811953 -318.969764) (xy 126.859067 -318.994863) (xy 126.902221 -319.026285)
			(xy 126.940575 -319.063415) (xy 126.957328 -319.084198) (xy 126.964933 -319.093008) (xy 126.985835 -319.10319)
			(xy 126.99746 -319.103756) (xy 127.077216 -319.103756) (xy 127.08885 -319.103227) (xy 127.10976 -319.093033)
			(xy 127.117348 -319.084198) (xy 127.134101 -319.063415) (xy 127.172455 -319.026285) (xy 127.215609 -318.994863)
			(xy 127.262723 -318.969764) (xy 127.312875 -318.951478) (xy 127.365086 -318.940361) (xy 127.418338 -318.936631)
			(xy 127.47159 -318.940361) (xy 127.523801 -318.951478) (xy 127.573953 -318.969764) (xy 127.621067 -318.994863)
			(xy 127.664221 -319.026285) (xy 127.702575 -319.063415) (xy 127.719328 -319.084198) (xy 127.726933 -319.093008)
			(xy 127.747835 -319.10319) (xy 127.75946 -319.103756) (xy 127.839216 -319.103756) (xy 127.85085 -319.103227)
			(xy 127.87176 -319.093033) (xy 127.879348 -319.084198) (xy 127.897568 -319.061739) (xy 127.939582 -319.022002)
			(xy 127.987111 -318.989061) (xy 128.039066 -318.963668) (xy 128.094259 -318.946406) (xy 128.151424 -318.937671)
			(xy 128.180338 -318.937132) (xy 128.21046 -318.937747) (xy 128.269954 -318.947218) (xy 128.327221 -318.965919)
			(xy 128.380839 -318.993385) (xy 128.429475 -319.028934) (xy 128.451102 -319.049908) (xy 128.458506 -319.056742)
			(xy 128.477102 -319.064465) (xy 128.48717 -319.064894) (xy 128.559306 -319.064894) (xy 128.569376 -319.064473)
			(xy 128.587974 -319.056749) (xy 128.595374 -319.049908) (xy 128.616988 -319.028916) (xy 128.66562 -318.993349)
			(xy 128.719239 -318.965871) (xy 128.776512 -318.947166) (xy 128.836013 -318.937698) (xy 128.866138 -318.937132)
			(xy 128.893394 -318.93752) (xy 128.947349 -318.945283) (xy 128.999651 -318.960646) (xy 129.049234 -318.983296)
			(xy 129.095089 -319.012771) (xy 129.136282 -319.048473) (xy 129.171975 -319.089673) (xy 129.201442 -319.135534)
			(xy 129.224082 -319.185122) (xy 129.239434 -319.237427) (xy 129.247186 -319.291384) (xy 129.247646 -319.31864)
			(xy 129.247105 -319.347556) (xy 129.238383 -319.404727) (xy 129.221131 -319.459927) (xy 129.195744 -319.511889)
			(xy 129.162803 -319.559423) (xy 129.123064 -319.60144) (xy 129.10058 -319.61963) (xy 129.091766 -319.62723)
			(xy 129.081587 -319.648136) (xy 129.081022 -319.659762) (xy 129.081022 -319.739518) (xy 129.081557 -319.751151)
			(xy 129.091748 -319.772061) (xy 129.10058 -319.77965) (xy 129.123035 -319.797874) (xy 129.162773 -319.839887)
			(xy 129.195716 -319.887414) (xy 129.221109 -319.939369) (xy 129.238372 -319.994561) (xy 129.247107 -320.051726)
			(xy 129.247646 -320.08064) (xy 129.24716 -320.107891) (xy 129.239399 -320.161836) (xy 129.22404 -320.214129)
			(xy 129.201397 -320.263703) (xy 129.17193 -320.309552) (xy 129.136239 -320.350741) (xy 129.09505 -320.386432)
			(xy 129.049202 -320.415898) (xy 128.999627 -320.438541) (xy 128.947334 -320.453899) (xy 128.893389 -320.46166)
			(xy 128.866138 -320.462148) (xy 128.836016 -320.461554) (xy 128.77652 -320.452079) (xy 128.719252 -320.433373)
			(xy 128.665635 -320.405903) (xy 128.617 -320.370349) (xy 128.595374 -320.349372) (xy 128.58798 -320.342524)
			(xy 128.569376 -320.33481) (xy 128.559306 -320.334386) (xy 128.48717 -320.334386) (xy 128.477096 -320.334773)
			(xy 128.458497 -320.342518) (xy 128.451102 -320.349372) (xy 128.429495 -320.370372) (xy 128.380862 -320.405938)
			(xy 128.327241 -320.433415) (xy 128.269967 -320.452119) (xy 128.210464 -320.461584) (xy 128.180338 -320.462148)
			(xy 128.151421 -320.461622) (xy 128.094249 -320.452898) (xy 128.03905 -320.435642) (xy 127.987088 -320.410252)
			(xy 127.939554 -320.377309) (xy 127.897537 -320.337568) (xy 127.879348 -320.315082) (xy 127.871713 -320.306303)
			(xy 127.850833 -320.296105) (xy 127.839216 -320.295524) (xy 127.75946 -320.295524) (xy 127.747826 -320.296046)
			(xy 127.726916 -320.306246) (xy 127.719328 -320.315082) (xy 127.702575 -320.335865) (xy 127.664221 -320.372995)
			(xy 127.621067 -320.404417) (xy 127.573953 -320.429516) (xy 127.523801 -320.447802) (xy 127.47159 -320.458919)
			(xy 127.418338 -320.462649) (xy 127.365086 -320.458919) (xy 127.312875 -320.447802) (xy 127.262723 -320.429516)
			(xy 127.215609 -320.404417) (xy 127.172455 -320.372995) (xy 127.134101 -320.335865) (xy 127.117348 -320.315082)
			(xy 127.109713 -320.306303) (xy 127.088833 -320.296105) (xy 127.077216 -320.295524) (xy 126.99746 -320.295524)
			(xy 126.985826 -320.296046) (xy 126.964916 -320.306246) (xy 126.957328 -320.315082) (xy 126.940575 -320.335865)
			(xy 126.902221 -320.372995) (xy 126.859067 -320.404417) (xy 126.811953 -320.429516) (xy 126.761801 -320.447802)
			(xy 126.70959 -320.458919) (xy 126.656338 -320.462649) (xy 126.603086 -320.458919) (xy 126.550875 -320.447802)
			(xy 126.500723 -320.429516) (xy 126.453609 -320.404417) (xy 126.410455 -320.372995) (xy 126.372101 -320.335865)
			(xy 126.355348 -320.315082) (xy 126.347713 -320.306303) (xy 126.326833 -320.296105) (xy 126.315216 -320.295524)
			(xy 126.23546 -320.295524) (xy 126.223826 -320.296046) (xy 126.202916 -320.306246) (xy 126.195328 -320.315082)
			(xy 126.178575 -320.335865) (xy 126.140221 -320.372995) (xy 126.097067 -320.404417) (xy 126.049953 -320.429516)
			(xy 125.999801 -320.447802) (xy 125.94759 -320.458919) (xy 125.894338 -320.462649) (xy 125.841086 -320.458919)
			(xy 125.788875 -320.447802) (xy 125.738723 -320.429516) (xy 125.691609 -320.404417) (xy 125.648455 -320.372995)
			(xy 125.610101 -320.335865) (xy 125.593348 -320.315082) (xy 125.585713 -320.306303) (xy 125.564833 -320.296105)
			(xy 125.553216 -320.295524) (xy 125.47346 -320.295524) (xy 125.461826 -320.296046) (xy 125.440916 -320.306246)
			(xy 125.433328 -320.315082) (xy 125.416575 -320.335865) (xy 125.378221 -320.372995) (xy 125.335067 -320.404417)
			(xy 125.287953 -320.429516) (xy 125.237801 -320.447802) (xy 125.18559 -320.458919) (xy 125.132338 -320.462649)
			(xy 125.079086 -320.458919) (xy 125.026875 -320.447802) (xy 124.976723 -320.429516) (xy 124.929609 -320.404417)
			(xy 124.886455 -320.372995) (xy 124.848101 -320.335865) (xy 124.831348 -320.315082) (xy 124.823713 -320.306303)
			(xy 124.802833 -320.296105) (xy 124.791216 -320.295524) (xy 124.71146 -320.295524) (xy 124.699826 -320.296046)
			(xy 124.678916 -320.306246) (xy 124.671328 -320.315082) (xy 124.654575 -320.335865) (xy 124.616221 -320.372995)
			(xy 124.573067 -320.404417) (xy 124.525953 -320.429516) (xy 124.475801 -320.447802) (xy 124.42359 -320.458919)
			(xy 124.370338 -320.462649) (xy 124.317086 -320.458919) (xy 124.264875 -320.447802) (xy 124.214723 -320.429516)
			(xy 124.167609 -320.404417) (xy 124.124455 -320.372995) (xy 124.086101 -320.335865) (xy 124.069348 -320.315082)
			(xy 124.061713 -320.306303) (xy 124.040833 -320.296105) (xy 124.029216 -320.295524) (xy 123.94946 -320.295524)
			(xy 123.937826 -320.296046) (xy 123.916916 -320.306246) (xy 123.909328 -320.315082) (xy 123.892575 -320.335865)
			(xy 123.854221 -320.372995) (xy 123.811067 -320.404417) (xy 123.763953 -320.429516) (xy 123.713801 -320.447802)
			(xy 123.66159 -320.458919) (xy 123.608338 -320.462649) (xy 123.555086 -320.458919) (xy 123.502875 -320.447802)
			(xy 123.452723 -320.429516) (xy 123.405609 -320.404417) (xy 123.362455 -320.372995) (xy 123.324101 -320.335865)
			(xy 123.307348 -320.315082) (xy 123.299713 -320.306303) (xy 123.278833 -320.296105) (xy 123.267216 -320.295524)
			(xy 123.18746 -320.295524) (xy 123.175826 -320.296046) (xy 123.154916 -320.306246) (xy 123.147328 -320.315082)
			(xy 123.130575 -320.335865) (xy 123.092221 -320.372995) (xy 123.049067 -320.404417) (xy 123.001953 -320.429516)
			(xy 122.951801 -320.447802) (xy 122.89959 -320.458919) (xy 122.846338 -320.462649) (xy 122.793086 -320.458919)
			(xy 122.740875 -320.447802) (xy 122.690723 -320.429516) (xy 122.643609 -320.404417) (xy 122.600455 -320.372995)
			(xy 122.562101 -320.335865) (xy 122.545348 -320.315082) (xy 122.537713 -320.306303) (xy 122.516833 -320.296105)
			(xy 122.505216 -320.295524) (xy 122.42546 -320.295524) (xy 122.413826 -320.296046) (xy 122.392916 -320.306246)
			(xy 122.385328 -320.315082) (xy 122.368575 -320.335865) (xy 122.330221 -320.372995) (xy 122.287067 -320.404417)
			(xy 122.239953 -320.429516) (xy 122.189801 -320.447802) (xy 122.13759 -320.458919) (xy 122.084338 -320.462649)
			(xy 122.031086 -320.458919) (xy 121.978875 -320.447802) (xy 121.928723 -320.429516) (xy 121.881609 -320.404417)
			(xy 121.838455 -320.372995) (xy 121.800101 -320.335865) (xy 121.783348 -320.315082) (xy 121.775713 -320.306303)
			(xy 121.754833 -320.296105) (xy 121.743216 -320.295524) (xy 121.66346 -320.295524) (xy 121.651826 -320.296046)
			(xy 121.630916 -320.306246) (xy 121.623328 -320.315082) (xy 121.606575 -320.335865) (xy 121.568221 -320.372995)
			(xy 121.525067 -320.404417) (xy 121.477953 -320.429516) (xy 121.427801 -320.447802) (xy 121.37559 -320.458919)
			(xy 121.322338 -320.462649) (xy 121.269086 -320.458919) (xy 121.216875 -320.447802) (xy 121.166723 -320.429516)
			(xy 121.119609 -320.404417) (xy 121.076455 -320.372995) (xy 121.038101 -320.335865) (xy 121.021348 -320.315082)
			(xy 121.013713 -320.306303) (xy 120.992833 -320.296105) (xy 120.981216 -320.295524) (xy 120.90146 -320.295524)
			(xy 120.889826 -320.296046) (xy 120.868916 -320.306246) (xy 120.861328 -320.315082) (xy 120.844575 -320.335865)
			(xy 120.806221 -320.372995) (xy 120.763067 -320.404417) (xy 120.715953 -320.429516) (xy 120.665801 -320.447802)
			(xy 120.61359 -320.458919) (xy 120.560338 -320.462649) (xy 120.507086 -320.458919) (xy 120.454875 -320.447802)
			(xy 120.404723 -320.429516) (xy 120.357609 -320.404417) (xy 120.314455 -320.372995) (xy 120.276101 -320.335865)
			(xy 120.259348 -320.315082) (xy 120.251713 -320.306303) (xy 120.230833 -320.296105) (xy 120.219216 -320.295524)
			(xy 120.13946 -320.295524) (xy 120.127826 -320.296046) (xy 120.106916 -320.306246) (xy 120.099328 -320.315082)
			(xy 120.081117 -320.337548) (xy 120.039102 -320.377285) (xy 119.991571 -320.410227) (xy 119.939614 -320.435618)
			(xy 119.88442 -320.452878) (xy 119.827253 -320.461611) (xy 119.798338 -320.462148) (xy 119.77109 -320.461587)
			(xy 119.717147 -320.453836) (xy 119.664856 -320.438488) (xy 119.615281 -320.415854) (xy 119.569433 -320.386396)
			(xy 119.528243 -320.350712) (xy 119.492551 -320.30953) (xy 119.463083 -320.263687) (xy 119.440439 -320.214117)
			(xy 119.42508 -320.16183) (xy 119.417319 -320.107888) (xy 119.41683 -320.08064) (xy 114.605816 -320.08064)
			(xy 114.605359 -320.107892) (xy 114.597598 -320.16184) (xy 114.582238 -320.214135) (xy 114.559593 -320.263712)
			(xy 114.530123 -320.309562) (xy 114.494429 -320.350751) (xy 114.453236 -320.386442) (xy 114.407384 -320.415908)
			(xy 114.357805 -320.438549) (xy 114.305509 -320.453904) (xy 114.25156 -320.461662) (xy 114.224308 -320.462148)
			(xy 114.19539 -320.461644) (xy 114.138218 -320.452914) (xy 114.083018 -320.435655) (xy 114.031056 -320.410261)
			(xy 113.983522 -320.377314) (xy 113.941507 -320.337569) (xy 113.923318 -320.315082) (xy 113.915696 -320.30629)
			(xy 113.894807 -320.296099) (xy 113.883186 -320.295524) (xy 113.80343 -320.295524) (xy 113.791801 -320.296086)
			(xy 113.77089 -320.306258) (xy 113.763298 -320.315082) (xy 113.746545 -320.335865) (xy 113.708191 -320.372995)
			(xy 113.665037 -320.404417) (xy 113.617923 -320.429516) (xy 113.567771 -320.447802) (xy 113.51556 -320.458919)
			(xy 113.462308 -320.462649) (xy 113.409056 -320.458919) (xy 113.356845 -320.447802) (xy 113.306693 -320.429516)
			(xy 113.259579 -320.404417) (xy 113.216425 -320.372995) (xy 113.178071 -320.335865) (xy 113.161318 -320.315082)
			(xy 113.153696 -320.30629) (xy 113.132807 -320.296099) (xy 113.121186 -320.295524) (xy 113.04143 -320.295524)
			(xy 113.029801 -320.296086) (xy 113.00889 -320.306258) (xy 113.001298 -320.315082) (xy 112.984545 -320.335865)
			(xy 112.946191 -320.372995) (xy 112.903037 -320.404417) (xy 112.855923 -320.429516) (xy 112.805771 -320.447802)
			(xy 112.75356 -320.458919) (xy 112.700308 -320.462649) (xy 112.647056 -320.458919) (xy 112.594845 -320.447802)
			(xy 112.544693 -320.429516) (xy 112.497579 -320.404417) (xy 112.454425 -320.372995) (xy 112.416071 -320.335865)
			(xy 112.399318 -320.315082) (xy 112.391696 -320.30629) (xy 112.370807 -320.296099) (xy 112.359186 -320.295524)
			(xy 112.27943 -320.295524) (xy 112.267801 -320.296086) (xy 112.24689 -320.306258) (xy 112.239298 -320.315082)
			(xy 112.222545 -320.335865) (xy 112.184191 -320.372995) (xy 112.141037 -320.404417) (xy 112.093923 -320.429516)
			(xy 112.043771 -320.447802) (xy 111.99156 -320.458919) (xy 111.938308 -320.462649) (xy 111.885056 -320.458919)
			(xy 111.832845 -320.447802) (xy 111.782693 -320.429516) (xy 111.735579 -320.404417) (xy 111.692425 -320.372995)
			(xy 111.654071 -320.335865) (xy 111.637318 -320.315082) (xy 111.629696 -320.30629) (xy 111.608807 -320.296099)
			(xy 111.597186 -320.295524) (xy 111.51743 -320.295524) (xy 111.505801 -320.296086) (xy 111.48489 -320.306258)
			(xy 111.477298 -320.315082) (xy 111.460545 -320.335865) (xy 111.422191 -320.372995) (xy 111.379037 -320.404417)
			(xy 111.331923 -320.429516) (xy 111.281771 -320.447802) (xy 111.22956 -320.458919) (xy 111.176308 -320.462649)
			(xy 111.123056 -320.458919) (xy 111.070845 -320.447802) (xy 111.020693 -320.429516) (xy 110.973579 -320.404417)
			(xy 110.930425 -320.372995) (xy 110.892071 -320.335865) (xy 110.875318 -320.315082) (xy 110.867696 -320.30629)
			(xy 110.846807 -320.296099) (xy 110.835186 -320.295524) (xy 110.75543 -320.295524) (xy 110.743801 -320.296086)
			(xy 110.72289 -320.306258) (xy 110.715298 -320.315082) (xy 110.698545 -320.335865) (xy 110.660191 -320.372995)
			(xy 110.617037 -320.404417) (xy 110.569923 -320.429516) (xy 110.519771 -320.447802) (xy 110.46756 -320.458919)
			(xy 110.414308 -320.462649) (xy 110.361056 -320.458919) (xy 110.308845 -320.447802) (xy 110.258693 -320.429516)
			(xy 110.211579 -320.404417) (xy 110.168425 -320.372995) (xy 110.130071 -320.335865) (xy 110.113318 -320.315082)
			(xy 110.105696 -320.30629) (xy 110.084807 -320.296099) (xy 110.073186 -320.295524) (xy 109.99343 -320.295524)
			(xy 109.981801 -320.296086) (xy 109.96089 -320.306258) (xy 109.953298 -320.315082) (xy 109.936545 -320.335865)
			(xy 109.898191 -320.372995) (xy 109.855037 -320.404417) (xy 109.807923 -320.429516) (xy 109.757771 -320.447802)
			(xy 109.70556 -320.458919) (xy 109.652308 -320.462649) (xy 109.599056 -320.458919) (xy 109.546845 -320.447802)
			(xy 109.496693 -320.429516) (xy 109.449579 -320.404417) (xy 109.406425 -320.372995) (xy 109.368071 -320.335865)
			(xy 109.351318 -320.315082) (xy 109.343696 -320.30629) (xy 109.322807 -320.296099) (xy 109.311186 -320.295524)
			(xy 109.23143 -320.295524) (xy 109.219801 -320.296086) (xy 109.19889 -320.306258) (xy 109.191298 -320.315082)
			(xy 109.174545 -320.335865) (xy 109.136191 -320.372995) (xy 109.093037 -320.404417) (xy 109.045923 -320.429516)
			(xy 108.995771 -320.447802) (xy 108.94356 -320.458919) (xy 108.890308 -320.462649) (xy 108.837056 -320.458919)
			(xy 108.784845 -320.447802) (xy 108.734693 -320.429516) (xy 108.687579 -320.404417) (xy 108.644425 -320.372995)
			(xy 108.606071 -320.335865) (xy 108.589318 -320.315082) (xy 108.581696 -320.30629) (xy 108.560807 -320.296099)
			(xy 108.549186 -320.295524) (xy 108.46943 -320.295524) (xy 108.457801 -320.296086) (xy 108.43689 -320.306258)
			(xy 108.429298 -320.315082) (xy 108.412545 -320.335865) (xy 108.374191 -320.372995) (xy 108.331037 -320.404417)
			(xy 108.283923 -320.429516) (xy 108.233771 -320.447802) (xy 108.18156 -320.458919) (xy 108.128308 -320.462649)
			(xy 108.075056 -320.458919) (xy 108.022845 -320.447802) (xy 107.972693 -320.429516) (xy 107.925579 -320.404417)
			(xy 107.882425 -320.372995) (xy 107.844071 -320.335865) (xy 107.827318 -320.315082) (xy 107.819696 -320.30629)
			(xy 107.798807 -320.296099) (xy 107.787186 -320.295524) (xy 107.70743 -320.295524) (xy 107.695801 -320.296086)
			(xy 107.67489 -320.306258) (xy 107.667298 -320.315082) (xy 107.650545 -320.335865) (xy 107.612191 -320.372995)
			(xy 107.569037 -320.404417) (xy 107.521923 -320.429516) (xy 107.471771 -320.447802) (xy 107.41956 -320.458919)
			(xy 107.366308 -320.462649) (xy 107.313056 -320.458919) (xy 107.260845 -320.447802) (xy 107.210693 -320.429516)
			(xy 107.163579 -320.404417) (xy 107.120425 -320.372995) (xy 107.082071 -320.335865) (xy 107.065318 -320.315082)
			(xy 107.057696 -320.30629) (xy 107.036807 -320.296099) (xy 107.025186 -320.295524) (xy 106.94543 -320.295524)
			(xy 106.933801 -320.296086) (xy 106.91289 -320.306258) (xy 106.905298 -320.315082) (xy 106.887104 -320.337563)
			(xy 106.845085 -320.377299) (xy 106.797551 -320.410239) (xy 106.74559 -320.435628) (xy 106.690393 -320.452884)
			(xy 106.633224 -320.461613) (xy 106.604308 -320.462148) (xy 106.577059 -320.461615) (xy 106.523115 -320.453861)
			(xy 106.470823 -320.438508) (xy 106.421249 -320.415871) (xy 106.3754 -320.386409) (xy 106.334211 -320.350723)
			(xy 106.298519 -320.309538) (xy 106.269052 -320.263693) (xy 106.246408 -320.214122) (xy 106.23105 -320.161832)
			(xy 106.223289 -320.107889) (xy 106.2228 -320.08064) (xy 102.236524 -320.08064) (xy 102.236524 -321.291712)
			(xy 102.23695 -321.301781) (xy 102.24467 -321.32038) (xy 102.25151 -321.32778) (xy 103.35641 -322.43268)
			(xy 103.363254 -322.440078) (xy 103.370973 -322.458678) (xy 103.371396 -322.468748) (xy 103.371396 -324.944232)
			(xy 103.372412 -324.95363) (xy 103.372412 -324.954138) (xy 103.374123 -324.961293) (xy 103.380967 -324.974309)
			(xy 103.385874 -324.979792) (xy 104.318054 -325.911972) (xy 104.323487 -325.916946) (xy 104.336529 -325.923781)
			(xy 104.343708 -325.925434) (xy 104.344216 -325.925434) (xy 104.353614 -325.92645) (xy 113.905284 -325.92645)
		)
		(stroke
			(width 0)
			(type solid)
		)
		(fill yes)
		(layer "In11.Cu")
		(net "GND")
	)
	(gr_poly
		(pts
			(xy 221.10319 -252.789944) (xy 221.111826 -252.7896) (xy 221.12811 -252.783842) (xy 221.141541 -252.772983)
			(xy 221.14637 -252.765814) (xy 221.191582 -252.692408) (xy 221.196662 -252.681994) (xy 221.197768 -252.678473)
			(xy 221.19905 -252.671204) (xy 221.199202 -252.667516) (xy 221.19971 -252.654562) (xy 221.194122 -252.642878)
			(xy 221.193868 -252.64237) (xy 221.181028 -252.615629) (xy 221.162848 -252.559168) (xy 221.153599 -252.500577)
			(xy 221.152974 -252.47092) (xy 221.153435 -252.443666) (xy 221.16119 -252.389712) (xy 221.176544 -252.33741)
			(xy 221.199185 -252.287826) (xy 221.228653 -252.241969) (xy 221.264346 -252.200773) (xy 221.305539 -252.165075)
			(xy 221.351393 -252.135604) (xy 221.400975 -252.112957) (xy 221.453274 -252.097598) (xy 221.507228 -252.089838)
			(xy 221.534482 -252.089412) (xy 221.560352 -252.089848) (xy 221.611618 -252.096849) (xy 221.661467 -252.110711)
			(xy 221.708987 -252.13118) (xy 221.753306 -252.157881) (xy 221.793612 -252.190324) (xy 221.829166 -252.227914)
			(xy 221.844616 -252.24867) (xy 221.848466 -252.253771) (xy 221.858238 -252.262002) (xy 221.86392 -252.264926)
			(xy 221.869762 -252.26772) (xy 221.882208 -252.27026) (xy 221.974156 -252.264926) (xy 221.98262 -252.264148)
			(xy 221.998347 -252.257727) (xy 222.011107 -252.246512) (xy 222.015558 -252.239272) (xy 222.015812 -252.238764)
			(xy 222.015812 -252.23851) (xy 222.030412 -252.213472) (xy 222.06599 -252.16772) (xy 222.108069 -252.127864)
			(xy 222.155683 -252.094818) (xy 222.207739 -252.06934) (xy 222.263046 -252.052013) (xy 222.320335 -252.043234)
			(xy 222.349314 -252.042676) (xy 222.37705 -252.043181) (xy 222.431936 -252.051227) (xy 222.48508 -252.067133)
			(xy 222.535362 -252.090563) (xy 222.581722 -252.121025) (xy 222.623186 -252.157876) (xy 222.658878 -252.200341)
			(xy 222.688048 -252.247524) (xy 222.710082 -252.298434) (xy 222.724514 -252.351996) (xy 222.728282 -252.37948)
			(xy 222.73006 -252.39472) (xy 222.731076 -252.424184) (xy 222.73056 -252.451709) (xy 222.722585 -252.50618)
			(xy 222.706872 -252.558941) (xy 222.683746 -252.608899) (xy 222.6691 -252.63221) (xy 222.668592 -252.632972)
			(xy 222.667068 -252.635512) (xy 222.66315 -252.643176) (xy 222.660168 -252.660118) (xy 222.662963 -252.677091)
			(xy 222.666814 -252.684788) (xy 222.709232 -252.763274) (xy 222.713663 -252.770736) (xy 222.726517 -252.782379)
			(xy 222.742505 -252.789099) (xy 222.751142 -252.789944) (xy 222.823532 -252.789944) (xy 222.835717 -252.789179)
			(xy 222.857335 -252.777909) (xy 222.864934 -252.768354) (xy 222.865696 -252.767338) (xy 222.912432 -252.693932)
			(xy 222.917258 -252.684026) (xy 222.919037 -252.678626) (xy 222.920438 -252.667347) (xy 222.920052 -252.661674)
			(xy 222.919036 -252.652784) (xy 222.91548 -252.64491) (xy 222.903797 -252.619195) (xy 222.887294 -252.565179)
			(xy 222.878938 -252.50932) (xy 222.878396 -252.48108) (xy 222.878883 -252.45383) (xy 222.886642 -252.399884)
			(xy 222.901999 -252.347592) (xy 222.924641 -252.298018) (xy 222.954108 -252.25217) (xy 222.9898 -252.210983)
			(xy 223.030989 -252.175294) (xy 223.076839 -252.14583) (xy 223.126415 -252.12319) (xy 223.178708 -252.107837)
			(xy 223.232654 -252.100081) (xy 223.259904 -252.099572) (xy 223.286819 -252.100028) (xy 223.340115 -252.107585)
			(xy 223.391818 -252.122561) (xy 223.440902 -252.14466) (xy 223.48639 -252.173442) (xy 223.527378 -252.208335)
			(xy 223.563052 -252.248645) (xy 223.592703 -252.293572) (xy 223.61574 -252.342222) (xy 223.62414 -252.367796)
			(xy 223.626172 -252.373638) (xy 223.62922 -252.378972) (xy 223.637094 -252.388878) (xy 223.67494 -252.426724)
			(xy 223.68239 -252.433608) (xy 223.701125 -252.441342) (xy 223.711262 -252.44171) (xy 223.721168 -252.440694)
			(xy 223.79178 -252.426216) (xy 223.803308 -252.423233) (xy 223.822006 -252.408536) (xy 223.827594 -252.398022)
			(xy 223.838588 -252.371715) (xy 223.867237 -252.322423) (xy 223.902892 -252.277934) (xy 223.944762 -252.239238)
			(xy 223.991918 -252.207193) (xy 224.043311 -252.182511) (xy 224.097802 -252.165739) (xy 224.15418 -252.15725)
			(xy 224.182686 -252.156722) (xy 224.209939 -252.157184) (xy 224.26389 -252.16494) (xy 224.316187 -252.180295)
			(xy 224.365767 -252.202937) (xy 224.41162 -252.232405) (xy 224.452812 -252.268099) (xy 224.488504 -252.309293)
			(xy 224.517971 -252.355147) (xy 224.540611 -252.404728) (xy 224.555963 -252.457026) (xy 224.563717 -252.510977)
			(xy 224.564194 -252.53823) (xy 224.564194 -252.538992) (xy 224.563565 -252.568966) (xy 224.554126 -252.628167)
			(xy 224.545398 -252.656848) (xy 224.543874 -252.661166) (xy 224.543366 -252.665992) (xy 224.54265 -252.673264)
			(xy 224.544854 -252.687702) (xy 224.547684 -252.69444) (xy 224.55251 -252.702568) (xy 224.600516 -252.768862)
			(xy 224.605342 -252.77445) (xy 224.60585 -252.774958) (xy 224.612588 -252.781193) (xy 224.629244 -252.788882)
			(xy 224.638362 -252.789944) (xy 225.178112 -252.789944) (xy 225.186929 -252.78908) (xy 225.203176 -252.782042)
			(xy 225.209862 -252.776228) (xy 225.21164 -252.77445) (xy 225.26371 -252.714506) (xy 225.267082 -252.710376)
			(xy 225.272211 -252.701031) (xy 225.27387 -252.695964) (xy 225.277172 -252.68555) (xy 225.275648 -252.674628)
			(xy 225.273988 -252.661802) (xy 225.27221 -252.635998) (xy 225.272092 -252.623066) (xy 225.27258 -252.595816)
			(xy 225.280341 -252.541872) (xy 225.295699 -252.489582) (xy 225.318342 -252.440009) (xy 225.347809 -252.394163)
			(xy 225.3835 -252.352976) (xy 225.42469 -252.317289) (xy 225.470539 -252.287825) (xy 225.520114 -252.265187)
			(xy 225.572406 -252.249833) (xy 225.62635 -252.242078) (xy 225.6536 -252.241558) (xy 225.679674 -252.242003)
			(xy 225.731335 -252.249103) (xy 225.781549 -252.263172) (xy 225.829379 -252.283946) (xy 225.873935 -252.31104)
			(xy 225.914387 -252.343949) (xy 225.932492 -252.362716) (xy 225.939786 -252.369825) (xy 225.958394 -252.378068)
			(xy 225.96856 -252.378718) (xy 225.973132 -252.378718) (xy 226.051618 -252.37313) (xy 226.062787 -252.371761)
			(xy 226.082425 -252.360827) (xy 226.089464 -252.352048) (xy 226.089464 -252.351794) (xy 226.104874 -252.330782)
			(xy 226.140477 -252.292736) (xy 226.180924 -252.259885) (xy 226.225463 -252.232841) (xy 226.273266 -252.212107)
			(xy 226.323446 -252.198067) (xy 226.375069 -252.190983) (xy 226.401122 -252.190504) (xy 226.429608 -252.191034)
			(xy 226.485946 -252.19951) (xy 226.540397 -252.21627) (xy 226.591751 -252.240941) (xy 226.638864 -252.272975)
			(xy 226.680689 -252.311659) (xy 226.716297 -252.356133) (xy 226.731068 -252.380496) (xy 226.734624 -252.386592)
			(xy 226.744022 -252.395736) (xy 226.749864 -252.399292) (xy 226.75582 -252.402357) (xy 226.76882 -252.405565)
			(xy 226.775518 -252.405642) (xy 226.864418 -252.404626) (xy 226.868736 -252.404372) (xy 226.874431 -252.403666)
			(xy 226.885332 -252.400086) (xy 226.890326 -252.39726) (xy 226.89566 -252.393958) (xy 226.904804 -252.384306)
			(xy 226.90836 -252.377956) (xy 226.92277 -252.352464) (xy 226.958198 -252.30584) (xy 227.00034 -252.265183)
			(xy 227.048205 -252.231452) (xy 227.100667 -252.205438) (xy 227.15649 -252.187756) (xy 227.214361 -252.17882)
			(xy 227.24364 -252.178312) (xy 227.271174 -252.178798) (xy 227.325669 -252.186719) (xy 227.37846 -252.202392)
			(xy 227.428449 -252.22549) (xy 227.474599 -252.255534) (xy 227.515951 -252.2919) (xy 227.551646 -252.333832)
			(xy 227.566728 -252.356874) (xy 227.570234 -252.362131) (xy 227.579364 -252.37086) (xy 227.584762 -252.374146)
			(xy 227.589842 -252.377194) (xy 227.595684 -252.378718) (xy 227.60813 -252.38075) (xy 227.69322 -252.382782)
			(xy 227.699346 -252.38274) (xy 227.711292 -252.380042) (xy 227.716842 -252.377448) (xy 227.72243 -252.374908)
			(xy 227.732082 -252.366526) (xy 227.735638 -252.361192) (xy 227.751012 -252.340102) (xy 227.786599 -252.301925)
			(xy 227.827059 -252.268956) (xy 227.871636 -252.241812) (xy 227.919497 -252.221) (xy 227.96975 -252.206907)
			(xy 228.021454 -252.199798) (xy 228.04755 -252.199394) (xy 228.074805 -252.199854) (xy 228.128761 -252.207605)
			(xy 228.181065 -252.222957) (xy 228.230651 -252.245597) (xy 228.276511 -252.275063) (xy 228.317709 -252.310757)
			(xy 228.353408 -252.351951) (xy 228.38288 -252.397806) (xy 228.405526 -252.44739) (xy 228.420885 -252.499692)
			(xy 228.428643 -252.553647) (xy 228.429058 -252.580902) (xy 228.428728 -252.602297) (xy 228.423888 -252.644815)
			(xy 228.419406 -252.665738) (xy 228.416866 -252.677168) (xy 228.419406 -252.68809) (xy 228.420828 -252.693678)
			(xy 228.425835 -252.704063) (xy 228.429312 -252.708664) (xy 228.478842 -252.770894) (xy 228.485446 -252.777752)
			(xy 228.492529 -252.78335) (xy 228.509446 -252.789616) (xy 228.518466 -252.789944) (xy 228.610668 -252.789944)
			(xy 228.620683 -252.789462) (xy 228.639193 -252.78181) (xy 228.653367 -252.767657) (xy 228.661047 -252.749158)
			(xy 228.661468 -252.739144) (xy 228.661468 -251.882148) (xy 228.661958 -251.856063) (xy 228.670132 -251.804536)
			(xy 228.686272 -251.754924) (xy 228.709977 -251.708449) (xy 228.740666 -251.666259) (xy 228.75875 -251.647452)
			(xy 229.223316 -251.182886) (xy 229.242096 -251.164772) (xy 229.284293 -251.134085) (xy 229.330774 -251.110383)
			(xy 229.380392 -251.094249) (xy 229.431924 -251.086083) (xy 229.458012 -251.085604) (xy 232.503472 -251.085604)
			(xy 232.52956 -251.086088) (xy 232.581095 -251.09425) (xy 232.630717 -251.110378) (xy 232.677203 -251.134073)
			(xy 232.719407 -251.164752) (xy 232.738168 -251.182886) (xy 233.388232 -251.83295) (xy 240.066072 -251.83295)
			(xy 240.066072 -251.77845) (xy 240.073828 -251.724504) (xy 240.089181 -251.672211) (xy 240.11182 -251.622635)
			(xy 240.141284 -251.576786) (xy 240.176973 -251.535595) (xy 240.21816 -251.499903) (xy 240.264007 -251.470436)
			(xy 240.313581 -251.447792) (xy 240.365873 -251.432434) (xy 240.419818 -251.424674) (xy 240.447068 -251.424186)
			(xy 240.474091 -251.424656) (xy 240.527597 -251.432275) (xy 240.579494 -251.447366) (xy 240.628743 -251.469625)
			(xy 240.67436 -251.498609) (xy 240.715433 -251.533737) (xy 240.75114 -251.574308) (xy 240.766346 -251.596652)
			(xy 240.77408 -251.607639) (xy 240.794151 -251.625488) (xy 240.818181 -251.637486) (xy 240.844507 -251.642807)
			(xy 240.87131 -251.64108) (xy 240.896737 -251.632426) (xy 240.919028 -251.617444) (xy 240.928144 -251.607574)
			(xy 240.946328 -251.587263) (xy 240.987496 -251.551526) (xy 241.033337 -251.522021) (xy 241.082914 -251.49935)
			(xy 241.135217 -251.483975) (xy 241.189176 -251.476211) (xy 241.216434 -251.475748) (xy 241.24368 -251.476324)
			(xy 241.297618 -251.484084) (xy 241.349903 -251.49944) (xy 241.39947 -251.522081) (xy 241.445311 -251.551545)
			(xy 241.486492 -251.587232) (xy 241.522176 -251.628416) (xy 241.551636 -251.67426) (xy 241.574272 -251.723829)
			(xy 241.589623 -251.776115) (xy 241.597378 -251.830053) (xy 241.597378 -251.857256) (xy 242.866416 -251.857256)
			(xy 242.870487 -251.801634) (xy 242.882613 -251.747197) (xy 242.902536 -251.695106) (xy 242.929832 -251.646471)
			(xy 242.963918 -251.602328) (xy 243.004067 -251.563619) (xy 243.049425 -251.531168) (xy 243.099025 -251.505667)
			(xy 243.151809 -251.48766) (xy 243.206652 -251.47753) (xy 243.262386 -251.475493) (xy 243.317823 -251.481593)
			(xy 243.37178 -251.495699) (xy 243.423109 -251.517511) (xy 243.470715 -251.546565) (xy 243.513583 -251.58224)
			(xy 243.5508 -251.623777) (xy 243.581573 -251.67029) (xy 243.605245 -251.720787) (xy 243.621313 -251.774194)
			(xy 243.629433 -251.82937) (xy 243.629942 -251.857256) (xy 243.629433 -251.885142) (xy 243.621313 -251.940318)
			(xy 243.605245 -251.993725) (xy 243.581573 -252.044222) (xy 243.5508 -252.090735) (xy 243.513583 -252.132272)
			(xy 243.470715 -252.167947) (xy 243.423109 -252.197001) (xy 243.37178 -252.218813) (xy 243.317823 -252.232919)
			(xy 243.262386 -252.239019) (xy 243.206652 -252.236982) (xy 243.151809 -252.226852) (xy 243.099025 -252.208845)
			(xy 243.049425 -252.183344) (xy 243.004067 -252.150893) (xy 242.963918 -252.112184) (xy 242.929832 -252.068041)
			(xy 242.902536 -252.019406) (xy 242.882613 -251.967315) (xy 242.870487 -251.912878) (xy 242.866416 -251.857256)
			(xy 241.597378 -251.857256) (xy 241.597378 -251.884547) (xy 241.589623 -251.938485) (xy 241.574272 -251.990771)
			(xy 241.551636 -252.04034) (xy 241.522176 -252.086184) (xy 241.486492 -252.127368) (xy 241.445311 -252.163055)
			(xy 241.39947 -252.192519) (xy 241.349903 -252.21516) (xy 241.297618 -252.230516) (xy 241.24368 -252.238276)
			(xy 241.216434 -252.238764) (xy 241.189412 -252.23827) (xy 241.135908 -252.230652) (xy 241.084013 -252.215564)
			(xy 241.034764 -252.193308) (xy 240.989147 -252.164329) (xy 240.948073 -252.129205) (xy 240.912364 -252.088639)
			(xy 240.897156 -252.066298) (xy 240.88942 -252.055313) (xy 240.869347 -252.037473) (xy 240.845318 -252.02548)
			(xy 240.818994 -252.020162) (xy 240.792194 -252.021887) (xy 240.766769 -252.030536) (xy 240.744476 -252.045511)
			(xy 240.735358 -252.055376) (xy 240.717162 -252.075676) (xy 240.675998 -252.111416) (xy 240.63016 -252.140924)
			(xy 240.580585 -252.163597) (xy 240.528284 -252.178974) (xy 240.474325 -252.186739) (xy 240.447068 -252.187202)
			(xy 240.419818 -252.186726) (xy 240.365873 -252.178966) (xy 240.313581 -252.163608) (xy 240.264007 -252.140964)
			(xy 240.21816 -252.111497) (xy 240.176973 -252.075805) (xy 240.141284 -252.034614) (xy 240.11182 -251.988765)
			(xy 240.089181 -251.939189) (xy 240.073828 -251.886896) (xy 240.066072 -251.83295) (xy 233.388232 -251.83295)
			(xy 234.33024 -252.774958) (xy 234.337639 -252.781803) (xy 234.356237 -252.789529) (xy 234.366308 -252.789944)
			(xy 234.474258 -252.789944) (xy 234.485688 -252.787404) (xy 234.494356 -252.78514) (xy 234.509459 -252.775524)
			(xy 234.515152 -252.768608) (xy 234.56265 -252.70587) (xy 234.568411 -252.697582) (xy 234.573521 -252.678071)
			(xy 234.572556 -252.668024) (xy 234.57154 -252.660912) (xy 234.570778 -252.657864) (xy 234.564559 -252.633505)
			(xy 234.557812 -252.583686) (xy 234.557316 -252.55855) (xy 234.557316 -252.554486) (xy 234.558009 -252.527377)
			(xy 234.566116 -252.473759) (xy 234.581733 -252.421829) (xy 234.604546 -252.372634) (xy 234.634095 -252.327164)
			(xy 234.669785 -252.286337) (xy 234.710896 -252.250975) (xy 234.7566 -252.22179) (xy 234.805976 -252.19937)
			(xy 234.858029 -252.184168) (xy 234.91171 -252.17649) (xy 234.965938 -252.17649) (xy 235.019619 -252.184168)
			(xy 235.071672 -252.19937) (xy 235.121048 -252.22179) (xy 235.166752 -252.250975) (xy 235.207863 -252.286337)
			(xy 235.243553 -252.327164) (xy 235.273102 -252.372634) (xy 235.295915 -252.421829) (xy 235.311532 -252.473759)
			(xy 235.319639 -252.527377) (xy 235.320332 -252.554486) (xy 235.320332 -252.558296) (xy 235.319881 -252.583498)
			(xy 235.313132 -252.633449) (xy 235.30687 -252.657864) (xy 235.306108 -252.660912) (xy 235.305092 -252.668024)
			(xy 235.304287 -252.675931) (xy 235.307014 -252.691579) (xy 235.310426 -252.698758) (xy 235.310426 -252.699266)
			(xy 235.314744 -252.706124) (xy 235.363004 -252.769624) (xy 235.367014 -252.774621) (xy 235.377045 -252.782587)
			(xy 235.382816 -252.785372) (xy 235.392976 -252.789944) (xy 245.137686 -252.789944) (xy 245.145814 -252.789182)
			(xy 245.146322 -252.789182) (xy 245.153841 -252.787582) (xy 245.167529 -252.780606) (xy 245.173246 -252.775466)
			(xy 245.738142 -252.21057) (xy 245.742968 -252.204982) (xy 245.747635 -252.198241) (xy 245.752815 -252.182695)
			(xy 245.753128 -252.174502) (xy 245.753128 -249.785886) (xy 245.752626 -249.775487) (xy 245.744363 -249.756401)
			(xy 245.729201 -249.742164) (xy 245.7196 -249.738134) (xy 245.630192 -249.705622) (xy 245.622732 -249.703233)
			(xy 245.607089 -249.702586) (xy 245.599458 -249.704352) (xy 245.592066 -249.706622) (xy 245.579005 -249.714887)
			(xy 245.573804 -249.720608) (xy 245.57355 -249.720862) (xy 245.55531 -249.741928) (xy 245.513766 -249.779063)
			(xy 245.467265 -249.809763) (xy 245.416794 -249.833375) (xy 245.363426 -249.849398) (xy 245.308295 -249.857491)
			(xy 245.280434 -249.858022) (xy 245.253179 -249.857561) (xy 245.199222 -249.849808) (xy 245.146918 -249.834454)
			(xy 245.097332 -249.811813) (xy 245.051473 -249.782345) (xy 245.010274 -249.74665) (xy 244.974576 -249.705455)
			(xy 244.945103 -249.659598) (xy 244.922457 -249.610014) (xy 244.907099 -249.557711) (xy 244.899341 -249.503755)
			(xy 244.899341 -249.449245) (xy 244.907099 -249.395289) (xy 244.922457 -249.342986) (xy 244.945103 -249.293402)
			(xy 244.974576 -249.247545) (xy 245.010274 -249.20635) (xy 245.051473 -249.170655) (xy 245.097332 -249.141187)
			(xy 245.146918 -249.118546) (xy 245.199222 -249.103192) (xy 245.253179 -249.095439) (xy 245.280434 -249.095006)
			(xy 245.308295 -249.095515) (xy 245.363423 -249.103619) (xy 245.416788 -249.119652) (xy 245.467256 -249.143271)
			(xy 245.513754 -249.173975) (xy 245.555295 -249.211113) (xy 245.57355 -249.232166) (xy 245.573804 -249.23242)
			(xy 245.578991 -249.23816) (xy 245.592052 -249.246437) (xy 245.599458 -249.248676) (xy 245.607087 -249.250486)
			(xy 245.622744 -249.249853) (xy 245.630192 -249.247406) (xy 245.7196 -249.214894) (xy 245.721632 -249.214132)
			(xy 245.730523 -249.209997) (xy 245.744496 -249.196269) (xy 245.74881 -249.187462) (xy 245.750813 -249.182622)
			(xy 245.752992 -249.172378) (xy 245.753128 -249.167142) (xy 245.753128 -245.055136) (xy 245.75299 -245.050246)
			(xy 245.751071 -245.040654) (xy 245.749318 -245.036086) (xy 245.745508 -245.026434) (xy 245.738142 -245.019322)
			(xy 244.45468 -243.73586) (xy 244.449092 -243.731034) (xy 244.442351 -243.726366) (xy 244.426806 -243.721183)
			(xy 244.418612 -243.720874) (xy 221.13113 -243.720874) (xy 221.121847 -243.720477) (xy 221.104509 -243.71384)
			(xy 221.097348 -243.70792) (xy 221.090236 -243.70157) (xy 221.0816 -243.698268) (xy 221.079822 -243.697506)
			(xy 221.075874 -243.696274) (xy 221.067702 -243.694998) (xy 221.063566 -243.694966) (xy 209.418936 -243.694966)
			(xy 209.408872 -243.69453) (xy 209.390287 -243.686796) (xy 209.382868 -243.67998) (xy 208.596738 -242.89385)
			(xy 208.589895 -242.886451) (xy 208.582173 -242.867852) (xy 208.581752 -242.857782) (xy 208.581752 -238.976154)
			(xy 208.581273 -238.96606) (xy 208.573423 -238.947457) (xy 208.566512 -238.940086) (xy 208.562643 -238.936417)
			(xy 208.55368 -238.930644) (xy 208.548732 -238.928656) (xy 208.459578 -238.895382) (xy 208.459324 -238.895382)
			(xy 208.451948 -238.892925) (xy 208.436429 -238.89215) (xy 208.428844 -238.893858) (xy 208.42859 -238.893858)
			(xy 208.421378 -238.896083) (xy 208.408594 -238.90409) (xy 208.403444 -238.909606) (xy 208.40319 -238.90986)
			(xy 208.384998 -238.930288) (xy 208.343767 -238.966233) (xy 208.297819 -238.995913) (xy 208.248099 -239.018718)
			(xy 208.19563 -239.034179) (xy 208.141488 -239.041977) (xy 208.114138 -239.042448) (xy 208.113884 -239.042448)
			(xy 208.085513 -239.04193) (xy 208.029399 -239.033512) (xy 208.002124 -239.025684) (xy 207.994763 -239.023678)
			(xy 207.979513 -239.023678) (xy 207.972152 -239.025684) (xy 207.944874 -239.033499) (xy 207.888762 -239.041921)
			(xy 207.860392 -239.042448) (xy 207.860138 -239.042448) (xy 207.83288 -239.041988) (xy 207.77892 -239.034234)
			(xy 207.726612 -239.01888) (xy 207.677022 -238.996237) (xy 207.631159 -238.966767) (xy 207.589957 -238.93107)
			(xy 207.554256 -238.889872) (xy 207.524781 -238.844012) (xy 207.502133 -238.794424) (xy 207.486774 -238.742117)
			(xy 207.479015 -238.688157) (xy 207.479015 -238.633643) (xy 207.486774 -238.579683) (xy 207.502133 -238.527376)
			(xy 207.524781 -238.477788) (xy 207.554256 -238.431928) (xy 207.589957 -238.39073) (xy 207.631159 -238.355033)
			(xy 207.677022 -238.325563) (xy 207.726612 -238.30292) (xy 207.77892 -238.287566) (xy 207.83288 -238.279812)
			(xy 207.860138 -238.279432) (xy 207.860392 -238.279432) (xy 207.888763 -238.279949) (xy 207.944879 -238.288362)
			(xy 207.972152 -238.296196) (xy 207.979513 -238.298202) (xy 207.994763 -238.298202) (xy 208.002124 -238.296196)
			(xy 208.029401 -238.28838) (xy 208.085514 -238.279955) (xy 208.113884 -238.279432) (xy 208.114138 -238.279432)
			(xy 208.141487 -238.279905) (xy 208.195622 -238.287723) (xy 208.248086 -238.303192) (xy 208.297803 -238.325996)
			(xy 208.343753 -238.355668) (xy 208.384994 -238.391598) (xy 208.40319 -238.41202) (xy 208.403444 -238.412274)
			(xy 208.408593 -238.417793) (xy 208.421376 -238.425802) (xy 208.42859 -238.428022) (xy 208.428844 -238.428022)
			(xy 208.436431 -238.429687) (xy 208.451938 -238.428905) (xy 208.459324 -238.426498) (xy 208.459578 -238.426498)
			(xy 208.548732 -238.393224) (xy 208.553663 -238.391203) (xy 208.562627 -238.385443) (xy 208.566512 -238.381794)
			(xy 208.57342 -238.37442) (xy 208.581271 -238.35582) (xy 208.581752 -238.345726) (xy 208.581752 -234.425744)
			(xy 208.582187 -234.415679) (xy 208.589921 -234.397095) (xy 208.596738 -234.389676) (xy 208.88071 -234.105704)
			(xy 208.888109 -234.098859) (xy 208.906707 -234.091127) (xy 208.916778 -234.090718) (xy 211.66836 -234.090718)
			(xy 211.680766 -234.089889) (xy 211.702666 -234.078204) (xy 211.71027 -234.068366) (xy 211.725535 -234.046491)
			(xy 211.761201 -234.006826) (xy 211.802043 -233.972516) (xy 211.847267 -233.944229) (xy 211.89599 -233.922516)
			(xy 211.947261 -233.907801) (xy 212.000083 -233.900372) (xy 212.053425 -233.900372) (xy 212.106247 -233.907801)
			(xy 212.157518 -233.922516) (xy 212.206241 -233.944229) (xy 212.251465 -233.972516) (xy 212.292307 -234.006826)
			(xy 212.327973 -234.046491) (xy 212.343238 -234.068366) (xy 212.350721 -234.078337) (xy 212.372698 -234.090046)
			(xy 212.385148 -234.090718) (xy 244.095016 -234.090718) (xy 244.103144 -234.089956) (xy 244.103652 -234.089956)
			(xy 244.111171 -234.088355) (xy 244.12486 -234.08138) (xy 244.130576 -234.07624) (xy 246.060214 -232.146602)
			(xy 246.06504 -232.141014) (xy 246.069714 -232.134275) (xy 246.074906 -232.118729) (xy 246.0752 -232.110534)
			(xy 246.0752 -222.955866) (xy 246.075629 -222.945799) (xy 246.083353 -222.927203) (xy 246.090186 -222.919798)
			(xy 248.278396 -220.731588) (xy 248.282206 -220.72219) (xy 248.292155 -220.698881) (xy 248.31733 -220.654896)
			(xy 248.348107 -220.614632) (xy 248.383943 -220.578796) (xy 248.424209 -220.548021) (xy 248.468195 -220.522848)
			(xy 248.491502 -220.512894) (xy 248.5009 -220.509084) (xy 248.541794 -220.46819) (xy 248.549188 -220.461333)
			(xy 248.567787 -220.453582) (xy 248.577862 -220.453204) (xy 249.81154 -220.453204) (xy 249.822719 -220.452694)
			(xy 249.843027 -220.443354) (xy 249.850656 -220.43517) (xy 249.852688 -220.432376) (xy 249.853196 -220.431868)
			(xy 249.869833 -220.40962) (xy 249.908493 -220.369727) (xy 249.952534 -220.335868) (xy 250.001022 -220.308758)
			(xy 250.052932 -220.288974) (xy 250.107163 -220.276933) (xy 250.162568 -220.272891) (xy 250.217973 -220.276933)
			(xy 250.272204 -220.288974) (xy 250.324114 -220.308758) (xy 250.372602 -220.335868) (xy 250.416643 -220.369727)
			(xy 250.455303 -220.40962) (xy 250.47194 -220.431868) (xy 250.472448 -220.432376) (xy 250.47448 -220.43517)
			(xy 250.482126 -220.443334) (xy 250.502422 -220.452668) (xy 250.513596 -220.453204) (xy 258.052316 -220.453204)
			(xy 258.064 -220.451934) (xy 258.071943 -220.449739) (xy 258.08594 -220.44106) (xy 258.091432 -220.434916)
			(xy 258.09194 -220.434408) (xy 258.141724 -220.3704) (xy 258.145204 -220.365802) (xy 258.150196 -220.355411)
			(xy 258.15163 -220.349826) (xy 258.153916 -220.338396) (xy 258.151122 -220.326966) (xy 258.145786 -220.304225)
			(xy 258.140051 -220.257866) (xy 258.139692 -220.23451) (xy 258.140155 -220.207257) (xy 258.14791 -220.153305)
			(xy 258.163266 -220.101006) (xy 258.185908 -220.051424) (xy 258.215375 -220.00557) (xy 258.251069 -219.964376)
			(xy 258.292262 -219.928681) (xy 258.338115 -219.899212) (xy 258.387696 -219.876569) (xy 258.439995 -219.861213)
			(xy 258.493947 -219.853455) (xy 258.5212 -219.853002) (xy 258.550583 -219.853543) (xy 258.608655 -219.862555)
			(xy 258.664657 -219.880366) (xy 258.717267 -219.906553) (xy 258.765238 -219.940498) (xy 258.807436 -219.981399)
			(xy 258.842863 -220.028286) (xy 258.857242 -220.053916) (xy 258.857242 -220.054424) (xy 258.857496 -220.054424)
			(xy 258.860403 -220.059462) (xy 258.868105 -220.068175) (xy 258.872736 -220.071696) (xy 258.877687 -220.074972)
			(xy 258.888728 -220.079329) (xy 258.89458 -220.080332) (xy 258.975352 -220.09227) (xy 258.976368 -220.092524)
			(xy 258.986815 -220.093341) (xy 259.006898 -220.087447) (xy 259.01523 -220.081094) (xy 259.017262 -220.079316)
			(xy 260.62432 -218.472258) (xy 260.629146 -218.46667) (xy 260.633813 -218.459929) (xy 260.638991 -218.444383)
			(xy 260.639306 -218.43619) (xy 260.639306 -215.11387) (xy 260.639157 -215.108002) (xy 260.636463 -215.096579)
			(xy 260.633972 -215.091264) (xy 260.631432 -215.086184) (xy 260.62432 -215.077294) (xy 260.61924 -215.073484)
			(xy 260.555486 -215.024716) (xy 260.544056 -215.018112) (xy 260.53415 -215.015064) (xy 260.522466 -215.012778)
			(xy 260.51383 -215.015064) (xy 260.488564 -215.021688) (xy 260.436822 -215.02882) (xy 260.410706 -215.029288)
			(xy 260.407658 -215.029288) (xy 260.380549 -215.028596) (xy 260.326932 -215.020489) (xy 260.275002 -215.004872)
			(xy 260.225807 -214.982059) (xy 260.180338 -214.95251) (xy 260.139512 -214.91682) (xy 260.104151 -214.875708)
			(xy 260.074968 -214.830004) (xy 260.05255 -214.780628) (xy 260.03735 -214.728574) (xy 260.029674 -214.674894)
			(xy 260.029198 -214.64778) (xy 260.029684 -214.620236) (xy 260.03761 -214.56572) (xy 260.053295 -214.512912)
			(xy 260.076412 -214.462908) (xy 260.106481 -214.41675) (xy 260.142877 -214.375396) (xy 260.163564 -214.357204)
			(xy 260.170784 -214.350532) (xy 260.17993 -214.333151) (xy 260.181344 -214.323422) (xy 260.181598 -214.317834)
			(xy 260.180836 -214.239856) (xy 260.180669 -214.234338) (xy 260.178233 -214.223573) (xy 260.17601 -214.21852)
			(xy 260.171438 -214.208868) (xy 260.162548 -214.201502) (xy 260.141292 -214.183275) (xy 260.103828 -214.141661)
			(xy 260.072844 -214.095023) (xy 260.049002 -214.044359) (xy 260.032814 -213.990758) (xy 260.024627 -213.935366)
			(xy 260.024118 -213.90737) (xy 260.024595 -213.880268) (xy 260.03227 -213.82661) (xy 260.04746 -213.774579)
			(xy 260.069861 -213.72522) (xy 260.099021 -213.679529) (xy 260.134354 -213.638423) (xy 260.175148 -213.602732)
			(xy 260.220582 -213.573172) (xy 260.269742 -213.550339) (xy 260.321639 -213.534693) (xy 260.375227 -213.526548)
			(xy 260.402324 -213.525862) (xy 260.40588 -213.525862) (xy 260.432197 -213.526321) (xy 260.484327 -213.533585)
			(xy 260.509766 -213.54034) (xy 260.52145 -213.543642) (xy 260.533134 -213.54161) (xy 260.537831 -213.540636)
			(xy 260.546777 -213.53718) (xy 260.550914 -213.534752) (xy 260.554724 -213.532212) (xy 260.618986 -213.48319)
			(xy 260.624066 -213.479126) (xy 260.631057 -213.47165) (xy 260.63893 -213.452777) (xy 260.639306 -213.44255)
			(xy 260.639306 -209.092292) (xy 260.639173 -209.0874) (xy 260.637263 -209.077805) (xy 260.635496 -209.073242)
			(xy 260.631686 -209.06359) (xy 260.62432 -209.056478) (xy 258.185412 -206.61757) (xy 258.181839 -206.614171)
			(xy 258.17365 -206.60868) (xy 258.169156 -206.606648) (xy 258.15925 -206.602584) (xy 258.145026 -206.602584)
			(xy 258.114181 -206.601973) (xy 258.053299 -206.592023) (xy 258.023868 -206.582772) (xy 258.012692 -206.578962)
			(xy 258.001516 -206.580232) (xy 257.996363 -206.580972) (xy 257.986498 -206.584291) (xy 257.981958 -206.586836)
			(xy 257.979926 -206.588106) (xy 257.913124 -206.631794) (xy 257.908328 -206.63507) (xy 257.900253 -206.643412)
			(xy 257.897122 -206.648304) (xy 257.891534 -206.657702) (xy 257.890264 -206.66964) (xy 257.887151 -206.697669)
			(xy 257.873722 -206.75244) (xy 257.85237 -206.804635) (xy 257.823562 -206.853115) (xy 257.787925 -206.896821)
			(xy 257.746238 -206.9348) (xy 257.699411 -206.966223) (xy 257.648465 -206.990405) (xy 257.594513 -207.006816)
			(xy 257.538731 -207.0151) (xy 257.510534 -207.015588) (xy 257.48328 -207.015127) (xy 257.429327 -207.007374)
			(xy 257.377026 -206.992021) (xy 257.327443 -206.96938) (xy 257.281587 -206.939912) (xy 257.240392 -206.904218)
			(xy 257.204696 -206.863025) (xy 257.175227 -206.81717) (xy 257.152584 -206.767587) (xy 257.137229 -206.715287)
			(xy 257.129474 -206.661334) (xy 257.129026 -206.63408) (xy 257.129562 -206.605163) (xy 257.138292 -206.547992)
			(xy 257.155551 -206.492793) (xy 257.180942 -206.440831) (xy 257.213883 -206.393296) (xy 257.253621 -206.351276)
			(xy 257.299245 -206.315735) (xy 257.34971 -206.287485) (xy 257.40386 -206.267175) (xy 257.432048 -206.2607)
			(xy 257.43281 -206.2607) (xy 257.43935 -206.258978) (xy 257.451307 -206.252668) (xy 257.456432 -206.248254)
			(xy 257.461258 -206.243682) (xy 257.46456 -206.238348) (xy 257.470402 -206.225648) (xy 257.496056 -206.139796)
			(xy 257.497812 -206.133265) (xy 257.498188 -206.11975) (xy 257.496818 -206.113126) (xy 257.495294 -206.106522)
			(xy 257.488436 -206.094584) (xy 257.48361 -206.089758) (xy 257.467251 -206.072774) (xy 257.438405 -206.035468)
			(xy 257.414365 -205.994898) (xy 257.404616 -205.973426) (xy 257.401452 -205.966707) (xy 257.39189 -205.955355)
			(xy 257.38582 -205.951074) (xy 257.379724 -205.94701) (xy 257.372612 -205.944978) (xy 257.369133 -205.944031)
			(xy 257.361994 -205.943013) (xy 257.358388 -205.942946) (xy 255.96977 -205.942946) (xy 255.959962 -205.943452)
			(xy 255.941808 -205.950902) (xy 255.934464 -205.957424) (xy 255.927352 -205.964282) (xy 255.919224 -205.982824)
			(xy 255.919224 -205.99273) (xy 255.918027 -206.024241) (xy 255.906579 -206.086247) (xy 255.88509 -206.145526)
			(xy 255.870202 -206.173324) (xy 255.859669 -206.191413) (xy 255.835228 -206.225398) (xy 255.821434 -206.241142)
			(xy 255.81737 -206.245714) (xy 255.799246 -206.264591) (xy 255.758726 -206.297707) (xy 255.714064 -206.32498)
			(xy 255.666096 -206.345899) (xy 255.61572 -206.360072) (xy 255.563881 -206.367234) (xy 255.537716 -206.367634)
			(xy 255.510777 -206.367165) (xy 255.457435 -206.359575) (xy 255.405691 -206.344558) (xy 255.356574 -206.322413)
			(xy 255.31106 -206.29358) (xy 255.270053 -206.258632) (xy 255.234369 -206.218264) (xy 255.204718 -206.173278)
			(xy 255.181689 -206.124569) (xy 255.165739 -206.073106) (xy 255.157186 -206.01991) (xy 255.156208 -205.992984)
			(xy 255.156208 -205.992476) (xy 255.155513 -205.98263) (xy 255.147639 -205.964551) (xy 255.13353 -205.950775)
			(xy 255.115268 -205.943337) (xy 255.105408 -205.942946) (xy 254.04064 -205.942946) (xy 254.030739 -205.94346)
			(xy 254.012438 -205.951035) (xy 254.00508 -205.957678) (xy 253.983236 -205.979268) (xy 253.980566 -205.981938)
			(xy 253.975979 -205.987935) (xy 253.974092 -205.991206) (xy 253.972822 -205.994) (xy 253.968758 -206.002636)
			(xy 253.96825 -206.012034) (xy 253.965945 -206.039276) (xy 253.954523 -206.092739) (xy 253.935589 -206.144026)
			(xy 253.90953 -206.192085) (xy 253.87688 -206.235934) (xy 253.838306 -206.274675) (xy 253.794598 -206.307515)
			(xy 253.746652 -206.333781) (xy 253.695448 -206.352937) (xy 253.642034 -206.364589) (xy 253.587504 -206.3685)
			(xy 253.532974 -206.364589) (xy 253.47956 -206.352937) (xy 253.428356 -206.333781) (xy 253.38041 -206.307515)
			(xy 253.336702 -206.274675) (xy 253.298128 -206.235934) (xy 253.265478 -206.192085) (xy 253.239419 -206.144026)
			(xy 253.220485 -206.092739) (xy 253.209063 -206.039276) (xy 253.206758 -206.012034) (xy 253.20625 -206.002636)
			(xy 253.202186 -205.994) (xy 253.200916 -205.991206) (xy 253.199026 -205.987938) (xy 253.194436 -205.981943)
			(xy 253.191772 -205.979268) (xy 253.169928 -205.957678) (xy 253.162572 -205.951027) (xy 253.144272 -205.94344)
			(xy 253.134368 -205.942946) (xy 252.924056 -205.942946) (xy 252.917198 -205.943454) (xy 252.906407 -205.945476)
			(xy 252.887867 -205.957197) (xy 252.881384 -205.96606) (xy 252.878082 -205.971902) (xy 252.869446 -205.989682)
			(xy 252.868684 -205.998572) (xy 252.865435 -206.0265) (xy 252.851782 -206.081041) (xy 252.830273 -206.132987)
			(xy 252.801373 -206.181215) (xy 252.76571 -206.22468) (xy 252.724054 -206.262441) (xy 252.677307 -206.29368)
			(xy 252.626483 -206.317721) (xy 252.572681 -206.334044) (xy 252.517066 -206.342295) (xy 252.460842 -206.342295)
			(xy 252.405227 -206.334044) (xy 252.351425 -206.317721) (xy 252.300601 -206.29368) (xy 252.253854 -206.262441)
			(xy 252.212198 -206.22468) (xy 252.176535 -206.181215) (xy 252.147635 -206.132987) (xy 252.126126 -206.081041)
			(xy 252.112473 -206.0265) (xy 252.109224 -205.998572) (xy 252.108462 -205.989682) (xy 252.099826 -205.971902)
			(xy 252.096524 -205.96606) (xy 252.090106 -205.957132) (xy 252.071531 -205.945411) (xy 252.06071 -205.943454)
			(xy 252.053852 -205.942946) (xy 242.078002 -205.942946) (xy 242.068923 -205.943307) (xy 242.051908 -205.949647)
			(xy 242.038203 -205.961556) (xy 242.033552 -205.969362) (xy 241.99088 -206.04734) (xy 241.986054 -206.059024)
			(xy 241.985215 -206.062645) (xy 241.984452 -206.07004) (xy 241.98453 -206.073756) (xy 241.985038 -206.087218)
			(xy 241.992658 -206.099156) (xy 242.006852 -206.122284) (xy 242.029273 -206.1717) (xy 242.044474 -206.223791)
			(xy 242.052149 -206.27751) (xy 242.052602 -206.304642) (xy 242.052602 -206.311246) (xy 242.051603 -206.339473)
			(xy 242.042312 -206.395184) (xy 242.024909 -206.448917) (xy 241.999776 -206.499498) (xy 241.996967 -206.503524)
			(xy 244.491762 -206.503524) (xy 244.495833 -206.447902) (xy 244.507959 -206.393465) (xy 244.527882 -206.341374)
			(xy 244.555178 -206.292739) (xy 244.589264 -206.248596) (xy 244.629413 -206.209887) (xy 244.674771 -206.177436)
			(xy 244.724371 -206.151935) (xy 244.777155 -206.133928) (xy 244.831998 -206.123798) (xy 244.887732 -206.121761)
			(xy 244.943169 -206.127861) (xy 244.997126 -206.141967) (xy 245.048455 -206.163779) (xy 245.096061 -206.192833)
			(xy 245.138929 -206.228508) (xy 245.176146 -206.270045) (xy 245.206919 -206.316558) (xy 245.230591 -206.367055)
			(xy 245.246659 -206.420462) (xy 245.254779 -206.475638) (xy 245.255288 -206.503524) (xy 245.254779 -206.53141)
			(xy 245.246659 -206.586586) (xy 245.230591 -206.639993) (xy 245.206919 -206.69049) (xy 245.176146 -206.737003)
			(xy 245.138929 -206.77854) (xy 245.096061 -206.814215) (xy 245.048455 -206.843269) (xy 244.997126 -206.865081)
			(xy 244.943169 -206.879187) (xy 244.887732 -206.885287) (xy 244.831998 -206.88325) (xy 244.777155 -206.87312)
			(xy 244.724371 -206.855113) (xy 244.674771 -206.829612) (xy 244.629413 -206.797161) (xy 244.589264 -206.758452)
			(xy 244.555178 -206.714309) (xy 244.527882 -206.665674) (xy 244.507959 -206.613583) (xy 244.495833 -206.559146)
			(xy 244.491762 -206.503524) (xy 241.996967 -206.503524) (xy 241.967461 -206.545821) (xy 241.928671 -206.586874)
			(xy 241.884252 -206.62176) (xy 241.835177 -206.649718) (xy 241.782516 -206.670136) (xy 241.72742 -206.682568)
			(xy 241.671094 -206.686742) (xy 241.614768 -206.682568) (xy 241.559672 -206.670136) (xy 241.507011 -206.649718)
			(xy 241.457936 -206.62176) (xy 241.413517 -206.586874) (xy 241.374727 -206.545821) (xy 241.342412 -206.499498)
			(xy 241.317279 -206.448917) (xy 241.299876 -206.395184) (xy 241.290585 -206.339473) (xy 241.289586 -206.311246)
			(xy 241.289586 -206.304642) (xy 241.290041 -206.277508) (xy 241.29769 -206.223783) (xy 241.312883 -206.171686)
			(xy 241.335312 -206.122271) (xy 241.34953 -206.099156) (xy 241.349784 -206.098902) (xy 241.353206 -206.093096)
			(xy 241.357187 -206.080225) (xy 241.357658 -206.073502) (xy 241.358166 -206.059786) (xy 241.308636 -205.969362)
			(xy 241.303944 -205.961593) (xy 241.29023 -205.949723) (xy 241.273253 -205.943342) (xy 241.264186 -205.942946)
			(xy 236.746796 -205.942946) (xy 236.736727 -205.942521) (xy 236.718129 -205.934799) (xy 236.710728 -205.92796)
			(xy 236.121448 -205.33868) (xy 236.11586 -205.333854) (xy 236.109119 -205.329189) (xy 236.093573 -205.324013)
			(xy 236.08538 -205.323694) (xy 229.058978 -205.323694) (xy 229.054152 -205.323948) (xy 229.046175 -205.324951)
			(xy 229.031408 -205.33129) (xy 229.025196 -205.336394) (xy 229.021132 -205.340458) (xy 228.970586 -205.396846)
			(xy 228.96707 -205.40101) (xy 228.961698 -205.410491) (xy 228.959918 -205.415642) (xy 228.95687 -205.425294)
			(xy 228.957886 -205.436216) (xy 228.958934 -205.446407) (xy 228.960075 -205.466865) (xy 228.960172 -205.47711)
			(xy 228.959686 -205.504361) (xy 228.95193 -205.558309) (xy 228.936575 -205.610604) (xy 228.913933 -205.660181)
			(xy 228.884467 -205.706031) (xy 228.848776 -205.747222) (xy 228.807585 -205.782913) (xy 228.761735 -205.812379)
			(xy 228.712158 -205.835021) (xy 228.659863 -205.850376) (xy 228.605915 -205.858132) (xy 228.551413 -205.858132)
			(xy 228.497465 -205.850376) (xy 228.44517 -205.835021) (xy 228.395593 -205.812379) (xy 228.349743 -205.782913)
			(xy 228.308552 -205.747222) (xy 228.272861 -205.706031) (xy 228.243395 -205.660181) (xy 228.220753 -205.610604)
			(xy 228.205398 -205.558309) (xy 228.197642 -205.504361) (xy 228.197156 -205.47711) (xy 228.197243 -205.466865)
			(xy 228.198386 -205.446407) (xy 228.199442 -205.436216) (xy 228.200458 -205.425294) (xy 228.19741 -205.415642)
			(xy 228.19568 -205.410468) (xy 228.190303 -205.400979) (xy 228.186742 -205.396846) (xy 228.136196 -205.340458)
			(xy 228.132132 -205.336394) (xy 228.125913 -205.3313) (xy 228.111151 -205.324955) (xy 228.103176 -205.323948)
			(xy 228.09835 -205.323694) (xy 228.042978 -205.323694) (xy 228.038152 -205.323948) (xy 228.030175 -205.324951)
			(xy 228.015408 -205.33129) (xy 228.009196 -205.336394) (xy 228.005132 -205.340458) (xy 227.954586 -205.396846)
			(xy 227.95107 -205.40101) (xy 227.945698 -205.410491) (xy 227.943918 -205.415642) (xy 227.94087 -205.425294)
			(xy 227.941886 -205.436216) (xy 227.942934 -205.446407) (xy 227.944075 -205.466865) (xy 227.944172 -205.47711)
			(xy 227.943686 -205.504361) (xy 227.93593 -205.558309) (xy 227.920575 -205.610604) (xy 227.897933 -205.660181)
			(xy 227.868467 -205.706031) (xy 227.832776 -205.747222) (xy 227.791585 -205.782913) (xy 227.745735 -205.812379)
			(xy 227.696158 -205.835021) (xy 227.643863 -205.850376) (xy 227.589915 -205.858132) (xy 227.535413 -205.858132)
			(xy 227.481465 -205.850376) (xy 227.42917 -205.835021) (xy 227.379593 -205.812379) (xy 227.333743 -205.782913)
			(xy 227.292552 -205.747222) (xy 227.256861 -205.706031) (xy 227.227395 -205.660181) (xy 227.204753 -205.610604)
			(xy 227.189398 -205.558309) (xy 227.181642 -205.504361) (xy 227.181156 -205.47711) (xy 227.181243 -205.466865)
			(xy 227.182386 -205.446407) (xy 227.183442 -205.436216) (xy 227.184458 -205.425294) (xy 227.18141 -205.415642)
			(xy 227.17968 -205.410468) (xy 227.174303 -205.400979) (xy 227.170742 -205.396846) (xy 227.120196 -205.340458)
			(xy 227.116132 -205.336394) (xy 227.109913 -205.3313) (xy 227.095151 -205.324955) (xy 227.087176 -205.323948)
			(xy 227.08235 -205.323694) (xy 227.026978 -205.323694) (xy 227.022152 -205.323948) (xy 227.014175 -205.324951)
			(xy 226.999408 -205.33129) (xy 226.993196 -205.336394) (xy 226.989132 -205.340458) (xy 226.938586 -205.396846)
			(xy 226.93507 -205.40101) (xy 226.929698 -205.410491) (xy 226.927918 -205.415642) (xy 226.92487 -205.425294)
			(xy 226.925886 -205.436216) (xy 226.926934 -205.446407) (xy 226.928075 -205.466865) (xy 226.928172 -205.47711)
			(xy 226.927686 -205.504361) (xy 226.91993 -205.558309) (xy 226.904575 -205.610604) (xy 226.881933 -205.660181)
			(xy 226.852467 -205.706031) (xy 226.816776 -205.747222) (xy 226.775585 -205.782913) (xy 226.729735 -205.812379)
			(xy 226.680158 -205.835021) (xy 226.627863 -205.850376) (xy 226.573915 -205.858132) (xy 226.519413 -205.858132)
			(xy 226.465465 -205.850376) (xy 226.41317 -205.835021) (xy 226.363593 -205.812379) (xy 226.317743 -205.782913)
			(xy 226.276552 -205.747222) (xy 226.240861 -205.706031) (xy 226.211395 -205.660181) (xy 226.188753 -205.610604)
			(xy 226.173398 -205.558309) (xy 226.165642 -205.504361) (xy 226.165156 -205.47711) (xy 226.165243 -205.466865)
			(xy 226.166386 -205.446407) (xy 226.167442 -205.436216) (xy 226.168458 -205.425294) (xy 226.16541 -205.415642)
			(xy 226.16368 -205.410468) (xy 226.158303 -205.400979) (xy 226.154742 -205.396846) (xy 226.104196 -205.340458)
			(xy 226.100132 -205.336394) (xy 226.093913 -205.3313) (xy 226.079151 -205.324955) (xy 226.071176 -205.323948)
			(xy 226.06635 -205.323694) (xy 226.010978 -205.323694) (xy 226.006152 -205.323948) (xy 225.998175 -205.324951)
			(xy 225.983408 -205.33129) (xy 225.977196 -205.336394) (xy 225.973132 -205.340458) (xy 225.922586 -205.396846)
			(xy 225.91907 -205.40101) (xy 225.913698 -205.410491) (xy 225.911918 -205.415642) (xy 225.90887 -205.425294)
			(xy 225.909886 -205.436216) (xy 225.910934 -205.446407) (xy 225.912075 -205.466865) (xy 225.912172 -205.47711)
			(xy 225.911686 -205.504361) (xy 225.90393 -205.558309) (xy 225.888575 -205.610604) (xy 225.865933 -205.660181)
			(xy 225.836467 -205.706031) (xy 225.800776 -205.747222) (xy 225.759585 -205.782913) (xy 225.713735 -205.812379)
			(xy 225.664158 -205.835021) (xy 225.611863 -205.850376) (xy 225.557915 -205.858132) (xy 225.503413 -205.858132)
			(xy 225.449465 -205.850376) (xy 225.39717 -205.835021) (xy 225.347593 -205.812379) (xy 225.301743 -205.782913)
			(xy 225.260552 -205.747222) (xy 225.224861 -205.706031) (xy 225.195395 -205.660181) (xy 225.172753 -205.610604)
			(xy 225.157398 -205.558309) (xy 225.149642 -205.504361) (xy 225.149156 -205.47711) (xy 225.149243 -205.466865)
			(xy 225.150386 -205.446407) (xy 225.151442 -205.436216) (xy 225.152458 -205.425294) (xy 225.14941 -205.415642)
			(xy 225.14768 -205.410468) (xy 225.142303 -205.400979) (xy 225.138742 -205.396846) (xy 225.088196 -205.340458)
			(xy 225.084132 -205.336394) (xy 225.077913 -205.3313) (xy 225.063151 -205.324955) (xy 225.055176 -205.323948)
			(xy 225.05035 -205.323694) (xy 224.994978 -205.323694) (xy 224.990152 -205.323948) (xy 224.982175 -205.324951)
			(xy 224.967408 -205.33129) (xy 224.961196 -205.336394) (xy 224.957132 -205.340458) (xy 224.906586 -205.396846)
			(xy 224.90307 -205.40101) (xy 224.897698 -205.410491) (xy 224.895918 -205.415642) (xy 224.89287 -205.425294)
			(xy 224.893886 -205.436216) (xy 224.894934 -205.446407) (xy 224.896075 -205.466865) (xy 224.896172 -205.47711)
			(xy 224.895686 -205.504361) (xy 224.88793 -205.558309) (xy 224.872575 -205.610604) (xy 224.849933 -205.660181)
			(xy 224.820467 -205.706031) (xy 224.784776 -205.747222) (xy 224.743585 -205.782913) (xy 224.697735 -205.812379)
			(xy 224.648158 -205.835021) (xy 224.595863 -205.850376) (xy 224.541915 -205.858132) (xy 224.487413 -205.858132)
			(xy 224.433465 -205.850376) (xy 224.38117 -205.835021) (xy 224.331593 -205.812379) (xy 224.285743 -205.782913)
			(xy 224.244552 -205.747222) (xy 224.208861 -205.706031) (xy 224.179395 -205.660181) (xy 224.156753 -205.610604)
			(xy 224.141398 -205.558309) (xy 224.133642 -205.504361) (xy 224.133156 -205.47711) (xy 224.133243 -205.466865)
			(xy 224.134386 -205.446407) (xy 224.135442 -205.436216) (xy 224.136458 -205.425294) (xy 224.13341 -205.415642)
			(xy 224.13168 -205.410468) (xy 224.126303 -205.400979) (xy 224.122742 -205.396846) (xy 224.072196 -205.340458)
			(xy 224.068132 -205.336394) (xy 224.061913 -205.3313) (xy 224.047151 -205.324955) (xy 224.039176 -205.323948)
			(xy 224.03435 -205.323694) (xy 223.978978 -205.323694) (xy 223.974152 -205.323948) (xy 223.966175 -205.324951)
			(xy 223.951408 -205.33129) (xy 223.945196 -205.336394) (xy 223.941132 -205.340458) (xy 223.890586 -205.396846)
			(xy 223.88707 -205.40101) (xy 223.881698 -205.410491) (xy 223.879918 -205.415642) (xy 223.87687 -205.425294)
			(xy 223.877886 -205.436216) (xy 223.878934 -205.446407) (xy 223.880075 -205.466865) (xy 223.880172 -205.47711)
			(xy 223.879686 -205.504361) (xy 223.87193 -205.558309) (xy 223.856575 -205.610604) (xy 223.833933 -205.660181)
			(xy 223.804467 -205.706031) (xy 223.768776 -205.747222) (xy 223.727585 -205.782913) (xy 223.681735 -205.812379)
			(xy 223.632158 -205.835021) (xy 223.579863 -205.850376) (xy 223.525915 -205.858132) (xy 223.471413 -205.858132)
			(xy 223.417465 -205.850376) (xy 223.36517 -205.835021) (xy 223.315593 -205.812379) (xy 223.269743 -205.782913)
			(xy 223.228552 -205.747222) (xy 223.192861 -205.706031) (xy 223.163395 -205.660181) (xy 223.140753 -205.610604)
			(xy 223.125398 -205.558309) (xy 223.117642 -205.504361) (xy 223.117156 -205.47711) (xy 223.117243 -205.466865)
			(xy 223.118386 -205.446407) (xy 223.119442 -205.436216) (xy 223.120458 -205.425294) (xy 223.11741 -205.415642)
			(xy 223.11568 -205.410468) (xy 223.110303 -205.400979) (xy 223.106742 -205.396846) (xy 223.056196 -205.340458)
			(xy 223.052132 -205.336394) (xy 223.045913 -205.3313) (xy 223.031151 -205.324955) (xy 223.023176 -205.323948)
			(xy 223.01835 -205.323694) (xy 222.962978 -205.323694) (xy 222.958152 -205.323948) (xy 222.950175 -205.324951)
			(xy 222.935408 -205.33129) (xy 222.929196 -205.336394) (xy 222.925132 -205.340458) (xy 222.874586 -205.396846)
			(xy 222.87107 -205.40101) (xy 222.865698 -205.410491) (xy 222.863918 -205.415642) (xy 222.86087 -205.425294)
			(xy 222.861886 -205.436216) (xy 222.862934 -205.446407) (xy 222.864075 -205.466865) (xy 222.864172 -205.47711)
			(xy 222.863686 -205.504361) (xy 222.85593 -205.558309) (xy 222.840575 -205.610604) (xy 222.817933 -205.660181)
			(xy 222.788467 -205.706031) (xy 222.752776 -205.747222) (xy 222.711585 -205.782913) (xy 222.665735 -205.812379)
			(xy 222.616158 -205.835021) (xy 222.563863 -205.850376) (xy 222.509915 -205.858132) (xy 222.455413 -205.858132)
			(xy 222.401465 -205.850376) (xy 222.34917 -205.835021) (xy 222.299593 -205.812379) (xy 222.253743 -205.782913)
			(xy 222.212552 -205.747222) (xy 222.176861 -205.706031) (xy 222.147395 -205.660181) (xy 222.124753 -205.610604)
			(xy 222.109398 -205.558309) (xy 222.101642 -205.504361) (xy 222.101156 -205.47711) (xy 222.101243 -205.466865)
			(xy 222.102386 -205.446407) (xy 222.103442 -205.436216) (xy 222.104458 -205.425294) (xy 222.10141 -205.415642)
			(xy 222.09968 -205.410468) (xy 222.094303 -205.400979) (xy 222.090742 -205.396846) (xy 222.040196 -205.340458)
			(xy 222.036132 -205.336394) (xy 222.029913 -205.3313) (xy 222.015151 -205.324955) (xy 222.007176 -205.323948)
			(xy 222.00235 -205.323694) (xy 220.58376 -205.323694) (xy 220.574177 -205.32424) (xy 220.556442 -205.331543)
			(xy 220.542627 -205.344848) (xy 220.538294 -205.353412) (xy 220.499686 -205.437232) (xy 220.497146 -205.44409)
			(xy 220.495761 -205.44937) (xy 220.494999 -205.460257) (xy 220.495622 -205.46568) (xy 220.496638 -205.472538)
			(xy 220.502734 -205.486) (xy 220.50756 -205.491588) (xy 220.524823 -205.512436) (xy 220.553906 -205.558086)
			(xy 220.576245 -205.607388) (xy 220.591392 -205.659353) (xy 220.599042 -205.712936) (xy 220.599508 -205.74)
			(xy 220.599022 -205.767251) (xy 220.591266 -205.821199) (xy 220.575911 -205.873494) (xy 220.553269 -205.923071)
			(xy 220.523803 -205.968921) (xy 220.488112 -206.010112) (xy 220.446921 -206.045803) (xy 220.401071 -206.075269)
			(xy 220.351494 -206.097911) (xy 220.299199 -206.113266) (xy 220.245251 -206.121022) (xy 220.190749 -206.121022)
			(xy 220.136801 -206.113266) (xy 220.084506 -206.097911) (xy 220.034929 -206.075269) (xy 219.989079 -206.045803)
			(xy 219.947888 -206.010112) (xy 219.912197 -205.968921) (xy 219.882731 -205.923071) (xy 219.860089 -205.873494)
			(xy 219.844734 -205.821199) (xy 219.836978 -205.767251) (xy 219.836492 -205.74) (xy 219.836964 -205.712936)
			(xy 219.844613 -205.659352) (xy 219.859756 -205.607386) (xy 219.88209 -205.558082) (xy 219.911167 -205.512428)
			(xy 219.92844 -205.491588) (xy 219.933087 -205.485865) (xy 219.939166 -205.472443) (xy 219.940378 -205.465172)
			(xy 219.941394 -205.458314) (xy 219.940378 -205.451456) (xy 219.939801 -205.447912) (xy 219.93776 -205.441027)
			(xy 219.936314 -205.43774) (xy 219.897706 -205.353412) (xy 219.893356 -205.34486) (xy 219.879547 -205.33156)
			(xy 219.861819 -205.324261) (xy 219.85224 -205.323694) (xy 218.55176 -205.323694) (xy 218.542177 -205.32424)
			(xy 218.524442 -205.331543) (xy 218.510627 -205.344848) (xy 218.506294 -205.353412) (xy 218.467686 -205.437232)
			(xy 218.465146 -205.44409) (xy 218.463761 -205.44937) (xy 218.462999 -205.460257) (xy 218.463622 -205.46568)
			(xy 218.464638 -205.472538) (xy 218.470734 -205.486) (xy 218.47556 -205.491588) (xy 218.492823 -205.512436)
			(xy 218.521906 -205.558086) (xy 218.544245 -205.607388) (xy 218.559392 -205.659353) (xy 218.567042 -205.712936)
			(xy 218.567508 -205.74) (xy 218.567022 -205.767251) (xy 218.559266 -205.821199) (xy 218.543911 -205.873494)
			(xy 218.521269 -205.923071) (xy 218.491803 -205.968921) (xy 218.456112 -206.010112) (xy 218.414921 -206.045803)
			(xy 218.369071 -206.075269) (xy 218.319494 -206.097911) (xy 218.267199 -206.113266) (xy 218.213251 -206.121022)
			(xy 218.158749 -206.121022) (xy 218.104801 -206.113266) (xy 218.052506 -206.097911) (xy 218.002929 -206.075269)
			(xy 217.957079 -206.045803) (xy 217.915888 -206.010112) (xy 217.880197 -205.968921) (xy 217.850731 -205.923071)
			(xy 217.828089 -205.873494) (xy 217.812734 -205.821199) (xy 217.804978 -205.767251) (xy 217.804492 -205.74)
			(xy 217.804964 -205.712936) (xy 217.812613 -205.659352) (xy 217.827756 -205.607386) (xy 217.85009 -205.558082)
			(xy 217.879167 -205.512428) (xy 217.89644 -205.491588) (xy 217.901087 -205.485865) (xy 217.907166 -205.472443)
			(xy 217.908378 -205.465172) (xy 217.909394 -205.458314) (xy 217.908378 -205.451456) (xy 217.907801 -205.447912)
			(xy 217.90576 -205.441027) (xy 217.904314 -205.43774) (xy 217.865706 -205.353412) (xy 217.861356 -205.34486)
			(xy 217.847547 -205.33156) (xy 217.829819 -205.324261) (xy 217.82024 -205.323694) (xy 208.23301 -205.323694)
			(xy 208.222926 -205.324113) (xy 208.204316 -205.331878) (xy 208.190163 -205.346242) (xy 208.18602 -205.355444)
			(xy 208.150714 -205.443328) (xy 208.148136 -205.450464) (xy 208.146848 -205.465575) (xy 208.148174 -205.473046)
			(xy 208.149698 -205.480158) (xy 208.157064 -205.493112) (xy 208.162906 -205.4987) (xy 208.181147 -205.516765)
			(xy 208.213112 -205.556938) (xy 208.239404 -205.601032) (xy 208.25955 -205.648252) (xy 208.273187 -205.697746)
			(xy 208.280068 -205.748621) (xy 208.280508 -205.77429) (xy 208.280022 -205.801541) (xy 208.272266 -205.855489)
			(xy 208.256911 -205.907784) (xy 208.234269 -205.957361) (xy 208.204803 -206.003211) (xy 208.169112 -206.044402)
			(xy 208.127921 -206.080093) (xy 208.082071 -206.109559) (xy 208.032494 -206.132201) (xy 207.980199 -206.147556)
			(xy 207.926251 -206.155312) (xy 207.871749 -206.155312) (xy 207.817801 -206.147556) (xy 207.765506 -206.132201)
			(xy 207.715929 -206.109559) (xy 207.670079 -206.080093) (xy 207.628888 -206.044402) (xy 207.593197 -206.003211)
			(xy 207.563731 -205.957361) (xy 207.541089 -205.907784) (xy 207.525734 -205.855489) (xy 207.517978 -205.801541)
			(xy 207.517492 -205.77429) (xy 207.51791 -205.74862) (xy 207.524793 -205.697744) (xy 207.538433 -205.648249)
			(xy 207.558584 -205.60103) (xy 207.584883 -205.556937) (xy 207.616855 -205.516768) (xy 207.635094 -205.4987)
			(xy 207.635348 -205.498446) (xy 207.640593 -205.493093) (xy 207.647953 -205.480048) (xy 207.649826 -205.472792)
			(xy 207.65135 -205.465426) (xy 207.650842 -205.45806) (xy 207.650455 -205.454273) (xy 207.648669 -205.446874)
			(xy 207.647286 -205.443328) (xy 207.61198 -205.355444) (xy 207.607785 -205.346285) (xy 207.593618 -205.331985)
			(xy 207.575053 -205.324203) (xy 207.56499 -205.323694) (xy 206.771748 -205.323694) (xy 206.762569 -205.324725)
			(xy 206.745806 -205.332447) (xy 206.732883 -205.345624) (xy 206.728822 -205.35392) (xy 206.690976 -205.438756)
			(xy 206.690722 -205.439264) (xy 206.688123 -205.445926) (xy 206.686312 -205.460105) (xy 206.687166 -205.467204)
			(xy 206.688182 -205.474316) (xy 206.694532 -205.487524) (xy 206.699612 -205.493112) (xy 206.717925 -205.514225)
			(xy 206.748816 -205.560801) (xy 206.772584 -205.611385) (xy 206.788721 -205.664893) (xy 206.796882 -205.720184)
			(xy 206.797402 -205.748128) (xy 206.796916 -205.775379) (xy 206.78916 -205.829327) (xy 206.773805 -205.881622)
			(xy 206.751163 -205.931199) (xy 206.721697 -205.977049) (xy 206.686006 -206.01824) (xy 206.644815 -206.053931)
			(xy 206.598965 -206.083397) (xy 206.549388 -206.106039) (xy 206.497093 -206.121394) (xy 206.443145 -206.12915)
			(xy 206.388643 -206.12915) (xy 206.334695 -206.121394) (xy 206.2824 -206.106039) (xy 206.232823 -206.083397)
			(xy 206.186973 -206.053931) (xy 206.145782 -206.01824) (xy 206.110091 -205.977049) (xy 206.080625 -205.931199)
			(xy 206.057983 -205.881622) (xy 206.042628 -205.829327) (xy 206.034872 -205.775379) (xy 206.034386 -205.748128)
			(xy 206.034873 -205.720181) (xy 206.043029 -205.664886) (xy 206.059169 -205.611374) (xy 206.082948 -205.560792)
			(xy 206.113856 -205.514222) (xy 206.132176 -205.493112) (xy 206.137256 -205.487524) (xy 206.143606 -205.474316)
			(xy 206.144622 -205.467204) (xy 206.145499 -205.460103) (xy 206.143703 -205.445915) (xy 206.141066 -205.439264)
			(xy 206.140812 -205.438756) (xy 206.102966 -205.35392) (xy 206.098868 -205.345651) (xy 206.085935 -205.332507)
			(xy 206.069207 -205.324748) (xy 206.06004 -205.323694) (xy 200.835006 -205.323694) (xy 200.826812 -205.324002)
			(xy 200.811264 -205.329182) (xy 200.804526 -205.333854) (xy 200.798938 -205.33868) (xy 200.209658 -205.92796)
			(xy 200.204611 -205.932754) (xy 200.192498 -205.939599) (xy 200.185782 -205.941422) (xy 200.176638 -205.94447)
			(xy 200.172503 -205.946467) (xy 200.164958 -205.951698) (xy 200.161652 -205.954884) (xy 199.827642 -206.288894)
			(xy 213.358982 -206.288894) (xy 213.363053 -206.233272) (xy 213.375179 -206.178835) (xy 213.395102 -206.126744)
			(xy 213.422398 -206.078109) (xy 213.456484 -206.033966) (xy 213.496633 -205.995257) (xy 213.541991 -205.962806)
			(xy 213.591591 -205.937305) (xy 213.644375 -205.919298) (xy 213.699218 -205.909168) (xy 213.754952 -205.907131)
			(xy 213.810389 -205.913231) (xy 213.864346 -205.927337) (xy 213.915675 -205.949149) (xy 213.963281 -205.978203)
			(xy 214.006149 -206.013878) (xy 214.043366 -206.055415) (xy 214.074139 -206.101928) (xy 214.097811 -206.152425)
			(xy 214.113879 -206.205832) (xy 214.121999 -206.261008) (xy 214.122508 -206.288894) (xy 214.121999 -206.31678)
			(xy 214.113879 -206.371956) (xy 214.097811 -206.425363) (xy 214.074139 -206.47586) (xy 214.043366 -206.522373)
			(xy 214.006149 -206.56391) (xy 213.963281 -206.599585) (xy 213.915675 -206.628639) (xy 213.864346 -206.650451)
			(xy 213.810389 -206.664557) (xy 213.754952 -206.670657) (xy 213.699218 -206.66862) (xy 213.644375 -206.65849)
			(xy 213.591591 -206.640483) (xy 213.541991 -206.614982) (xy 213.496633 -206.582531) (xy 213.456484 -206.543822)
			(xy 213.422398 -206.499679) (xy 213.395102 -206.451044) (xy 213.375179 -206.398953) (xy 213.363053 -206.344516)
			(xy 213.358982 -206.288894) (xy 199.827642 -206.288894) (xy 199.360536 -206.756) (xy 206.259174 -206.756)
			(xy 206.263245 -206.700378) (xy 206.275371 -206.645941) (xy 206.295294 -206.59385) (xy 206.32259 -206.545215)
			(xy 206.356676 -206.501072) (xy 206.396825 -206.462363) (xy 206.442183 -206.429912) (xy 206.491783 -206.404411)
			(xy 206.544567 -206.386404) (xy 206.59941 -206.376274) (xy 206.655144 -206.374237) (xy 206.710581 -206.380337)
			(xy 206.764538 -206.394443) (xy 206.815867 -206.416255) (xy 206.863473 -206.445309) (xy 206.906341 -206.480984)
			(xy 206.943558 -206.522521) (xy 206.974331 -206.569034) (xy 206.998003 -206.619531) (xy 207.014071 -206.672938)
			(xy 207.022191 -206.728114) (xy 207.0227 -206.756) (xy 207.516982 -206.756) (xy 207.521053 -206.700378)
			(xy 207.533179 -206.645941) (xy 207.553102 -206.59385) (xy 207.580398 -206.545215) (xy 207.614484 -206.501072)
			(xy 207.654633 -206.462363) (xy 207.699991 -206.429912) (xy 207.749591 -206.404411) (xy 207.802375 -206.386404)
			(xy 207.857218 -206.376274) (xy 207.912952 -206.374237) (xy 207.968389 -206.380337) (xy 208.022346 -206.394443)
			(xy 208.073675 -206.416255) (xy 208.121281 -206.445309) (xy 208.164149 -206.480984) (xy 208.201366 -206.522521)
			(xy 208.232139 -206.569034) (xy 208.255811 -206.619531) (xy 208.271879 -206.672938) (xy 208.279999 -206.728114)
			(xy 208.280508 -206.756) (xy 208.279999 -206.783886) (xy 208.271879 -206.839062) (xy 208.25866 -206.883)
			(xy 209.040982 -206.883) (xy 209.045053 -206.827378) (xy 209.057179 -206.772941) (xy 209.077102 -206.72085)
			(xy 209.104398 -206.672215) (xy 209.138484 -206.628072) (xy 209.178633 -206.589363) (xy 209.223991 -206.556912)
			(xy 209.273591 -206.531411) (xy 209.326375 -206.513404) (xy 209.381218 -206.503274) (xy 209.436952 -206.501237)
			(xy 209.492389 -206.507337) (xy 209.546346 -206.521443) (xy 209.597675 -206.543255) (xy 209.645281 -206.572309)
			(xy 209.688149 -206.607984) (xy 209.725366 -206.649521) (xy 209.756139 -206.696034) (xy 209.779811 -206.746531)
			(xy 209.795879 -206.799938) (xy 209.803999 -206.855114) (xy 209.804508 -206.883) (xy 209.803999 -206.910886)
			(xy 209.795879 -206.966062) (xy 209.779811 -207.019469) (xy 209.756139 -207.069966) (xy 209.725366 -207.116479)
			(xy 209.688149 -207.158016) (xy 209.645281 -207.193691) (xy 209.597675 -207.222745) (xy 209.546346 -207.244557)
			(xy 209.492389 -207.258663) (xy 209.436952 -207.264763) (xy 209.381218 -207.262726) (xy 209.326375 -207.252596)
			(xy 209.273591 -207.234589) (xy 209.223991 -207.209088) (xy 209.178633 -207.176637) (xy 209.138484 -207.137928)
			(xy 209.104398 -207.093785) (xy 209.077102 -207.04515) (xy 209.057179 -206.993059) (xy 209.045053 -206.938622)
			(xy 209.040982 -206.883) (xy 208.25866 -206.883) (xy 208.255811 -206.892469) (xy 208.232139 -206.942966)
			(xy 208.201366 -206.989479) (xy 208.164149 -207.031016) (xy 208.121281 -207.066691) (xy 208.073675 -207.095745)
			(xy 208.022346 -207.117557) (xy 207.968389 -207.131663) (xy 207.912952 -207.137763) (xy 207.857218 -207.135726)
			(xy 207.802375 -207.125596) (xy 207.749591 -207.107589) (xy 207.699991 -207.082088) (xy 207.654633 -207.049637)
			(xy 207.614484 -207.010928) (xy 207.580398 -206.966785) (xy 207.553102 -206.91815) (xy 207.533179 -206.866059)
			(xy 207.521053 -206.811622) (xy 207.516982 -206.756) (xy 207.0227 -206.756) (xy 207.022191 -206.783886)
			(xy 207.014071 -206.839062) (xy 206.998003 -206.892469) (xy 206.974331 -206.942966) (xy 206.943558 -206.989479)
			(xy 206.906341 -207.031016) (xy 206.863473 -207.066691) (xy 206.815867 -207.095745) (xy 206.764538 -207.117557)
			(xy 206.710581 -207.131663) (xy 206.655144 -207.137763) (xy 206.59941 -207.135726) (xy 206.544567 -207.125596)
			(xy 206.491783 -207.107589) (xy 206.442183 -207.082088) (xy 206.396825 -207.049637) (xy 206.356676 -207.010928)
			(xy 206.32259 -206.966785) (xy 206.295294 -206.91815) (xy 206.275371 -206.866059) (xy 206.263245 -206.811622)
			(xy 206.259174 -206.756) (xy 199.360536 -206.756) (xy 198.37527 -207.741266) (xy 207.350612 -207.741266)
			(xy 207.354683 -207.685644) (xy 207.366809 -207.631207) (xy 207.386732 -207.579116) (xy 207.414028 -207.530481)
			(xy 207.448114 -207.486338) (xy 207.488263 -207.447629) (xy 207.533621 -207.415178) (xy 207.583221 -207.389677)
			(xy 207.636005 -207.37167) (xy 207.690848 -207.36154) (xy 207.746582 -207.359503) (xy 207.802019 -207.365603)
			(xy 207.855976 -207.379709) (xy 207.907305 -207.401521) (xy 207.954911 -207.430575) (xy 207.997779 -207.46625)
			(xy 208.034996 -207.507787) (xy 208.065769 -207.5543) (xy 208.089441 -207.604797) (xy 208.101536 -207.645)
			(xy 215.391492 -207.645) (xy 215.39196 -207.61763) (xy 215.399778 -207.563451) (xy 215.415266 -207.510948)
			(xy 215.438108 -207.461201) (xy 215.467831 -207.415234) (xy 215.485472 -207.394302) (xy 215.491568 -207.38719)
			(xy 215.494616 -207.378808) (xy 215.496142 -207.374522) (xy 215.497797 -207.365576) (xy 215.497918 -207.361028)
			(xy 215.497918 -207.293972) (xy 215.49781 -207.289423) (xy 215.496145 -207.280478) (xy 215.494616 -207.276192)
			(xy 215.491568 -207.26781) (xy 215.485472 -207.260698) (xy 215.467829 -207.239766) (xy 215.438101 -207.193799)
			(xy 215.415253 -207.144053) (xy 215.399755 -207.091551) (xy 215.391925 -207.037371) (xy 215.391925 -206.982629)
			(xy 215.399755 -206.928449) (xy 215.415253 -206.875947) (xy 215.438101 -206.826201) (xy 215.467829 -206.780234)
			(xy 215.485472 -206.759302) (xy 215.491568 -206.75219) (xy 215.494616 -206.743808) (xy 215.496142 -206.739522)
			(xy 215.497797 -206.730576) (xy 215.497918 -206.726028) (xy 215.497918 -206.658972) (xy 215.49781 -206.654423)
			(xy 215.496145 -206.645478) (xy 215.494616 -206.641192) (xy 215.491568 -206.63281) (xy 215.485472 -206.625698)
			(xy 215.467814 -206.604781) (xy 215.438106 -206.558804) (xy 215.415274 -206.509052) (xy 215.399787 -206.456548)
			(xy 215.391964 -206.40237) (xy 215.391492 -206.375) (xy 215.391978 -206.347749) (xy 215.399734 -206.293801)
			(xy 215.415089 -206.241506) (xy 215.437731 -206.191929) (xy 215.467197 -206.146079) (xy 215.502888 -206.104888)
			(xy 215.544079 -206.069197) (xy 215.589929 -206.039731) (xy 215.639506 -206.017089) (xy 215.691801 -206.001734)
			(xy 215.745749 -205.993978) (xy 215.800251 -205.993978) (xy 215.854199 -206.001734) (xy 215.906494 -206.017089)
			(xy 215.956071 -206.039731) (xy 216.001921 -206.069197) (xy 216.043112 -206.104888) (xy 216.078803 -206.146079)
			(xy 216.108269 -206.191929) (xy 216.128541 -206.236316) (xy 231.701846 -206.236316) (xy 231.705917 -206.180694)
			(xy 231.718043 -206.126257) (xy 231.737966 -206.074166) (xy 231.765262 -206.025531) (xy 231.799348 -205.981388)
			(xy 231.839497 -205.942679) (xy 231.884855 -205.910228) (xy 231.934455 -205.884727) (xy 231.987239 -205.86672)
			(xy 232.042082 -205.85659) (xy 232.097816 -205.854553) (xy 232.153253 -205.860653) (xy 232.20721 -205.874759)
			(xy 232.258539 -205.896571) (xy 232.306145 -205.925625) (xy 232.349013 -205.9613) (xy 232.38623 -206.002837)
			(xy 232.417003 -206.04935) (xy 232.434517 -206.08671) (xy 232.739944 -206.08671) (xy 232.744015 -206.031088)
			(xy 232.756141 -205.976651) (xy 232.776064 -205.92456) (xy 232.80336 -205.875925) (xy 232.837446 -205.831782)
			(xy 232.877595 -205.793073) (xy 232.922953 -205.760622) (xy 232.972553 -205.735121) (xy 233.025337 -205.717114)
			(xy 233.08018 -205.706984) (xy 233.135914 -205.704947) (xy 233.191351 -205.711047) (xy 233.245308 -205.725153)
			(xy 233.296637 -205.746965) (xy 233.344243 -205.776019) (xy 233.387111 -205.811694) (xy 233.424328 -205.853231)
			(xy 233.455101 -205.899744) (xy 233.478773 -205.950241) (xy 233.489264 -205.98511) (xy 233.752642 -205.98511)
			(xy 233.756713 -205.929488) (xy 233.768839 -205.875051) (xy 233.788762 -205.82296) (xy 233.816058 -205.774325)
			(xy 233.850144 -205.730182) (xy 233.890293 -205.691473) (xy 233.935651 -205.659022) (xy 233.985251 -205.633521)
			(xy 234.038035 -205.615514) (xy 234.092878 -205.605384) (xy 234.148612 -205.603347) (xy 234.204049 -205.609447)
			(xy 234.258006 -205.623553) (xy 234.309335 -205.645365) (xy 234.356941 -205.674419) (xy 234.399809 -205.710094)
			(xy 234.437026 -205.751631) (xy 234.467799 -205.798144) (xy 234.491471 -205.848641) (xy 234.507539 -205.902048)
			(xy 234.515659 -205.957224) (xy 234.516168 -205.98511) (xy 234.515659 -206.012996) (xy 234.507539 -206.068172)
			(xy 234.491471 -206.121579) (xy 234.467799 -206.172076) (xy 234.437026 -206.218589) (xy 234.399809 -206.260126)
			(xy 234.356941 -206.295801) (xy 234.309335 -206.324855) (xy 234.258006 -206.346667) (xy 234.204049 -206.360773)
			(xy 234.148612 -206.366873) (xy 234.092878 -206.364836) (xy 234.038035 -206.354706) (xy 233.985251 -206.336699)
			(xy 233.935651 -206.311198) (xy 233.890293 -206.278747) (xy 233.850144 -206.240038) (xy 233.816058 -206.195895)
			(xy 233.788762 -206.14726) (xy 233.768839 -206.095169) (xy 233.756713 -206.040732) (xy 233.752642 -205.98511)
			(xy 233.489264 -205.98511) (xy 233.494841 -206.003648) (xy 233.502961 -206.058824) (xy 233.50347 -206.08671)
			(xy 233.502961 -206.114596) (xy 233.494841 -206.169772) (xy 233.478773 -206.223179) (xy 233.455101 -206.273676)
			(xy 233.424328 -206.320189) (xy 233.387111 -206.361726) (xy 233.344243 -206.397401) (xy 233.296637 -206.426455)
			(xy 233.245308 -206.448267) (xy 233.191351 -206.462373) (xy 233.135914 -206.468473) (xy 233.08018 -206.466436)
			(xy 233.025337 -206.456306) (xy 232.972553 -206.438299) (xy 232.922953 -206.412798) (xy 232.877595 -206.380347)
			(xy 232.837446 -206.341638) (xy 232.80336 -206.297495) (xy 232.776064 -206.24886) (xy 232.756141 -206.196769)
			(xy 232.744015 -206.142332) (xy 232.739944 -206.08671) (xy 232.434517 -206.08671) (xy 232.440675 -206.099847)
			(xy 232.456743 -206.153254) (xy 232.464863 -206.20843) (xy 232.465372 -206.236316) (xy 232.464863 -206.264202)
			(xy 232.456743 -206.319378) (xy 232.440675 -206.372785) (xy 232.417003 -206.423282) (xy 232.38623 -206.469795)
			(xy 232.349013 -206.511332) (xy 232.306145 -206.547007) (xy 232.258539 -206.576061) (xy 232.20721 -206.597873)
			(xy 232.153253 -206.611979) (xy 232.097816 -206.618079) (xy 232.042082 -206.616042) (xy 231.987239 -206.605912)
			(xy 231.934455 -206.587905) (xy 231.884855 -206.562404) (xy 231.839497 -206.529953) (xy 231.799348 -206.491244)
			(xy 231.765262 -206.447101) (xy 231.737966 -206.398466) (xy 231.718043 -206.346375) (xy 231.705917 -206.291938)
			(xy 231.701846 -206.236316) (xy 216.128541 -206.236316) (xy 216.130911 -206.241506) (xy 216.146266 -206.293801)
			(xy 216.154022 -206.347749) (xy 216.154508 -206.375) (xy 216.15404 -206.40237) (xy 216.146222 -206.456549)
			(xy 216.130734 -206.509052) (xy 216.107892 -206.558799) (xy 216.078169 -206.604766) (xy 216.060528 -206.625698)
			(xy 216.054432 -206.63281) (xy 216.051384 -206.641192) (xy 216.049858 -206.645478) (xy 216.048203 -206.654424)
			(xy 216.048082 -206.658972) (xy 216.048082 -206.726028) (xy 216.04819 -206.730577) (xy 216.049855 -206.739522)
			(xy 216.051384 -206.743808) (xy 216.054432 -206.75219) (xy 216.057698 -206.756) (xy 217.803982 -206.756)
			(xy 217.808053 -206.700378) (xy 217.820179 -206.645941) (xy 217.840102 -206.59385) (xy 217.867398 -206.545215)
			(xy 217.901484 -206.501072) (xy 217.941633 -206.462363) (xy 217.986991 -206.429912) (xy 218.036591 -206.404411)
			(xy 218.089375 -206.386404) (xy 218.144218 -206.376274) (xy 218.199952 -206.374237) (xy 218.255389 -206.380337)
			(xy 218.309346 -206.394443) (xy 218.360675 -206.416255) (xy 218.408281 -206.445309) (xy 218.451149 -206.480984)
			(xy 218.488366 -206.522521) (xy 218.519139 -206.569034) (xy 218.542811 -206.619531) (xy 218.558879 -206.672938)
			(xy 218.566999 -206.728114) (xy 218.567508 -206.756) (xy 218.566999 -206.783886) (xy 218.558879 -206.839062)
			(xy 218.542811 -206.892469) (xy 218.519139 -206.942966) (xy 218.488366 -206.989479) (xy 218.451149 -207.031016)
			(xy 218.408281 -207.066691) (xy 218.360675 -207.095745) (xy 218.309346 -207.117557) (xy 218.255389 -207.131663)
			(xy 218.199952 -207.137763) (xy 218.144218 -207.135726) (xy 218.089375 -207.125596) (xy 218.036591 -207.107589)
			(xy 217.986991 -207.082088) (xy 217.941633 -207.049637) (xy 217.901484 -207.010928) (xy 217.867398 -206.966785)
			(xy 217.840102 -206.91815) (xy 217.820179 -206.866059) (xy 217.808053 -206.811622) (xy 217.803982 -206.756)
			(xy 216.057698 -206.756) (xy 216.060528 -206.759302) (xy 216.078171 -206.780234) (xy 216.107899 -206.826201)
			(xy 216.130747 -206.875947) (xy 216.146245 -206.928449) (xy 216.154075 -206.982629) (xy 216.154075 -207.037371)
			(xy 216.146245 -207.091551) (xy 216.130747 -207.144053) (xy 216.107899 -207.193799) (xy 216.078171 -207.239766)
			(xy 216.060528 -207.260698) (xy 216.054432 -207.26781) (xy 216.051384 -207.276192) (xy 216.049858 -207.280478)
			(xy 216.048203 -207.289424) (xy 216.048082 -207.293972) (xy 216.048082 -207.361028) (xy 216.04819 -207.365577)
			(xy 216.049855 -207.374522) (xy 216.051384 -207.378808) (xy 216.054432 -207.38719) (xy 216.060528 -207.394302)
			(xy 216.078186 -207.415219) (xy 216.107894 -207.461196) (xy 216.130726 -207.510948) (xy 216.146213 -207.563452)
			(xy 216.154036 -207.61763) (xy 216.154508 -207.645) (xy 216.154022 -207.672251) (xy 216.146266 -207.726199)
			(xy 216.132818 -207.772) (xy 217.803982 -207.772) (xy 217.808053 -207.716378) (xy 217.820179 -207.661941)
			(xy 217.840102 -207.60985) (xy 217.867398 -207.561215) (xy 217.901484 -207.517072) (xy 217.941633 -207.478363)
			(xy 217.986991 -207.445912) (xy 218.036591 -207.420411) (xy 218.089375 -207.402404) (xy 218.144218 -207.392274)
			(xy 218.199952 -207.390237) (xy 218.255389 -207.396337) (xy 218.309346 -207.410443) (xy 218.33233 -207.42021)
			(xy 221.283782 -207.42021) (xy 221.287853 -207.364588) (xy 221.299979 -207.310151) (xy 221.319902 -207.25806)
			(xy 221.347198 -207.209425) (xy 221.381284 -207.165282) (xy 221.421433 -207.126573) (xy 221.466791 -207.094122)
			(xy 221.516391 -207.068621) (xy 221.569175 -207.050614) (xy 221.624018 -207.040484) (xy 221.679752 -207.038447)
			(xy 221.735189 -207.044547) (xy 221.789146 -207.058653) (xy 221.840475 -207.080465) (xy 221.888081 -207.109519)
			(xy 221.930949 -207.145194) (xy 221.968166 -207.186731) (xy 221.998939 -207.233244) (xy 222.022611 -207.283741)
			(xy 222.038679 -207.337148) (xy 222.046799 -207.392324) (xy 222.047308 -207.42021) (xy 222.046799 -207.448096)
			(xy 222.038679 -207.503272) (xy 222.031104 -207.528451) (xy 234.626891 -207.528451) (xy 234.626891 -207.473949)
			(xy 234.634648 -207.420002) (xy 234.650003 -207.367708) (xy 234.672644 -207.318132) (xy 234.702111 -207.272283)
			(xy 234.737802 -207.231094) (xy 234.778992 -207.195403) (xy 234.824843 -207.165938) (xy 234.87442 -207.143299)
			(xy 234.926714 -207.127945) (xy 234.980661 -207.12019) (xy 235.007912 -207.119728) (xy 235.033833 -207.120178)
			(xy 235.085195 -207.127211) (xy 235.135133 -207.141131) (xy 235.182727 -207.161682) (xy 235.227101 -207.188487)
			(xy 235.267439 -207.221051) (xy 235.285534 -207.239616) (xy 235.292646 -207.246982) (xy 235.301536 -207.251046)
			(xy 235.30619 -207.253034) (xy 235.316041 -207.255343) (xy 235.321094 -207.255618) (xy 235.392722 -207.257904)
			(xy 235.397794 -207.257894) (xy 235.407777 -207.256108) (xy 235.412534 -207.254348) (xy 235.421932 -207.250792)
			(xy 235.429298 -207.243934) (xy 235.450631 -207.224563) (xy 235.498058 -207.191837) (xy 235.549869 -207.166619)
			(xy 235.604885 -207.149485) (xy 235.661853 -207.140825) (xy 235.690664 -207.140302) (xy 235.717919 -207.140742)
			(xy 235.771876 -207.148495) (xy 235.824179 -207.163849) (xy 235.873765 -207.18649) (xy 235.919624 -207.215958)
			(xy 235.960822 -207.251652) (xy 235.996521 -207.292847) (xy 236.025993 -207.338703) (xy 236.048639 -207.388287)
			(xy 236.063997 -207.440589) (xy 236.071755 -207.494545) (xy 236.071755 -207.549055) (xy 236.063997 -207.603011)
			(xy 236.048639 -207.655313) (xy 236.025993 -207.704897) (xy 235.996521 -207.750753) (xy 235.960822 -207.791948)
			(xy 235.919624 -207.827642) (xy 235.873765 -207.85711) (xy 235.824179 -207.879751) (xy 235.771876 -207.895105)
			(xy 235.717919 -207.902858) (xy 235.690664 -207.903318) (xy 235.664743 -207.902869) (xy 235.613381 -207.895835)
			(xy 235.563444 -207.881913) (xy 235.51585 -207.861361) (xy 235.471476 -207.834557) (xy 235.431138 -207.801994)
			(xy 235.413042 -207.78343) (xy 235.40593 -207.776064) (xy 235.39704 -207.772) (xy 235.39239 -207.770003)
			(xy 235.382536 -207.7677) (xy 235.377482 -207.767428) (xy 235.305854 -207.765142) (xy 235.300781 -207.765133)
			(xy 235.290796 -207.766926) (xy 235.286042 -207.768698) (xy 235.276644 -207.772254) (xy 235.269278 -207.779112)
			(xy 235.247921 -207.798455) (xy 235.200499 -207.831183) (xy 235.148694 -207.856405) (xy 235.093684 -207.873546)
			(xy 235.036721 -207.882216) (xy 235.007912 -207.882744) (xy 234.980661 -207.88221) (xy 234.926714 -207.874455)
			(xy 234.87442 -207.859101) (xy 234.824843 -207.836462) (xy 234.778992 -207.806997) (xy 234.737802 -207.771306)
			(xy 234.702111 -207.730117) (xy 234.672644 -207.684268) (xy 234.650003 -207.634692) (xy 234.634648 -207.582398)
			(xy 234.626891 -207.528451) (xy 222.031104 -207.528451) (xy 222.022611 -207.556679) (xy 221.998939 -207.607176)
			(xy 221.968166 -207.653689) (xy 221.930949 -207.695226) (xy 221.888081 -207.730901) (xy 221.840475 -207.759955)
			(xy 221.789146 -207.781767) (xy 221.735189 -207.795873) (xy 221.679752 -207.801973) (xy 221.624018 -207.799936)
			(xy 221.569175 -207.789806) (xy 221.516391 -207.771799) (xy 221.466791 -207.746298) (xy 221.421433 -207.713847)
			(xy 221.381284 -207.675138) (xy 221.347198 -207.630995) (xy 221.319902 -207.58236) (xy 221.299979 -207.530269)
			(xy 221.287853 -207.475832) (xy 221.283782 -207.42021) (xy 218.33233 -207.42021) (xy 218.360675 -207.432255)
			(xy 218.408281 -207.461309) (xy 218.451149 -207.496984) (xy 218.488366 -207.538521) (xy 218.519139 -207.585034)
			(xy 218.542811 -207.635531) (xy 218.558879 -207.688938) (xy 218.566999 -207.744114) (xy 218.567508 -207.772)
			(xy 218.566999 -207.799886) (xy 218.558879 -207.855062) (xy 218.542811 -207.908469) (xy 218.519139 -207.958966)
			(xy 218.492602 -207.999076) (xy 241.351814 -207.999076) (xy 241.355885 -207.943454) (xy 241.368011 -207.889017)
			(xy 241.387934 -207.836926) (xy 241.41523 -207.788291) (xy 241.449316 -207.744148) (xy 241.489465 -207.705439)
			(xy 241.534823 -207.672988) (xy 241.584423 -207.647487) (xy 241.637207 -207.62948) (xy 241.69205 -207.61935)
			(xy 241.747784 -207.617313) (xy 241.803221 -207.623413) (xy 241.857178 -207.637519) (xy 241.908507 -207.659331)
			(xy 241.956113 -207.688385) (xy 241.998981 -207.72406) (xy 242.036198 -207.765597) (xy 242.066971 -207.81211)
			(xy 242.090643 -207.862607) (xy 242.106711 -207.916014) (xy 242.114831 -207.97119) (xy 242.11534 -207.999076)
			(xy 242.115029 -208.016094) (xy 244.483126 -208.016094) (xy 244.487197 -207.960472) (xy 244.499323 -207.906035)
			(xy 244.519246 -207.853944) (xy 244.546542 -207.805309) (xy 244.580628 -207.761166) (xy 244.620777 -207.722457)
			(xy 244.666135 -207.690006) (xy 244.715735 -207.664505) (xy 244.768519 -207.646498) (xy 244.823362 -207.636368)
			(xy 244.879096 -207.634331) (xy 244.934533 -207.640431) (xy 244.98849 -207.654537) (xy 245.036579 -207.674972)
			(xy 248.278904 -207.674972) (xy 248.279353 -207.647263) (xy 248.287362 -207.592428) (xy 248.303221 -207.539329)
			(xy 248.326598 -207.489084) (xy 248.357 -207.442751) (xy 248.393786 -207.401304) (xy 248.436183 -207.365617)
			(xy 248.483297 -207.336441) (xy 248.50852 -207.32496) (xy 248.520748 -207.319268) (xy 248.541812 -207.302432)
			(xy 248.557734 -207.280668) (xy 248.567402 -207.255495) (xy 248.570142 -207.228669) (xy 248.565763 -207.202061)
			(xy 248.554569 -207.177528) (xy 248.537343 -207.156781) (xy 248.526554 -207.148684) (xy 248.50536 -207.133344)
			(xy 248.467021 -207.097742) (xy 248.433906 -207.057234) (xy 248.406638 -207.012582) (xy 248.385728 -206.964622)
			(xy 248.371567 -206.914254) (xy 248.364422 -206.862424) (xy 248.363994 -206.836264) (xy 248.36448 -206.809013)
			(xy 248.372236 -206.755065) (xy 248.387591 -206.70277) (xy 248.410233 -206.653193) (xy 248.439699 -206.607343)
			(xy 248.47539 -206.566152) (xy 248.516581 -206.530461) (xy 248.562431 -206.500995) (xy 248.612008 -206.478353)
			(xy 248.664303 -206.462998) (xy 248.718251 -206.455242) (xy 248.772753 -206.455242) (xy 248.826701 -206.462998)
			(xy 248.878996 -206.478353) (xy 248.928573 -206.500995) (xy 248.974423 -206.530461) (xy 249.015614 -206.566152)
			(xy 249.051305 -206.607343) (xy 249.080771 -206.653193) (xy 249.103413 -206.70277) (xy 249.118768 -206.755065)
			(xy 249.126524 -206.809013) (xy 249.12701 -206.836264) (xy 249.126499 -206.86397) (xy 249.118499 -206.918802)
			(xy 249.102649 -206.9719) (xy 249.079281 -207.022144) (xy 249.048888 -207.068478) (xy 249.01211 -207.109925)
			(xy 248.969721 -207.145614) (xy 248.922614 -207.174793) (xy 248.897394 -207.186276) (xy 248.885216 -207.192064)
			(xy 248.864156 -207.208884) (xy 248.848235 -207.23063) (xy 248.838564 -207.255787) (xy 248.835817 -207.282598)
			(xy 248.838646 -207.299814) (xy 252.699772 -207.299814) (xy 252.703843 -207.244192) (xy 252.715969 -207.189755)
			(xy 252.735892 -207.137664) (xy 252.763188 -207.089029) (xy 252.797274 -207.044886) (xy 252.837423 -207.006177)
			(xy 252.882781 -206.973726) (xy 252.932381 -206.948225) (xy 252.985165 -206.930218) (xy 253.040008 -206.920088)
			(xy 253.095742 -206.918051) (xy 253.151179 -206.924151) (xy 253.205136 -206.938257) (xy 253.256465 -206.960069)
			(xy 253.304071 -206.989123) (xy 253.346939 -207.024798) (xy 253.384156 -207.066335) (xy 253.414929 -207.112848)
			(xy 253.438601 -207.163345) (xy 253.454669 -207.216752) (xy 253.462789 -207.271928) (xy 253.463298 -207.299814)
			(xy 253.462789 -207.3277) (xy 253.454669 -207.382876) (xy 253.438601 -207.436283) (xy 253.414929 -207.48678)
			(xy 253.384156 -207.533293) (xy 253.346939 -207.57483) (xy 253.304071 -207.610505) (xy 253.256465 -207.639559)
			(xy 253.205136 -207.661371) (xy 253.151179 -207.675477) (xy 253.095742 -207.681577) (xy 253.040008 -207.67954)
			(xy 252.985165 -207.66941) (xy 252.932381 -207.651403) (xy 252.882781 -207.625902) (xy 252.837423 -207.593451)
			(xy 252.797274 -207.554742) (xy 252.763188 -207.510599) (xy 252.735892 -207.461964) (xy 252.715969 -207.409873)
			(xy 252.703843 -207.355436) (xy 252.699772 -207.299814) (xy 248.838646 -207.299814) (xy 248.840187 -207.309193)
			(xy 248.851367 -207.333717) (xy 248.868579 -207.354457) (xy 248.87936 -207.362552) (xy 248.900527 -207.377927)
			(xy 248.938867 -207.413524) (xy 248.971982 -207.454026) (xy 248.999254 -207.498672) (xy 249.020169 -207.546626)
			(xy 249.034335 -207.596988) (xy 249.041487 -207.648814) (xy 249.04192 -207.674972) (xy 249.041434 -207.702223)
			(xy 249.033678 -207.756171) (xy 249.018323 -207.808466) (xy 248.995681 -207.858043) (xy 248.966215 -207.903893)
			(xy 248.938542 -207.93583) (xy 250.545344 -207.93583) (xy 250.549415 -207.880208) (xy 250.561541 -207.825771)
			(xy 250.581464 -207.77368) (xy 250.60876 -207.725045) (xy 250.642846 -207.680902) (xy 250.682995 -207.642193)
			(xy 250.728353 -207.609742) (xy 250.777953 -207.584241) (xy 250.830737 -207.566234) (xy 250.88558 -207.556104)
			(xy 250.941314 -207.554067) (xy 250.996751 -207.560167) (xy 251.050708 -207.574273) (xy 251.102037 -207.596085)
			(xy 251.149643 -207.625139) (xy 251.192511 -207.660814) (xy 251.229728 -207.702351) (xy 251.260501 -207.748864)
			(xy 251.284173 -207.799361) (xy 251.300241 -207.852768) (xy 251.308361 -207.907944) (xy 251.30887 -207.93583)
			(xy 251.308361 -207.963716) (xy 251.300241 -208.018892) (xy 251.284173 -208.072299) (xy 251.260501 -208.122796)
			(xy 251.242535 -208.149952) (xy 253.573532 -208.149952) (xy 253.577603 -208.09433) (xy 253.589729 -208.039893)
			(xy 253.609652 -207.987802) (xy 253.636948 -207.939167) (xy 253.671034 -207.895024) (xy 253.711183 -207.856315)
			(xy 253.756541 -207.823864) (xy 253.806141 -207.798363) (xy 253.858925 -207.780356) (xy 253.913768 -207.770226)
			(xy 253.969502 -207.768189) (xy 254.024939 -207.774289) (xy 254.078896 -207.788395) (xy 254.130225 -207.810207)
			(xy 254.177831 -207.839261) (xy 254.220699 -207.874936) (xy 254.257916 -207.916473) (xy 254.288689 -207.962986)
			(xy 254.312361 -208.013483) (xy 254.328429 -208.06689) (xy 254.336549 -208.122066) (xy 254.337058 -208.149952)
			(xy 254.336549 -208.177838) (xy 254.328429 -208.233014) (xy 254.312361 -208.286421) (xy 254.288689 -208.336918)
			(xy 254.257916 -208.383431) (xy 254.220699 -208.424968) (xy 254.177831 -208.460643) (xy 254.130225 -208.489697)
			(xy 254.078896 -208.511509) (xy 254.024939 -208.525615) (xy 253.969502 -208.531715) (xy 253.913768 -208.529678)
			(xy 253.858925 -208.519548) (xy 253.806141 -208.501541) (xy 253.756541 -208.47604) (xy 253.711183 -208.443589)
			(xy 253.671034 -208.40488) (xy 253.636948 -208.360737) (xy 253.609652 -208.312102) (xy 253.589729 -208.260011)
			(xy 253.577603 -208.205574) (xy 253.573532 -208.149952) (xy 251.242535 -208.149952) (xy 251.229728 -208.169309)
			(xy 251.192511 -208.210846) (xy 251.149643 -208.246521) (xy 251.102037 -208.275575) (xy 251.050708 -208.297387)
			(xy 250.996751 -208.311493) (xy 250.941314 -208.317593) (xy 250.88558 -208.315556) (xy 250.830737 -208.305426)
			(xy 250.777953 -208.287419) (xy 250.728353 -208.261918) (xy 250.682995 -208.229467) (xy 250.642846 -208.190758)
			(xy 250.60876 -208.146615) (xy 250.581464 -208.09798) (xy 250.561541 -208.045889) (xy 250.549415 -207.991452)
			(xy 250.545344 -207.93583) (xy 248.938542 -207.93583) (xy 248.930524 -207.945084) (xy 248.889333 -207.980775)
			(xy 248.843483 -208.010241) (xy 248.793906 -208.032883) (xy 248.741611 -208.048238) (xy 248.687663 -208.055994)
			(xy 248.633161 -208.055994) (xy 248.579213 -208.048238) (xy 248.526918 -208.032883) (xy 248.477341 -208.010241)
			(xy 248.431491 -207.980775) (xy 248.3903 -207.945084) (xy 248.354609 -207.903893) (xy 248.325143 -207.858043)
			(xy 248.302501 -207.808466) (xy 248.287146 -207.756171) (xy 248.27939 -207.702223) (xy 248.278904 -207.674972)
			(xy 245.036579 -207.674972) (xy 245.039819 -207.676349) (xy 245.087425 -207.705403) (xy 245.130293 -207.741078)
			(xy 245.16751 -207.782615) (xy 245.198283 -207.829128) (xy 245.221955 -207.879625) (xy 245.238023 -207.933032)
			(xy 245.246143 -207.988208) (xy 245.246652 -208.016094) (xy 245.246143 -208.04398) (xy 245.238023 -208.099156)
			(xy 245.221955 -208.152563) (xy 245.198283 -208.20306) (xy 245.16751 -208.249573) (xy 245.130293 -208.29111)
			(xy 245.087425 -208.326785) (xy 245.039819 -208.355839) (xy 244.98849 -208.377651) (xy 244.934533 -208.391757)
			(xy 244.879096 -208.397857) (xy 244.823362 -208.39582) (xy 244.768519 -208.38569) (xy 244.715735 -208.367683)
			(xy 244.666135 -208.342182) (xy 244.620777 -208.309731) (xy 244.580628 -208.271022) (xy 244.546542 -208.226879)
			(xy 244.519246 -208.178244) (xy 244.499323 -208.126153) (xy 244.487197 -208.071716) (xy 244.483126 -208.016094)
			(xy 242.115029 -208.016094) (xy 242.114831 -208.026962) (xy 242.106711 -208.082138) (xy 242.090643 -208.135545)
			(xy 242.066971 -208.186042) (xy 242.036198 -208.232555) (xy 241.998981 -208.274092) (xy 241.956113 -208.309767)
			(xy 241.908507 -208.338821) (xy 241.857178 -208.360633) (xy 241.803221 -208.374739) (xy 241.747784 -208.380839)
			(xy 241.69205 -208.378802) (xy 241.637207 -208.368672) (xy 241.584423 -208.350665) (xy 241.534823 -208.325164)
			(xy 241.489465 -208.292713) (xy 241.449316 -208.254004) (xy 241.41523 -208.209861) (xy 241.387934 -208.161226)
			(xy 241.368011 -208.109135) (xy 241.355885 -208.054698) (xy 241.351814 -207.999076) (xy 218.492602 -207.999076)
			(xy 218.488366 -208.005479) (xy 218.451149 -208.047016) (xy 218.408281 -208.082691) (xy 218.360675 -208.111745)
			(xy 218.309346 -208.133557) (xy 218.255389 -208.147663) (xy 218.199952 -208.153763) (xy 218.144218 -208.151726)
			(xy 218.089375 -208.141596) (xy 218.036591 -208.123589) (xy 217.986991 -208.098088) (xy 217.941633 -208.065637)
			(xy 217.901484 -208.026928) (xy 217.867398 -207.982785) (xy 217.840102 -207.93415) (xy 217.820179 -207.882059)
			(xy 217.808053 -207.827622) (xy 217.803982 -207.772) (xy 216.132818 -207.772) (xy 216.130911 -207.778494)
			(xy 216.108269 -207.828071) (xy 216.078803 -207.873921) (xy 216.043112 -207.915112) (xy 216.001921 -207.950803)
			(xy 215.956071 -207.980269) (xy 215.906494 -208.002911) (xy 215.854199 -208.018266) (xy 215.800251 -208.026022)
			(xy 215.745749 -208.026022) (xy 215.691801 -208.018266) (xy 215.639506 -208.002911) (xy 215.589929 -207.980269)
			(xy 215.544079 -207.950803) (xy 215.502888 -207.915112) (xy 215.467197 -207.873921) (xy 215.437731 -207.828071)
			(xy 215.415089 -207.778494) (xy 215.399734 -207.726199) (xy 215.391978 -207.672251) (xy 215.391492 -207.645)
			(xy 208.101536 -207.645) (xy 208.105509 -207.658204) (xy 208.113629 -207.71338) (xy 208.114138 -207.741266)
			(xy 208.113629 -207.769152) (xy 208.105509 -207.824328) (xy 208.089441 -207.877735) (xy 208.065769 -207.928232)
			(xy 208.034996 -207.974745) (xy 207.997779 -208.016282) (xy 207.954911 -208.051957) (xy 207.907305 -208.081011)
			(xy 207.855976 -208.102823) (xy 207.802019 -208.116929) (xy 207.746582 -208.123029) (xy 207.690848 -208.120992)
			(xy 207.636005 -208.110862) (xy 207.583221 -208.092855) (xy 207.533621 -208.067354) (xy 207.488263 -208.034903)
			(xy 207.448114 -207.996194) (xy 207.414028 -207.952051) (xy 207.386732 -207.903416) (xy 207.366809 -207.851325)
			(xy 207.354683 -207.796888) (xy 207.350612 -207.741266) (xy 198.37527 -207.741266) (xy 197.52564 -208.590896)
			(xy 248.084338 -208.590896) (xy 248.088409 -208.535274) (xy 248.100535 -208.480837) (xy 248.120458 -208.428746)
			(xy 248.147754 -208.380111) (xy 248.18184 -208.335968) (xy 248.221989 -208.297259) (xy 248.267347 -208.264808)
			(xy 248.316947 -208.239307) (xy 248.369731 -208.2213) (xy 248.424574 -208.21117) (xy 248.480308 -208.209133)
			(xy 248.535745 -208.215233) (xy 248.589702 -208.229339) (xy 248.641031 -208.251151) (xy 248.688637 -208.280205)
			(xy 248.731505 -208.31588) (xy 248.768722 -208.357417) (xy 248.799495 -208.40393) (xy 248.823167 -208.454427)
			(xy 248.839235 -208.507834) (xy 248.847355 -208.56301) (xy 248.847753 -208.5848) (xy 249.122182 -208.5848)
			(xy 249.126253 -208.529178) (xy 249.138379 -208.474741) (xy 249.158302 -208.42265) (xy 249.185598 -208.374015)
			(xy 249.219684 -208.329872) (xy 249.259833 -208.291163) (xy 249.305191 -208.258712) (xy 249.354791 -208.233211)
			(xy 249.407575 -208.215204) (xy 249.462418 -208.205074) (xy 249.518152 -208.203037) (xy 249.573589 -208.209137)
			(xy 249.627546 -208.223243) (xy 249.678875 -208.245055) (xy 249.726481 -208.274109) (xy 249.769349 -208.309784)
			(xy 249.806566 -208.351321) (xy 249.837339 -208.397834) (xy 249.861011 -208.448331) (xy 249.877079 -208.501738)
			(xy 249.885199 -208.556914) (xy 249.885708 -208.5848) (xy 249.885199 -208.612686) (xy 249.877079 -208.667862)
			(xy 249.861011 -208.721269) (xy 249.837339 -208.771766) (xy 249.806566 -208.818279) (xy 249.769349 -208.859816)
			(xy 249.726481 -208.895491) (xy 249.678875 -208.924545) (xy 249.627546 -208.946357) (xy 249.573589 -208.960463)
			(xy 249.518152 -208.966563) (xy 249.462418 -208.964526) (xy 249.407575 -208.954396) (xy 249.354791 -208.936389)
			(xy 249.305191 -208.910888) (xy 249.259833 -208.878437) (xy 249.219684 -208.839728) (xy 249.185598 -208.795585)
			(xy 249.158302 -208.74695) (xy 249.138379 -208.694859) (xy 249.126253 -208.640422) (xy 249.122182 -208.5848)
			(xy 248.847753 -208.5848) (xy 248.847864 -208.590896) (xy 248.847355 -208.618782) (xy 248.839235 -208.673958)
			(xy 248.823167 -208.727365) (xy 248.799495 -208.777862) (xy 248.768722 -208.824375) (xy 248.731505 -208.865912)
			(xy 248.688637 -208.901587) (xy 248.641031 -208.930641) (xy 248.589702 -208.952453) (xy 248.535745 -208.966559)
			(xy 248.480308 -208.972659) (xy 248.424574 -208.970622) (xy 248.369731 -208.960492) (xy 248.316947 -208.942485)
			(xy 248.267347 -208.916984) (xy 248.221989 -208.884533) (xy 248.18184 -208.845824) (xy 248.147754 -208.801681)
			(xy 248.120458 -208.753046) (xy 248.100535 -208.700955) (xy 248.088409 -208.646518) (xy 248.084338 -208.590896)
			(xy 197.52564 -208.590896) (xy 196.983604 -209.132932) (xy 196.978778 -209.13852) (xy 196.974108 -209.14526)
			(xy 196.968924 -209.160806) (xy 196.968618 -209.169) (xy 196.968618 -209.365456) (xy 206.115819 -209.365456)
			(xy 206.115819 -209.310944) (xy 206.123577 -209.256986) (xy 206.138936 -209.204681) (xy 206.161582 -209.155095)
			(xy 206.191055 -209.109237) (xy 206.226754 -209.06804) (xy 206.267953 -209.032343) (xy 206.313813 -209.002872)
			(xy 206.3634 -208.980229) (xy 206.415705 -208.964873) (xy 206.469664 -208.957118) (xy 206.49692 -208.956656)
			(xy 206.522118 -208.957053) (xy 206.572075 -208.963699) (xy 206.620719 -208.976872) (xy 206.667203 -208.996342)
			(xy 206.710714 -209.02177) (xy 206.730854 -209.03692) (xy 206.73822 -209.042508) (xy 206.746856 -209.045302)
			(xy 206.75144 -209.046582) (xy 206.760901 -209.047607) (xy 206.765652 -209.047334) (xy 206.832962 -209.042762)
			(xy 206.837488 -209.042384) (xy 206.846308 -209.040221) (xy 206.850488 -209.038444) (xy 206.85887 -209.034634)
			(xy 206.865474 -209.02803) (xy 206.887125 -209.006922) (xy 206.935847 -208.971118) (xy 206.989609 -208.943449)
			(xy 207.047062 -208.924609) (xy 207.106768 -208.91507) (xy 207.137 -208.914492) (xy 207.164251 -208.914978)
			(xy 207.218199 -208.922734) (xy 207.270494 -208.938089) (xy 207.320071 -208.960731) (xy 207.365921 -208.990197)
			(xy 207.407112 -209.025888) (xy 207.442803 -209.067079) (xy 207.444198 -209.069249) (xy 209.657978 -209.069249)
			(xy 209.657978 -209.014751) (xy 209.665733 -208.960808) (xy 209.681085 -208.908517) (xy 209.703723 -208.858943)
			(xy 209.733185 -208.813095) (xy 209.768871 -208.771906) (xy 209.810055 -208.736215) (xy 209.855899 -208.706747)
			(xy 209.90547 -208.684103) (xy 209.957759 -208.668743) (xy 210.011701 -208.660981) (xy 210.03895 -208.660492)
			(xy 210.065553 -208.660982) (xy 210.118244 -208.668357) (xy 210.169398 -208.682984) (xy 210.218023 -208.70458)
			(xy 210.263174 -208.732725) (xy 210.303974 -208.766873) (xy 210.339632 -208.806361) (xy 210.354926 -208.828132)
			(xy 210.36326 -208.839612) (xy 210.385004 -208.857816) (xy 210.410917 -208.869334) (xy 210.439 -208.873274)
			(xy 210.467083 -208.869334) (xy 210.492996 -208.857816) (xy 210.51474 -208.839612) (xy 210.523074 -208.828132)
			(xy 210.538371 -208.806363) (xy 210.574037 -208.766884) (xy 210.61484 -208.732741) (xy 210.65999 -208.704596)
			(xy 210.708611 -208.682993) (xy 210.759761 -208.668352) (xy 210.812448 -208.660956) (xy 210.83905 -208.660492)
			(xy 210.866305 -208.660952) (xy 210.920262 -208.668703) (xy 210.972565 -208.684055) (xy 211.022152 -208.706694)
			(xy 211.068011 -208.736161) (xy 211.10921 -208.771855) (xy 211.144909 -208.813049) (xy 211.174382 -208.858904)
			(xy 211.197028 -208.908488) (xy 211.212386 -208.96079) (xy 211.220145 -209.014745) (xy 211.220145 -209.069255)
			(xy 211.212386 -209.12321) (xy 211.197028 -209.175512) (xy 211.174382 -209.225096) (xy 211.144909 -209.270951)
			(xy 211.10921 -209.312145) (xy 211.068011 -209.347839) (xy 211.022152 -209.377306) (xy 210.977145 -209.397854)
			(xy 212.189058 -209.397854) (xy 212.193129 -209.342232) (xy 212.205255 -209.287795) (xy 212.225178 -209.235704)
			(xy 212.252474 -209.187069) (xy 212.28656 -209.142926) (xy 212.326709 -209.104217) (xy 212.372067 -209.071766)
			(xy 212.421667 -209.046265) (xy 212.474451 -209.028258) (xy 212.529294 -209.018128) (xy 212.585028 -209.016091)
			(xy 212.640465 -209.022191) (xy 212.694422 -209.036297) (xy 212.745751 -209.058109) (xy 212.793357 -209.087163)
			(xy 212.836225 -209.122838) (xy 212.873442 -209.164375) (xy 212.876838 -209.169508) (xy 215.066878 -209.169508)
			(xy 215.070949 -209.113886) (xy 215.083075 -209.059449) (xy 215.102998 -209.007358) (xy 215.130294 -208.958723)
			(xy 215.16438 -208.91458) (xy 215.204529 -208.875871) (xy 215.249887 -208.84342) (xy 215.299487 -208.817919)
			(xy 215.352271 -208.799912) (xy 215.407114 -208.789782) (xy 215.462848 -208.787745) (xy 215.518285 -208.793845)
			(xy 215.572242 -208.807951) (xy 215.623571 -208.829763) (xy 215.671177 -208.858817) (xy 215.714045 -208.894492)
			(xy 215.751262 -208.936029) (xy 215.782035 -208.982542) (xy 215.805707 -209.033039) (xy 215.821775 -209.086446)
			(xy 215.829895 -209.141622) (xy 215.830404 -209.169508) (xy 215.829895 -209.197394) (xy 215.82585 -209.22488)
			(xy 215.97061 -209.22488) (xy 215.974681 -209.169258) (xy 215.986807 -209.114821) (xy 216.00673 -209.06273)
			(xy 216.034026 -209.014095) (xy 216.068112 -208.969952) (xy 216.108261 -208.931243) (xy 216.153619 -208.898792)
			(xy 216.203219 -208.873291) (xy 216.256003 -208.855284) (xy 216.310846 -208.845154) (xy 216.36658 -208.843117)
			(xy 216.422017 -208.849217) (xy 216.475974 -208.863323) (xy 216.527303 -208.885135) (xy 216.574909 -208.914189)
			(xy 216.617777 -208.949864) (xy 216.654994 -208.991401) (xy 216.685767 -209.037914) (xy 216.709439 -209.088411)
			(xy 216.725507 -209.141818) (xy 216.733627 -209.196994) (xy 216.734136 -209.22488) (xy 216.733627 -209.252766)
			(xy 216.725507 -209.307942) (xy 216.709439 -209.361349) (xy 216.685767 -209.411846) (xy 216.66036 -209.450249)
			(xy 218.420978 -209.450249) (xy 218.420978 -209.395751) (xy 218.428733 -209.341808) (xy 218.444085 -209.289517)
			(xy 218.466723 -209.239943) (xy 218.496185 -209.194095) (xy 218.531871 -209.152906) (xy 218.573055 -209.117215)
			(xy 218.618899 -209.087747) (xy 218.66847 -209.065103) (xy 218.720759 -209.049743) (xy 218.774701 -209.041981)
			(xy 218.80195 -209.041492) (xy 218.828553 -209.041982) (xy 218.881244 -209.049357) (xy 218.932398 -209.063984)
			(xy 218.981023 -209.08558) (xy 219.026174 -209.113725) (xy 219.066974 -209.147873) (xy 219.102632 -209.187361)
			(xy 219.117926 -209.209132) (xy 219.12626 -209.220612) (xy 219.148004 -209.238816) (xy 219.173917 -209.250334)
			(xy 219.202 -209.254274) (xy 219.230083 -209.250334) (xy 219.255996 -209.238816) (xy 219.27774 -209.220612)
			(xy 219.286074 -209.209132) (xy 219.301371 -209.187363) (xy 219.337037 -209.147884) (xy 219.37784 -209.113741)
			(xy 219.42299 -209.085596) (xy 219.471611 -209.063993) (xy 219.522761 -209.049352) (xy 219.575448 -209.041956)
			(xy 219.60205 -209.041492) (xy 219.629305 -209.041952) (xy 219.683262 -209.049703) (xy 219.735565 -209.065055)
			(xy 219.785152 -209.087694) (xy 219.831011 -209.117161) (xy 219.87221 -209.152855) (xy 219.907909 -209.194049)
			(xy 219.937382 -209.239904) (xy 219.960028 -209.289488) (xy 219.975386 -209.34179) (xy 219.983145 -209.395745)
			(xy 219.983145 -209.450255) (xy 219.975386 -209.50421) (xy 219.960028 -209.556512) (xy 219.937382 -209.606096)
			(xy 219.933876 -209.611551) (xy 236.453168 -209.611551) (xy 236.453168 -209.557049) (xy 236.460924 -209.503103)
			(xy 236.476278 -209.450809) (xy 236.498918 -209.401232) (xy 236.528382 -209.355382) (xy 236.564071 -209.314191)
			(xy 236.605259 -209.278499) (xy 236.651107 -209.249031) (xy 236.700682 -209.226388) (xy 236.752975 -209.21103)
			(xy 236.806921 -209.20327) (xy 236.834172 -209.202782) (xy 236.860976 -209.203273) (xy 236.914055 -209.21079)
			(xy 236.965559 -209.225667) (xy 237.014472 -209.247609) (xy 237.05983 -209.276184) (xy 237.100739 -209.31083)
			(xy 237.118906 -209.330544) (xy 237.119668 -209.331306) (xy 237.1217 -209.333592) (xy 237.128323 -209.339451)
			(xy 237.144421 -209.346732) (xy 237.153196 -209.347816) (xy 237.154212 -209.347816) (xy 237.15726 -209.34807)
			(xy 237.23346 -209.34807) (xy 237.236508 -209.347816) (xy 237.237524 -209.347816) (xy 237.246312 -209.346775)
			(xy 237.262425 -209.339493) (xy 237.26902 -209.333592) (xy 237.271052 -209.331306) (xy 237.271814 -209.330544)
			(xy 237.289961 -209.310808) (xy 237.330866 -209.276147) (xy 237.376225 -209.247562) (xy 237.425143 -209.225616)
			(xy 237.476654 -209.210742) (xy 237.52974 -209.203234) (xy 237.556548 -209.202782) (xy 237.583796 -209.203292)
			(xy 237.637737 -209.211053) (xy 237.690025 -209.226412) (xy 237.739595 -209.249055) (xy 237.785438 -209.278522)
			(xy 237.826621 -209.314213) (xy 237.862307 -209.355401) (xy 237.891768 -209.401247) (xy 237.914405 -209.45082)
			(xy 237.929757 -209.50311) (xy 237.933613 -209.529934) (xy 240.342672 -209.529934) (xy 240.346743 -209.474312)
			(xy 240.358869 -209.419875) (xy 240.378792 -209.367784) (xy 240.406088 -209.319149) (xy 240.440174 -209.275006)
			(xy 240.480323 -209.236297) (xy 240.525681 -209.203846) (xy 240.575281 -209.178345) (xy 240.628065 -209.160338)
			(xy 240.682908 -209.150208) (xy 240.738642 -209.148171) (xy 240.794079 -209.154271) (xy 240.848036 -209.168377)
			(xy 240.899365 -209.190189) (xy 240.946971 -209.219243) (xy 240.989839 -209.254918) (xy 241.027056 -209.296455)
			(xy 241.057829 -209.342968) (xy 241.081501 -209.393465) (xy 241.097569 -209.446872) (xy 241.105689 -209.502048)
			(xy 241.106198 -209.529934) (xy 241.105689 -209.55782) (xy 241.097569 -209.612996) (xy 241.081501 -209.666403)
			(xy 241.057829 -209.7169) (xy 241.027056 -209.763413) (xy 240.989839 -209.80495) (xy 240.946971 -209.840625)
			(xy 240.899365 -209.869679) (xy 240.848036 -209.891491) (xy 240.794079 -209.905597) (xy 240.738642 -209.911697)
			(xy 240.682908 -209.90966) (xy 240.628065 -209.89953) (xy 240.575281 -209.881523) (xy 240.525681 -209.856022)
			(xy 240.480323 -209.823571) (xy 240.440174 -209.784862) (xy 240.406088 -209.740719) (xy 240.378792 -209.692084)
			(xy 240.358869 -209.639993) (xy 240.346743 -209.585556) (xy 240.342672 -209.529934) (xy 237.933613 -209.529934)
			(xy 237.937512 -209.557052) (xy 237.937512 -209.611548) (xy 237.929757 -209.66549) (xy 237.914405 -209.71778)
			(xy 237.891768 -209.767353) (xy 237.862307 -209.813199) (xy 237.826621 -209.854387) (xy 237.785438 -209.890078)
			(xy 237.739595 -209.919545) (xy 237.690025 -209.942188) (xy 237.637737 -209.957547) (xy 237.583796 -209.965308)
			(xy 237.556548 -209.965798) (xy 237.529741 -209.965368) (xy 237.476659 -209.957839) (xy 237.425155 -209.942951)
			(xy 237.376242 -209.920998) (xy 237.330886 -209.892411) (xy 237.289979 -209.857755) (xy 237.271814 -209.838036)
			(xy 237.271052 -209.837274) (xy 237.26902 -209.834988) (xy 237.262423 -209.829096) (xy 237.246305 -209.821835)
			(xy 237.237524 -209.820764) (xy 237.236508 -209.820764) (xy 237.23346 -209.82051) (xy 237.15726 -209.82051)
			(xy 237.154212 -209.820764) (xy 237.153196 -209.820764) (xy 237.144411 -209.821819) (xy 237.128297 -209.829092)
			(xy 237.1217 -209.834988) (xy 237.119668 -209.837274) (xy 237.118906 -209.838036) (xy 237.100744 -209.857758)
			(xy 237.059843 -209.892421) (xy 237.014487 -209.921008) (xy 236.965572 -209.942957) (xy 236.914064 -209.957833)
			(xy 236.860979 -209.965344) (xy 236.834172 -209.965798) (xy 236.806921 -209.96533) (xy 236.752975 -209.95757)
			(xy 236.700682 -209.942212) (xy 236.651107 -209.919569) (xy 236.605259 -209.890101) (xy 236.564071 -209.854409)
			(xy 236.528382 -209.813218) (xy 236.498918 -209.767368) (xy 236.476278 -209.717791) (xy 236.460924 -209.665497)
			(xy 236.453168 -209.611551) (xy 219.933876 -209.611551) (xy 219.907909 -209.651951) (xy 219.87221 -209.693145)
			(xy 219.831011 -209.728839) (xy 219.785152 -209.758306) (xy 219.735565 -209.780945) (xy 219.683262 -209.796297)
			(xy 219.629305 -209.804048) (xy 219.60205 -209.804508) (xy 219.575447 -209.804018) (xy 219.522756 -209.796643)
			(xy 219.471602 -209.782016) (xy 219.422977 -209.76042) (xy 219.377826 -209.732275) (xy 219.337026 -209.698127)
			(xy 219.301368 -209.658639) (xy 219.286074 -209.636868) (xy 219.27774 -209.625388) (xy 219.255996 -209.607184)
			(xy 219.230083 -209.595666) (xy 219.202 -209.591726) (xy 219.173917 -209.595666) (xy 219.148004 -209.607184)
			(xy 219.12626 -209.625388) (xy 219.117926 -209.636868) (xy 219.102629 -209.658637) (xy 219.066963 -209.698116)
			(xy 219.02616 -209.732259) (xy 218.98101 -209.760404) (xy 218.932389 -209.782007) (xy 218.881239 -209.796648)
			(xy 218.828552 -209.804044) (xy 218.80195 -209.804508) (xy 218.774701 -209.804019) (xy 218.720759 -209.796257)
			(xy 218.66847 -209.780897) (xy 218.618899 -209.758253) (xy 218.573055 -209.728785) (xy 218.531871 -209.693094)
			(xy 218.496185 -209.651905) (xy 218.466723 -209.606057) (xy 218.444085 -209.556483) (xy 218.428733 -209.504192)
			(xy 218.420978 -209.450249) (xy 216.66036 -209.450249) (xy 216.654994 -209.458359) (xy 216.617777 -209.499896)
			(xy 216.574909 -209.535571) (xy 216.527303 -209.564625) (xy 216.475974 -209.586437) (xy 216.422017 -209.600543)
			(xy 216.36658 -209.606643) (xy 216.310846 -209.604606) (xy 216.256003 -209.594476) (xy 216.203219 -209.576469)
			(xy 216.153619 -209.550968) (xy 216.108261 -209.518517) (xy 216.068112 -209.479808) (xy 216.034026 -209.435665)
			(xy 216.00673 -209.38703) (xy 215.986807 -209.334939) (xy 215.974681 -209.280502) (xy 215.97061 -209.22488)
			(xy 215.82585 -209.22488) (xy 215.821775 -209.25257) (xy 215.805707 -209.305977) (xy 215.782035 -209.356474)
			(xy 215.751262 -209.402987) (xy 215.714045 -209.444524) (xy 215.671177 -209.480199) (xy 215.623571 -209.509253)
			(xy 215.572242 -209.531065) (xy 215.518285 -209.545171) (xy 215.462848 -209.551271) (xy 215.407114 -209.549234)
			(xy 215.352271 -209.539104) (xy 215.299487 -209.521097) (xy 215.249887 -209.495596) (xy 215.204529 -209.463145)
			(xy 215.16438 -209.424436) (xy 215.130294 -209.380293) (xy 215.102998 -209.331658) (xy 215.083075 -209.279567)
			(xy 215.070949 -209.22513) (xy 215.066878 -209.169508) (xy 212.876838 -209.169508) (xy 212.904215 -209.210888)
			(xy 212.927887 -209.261385) (xy 212.943955 -209.314792) (xy 212.952075 -209.369968) (xy 212.952584 -209.397854)
			(xy 212.952075 -209.42574) (xy 212.943955 -209.480916) (xy 212.927887 -209.534323) (xy 212.904215 -209.58482)
			(xy 212.873442 -209.631333) (xy 212.836225 -209.67287) (xy 212.793357 -209.708545) (xy 212.745751 -209.737599)
			(xy 212.694422 -209.759411) (xy 212.640465 -209.773517) (xy 212.585028 -209.779617) (xy 212.529294 -209.77758)
			(xy 212.474451 -209.76745) (xy 212.421667 -209.749443) (xy 212.372067 -209.723942) (xy 212.326709 -209.691491)
			(xy 212.28656 -209.652782) (xy 212.252474 -209.608639) (xy 212.225178 -209.560004) (xy 212.205255 -209.507913)
			(xy 212.193129 -209.453476) (xy 212.189058 -209.397854) (xy 210.977145 -209.397854) (xy 210.972565 -209.399945)
			(xy 210.920262 -209.415297) (xy 210.866305 -209.423048) (xy 210.83905 -209.423508) (xy 210.812447 -209.423018)
			(xy 210.759756 -209.415643) (xy 210.708602 -209.401016) (xy 210.659977 -209.37942) (xy 210.614826 -209.351275)
			(xy 210.574026 -209.317127) (xy 210.538368 -209.277639) (xy 210.523074 -209.255868) (xy 210.51474 -209.244388)
			(xy 210.492996 -209.226184) (xy 210.467083 -209.214666) (xy 210.439 -209.210726) (xy 210.410917 -209.214666)
			(xy 210.385004 -209.226184) (xy 210.36326 -209.244388) (xy 210.354926 -209.255868) (xy 210.339629 -209.277637)
			(xy 210.303963 -209.317116) (xy 210.26316 -209.351259) (xy 210.21801 -209.379404) (xy 210.169389 -209.401007)
			(xy 210.118239 -209.415648) (xy 210.065552 -209.423044) (xy 210.03895 -209.423508) (xy 210.011701 -209.423019)
			(xy 209.957759 -209.415257) (xy 209.90547 -209.399897) (xy 209.855899 -209.377253) (xy 209.810055 -209.347785)
			(xy 209.768871 -209.312094) (xy 209.733185 -209.270905) (xy 209.703723 -209.225057) (xy 209.681085 -209.175483)
			(xy 209.665733 -209.123192) (xy 209.657978 -209.069249) (xy 207.444198 -209.069249) (xy 207.472269 -209.112929)
			(xy 207.494911 -209.162506) (xy 207.510266 -209.214801) (xy 207.518022 -209.268749) (xy 207.518022 -209.323251)
			(xy 207.510266 -209.377199) (xy 207.494911 -209.429494) (xy 207.472269 -209.479071) (xy 207.442803 -209.524921)
			(xy 207.407112 -209.566112) (xy 207.365921 -209.601803) (xy 207.320071 -209.631269) (xy 207.270494 -209.653911)
			(xy 207.218199 -209.669266) (xy 207.164251 -209.677022) (xy 207.137 -209.677508) (xy 207.111802 -209.677108)
			(xy 207.061845 -209.670464) (xy 207.0132 -209.657292) (xy 206.966717 -209.637822) (xy 206.923205 -209.612394)
			(xy 206.903066 -209.597244) (xy 206.8957 -209.591656) (xy 206.887064 -209.588862) (xy 206.882478 -209.587589)
			(xy 206.873019 -209.586559) (xy 206.868268 -209.58683) (xy 206.800958 -209.591402) (xy 206.796429 -209.591754)
			(xy 206.78761 -209.593934) (xy 206.783432 -209.59572) (xy 206.77505 -209.59953) (xy 206.768446 -209.606134)
			(xy 206.74678 -209.627226) (xy 206.698062 -209.663034) (xy 206.644305 -209.690706) (xy 206.586855 -209.70955)
			(xy 206.527151 -209.719093) (xy 206.49692 -209.719672) (xy 206.469664 -209.719282) (xy 206.415705 -209.711527)
			(xy 206.3634 -209.696171) (xy 206.313813 -209.673528) (xy 206.267953 -209.644057) (xy 206.226754 -209.60836)
			(xy 206.191055 -209.567163) (xy 206.161582 -209.521305) (xy 206.138936 -209.471719) (xy 206.123577 -209.419414)
			(xy 206.115819 -209.365456) (xy 196.968618 -209.365456) (xy 196.968618 -209.990436) (xy 242.127532 -209.990436)
			(xy 242.127989 -209.963182) (xy 242.135742 -209.909229) (xy 242.151096 -209.856929) (xy 242.173737 -209.807346)
			(xy 242.203205 -209.761491) (xy 242.238899 -209.720297) (xy 242.280094 -209.684602) (xy 242.325949 -209.655135)
			(xy 242.375532 -209.632494) (xy 242.427833 -209.617141) (xy 242.481786 -209.609389) (xy 242.50904 -209.608928)
			(xy 242.53594 -209.60939) (xy 242.589206 -209.616947) (xy 242.640881 -209.631918) (xy 242.689937 -209.654007)
			(xy 242.7354 -209.682775) (xy 242.756182 -209.69986) (xy 242.763548 -209.70621) (xy 242.772946 -209.709258)
			(xy 242.777504 -209.710686) (xy 242.786968 -209.711963) (xy 242.791742 -209.711798) (xy 242.8621 -209.707734)
			(xy 242.866898 -209.7074) (xy 242.876235 -209.705089) (xy 242.880642 -209.703162) (xy 242.889278 -209.699098)
			(xy 242.896136 -209.691732) (xy 242.914224 -209.673073) (xy 242.954603 -209.640361) (xy 242.99905 -209.613434)
			(xy 243.046742 -209.592793) (xy 243.096795 -209.578819) (xy 243.148282 -209.571771) (xy 243.174266 -209.571336)
			(xy 243.20152 -209.571787) (xy 243.255474 -209.579541) (xy 243.307774 -209.594894) (xy 243.357357 -209.617536)
			(xy 243.403213 -209.647005) (xy 243.444407 -209.6827) (xy 243.480101 -209.723895) (xy 243.509569 -209.769751)
			(xy 243.532209 -209.819335) (xy 243.547562 -209.871636) (xy 243.555314 -209.92559) (xy 243.555774 -209.952844)
			(xy 243.555206 -209.981771) (xy 243.546465 -210.038962) (xy 243.529189 -210.094177) (xy 243.503775 -210.146152)
			(xy 243.470806 -210.193693) (xy 243.431037 -210.235712) (xy 243.38538 -210.271246) (xy 243.334882 -210.299479)
			(xy 243.2807 -210.319764) (xy 243.252498 -210.326224) (xy 243.252244 -210.326224) (xy 243.246174 -210.327779)
			(xy 243.234997 -210.333434) (xy 243.230146 -210.3374) (xy 243.229892 -210.3374) (xy 243.225261 -210.341638)
			(xy 243.218066 -210.351919) (xy 243.215668 -210.35772) (xy 243.184934 -210.437476) (xy 243.182648 -210.445858)
			(xy 243.18187 -210.450068) (xy 243.181619 -210.458626) (xy 243.18214 -210.462876) (xy 243.183156 -210.469226)
			(xy 243.187728 -210.480656) (xy 243.191538 -210.48599) (xy 243.209093 -210.510747) (xy 243.224656 -210.540854)
			(xy 245.32209 -210.540854) (xy 245.322568 -210.512047) (xy 245.331225 -210.455086) (xy 245.348349 -210.400076)
			(xy 245.373551 -210.348266) (xy 245.406258 -210.300835) (xy 245.445727 -210.258863) (xy 245.491058 -210.223303)
			(xy 245.541222 -210.194966) (xy 245.567962 -210.184238) (xy 245.578376 -210.180428) (xy 245.58625 -210.1723)
			(xy 245.591584 -210.16595) (xy 245.597934 -210.154012) (xy 245.623842 -210.081622) (xy 245.625586 -210.076474)
			(xy 245.627126 -210.065716) (xy 245.62689 -210.060286) (xy 245.625874 -210.04911) (xy 245.62054 -210.039458)
			(xy 245.608887 -210.017981) (xy 245.590578 -209.972676) (xy 245.57819 -209.925407) (xy 245.571925 -209.876946)
			(xy 245.571518 -209.852514) (xy 245.572004 -209.825263) (xy 245.57976 -209.771315) (xy 245.595115 -209.71902)
			(xy 245.617757 -209.669443) (xy 245.647223 -209.623593) (xy 245.682914 -209.582402) (xy 245.724105 -209.546711)
			(xy 245.769955 -209.517245) (xy 245.819532 -209.494603) (xy 245.871827 -209.479248) (xy 245.925775 -209.471492)
			(xy 245.980277 -209.471492) (xy 246.034225 -209.479248) (xy 246.08652 -209.494603) (xy 246.136097 -209.517245)
			(xy 246.181947 -209.546711) (xy 246.223138 -209.582402) (xy 246.258829 -209.623593) (xy 246.288295 -209.669443)
			(xy 246.310937 -209.71902) (xy 246.326292 -209.771315) (xy 246.334048 -209.825263) (xy 246.334534 -209.852514)
			(xy 246.334012 -209.88132) (xy 246.325361 -209.938277) (xy 246.308243 -209.993286) (xy 246.283047 -210.045095)
			(xy 246.250345 -210.092525) (xy 246.210883 -210.134499) (xy 246.165558 -210.17006) (xy 246.1154 -210.1984)
			(xy 246.088662 -210.20913) (xy 246.078248 -210.21294) (xy 246.070374 -210.221068) (xy 246.06504 -210.227418)
			(xy 246.05869 -210.239356) (xy 246.032782 -210.311746) (xy 246.031018 -210.316888) (xy 246.029491 -210.327651)
			(xy 246.029734 -210.333082) (xy 246.03075 -210.344258) (xy 246.036084 -210.35391) (xy 246.047718 -210.375397)
			(xy 246.066033 -210.420698) (xy 246.078427 -210.467963) (xy 246.084697 -210.516423) (xy 246.085106 -210.540854)
			(xy 246.08462 -210.568105) (xy 246.079116 -210.606386) (xy 250.49429 -210.606386) (xy 250.498361 -210.550764)
			(xy 250.510487 -210.496327) (xy 250.53041 -210.444236) (xy 250.557706 -210.395601) (xy 250.591792 -210.351458)
			(xy 250.631941 -210.312749) (xy 250.677299 -210.280298) (xy 250.726899 -210.254797) (xy 250.779683 -210.23679)
			(xy 250.834526 -210.22666) (xy 250.89026 -210.224623) (xy 250.945697 -210.230723) (xy 250.999654 -210.244829)
			(xy 251.050983 -210.266641) (xy 251.098589 -210.295695) (xy 251.141457 -210.33137) (xy 251.178674 -210.372907)
			(xy 251.209447 -210.41942) (xy 251.233119 -210.469917) (xy 251.249187 -210.523324) (xy 251.255467 -210.566)
			(xy 252.117858 -210.566) (xy 252.121929 -210.510378) (xy 252.134055 -210.455941) (xy 252.153978 -210.40385)
			(xy 252.181274 -210.355215) (xy 252.21536 -210.311072) (xy 252.255509 -210.272363) (xy 252.300867 -210.239912)
			(xy 252.350467 -210.214411) (xy 252.403251 -210.196404) (xy 252.458094 -210.186274) (xy 252.513828 -210.184237)
			(xy 252.569265 -210.190337) (xy 252.623222 -210.204443) (xy 252.674551 -210.226255) (xy 252.722157 -210.255309)
			(xy 252.765025 -210.290984) (xy 252.802242 -210.332521) (xy 252.833015 -210.379034) (xy 252.856687 -210.429531)
			(xy 252.858084 -210.434174) (xy 257.763262 -210.434174) (xy 257.767333 -210.378552) (xy 257.779459 -210.324115)
			(xy 257.799382 -210.272024) (xy 257.826678 -210.223389) (xy 257.860764 -210.179246) (xy 257.900913 -210.140537)
			(xy 257.946271 -210.108086) (xy 257.995871 -210.082585) (xy 258.048655 -210.064578) (xy 258.103498 -210.054448)
			(xy 258.159232 -210.052411) (xy 258.214669 -210.058511) (xy 258.268626 -210.072617) (xy 258.319955 -210.094429)
			(xy 258.367561 -210.123483) (xy 258.410429 -210.159158) (xy 258.447646 -210.200695) (xy 258.478419 -210.247208)
			(xy 258.502091 -210.297705) (xy 258.518159 -210.351112) (xy 258.526279 -210.406288) (xy 258.526788 -210.434174)
			(xy 258.526279 -210.46206) (xy 258.518159 -210.517236) (xy 258.502091 -210.570643) (xy 258.478419 -210.62114)
			(xy 258.447646 -210.667653) (xy 258.410429 -210.70919) (xy 258.367561 -210.744865) (xy 258.319955 -210.773919)
			(xy 258.268626 -210.795731) (xy 258.214669 -210.809837) (xy 258.159232 -210.815937) (xy 258.103498 -210.8139)
			(xy 258.048655 -210.80377) (xy 257.995871 -210.785763) (xy 257.946271 -210.760262) (xy 257.900913 -210.727811)
			(xy 257.860764 -210.689102) (xy 257.826678 -210.644959) (xy 257.799382 -210.596324) (xy 257.779459 -210.544233)
			(xy 257.767333 -210.489796) (xy 257.763262 -210.434174) (xy 252.858084 -210.434174) (xy 252.872755 -210.482938)
			(xy 252.880875 -210.538114) (xy 252.881384 -210.566) (xy 252.880875 -210.593886) (xy 252.872755 -210.649062)
			(xy 252.856687 -210.702469) (xy 252.833015 -210.752966) (xy 252.802242 -210.799479) (xy 252.765025 -210.841016)
			(xy 252.722157 -210.876691) (xy 252.674551 -210.905745) (xy 252.623222 -210.927557) (xy 252.569265 -210.941663)
			(xy 252.513828 -210.947763) (xy 252.458094 -210.945726) (xy 252.403251 -210.935596) (xy 252.350467 -210.917589)
			(xy 252.300867 -210.892088) (xy 252.255509 -210.859637) (xy 252.21536 -210.820928) (xy 252.181274 -210.776785)
			(xy 252.153978 -210.72815) (xy 252.134055 -210.676059) (xy 252.121929 -210.621622) (xy 252.117858 -210.566)
			(xy 251.255467 -210.566) (xy 251.257307 -210.5785) (xy 251.257816 -210.606386) (xy 251.257307 -210.634272)
			(xy 251.249187 -210.689448) (xy 251.233119 -210.742855) (xy 251.209447 -210.793352) (xy 251.178674 -210.839865)
			(xy 251.141457 -210.881402) (xy 251.098589 -210.917077) (xy 251.050983 -210.946131) (xy 250.999654 -210.967943)
			(xy 250.945697 -210.982049) (xy 250.89026 -210.988149) (xy 250.834526 -210.986112) (xy 250.779683 -210.975982)
			(xy 250.726899 -210.957975) (xy 250.677299 -210.932474) (xy 250.631941 -210.900023) (xy 250.591792 -210.861314)
			(xy 250.557706 -210.817171) (xy 250.53041 -210.768536) (xy 250.510487 -210.716445) (xy 250.498361 -210.662008)
			(xy 250.49429 -210.606386) (xy 246.079116 -210.606386) (xy 246.076864 -210.622053) (xy 246.061509 -210.674348)
			(xy 246.038867 -210.723925) (xy 246.009401 -210.769775) (xy 245.97371 -210.810966) (xy 245.932519 -210.846657)
			(xy 245.886669 -210.876123) (xy 245.837092 -210.898765) (xy 245.784797 -210.91412) (xy 245.730849 -210.921876)
			(xy 245.676347 -210.921876) (xy 245.622399 -210.91412) (xy 245.570104 -210.898765) (xy 245.520527 -210.876123)
			(xy 245.474677 -210.846657) (xy 245.433486 -210.810966) (xy 245.397795 -210.769775) (xy 245.368329 -210.723925)
			(xy 245.345687 -210.674348) (xy 245.330332 -210.622053) (xy 245.322576 -210.568105) (xy 245.32209 -210.540854)
			(xy 243.224656 -210.540854) (xy 243.236961 -210.564659) (xy 243.255957 -210.622297) (xy 243.265604 -210.682214)
			(xy 243.266214 -210.712558) (xy 243.265728 -210.739809) (xy 243.257972 -210.793757) (xy 243.242617 -210.846052)
			(xy 243.219975 -210.895629) (xy 243.190509 -210.941479) (xy 243.154818 -210.98267) (xy 243.113627 -211.018361)
			(xy 243.067777 -211.047827) (xy 243.0182 -211.070469) (xy 242.965905 -211.085824) (xy 242.911957 -211.09358)
			(xy 242.857455 -211.09358) (xy 242.803507 -211.085824) (xy 242.751212 -211.070469) (xy 242.701635 -211.047827)
			(xy 242.655785 -211.018361) (xy 242.614594 -210.98267) (xy 242.578903 -210.941479) (xy 242.549437 -210.895629)
			(xy 242.526795 -210.846052) (xy 242.51144 -210.793757) (xy 242.503684 -210.739809) (xy 242.503198 -210.712558)
			(xy 242.503587 -210.687653) (xy 242.510079 -210.638269) (xy 242.522934 -210.590147) (xy 242.541935 -210.544104)
			(xy 242.553998 -210.522312) (xy 242.560602 -210.510882) (xy 242.560856 -210.498182) (xy 242.559332 -210.484974)
			(xy 242.555014 -210.473544) (xy 242.515644 -210.397598) (xy 242.515136 -210.396582) (xy 242.511901 -210.391042)
			(xy 242.503166 -210.381651) (xy 242.497864 -210.37804) (xy 242.487958 -210.37169) (xy 242.475004 -210.37042)
			(xy 242.446898 -210.367321) (xy 242.391942 -210.354026) (xy 242.33955 -210.332764) (xy 242.290871 -210.304002)
			(xy 242.246971 -210.268369) (xy 242.208811 -210.226647) (xy 242.177227 -210.17975) (xy 242.152912 -210.128704)
			(xy 242.136398 -210.074628) (xy 242.128047 -210.018707) (xy 242.127532 -209.990436) (xy 196.968618 -209.990436)
			(xy 196.968618 -210.844638) (xy 206.847184 -210.844638) (xy 206.851255 -210.789016) (xy 206.863381 -210.734579)
			(xy 206.883304 -210.682488) (xy 206.9106 -210.633853) (xy 206.944686 -210.58971) (xy 206.984835 -210.551001)
			(xy 207.030193 -210.51855) (xy 207.079793 -210.493049) (xy 207.132577 -210.475042) (xy 207.18742 -210.464912)
			(xy 207.243154 -210.462875) (xy 207.298591 -210.468975) (xy 207.352548 -210.483081) (xy 207.403877 -210.504893)
			(xy 207.451483 -210.533947) (xy 207.494351 -210.569622) (xy 207.531568 -210.611159) (xy 207.562341 -210.657672)
			(xy 207.586013 -210.708169) (xy 207.602081 -210.761576) (xy 207.602754 -210.766152) (xy 210.424776 -210.766152)
			(xy 210.425262 -210.738901) (xy 210.433018 -210.684953) (xy 210.448373 -210.632658) (xy 210.471015 -210.583081)
			(xy 210.500481 -210.537231) (xy 210.536172 -210.49604) (xy 210.577363 -210.460349) (xy 210.623213 -210.430883)
			(xy 210.67279 -210.408241) (xy 210.725085 -210.392886) (xy 210.779033 -210.38513) (xy 210.833535 -210.38513)
			(xy 210.887483 -210.392886) (xy 210.939778 -210.408241) (xy 210.989355 -210.430883) (xy 211.003171 -210.439762)
			(xy 219.192348 -210.439762) (xy 219.192834 -210.412511) (xy 219.20059 -210.358563) (xy 219.215945 -210.306268)
			(xy 219.238587 -210.256691) (xy 219.268053 -210.210841) (xy 219.303744 -210.16965) (xy 219.344935 -210.133959)
			(xy 219.390785 -210.104493) (xy 219.440362 -210.081851) (xy 219.492657 -210.066496) (xy 219.546605 -210.05874)
			(xy 219.601107 -210.05874) (xy 219.655055 -210.066496) (xy 219.70735 -210.081851) (xy 219.756927 -210.104493)
			(xy 219.802777 -210.133959) (xy 219.843968 -210.16965) (xy 219.879659 -210.210841) (xy 219.909125 -210.256691)
			(xy 219.931767 -210.306268) (xy 219.947122 -210.358563) (xy 219.954878 -210.412511) (xy 219.955364 -210.439762)
			(xy 219.955128 -210.451192) (xy 225.760786 -210.451192) (xy 225.764857 -210.39557) (xy 225.776983 -210.341133)
			(xy 225.796906 -210.289042) (xy 225.824202 -210.240407) (xy 225.858288 -210.196264) (xy 225.898437 -210.157555)
			(xy 225.943795 -210.125104) (xy 225.993395 -210.099603) (xy 226.046179 -210.081596) (xy 226.101022 -210.071466)
			(xy 226.156756 -210.069429) (xy 226.212193 -210.075529) (xy 226.26615 -210.089635) (xy 226.317479 -210.111447)
			(xy 226.365085 -210.140501) (xy 226.407953 -210.176176) (xy 226.44517 -210.217713) (xy 226.475943 -210.264226)
			(xy 226.499615 -210.314723) (xy 226.515683 -210.36813) (xy 226.523803 -210.423306) (xy 226.524312 -210.451192)
			(xy 226.960682 -210.451192) (xy 226.964753 -210.39557) (xy 226.976879 -210.341133) (xy 226.996802 -210.289042)
			(xy 227.024098 -210.240407) (xy 227.058184 -210.196264) (xy 227.098333 -210.157555) (xy 227.143691 -210.125104)
			(xy 227.193291 -210.099603) (xy 227.246075 -210.081596) (xy 227.300918 -210.071466) (xy 227.356652 -210.069429)
			(xy 227.412089 -210.075529) (xy 227.466046 -210.089635) (xy 227.517375 -210.111447) (xy 227.564981 -210.140501)
			(xy 227.607849 -210.176176) (xy 227.645066 -210.217713) (xy 227.675839 -210.264226) (xy 227.699511 -210.314723)
			(xy 227.715579 -210.36813) (xy 227.723699 -210.423306) (xy 227.724208 -210.451192) (xy 227.723699 -210.479078)
			(xy 227.715579 -210.534254) (xy 227.699511 -210.587661) (xy 227.675839 -210.638158) (xy 227.645066 -210.684671)
			(xy 227.607849 -210.726208) (xy 227.564981 -210.761883) (xy 227.525523 -210.785964) (xy 230.220518 -210.785964)
			(xy 230.224589 -210.730342) (xy 230.236715 -210.675905) (xy 230.256638 -210.623814) (xy 230.283934 -210.575179)
			(xy 230.31802 -210.531036) (xy 230.358169 -210.492327) (xy 230.403527 -210.459876) (xy 230.453127 -210.434375)
			(xy 230.505911 -210.416368) (xy 230.560754 -210.406238) (xy 230.616488 -210.404201) (xy 230.671925 -210.410301)
			(xy 230.725882 -210.424407) (xy 230.777211 -210.446219) (xy 230.824817 -210.475273) (xy 230.845437 -210.492433)
			(xy 235.785717 -210.492433) (xy 235.785719 -210.437939) (xy 235.793476 -210.383999) (xy 235.80883 -210.331713)
			(xy 235.831469 -210.282143) (xy 235.860931 -210.2363) (xy 235.896618 -210.195116) (xy 235.937802 -210.15943)
			(xy 235.983645 -210.129968) (xy 236.033215 -210.107329) (xy 236.085501 -210.091976) (xy 236.139441 -210.084219)
			(xy 236.193935 -210.084217) (xy 236.247875 -210.091971) (xy 236.300163 -210.107321) (xy 236.349734 -210.129956)
			(xy 236.395579 -210.159416) (xy 236.436765 -210.195099) (xy 236.472454 -210.236281) (xy 236.50192 -210.282122)
			(xy 236.524561 -210.33169) (xy 236.539919 -210.383976) (xy 236.547679 -210.437915) (xy 236.548168 -210.465162)
			(xy 236.548168 -210.465924) (xy 236.547664 -210.492902) (xy 236.540021 -210.546316) (xy 236.532928 -210.57235)
			(xy 236.530896 -210.578954) (xy 236.530642 -210.591654) (xy 236.531912 -210.598004) (xy 236.533574 -210.604416)
			(xy 236.539748 -210.616129) (xy 236.544104 -210.621118) (xy 236.603032 -210.685126) (xy 236.6137 -210.693762)
			(xy 236.62513 -210.699096) (xy 236.630972 -210.701128) (xy 236.64418 -210.701636) (xy 236.650784 -210.700366)
			(xy 236.669813 -210.696696) (xy 236.708368 -210.692753) (xy 236.727746 -210.692492) (xy 236.728 -210.692492)
			(xy 236.754141 -210.6929) (xy 236.805932 -210.700059) (xy 236.856262 -210.714215) (xy 236.904191 -210.735104)
			(xy 236.948823 -210.762335) (xy 236.989324 -210.795399) (xy 237.024935 -210.833679) (xy 237.054993 -210.876458)
			(xy 237.067344 -210.899502) (xy 237.070392 -210.905344) (xy 237.07852 -210.914488) (xy 237.0836 -210.918044)
			(xy 237.088733 -210.921374) (xy 237.100161 -210.925733) (xy 237.106206 -210.92668) (xy 237.189772 -210.937094)
			(xy 237.190534 -210.937094) (xy 237.196599 -210.93763) (xy 237.208673 -210.936086) (xy 237.21441 -210.934046)
			(xy 237.21441 -210.933792) (xy 237.219941 -210.931464) (xy 237.229829 -210.924674) (xy 237.233968 -210.92033)
			(xy 237.234476 -210.919822) (xy 237.252666 -210.899739) (xy 237.293748 -210.86441) (xy 237.339417 -210.835253)
			(xy 237.388755 -210.812855) (xy 237.440766 -210.797667) (xy 237.494404 -210.789996) (xy 237.521496 -210.78952)
			(xy 237.548751 -210.789927) (xy 237.602706 -210.797684) (xy 237.655009 -210.813041) (xy 237.704593 -210.835685)
			(xy 237.75045 -210.865155) (xy 237.791646 -210.900851) (xy 237.827343 -210.942047) (xy 237.856814 -210.987903)
			(xy 237.861334 -210.9978) (xy 238.403382 -210.9978) (xy 238.407453 -210.942178) (xy 238.419579 -210.887741)
			(xy 238.439502 -210.83565) (xy 238.466798 -210.787015) (xy 238.500884 -210.742872) (xy 238.541033 -210.704163)
			(xy 238.586391 -210.671712) (xy 238.635991 -210.646211) (xy 238.688775 -210.628204) (xy 238.743618 -210.618074)
			(xy 238.799352 -210.616037) (xy 238.854789 -210.622137) (xy 238.908746 -210.636243) (xy 238.960075 -210.658055)
			(xy 239.007681 -210.687109) (xy 239.050549 -210.722784) (xy 239.087766 -210.764321) (xy 239.118539 -210.810834)
			(xy 239.142211 -210.861331) (xy 239.158279 -210.914738) (xy 239.166399 -210.969914) (xy 239.166908 -210.9978)
			(xy 239.166399 -211.025686) (xy 239.158279 -211.080862) (xy 239.142211 -211.134269) (xy 239.118539 -211.184766)
			(xy 239.087766 -211.231279) (xy 239.050549 -211.272816) (xy 239.007681 -211.308491) (xy 238.960075 -211.337545)
			(xy 238.908746 -211.359357) (xy 238.854789 -211.373463) (xy 238.799352 -211.379563) (xy 238.743618 -211.377526)
			(xy 238.688775 -211.367396) (xy 238.635991 -211.349389) (xy 238.586391 -211.323888) (xy 238.541033 -211.291437)
			(xy 238.500884 -211.252728) (xy 238.466798 -211.208585) (xy 238.439502 -211.15995) (xy 238.419579 -211.107859)
			(xy 238.407453 -211.053422) (xy 238.403382 -210.9978) (xy 237.861334 -210.9978) (xy 237.879458 -211.037488)
			(xy 237.894815 -211.08979) (xy 237.902573 -211.143745) (xy 237.902573 -211.198255) (xy 237.894815 -211.25221)
			(xy 237.879458 -211.304512) (xy 237.856814 -211.354097) (xy 237.827343 -211.399953) (xy 237.791646 -211.441149)
			(xy 237.75045 -211.476845) (xy 237.704593 -211.506315) (xy 237.655009 -211.528959) (xy 237.602706 -211.544316)
			(xy 237.548751 -211.552073) (xy 237.521496 -211.552536) (xy 237.495355 -211.552116) (xy 237.443566 -211.544958)
			(xy 237.393236 -211.530802) (xy 237.345308 -211.509915) (xy 237.300676 -211.482685) (xy 237.260176 -211.449623)
			(xy 237.224563 -211.411345) (xy 237.194504 -211.368568) (xy 237.182152 -211.345526) (xy 237.179104 -211.339684)
			(xy 237.170976 -211.33054) (xy 237.165896 -211.326984) (xy 237.160763 -211.323656) (xy 237.149335 -211.319295)
			(xy 237.14329 -211.318348) (xy 237.059724 -211.307934) (xy 237.058962 -211.307934) (xy 237.052897 -211.307401)
			(xy 237.040823 -211.308944) (xy 237.035086 -211.310982) (xy 237.035086 -211.311236) (xy 237.029552 -211.313557)
			(xy 237.019665 -211.320352) (xy 237.015528 -211.324698) (xy 237.01502 -211.325206) (xy 236.996838 -211.345297)
			(xy 236.955754 -211.380624) (xy 236.910082 -211.409779) (xy 236.860743 -211.432176) (xy 236.808731 -211.447362)
			(xy 236.755092 -211.455033) (xy 236.728 -211.455508) (xy 236.700749 -211.455022) (xy 236.646801 -211.447266)
			(xy 236.594506 -211.431911) (xy 236.544929 -211.409269) (xy 236.499079 -211.379803) (xy 236.457888 -211.344112)
			(xy 236.422197 -211.302921) (xy 236.392731 -211.257071) (xy 236.370089 -211.207494) (xy 236.354734 -211.155199)
			(xy 236.346978 -211.101251) (xy 236.346492 -211.074) (xy 236.346492 -211.073238) (xy 236.34699 -211.046259)
			(xy 236.354637 -210.992846) (xy 236.361732 -210.966812) (xy 236.363764 -210.960208) (xy 236.364018 -210.947508)
			(xy 236.362748 -210.941158) (xy 236.361106 -210.93474) (xy 236.354919 -210.92303) (xy 236.350556 -210.918044)
			(xy 236.291628 -210.854036) (xy 236.28096 -210.8454) (xy 236.26953 -210.840066) (xy 236.263688 -210.838034)
			(xy 236.25048 -210.837526) (xy 236.243876 -210.838796) (xy 236.224846 -210.842457) (xy 236.186292 -210.846406)
			(xy 236.166914 -210.84667) (xy 236.16666 -210.84667) (xy 236.139413 -210.846179) (xy 236.085474 -210.838418)
			(xy 236.033188 -210.823061) (xy 235.983621 -210.800419) (xy 235.937779 -210.770953) (xy 235.896598 -210.735264)
			(xy 235.860914 -210.694077) (xy 235.831455 -210.648232) (xy 235.80882 -210.598661) (xy 235.79347 -210.546373)
			(xy 235.785717 -210.492433) (xy 230.845437 -210.492433) (xy 230.867685 -210.510948) (xy 230.904902 -210.552485)
			(xy 230.935675 -210.598998) (xy 230.959347 -210.649495) (xy 230.975415 -210.702902) (xy 230.983535 -210.758078)
			(xy 230.984044 -210.785964) (xy 230.983535 -210.81385) (xy 230.975415 -210.869026) (xy 230.959347 -210.922433)
			(xy 230.935675 -210.97293) (xy 230.904902 -211.019443) (xy 230.867685 -211.06098) (xy 230.824817 -211.096655)
			(xy 230.777211 -211.125709) (xy 230.725882 -211.147521) (xy 230.671925 -211.161627) (xy 230.616488 -211.167727)
			(xy 230.560754 -211.16569) (xy 230.505911 -211.15556) (xy 230.453127 -211.137553) (xy 230.403527 -211.112052)
			(xy 230.358169 -211.079601) (xy 230.31802 -211.040892) (xy 230.283934 -210.996749) (xy 230.256638 -210.948114)
			(xy 230.236715 -210.896023) (xy 230.224589 -210.841586) (xy 230.220518 -210.785964) (xy 227.525523 -210.785964)
			(xy 227.517375 -210.790937) (xy 227.466046 -210.812749) (xy 227.412089 -210.826855) (xy 227.356652 -210.832955)
			(xy 227.300918 -210.830918) (xy 227.246075 -210.820788) (xy 227.193291 -210.802781) (xy 227.143691 -210.77728)
			(xy 227.098333 -210.744829) (xy 227.058184 -210.70612) (xy 227.024098 -210.661977) (xy 226.996802 -210.613342)
			(xy 226.976879 -210.561251) (xy 226.964753 -210.506814) (xy 226.960682 -210.451192) (xy 226.524312 -210.451192)
			(xy 226.523803 -210.479078) (xy 226.515683 -210.534254) (xy 226.499615 -210.587661) (xy 226.475943 -210.638158)
			(xy 226.44517 -210.684671) (xy 226.407953 -210.726208) (xy 226.365085 -210.761883) (xy 226.317479 -210.790937)
			(xy 226.26615 -210.812749) (xy 226.212193 -210.826855) (xy 226.156756 -210.832955) (xy 226.101022 -210.830918)
			(xy 226.046179 -210.820788) (xy 225.993395 -210.802781) (xy 225.943795 -210.77728) (xy 225.898437 -210.744829)
			(xy 225.858288 -210.70612) (xy 225.824202 -210.661977) (xy 225.796906 -210.613342) (xy 225.776983 -210.561251)
			(xy 225.764857 -210.506814) (xy 225.760786 -210.451192) (xy 219.955128 -210.451192) (xy 219.954731 -210.470454)
			(xy 219.944914 -210.531049) (xy 219.925528 -210.589291) (xy 219.89707 -210.643681) (xy 219.879164 -210.668616)
			(xy 219.87256 -210.677252) (xy 219.870274 -210.687666) (xy 219.869166 -210.692868) (xy 219.868907 -210.703499)
			(xy 219.869766 -210.708748) (xy 219.884244 -210.782662) (xy 219.885409 -210.788052) (xy 219.889764 -210.798179)
			(xy 219.89288 -210.802728) (xy 219.898722 -210.810856) (xy 219.907866 -210.816698) (xy 219.931649 -210.831553)
			(xy 219.974939 -210.867195) (xy 220.012542 -210.908794) (xy 220.043644 -210.955452) (xy 220.067577 -211.006164)
			(xy 220.083822 -211.059834) (xy 220.092031 -211.115305) (xy 220.092524 -211.143342) (xy 220.092038 -211.170593)
			(xy 220.084282 -211.224541) (xy 220.068927 -211.276836) (xy 220.046285 -211.326413) (xy 220.016819 -211.372263)
			(xy 219.981128 -211.413454) (xy 219.939937 -211.449145) (xy 219.894087 -211.478611) (xy 219.84451 -211.501253)
			(xy 219.792215 -211.516608) (xy 219.738267 -211.524364) (xy 219.683765 -211.524364) (xy 219.629817 -211.516608)
			(xy 219.577522 -211.501253) (xy 219.527945 -211.478611) (xy 219.482095 -211.449145) (xy 219.440904 -211.413454)
			(xy 219.405213 -211.372263) (xy 219.375747 -211.326413) (xy 219.353105 -211.276836) (xy 219.33775 -211.224541)
			(xy 219.329994 -211.170593) (xy 219.329508 -211.143342) (xy 219.330148 -211.11265) (xy 219.339964 -211.052056)
			(xy 219.359349 -210.993814) (xy 219.387803 -210.939423) (xy 219.405708 -210.914488) (xy 219.412312 -210.905852)
			(xy 219.414598 -210.895438) (xy 219.415705 -210.890236) (xy 219.415965 -210.879605) (xy 219.415106 -210.874356)
			(xy 219.400628 -210.800442) (xy 219.399465 -210.795052) (xy 219.395109 -210.784925) (xy 219.391992 -210.780376)
			(xy 219.38615 -210.772248) (xy 219.377006 -210.766406) (xy 219.353218 -210.751558) (xy 219.309929 -210.715914)
			(xy 219.272329 -210.674313) (xy 219.241227 -210.627654) (xy 219.217295 -210.576942) (xy 219.20105 -210.523271)
			(xy 219.192842 -210.4678) (xy 219.192348 -210.439762) (xy 211.003171 -210.439762) (xy 211.035205 -210.460349)
			(xy 211.076396 -210.49604) (xy 211.112087 -210.537231) (xy 211.141553 -210.583081) (xy 211.164195 -210.632658)
			(xy 211.17955 -210.684953) (xy 211.187306 -210.738901) (xy 211.187792 -210.766152) (xy 211.187292 -210.793621)
			(xy 211.179418 -210.847991) (xy 211.163826 -210.900669) (xy 211.140838 -210.950566) (xy 211.110931 -210.996649)
			(xy 211.074722 -211.037965) (xy 211.032961 -211.07366) (xy 211.009992 -211.088732) (xy 210.997643 -211.097198)
			(xy 210.978014 -211.119779) (xy 210.96578 -211.147084) (xy 210.96535 -211.150454) (xy 212.175598 -211.150454)
			(xy 212.176035 -211.123201) (xy 212.183798 -211.069252) (xy 212.199159 -211.016956) (xy 212.221806 -210.967378)
			(xy 212.251278 -210.921527) (xy 212.286974 -210.880337) (xy 212.328169 -210.844647) (xy 212.374023 -210.815181)
			(xy 212.423604 -210.792541) (xy 212.475902 -210.777187) (xy 212.529853 -210.769431) (xy 212.557106 -210.768946)
			(xy 212.584915 -210.769388) (xy 212.639941 -210.777491) (xy 212.693207 -210.793496) (xy 212.743586 -210.817064)
			(xy 212.79001 -210.847695) (xy 212.831496 -210.88474) (xy 212.867166 -210.927416) (xy 212.896262 -210.974817)
			(xy 212.91817 -211.025939) (xy 212.932425 -211.0797) (xy 212.936074 -211.107274) (xy 212.938176 -211.121748)
			(xy 212.949591 -211.148665) (xy 212.968175 -211.171236) (xy 212.992399 -211.187608) (xy 213.020273 -211.196433)
			(xy 213.03488 -211.19719) (xy 213.061709 -211.198305) (xy 213.114681 -211.207093) (xy 213.165898 -211.223218)
			(xy 213.21435 -211.246363) (xy 213.25908 -211.276069) (xy 213.299206 -211.311751) (xy 213.333934 -211.352704)
			(xy 213.36258 -211.398121) (xy 213.384578 -211.447104) (xy 213.399494 -211.498686) (xy 213.407034 -211.55185)
			(xy 213.407498 -211.578698) (xy 213.407043 -211.605951) (xy 213.399286 -211.659903) (xy 213.38393 -211.712202)
			(xy 213.361287 -211.761782) (xy 213.331818 -211.807636) (xy 213.296123 -211.848829) (xy 213.25493 -211.884523)
			(xy 213.209075 -211.91399) (xy 213.159494 -211.936632) (xy 213.107195 -211.951988) (xy 213.053243 -211.959743)
			(xy 213.02599 -211.960206) (xy 212.998183 -211.959722) (xy 212.943161 -211.951619) (xy 212.889899 -211.935616)
			(xy 212.839523 -211.912052) (xy 212.7931 -211.881426) (xy 212.751615 -211.844385) (xy 212.715945 -211.801716)
			(xy 212.686846 -211.754321) (xy 212.664935 -211.703205) (xy 212.650675 -211.649449) (xy 212.647022 -211.621878)
			(xy 212.644886 -211.60741) (xy 212.633483 -211.580492) (xy 212.614908 -211.557918) (xy 212.59069 -211.541545)
			(xy 212.562821 -211.532719) (xy 212.548216 -211.531962) (xy 212.521384 -211.530898) (xy 212.468408 -211.522108)
			(xy 212.417186 -211.50598) (xy 212.368731 -211.482832) (xy 212.323999 -211.45312) (xy 212.283873 -211.417433)
			(xy 212.249145 -211.376473) (xy 212.2205 -211.331051) (xy 212.198505 -211.282062) (xy 212.183593 -211.230473)
			(xy 212.176059 -211.177304) (xy 212.175598 -211.150454) (xy 210.96535 -211.150454) (xy 210.961992 -211.176764)
			(xy 210.966977 -211.206266) (xy 210.980306 -211.233054) (xy 211.000832 -211.254823) (xy 211.013548 -211.262722)
			(xy 211.038087 -211.277463) (xy 211.082906 -211.31307) (xy 211.121905 -211.354971) (xy 211.154209 -211.402227)
			(xy 211.179093 -211.453776) (xy 211.196001 -211.508464) (xy 211.204551 -211.565063) (xy 211.205064 -211.593684)
			(xy 211.204578 -211.620935) (xy 211.196822 -211.674883) (xy 211.181467 -211.727178) (xy 211.158825 -211.776755)
			(xy 211.129359 -211.822605) (xy 211.093668 -211.863796) (xy 211.052477 -211.899487) (xy 211.006627 -211.928953)
			(xy 210.95705 -211.951595) (xy 210.904755 -211.96695) (xy 210.850807 -211.974706) (xy 210.796305 -211.974706)
			(xy 210.742357 -211.96695) (xy 210.690062 -211.951595) (xy 210.640485 -211.928953) (xy 210.594635 -211.899487)
			(xy 210.553444 -211.863796) (xy 210.517753 -211.822605) (xy 210.488287 -211.776755) (xy 210.465645 -211.727178)
			(xy 210.45029 -211.674883) (xy 210.442534 -211.620935) (xy 210.442048 -211.593684) (xy 210.44248 -211.566213)
			(xy 210.450364 -211.511839) (xy 210.465967 -211.459158) (xy 210.488965 -211.409261) (xy 210.518883 -211.363178)
			(xy 210.555103 -211.321865) (xy 210.596874 -211.286174) (xy 210.619848 -211.271104) (xy 210.632266 -211.262728)
			(xy 210.65191 -211.24013) (xy 210.66415 -211.212804) (xy 210.667933 -211.183102) (xy 210.662932 -211.15358)
			(xy 210.649579 -211.12678) (xy 210.629023 -211.105009) (xy 210.616292 -211.097114) (xy 210.591711 -211.08244)
			(xy 210.546895 -211.04682) (xy 210.507901 -211.004906) (xy 210.475602 -210.957639) (xy 210.450725 -210.90608)
			(xy 210.433826 -210.851383) (xy 210.425284 -210.794776) (xy 210.424776 -210.766152) (xy 207.602754 -210.766152)
			(xy 207.610201 -210.816752) (xy 207.61071 -210.844638) (xy 207.610201 -210.872524) (xy 207.602081 -210.9277)
			(xy 207.586013 -210.981107) (xy 207.562341 -211.031604) (xy 207.531568 -211.078117) (xy 207.494351 -211.119654)
			(xy 207.451483 -211.155329) (xy 207.403877 -211.184383) (xy 207.352548 -211.206195) (xy 207.298591 -211.220301)
			(xy 207.243154 -211.226401) (xy 207.18742 -211.224364) (xy 207.132577 -211.214234) (xy 207.079793 -211.196227)
			(xy 207.030193 -211.170726) (xy 206.984835 -211.138275) (xy 206.944686 -211.099566) (xy 206.9106 -211.055423)
			(xy 206.883304 -211.006788) (xy 206.863381 -210.954697) (xy 206.851255 -210.90026) (xy 206.847184 -210.844638)
			(xy 196.968618 -210.844638) (xy 196.968618 -212.127084) (xy 206.34528 -212.127084) (xy 206.349351 -212.071462)
			(xy 206.361477 -212.017025) (xy 206.3814 -211.964934) (xy 206.408696 -211.916299) (xy 206.442782 -211.872156)
			(xy 206.482931 -211.833447) (xy 206.528289 -211.800996) (xy 206.577889 -211.775495) (xy 206.630673 -211.757488)
			(xy 206.685516 -211.747358) (xy 206.74125 -211.745321) (xy 206.796687 -211.751421) (xy 206.850644 -211.765527)
			(xy 206.901973 -211.787339) (xy 206.949579 -211.816393) (xy 206.992447 -211.852068) (xy 207.029664 -211.893605)
			(xy 207.060437 -211.940118) (xy 207.084109 -211.990615) (xy 207.100177 -212.044022) (xy 207.108297 -212.099198)
			(xy 207.108806 -212.127084) (xy 207.108297 -212.15497) (xy 207.100177 -212.210146) (xy 207.084109 -212.263553)
			(xy 207.060437 -212.31405) (xy 207.029664 -212.360563) (xy 206.992447 -212.4021) (xy 206.949579 -212.437775)
			(xy 206.901973 -212.466829) (xy 206.850644 -212.488641) (xy 206.796687 -212.502747) (xy 206.74125 -212.508847)
			(xy 206.685516 -212.50681) (xy 206.630673 -212.49668) (xy 206.577889 -212.478673) (xy 206.528289 -212.453172)
			(xy 206.482931 -212.420721) (xy 206.442782 -212.382012) (xy 206.408696 -212.337869) (xy 206.3814 -212.289234)
			(xy 206.361477 -212.237143) (xy 206.349351 -212.182706) (xy 206.34528 -212.127084) (xy 196.968618 -212.127084)
			(xy 196.968618 -213.610041) (xy 206.450812 -213.610041) (xy 206.450814 -213.555526) (xy 206.458575 -213.501567)
			(xy 206.473937 -213.449262) (xy 206.496586 -213.399675) (xy 206.526062 -213.353817) (xy 206.561765 -213.31262)
			(xy 206.602967 -213.276924) (xy 206.64883 -213.247456) (xy 206.69842 -213.224815) (xy 206.750728 -213.209462)
			(xy 206.804689 -213.20171) (xy 206.831946 -213.20125) (xy 206.844646 -213.201504) (xy 206.858153 -213.201523)
			(xy 206.88443 -213.19531) (xy 206.908161 -213.182428) (xy 206.927686 -213.163778) (xy 206.941641 -213.140662)
			(xy 206.949051 -213.114697) (xy 206.949397 -213.087698) (xy 206.942655 -213.061552) (xy 206.93634 -213.049612)
			(xy 206.92449 -213.027995) (xy 206.905868 -212.982348) (xy 206.893282 -212.934683) (xy 206.886939 -212.885794)
			(xy 206.886556 -212.861144) (xy 206.887008 -212.833887) (xy 206.89476 -212.779926) (xy 206.910113 -212.727618)
			(xy 206.932755 -212.678028) (xy 206.962223 -212.632165) (xy 206.997919 -212.590963) (xy 207.039116 -212.55526)
			(xy 207.084974 -212.525784) (xy 207.134561 -212.503135) (xy 207.186866 -212.487773) (xy 207.240825 -212.480012)
			(xy 207.29534 -212.48001) (xy 207.3493 -212.487766) (xy 207.401607 -212.503123) (xy 207.423595 -212.513164)
			(xy 209.351116 -212.513164) (xy 209.355187 -212.457542) (xy 209.367313 -212.403105) (xy 209.387236 -212.351014)
			(xy 209.414532 -212.302379) (xy 209.448618 -212.258236) (xy 209.488767 -212.219527) (xy 209.534125 -212.187076)
			(xy 209.583725 -212.161575) (xy 209.636509 -212.143568) (xy 209.691352 -212.133438) (xy 209.747086 -212.131401)
			(xy 209.802523 -212.137501) (xy 209.840441 -212.147414) (xy 211.849514 -212.147414) (xy 211.849519 -212.092918)
			(xy 211.857279 -212.038976) (xy 211.872637 -211.986689) (xy 211.89528 -211.937119) (xy 211.924747 -211.891276)
			(xy 211.960438 -211.850093) (xy 212.001627 -211.814409) (xy 212.047475 -211.784949) (xy 212.097049 -211.762315)
			(xy 212.149339 -211.746965) (xy 212.203282 -211.739214) (xy 212.257778 -211.739218) (xy 212.31172 -211.746978)
			(xy 212.364008 -211.762336) (xy 212.413578 -211.784978) (xy 212.459421 -211.814445) (xy 212.500604 -211.850135)
			(xy 212.536289 -211.891324) (xy 212.565749 -211.937171) (xy 212.588384 -211.986745) (xy 212.603734 -212.039035)
			(xy 212.611486 -212.092978) (xy 212.61197 -212.120226) (xy 212.611462 -212.138514) (xy 212.611227 -212.153217)
			(xy 212.618247 -212.181762) (xy 212.63309 -212.207135) (xy 212.654533 -212.227243) (xy 212.680806 -212.240427)
			(xy 212.709743 -212.2456) (xy 212.738957 -212.242335) (xy 212.752686 -212.237066) (xy 212.776281 -212.227514)
			(xy 212.825377 -212.214073) (xy 212.875825 -212.207277) (xy 212.901276 -212.20684) (xy 212.928529 -212.207252)
			(xy 212.98248 -212.215005) (xy 213.034778 -212.230358) (xy 213.042439 -212.233856) (xy 215.108441 -212.233856)
			(xy 215.108441 -212.179344) (xy 215.116199 -212.125388) (xy 215.131558 -212.073086) (xy 215.154204 -212.023501)
			(xy 215.183676 -211.977645) (xy 215.219375 -211.936449) (xy 215.260574 -211.900754) (xy 215.306433 -211.871286)
			(xy 215.356019 -211.848645) (xy 215.408324 -211.833292) (xy 215.46228 -211.825538) (xy 215.489536 -211.825078)
			(xy 215.48979 -211.825078) (xy 215.516084 -211.82555) (xy 215.568172 -211.832794) (xy 215.618773 -211.847118)
			(xy 215.666929 -211.868251) (xy 215.711729 -211.895793) (xy 215.752325 -211.929223) (xy 215.77046 -211.948268)
			(xy 215.777999 -211.955649) (xy 215.797266 -211.964187) (xy 215.807798 -211.964778) (xy 215.882474 -211.964778)
			(xy 215.893025 -211.964255) (xy 215.91232 -211.955716) (xy 215.919812 -211.948268) (xy 215.937939 -211.92921)
			(xy 215.97852 -211.895752) (xy 216.023316 -211.868191) (xy 216.071477 -211.847051) (xy 216.122086 -211.832735)
			(xy 216.174184 -211.825514) (xy 216.200482 -211.825078) (xy 216.200736 -211.825078) (xy 216.227985 -211.825595)
			(xy 216.279125 -211.832952) (xy 242.36883 -211.832952) (xy 242.372901 -211.77733) (xy 242.385027 -211.722893)
			(xy 242.40495 -211.670802) (xy 242.432246 -211.622167) (xy 242.466332 -211.578024) (xy 242.506481 -211.539315)
			(xy 242.551839 -211.506864) (xy 242.601439 -211.481363) (xy 242.654223 -211.463356) (xy 242.709066 -211.453226)
			(xy 242.7648 -211.451189) (xy 242.820237 -211.457289) (xy 242.874194 -211.471395) (xy 242.925523 -211.493207)
			(xy 242.973129 -211.522261) (xy 243.015997 -211.557936) (xy 243.053214 -211.599473) (xy 243.083987 -211.645986)
			(xy 243.107659 -211.696483) (xy 243.123727 -211.74989) (xy 243.131847 -211.805066) (xy 243.132356 -211.832952)
			(xy 243.131847 -211.860838) (xy 243.123727 -211.916014) (xy 243.107659 -211.969421) (xy 243.083987 -212.019918)
			(xy 243.053214 -212.066431) (xy 243.034145 -212.087714) (xy 246.890032 -212.087714) (xy 246.890468 -212.06046)
			(xy 246.898225 -212.006506) (xy 246.913581 -211.954205) (xy 246.936225 -211.904622) (xy 246.965695 -211.858767)
			(xy 247.001392 -211.817573) (xy 247.042588 -211.781879) (xy 247.088445 -211.752412) (xy 247.138029 -211.729772)
			(xy 247.190331 -211.714419) (xy 247.244286 -211.706667) (xy 247.27154 -211.706206) (xy 247.298049 -211.706686)
			(xy 247.350556 -211.714031) (xy 247.40154 -211.728575) (xy 247.45002 -211.750037) (xy 247.495062 -211.778004)
			(xy 247.535798 -211.811938) (xy 247.571444 -211.851185) (xy 247.586754 -211.87283) (xy 247.59031 -211.878164)
			(xy 247.5992 -211.886038) (xy 247.604788 -211.889086) (xy 247.61026 -211.891759) (xy 247.62207 -211.894717)
			(xy 247.628156 -211.894928) (xy 247.711468 -211.895944) (xy 247.715933 -211.895935) (xy 247.72475 -211.894537)
			(xy 247.728994 -211.89315) (xy 247.735344 -211.890356) (xy 247.740678 -211.887816) (xy 247.75033 -211.879434)
			(xy 247.753632 -211.874354) (xy 247.769051 -211.853347) (xy 247.804649 -211.815293) (xy 247.845092 -211.782435)
			(xy 247.889629 -211.755385) (xy 247.937432 -211.734643) (xy 247.987612 -211.720597) (xy 248.039236 -211.713508)
			(xy 248.06529 -211.713064) (xy 248.099446 -211.713886) (xy 248.16665 -211.726152) (xy 248.198894 -211.737448)
			(xy 248.199402 -211.737448) (xy 248.211086 -211.741766) (xy 248.223532 -211.740242) (xy 248.229817 -211.739182)
			(xy 248.241641 -211.734442) (xy 248.2469 -211.730844) (xy 248.31548 -211.68106) (xy 248.320387 -211.677266)
			(xy 248.328348 -211.667758) (xy 248.331228 -211.662264) (xy 248.336816 -211.650834) (xy 248.336308 -211.638134)
			(xy 248.336054 -211.622386) (xy 248.33657 -211.595134) (xy 248.344329 -211.541184) (xy 248.359687 -211.488888)
			(xy 248.382331 -211.43931) (xy 248.4118 -211.39346) (xy 248.447495 -211.35227) (xy 248.488689 -211.316579)
			(xy 248.534542 -211.287114) (xy 248.584122 -211.264474) (xy 248.63642 -211.249122) (xy 248.69037 -211.241368)
			(xy 248.744874 -211.241371) (xy 248.798823 -211.249131) (xy 248.851119 -211.26449) (xy 248.900697 -211.287135)
			(xy 248.946547 -211.316605) (xy 248.987736 -211.352301) (xy 249.023426 -211.393495) (xy 249.05289 -211.439349)
			(xy 249.075528 -211.48893) (xy 249.09088 -211.541227) (xy 249.098633 -211.595178) (xy 249.098631 -211.61629)
			(xy 251.855476 -211.61629) (xy 251.859547 -211.560668) (xy 251.871673 -211.506231) (xy 251.891596 -211.45414)
			(xy 251.918892 -211.405505) (xy 251.952978 -211.361362) (xy 251.993127 -211.322653) (xy 252.038485 -211.290202)
			(xy 252.088085 -211.264701) (xy 252.140869 -211.246694) (xy 252.195712 -211.236564) (xy 252.251446 -211.234527)
			(xy 252.306883 -211.240627) (xy 252.36084 -211.254733) (xy 252.412169 -211.276545) (xy 252.459775 -211.305599)
			(xy 252.502643 -211.341274) (xy 252.53986 -211.382811) (xy 252.570633 -211.429324) (xy 252.594305 -211.479821)
			(xy 252.610373 -211.533228) (xy 252.618493 -211.588404) (xy 252.619002 -211.61629) (xy 252.618493 -211.644176)
			(xy 252.610373 -211.699352) (xy 252.594305 -211.752759) (xy 252.570633 -211.803256) (xy 252.53986 -211.849769)
			(xy 252.502643 -211.891306) (xy 252.459775 -211.926981) (xy 252.421802 -211.950156) (xy 253.712623 -211.950156)
			(xy 253.712623 -211.895644) (xy 253.720381 -211.841686) (xy 253.73574 -211.789381) (xy 253.758386 -211.739795)
			(xy 253.787859 -211.693937) (xy 253.823559 -211.65274) (xy 253.864758 -211.617044) (xy 253.910618 -211.587574)
			(xy 253.960206 -211.564931) (xy 254.012511 -211.549576) (xy 254.06647 -211.541821) (xy 254.093726 -211.54136)
			(xy 254.12133 -211.541848) (xy 254.17596 -211.549809) (xy 254.228873 -211.56556) (xy 254.278963 -211.588772)
			(xy 254.325185 -211.618962) (xy 254.346202 -211.636864) (xy 254.353314 -211.64296) (xy 254.36195 -211.646262)
			(xy 254.363728 -211.647024) (xy 254.367687 -211.648211) (xy 254.375852 -211.649493) (xy 254.379984 -211.649564)
			(xy 254.44704 -211.649564) (xy 254.451176 -211.649525) (xy 254.459347 -211.648253) (xy 254.463296 -211.647024)
			(xy 254.465074 -211.646262) (xy 254.47371 -211.64296) (xy 254.480822 -211.636864) (xy 254.501844 -211.618968)
			(xy 254.548063 -211.588774) (xy 254.598152 -211.56556) (xy 254.651064 -211.549808) (xy 254.705694 -211.541849)
			(xy 254.733298 -211.54136) (xy 254.760549 -211.541887) (xy 254.814495 -211.549643) (xy 254.866789 -211.564998)
			(xy 254.916365 -211.587638) (xy 254.962215 -211.617104) (xy 255.003404 -211.652794) (xy 255.039095 -211.693984)
			(xy 255.068561 -211.739833) (xy 255.072924 -211.749386) (xy 258.876544 -211.749386) (xy 258.880615 -211.693764)
			(xy 258.892741 -211.639327) (xy 258.912664 -211.587236) (xy 258.93996 -211.538601) (xy 258.974046 -211.494458)
			(xy 259.014195 -211.455749) (xy 259.059553 -211.423298) (xy 259.109153 -211.397797) (xy 259.161937 -211.37979)
			(xy 259.21678 -211.36966) (xy 259.272514 -211.367623) (xy 259.327951 -211.373723) (xy 259.381908 -211.387829)
			(xy 259.433237 -211.409641) (xy 259.480843 -211.438695) (xy 259.523711 -211.47437) (xy 259.560928 -211.515907)
			(xy 259.591701 -211.56242) (xy 259.615373 -211.612917) (xy 259.631441 -211.666324) (xy 259.639561 -211.7215)
			(xy 259.64007 -211.749386) (xy 259.639561 -211.777272) (xy 259.631441 -211.832448) (xy 259.615373 -211.885855)
			(xy 259.591701 -211.936352) (xy 259.560928 -211.982865) (xy 259.523711 -212.024402) (xy 259.480843 -212.060077)
			(xy 259.433237 -212.089131) (xy 259.381908 -212.110943) (xy 259.327951 -212.125049) (xy 259.272514 -212.131149)
			(xy 259.21678 -212.129112) (xy 259.161937 -212.118982) (xy 259.109153 -212.100975) (xy 259.059553 -212.075474)
			(xy 259.014195 -212.043023) (xy 258.974046 -212.004314) (xy 258.93996 -211.960171) (xy 258.912664 -211.911536)
			(xy 258.892741 -211.859445) (xy 258.880615 -211.805008) (xy 258.876544 -211.749386) (xy 255.072924 -211.749386)
			(xy 255.091202 -211.789409) (xy 255.106556 -211.841703) (xy 255.114313 -211.895649) (xy 255.114313 -211.950151)
			(xy 255.106556 -212.004097) (xy 255.091202 -212.056391) (xy 255.068561 -212.105967) (xy 255.039095 -212.151816)
			(xy 255.003404 -212.193006) (xy 254.962215 -212.228696) (xy 254.916365 -212.258162) (xy 254.866789 -212.280802)
			(xy 254.814495 -212.296157) (xy 254.760549 -212.303913) (xy 254.733298 -212.304376) (xy 254.705695 -212.303864)
			(xy 254.651066 -212.295908) (xy 254.598154 -212.280162) (xy 254.548063 -212.256955) (xy 254.50184 -212.226771)
			(xy 254.480822 -212.208872) (xy 254.47371 -212.202776) (xy 254.465074 -212.199474) (xy 254.463296 -212.198712)
			(xy 254.459342 -212.197506) (xy 254.451173 -212.196237) (xy 254.44704 -212.196172) (xy 254.379984 -212.196172)
			(xy 254.375847 -212.196191) (xy 254.367676 -212.197476) (xy 254.363728 -212.198712) (xy 254.36195 -212.199474)
			(xy 254.353314 -212.202776) (xy 254.346202 -212.208872) (xy 254.325175 -212.226763) (xy 254.278957 -212.256956)
			(xy 254.228869 -212.280171) (xy 254.175958 -212.295924) (xy 254.121329 -212.303885) (xy 254.093726 -212.304376)
			(xy 254.06647 -212.303979) (xy 254.012511 -212.296224) (xy 253.960206 -212.280869) (xy 253.910618 -212.258226)
			(xy 253.864758 -212.228756) (xy 253.823559 -212.19306) (xy 253.787859 -212.151863) (xy 253.758386 -212.106005)
			(xy 253.73574 -212.056419) (xy 253.720381 -212.004114) (xy 253.712623 -211.950156) (xy 252.421802 -211.950156)
			(xy 252.412169 -211.956035) (xy 252.36084 -211.977847) (xy 252.306883 -211.991953) (xy 252.251446 -211.998053)
			(xy 252.195712 -211.996016) (xy 252.140869 -211.985886) (xy 252.088085 -211.967879) (xy 252.038485 -211.942378)
			(xy 251.993127 -211.909927) (xy 251.952978 -211.871218) (xy 251.918892 -211.827075) (xy 251.891596 -211.77844)
			(xy 251.871673 -211.726349) (xy 251.859547 -211.671912) (xy 251.855476 -211.61629) (xy 249.098631 -211.61629)
			(xy 249.098629 -211.649682) (xy 249.090867 -211.703631) (xy 249.075507 -211.755927) (xy 249.052861 -211.805504)
			(xy 249.02339 -211.851353) (xy 248.987694 -211.892542) (xy 248.946499 -211.928231) (xy 248.900644 -211.957694)
			(xy 248.851063 -211.980331) (xy 248.798765 -211.995682) (xy 248.744814 -212.003433) (xy 248.717562 -212.003894)
			(xy 248.683407 -212.003061) (xy 248.616202 -211.990803) (xy 248.583958 -211.97951) (xy 248.58345 -211.97951)
			(xy 248.571766 -211.975192) (xy 248.55932 -211.976716) (xy 248.55303 -211.977751) (xy 248.541208 -211.982508)
			(xy 248.535952 -211.986114) (xy 248.467372 -212.035898) (xy 248.462466 -212.039693) (xy 248.454504 -212.049201)
			(xy 248.451624 -212.054694) (xy 248.446036 -212.066124) (xy 248.446544 -212.078824) (xy 248.446798 -212.094572)
			(xy 248.446595 -212.11343) (xy 248.442901 -212.150965) (xy 248.439432 -212.169502) (xy 248.437908 -212.176614)
			(xy 248.438924 -212.189822) (xy 248.44121 -212.196172) (xy 248.443686 -212.202668) (xy 248.451533 -212.214133)
			(xy 248.456704 -212.218778) (xy 248.525284 -212.275674) (xy 248.530636 -212.279873) (xy 248.542993 -212.285544)
			(xy 248.549668 -212.28685) (xy 248.556526 -212.287866) (xy 248.570242 -212.286342) (xy 248.576592 -212.283802)
			(xy 248.599054 -212.275256) (xy 248.645597 -212.263271) (xy 248.693277 -212.257237) (xy 248.717308 -212.256878)
			(xy 248.717562 -212.256878) (xy 248.744816 -212.257367) (xy 248.798769 -212.265119) (xy 248.851069 -212.280471)
			(xy 248.900652 -212.303111) (xy 248.946508 -212.332577) (xy 248.987704 -212.368269) (xy 249.023401 -212.409461)
			(xy 249.052871 -212.455314) (xy 249.075516 -212.504895) (xy 249.090873 -212.557194) (xy 249.098631 -212.611146)
			(xy 249.098631 -212.638386) (xy 250.494544 -212.638386) (xy 250.498615 -212.582764) (xy 250.510741 -212.528327)
			(xy 250.530664 -212.476236) (xy 250.55796 -212.427601) (xy 250.592046 -212.383458) (xy 250.632195 -212.344749)
			(xy 250.677553 -212.312298) (xy 250.727153 -212.286797) (xy 250.779937 -212.26879) (xy 250.83478 -212.25866)
			(xy 250.890514 -212.256623) (xy 250.945951 -212.262723) (xy 250.999908 -212.276829) (xy 251.051237 -212.298641)
			(xy 251.098843 -212.327695) (xy 251.141711 -212.36337) (xy 251.178928 -212.404907) (xy 251.209701 -212.45142)
			(xy 251.233373 -212.501917) (xy 251.249441 -212.555324) (xy 251.257561 -212.6105) (xy 251.25807 -212.638386)
			(xy 251.257561 -212.666272) (xy 251.249441 -212.721448) (xy 251.236222 -212.765386) (xy 256.844544 -212.765386)
			(xy 256.848615 -212.709764) (xy 256.860741 -212.655327) (xy 256.880664 -212.603236) (xy 256.90796 -212.554601)
			(xy 256.942046 -212.510458) (xy 256.982195 -212.471749) (xy 257.027553 -212.439298) (xy 257.077153 -212.413797)
			(xy 257.129937 -212.39579) (xy 257.18478 -212.38566) (xy 257.240514 -212.383623) (xy 257.295951 -212.389723)
			(xy 257.349908 -212.403829) (xy 257.401237 -212.425641) (xy 257.448843 -212.454695) (xy 257.491711 -212.49037)
			(xy 257.528928 -212.531907) (xy 257.559701 -212.57842) (xy 257.583373 -212.628917) (xy 257.599441 -212.682324)
			(xy 257.607561 -212.7375) (xy 257.60807 -212.765386) (xy 257.607561 -212.793272) (xy 257.599441 -212.848448)
			(xy 257.583373 -212.901855) (xy 257.559701 -212.952352) (xy 257.528928 -212.998865) (xy 257.491711 -213.040402)
			(xy 257.448843 -213.076077) (xy 257.401237 -213.105131) (xy 257.349908 -213.126943) (xy 257.295951 -213.141049)
			(xy 257.240514 -213.147149) (xy 257.18478 -213.145112) (xy 257.129937 -213.134982) (xy 257.077153 -213.116975)
			(xy 257.027553 -213.091474) (xy 256.982195 -213.059023) (xy 256.942046 -213.020314) (xy 256.90796 -212.976171)
			(xy 256.880664 -212.927536) (xy 256.860741 -212.875445) (xy 256.848615 -212.821008) (xy 256.844544 -212.765386)
			(xy 251.236222 -212.765386) (xy 251.233373 -212.774855) (xy 251.209701 -212.825352) (xy 251.178928 -212.871865)
			(xy 251.141711 -212.913402) (xy 251.098843 -212.949077) (xy 251.051237 -212.978131) (xy 250.999908 -212.999943)
			(xy 250.945951 -213.014049) (xy 250.890514 -213.020149) (xy 250.83478 -213.018112) (xy 250.779937 -213.007982)
			(xy 250.727153 -212.989975) (xy 250.677553 -212.964474) (xy 250.632195 -212.932023) (xy 250.592046 -212.893314)
			(xy 250.55796 -212.849171) (xy 250.530664 -212.800536) (xy 250.510741 -212.748445) (xy 250.498615 -212.694008)
			(xy 250.494544 -212.638386) (xy 249.098631 -212.638386) (xy 249.098631 -212.665654) (xy 249.090873 -212.719606)
			(xy 249.075516 -212.771905) (xy 249.052871 -212.821486) (xy 249.023401 -212.867339) (xy 248.987704 -212.908531)
			(xy 248.946508 -212.944223) (xy 248.900652 -212.973689) (xy 248.851069 -212.996329) (xy 248.798769 -213.011681)
			(xy 248.744816 -213.019433) (xy 248.717562 -213.019894) (xy 248.692527 -213.019478) (xy 248.642891 -213.012901)
			(xy 248.594537 -212.999904) (xy 248.571258 -212.990684) (xy 248.562368 -212.986874) (xy 248.55297 -212.98662)
			(xy 248.548432 -212.986673) (xy 248.53949 -212.988215) (xy 248.53519 -212.989668) (xy 248.47042 -213.012528)
			(xy 248.466081 -213.014164) (xy 248.45803 -213.018763) (xy 248.454418 -213.021672) (xy 248.447306 -213.027768)
			(xy 248.442734 -213.03615) (xy 248.428366 -213.061709) (xy 248.392932 -213.108425) (xy 248.350766 -213.149167)
			(xy 248.302861 -213.182976) (xy 248.250347 -213.209056) (xy 248.19446 -213.226791) (xy 248.136517 -213.235765)
			(xy 248.1072 -213.236302) (xy 248.079598 -213.235783) (xy 248.024969 -213.227827) (xy 247.972057 -213.212083)
			(xy 247.921967 -213.188878) (xy 247.875743 -213.158696) (xy 247.854724 -213.140798) (xy 247.847612 -213.134702)
			(xy 247.838976 -213.1314) (xy 247.837198 -213.130638) (xy 247.833244 -213.129434) (xy 247.825075 -213.128163)
			(xy 247.820942 -213.128098) (xy 247.753886 -213.128098) (xy 247.749749 -213.128116) (xy 247.741578 -213.129402)
			(xy 247.73763 -213.130638) (xy 247.735852 -213.1314) (xy 247.727216 -213.134702) (xy 247.720104 -213.140798)
			(xy 247.699067 -213.158676) (xy 247.652853 -213.188873) (xy 247.602768 -213.212092) (xy 247.549859 -213.227848)
			(xy 247.495231 -213.235811) (xy 247.467628 -213.236302) (xy 247.440376 -213.235819) (xy 247.386425 -213.228065)
			(xy 247.334127 -213.212713) (xy 247.284547 -213.190073) (xy 247.238693 -213.160607) (xy 247.1975 -213.124916)
			(xy 247.161806 -213.083724) (xy 247.132338 -213.037873) (xy 247.109695 -212.988293) (xy 247.094339 -212.935996)
			(xy 247.086583 -212.882046) (xy 247.08612 -212.854794) (xy 247.086576 -212.82773) (xy 247.094228 -212.774146)
			(xy 247.109376 -212.722181) (xy 247.131718 -212.672879) (xy 247.160804 -212.62723) (xy 247.178068 -212.606382)
			(xy 247.178576 -212.605874) (xy 247.18645 -212.596476) (xy 247.189244 -212.584284) (xy 247.190439 -212.578367)
			(xy 247.190305 -212.5663) (xy 247.18899 -212.560408) (xy 247.168416 -212.479636) (xy 247.166892 -212.475064)
			(xy 247.165213 -212.470549) (xy 247.160347 -212.462236) (xy 247.15724 -212.458554) (xy 247.153176 -212.453982)
			(xy 247.143016 -212.44687) (xy 247.137174 -212.444838) (xy 247.110313 -212.434188) (xy 247.059928 -212.405901)
			(xy 247.014383 -212.370344) (xy 246.974718 -212.328327) (xy 246.94184 -212.280811) (xy 246.9165 -212.228882)
			(xy 246.899277 -212.173726) (xy 246.890565 -212.116605) (xy 246.890032 -212.087714) (xy 243.034145 -212.087714)
			(xy 243.015997 -212.107968) (xy 242.973129 -212.143643) (xy 242.925523 -212.172697) (xy 242.874194 -212.194509)
			(xy 242.820237 -212.208615) (xy 242.7648 -212.214715) (xy 242.709066 -212.212678) (xy 242.654223 -212.202548)
			(xy 242.601439 -212.184541) (xy 242.551839 -212.15904) (xy 242.506481 -212.126589) (xy 242.466332 -212.08788)
			(xy 242.432246 -212.043737) (xy 242.40495 -211.995102) (xy 242.385027 -211.943011) (xy 242.372901 -211.888574)
			(xy 242.36883 -211.832952) (xy 216.279125 -211.832952) (xy 216.281926 -211.833355) (xy 216.334215 -211.848713)
			(xy 216.383786 -211.871355) (xy 216.42963 -211.900821) (xy 216.470814 -211.936511) (xy 216.5065 -211.977699)
			(xy 216.535962 -212.023546) (xy 216.5586 -212.073119) (xy 216.573953 -212.125409) (xy 216.581708 -212.179351)
			(xy 216.581708 -212.233849) (xy 216.573953 -212.287791) (xy 216.561453 -212.330363) (xy 222.737682 -212.330363)
			(xy 222.737682 -212.278389) (xy 222.745812 -212.227054) (xy 222.761873 -212.177624) (xy 222.785469 -212.131314)
			(xy 222.816019 -212.089266) (xy 222.85277 -212.052515) (xy 222.894818 -212.021965) (xy 222.941128 -211.998369)
			(xy 222.990558 -211.982308) (xy 223.041893 -211.974178) (xy 223.093867 -211.974178) (xy 223.145202 -211.982308)
			(xy 223.194632 -211.998369) (xy 223.240942 -212.021965) (xy 223.28299 -212.052515) (xy 223.319741 -212.089266)
			(xy 223.350291 -212.131314) (xy 223.373887 -212.177624) (xy 223.389948 -212.227054) (xy 223.398078 -212.278389)
			(xy 223.398588 -212.304376) (xy 223.398078 -212.330363) (xy 223.537782 -212.330363) (xy 223.537782 -212.278389)
			(xy 223.545912 -212.227054) (xy 223.561973 -212.177624) (xy 223.585569 -212.131314) (xy 223.616119 -212.089266)
			(xy 223.65287 -212.052515) (xy 223.694918 -212.021965) (xy 223.741228 -211.998369) (xy 223.790658 -211.982308)
			(xy 223.841993 -211.974178) (xy 223.893967 -211.974178) (xy 223.945302 -211.982308) (xy 223.994732 -211.998369)
			(xy 224.041042 -212.021965) (xy 224.08309 -212.052515) (xy 224.119841 -212.089266) (xy 224.150391 -212.131314)
			(xy 224.173987 -212.177624) (xy 224.180204 -212.196759) (xy 224.737424 -212.196759) (xy 224.737424 -212.144785)
			(xy 224.745554 -212.09345) (xy 224.761615 -212.04402) (xy 224.785211 -211.99771) (xy 224.815761 -211.955662)
			(xy 224.852512 -211.918911) (xy 224.89456 -211.888361) (xy 224.94087 -211.864765) (xy 224.9903 -211.848704)
			(xy 225.041635 -211.840574) (xy 225.093609 -211.840574) (xy 225.144944 -211.848704) (xy 225.194374 -211.864765)
			(xy 225.240684 -211.888361) (xy 225.282732 -211.918911) (xy 225.319483 -211.955662) (xy 225.350033 -211.99771)
			(xy 225.373629 -212.04402) (xy 225.38969 -212.09345) (xy 225.39782 -212.144785) (xy 225.39833 -212.170772)
			(xy 225.39782 -212.196759) (xy 225.38969 -212.248094) (xy 225.373629 -212.297524) (xy 225.356638 -212.330871)
			(xy 226.737674 -212.330871) (xy 226.737674 -212.278897) (xy 226.745804 -212.227562) (xy 226.761865 -212.178132)
			(xy 226.785461 -212.131822) (xy 226.816011 -212.089774) (xy 226.852762 -212.053023) (xy 226.89481 -212.022473)
			(xy 226.94112 -211.998877) (xy 226.99055 -211.982816) (xy 227.041885 -211.974686) (xy 227.093859 -211.974686)
			(xy 227.145194 -211.982816) (xy 227.194624 -211.998877) (xy 227.240934 -212.022473) (xy 227.282982 -212.053023)
			(xy 227.319733 -212.089774) (xy 227.350283 -212.131822) (xy 227.373879 -212.178132) (xy 227.38994 -212.227562)
			(xy 227.39807 -212.278897) (xy 227.39858 -212.304884) (xy 227.39808 -212.330363) (xy 228.337366 -212.330363)
			(xy 228.337366 -212.278389) (xy 228.345496 -212.227054) (xy 228.361557 -212.177624) (xy 228.385153 -212.131314)
			(xy 228.415703 -212.089266) (xy 228.452454 -212.052515) (xy 228.494502 -212.021965) (xy 228.540812 -211.998369)
			(xy 228.590242 -211.982308) (xy 228.641577 -211.974178) (xy 228.693551 -211.974178) (xy 228.744886 -211.982308)
			(xy 228.794316 -211.998369) (xy 228.840626 -212.021965) (xy 228.882674 -212.052515) (xy 228.919425 -212.089266)
			(xy 228.949975 -212.131314) (xy 228.973571 -212.177624) (xy 228.989632 -212.227054) (xy 228.997762 -212.278389)
			(xy 228.998272 -212.304376) (xy 228.997762 -212.330363) (xy 233.137204 -212.330363) (xy 233.137204 -212.278389)
			(xy 233.145334 -212.227054) (xy 233.161395 -212.177624) (xy 233.184991 -212.131314) (xy 233.215541 -212.089266)
			(xy 233.252292 -212.052515) (xy 233.29434 -212.021965) (xy 233.34065 -211.998369) (xy 233.39008 -211.982308)
			(xy 233.441415 -211.974178) (xy 233.493389 -211.974178) (xy 233.544724 -211.982308) (xy 233.594154 -211.998369)
			(xy 233.640464 -212.021965) (xy 233.682512 -212.052515) (xy 233.719263 -212.089266) (xy 233.749813 -212.131314)
			(xy 233.773409 -212.177624) (xy 233.78947 -212.227054) (xy 233.7976 -212.278389) (xy 233.79811 -212.304376)
			(xy 233.7976 -212.330363) (xy 235.53725 -212.330363) (xy 235.53725 -212.278389) (xy 235.54538 -212.227054)
			(xy 235.561441 -212.177624) (xy 235.585037 -212.131314) (xy 235.615587 -212.089266) (xy 235.652338 -212.052515)
			(xy 235.694386 -212.021965) (xy 235.740696 -211.998369) (xy 235.790126 -211.982308) (xy 235.841461 -211.974178)
			(xy 235.893435 -211.974178) (xy 235.94477 -211.982308) (xy 235.9942 -211.998369) (xy 236.04051 -212.021965)
			(xy 236.082558 -212.052515) (xy 236.119309 -212.089266) (xy 236.149859 -212.131314) (xy 236.173455 -212.177624)
			(xy 236.189516 -212.227054) (xy 236.197646 -212.278389) (xy 236.197937 -212.2932) (xy 240.647472 -212.2932)
			(xy 240.651543 -212.237578) (xy 240.663669 -212.183141) (xy 240.683592 -212.13105) (xy 240.710888 -212.082415)
			(xy 240.744974 -212.038272) (xy 240.785123 -211.999563) (xy 240.830481 -211.967112) (xy 240.880081 -211.941611)
			(xy 240.932865 -211.923604) (xy 240.987708 -211.913474) (xy 241.043442 -211.911437) (xy 241.098879 -211.917537)
			(xy 241.152836 -211.931643) (xy 241.204165 -211.953455) (xy 241.251771 -211.982509) (xy 241.294639 -212.018184)
			(xy 241.331856 -212.059721) (xy 241.362629 -212.106234) (xy 241.386301 -212.156731) (xy 241.402369 -212.210138)
			(xy 241.410489 -212.265314) (xy 241.410998 -212.2932) (xy 241.410489 -212.321086) (xy 241.402369 -212.376262)
			(xy 241.386301 -212.429669) (xy 241.362629 -212.480166) (xy 241.331856 -212.526679) (xy 241.294639 -212.568216)
			(xy 241.251771 -212.603891) (xy 241.204165 -212.632945) (xy 241.152836 -212.654757) (xy 241.098879 -212.668863)
			(xy 241.043442 -212.674963) (xy 240.987708 -212.672926) (xy 240.932865 -212.662796) (xy 240.880081 -212.644789)
			(xy 240.830481 -212.619288) (xy 240.785123 -212.586837) (xy 240.744974 -212.548128) (xy 240.710888 -212.503985)
			(xy 240.683592 -212.45535) (xy 240.663669 -212.403259) (xy 240.651543 -212.348822) (xy 240.647472 -212.2932)
			(xy 236.197937 -212.2932) (xy 236.198156 -212.304376) (xy 236.197646 -212.330363) (xy 236.189516 -212.381698)
			(xy 236.173455 -212.431128) (xy 236.149859 -212.477438) (xy 236.119309 -212.519486) (xy 236.082558 -212.556237)
			(xy 236.04051 -212.586787) (xy 235.9942 -212.610383) (xy 235.94477 -212.626444) (xy 235.893435 -212.634574)
			(xy 235.841461 -212.634574) (xy 235.790126 -212.626444) (xy 235.740696 -212.610383) (xy 235.694386 -212.586787)
			(xy 235.652338 -212.556237) (xy 235.615587 -212.519486) (xy 235.585037 -212.477438) (xy 235.561441 -212.431128)
			(xy 235.54538 -212.381698) (xy 235.53725 -212.330363) (xy 233.7976 -212.330363) (xy 233.78947 -212.381698)
			(xy 233.773409 -212.431128) (xy 233.749813 -212.477438) (xy 233.719263 -212.519486) (xy 233.682512 -212.556237)
			(xy 233.640464 -212.586787) (xy 233.594154 -212.610383) (xy 233.544724 -212.626444) (xy 233.493389 -212.634574)
			(xy 233.441415 -212.634574) (xy 233.39008 -212.626444) (xy 233.34065 -212.610383) (xy 233.29434 -212.586787)
			(xy 233.252292 -212.556237) (xy 233.215541 -212.519486) (xy 233.184991 -212.477438) (xy 233.161395 -212.431128)
			(xy 233.145334 -212.381698) (xy 233.137204 -212.330363) (xy 228.997762 -212.330363) (xy 228.989632 -212.381698)
			(xy 228.973571 -212.431128) (xy 228.949975 -212.477438) (xy 228.919425 -212.519486) (xy 228.882674 -212.556237)
			(xy 228.840626 -212.586787) (xy 228.794316 -212.610383) (xy 228.744886 -212.626444) (xy 228.693551 -212.634574)
			(xy 228.641577 -212.634574) (xy 228.590242 -212.626444) (xy 228.540812 -212.610383) (xy 228.494502 -212.586787)
			(xy 228.452454 -212.556237) (xy 228.415703 -212.519486) (xy 228.385153 -212.477438) (xy 228.361557 -212.431128)
			(xy 228.345496 -212.381698) (xy 228.337366 -212.330363) (xy 227.39808 -212.330363) (xy 227.39807 -212.330871)
			(xy 227.38994 -212.382206) (xy 227.373879 -212.431636) (xy 227.350283 -212.477946) (xy 227.319733 -212.519994)
			(xy 227.282982 -212.556745) (xy 227.240934 -212.587295) (xy 227.194624 -212.610891) (xy 227.145194 -212.626952)
			(xy 227.093859 -212.635082) (xy 227.041885 -212.635082) (xy 226.99055 -212.626952) (xy 226.94112 -212.610891)
			(xy 226.89481 -212.587295) (xy 226.852762 -212.556745) (xy 226.816011 -212.519994) (xy 226.785461 -212.477946)
			(xy 226.761865 -212.431636) (xy 226.745804 -212.382206) (xy 226.737674 -212.330871) (xy 225.356638 -212.330871)
			(xy 225.350033 -212.343834) (xy 225.319483 -212.385882) (xy 225.282732 -212.422633) (xy 225.240684 -212.453183)
			(xy 225.194374 -212.476779) (xy 225.144944 -212.49284) (xy 225.093609 -212.50097) (xy 225.041635 -212.50097)
			(xy 224.9903 -212.49284) (xy 224.94087 -212.476779) (xy 224.89456 -212.453183) (xy 224.852512 -212.422633)
			(xy 224.815761 -212.385882) (xy 224.785211 -212.343834) (xy 224.761615 -212.297524) (xy 224.745554 -212.248094)
			(xy 224.737424 -212.196759) (xy 224.180204 -212.196759) (xy 224.190048 -212.227054) (xy 224.198178 -212.278389)
			(xy 224.198688 -212.304376) (xy 224.198178 -212.330363) (xy 224.190048 -212.381698) (xy 224.173987 -212.431128)
			(xy 224.150391 -212.477438) (xy 224.119841 -212.519486) (xy 224.08309 -212.556237) (xy 224.041042 -212.586787)
			(xy 223.994732 -212.610383) (xy 223.945302 -212.626444) (xy 223.893967 -212.634574) (xy 223.841993 -212.634574)
			(xy 223.790658 -212.626444) (xy 223.741228 -212.610383) (xy 223.694918 -212.586787) (xy 223.65287 -212.556237)
			(xy 223.616119 -212.519486) (xy 223.585569 -212.477438) (xy 223.561973 -212.431128) (xy 223.545912 -212.381698)
			(xy 223.537782 -212.330363) (xy 223.398078 -212.330363) (xy 223.389948 -212.381698) (xy 223.373887 -212.431128)
			(xy 223.350291 -212.477438) (xy 223.319741 -212.519486) (xy 223.28299 -212.556237) (xy 223.240942 -212.586787)
			(xy 223.194632 -212.610383) (xy 223.145202 -212.626444) (xy 223.093867 -212.634574) (xy 223.041893 -212.634574)
			(xy 222.990558 -212.626444) (xy 222.941128 -212.610383) (xy 222.894818 -212.586787) (xy 222.85277 -212.556237)
			(xy 222.816019 -212.519486) (xy 222.785469 -212.477438) (xy 222.761873 -212.431128) (xy 222.745812 -212.381698)
			(xy 222.737682 -212.330363) (xy 216.561453 -212.330363) (xy 216.5586 -212.340081) (xy 216.535962 -212.389654)
			(xy 216.5065 -212.435501) (xy 216.470814 -212.476689) (xy 216.42963 -212.512379) (xy 216.383786 -212.541845)
			(xy 216.334215 -212.564487) (xy 216.281926 -212.579845) (xy 216.227985 -212.587605) (xy 216.200736 -212.588094)
			(xy 216.200482 -212.588094) (xy 216.174187 -212.587649) (xy 216.122097 -212.580401) (xy 216.071496 -212.566073)
			(xy 216.023339 -212.544935) (xy 215.97854 -212.517387) (xy 215.937946 -212.483952) (xy 215.919812 -212.464904)
			(xy 215.912287 -212.457506) (xy 215.89301 -212.44898) (xy 215.882474 -212.448394) (xy 215.807798 -212.448394)
			(xy 215.797247 -212.44891) (xy 215.777952 -212.457455) (xy 215.77046 -212.464904) (xy 215.752361 -212.483989)
			(xy 215.711772 -212.517443) (xy 215.66697 -212.544998) (xy 215.618804 -212.566132) (xy 215.56819 -212.580443)
			(xy 215.516089 -212.58766) (xy 215.48979 -212.588094) (xy 215.489536 -212.588094) (xy 215.46228 -212.587662)
			(xy 215.408324 -212.579908) (xy 215.356019 -212.564555) (xy 215.306433 -212.541914) (xy 215.260574 -212.512446)
			(xy 215.219375 -212.476751) (xy 215.183676 -212.435555) (xy 215.154204 -212.389699) (xy 215.131558 -212.340114)
			(xy 215.116199 -212.287812) (xy 215.108441 -212.233856) (xy 213.042439 -212.233856) (xy 213.084359 -212.252997)
			(xy 213.130214 -212.282461) (xy 213.171409 -212.318152) (xy 213.207105 -212.359341) (xy 213.236576 -212.405192)
			(xy 213.259223 -212.45477) (xy 213.274583 -212.507066) (xy 213.282344 -212.561015) (xy 213.282348 -212.615521)
			(xy 213.274596 -212.669472) (xy 213.259245 -212.72177) (xy 213.236607 -212.771352) (xy 213.207144 -212.817207)
			(xy 213.171454 -212.858403) (xy 213.130265 -212.8941) (xy 213.084415 -212.923573) (xy 213.034838 -212.94622)
			(xy 212.982542 -212.961581) (xy 212.928593 -212.969343) (xy 212.874087 -212.969349) (xy 212.820136 -212.961598)
			(xy 212.767837 -212.946248) (xy 212.718255 -212.923611) (xy 212.672399 -212.894148) (xy 212.631203 -212.85846)
			(xy 212.595504 -212.817272) (xy 212.566031 -212.771422) (xy 212.543383 -212.721845) (xy 212.528021 -212.66955)
			(xy 212.520257 -212.615601) (xy 212.519768 -212.588348) (xy 212.520276 -212.57006) (xy 212.520535 -212.555353)
			(xy 212.513528 -212.526794) (xy 212.498687 -212.501408) (xy 212.477238 -212.481291) (xy 212.450954 -212.468107)
			(xy 212.422005 -212.462943) (xy 212.392782 -212.466227) (xy 212.379052 -212.471508) (xy 212.355454 -212.481052)
			(xy 212.306359 -212.494495) (xy 212.255913 -212.501295) (xy 212.230462 -212.501734) (xy 212.203214 -212.501181)
			(xy 212.149273 -212.49342) (xy 212.096985 -212.478062) (xy 212.047415 -212.455418) (xy 212.001573 -212.425951)
			(xy 211.96039 -212.390259) (xy 211.924706 -212.34907) (xy 211.895247 -212.303222) (xy 211.872613 -212.253648)
			(xy 211.857265 -212.201357) (xy 211.849514 -212.147414) (xy 209.840441 -212.147414) (xy 209.85648 -212.151607)
			(xy 209.907809 -212.173419) (xy 209.955415 -212.202473) (xy 209.998283 -212.238148) (xy 210.0355 -212.279685)
			(xy 210.066273 -212.326198) (xy 210.089945 -212.376695) (xy 210.106013 -212.430102) (xy 210.114133 -212.485278)
			(xy 210.114642 -212.513164) (xy 210.114133 -212.54105) (xy 210.106013 -212.596226) (xy 210.089945 -212.649633)
			(xy 210.066273 -212.70013) (xy 210.0355 -212.746643) (xy 209.998283 -212.78818) (xy 209.955415 -212.823855)
			(xy 209.907809 -212.852909) (xy 209.85648 -212.874721) (xy 209.802523 -212.888827) (xy 209.747086 -212.894927)
			(xy 209.691352 -212.89289) (xy 209.636509 -212.88276) (xy 209.583725 -212.864753) (xy 209.534125 -212.839252)
			(xy 209.488767 -212.806801) (xy 209.448618 -212.768092) (xy 209.414532 -212.723949) (xy 209.387236 -212.675314)
			(xy 209.367313 -212.623223) (xy 209.355187 -212.568786) (xy 209.351116 -212.513164) (xy 207.423595 -212.513164)
			(xy 207.451195 -212.525768) (xy 207.497056 -212.555239) (xy 207.538256 -212.590938) (xy 207.573956 -212.632137)
			(xy 207.603429 -212.677998) (xy 207.626075 -212.727586) (xy 207.641432 -212.779892) (xy 207.64919 -212.833852)
			(xy 207.649188 -212.888367) (xy 207.641428 -212.942326) (xy 207.626068 -212.994632) (xy 207.60342 -213.044219)
			(xy 207.573945 -213.090078) (xy 207.555744 -213.11108) (xy 210.384896 -213.11108) (xy 210.388967 -213.055458)
			(xy 210.401093 -213.001021) (xy 210.421016 -212.94893) (xy 210.448312 -212.900295) (xy 210.482398 -212.856152)
			(xy 210.522547 -212.817443) (xy 210.567905 -212.784992) (xy 210.617505 -212.759491) (xy 210.670289 -212.741484)
			(xy 210.725132 -212.731354) (xy 210.780866 -212.729317) (xy 210.836303 -212.735417) (xy 210.89026 -212.749523)
			(xy 210.941589 -212.771335) (xy 210.989195 -212.800389) (xy 211.032063 -212.836064) (xy 211.06928 -212.877601)
			(xy 211.100053 -212.924114) (xy 211.123725 -212.974611) (xy 211.139793 -213.028018) (xy 211.147913 -213.083194)
			(xy 211.148422 -213.11108) (xy 211.147913 -213.138966) (xy 211.139793 -213.194142) (xy 211.123725 -213.247549)
			(xy 211.122644 -213.249856) (xy 215.108441 -213.249856) (xy 215.108441 -213.195344) (xy 215.116199 -213.141388)
			(xy 215.131558 -213.089086) (xy 215.154204 -213.039501) (xy 215.183676 -212.993645) (xy 215.219375 -212.952449)
			(xy 215.260574 -212.916754) (xy 215.306433 -212.887286) (xy 215.356019 -212.864645) (xy 215.408324 -212.849292)
			(xy 215.46228 -212.841538) (xy 215.489536 -212.841078) (xy 215.48979 -212.841078) (xy 215.516084 -212.84155)
			(xy 215.568172 -212.848794) (xy 215.618773 -212.863118) (xy 215.666929 -212.884251) (xy 215.711729 -212.911793)
			(xy 215.752325 -212.945223) (xy 215.77046 -212.964268) (xy 215.777999 -212.971649) (xy 215.797266 -212.980187)
			(xy 215.807798 -212.980778) (xy 215.882474 -212.980778) (xy 215.893025 -212.980255) (xy 215.91232 -212.971716)
			(xy 215.919812 -212.964268) (xy 215.937939 -212.94521) (xy 215.97852 -212.911752) (xy 216.023316 -212.884191)
			(xy 216.071477 -212.863051) (xy 216.122086 -212.848735) (xy 216.174184 -212.841514) (xy 216.200482 -212.841078)
			(xy 216.200736 -212.841078) (xy 216.227985 -212.841595) (xy 216.281926 -212.849355) (xy 216.334215 -212.864713)
			(xy 216.383786 -212.887355) (xy 216.42963 -212.916821) (xy 216.470814 -212.952511) (xy 216.5065 -212.993699)
			(xy 216.535962 -213.039546) (xy 216.5586 -213.089119) (xy 216.570739 -213.130463) (xy 226.737674 -213.130463)
			(xy 226.737674 -213.078489) (xy 226.745804 -213.027154) (xy 226.761865 -212.977724) (xy 226.785461 -212.931414)
			(xy 226.816011 -212.889366) (xy 226.852762 -212.852615) (xy 226.89481 -212.822065) (xy 226.94112 -212.798469)
			(xy 226.99055 -212.782408) (xy 227.041885 -212.774278) (xy 227.093859 -212.774278) (xy 227.145194 -212.782408)
			(xy 227.194624 -212.798469) (xy 227.240934 -212.822065) (xy 227.282982 -212.852615) (xy 227.319733 -212.889366)
			(xy 227.350283 -212.931414) (xy 227.373879 -212.977724) (xy 227.38994 -213.027154) (xy 227.39807 -213.078489)
			(xy 227.39858 -213.104476) (xy 227.39808 -213.129955) (xy 228.33762 -213.129955) (xy 228.33762 -213.077981)
			(xy 228.34575 -213.026646) (xy 228.361811 -212.977216) (xy 228.385407 -212.930906) (xy 228.415957 -212.888858)
			(xy 228.452708 -212.852107) (xy 228.494756 -212.821557) (xy 228.541066 -212.797961) (xy 228.590496 -212.7819)
			(xy 228.641831 -212.77377) (xy 228.693805 -212.77377) (xy 228.74514 -212.7819) (xy 228.79457 -212.797961)
			(xy 228.84088 -212.821557) (xy 228.882928 -212.852107) (xy 228.919679 -212.888858) (xy 228.950229 -212.930906)
			(xy 228.973825 -212.977216) (xy 228.989886 -213.026646) (xy 228.998016 -213.077981) (xy 228.998526 -213.103968)
			(xy 228.998016 -213.129955) (xy 228.997936 -213.130463) (xy 229.937312 -213.130463) (xy 229.937312 -213.078489)
			(xy 229.945442 -213.027154) (xy 229.961503 -212.977724) (xy 229.985099 -212.931414) (xy 230.015649 -212.889366)
			(xy 230.0524 -212.852615) (xy 230.094448 -212.822065) (xy 230.140758 -212.798469) (xy 230.190188 -212.782408)
			(xy 230.241523 -212.774278) (xy 230.293497 -212.774278) (xy 230.344832 -212.782408) (xy 230.394262 -212.798469)
			(xy 230.440572 -212.822065) (xy 230.48262 -212.852615) (xy 230.519371 -212.889366) (xy 230.549921 -212.931414)
			(xy 230.573517 -212.977724) (xy 230.589578 -213.027154) (xy 230.597708 -213.078489) (xy 230.598218 -213.104476)
			(xy 230.597708 -213.130463) (xy 230.737158 -213.130463) (xy 230.737158 -213.078489) (xy 230.745288 -213.027154)
			(xy 230.761349 -212.977724) (xy 230.784945 -212.931414) (xy 230.815495 -212.889366) (xy 230.852246 -212.852615)
			(xy 230.894294 -212.822065) (xy 230.940604 -212.798469) (xy 230.990034 -212.782408) (xy 231.041369 -212.774278)
			(xy 231.093343 -212.774278) (xy 231.144678 -212.782408) (xy 231.194108 -212.798469) (xy 231.240418 -212.822065)
			(xy 231.282466 -212.852615) (xy 231.319217 -212.889366) (xy 231.349767 -212.931414) (xy 231.373363 -212.977724)
			(xy 231.389424 -213.027154) (xy 231.397554 -213.078489) (xy 231.398064 -213.104476) (xy 231.397554 -213.130463)
			(xy 233.137204 -213.130463) (xy 233.137204 -213.078489) (xy 233.145334 -213.027154) (xy 233.161395 -212.977724)
			(xy 233.184991 -212.931414) (xy 233.215541 -212.889366) (xy 233.252292 -212.852615) (xy 233.29434 -212.822065)
			(xy 233.34065 -212.798469) (xy 233.39008 -212.782408) (xy 233.441415 -212.774278) (xy 233.493389 -212.774278)
			(xy 233.502999 -212.7758) (xy 242.111782 -212.7758) (xy 242.115853 -212.720178) (xy 242.127979 -212.665741)
			(xy 242.147902 -212.61365) (xy 242.175198 -212.565015) (xy 242.209284 -212.520872) (xy 242.249433 -212.482163)
			(xy 242.294791 -212.449712) (xy 242.344391 -212.424211) (xy 242.397175 -212.406204) (xy 242.452018 -212.396074)
			(xy 242.507752 -212.394037) (xy 242.563189 -212.400137) (xy 242.617146 -212.414243) (xy 242.668475 -212.436055)
			(xy 242.716081 -212.465109) (xy 242.758949 -212.500784) (xy 242.796166 -212.542321) (xy 242.826939 -212.588834)
			(xy 242.850611 -212.639331) (xy 242.866679 -212.692738) (xy 242.874799 -212.747914) (xy 242.875308 -212.7758)
			(xy 242.874799 -212.803686) (xy 242.866679 -212.858862) (xy 242.850611 -212.912269) (xy 242.826939 -212.962766)
			(xy 242.811997 -212.98535) (xy 243.756432 -212.98535) (xy 243.760503 -212.929728) (xy 243.772629 -212.875291)
			(xy 243.792552 -212.8232) (xy 243.819848 -212.774565) (xy 243.853934 -212.730422) (xy 243.894083 -212.691713)
			(xy 243.939441 -212.659262) (xy 243.989041 -212.633761) (xy 244.041825 -212.615754) (xy 244.096668 -212.605624)
			(xy 244.152402 -212.603587) (xy 244.207839 -212.609687) (xy 244.261796 -212.623793) (xy 244.313125 -212.645605)
			(xy 244.360731 -212.674659) (xy 244.403599 -212.710334) (xy 244.440816 -212.751871) (xy 244.471589 -212.798384)
			(xy 244.495261 -212.848881) (xy 244.511329 -212.902288) (xy 244.519449 -212.957464) (xy 244.519958 -212.98535)
			(xy 244.519449 -213.013236) (xy 244.511329 -213.068412) (xy 244.495261 -213.121819) (xy 244.471589 -213.172316)
			(xy 244.459336 -213.190836) (xy 245.822468 -213.190836) (xy 245.826539 -213.135214) (xy 245.838665 -213.080777)
			(xy 245.858588 -213.028686) (xy 245.885884 -212.980051) (xy 245.91997 -212.935908) (xy 245.960119 -212.897199)
			(xy 246.005477 -212.864748) (xy 246.055077 -212.839247) (xy 246.107861 -212.82124) (xy 246.162704 -212.81111)
			(xy 246.218438 -212.809073) (xy 246.273875 -212.815173) (xy 246.327832 -212.829279) (xy 246.379161 -212.851091)
			(xy 246.426767 -212.880145) (xy 246.469635 -212.91582) (xy 246.506852 -212.957357) (xy 246.537625 -213.00387)
			(xy 246.561297 -213.054367) (xy 246.577365 -213.107774) (xy 246.585485 -213.16295) (xy 246.585994 -213.190836)
			(xy 246.585485 -213.218722) (xy 246.577365 -213.273898) (xy 246.561297 -213.327305) (xy 246.537625 -213.377802)
			(xy 246.506852 -213.424315) (xy 246.469635 -213.465852) (xy 246.426767 -213.501527) (xy 246.379161 -213.530581)
			(xy 246.327832 -213.552393) (xy 246.273875 -213.566499) (xy 246.218438 -213.572599) (xy 246.162704 -213.570562)
			(xy 246.107861 -213.560432) (xy 246.055077 -213.542425) (xy 246.005477 -213.516924) (xy 245.960119 -213.484473)
			(xy 245.91997 -213.445764) (xy 245.885884 -213.401621) (xy 245.858588 -213.352986) (xy 245.838665 -213.300895)
			(xy 245.826539 -213.246458) (xy 245.822468 -213.190836) (xy 244.459336 -213.190836) (xy 244.440816 -213.218829)
			(xy 244.403599 -213.260366) (xy 244.360731 -213.296041) (xy 244.313125 -213.325095) (xy 244.261796 -213.346907)
			(xy 244.207839 -213.361013) (xy 244.152402 -213.367113) (xy 244.096668 -213.365076) (xy 244.041825 -213.354946)
			(xy 243.989041 -213.336939) (xy 243.939441 -213.311438) (xy 243.894083 -213.278987) (xy 243.853934 -213.240278)
			(xy 243.819848 -213.196135) (xy 243.792552 -213.1475) (xy 243.772629 -213.095409) (xy 243.760503 -213.040972)
			(xy 243.756432 -212.98535) (xy 242.811997 -212.98535) (xy 242.796166 -213.009279) (xy 242.758949 -213.050816)
			(xy 242.716081 -213.086491) (xy 242.668475 -213.115545) (xy 242.617146 -213.137357) (xy 242.563189 -213.151463)
			(xy 242.507752 -213.157563) (xy 242.452018 -213.155526) (xy 242.397175 -213.145396) (xy 242.344391 -213.127389)
			(xy 242.294791 -213.101888) (xy 242.249433 -213.069437) (xy 242.209284 -213.030728) (xy 242.175198 -212.986585)
			(xy 242.147902 -212.93795) (xy 242.127979 -212.885859) (xy 242.115853 -212.831422) (xy 242.111782 -212.7758)
			(xy 233.502999 -212.7758) (xy 233.544724 -212.782408) (xy 233.594154 -212.798469) (xy 233.640464 -212.822065)
			(xy 233.682512 -212.852615) (xy 233.719263 -212.889366) (xy 233.749813 -212.931414) (xy 233.773409 -212.977724)
			(xy 233.78947 -213.027154) (xy 233.7976 -213.078489) (xy 233.79811 -213.104476) (xy 233.7976 -213.130463)
			(xy 233.78947 -213.181798) (xy 233.773409 -213.231228) (xy 233.749813 -213.277538) (xy 233.719263 -213.319586)
			(xy 233.682512 -213.356337) (xy 233.640464 -213.386887) (xy 233.594154 -213.410483) (xy 233.544724 -213.426544)
			(xy 233.493389 -213.434674) (xy 233.441415 -213.434674) (xy 233.39008 -213.426544) (xy 233.34065 -213.410483)
			(xy 233.29434 -213.386887) (xy 233.252292 -213.356337) (xy 233.215541 -213.319586) (xy 233.184991 -213.277538)
			(xy 233.161395 -213.231228) (xy 233.145334 -213.181798) (xy 233.137204 -213.130463) (xy 231.397554 -213.130463)
			(xy 231.389424 -213.181798) (xy 231.373363 -213.231228) (xy 231.349767 -213.277538) (xy 231.319217 -213.319586)
			(xy 231.282466 -213.356337) (xy 231.240418 -213.386887) (xy 231.194108 -213.410483) (xy 231.144678 -213.426544)
			(xy 231.093343 -213.434674) (xy 231.041369 -213.434674) (xy 230.990034 -213.426544) (xy 230.940604 -213.410483)
			(xy 230.894294 -213.386887) (xy 230.852246 -213.356337) (xy 230.815495 -213.319586) (xy 230.784945 -213.277538)
			(xy 230.761349 -213.231228) (xy 230.745288 -213.181798) (xy 230.737158 -213.130463) (xy 230.597708 -213.130463)
			(xy 230.589578 -213.181798) (xy 230.573517 -213.231228) (xy 230.549921 -213.277538) (xy 230.519371 -213.319586)
			(xy 230.48262 -213.356337) (xy 230.440572 -213.386887) (xy 230.394262 -213.410483) (xy 230.344832 -213.426544)
			(xy 230.293497 -213.434674) (xy 230.241523 -213.434674) (xy 230.190188 -213.426544) (xy 230.140758 -213.410483)
			(xy 230.094448 -213.386887) (xy 230.0524 -213.356337) (xy 230.015649 -213.319586) (xy 229.985099 -213.277538)
			(xy 229.961503 -213.231228) (xy 229.945442 -213.181798) (xy 229.937312 -213.130463) (xy 228.997936 -213.130463)
			(xy 228.989886 -213.18129) (xy 228.973825 -213.23072) (xy 228.950229 -213.27703) (xy 228.919679 -213.319078)
			(xy 228.882928 -213.355829) (xy 228.84088 -213.386379) (xy 228.79457 -213.409975) (xy 228.74514 -213.426036)
			(xy 228.693805 -213.434166) (xy 228.641831 -213.434166) (xy 228.590496 -213.426036) (xy 228.541066 -213.409975)
			(xy 228.494756 -213.386379) (xy 228.452708 -213.355829) (xy 228.415957 -213.319078) (xy 228.385407 -213.27703)
			(xy 228.361811 -213.23072) (xy 228.34575 -213.18129) (xy 228.33762 -213.129955) (xy 227.39808 -213.129955)
			(xy 227.39807 -213.130463) (xy 227.38994 -213.181798) (xy 227.373879 -213.231228) (xy 227.350283 -213.277538)
			(xy 227.319733 -213.319586) (xy 227.282982 -213.356337) (xy 227.240934 -213.386887) (xy 227.194624 -213.410483)
			(xy 227.145194 -213.426544) (xy 227.093859 -213.434674) (xy 227.041885 -213.434674) (xy 226.99055 -213.426544)
			(xy 226.94112 -213.410483) (xy 226.89481 -213.386887) (xy 226.852762 -213.356337) (xy 226.816011 -213.319586)
			(xy 226.785461 -213.277538) (xy 226.761865 -213.231228) (xy 226.745804 -213.181798) (xy 226.737674 -213.130463)
			(xy 216.570739 -213.130463) (xy 216.573953 -213.141409) (xy 216.581708 -213.195351) (xy 216.581708 -213.249849)
			(xy 216.573953 -213.303791) (xy 216.5586 -213.356081) (xy 216.535962 -213.405654) (xy 216.5065 -213.451501)
			(xy 216.470814 -213.492689) (xy 216.42963 -213.528379) (xy 216.383786 -213.557845) (xy 216.334215 -213.580487)
			(xy 216.281926 -213.595845) (xy 216.227985 -213.603605) (xy 216.200736 -213.604094) (xy 216.200482 -213.604094)
			(xy 216.174187 -213.603649) (xy 216.122097 -213.596401) (xy 216.071496 -213.582073) (xy 216.023339 -213.560935)
			(xy 215.97854 -213.533387) (xy 215.937946 -213.499952) (xy 215.919812 -213.480904) (xy 215.912287 -213.473506)
			(xy 215.89301 -213.46498) (xy 215.882474 -213.464394) (xy 215.807798 -213.464394) (xy 215.797247 -213.46491)
			(xy 215.777952 -213.473455) (xy 215.77046 -213.480904) (xy 215.752361 -213.499989) (xy 215.711772 -213.533443)
			(xy 215.66697 -213.560998) (xy 215.618804 -213.582132) (xy 215.56819 -213.596443) (xy 215.516089 -213.60366)
			(xy 215.48979 -213.604094) (xy 215.489536 -213.604094) (xy 215.46228 -213.603662) (xy 215.408324 -213.595908)
			(xy 215.356019 -213.580555) (xy 215.306433 -213.557914) (xy 215.260574 -213.528446) (xy 215.219375 -213.492751)
			(xy 215.183676 -213.451555) (xy 215.154204 -213.405699) (xy 215.131558 -213.356114) (xy 215.116199 -213.303812)
			(xy 215.108441 -213.249856) (xy 211.122644 -213.249856) (xy 211.100053 -213.298046) (xy 211.06928 -213.344559)
			(xy 211.032063 -213.386096) (xy 210.989195 -213.421771) (xy 210.941589 -213.450825) (xy 210.89026 -213.472637)
			(xy 210.836303 -213.486743) (xy 210.780866 -213.492843) (xy 210.725132 -213.490806) (xy 210.670289 -213.480676)
			(xy 210.617505 -213.462669) (xy 210.567905 -213.437168) (xy 210.522547 -213.404717) (xy 210.482398 -213.366008)
			(xy 210.448312 -213.321865) (xy 210.421016 -213.27323) (xy 210.401093 -213.221139) (xy 210.388967 -213.166702)
			(xy 210.384896 -213.11108) (xy 207.555744 -213.11108) (xy 207.538243 -213.131275) (xy 207.497041 -213.166972)
			(xy 207.451179 -213.196441) (xy 207.401589 -213.219084) (xy 207.349282 -213.234438) (xy 207.295321 -213.242192)
			(xy 207.268064 -213.242652) (xy 207.255364 -213.242398) (xy 207.241856 -213.242384) (xy 207.215579 -213.248595)
			(xy 207.191848 -213.261475) (xy 207.172322 -213.280125) (xy 207.158366 -213.30324) (xy 207.150957 -213.329205)
			(xy 207.150611 -213.356205) (xy 207.157354 -213.382351) (xy 207.16367 -213.39429) (xy 207.175522 -213.415906)
			(xy 207.194143 -213.461554) (xy 207.206729 -213.509219) (xy 207.213071 -213.558108) (xy 207.213454 -213.582758)
			(xy 207.21299 -213.610015) (xy 207.205237 -213.663976) (xy 207.189884 -213.716283) (xy 207.167242 -213.765873)
			(xy 207.137773 -213.811736) (xy 207.102077 -213.852938) (xy 207.06088 -213.88864) (xy 207.015021 -213.918116)
			(xy 206.965435 -213.940765) (xy 206.913129 -213.956126) (xy 206.85917 -213.963886) (xy 206.804655 -213.963888)
			(xy 206.750696 -213.956131) (xy 206.698389 -213.940774) (xy 206.648801 -213.918128) (xy 206.60294 -213.888656)
			(xy 206.561741 -213.852956) (xy 206.526042 -213.811757) (xy 206.49657 -213.765896) (xy 206.473925 -213.716307)
			(xy 206.458568 -213.664) (xy 206.450812 -213.610041) (xy 196.968618 -213.610041) (xy 196.968618 -214.038688)
			(xy 210.37626 -214.038688) (xy 210.380331 -213.983066) (xy 210.392457 -213.928629) (xy 210.41238 -213.876538)
			(xy 210.439676 -213.827903) (xy 210.473762 -213.78376) (xy 210.513911 -213.745051) (xy 210.559269 -213.7126)
			(xy 210.608869 -213.687099) (xy 210.661653 -213.669092) (xy 210.716496 -213.658962) (xy 210.77223 -213.656925)
			(xy 210.827667 -213.663025) (xy 210.881624 -213.677131) (xy 210.932953 -213.698943) (xy 210.980559 -213.727997)
			(xy 211.023427 -213.763672) (xy 211.060644 -213.805209) (xy 211.091417 -213.851722) (xy 211.115089 -213.902219)
			(xy 211.131157 -213.955626) (xy 211.139277 -214.010802) (xy 211.139786 -214.038688) (xy 211.139277 -214.066574)
			(xy 211.131157 -214.12175) (xy 211.115089 -214.175157) (xy 211.091417 -214.225654) (xy 211.064819 -214.265856)
			(xy 215.108441 -214.265856) (xy 215.108441 -214.211344) (xy 215.116199 -214.157388) (xy 215.131558 -214.105086)
			(xy 215.154204 -214.055501) (xy 215.183676 -214.009645) (xy 215.219375 -213.968449) (xy 215.260574 -213.932754)
			(xy 215.306433 -213.903286) (xy 215.356019 -213.880645) (xy 215.408324 -213.865292) (xy 215.46228 -213.857538)
			(xy 215.489536 -213.857078) (xy 215.48979 -213.857078) (xy 215.516084 -213.85755) (xy 215.568172 -213.864794)
			(xy 215.618773 -213.879118) (xy 215.666929 -213.900251) (xy 215.711729 -213.927793) (xy 215.752325 -213.961223)
			(xy 215.77046 -213.980268) (xy 215.777999 -213.987649) (xy 215.797266 -213.996187) (xy 215.807798 -213.996778)
			(xy 215.882474 -213.996778) (xy 215.893025 -213.996255) (xy 215.91232 -213.987716) (xy 215.919812 -213.980268)
			(xy 215.937939 -213.96121) (xy 215.97852 -213.927752) (xy 216.023316 -213.900191) (xy 216.071477 -213.879051)
			(xy 216.122086 -213.864735) (xy 216.174184 -213.857514) (xy 216.200482 -213.857078) (xy 216.200736 -213.857078)
			(xy 216.227985 -213.857595) (xy 216.281926 -213.865355) (xy 216.334215 -213.880713) (xy 216.383786 -213.903355)
			(xy 216.425722 -213.930309) (xy 224.337628 -213.930309) (xy 224.337628 -213.878335) (xy 224.345758 -213.827)
			(xy 224.361819 -213.77757) (xy 224.385415 -213.73126) (xy 224.415965 -213.689212) (xy 224.452716 -213.652461)
			(xy 224.494764 -213.621911) (xy 224.541074 -213.598315) (xy 224.590504 -213.582254) (xy 224.641839 -213.574124)
			(xy 224.693813 -213.574124) (xy 224.745148 -213.582254) (xy 224.794578 -213.598315) (xy 224.840888 -213.621911)
			(xy 224.882936 -213.652461) (xy 224.919687 -213.689212) (xy 224.950237 -213.73126) (xy 224.973833 -213.77757)
			(xy 224.989894 -213.827) (xy 224.998024 -213.878335) (xy 224.998534 -213.904322) (xy 224.998024 -213.930309)
			(xy 225.137728 -213.930309) (xy 225.137728 -213.878335) (xy 225.145858 -213.827) (xy 225.161919 -213.77757)
			(xy 225.185515 -213.73126) (xy 225.216065 -213.689212) (xy 225.252816 -213.652461) (xy 225.294864 -213.621911)
			(xy 225.341174 -213.598315) (xy 225.390604 -213.582254) (xy 225.441939 -213.574124) (xy 225.493913 -213.574124)
			(xy 225.545248 -213.582254) (xy 225.594678 -213.598315) (xy 225.640988 -213.621911) (xy 225.683036 -213.652461)
			(xy 225.719787 -213.689212) (xy 225.750337 -213.73126) (xy 225.773933 -213.77757) (xy 225.789994 -213.827)
			(xy 225.798124 -213.878335) (xy 225.798634 -213.904322) (xy 225.798124 -213.930309) (xy 225.937574 -213.930309)
			(xy 225.937574 -213.878335) (xy 225.945704 -213.827) (xy 225.961765 -213.77757) (xy 225.985361 -213.73126)
			(xy 226.015911 -213.689212) (xy 226.052662 -213.652461) (xy 226.09471 -213.621911) (xy 226.14102 -213.598315)
			(xy 226.19045 -213.582254) (xy 226.241785 -213.574124) (xy 226.293759 -213.574124) (xy 226.345094 -213.582254)
			(xy 226.394524 -213.598315) (xy 226.440834 -213.621911) (xy 226.482882 -213.652461) (xy 226.519633 -213.689212)
			(xy 226.550183 -213.73126) (xy 226.573779 -213.77757) (xy 226.58984 -213.827) (xy 226.59797 -213.878335)
			(xy 226.59848 -213.904322) (xy 226.59797 -213.930309) (xy 226.737674 -213.930309) (xy 226.737674 -213.878335)
			(xy 226.745804 -213.827) (xy 226.761865 -213.77757) (xy 226.785461 -213.73126) (xy 226.816011 -213.689212)
			(xy 226.852762 -213.652461) (xy 226.89481 -213.621911) (xy 226.94112 -213.598315) (xy 226.99055 -213.582254)
			(xy 227.041885 -213.574124) (xy 227.093859 -213.574124) (xy 227.145194 -213.582254) (xy 227.194624 -213.598315)
			(xy 227.240934 -213.621911) (xy 227.282982 -213.652461) (xy 227.319733 -213.689212) (xy 227.350283 -213.73126)
			(xy 227.373879 -213.77757) (xy 227.38994 -213.827) (xy 227.39807 -213.878335) (xy 227.39858 -213.904322)
			(xy 227.39807 -213.930309) (xy 227.537774 -213.930309) (xy 227.537774 -213.878335) (xy 227.545904 -213.827)
			(xy 227.561965 -213.77757) (xy 227.585561 -213.73126) (xy 227.616111 -213.689212) (xy 227.652862 -213.652461)
			(xy 227.69491 -213.621911) (xy 227.74122 -213.598315) (xy 227.79065 -213.582254) (xy 227.841985 -213.574124)
			(xy 227.893959 -213.574124) (xy 227.945294 -213.582254) (xy 227.994724 -213.598315) (xy 228.041034 -213.621911)
			(xy 228.083082 -213.652461) (xy 228.119833 -213.689212) (xy 228.150383 -213.73126) (xy 228.173979 -213.77757)
			(xy 228.19004 -213.827) (xy 228.19817 -213.878335) (xy 228.19868 -213.904322) (xy 228.19817 -213.930309)
			(xy 228.33762 -213.930309) (xy 228.33762 -213.878335) (xy 228.34575 -213.827) (xy 228.361811 -213.77757)
			(xy 228.385407 -213.73126) (xy 228.415957 -213.689212) (xy 228.452708 -213.652461) (xy 228.494756 -213.621911)
			(xy 228.541066 -213.598315) (xy 228.590496 -213.582254) (xy 228.641831 -213.574124) (xy 228.693805 -213.574124)
			(xy 228.74514 -213.582254) (xy 228.79457 -213.598315) (xy 228.84088 -213.621911) (xy 228.882928 -213.652461)
			(xy 228.919679 -213.689212) (xy 228.950229 -213.73126) (xy 228.973825 -213.77757) (xy 228.989886 -213.827)
			(xy 228.998016 -213.878335) (xy 228.998526 -213.904322) (xy 228.998016 -213.930309) (xy 229.937312 -213.930309)
			(xy 229.937312 -213.878335) (xy 229.945442 -213.827) (xy 229.961503 -213.77757) (xy 229.985099 -213.73126)
			(xy 230.015649 -213.689212) (xy 230.0524 -213.652461) (xy 230.094448 -213.621911) (xy 230.140758 -213.598315)
			(xy 230.190188 -213.582254) (xy 230.241523 -213.574124) (xy 230.293497 -213.574124) (xy 230.344832 -213.582254)
			(xy 230.394262 -213.598315) (xy 230.440572 -213.621911) (xy 230.48262 -213.652461) (xy 230.519371 -213.689212)
			(xy 230.549921 -213.73126) (xy 230.573517 -213.77757) (xy 230.589578 -213.827) (xy 230.597708 -213.878335)
			(xy 230.598218 -213.904322) (xy 230.597708 -213.930309) (xy 230.737158 -213.930309) (xy 230.737158 -213.878335)
			(xy 230.745288 -213.827) (xy 230.761349 -213.77757) (xy 230.784945 -213.73126) (xy 230.815495 -213.689212)
			(xy 230.852246 -213.652461) (xy 230.894294 -213.621911) (xy 230.940604 -213.598315) (xy 230.990034 -213.582254)
			(xy 231.041369 -213.574124) (xy 231.093343 -213.574124) (xy 231.144678 -213.582254) (xy 231.194108 -213.598315)
			(xy 231.240418 -213.621911) (xy 231.282466 -213.652461) (xy 231.319217 -213.689212) (xy 231.349767 -213.73126)
			(xy 231.373363 -213.77757) (xy 231.389424 -213.827) (xy 231.397554 -213.878335) (xy 231.398064 -213.904322)
			(xy 231.397554 -213.930309) (xy 231.537258 -213.930309) (xy 231.537258 -213.878335) (xy 231.545388 -213.827)
			(xy 231.561449 -213.77757) (xy 231.585045 -213.73126) (xy 231.615595 -213.689212) (xy 231.652346 -213.652461)
			(xy 231.694394 -213.621911) (xy 231.740704 -213.598315) (xy 231.790134 -213.582254) (xy 231.841469 -213.574124)
			(xy 231.893443 -213.574124) (xy 231.944778 -213.582254) (xy 231.994208 -213.598315) (xy 232.040518 -213.621911)
			(xy 232.082566 -213.652461) (xy 232.119317 -213.689212) (xy 232.149867 -213.73126) (xy 232.173463 -213.77757)
			(xy 232.189524 -213.827) (xy 232.197654 -213.878335) (xy 232.198164 -213.904322) (xy 232.197654 -213.930309)
			(xy 232.337358 -213.930309) (xy 232.337358 -213.878335) (xy 232.345488 -213.827) (xy 232.361549 -213.77757)
			(xy 232.385145 -213.73126) (xy 232.415695 -213.689212) (xy 232.452446 -213.652461) (xy 232.494494 -213.621911)
			(xy 232.540804 -213.598315) (xy 232.590234 -213.582254) (xy 232.641569 -213.574124) (xy 232.693543 -213.574124)
			(xy 232.744878 -213.582254) (xy 232.794308 -213.598315) (xy 232.840618 -213.621911) (xy 232.882666 -213.652461)
			(xy 232.919417 -213.689212) (xy 232.949967 -213.73126) (xy 232.973563 -213.77757) (xy 232.989624 -213.827)
			(xy 232.997754 -213.878335) (xy 232.998264 -213.904322) (xy 232.997754 -213.930309) (xy 233.137204 -213.930309)
			(xy 233.137204 -213.878335) (xy 233.145334 -213.827) (xy 233.161395 -213.77757) (xy 233.184991 -213.73126)
			(xy 233.215541 -213.689212) (xy 233.252292 -213.652461) (xy 233.29434 -213.621911) (xy 233.34065 -213.598315)
			(xy 233.39008 -213.582254) (xy 233.441415 -213.574124) (xy 233.493389 -213.574124) (xy 233.544724 -213.582254)
			(xy 233.594154 -213.598315) (xy 233.640464 -213.621911) (xy 233.682512 -213.652461) (xy 233.719263 -213.689212)
			(xy 233.749813 -213.73126) (xy 233.773409 -213.77757) (xy 233.78947 -213.827) (xy 233.7976 -213.878335)
			(xy 233.79811 -213.904322) (xy 233.7976 -213.930309) (xy 233.937304 -213.930309) (xy 233.937304 -213.878335)
			(xy 233.945434 -213.827) (xy 233.961495 -213.77757) (xy 233.985091 -213.73126) (xy 234.015641 -213.689212)
			(xy 234.052392 -213.652461) (xy 234.09444 -213.621911) (xy 234.14075 -213.598315) (xy 234.19018 -213.582254)
			(xy 234.241515 -213.574124) (xy 234.293489 -213.574124) (xy 234.344824 -213.582254) (xy 234.358883 -213.586822)
			(xy 236.605826 -213.586822) (xy 236.606312 -213.559571) (xy 236.614068 -213.505623) (xy 236.629423 -213.453328)
			(xy 236.652065 -213.403751) (xy 236.681531 -213.357901) (xy 236.717222 -213.31671) (xy 236.758413 -213.281019)
			(xy 236.804263 -213.251553) (xy 236.85384 -213.228911) (xy 236.906135 -213.213556) (xy 236.960083 -213.2058)
			(xy 237.014585 -213.2058) (xy 237.068533 -213.213556) (xy 237.120828 -213.228911) (xy 237.170405 -213.251553)
			(xy 237.216255 -213.281019) (xy 237.257446 -213.31671) (xy 237.293137 -213.357901) (xy 237.322603 -213.403751)
			(xy 237.345245 -213.453328) (xy 237.3606 -213.505623) (xy 237.368356 -213.559571) (xy 237.368842 -213.586822)
			(xy 237.368341 -213.614) (xy 237.666782 -213.614) (xy 237.670853 -213.558378) (xy 237.682979 -213.503941)
			(xy 237.702902 -213.45185) (xy 237.730198 -213.403215) (xy 237.764284 -213.359072) (xy 237.804433 -213.320363)
			(xy 237.849791 -213.287912) (xy 237.899391 -213.262411) (xy 237.952175 -213.244404) (xy 238.007018 -213.234274)
			(xy 238.062752 -213.232237) (xy 238.118189 -213.238337) (xy 238.172146 -213.252443) (xy 238.223475 -213.274255)
			(xy 238.271081 -213.303309) (xy 238.313949 -213.338984) (xy 238.34962 -213.378796) (xy 238.559846 -213.378796)
			(xy 238.563917 -213.323174) (xy 238.576043 -213.268737) (xy 238.595966 -213.216646) (xy 238.623262 -213.168011)
			(xy 238.657348 -213.123868) (xy 238.697497 -213.085159) (xy 238.742855 -213.052708) (xy 238.792455 -213.027207)
			(xy 238.845239 -213.0092) (xy 238.900082 -212.99907) (xy 238.955816 -212.997033) (xy 239.011253 -213.003133)
			(xy 239.06521 -213.017239) (xy 239.116539 -213.039051) (xy 239.164145 -213.068105) (xy 239.207013 -213.10378)
			(xy 239.24423 -213.145317) (xy 239.275003 -213.19183) (xy 239.298675 -213.242327) (xy 239.314743 -213.295734)
			(xy 239.322863 -213.35091) (xy 239.322913 -213.35365) (xy 239.46942 -213.35365) (xy 239.473491 -213.298028)
			(xy 239.485617 -213.243591) (xy 239.50554 -213.1915) (xy 239.532836 -213.142865) (xy 239.566922 -213.098722)
			(xy 239.607071 -213.060013) (xy 239.652429 -213.027562) (xy 239.702029 -213.002061) (xy 239.754813 -212.984054)
			(xy 239.809656 -212.973924) (xy 239.86539 -212.971887) (xy 239.920827 -212.977987) (xy 239.974784 -212.992093)
			(xy 240.026113 -213.013905) (xy 240.073719 -213.042959) (xy 240.116587 -213.078634) (xy 240.153804 -213.120171)
			(xy 240.184577 -213.166684) (xy 240.208249 -213.217181) (xy 240.224317 -213.270588) (xy 240.232437 -213.325764)
			(xy 240.232946 -213.35365) (xy 240.232437 -213.381536) (xy 240.224317 -213.436712) (xy 240.208249 -213.490119)
			(xy 240.184577 -213.540616) (xy 240.153804 -213.587129) (xy 240.116587 -213.628666) (xy 240.073719 -213.664341)
			(xy 240.026113 -213.693395) (xy 239.974784 -213.715207) (xy 239.920827 -213.729313) (xy 239.86539 -213.735413)
			(xy 239.809656 -213.733376) (xy 239.754813 -213.723246) (xy 239.702029 -213.705239) (xy 239.652429 -213.679738)
			(xy 239.607071 -213.647287) (xy 239.566922 -213.608578) (xy 239.532836 -213.564435) (xy 239.50554 -213.5158)
			(xy 239.485617 -213.463709) (xy 239.473491 -213.409272) (xy 239.46942 -213.35365) (xy 239.322913 -213.35365)
			(xy 239.323372 -213.378796) (xy 239.322863 -213.406682) (xy 239.314743 -213.461858) (xy 239.298675 -213.515265)
			(xy 239.275003 -213.565762) (xy 239.24423 -213.612275) (xy 239.207013 -213.653812) (xy 239.164145 -213.689487)
			(xy 239.116539 -213.718541) (xy 239.06521 -213.740353) (xy 239.011253 -213.754459) (xy 238.955816 -213.760559)
			(xy 238.900082 -213.758522) (xy 238.845239 -213.748392) (xy 238.792455 -213.730385) (xy 238.742855 -213.704884)
			(xy 238.697497 -213.672433) (xy 238.657348 -213.633724) (xy 238.623262 -213.589581) (xy 238.595966 -213.540946)
			(xy 238.576043 -213.488855) (xy 238.563917 -213.434418) (xy 238.559846 -213.378796) (xy 238.34962 -213.378796)
			(xy 238.351166 -213.380521) (xy 238.381939 -213.427034) (xy 238.405611 -213.477531) (xy 238.421679 -213.530938)
			(xy 238.429799 -213.586114) (xy 238.430308 -213.614) (xy 238.429799 -213.641886) (xy 238.421679 -213.697062)
			(xy 238.405611 -213.750469) (xy 238.381939 -213.800966) (xy 238.351166 -213.847479) (xy 238.313949 -213.889016)
			(xy 238.271081 -213.924691) (xy 238.223475 -213.953745) (xy 238.172146 -213.975557) (xy 238.118189 -213.989663)
			(xy 238.062752 -213.995763) (xy 238.007018 -213.993726) (xy 237.952175 -213.983596) (xy 237.899391 -213.965589)
			(xy 237.849791 -213.940088) (xy 237.804433 -213.907637) (xy 237.764284 -213.868928) (xy 237.730198 -213.824785)
			(xy 237.702902 -213.77615) (xy 237.682979 -213.724059) (xy 237.670853 -213.669622) (xy 237.666782 -213.614)
			(xy 237.368341 -213.614) (xy 237.368338 -213.614139) (xy 237.360549 -213.668216) (xy 237.34512 -213.720627)
			(xy 237.322367 -213.770298) (xy 237.292755 -213.816212) (xy 237.256892 -213.857428) (xy 237.236508 -213.87562)
			(xy 237.236 -213.876128) (xy 237.227618 -213.883494) (xy 237.223046 -213.8934) (xy 237.219236 -213.905592)
			(xy 237.218474 -213.91499) (xy 237.21949 -214.004398) (xy 237.224316 -214.014304) (xy 237.226816 -214.019126)
			(xy 237.233473 -214.027704) (xy 237.237524 -214.031322) (xy 237.238032 -214.031576) (xy 237.254727 -214.0458)
			(xy 242.111782 -214.0458) (xy 242.115853 -213.990178) (xy 242.127979 -213.935741) (xy 242.147902 -213.88365)
			(xy 242.175198 -213.835015) (xy 242.209284 -213.790872) (xy 242.249433 -213.752163) (xy 242.294791 -213.719712)
			(xy 242.344391 -213.694211) (xy 242.397175 -213.676204) (xy 242.452018 -213.666074) (xy 242.507752 -213.664037)
			(xy 242.563189 -213.670137) (xy 242.617146 -213.684243) (xy 242.668475 -213.706055) (xy 242.716081 -213.735109)
			(xy 242.758949 -213.770784) (xy 242.796166 -213.812321) (xy 242.826939 -213.858834) (xy 242.850611 -213.909331)
			(xy 242.866679 -213.962738) (xy 242.874799 -214.017914) (xy 242.875308 -214.0458) (xy 242.874799 -214.073686)
			(xy 242.871315 -214.097362) (xy 246.008142 -214.097362) (xy 246.012213 -214.04174) (xy 246.024339 -213.987303)
			(xy 246.044262 -213.935212) (xy 246.071558 -213.886577) (xy 246.105644 -213.842434) (xy 246.145793 -213.803725)
			(xy 246.191151 -213.771274) (xy 246.240751 -213.745773) (xy 246.293535 -213.727766) (xy 246.348378 -213.717636)
			(xy 246.404112 -213.715599) (xy 246.459549 -213.721699) (xy 246.513506 -213.735805) (xy 246.564835 -213.757617)
			(xy 246.612441 -213.786671) (xy 246.655309 -213.822346) (xy 246.692526 -213.863883) (xy 246.723299 -213.910396)
			(xy 246.746971 -213.960893) (xy 246.763039 -214.0143) (xy 246.771159 -214.069476) (xy 246.771668 -214.097362)
			(xy 246.771159 -214.125248) (xy 246.763039 -214.180424) (xy 246.746971 -214.233831) (xy 246.723299 -214.284328)
			(xy 246.692526 -214.330841) (xy 246.655309 -214.372378) (xy 246.612441 -214.408053) (xy 246.564835 -214.437107)
			(xy 246.513506 -214.458919) (xy 246.459549 -214.473025) (xy 246.404112 -214.479125) (xy 246.348378 -214.477088)
			(xy 246.293535 -214.466958) (xy 246.240751 -214.448951) (xy 246.191151 -214.42345) (xy 246.145793 -214.390999)
			(xy 246.105644 -214.35229) (xy 246.071558 -214.308147) (xy 246.044262 -214.259512) (xy 246.024339 -214.207421)
			(xy 246.012213 -214.152984) (xy 246.008142 -214.097362) (xy 242.871315 -214.097362) (xy 242.866679 -214.128862)
			(xy 242.850611 -214.182269) (xy 242.826939 -214.232766) (xy 242.796166 -214.279279) (xy 242.758949 -214.320816)
			(xy 242.716081 -214.356491) (xy 242.668475 -214.385545) (xy 242.617146 -214.407357) (xy 242.563189 -214.421463)
			(xy 242.507752 -214.427563) (xy 242.452018 -214.425526) (xy 242.397175 -214.415396) (xy 242.344391 -214.397389)
			(xy 242.294791 -214.371888) (xy 242.249433 -214.339437) (xy 242.209284 -214.300728) (xy 242.175198 -214.256585)
			(xy 242.147902 -214.20795) (xy 242.127979 -214.155859) (xy 242.115853 -214.101422) (xy 242.111782 -214.0458)
			(xy 237.254727 -214.0458) (xy 237.259403 -214.049784) (xy 237.297076 -214.091412) (xy 237.328239 -214.138112)
			(xy 237.352219 -214.188876) (xy 237.3685 -214.242607) (xy 237.376727 -214.298144) (xy 237.377224 -214.326216)
			(xy 237.376738 -214.353467) (xy 237.368982 -214.407415) (xy 237.353627 -214.45971) (xy 237.330985 -214.509287)
			(xy 237.301519 -214.555137) (xy 237.265828 -214.596328) (xy 237.224637 -214.632019) (xy 237.178787 -214.661485)
			(xy 237.12921 -214.684127) (xy 237.076915 -214.699482) (xy 237.022967 -214.707238) (xy 236.968465 -214.707238)
			(xy 236.914517 -214.699482) (xy 236.862222 -214.684127) (xy 236.812645 -214.661485) (xy 236.766795 -214.632019)
			(xy 236.725604 -214.596328) (xy 236.689913 -214.555137) (xy 236.660447 -214.509287) (xy 236.637805 -214.45971)
			(xy 236.62245 -214.407415) (xy 236.614694 -214.353467) (xy 236.614208 -214.326216) (xy 236.614652 -214.298896)
			(xy 236.622451 -214.244816) (xy 236.637891 -214.192404) (xy 236.660655 -214.142732) (xy 236.690278 -214.09682)
			(xy 236.726153 -214.055608) (xy 236.746542 -214.037418) (xy 236.74705 -214.03691) (xy 236.755432 -214.029544)
			(xy 236.760004 -214.019638) (xy 236.763814 -214.007446) (xy 236.764576 -213.998048) (xy 236.76356 -213.90864)
			(xy 236.758734 -213.898734) (xy 236.756238 -213.89391) (xy 236.749578 -213.885333) (xy 236.745526 -213.881716)
			(xy 236.745018 -213.881462) (xy 236.723627 -213.863276) (xy 236.685954 -213.821645) (xy 236.654792 -213.77494)
			(xy 236.630815 -213.724172) (xy 236.61454 -213.670436) (xy 236.606319 -213.614895) (xy 236.605826 -213.586822)
			(xy 234.358883 -213.586822) (xy 234.394254 -213.598315) (xy 234.440564 -213.621911) (xy 234.482612 -213.652461)
			(xy 234.519363 -213.689212) (xy 234.549913 -213.73126) (xy 234.573509 -213.77757) (xy 234.58957 -213.827)
			(xy 234.5977 -213.878335) (xy 234.59821 -213.904322) (xy 234.5977 -213.930309) (xy 234.58957 -213.981644)
			(xy 234.573509 -214.031074) (xy 234.549913 -214.077384) (xy 234.519363 -214.119432) (xy 234.482612 -214.156183)
			(xy 234.440564 -214.186733) (xy 234.394254 -214.210329) (xy 234.344824 -214.22639) (xy 234.293489 -214.23452)
			(xy 234.241515 -214.23452) (xy 234.19018 -214.22639) (xy 234.14075 -214.210329) (xy 234.09444 -214.186733)
			(xy 234.052392 -214.156183) (xy 234.015641 -214.119432) (xy 233.985091 -214.077384) (xy 233.961495 -214.031074)
			(xy 233.945434 -213.981644) (xy 233.937304 -213.930309) (xy 233.7976 -213.930309) (xy 233.78947 -213.981644)
			(xy 233.773409 -214.031074) (xy 233.749813 -214.077384) (xy 233.719263 -214.119432) (xy 233.682512 -214.156183)
			(xy 233.640464 -214.186733) (xy 233.594154 -214.210329) (xy 233.544724 -214.22639) (xy 233.493389 -214.23452)
			(xy 233.441415 -214.23452) (xy 233.39008 -214.22639) (xy 233.34065 -214.210329) (xy 233.29434 -214.186733)
			(xy 233.252292 -214.156183) (xy 233.215541 -214.119432) (xy 233.184991 -214.077384) (xy 233.161395 -214.031074)
			(xy 233.145334 -213.981644) (xy 233.137204 -213.930309) (xy 232.997754 -213.930309) (xy 232.989624 -213.981644)
			(xy 232.973563 -214.031074) (xy 232.949967 -214.077384) (xy 232.919417 -214.119432) (xy 232.882666 -214.156183)
			(xy 232.840618 -214.186733) (xy 232.794308 -214.210329) (xy 232.744878 -214.22639) (xy 232.693543 -214.23452)
			(xy 232.641569 -214.23452) (xy 232.590234 -214.22639) (xy 232.540804 -214.210329) (xy 232.494494 -214.186733)
			(xy 232.452446 -214.156183) (xy 232.415695 -214.119432) (xy 232.385145 -214.077384) (xy 232.361549 -214.031074)
			(xy 232.345488 -213.981644) (xy 232.337358 -213.930309) (xy 232.197654 -213.930309) (xy 232.189524 -213.981644)
			(xy 232.173463 -214.031074) (xy 232.149867 -214.077384) (xy 232.119317 -214.119432) (xy 232.082566 -214.156183)
			(xy 232.040518 -214.186733) (xy 231.994208 -214.210329) (xy 231.944778 -214.22639) (xy 231.893443 -214.23452)
			(xy 231.841469 -214.23452) (xy 231.790134 -214.22639) (xy 231.740704 -214.210329) (xy 231.694394 -214.186733)
			(xy 231.652346 -214.156183) (xy 231.615595 -214.119432) (xy 231.585045 -214.077384) (xy 231.561449 -214.031074)
			(xy 231.545388 -213.981644) (xy 231.537258 -213.930309) (xy 231.397554 -213.930309) (xy 231.389424 -213.981644)
			(xy 231.373363 -214.031074) (xy 231.349767 -214.077384) (xy 231.319217 -214.119432) (xy 231.282466 -214.156183)
			(xy 231.240418 -214.186733) (xy 231.194108 -214.210329) (xy 231.144678 -214.22639) (xy 231.093343 -214.23452)
			(xy 231.041369 -214.23452) (xy 230.990034 -214.22639) (xy 230.940604 -214.210329) (xy 230.894294 -214.186733)
			(xy 230.852246 -214.156183) (xy 230.815495 -214.119432) (xy 230.784945 -214.077384) (xy 230.761349 -214.031074)
			(xy 230.745288 -213.981644) (xy 230.737158 -213.930309) (xy 230.597708 -213.930309) (xy 230.589578 -213.981644)
			(xy 230.573517 -214.031074) (xy 230.549921 -214.077384) (xy 230.519371 -214.119432) (xy 230.48262 -214.156183)
			(xy 230.440572 -214.186733) (xy 230.394262 -214.210329) (xy 230.344832 -214.22639) (xy 230.293497 -214.23452)
			(xy 230.241523 -214.23452) (xy 230.190188 -214.22639) (xy 230.140758 -214.210329) (xy 230.094448 -214.186733)
			(xy 230.0524 -214.156183) (xy 230.015649 -214.119432) (xy 229.985099 -214.077384) (xy 229.961503 -214.031074)
			(xy 229.945442 -213.981644) (xy 229.937312 -213.930309) (xy 228.998016 -213.930309) (xy 228.989886 -213.981644)
			(xy 228.973825 -214.031074) (xy 228.950229 -214.077384) (xy 228.919679 -214.119432) (xy 228.882928 -214.156183)
			(xy 228.84088 -214.186733) (xy 228.79457 -214.210329) (xy 228.74514 -214.22639) (xy 228.693805 -214.23452)
			(xy 228.641831 -214.23452) (xy 228.590496 -214.22639) (xy 228.541066 -214.210329) (xy 228.494756 -214.186733)
			(xy 228.452708 -214.156183) (xy 228.415957 -214.119432) (xy 228.385407 -214.077384) (xy 228.361811 -214.031074)
			(xy 228.34575 -213.981644) (xy 228.33762 -213.930309) (xy 228.19817 -213.930309) (xy 228.19004 -213.981644)
			(xy 228.173979 -214.031074) (xy 228.150383 -214.077384) (xy 228.119833 -214.119432) (xy 228.083082 -214.156183)
			(xy 228.041034 -214.186733) (xy 227.994724 -214.210329) (xy 227.945294 -214.22639) (xy 227.893959 -214.23452)
			(xy 227.841985 -214.23452) (xy 227.79065 -214.22639) (xy 227.74122 -214.210329) (xy 227.69491 -214.186733)
			(xy 227.652862 -214.156183) (xy 227.616111 -214.119432) (xy 227.585561 -214.077384) (xy 227.561965 -214.031074)
			(xy 227.545904 -213.981644) (xy 227.537774 -213.930309) (xy 227.39807 -213.930309) (xy 227.38994 -213.981644)
			(xy 227.373879 -214.031074) (xy 227.350283 -214.077384) (xy 227.319733 -214.119432) (xy 227.282982 -214.156183)
			(xy 227.240934 -214.186733) (xy 227.194624 -214.210329) (xy 227.145194 -214.22639) (xy 227.093859 -214.23452)
			(xy 227.041885 -214.23452) (xy 226.99055 -214.22639) (xy 226.94112 -214.210329) (xy 226.89481 -214.186733)
			(xy 226.852762 -214.156183) (xy 226.816011 -214.119432) (xy 226.785461 -214.077384) (xy 226.761865 -214.031074)
			(xy 226.745804 -213.981644) (xy 226.737674 -213.930309) (xy 226.59797 -213.930309) (xy 226.58984 -213.981644)
			(xy 226.573779 -214.031074) (xy 226.550183 -214.077384) (xy 226.519633 -214.119432) (xy 226.482882 -214.156183)
			(xy 226.440834 -214.186733) (xy 226.394524 -214.210329) (xy 226.345094 -214.22639) (xy 226.293759 -214.23452)
			(xy 226.241785 -214.23452) (xy 226.19045 -214.22639) (xy 226.14102 -214.210329) (xy 226.09471 -214.186733)
			(xy 226.052662 -214.156183) (xy 226.015911 -214.119432) (xy 225.985361 -214.077384) (xy 225.961765 -214.031074)
			(xy 225.945704 -213.981644) (xy 225.937574 -213.930309) (xy 225.798124 -213.930309) (xy 225.789994 -213.981644)
			(xy 225.773933 -214.031074) (xy 225.750337 -214.077384) (xy 225.719787 -214.119432) (xy 225.683036 -214.156183)
			(xy 225.640988 -214.186733) (xy 225.594678 -214.210329) (xy 225.545248 -214.22639) (xy 225.493913 -214.23452)
			(xy 225.441939 -214.23452) (xy 225.390604 -214.22639) (xy 225.341174 -214.210329) (xy 225.294864 -214.186733)
			(xy 225.252816 -214.156183) (xy 225.216065 -214.119432) (xy 225.185515 -214.077384) (xy 225.161919 -214.031074)
			(xy 225.145858 -213.981644) (xy 225.137728 -213.930309) (xy 224.998024 -213.930309) (xy 224.989894 -213.981644)
			(xy 224.973833 -214.031074) (xy 224.950237 -214.077384) (xy 224.919687 -214.119432) (xy 224.882936 -214.156183)
			(xy 224.840888 -214.186733) (xy 224.794578 -214.210329) (xy 224.745148 -214.22639) (xy 224.693813 -214.23452)
			(xy 224.641839 -214.23452) (xy 224.590504 -214.22639) (xy 224.541074 -214.210329) (xy 224.494764 -214.186733)
			(xy 224.452716 -214.156183) (xy 224.415965 -214.119432) (xy 224.385415 -214.077384) (xy 224.361819 -214.031074)
			(xy 224.345758 -213.981644) (xy 224.337628 -213.930309) (xy 216.425722 -213.930309) (xy 216.42963 -213.932821)
			(xy 216.470814 -213.968511) (xy 216.5065 -214.009699) (xy 216.535962 -214.055546) (xy 216.5586 -214.105119)
			(xy 216.573953 -214.157409) (xy 216.581708 -214.211351) (xy 216.581708 -214.265849) (xy 216.573953 -214.319791)
			(xy 216.5586 -214.372081) (xy 216.535962 -214.421654) (xy 216.5065 -214.467501) (xy 216.470814 -214.508689)
			(xy 216.42963 -214.544379) (xy 216.383786 -214.573845) (xy 216.334215 -214.596487) (xy 216.281926 -214.611845)
			(xy 216.227985 -214.619605) (xy 216.200736 -214.620094) (xy 216.200482 -214.620094) (xy 216.174187 -214.619649)
			(xy 216.122097 -214.612401) (xy 216.071496 -214.598073) (xy 216.023339 -214.576935) (xy 215.97854 -214.549387)
			(xy 215.937946 -214.515952) (xy 215.919812 -214.496904) (xy 215.912287 -214.489506) (xy 215.89301 -214.48098)
			(xy 215.882474 -214.480394) (xy 215.807798 -214.480394) (xy 215.797247 -214.48091) (xy 215.777952 -214.489455)
			(xy 215.77046 -214.496904) (xy 215.752361 -214.515989) (xy 215.711772 -214.549443) (xy 215.66697 -214.576998)
			(xy 215.618804 -214.598132) (xy 215.56819 -214.612443) (xy 215.516089 -214.61966) (xy 215.48979 -214.620094)
			(xy 215.489536 -214.620094) (xy 215.46228 -214.619662) (xy 215.408324 -214.611908) (xy 215.356019 -214.596555)
			(xy 215.306433 -214.573914) (xy 215.260574 -214.544446) (xy 215.219375 -214.508751) (xy 215.183676 -214.467555)
			(xy 215.154204 -214.421699) (xy 215.131558 -214.372114) (xy 215.116199 -214.319812) (xy 215.108441 -214.265856)
			(xy 211.064819 -214.265856) (xy 211.060644 -214.272167) (xy 211.023427 -214.313704) (xy 210.980559 -214.349379)
			(xy 210.932953 -214.378433) (xy 210.881624 -214.400245) (xy 210.827667 -214.414351) (xy 210.77223 -214.420451)
			(xy 210.716496 -214.418414) (xy 210.661653 -214.408284) (xy 210.608869 -214.390277) (xy 210.559269 -214.364776)
			(xy 210.513911 -214.332325) (xy 210.473762 -214.293616) (xy 210.439676 -214.249473) (xy 210.41238 -214.200838)
			(xy 210.392457 -214.148747) (xy 210.380331 -214.09431) (xy 210.37626 -214.038688) (xy 196.968618 -214.038688)
			(xy 196.968618 -214.776812) (xy 206.89138 -214.776812) (xy 206.895451 -214.72119) (xy 206.907577 -214.666753)
			(xy 206.9275 -214.614662) (xy 206.954796 -214.566027) (xy 206.988882 -214.521884) (xy 207.029031 -214.483175)
			(xy 207.074389 -214.450724) (xy 207.123989 -214.425223) (xy 207.176773 -214.407216) (xy 207.231616 -214.397086)
			(xy 207.28735 -214.395049) (xy 207.342787 -214.401149) (xy 207.396744 -214.415255) (xy 207.448073 -214.437067)
			(xy 207.495679 -214.466121) (xy 207.538547 -214.501796) (xy 207.575764 -214.543333) (xy 207.606537 -214.589846)
			(xy 207.630209 -214.640343) (xy 207.646277 -214.69375) (xy 207.651672 -214.730409) (xy 222.737682 -214.730409)
			(xy 222.737682 -214.678435) (xy 222.745812 -214.6271) (xy 222.761873 -214.57767) (xy 222.785469 -214.53136)
			(xy 222.816019 -214.489312) (xy 222.85277 -214.452561) (xy 222.894818 -214.422011) (xy 222.941128 -214.398415)
			(xy 222.990558 -214.382354) (xy 223.041893 -214.374224) (xy 223.093867 -214.374224) (xy 223.145202 -214.382354)
			(xy 223.194632 -214.398415) (xy 223.240942 -214.422011) (xy 223.28299 -214.452561) (xy 223.319741 -214.489312)
			(xy 223.350291 -214.53136) (xy 223.373887 -214.57767) (xy 223.389948 -214.6271) (xy 223.398078 -214.678435)
			(xy 223.398588 -214.704422) (xy 223.398078 -214.730409) (xy 223.537782 -214.730409) (xy 223.537782 -214.678435)
			(xy 223.545912 -214.6271) (xy 223.561973 -214.57767) (xy 223.585569 -214.53136) (xy 223.616119 -214.489312)
			(xy 223.65287 -214.452561) (xy 223.694918 -214.422011) (xy 223.741228 -214.398415) (xy 223.790658 -214.382354)
			(xy 223.841993 -214.374224) (xy 223.893967 -214.374224) (xy 223.945302 -214.382354) (xy 223.994732 -214.398415)
			(xy 224.041042 -214.422011) (xy 224.08309 -214.452561) (xy 224.119841 -214.489312) (xy 224.150391 -214.53136)
			(xy 224.173987 -214.57767) (xy 224.190048 -214.6271) (xy 224.198178 -214.678435) (xy 224.198688 -214.704422)
			(xy 224.198178 -214.730409) (xy 224.337628 -214.730409) (xy 224.337628 -214.678435) (xy 224.345758 -214.6271)
			(xy 224.361819 -214.57767) (xy 224.385415 -214.53136) (xy 224.415965 -214.489312) (xy 224.452716 -214.452561)
			(xy 224.494764 -214.422011) (xy 224.541074 -214.398415) (xy 224.590504 -214.382354) (xy 224.641839 -214.374224)
			(xy 224.693813 -214.374224) (xy 224.745148 -214.382354) (xy 224.794578 -214.398415) (xy 224.840888 -214.422011)
			(xy 224.882936 -214.452561) (xy 224.919687 -214.489312) (xy 224.950237 -214.53136) (xy 224.973833 -214.57767)
			(xy 224.989894 -214.6271) (xy 224.998024 -214.678435) (xy 224.998534 -214.704422) (xy 224.998024 -214.730409)
			(xy 225.137728 -214.730409) (xy 225.137728 -214.678435) (xy 225.145858 -214.6271) (xy 225.161919 -214.57767)
			(xy 225.185515 -214.53136) (xy 225.216065 -214.489312) (xy 225.252816 -214.452561) (xy 225.294864 -214.422011)
			(xy 225.341174 -214.398415) (xy 225.390604 -214.382354) (xy 225.441939 -214.374224) (xy 225.493913 -214.374224)
			(xy 225.545248 -214.382354) (xy 225.594678 -214.398415) (xy 225.640988 -214.422011) (xy 225.683036 -214.452561)
			(xy 225.719787 -214.489312) (xy 225.750337 -214.53136) (xy 225.773933 -214.57767) (xy 225.789994 -214.6271)
			(xy 225.798124 -214.678435) (xy 225.798634 -214.704422) (xy 225.798124 -214.730409) (xy 225.937574 -214.730409)
			(xy 225.937574 -214.678435) (xy 225.945704 -214.6271) (xy 225.961765 -214.57767) (xy 225.985361 -214.53136)
			(xy 226.015911 -214.489312) (xy 226.052662 -214.452561) (xy 226.09471 -214.422011) (xy 226.14102 -214.398415)
			(xy 226.19045 -214.382354) (xy 226.241785 -214.374224) (xy 226.293759 -214.374224) (xy 226.345094 -214.382354)
			(xy 226.394524 -214.398415) (xy 226.440834 -214.422011) (xy 226.482882 -214.452561) (xy 226.519633 -214.489312)
			(xy 226.550183 -214.53136) (xy 226.573779 -214.57767) (xy 226.58984 -214.6271) (xy 226.59797 -214.678435)
			(xy 226.59848 -214.704422) (xy 226.59797 -214.730409) (xy 226.737674 -214.730409) (xy 226.737674 -214.678435)
			(xy 226.745804 -214.6271) (xy 226.761865 -214.57767) (xy 226.785461 -214.53136) (xy 226.816011 -214.489312)
			(xy 226.852762 -214.452561) (xy 226.89481 -214.422011) (xy 226.94112 -214.398415) (xy 226.99055 -214.382354)
			(xy 227.041885 -214.374224) (xy 227.093859 -214.374224) (xy 227.145194 -214.382354) (xy 227.194624 -214.398415)
			(xy 227.240934 -214.422011) (xy 227.282982 -214.452561) (xy 227.319733 -214.489312) (xy 227.350283 -214.53136)
			(xy 227.373879 -214.57767) (xy 227.38994 -214.6271) (xy 227.39807 -214.678435) (xy 227.39858 -214.704422)
			(xy 227.39807 -214.730409) (xy 227.537774 -214.730409) (xy 227.537774 -214.678435) (xy 227.545904 -214.6271)
			(xy 227.561965 -214.57767) (xy 227.585561 -214.53136) (xy 227.616111 -214.489312) (xy 227.652862 -214.452561)
			(xy 227.69491 -214.422011) (xy 227.74122 -214.398415) (xy 227.79065 -214.382354) (xy 227.841985 -214.374224)
			(xy 227.893959 -214.374224) (xy 227.945294 -214.382354) (xy 227.994724 -214.398415) (xy 228.041034 -214.422011)
			(xy 228.083082 -214.452561) (xy 228.119833 -214.489312) (xy 228.150383 -214.53136) (xy 228.173979 -214.57767)
			(xy 228.19004 -214.6271) (xy 228.19817 -214.678435) (xy 228.19868 -214.704422) (xy 228.19817 -214.730409)
			(xy 228.33762 -214.730409) (xy 228.33762 -214.678435) (xy 228.34575 -214.6271) (xy 228.361811 -214.57767)
			(xy 228.385407 -214.53136) (xy 228.415957 -214.489312) (xy 228.452708 -214.452561) (xy 228.494756 -214.422011)
			(xy 228.541066 -214.398415) (xy 228.590496 -214.382354) (xy 228.641831 -214.374224) (xy 228.693805 -214.374224)
			(xy 228.74514 -214.382354) (xy 228.79457 -214.398415) (xy 228.84088 -214.422011) (xy 228.882928 -214.452561)
			(xy 228.919679 -214.489312) (xy 228.950229 -214.53136) (xy 228.973825 -214.57767) (xy 228.989886 -214.6271)
			(xy 228.998016 -214.678435) (xy 228.998526 -214.704422) (xy 228.998016 -214.730409) (xy 229.937312 -214.730409)
			(xy 229.937312 -214.678435) (xy 229.945442 -214.6271) (xy 229.961503 -214.57767) (xy 229.985099 -214.53136)
			(xy 230.015649 -214.489312) (xy 230.0524 -214.452561) (xy 230.094448 -214.422011) (xy 230.140758 -214.398415)
			(xy 230.190188 -214.382354) (xy 230.241523 -214.374224) (xy 230.293497 -214.374224) (xy 230.344832 -214.382354)
			(xy 230.394262 -214.398415) (xy 230.440572 -214.422011) (xy 230.48262 -214.452561) (xy 230.519371 -214.489312)
			(xy 230.549921 -214.53136) (xy 230.573517 -214.57767) (xy 230.589578 -214.6271) (xy 230.597708 -214.678435)
			(xy 230.598218 -214.704422) (xy 230.597708 -214.730409) (xy 230.737158 -214.730409) (xy 230.737158 -214.678435)
			(xy 230.745288 -214.6271) (xy 230.761349 -214.57767) (xy 230.784945 -214.53136) (xy 230.815495 -214.489312)
			(xy 230.852246 -214.452561) (xy 230.894294 -214.422011) (xy 230.940604 -214.398415) (xy 230.990034 -214.382354)
			(xy 231.041369 -214.374224) (xy 231.093343 -214.374224) (xy 231.144678 -214.382354) (xy 231.194108 -214.398415)
			(xy 231.240418 -214.422011) (xy 231.282466 -214.452561) (xy 231.319217 -214.489312) (xy 231.349767 -214.53136)
			(xy 231.373363 -214.57767) (xy 231.389424 -214.6271) (xy 231.397554 -214.678435) (xy 231.398064 -214.704422)
			(xy 231.397554 -214.730409) (xy 231.537258 -214.730409) (xy 231.537258 -214.678435) (xy 231.545388 -214.6271)
			(xy 231.561449 -214.57767) (xy 231.585045 -214.53136) (xy 231.615595 -214.489312) (xy 231.652346 -214.452561)
			(xy 231.694394 -214.422011) (xy 231.740704 -214.398415) (xy 231.790134 -214.382354) (xy 231.841469 -214.374224)
			(xy 231.893443 -214.374224) (xy 231.944778 -214.382354) (xy 231.994208 -214.398415) (xy 232.040518 -214.422011)
			(xy 232.082566 -214.452561) (xy 232.119317 -214.489312) (xy 232.149867 -214.53136) (xy 232.173463 -214.57767)
			(xy 232.189524 -214.6271) (xy 232.197654 -214.678435) (xy 232.198164 -214.704422) (xy 232.197654 -214.730409)
			(xy 232.337358 -214.730409) (xy 232.337358 -214.678435) (xy 232.345488 -214.6271) (xy 232.361549 -214.57767)
			(xy 232.385145 -214.53136) (xy 232.415695 -214.489312) (xy 232.452446 -214.452561) (xy 232.494494 -214.422011)
			(xy 232.540804 -214.398415) (xy 232.590234 -214.382354) (xy 232.641569 -214.374224) (xy 232.693543 -214.374224)
			(xy 232.744878 -214.382354) (xy 232.794308 -214.398415) (xy 232.840618 -214.422011) (xy 232.882666 -214.452561)
			(xy 232.919417 -214.489312) (xy 232.949967 -214.53136) (xy 232.973563 -214.57767) (xy 232.989624 -214.6271)
			(xy 232.997754 -214.678435) (xy 232.998264 -214.704422) (xy 232.997754 -214.730409) (xy 233.137204 -214.730409)
			(xy 233.137204 -214.678435) (xy 233.145334 -214.6271) (xy 233.161395 -214.57767) (xy 233.184991 -214.53136)
			(xy 233.215541 -214.489312) (xy 233.252292 -214.452561) (xy 233.29434 -214.422011) (xy 233.34065 -214.398415)
			(xy 233.39008 -214.382354) (xy 233.441415 -214.374224) (xy 233.493389 -214.374224) (xy 233.544724 -214.382354)
			(xy 233.594154 -214.398415) (xy 233.640464 -214.422011) (xy 233.682512 -214.452561) (xy 233.719263 -214.489312)
			(xy 233.749813 -214.53136) (xy 233.773409 -214.57767) (xy 233.78947 -214.6271) (xy 233.7976 -214.678435)
			(xy 233.79811 -214.704422) (xy 233.7976 -214.730409) (xy 233.937304 -214.730409) (xy 233.937304 -214.678435)
			(xy 233.945434 -214.6271) (xy 233.961495 -214.57767) (xy 233.985091 -214.53136) (xy 234.015641 -214.489312)
			(xy 234.052392 -214.452561) (xy 234.09444 -214.422011) (xy 234.14075 -214.398415) (xy 234.19018 -214.382354)
			(xy 234.241515 -214.374224) (xy 234.293489 -214.374224) (xy 234.344824 -214.382354) (xy 234.394254 -214.398415)
			(xy 234.440564 -214.422011) (xy 234.482612 -214.452561) (xy 234.519363 -214.489312) (xy 234.549913 -214.53136)
			(xy 234.573509 -214.57767) (xy 234.58957 -214.6271) (xy 234.5977 -214.678435) (xy 234.59821 -214.704422)
			(xy 234.5977 -214.730409) (xy 234.73715 -214.730409) (xy 234.73715 -214.678435) (xy 234.74528 -214.6271)
			(xy 234.761341 -214.57767) (xy 234.784937 -214.53136) (xy 234.815487 -214.489312) (xy 234.852238 -214.452561)
			(xy 234.894286 -214.422011) (xy 234.940596 -214.398415) (xy 234.990026 -214.382354) (xy 235.041361 -214.374224)
			(xy 235.093335 -214.374224) (xy 235.14467 -214.382354) (xy 235.1941 -214.398415) (xy 235.24041 -214.422011)
			(xy 235.282458 -214.452561) (xy 235.319209 -214.489312) (xy 235.349759 -214.53136) (xy 235.373355 -214.57767)
			(xy 235.389416 -214.6271) (xy 235.397546 -214.678435) (xy 235.398056 -214.704422) (xy 235.397546 -214.730409)
			(xy 235.389416 -214.781744) (xy 235.373355 -214.831174) (xy 235.349759 -214.877484) (xy 235.319209 -214.919532)
			(xy 235.282458 -214.956283) (xy 235.24041 -214.986833) (xy 235.1941 -215.010429) (xy 235.14467 -215.02649)
			(xy 235.093335 -215.03462) (xy 235.041361 -215.03462) (xy 234.990026 -215.02649) (xy 234.940596 -215.010429)
			(xy 234.894286 -214.986833) (xy 234.852238 -214.956283) (xy 234.815487 -214.919532) (xy 234.784937 -214.877484)
			(xy 234.761341 -214.831174) (xy 234.74528 -214.781744) (xy 234.73715 -214.730409) (xy 234.5977 -214.730409)
			(xy 234.58957 -214.781744) (xy 234.573509 -214.831174) (xy 234.549913 -214.877484) (xy 234.519363 -214.919532)
			(xy 234.482612 -214.956283) (xy 234.440564 -214.986833) (xy 234.394254 -215.010429) (xy 234.344824 -215.02649)
			(xy 234.293489 -215.03462) (xy 234.241515 -215.03462) (xy 234.19018 -215.02649) (xy 234.14075 -215.010429)
			(xy 234.09444 -214.986833) (xy 234.052392 -214.956283) (xy 234.015641 -214.919532) (xy 233.985091 -214.877484)
			(xy 233.961495 -214.831174) (xy 233.945434 -214.781744) (xy 233.937304 -214.730409) (xy 233.7976 -214.730409)
			(xy 233.78947 -214.781744) (xy 233.773409 -214.831174) (xy 233.749813 -214.877484) (xy 233.719263 -214.919532)
			(xy 233.682512 -214.956283) (xy 233.640464 -214.986833) (xy 233.594154 -215.010429) (xy 233.544724 -215.02649)
			(xy 233.493389 -215.03462) (xy 233.441415 -215.03462) (xy 233.39008 -215.02649) (xy 233.34065 -215.010429)
			(xy 233.29434 -214.986833) (xy 233.252292 -214.956283) (xy 233.215541 -214.919532) (xy 233.184991 -214.877484)
			(xy 233.161395 -214.831174) (xy 233.145334 -214.781744) (xy 233.137204 -214.730409) (xy 232.997754 -214.730409)
			(xy 232.989624 -214.781744) (xy 232.973563 -214.831174) (xy 232.949967 -214.877484) (xy 232.919417 -214.919532)
			(xy 232.882666 -214.956283) (xy 232.840618 -214.986833) (xy 232.794308 -215.010429) (xy 232.744878 -215.02649)
			(xy 232.693543 -215.03462) (xy 232.641569 -215.03462) (xy 232.590234 -215.02649) (xy 232.540804 -215.010429)
			(xy 232.494494 -214.986833) (xy 232.452446 -214.956283) (xy 232.415695 -214.919532) (xy 232.385145 -214.877484)
			(xy 232.361549 -214.831174) (xy 232.345488 -214.781744) (xy 232.337358 -214.730409) (xy 232.197654 -214.730409)
			(xy 232.189524 -214.781744) (xy 232.173463 -214.831174) (xy 232.149867 -214.877484) (xy 232.119317 -214.919532)
			(xy 232.082566 -214.956283) (xy 232.040518 -214.986833) (xy 231.994208 -215.010429) (xy 231.944778 -215.02649)
			(xy 231.893443 -215.03462) (xy 231.841469 -215.03462) (xy 231.790134 -215.02649) (xy 231.740704 -215.010429)
			(xy 231.694394 -214.986833) (xy 231.652346 -214.956283) (xy 231.615595 -214.919532) (xy 231.585045 -214.877484)
			(xy 231.561449 -214.831174) (xy 231.545388 -214.781744) (xy 231.537258 -214.730409) (xy 231.397554 -214.730409)
			(xy 231.389424 -214.781744) (xy 231.373363 -214.831174) (xy 231.349767 -214.877484) (xy 231.319217 -214.919532)
			(xy 231.282466 -214.956283) (xy 231.240418 -214.986833) (xy 231.194108 -215.010429) (xy 231.144678 -215.02649)
			(xy 231.093343 -215.03462) (xy 231.041369 -215.03462) (xy 230.990034 -215.02649) (xy 230.940604 -215.010429)
			(xy 230.894294 -214.986833) (xy 230.852246 -214.956283) (xy 230.815495 -214.919532) (xy 230.784945 -214.877484)
			(xy 230.761349 -214.831174) (xy 230.745288 -214.781744) (xy 230.737158 -214.730409) (xy 230.597708 -214.730409)
			(xy 230.589578 -214.781744) (xy 230.573517 -214.831174) (xy 230.549921 -214.877484) (xy 230.519371 -214.919532)
			(xy 230.48262 -214.956283) (xy 230.440572 -214.986833) (xy 230.394262 -215.010429) (xy 230.344832 -215.02649)
			(xy 230.293497 -215.03462) (xy 230.241523 -215.03462) (xy 230.190188 -215.02649) (xy 230.140758 -215.010429)
			(xy 230.094448 -214.986833) (xy 230.0524 -214.956283) (xy 230.015649 -214.919532) (xy 229.985099 -214.877484)
			(xy 229.961503 -214.831174) (xy 229.945442 -214.781744) (xy 229.937312 -214.730409) (xy 228.998016 -214.730409)
			(xy 228.989886 -214.781744) (xy 228.973825 -214.831174) (xy 228.950229 -214.877484) (xy 228.919679 -214.919532)
			(xy 228.882928 -214.956283) (xy 228.84088 -214.986833) (xy 228.79457 -215.010429) (xy 228.74514 -215.02649)
			(xy 228.693805 -215.03462) (xy 228.641831 -215.03462) (xy 228.590496 -215.02649) (xy 228.541066 -215.010429)
			(xy 228.494756 -214.986833) (xy 228.452708 -214.956283) (xy 228.415957 -214.919532) (xy 228.385407 -214.877484)
			(xy 228.361811 -214.831174) (xy 228.34575 -214.781744) (xy 228.33762 -214.730409) (xy 228.19817 -214.730409)
			(xy 228.19004 -214.781744) (xy 228.173979 -214.831174) (xy 228.150383 -214.877484) (xy 228.119833 -214.919532)
			(xy 228.083082 -214.956283) (xy 228.041034 -214.986833) (xy 227.994724 -215.010429) (xy 227.945294 -215.02649)
			(xy 227.893959 -215.03462) (xy 227.841985 -215.03462) (xy 227.79065 -215.02649) (xy 227.74122 -215.010429)
			(xy 227.69491 -214.986833) (xy 227.652862 -214.956283) (xy 227.616111 -214.919532) (xy 227.585561 -214.877484)
			(xy 227.561965 -214.831174) (xy 227.545904 -214.781744) (xy 227.537774 -214.730409) (xy 227.39807 -214.730409)
			(xy 227.38994 -214.781744) (xy 227.373879 -214.831174) (xy 227.350283 -214.877484) (xy 227.319733 -214.919532)
			(xy 227.282982 -214.956283) (xy 227.240934 -214.986833) (xy 227.194624 -215.010429) (xy 227.145194 -215.02649)
			(xy 227.093859 -215.03462) (xy 227.041885 -215.03462) (xy 226.99055 -215.02649) (xy 226.94112 -215.010429)
			(xy 226.89481 -214.986833) (xy 226.852762 -214.956283) (xy 226.816011 -214.919532) (xy 226.785461 -214.877484)
			(xy 226.761865 -214.831174) (xy 226.745804 -214.781744) (xy 226.737674 -214.730409) (xy 226.59797 -214.730409)
			(xy 226.58984 -214.781744) (xy 226.573779 -214.831174) (xy 226.550183 -214.877484) (xy 226.519633 -214.919532)
			(xy 226.482882 -214.956283) (xy 226.440834 -214.986833) (xy 226.394524 -215.010429) (xy 226.345094 -215.02649)
			(xy 226.293759 -215.03462) (xy 226.241785 -215.03462) (xy 226.19045 -215.02649) (xy 226.14102 -215.010429)
			(xy 226.09471 -214.986833) (xy 226.052662 -214.956283) (xy 226.015911 -214.919532) (xy 225.985361 -214.877484)
			(xy 225.961765 -214.831174) (xy 225.945704 -214.781744) (xy 225.937574 -214.730409) (xy 225.798124 -214.730409)
			(xy 225.789994 -214.781744) (xy 225.773933 -214.831174) (xy 225.750337 -214.877484) (xy 225.719787 -214.919532)
			(xy 225.683036 -214.956283) (xy 225.640988 -214.986833) (xy 225.594678 -215.010429) (xy 225.545248 -215.02649)
			(xy 225.493913 -215.03462) (xy 225.441939 -215.03462) (xy 225.390604 -215.02649) (xy 225.341174 -215.010429)
			(xy 225.294864 -214.986833) (xy 225.252816 -214.956283) (xy 225.216065 -214.919532) (xy 225.185515 -214.877484)
			(xy 225.161919 -214.831174) (xy 225.145858 -214.781744) (xy 225.137728 -214.730409) (xy 224.998024 -214.730409)
			(xy 224.989894 -214.781744) (xy 224.973833 -214.831174) (xy 224.950237 -214.877484) (xy 224.919687 -214.919532)
			(xy 224.882936 -214.956283) (xy 224.840888 -214.986833) (xy 224.794578 -215.010429) (xy 224.745148 -215.02649)
			(xy 224.693813 -215.03462) (xy 224.641839 -215.03462) (xy 224.590504 -215.02649) (xy 224.541074 -215.010429)
			(xy 224.494764 -214.986833) (xy 224.452716 -214.956283) (xy 224.415965 -214.919532) (xy 224.385415 -214.877484)
			(xy 224.361819 -214.831174) (xy 224.345758 -214.781744) (xy 224.337628 -214.730409) (xy 224.198178 -214.730409)
			(xy 224.190048 -214.781744) (xy 224.173987 -214.831174) (xy 224.150391 -214.877484) (xy 224.119841 -214.919532)
			(xy 224.08309 -214.956283) (xy 224.041042 -214.986833) (xy 223.994732 -215.010429) (xy 223.945302 -215.02649)
			(xy 223.893967 -215.03462) (xy 223.841993 -215.03462) (xy 223.790658 -215.02649) (xy 223.741228 -215.010429)
			(xy 223.694918 -214.986833) (xy 223.65287 -214.956283) (xy 223.616119 -214.919532) (xy 223.585569 -214.877484)
			(xy 223.561973 -214.831174) (xy 223.545912 -214.781744) (xy 223.537782 -214.730409) (xy 223.398078 -214.730409)
			(xy 223.389948 -214.781744) (xy 223.373887 -214.831174) (xy 223.350291 -214.877484) (xy 223.319741 -214.919532)
			(xy 223.28299 -214.956283) (xy 223.240942 -214.986833) (xy 223.194632 -215.010429) (xy 223.145202 -215.02649)
			(xy 223.093867 -215.03462) (xy 223.041893 -215.03462) (xy 222.990558 -215.02649) (xy 222.941128 -215.010429)
			(xy 222.894818 -214.986833) (xy 222.85277 -214.956283) (xy 222.816019 -214.919532) (xy 222.785469 -214.877484)
			(xy 222.761873 -214.831174) (xy 222.745812 -214.781744) (xy 222.737682 -214.730409) (xy 207.651672 -214.730409)
			(xy 207.654397 -214.748926) (xy 207.654906 -214.776812) (xy 207.654397 -214.804698) (xy 207.646277 -214.859874)
			(xy 207.630209 -214.913281) (xy 207.606537 -214.963778) (xy 207.575764 -215.010291) (xy 207.538547 -215.051828)
			(xy 207.495679 -215.087503) (xy 207.448073 -215.116557) (xy 207.396744 -215.138369) (xy 207.342787 -215.152475)
			(xy 207.28735 -215.158575) (xy 207.231616 -215.156538) (xy 207.176773 -215.146408) (xy 207.123989 -215.128401)
			(xy 207.074389 -215.1029) (xy 207.029031 -215.070449) (xy 206.988882 -215.03174) (xy 206.954796 -214.987597)
			(xy 206.9275 -214.938962) (xy 206.907577 -214.886871) (xy 206.895451 -214.832434) (xy 206.89138 -214.776812)
			(xy 196.968618 -214.776812) (xy 196.968618 -215.525604) (xy 208.560414 -215.525604) (xy 208.564485 -215.469982)
			(xy 208.576611 -215.415545) (xy 208.596534 -215.363454) (xy 208.62383 -215.314819) (xy 208.657916 -215.270676)
			(xy 208.698065 -215.231967) (xy 208.743423 -215.199516) (xy 208.793023 -215.174015) (xy 208.845807 -215.156008)
			(xy 208.90065 -215.145878) (xy 208.956384 -215.143841) (xy 209.011821 -215.149941) (xy 209.065778 -215.164047)
			(xy 209.117107 -215.185859) (xy 209.164713 -215.214913) (xy 209.207581 -215.250588) (xy 209.244798 -215.292125)
			(xy 209.275571 -215.338638) (xy 209.27989 -215.347851) (xy 211.763581 -215.347851) (xy 211.763581 -215.293349)
			(xy 211.771338 -215.2394) (xy 211.786693 -215.187105) (xy 211.809335 -215.137528) (xy 211.838802 -215.091677)
			(xy 211.874494 -215.050487) (xy 211.915685 -215.014796) (xy 211.961537 -214.98533) (xy 212.011115 -214.96269)
			(xy 212.06341 -214.947336) (xy 212.117359 -214.939581) (xy 212.14461 -214.939118) (xy 212.170835 -214.939549)
			(xy 212.222792 -214.94673) (xy 212.273277 -214.960957) (xy 212.321339 -214.98196) (xy 212.366073 -215.009345)
			(xy 212.406638 -215.042596) (xy 212.424772 -215.061546) (xy 212.432646 -215.070436) (xy 212.443314 -215.0745)
			(xy 212.446819 -215.075767) (xy 212.454084 -215.077429) (xy 212.457792 -215.077802) (xy 212.465666 -215.077802)
			(xy 212.557106 -215.07069) (xy 212.566504 -215.065102) (xy 212.571514 -215.062067) (xy 212.580111 -215.054116)
			(xy 212.583522 -215.049354) (xy 212.598768 -215.027468) (xy 212.634444 -214.987814) (xy 212.675293 -214.953514)
			(xy 212.72052 -214.925236) (xy 212.769244 -214.903531) (xy 212.820516 -214.888822) (xy 212.873336 -214.881396)
			(xy 212.900006 -214.880952) (xy 212.927254 -214.881519) (xy 212.981195 -214.889275) (xy 213.033484 -214.904629)
			(xy 213.083055 -214.927268) (xy 213.1289 -214.956731) (xy 213.170085 -214.992419) (xy 213.205772 -215.033605)
			(xy 213.235235 -215.07945) (xy 213.257873 -215.129022) (xy 213.273226 -215.18131) (xy 213.280982 -215.235252)
			(xy 213.280982 -215.289748) (xy 213.280981 -215.289756) (xy 214.563615 -215.289756) (xy 214.563615 -215.235244)
			(xy 214.571373 -215.181287) (xy 214.586731 -215.128983) (xy 214.609376 -215.079397) (xy 214.638848 -215.033539)
			(xy 214.674546 -214.992342) (xy 214.715744 -214.956644) (xy 214.761602 -214.927173) (xy 214.811189 -214.904529)
			(xy 214.863493 -214.889172) (xy 214.91745 -214.881415) (xy 214.944706 -214.880952) (xy 214.971606 -214.881428)
			(xy 215.024872 -214.888981) (xy 215.076546 -214.903949) (xy 215.125602 -214.926035) (xy 215.171065 -214.9548)
			(xy 215.191848 -214.971884) (xy 215.19896 -214.97798) (xy 215.207342 -214.981028) (xy 215.214708 -214.98306)
			(xy 215.225376 -214.984076) (xy 215.292178 -214.98306) (xy 215.296791 -214.982968) (xy 215.305865 -214.981303)
			(xy 215.310212 -214.979758) (xy 215.31834 -214.976456) (xy 215.325452 -214.970106) (xy 215.346563 -214.951952)
			(xy 215.393028 -214.921279) (xy 215.443459 -214.897687) (xy 215.496783 -214.881674) (xy 215.551868 -214.873583)
			(xy 215.579706 -214.873078) (xy 215.607077 -214.873522) (xy 215.661258 -214.881342) (xy 215.713762 -214.896835)
			(xy 215.763509 -214.919682) (xy 215.809474 -214.949413) (xy 215.830404 -214.967058) (xy 215.837516 -214.973154)
			(xy 215.845898 -214.976202) (xy 215.850183 -214.977732) (xy 215.859129 -214.979384) (xy 215.863678 -214.979504)
			(xy 215.930734 -214.979504) (xy 215.935283 -214.979399) (xy 215.944228 -214.977732) (xy 215.948514 -214.976202)
			(xy 215.956896 -214.973154) (xy 215.964008 -214.967058) (xy 215.984921 -214.949395) (xy 216.030899 -214.919688)
			(xy 216.080652 -214.896857) (xy 216.133157 -214.881372) (xy 216.187336 -214.873549) (xy 216.214706 -214.873078)
			(xy 216.241956 -214.873593) (xy 216.295901 -214.88135) (xy 216.348193 -214.896705) (xy 216.397768 -214.919345)
			(xy 216.443616 -214.948811) (xy 216.484803 -214.984501) (xy 216.520493 -215.025689) (xy 216.549958 -215.071538)
			(xy 216.572597 -215.121113) (xy 216.587952 -215.173405) (xy 216.595708 -215.22735) (xy 216.595708 -215.28185)
			(xy 216.587952 -215.335795) (xy 216.572597 -215.388087) (xy 216.549958 -215.437662) (xy 216.520493 -215.483511)
			(xy 216.484803 -215.524699) (xy 216.443616 -215.560389) (xy 216.417907 -215.576912) (xy 217.845892 -215.576912)
			(xy 217.849963 -215.52129) (xy 217.862089 -215.466853) (xy 217.882012 -215.414762) (xy 217.909308 -215.366127)
			(xy 217.943394 -215.321984) (xy 217.983543 -215.283275) (xy 218.028901 -215.250824) (xy 218.078501 -215.225323)
			(xy 218.131285 -215.207316) (xy 218.186128 -215.197186) (xy 218.241862 -215.195149) (xy 218.297299 -215.201249)
			(xy 218.351256 -215.215355) (xy 218.402585 -215.237167) (xy 218.450191 -215.266221) (xy 218.493059 -215.301896)
			(xy 218.530276 -215.343433) (xy 218.561049 -215.389946) (xy 218.584721 -215.440443) (xy 218.600789 -215.49385)
			(xy 218.606147 -215.530255) (xy 222.737682 -215.530255) (xy 222.737682 -215.478281) (xy 222.745812 -215.426946)
			(xy 222.761873 -215.377516) (xy 222.785469 -215.331206) (xy 222.816019 -215.289158) (xy 222.85277 -215.252407)
			(xy 222.894818 -215.221857) (xy 222.941128 -215.198261) (xy 222.990558 -215.1822) (xy 223.041893 -215.17407)
			(xy 223.093867 -215.17407) (xy 223.145202 -215.1822) (xy 223.194632 -215.198261) (xy 223.240942 -215.221857)
			(xy 223.28299 -215.252407) (xy 223.319741 -215.289158) (xy 223.350291 -215.331206) (xy 223.373887 -215.377516)
			(xy 223.389948 -215.426946) (xy 223.398078 -215.478281) (xy 223.398588 -215.504268) (xy 223.398078 -215.530255)
			(xy 223.537782 -215.530255) (xy 223.537782 -215.478281) (xy 223.545912 -215.426946) (xy 223.561973 -215.377516)
			(xy 223.585569 -215.331206) (xy 223.616119 -215.289158) (xy 223.65287 -215.252407) (xy 223.694918 -215.221857)
			(xy 223.741228 -215.198261) (xy 223.790658 -215.1822) (xy 223.841993 -215.17407) (xy 223.893967 -215.17407)
			(xy 223.945302 -215.1822) (xy 223.994732 -215.198261) (xy 224.041042 -215.221857) (xy 224.08309 -215.252407)
			(xy 224.119841 -215.289158) (xy 224.150391 -215.331206) (xy 224.173987 -215.377516) (xy 224.190048 -215.426946)
			(xy 224.198178 -215.478281) (xy 224.198688 -215.504268) (xy 224.198178 -215.530255) (xy 224.337628 -215.530255)
			(xy 224.337628 -215.478281) (xy 224.345758 -215.426946) (xy 224.361819 -215.377516) (xy 224.385415 -215.331206)
			(xy 224.415965 -215.289158) (xy 224.452716 -215.252407) (xy 224.494764 -215.221857) (xy 224.541074 -215.198261)
			(xy 224.590504 -215.1822) (xy 224.641839 -215.17407) (xy 224.693813 -215.17407) (xy 224.745148 -215.1822)
			(xy 224.794578 -215.198261) (xy 224.840888 -215.221857) (xy 224.882936 -215.252407) (xy 224.919687 -215.289158)
			(xy 224.950237 -215.331206) (xy 224.973833 -215.377516) (xy 224.989894 -215.426946) (xy 224.998024 -215.478281)
			(xy 224.998534 -215.504268) (xy 224.998024 -215.530255) (xy 225.137728 -215.530255) (xy 225.137728 -215.478281)
			(xy 225.145858 -215.426946) (xy 225.161919 -215.377516) (xy 225.185515 -215.331206) (xy 225.216065 -215.289158)
			(xy 225.252816 -215.252407) (xy 225.294864 -215.221857) (xy 225.341174 -215.198261) (xy 225.390604 -215.1822)
			(xy 225.441939 -215.17407) (xy 225.493913 -215.17407) (xy 225.545248 -215.1822) (xy 225.594678 -215.198261)
			(xy 225.640988 -215.221857) (xy 225.683036 -215.252407) (xy 225.719787 -215.289158) (xy 225.750337 -215.331206)
			(xy 225.773933 -215.377516) (xy 225.789994 -215.426946) (xy 225.798124 -215.478281) (xy 225.798634 -215.504268)
			(xy 225.798124 -215.530255) (xy 225.937574 -215.530255) (xy 225.937574 -215.478281) (xy 225.945704 -215.426946)
			(xy 225.961765 -215.377516) (xy 225.985361 -215.331206) (xy 226.015911 -215.289158) (xy 226.052662 -215.252407)
			(xy 226.09471 -215.221857) (xy 226.14102 -215.198261) (xy 226.19045 -215.1822) (xy 226.241785 -215.17407)
			(xy 226.293759 -215.17407) (xy 226.345094 -215.1822) (xy 226.394524 -215.198261) (xy 226.440834 -215.221857)
			(xy 226.482882 -215.252407) (xy 226.519633 -215.289158) (xy 226.550183 -215.331206) (xy 226.573779 -215.377516)
			(xy 226.58984 -215.426946) (xy 226.59797 -215.478281) (xy 226.59848 -215.504268) (xy 226.59797 -215.530255)
			(xy 226.737674 -215.530255) (xy 226.737674 -215.478281) (xy 226.745804 -215.426946) (xy 226.761865 -215.377516)
			(xy 226.785461 -215.331206) (xy 226.816011 -215.289158) (xy 226.852762 -215.252407) (xy 226.89481 -215.221857)
			(xy 226.94112 -215.198261) (xy 226.99055 -215.1822) (xy 227.041885 -215.17407) (xy 227.093859 -215.17407)
			(xy 227.145194 -215.1822) (xy 227.194624 -215.198261) (xy 227.240934 -215.221857) (xy 227.282982 -215.252407)
			(xy 227.319733 -215.289158) (xy 227.350283 -215.331206) (xy 227.373879 -215.377516) (xy 227.38994 -215.426946)
			(xy 227.39807 -215.478281) (xy 227.39858 -215.504268) (xy 227.39807 -215.530255) (xy 230.737158 -215.530255)
			(xy 230.737158 -215.478281) (xy 230.745288 -215.426946) (xy 230.761349 -215.377516) (xy 230.784945 -215.331206)
			(xy 230.815495 -215.289158) (xy 230.852246 -215.252407) (xy 230.894294 -215.221857) (xy 230.940604 -215.198261)
			(xy 230.990034 -215.1822) (xy 231.041369 -215.17407) (xy 231.093343 -215.17407) (xy 231.144678 -215.1822)
			(xy 231.194108 -215.198261) (xy 231.240418 -215.221857) (xy 231.282466 -215.252407) (xy 231.319217 -215.289158)
			(xy 231.349767 -215.331206) (xy 231.373363 -215.377516) (xy 231.389424 -215.426946) (xy 231.397554 -215.478281)
			(xy 231.398064 -215.504268) (xy 231.397554 -215.530255) (xy 231.537258 -215.530255) (xy 231.537258 -215.478281)
			(xy 231.545388 -215.426946) (xy 231.561449 -215.377516) (xy 231.585045 -215.331206) (xy 231.615595 -215.289158)
			(xy 231.652346 -215.252407) (xy 231.694394 -215.221857) (xy 231.740704 -215.198261) (xy 231.790134 -215.1822)
			(xy 231.841469 -215.17407) (xy 231.893443 -215.17407) (xy 231.944778 -215.1822) (xy 231.994208 -215.198261)
			(xy 232.040518 -215.221857) (xy 232.082566 -215.252407) (xy 232.119317 -215.289158) (xy 232.149867 -215.331206)
			(xy 232.173463 -215.377516) (xy 232.189524 -215.426946) (xy 232.197654 -215.478281) (xy 232.198164 -215.504268)
			(xy 232.197654 -215.530255) (xy 232.337358 -215.530255) (xy 232.337358 -215.478281) (xy 232.345488 -215.426946)
			(xy 232.361549 -215.377516) (xy 232.385145 -215.331206) (xy 232.415695 -215.289158) (xy 232.452446 -215.252407)
			(xy 232.494494 -215.221857) (xy 232.540804 -215.198261) (xy 232.590234 -215.1822) (xy 232.641569 -215.17407)
			(xy 232.693543 -215.17407) (xy 232.744878 -215.1822) (xy 232.794308 -215.198261) (xy 232.840618 -215.221857)
			(xy 232.882666 -215.252407) (xy 232.919417 -215.289158) (xy 232.949967 -215.331206) (xy 232.973563 -215.377516)
			(xy 232.989624 -215.426946) (xy 232.997754 -215.478281) (xy 232.998264 -215.504268) (xy 232.997754 -215.530255)
			(xy 232.989624 -215.58159) (xy 232.973563 -215.63102) (xy 232.949967 -215.67733) (xy 232.919417 -215.719378)
			(xy 232.882666 -215.756129) (xy 232.840618 -215.786679) (xy 232.794308 -215.810275) (xy 232.744878 -215.826336)
			(xy 232.693543 -215.834466) (xy 232.641569 -215.834466) (xy 232.590234 -215.826336) (xy 232.540804 -215.810275)
			(xy 232.494494 -215.786679) (xy 232.452446 -215.756129) (xy 232.415695 -215.719378) (xy 232.385145 -215.67733)
			(xy 232.361549 -215.63102) (xy 232.345488 -215.58159) (xy 232.337358 -215.530255) (xy 232.197654 -215.530255)
			(xy 232.189524 -215.58159) (xy 232.173463 -215.63102) (xy 232.149867 -215.67733) (xy 232.119317 -215.719378)
			(xy 232.082566 -215.756129) (xy 232.040518 -215.786679) (xy 231.994208 -215.810275) (xy 231.944778 -215.826336)
			(xy 231.893443 -215.834466) (xy 231.841469 -215.834466) (xy 231.790134 -215.826336) (xy 231.740704 -215.810275)
			(xy 231.694394 -215.786679) (xy 231.652346 -215.756129) (xy 231.615595 -215.719378) (xy 231.585045 -215.67733)
			(xy 231.561449 -215.63102) (xy 231.545388 -215.58159) (xy 231.537258 -215.530255) (xy 231.397554 -215.530255)
			(xy 231.389424 -215.58159) (xy 231.373363 -215.63102) (xy 231.349767 -215.67733) (xy 231.319217 -215.719378)
			(xy 231.282466 -215.756129) (xy 231.240418 -215.786679) (xy 231.194108 -215.810275) (xy 231.144678 -215.826336)
			(xy 231.093343 -215.834466) (xy 231.041369 -215.834466) (xy 230.990034 -215.826336) (xy 230.940604 -215.810275)
			(xy 230.894294 -215.786679) (xy 230.852246 -215.756129) (xy 230.815495 -215.719378) (xy 230.784945 -215.67733)
			(xy 230.761349 -215.63102) (xy 230.745288 -215.58159) (xy 230.737158 -215.530255) (xy 227.39807 -215.530255)
			(xy 227.38994 -215.58159) (xy 227.373879 -215.63102) (xy 227.350283 -215.67733) (xy 227.319733 -215.719378)
			(xy 227.282982 -215.756129) (xy 227.240934 -215.786679) (xy 227.194624 -215.810275) (xy 227.145194 -215.826336)
			(xy 227.093859 -215.834466) (xy 227.041885 -215.834466) (xy 226.99055 -215.826336) (xy 226.94112 -215.810275)
			(xy 226.89481 -215.786679) (xy 226.852762 -215.756129) (xy 226.816011 -215.719378) (xy 226.785461 -215.67733)
			(xy 226.761865 -215.63102) (xy 226.745804 -215.58159) (xy 226.737674 -215.530255) (xy 226.59797 -215.530255)
			(xy 226.58984 -215.58159) (xy 226.573779 -215.63102) (xy 226.550183 -215.67733) (xy 226.519633 -215.719378)
			(xy 226.482882 -215.756129) (xy 226.440834 -215.786679) (xy 226.394524 -215.810275) (xy 226.345094 -215.826336)
			(xy 226.293759 -215.834466) (xy 226.241785 -215.834466) (xy 226.19045 -215.826336) (xy 226.14102 -215.810275)
			(xy 226.09471 -215.786679) (xy 226.052662 -215.756129) (xy 226.015911 -215.719378) (xy 225.985361 -215.67733)
			(xy 225.961765 -215.63102) (xy 225.945704 -215.58159) (xy 225.937574 -215.530255) (xy 225.798124 -215.530255)
			(xy 225.789994 -215.58159) (xy 225.773933 -215.63102) (xy 225.750337 -215.67733) (xy 225.719787 -215.719378)
			(xy 225.683036 -215.756129) (xy 225.640988 -215.786679) (xy 225.594678 -215.810275) (xy 225.545248 -215.826336)
			(xy 225.493913 -215.834466) (xy 225.441939 -215.834466) (xy 225.390604 -215.826336) (xy 225.341174 -215.810275)
			(xy 225.294864 -215.786679) (xy 225.252816 -215.756129) (xy 225.216065 -215.719378) (xy 225.185515 -215.67733)
			(xy 225.161919 -215.63102) (xy 225.145858 -215.58159) (xy 225.137728 -215.530255) (xy 224.998024 -215.530255)
			(xy 224.989894 -215.58159) (xy 224.973833 -215.63102) (xy 224.950237 -215.67733) (xy 224.919687 -215.719378)
			(xy 224.882936 -215.756129) (xy 224.840888 -215.786679) (xy 224.794578 -215.810275) (xy 224.745148 -215.826336)
			(xy 224.693813 -215.834466) (xy 224.641839 -215.834466) (xy 224.590504 -215.826336) (xy 224.541074 -215.810275)
			(xy 224.494764 -215.786679) (xy 224.452716 -215.756129) (xy 224.415965 -215.719378) (xy 224.385415 -215.67733)
			(xy 224.361819 -215.63102) (xy 224.345758 -215.58159) (xy 224.337628 -215.530255) (xy 224.198178 -215.530255)
			(xy 224.190048 -215.58159) (xy 224.173987 -215.63102) (xy 224.150391 -215.67733) (xy 224.119841 -215.719378)
			(xy 224.08309 -215.756129) (xy 224.041042 -215.786679) (xy 223.994732 -215.810275) (xy 223.945302 -215.826336)
			(xy 223.893967 -215.834466) (xy 223.841993 -215.834466) (xy 223.790658 -215.826336) (xy 223.741228 -215.810275)
			(xy 223.694918 -215.786679) (xy 223.65287 -215.756129) (xy 223.616119 -215.719378) (xy 223.585569 -215.67733)
			(xy 223.561973 -215.63102) (xy 223.545912 -215.58159) (xy 223.537782 -215.530255) (xy 223.398078 -215.530255)
			(xy 223.389948 -215.58159) (xy 223.373887 -215.63102) (xy 223.350291 -215.67733) (xy 223.319741 -215.719378)
			(xy 223.28299 -215.756129) (xy 223.240942 -215.786679) (xy 223.194632 -215.810275) (xy 223.145202 -215.826336)
			(xy 223.093867 -215.834466) (xy 223.041893 -215.834466) (xy 222.990558 -215.826336) (xy 222.941128 -215.810275)
			(xy 222.894818 -215.786679) (xy 222.85277 -215.756129) (xy 222.816019 -215.719378) (xy 222.785469 -215.67733)
			(xy 222.761873 -215.63102) (xy 222.745812 -215.58159) (xy 222.737682 -215.530255) (xy 218.606147 -215.530255)
			(xy 218.608909 -215.549026) (xy 218.609418 -215.576912) (xy 218.608909 -215.604798) (xy 218.600789 -215.659974)
			(xy 218.584721 -215.713381) (xy 218.561049 -215.763878) (xy 218.530276 -215.810391) (xy 218.493059 -215.851928)
			(xy 218.450191 -215.887603) (xy 218.402585 -215.916657) (xy 218.351256 -215.938469) (xy 218.297299 -215.952575)
			(xy 218.241862 -215.958675) (xy 218.186128 -215.956638) (xy 218.131285 -215.946508) (xy 218.078501 -215.928501)
			(xy 218.028901 -215.903) (xy 217.983543 -215.870549) (xy 217.943394 -215.83184) (xy 217.909308 -215.787697)
			(xy 217.882012 -215.739062) (xy 217.862089 -215.686971) (xy 217.849963 -215.632534) (xy 217.845892 -215.576912)
			(xy 216.417907 -215.576912) (xy 216.397768 -215.589855) (xy 216.348193 -215.612495) (xy 216.295901 -215.62785)
			(xy 216.241956 -215.635607) (xy 216.214706 -215.636094) (xy 216.187336 -215.635626) (xy 216.133157 -215.627809)
			(xy 216.080654 -215.61232) (xy 216.030907 -215.589479) (xy 215.98494 -215.559755) (xy 215.964008 -215.542114)
			(xy 215.956896 -215.536018) (xy 215.948514 -215.53297) (xy 215.944228 -215.531445) (xy 215.935282 -215.529789)
			(xy 215.930734 -215.529668) (xy 215.863678 -215.529668) (xy 215.859129 -215.529778) (xy 215.850184 -215.531442)
			(xy 215.845898 -215.53297) (xy 215.837516 -215.536018) (xy 215.830404 -215.542114) (xy 215.809483 -215.559767)
			(xy 215.763507 -215.589476) (xy 215.713757 -215.612309) (xy 215.661254 -215.627797) (xy 215.607076 -215.635622)
			(xy 215.579706 -215.636094) (xy 215.552806 -215.635623) (xy 215.499539 -215.628071) (xy 215.447864 -215.613103)
			(xy 215.398808 -215.591015) (xy 215.353346 -215.562247) (xy 215.332564 -215.545162) (xy 215.325452 -215.539066)
			(xy 215.31707 -215.536018) (xy 215.309704 -215.533986) (xy 215.299036 -215.53297) (xy 215.232234 -215.533986)
			(xy 215.227621 -215.534078) (xy 215.218547 -215.535743) (xy 215.2142 -215.537288) (xy 215.206072 -215.54059)
			(xy 215.19896 -215.54694) (xy 215.177851 -215.565096) (xy 215.131384 -215.595766) (xy 215.080953 -215.619358)
			(xy 215.027629 -215.63537) (xy 214.972544 -215.643463) (xy 214.944706 -215.643968) (xy 214.91745 -215.643585)
			(xy 214.863493 -215.635828) (xy 214.811189 -215.620471) (xy 214.761602 -215.597827) (xy 214.715744 -215.568356)
			(xy 214.674546 -215.532658) (xy 214.638848 -215.491461) (xy 214.609376 -215.445603) (xy 214.586731 -215.396017)
			(xy 214.571373 -215.343713) (xy 214.563615 -215.289756) (xy 213.280981 -215.289756) (xy 213.273226 -215.34369)
			(xy 213.257873 -215.395978) (xy 213.235235 -215.44555) (xy 213.205772 -215.491395) (xy 213.170085 -215.532581)
			(xy 213.1289 -215.568269) (xy 213.083055 -215.597732) (xy 213.033484 -215.620371) (xy 212.981195 -215.635725)
			(xy 212.927254 -215.643481) (xy 212.900006 -215.643968) (xy 212.873781 -215.643531) (xy 212.821824 -215.636351)
			(xy 212.771339 -215.622126) (xy 212.723277 -215.601124) (xy 212.678543 -215.57374) (xy 212.637978 -215.54049)
			(xy 212.619844 -215.52154) (xy 212.61197 -215.51265) (xy 212.601302 -215.508586) (xy 212.597803 -215.507302)
			(xy 212.590534 -215.505651) (xy 212.586824 -215.505284) (xy 212.57895 -215.505284) (xy 212.48751 -215.512396)
			(xy 212.478112 -215.517984) (xy 212.473106 -215.521025) (xy 212.464506 -215.528972) (xy 212.461094 -215.533732)
			(xy 212.445833 -215.555608) (xy 212.410161 -215.595262) (xy 212.369314 -215.629564) (xy 212.32409 -215.657843)
			(xy 212.275368 -215.67955) (xy 212.224098 -215.69426) (xy 212.171279 -215.701689) (xy 212.14461 -215.702134)
			(xy 212.117359 -215.701619) (xy 212.06341 -215.693864) (xy 212.011115 -215.67851) (xy 211.961537 -215.65587)
			(xy 211.915685 -215.626404) (xy 211.874494 -215.590713) (xy 211.838802 -215.549523) (xy 211.809335 -215.503672)
			(xy 211.786693 -215.454095) (xy 211.771338 -215.4018) (xy 211.763581 -215.347851) (xy 209.27989 -215.347851)
			(xy 209.299243 -215.389135) (xy 209.315311 -215.442542) (xy 209.323431 -215.497718) (xy 209.32394 -215.525604)
			(xy 209.323431 -215.55349) (xy 209.315311 -215.608666) (xy 209.299243 -215.662073) (xy 209.275571 -215.71257)
			(xy 209.244798 -215.759083) (xy 209.207581 -215.80062) (xy 209.164713 -215.836295) (xy 209.117107 -215.865349)
			(xy 209.065778 -215.887161) (xy 209.011821 -215.901267) (xy 208.956384 -215.907367) (xy 208.90065 -215.90533)
			(xy 208.845807 -215.8952) (xy 208.793023 -215.877193) (xy 208.743423 -215.851692) (xy 208.698065 -215.819241)
			(xy 208.657916 -215.780532) (xy 208.62383 -215.736389) (xy 208.596534 -215.687754) (xy 208.576611 -215.635663)
			(xy 208.564485 -215.581226) (xy 208.560414 -215.525604) (xy 196.968618 -215.525604) (xy 196.968618 -216.6112)
			(xy 206.16621 -216.6112) (xy 206.170281 -216.555578) (xy 206.182407 -216.501141) (xy 206.20233 -216.44905)
			(xy 206.229626 -216.400415) (xy 206.263712 -216.356272) (xy 206.303861 -216.317563) (xy 206.349219 -216.285112)
			(xy 206.398819 -216.259611) (xy 206.451603 -216.241604) (xy 206.506446 -216.231474) (xy 206.56218 -216.229437)
			(xy 206.617617 -216.235537) (xy 206.671574 -216.249643) (xy 206.722903 -216.271455) (xy 206.770509 -216.300509)
			(xy 206.813377 -216.336184) (xy 206.850594 -216.377721) (xy 206.881367 -216.424234) (xy 206.905039 -216.474731)
			(xy 206.921107 -216.528138) (xy 206.924958 -216.554304) (xy 208.638646 -216.554304) (xy 208.642717 -216.498682)
			(xy 208.654843 -216.444245) (xy 208.674766 -216.392154) (xy 208.702062 -216.343519) (xy 208.736148 -216.299376)
			(xy 208.776297 -216.260667) (xy 208.821655 -216.228216) (xy 208.871255 -216.202715) (xy 208.924039 -216.184708)
			(xy 208.978882 -216.174578) (xy 209.034616 -216.172541) (xy 209.090053 -216.178641) (xy 209.14401 -216.192747)
			(xy 209.195339 -216.214559) (xy 209.242945 -216.243613) (xy 209.285813 -216.279288) (xy 209.32303 -216.320825)
			(xy 209.353803 -216.367338) (xy 209.377475 -216.417835) (xy 209.382715 -216.435251) (xy 210.184978 -216.435251)
			(xy 210.184978 -216.380749) (xy 210.192734 -216.326801) (xy 210.208089 -216.274506) (xy 210.230731 -216.224929)
			(xy 210.260197 -216.179079) (xy 210.295888 -216.137888) (xy 210.337079 -216.102197) (xy 210.382929 -216.072731)
			(xy 210.432506 -216.050089) (xy 210.484801 -216.034734) (xy 210.538749 -216.026978) (xy 210.566 -216.026492)
			(xy 210.592844 -216.026887) (xy 210.646003 -216.034401) (xy 210.697584 -216.049294) (xy 210.746567 -216.071273)
			(xy 210.791984 -216.099902) (xy 210.832939 -216.134617) (xy 210.868621 -216.174732) (xy 210.898326 -216.219453)
			(xy 210.921467 -216.267898) (xy 210.930897 -216.297856) (xy 212.327141 -216.297856) (xy 212.327141 -216.243344)
			(xy 212.334899 -216.189388) (xy 212.350258 -216.137086) (xy 212.372904 -216.087501) (xy 212.402376 -216.041645)
			(xy 212.438075 -216.000449) (xy 212.479274 -215.964754) (xy 212.525133 -215.935286) (xy 212.574719 -215.912645)
			(xy 212.627024 -215.897292) (xy 212.68098 -215.889538) (xy 212.708236 -215.889078) (xy 212.70849 -215.889078)
			(xy 212.734784 -215.88955) (xy 212.786872 -215.896794) (xy 212.837473 -215.911118) (xy 212.885629 -215.932251)
			(xy 212.930429 -215.959793) (xy 212.971025 -215.993223) (xy 212.98916 -216.012268) (xy 212.996699 -216.019649)
			(xy 213.015966 -216.028187) (xy 213.026498 -216.028778) (xy 213.101174 -216.028778) (xy 213.111725 -216.028255)
			(xy 213.13102 -216.019716) (xy 213.138512 -216.012268) (xy 213.156639 -215.99321) (xy 213.19722 -215.959752)
			(xy 213.242016 -215.932191) (xy 213.290177 -215.911051) (xy 213.340786 -215.896735) (xy 213.392884 -215.889514)
			(xy 213.419182 -215.889078) (xy 213.419436 -215.889078) (xy 213.446685 -215.889595) (xy 213.500626 -215.897355)
			(xy 213.552915 -215.912713) (xy 213.602486 -215.935355) (xy 213.64833 -215.964821) (xy 213.689514 -216.000511)
			(xy 213.7252 -216.041699) (xy 213.754662 -216.087546) (xy 213.7773 -216.137119) (xy 213.792653 -216.189409)
			(xy 213.800408 -216.243351) (xy 213.800408 -216.297849) (xy 213.800407 -216.297856) (xy 215.108441 -216.297856)
			(xy 215.108441 -216.243344) (xy 215.116199 -216.189388) (xy 215.131558 -216.137086) (xy 215.154204 -216.087501)
			(xy 215.183676 -216.041645) (xy 215.219375 -216.000449) (xy 215.260574 -215.964754) (xy 215.306433 -215.935286)
			(xy 215.356019 -215.912645) (xy 215.408324 -215.897292) (xy 215.46228 -215.889538) (xy 215.489536 -215.889078)
			(xy 215.48979 -215.889078) (xy 215.516084 -215.88955) (xy 215.568172 -215.896794) (xy 215.618773 -215.911118)
			(xy 215.666929 -215.932251) (xy 215.711729 -215.959793) (xy 215.752325 -215.993223) (xy 215.77046 -216.012268)
			(xy 215.777999 -216.019649) (xy 215.797266 -216.028187) (xy 215.807798 -216.028778) (xy 215.882474 -216.028778)
			(xy 215.893025 -216.028255) (xy 215.91232 -216.019716) (xy 215.919812 -216.012268) (xy 215.937939 -215.99321)
			(xy 215.97852 -215.959752) (xy 216.023316 -215.932191) (xy 216.071477 -215.911051) (xy 216.122086 -215.896735)
			(xy 216.174184 -215.889514) (xy 216.200482 -215.889078) (xy 216.200736 -215.889078) (xy 216.227985 -215.889595)
			(xy 216.281926 -215.897355) (xy 216.334215 -215.912713) (xy 216.383786 -215.935355) (xy 216.42963 -215.964821)
			(xy 216.470814 -216.000511) (xy 216.5065 -216.041699) (xy 216.535962 -216.087546) (xy 216.5586 -216.137119)
			(xy 216.573953 -216.189409) (xy 216.581708 -216.243351) (xy 216.581708 -216.297849) (xy 216.577035 -216.330355)
			(xy 222.737682 -216.330355) (xy 222.737682 -216.278381) (xy 222.745812 -216.227046) (xy 222.761873 -216.177616)
			(xy 222.785469 -216.131306) (xy 222.816019 -216.089258) (xy 222.85277 -216.052507) (xy 222.894818 -216.021957)
			(xy 222.941128 -215.998361) (xy 222.990558 -215.9823) (xy 223.041893 -215.97417) (xy 223.093867 -215.97417)
			(xy 223.145202 -215.9823) (xy 223.194632 -215.998361) (xy 223.240942 -216.021957) (xy 223.28299 -216.052507)
			(xy 223.319741 -216.089258) (xy 223.350291 -216.131306) (xy 223.373887 -216.177616) (xy 223.389948 -216.227046)
			(xy 223.398078 -216.278381) (xy 223.398588 -216.304368) (xy 223.398078 -216.330355) (xy 223.537782 -216.330355)
			(xy 223.537782 -216.278381) (xy 223.545912 -216.227046) (xy 223.561973 -216.177616) (xy 223.585569 -216.131306)
			(xy 223.616119 -216.089258) (xy 223.65287 -216.052507) (xy 223.694918 -216.021957) (xy 223.741228 -215.998361)
			(xy 223.790658 -215.9823) (xy 223.841993 -215.97417) (xy 223.893967 -215.97417) (xy 223.945302 -215.9823)
			(xy 223.994732 -215.998361) (xy 224.041042 -216.021957) (xy 224.08309 -216.052507) (xy 224.119841 -216.089258)
			(xy 224.150391 -216.131306) (xy 224.173987 -216.177616) (xy 224.190048 -216.227046) (xy 224.198178 -216.278381)
			(xy 224.198688 -216.304368) (xy 224.198178 -216.330355) (xy 224.337628 -216.330355) (xy 224.337628 -216.278381)
			(xy 224.345758 -216.227046) (xy 224.361819 -216.177616) (xy 224.385415 -216.131306) (xy 224.415965 -216.089258)
			(xy 224.452716 -216.052507) (xy 224.494764 -216.021957) (xy 224.541074 -215.998361) (xy 224.590504 -215.9823)
			(xy 224.641839 -215.97417) (xy 224.693813 -215.97417) (xy 224.745148 -215.9823) (xy 224.794578 -215.998361)
			(xy 224.840888 -216.021957) (xy 224.882936 -216.052507) (xy 224.919687 -216.089258) (xy 224.950237 -216.131306)
			(xy 224.973833 -216.177616) (xy 224.989894 -216.227046) (xy 224.998024 -216.278381) (xy 224.998534 -216.304368)
			(xy 224.998024 -216.330355) (xy 225.937574 -216.330355) (xy 225.937574 -216.278381) (xy 225.945704 -216.227046)
			(xy 225.961765 -216.177616) (xy 225.985361 -216.131306) (xy 226.015911 -216.089258) (xy 226.052662 -216.052507)
			(xy 226.09471 -216.021957) (xy 226.14102 -215.998361) (xy 226.19045 -215.9823) (xy 226.241785 -215.97417)
			(xy 226.293759 -215.97417) (xy 226.345094 -215.9823) (xy 226.394524 -215.998361) (xy 226.440834 -216.021957)
			(xy 226.482882 -216.052507) (xy 226.519633 -216.089258) (xy 226.550183 -216.131306) (xy 226.573779 -216.177616)
			(xy 226.58984 -216.227046) (xy 226.59797 -216.278381) (xy 226.59848 -216.304368) (xy 226.597975 -216.330101)
			(xy 226.73742 -216.330101) (xy 226.73742 -216.278127) (xy 226.74555 -216.226792) (xy 226.761611 -216.177362)
			(xy 226.785207 -216.131052) (xy 226.815757 -216.089004) (xy 226.852508 -216.052253) (xy 226.894556 -216.021703)
			(xy 226.940866 -215.998107) (xy 226.990296 -215.982046) (xy 227.041631 -215.973916) (xy 227.093605 -215.973916)
			(xy 227.14494 -215.982046) (xy 227.19437 -215.998107) (xy 227.24068 -216.021703) (xy 227.282728 -216.052253)
			(xy 227.319479 -216.089004) (xy 227.350029 -216.131052) (xy 227.373625 -216.177362) (xy 227.389686 -216.226792)
			(xy 227.397816 -216.278127) (xy 227.398326 -216.304114) (xy 227.397816 -216.330101) (xy 227.397776 -216.330355)
			(xy 227.537774 -216.330355) (xy 227.537774 -216.278381) (xy 227.545904 -216.227046) (xy 227.561965 -216.177616)
			(xy 227.585561 -216.131306) (xy 227.616111 -216.089258) (xy 227.652862 -216.052507) (xy 227.69491 -216.021957)
			(xy 227.74122 -215.998361) (xy 227.79065 -215.9823) (xy 227.841985 -215.97417) (xy 227.893959 -215.97417)
			(xy 227.945294 -215.9823) (xy 227.994724 -215.998361) (xy 228.041034 -216.021957) (xy 228.083082 -216.052507)
			(xy 228.119833 -216.089258) (xy 228.150383 -216.131306) (xy 228.173979 -216.177616) (xy 228.19004 -216.227046)
			(xy 228.19817 -216.278381) (xy 228.19868 -216.304368) (xy 228.19817 -216.330355) (xy 228.33762 -216.330355)
			(xy 228.33762 -216.278381) (xy 228.34575 -216.227046) (xy 228.361811 -216.177616) (xy 228.385407 -216.131306)
			(xy 228.415957 -216.089258) (xy 228.452708 -216.052507) (xy 228.494756 -216.021957) (xy 228.541066 -215.998361)
			(xy 228.590496 -215.9823) (xy 228.641831 -215.97417) (xy 228.693805 -215.97417) (xy 228.74514 -215.9823)
			(xy 228.79457 -215.998361) (xy 228.84088 -216.021957) (xy 228.882928 -216.052507) (xy 228.919679 -216.089258)
			(xy 228.950229 -216.131306) (xy 228.973825 -216.177616) (xy 228.989886 -216.227046) (xy 228.998016 -216.278381)
			(xy 228.998526 -216.304368) (xy 228.998016 -216.330355) (xy 229.937312 -216.330355) (xy 229.937312 -216.278381)
			(xy 229.945442 -216.227046) (xy 229.961503 -216.177616) (xy 229.985099 -216.131306) (xy 230.015649 -216.089258)
			(xy 230.0524 -216.052507) (xy 230.094448 -216.021957) (xy 230.140758 -215.998361) (xy 230.190188 -215.9823)
			(xy 230.241523 -215.97417) (xy 230.293497 -215.97417) (xy 230.344832 -215.9823) (xy 230.394262 -215.998361)
			(xy 230.440572 -216.021957) (xy 230.48262 -216.052507) (xy 230.519371 -216.089258) (xy 230.549921 -216.131306)
			(xy 230.573517 -216.177616) (xy 230.589578 -216.227046) (xy 230.597708 -216.278381) (xy 230.598218 -216.304368)
			(xy 230.597708 -216.330355) (xy 230.737158 -216.330355) (xy 230.737158 -216.278381) (xy 230.745288 -216.227046)
			(xy 230.761349 -216.177616) (xy 230.784945 -216.131306) (xy 230.815495 -216.089258) (xy 230.852246 -216.052507)
			(xy 230.894294 -216.021957) (xy 230.940604 -215.998361) (xy 230.990034 -215.9823) (xy 231.041369 -215.97417)
			(xy 231.093343 -215.97417) (xy 231.144678 -215.9823) (xy 231.194108 -215.998361) (xy 231.240418 -216.021957)
			(xy 231.282466 -216.052507) (xy 231.319217 -216.089258) (xy 231.349767 -216.131306) (xy 231.373363 -216.177616)
			(xy 231.389424 -216.227046) (xy 231.397554 -216.278381) (xy 231.398064 -216.304368) (xy 231.397554 -216.330355)
			(xy 231.537258 -216.330355) (xy 231.537258 -216.278381) (xy 231.545388 -216.227046) (xy 231.561449 -216.177616)
			(xy 231.585045 -216.131306) (xy 231.615595 -216.089258) (xy 231.652346 -216.052507) (xy 231.694394 -216.021957)
			(xy 231.740704 -215.998361) (xy 231.790134 -215.9823) (xy 231.841469 -215.97417) (xy 231.893443 -215.97417)
			(xy 231.944778 -215.9823) (xy 231.994208 -215.998361) (xy 232.040518 -216.021957) (xy 232.082566 -216.052507)
			(xy 232.119317 -216.089258) (xy 232.149867 -216.131306) (xy 232.173463 -216.177616) (xy 232.189524 -216.227046)
			(xy 232.197654 -216.278381) (xy 232.198164 -216.304368) (xy 232.197654 -216.330355) (xy 232.337358 -216.330355)
			(xy 232.337358 -216.278381) (xy 232.345488 -216.227046) (xy 232.361549 -216.177616) (xy 232.385145 -216.131306)
			(xy 232.415695 -216.089258) (xy 232.452446 -216.052507) (xy 232.494494 -216.021957) (xy 232.540804 -215.998361)
			(xy 232.590234 -215.9823) (xy 232.641569 -215.97417) (xy 232.693543 -215.97417) (xy 232.744878 -215.9823)
			(xy 232.794308 -215.998361) (xy 232.840618 -216.021957) (xy 232.882666 -216.052507) (xy 232.919417 -216.089258)
			(xy 232.949967 -216.131306) (xy 232.973563 -216.177616) (xy 232.989624 -216.227046) (xy 232.997754 -216.278381)
			(xy 232.998264 -216.304368) (xy 233.115104 -216.304368) (xy 233.115104 -216.304114) (xy 233.115629 -216.27697)
			(xy 233.123955 -216.223325) (xy 233.140413 -216.171592) (xy 233.164612 -216.122997) (xy 233.19598 -216.078689)
			(xy 233.233774 -216.039718) (xy 233.2771 -216.007006) (xy 233.300778 -215.993726) (xy 233.312621 -215.986828)
			(xy 233.332439 -215.967916) (xy 233.346505 -215.944409) (xy 233.353803 -215.918005) (xy 233.353805 -215.890612)
			(xy 233.346512 -215.864206) (xy 233.33245 -215.840697) (xy 233.312635 -215.821782) (xy 233.300778 -215.81491)
			(xy 233.277102 -215.801625) (xy 233.233774 -215.768915) (xy 233.195976 -215.729945) (xy 233.164604 -215.685639)
			(xy 233.140401 -215.637044) (xy 233.123938 -215.585312) (xy 233.115607 -215.531666) (xy 233.115104 -215.504522)
			(xy 233.115104 -215.504268) (xy 233.115596 -215.477904) (xy 233.123455 -215.425764) (xy 233.138997 -215.375379)
			(xy 233.161875 -215.327872) (xy 233.191578 -215.284306) (xy 233.227442 -215.245653) (xy 233.268667 -215.212778)
			(xy 233.314331 -215.186413) (xy 233.363415 -215.16715) (xy 233.414821 -215.155416) (xy 233.467402 -215.151476)
			(xy 233.519983 -215.155416) (xy 233.571389 -215.16715) (xy 233.620473 -215.186413) (xy 233.666137 -215.212778)
			(xy 233.707362 -215.245653) (xy 233.743226 -215.284306) (xy 233.772929 -215.327872) (xy 233.795807 -215.375379)
			(xy 233.811349 -215.425764) (xy 233.819208 -215.477904) (xy 233.8197 -215.504268) (xy 233.8197 -215.504522)
			(xy 233.819202 -215.531667) (xy 233.81087 -215.585313) (xy 233.794408 -215.637046) (xy 233.770204 -215.685642)
			(xy 233.762303 -215.6968) (xy 240.079782 -215.6968) (xy 240.083853 -215.641178) (xy 240.095979 -215.586741)
			(xy 240.115902 -215.53465) (xy 240.143198 -215.486015) (xy 240.177284 -215.441872) (xy 240.217433 -215.403163)
			(xy 240.262791 -215.370712) (xy 240.312391 -215.345211) (xy 240.365175 -215.327204) (xy 240.420018 -215.317074)
			(xy 240.475752 -215.315037) (xy 240.531189 -215.321137) (xy 240.585146 -215.335243) (xy 240.636475 -215.357055)
			(xy 240.684081 -215.386109) (xy 240.726949 -215.421784) (xy 240.764166 -215.463321) (xy 240.794939 -215.509834)
			(xy 240.818611 -215.560331) (xy 240.834679 -215.613738) (xy 240.842799 -215.668914) (xy 240.843308 -215.6968)
			(xy 240.842799 -215.724686) (xy 240.834679 -215.779862) (xy 240.818611 -215.833269) (xy 240.794939 -215.883766)
			(xy 240.764166 -215.930279) (xy 240.726949 -215.971816) (xy 240.684081 -216.007491) (xy 240.636475 -216.036545)
			(xy 240.585146 -216.058357) (xy 240.531189 -216.072463) (xy 240.475752 -216.078563) (xy 240.420018 -216.076526)
			(xy 240.365175 -216.066396) (xy 240.312391 -216.048389) (xy 240.262791 -216.022888) (xy 240.217433 -215.990437)
			(xy 240.177284 -215.951728) (xy 240.143198 -215.907585) (xy 240.115902 -215.85895) (xy 240.095979 -215.806859)
			(xy 240.083853 -215.752422) (xy 240.079782 -215.6968) (xy 233.762303 -215.6968) (xy 233.738832 -215.729949)
			(xy 233.701034 -215.768919) (xy 233.657706 -215.80163) (xy 233.634026 -215.81491) (xy 233.62215 -215.821756)
			(xy 233.602328 -215.840677) (xy 233.588261 -215.864193) (xy 233.580965 -215.890607) (xy 233.580967 -215.91801)
			(xy 233.588268 -215.944422) (xy 233.602339 -215.967937) (xy 233.622164 -215.986854) (xy 233.634026 -215.993726)
			(xy 233.657696 -216.007024) (xy 233.701029 -216.039727) (xy 233.73883 -216.078692) (xy 233.770205 -216.122997)
			(xy 233.79441 -216.171591) (xy 233.810871 -216.223324) (xy 233.8192 -216.27697) (xy 233.8197 -216.304114)
			(xy 233.8197 -216.304368) (xy 233.819215 -216.330355) (xy 233.937304 -216.330355) (xy 233.937304 -216.278381)
			(xy 233.945434 -216.227046) (xy 233.961495 -216.177616) (xy 233.985091 -216.131306) (xy 234.015641 -216.089258)
			(xy 234.052392 -216.052507) (xy 234.09444 -216.021957) (xy 234.14075 -215.998361) (xy 234.19018 -215.9823)
			(xy 234.241515 -215.97417) (xy 234.293489 -215.97417) (xy 234.344824 -215.9823) (xy 234.394254 -215.998361)
			(xy 234.440564 -216.021957) (xy 234.482612 -216.052507) (xy 234.519363 -216.089258) (xy 234.549913 -216.131306)
			(xy 234.573509 -216.177616) (xy 234.58957 -216.227046) (xy 234.5977 -216.278381) (xy 234.59821 -216.304368)
			(xy 234.5977 -216.330355) (xy 234.73715 -216.330355) (xy 234.73715 -216.278381) (xy 234.74528 -216.227046)
			(xy 234.761341 -216.177616) (xy 234.784937 -216.131306) (xy 234.815487 -216.089258) (xy 234.852238 -216.052507)
			(xy 234.894286 -216.021957) (xy 234.940596 -215.998361) (xy 234.990026 -215.9823) (xy 235.041361 -215.97417)
			(xy 235.093335 -215.97417) (xy 235.14467 -215.9823) (xy 235.1941 -215.998361) (xy 235.24041 -216.021957)
			(xy 235.282458 -216.052507) (xy 235.319209 -216.089258) (xy 235.349759 -216.131306) (xy 235.373355 -216.177616)
			(xy 235.389416 -216.227046) (xy 235.397546 -216.278381) (xy 235.398056 -216.304368) (xy 235.397546 -216.330355)
			(xy 235.389416 -216.38169) (xy 235.373355 -216.43112) (xy 235.349759 -216.47743) (xy 235.319209 -216.519478)
			(xy 235.282458 -216.556229) (xy 235.24041 -216.586779) (xy 235.1941 -216.610375) (xy 235.14467 -216.626436)
			(xy 235.093335 -216.634566) (xy 235.041361 -216.634566) (xy 234.990026 -216.626436) (xy 234.940596 -216.610375)
			(xy 234.894286 -216.586779) (xy 234.852238 -216.556229) (xy 234.815487 -216.519478) (xy 234.784937 -216.47743)
			(xy 234.761341 -216.43112) (xy 234.74528 -216.38169) (xy 234.73715 -216.330355) (xy 234.5977 -216.330355)
			(xy 234.58957 -216.38169) (xy 234.573509 -216.43112) (xy 234.549913 -216.47743) (xy 234.519363 -216.519478)
			(xy 234.482612 -216.556229) (xy 234.440564 -216.586779) (xy 234.394254 -216.610375) (xy 234.344824 -216.626436)
			(xy 234.293489 -216.634566) (xy 234.241515 -216.634566) (xy 234.19018 -216.626436) (xy 234.14075 -216.610375)
			(xy 234.09444 -216.586779) (xy 234.052392 -216.556229) (xy 234.015641 -216.519478) (xy 233.985091 -216.47743)
			(xy 233.961495 -216.43112) (xy 233.945434 -216.38169) (xy 233.937304 -216.330355) (xy 233.819215 -216.330355)
			(xy 233.819208 -216.330732) (xy 233.811349 -216.382872) (xy 233.795807 -216.433257) (xy 233.772929 -216.480764)
			(xy 233.743226 -216.52433) (xy 233.707362 -216.562983) (xy 233.666137 -216.595858) (xy 233.620473 -216.622223)
			(xy 233.571389 -216.641486) (xy 233.519983 -216.65322) (xy 233.467402 -216.65716) (xy 233.414821 -216.65322)
			(xy 233.363415 -216.641486) (xy 233.314331 -216.622223) (xy 233.268667 -216.595858) (xy 233.227442 -216.562983)
			(xy 233.191578 -216.52433) (xy 233.161875 -216.480764) (xy 233.138997 -216.433257) (xy 233.123455 -216.382872)
			(xy 233.115596 -216.330732) (xy 233.115104 -216.304368) (xy 232.998264 -216.304368) (xy 232.997754 -216.330355)
			(xy 232.989624 -216.38169) (xy 232.973563 -216.43112) (xy 232.949967 -216.47743) (xy 232.919417 -216.519478)
			(xy 232.882666 -216.556229) (xy 232.840618 -216.586779) (xy 232.794308 -216.610375) (xy 232.744878 -216.626436)
			(xy 232.693543 -216.634566) (xy 232.641569 -216.634566) (xy 232.590234 -216.626436) (xy 232.540804 -216.610375)
			(xy 232.494494 -216.586779) (xy 232.452446 -216.556229) (xy 232.415695 -216.519478) (xy 232.385145 -216.47743)
			(xy 232.361549 -216.43112) (xy 232.345488 -216.38169) (xy 232.337358 -216.330355) (xy 232.197654 -216.330355)
			(xy 232.189524 -216.38169) (xy 232.173463 -216.43112) (xy 232.149867 -216.47743) (xy 232.119317 -216.519478)
			(xy 232.082566 -216.556229) (xy 232.040518 -216.586779) (xy 231.994208 -216.610375) (xy 231.944778 -216.626436)
			(xy 231.893443 -216.634566) (xy 231.841469 -216.634566) (xy 231.790134 -216.626436) (xy 231.740704 -216.610375)
			(xy 231.694394 -216.586779) (xy 231.652346 -216.556229) (xy 231.615595 -216.519478) (xy 231.585045 -216.47743)
			(xy 231.561449 -216.43112) (xy 231.545388 -216.38169) (xy 231.537258 -216.330355) (xy 231.397554 -216.330355)
			(xy 231.389424 -216.38169) (xy 231.373363 -216.43112) (xy 231.349767 -216.47743) (xy 231.319217 -216.519478)
			(xy 231.282466 -216.556229) (xy 231.240418 -216.586779) (xy 231.194108 -216.610375) (xy 231.144678 -216.626436)
			(xy 231.093343 -216.634566) (xy 231.041369 -216.634566) (xy 230.990034 -216.626436) (xy 230.940604 -216.610375)
			(xy 230.894294 -216.586779) (xy 230.852246 -216.556229) (xy 230.815495 -216.519478) (xy 230.784945 -216.47743)
			(xy 230.761349 -216.43112) (xy 230.745288 -216.38169) (xy 230.737158 -216.330355) (xy 230.597708 -216.330355)
			(xy 230.589578 -216.38169) (xy 230.573517 -216.43112) (xy 230.549921 -216.47743) (xy 230.519371 -216.519478)
			(xy 230.48262 -216.556229) (xy 230.440572 -216.586779) (xy 230.394262 -216.610375) (xy 230.344832 -216.626436)
			(xy 230.293497 -216.634566) (xy 230.241523 -216.634566) (xy 230.190188 -216.626436) (xy 230.140758 -216.610375)
			(xy 230.094448 -216.586779) (xy 230.0524 -216.556229) (xy 230.015649 -216.519478) (xy 229.985099 -216.47743)
			(xy 229.961503 -216.43112) (xy 229.945442 -216.38169) (xy 229.937312 -216.330355) (xy 228.998016 -216.330355)
			(xy 228.989886 -216.38169) (xy 228.973825 -216.43112) (xy 228.950229 -216.47743) (xy 228.919679 -216.519478)
			(xy 228.882928 -216.556229) (xy 228.84088 -216.586779) (xy 228.79457 -216.610375) (xy 228.74514 -216.626436)
			(xy 228.693805 -216.634566) (xy 228.641831 -216.634566) (xy 228.590496 -216.626436) (xy 228.541066 -216.610375)
			(xy 228.494756 -216.586779) (xy 228.452708 -216.556229) (xy 228.415957 -216.519478) (xy 228.385407 -216.47743)
			(xy 228.361811 -216.43112) (xy 228.34575 -216.38169) (xy 228.33762 -216.330355) (xy 228.19817 -216.330355)
			(xy 228.19004 -216.38169) (xy 228.173979 -216.43112) (xy 228.150383 -216.47743) (xy 228.119833 -216.519478)
			(xy 228.083082 -216.556229) (xy 228.041034 -216.586779) (xy 227.994724 -216.610375) (xy 227.945294 -216.626436)
			(xy 227.893959 -216.634566) (xy 227.841985 -216.634566) (xy 227.79065 -216.626436) (xy 227.74122 -216.610375)
			(xy 227.69491 -216.586779) (xy 227.652862 -216.556229) (xy 227.616111 -216.519478) (xy 227.585561 -216.47743)
			(xy 227.561965 -216.43112) (xy 227.545904 -216.38169) (xy 227.537774 -216.330355) (xy 227.397776 -216.330355)
			(xy 227.389686 -216.381436) (xy 227.373625 -216.430866) (xy 227.350029 -216.477176) (xy 227.319479 -216.519224)
			(xy 227.282728 -216.555975) (xy 227.24068 -216.586525) (xy 227.19437 -216.610121) (xy 227.14494 -216.626182)
			(xy 227.093605 -216.634312) (xy 227.041631 -216.634312) (xy 226.990296 -216.626182) (xy 226.940866 -216.610121)
			(xy 226.894556 -216.586525) (xy 226.852508 -216.555975) (xy 226.815757 -216.519224) (xy 226.785207 -216.477176)
			(xy 226.761611 -216.430866) (xy 226.74555 -216.381436) (xy 226.73742 -216.330101) (xy 226.597975 -216.330101)
			(xy 226.59797 -216.330355) (xy 226.58984 -216.38169) (xy 226.573779 -216.43112) (xy 226.550183 -216.47743)
			(xy 226.519633 -216.519478) (xy 226.482882 -216.556229) (xy 226.440834 -216.586779) (xy 226.394524 -216.610375)
			(xy 226.345094 -216.626436) (xy 226.293759 -216.634566) (xy 226.241785 -216.634566) (xy 226.19045 -216.626436)
			(xy 226.14102 -216.610375) (xy 226.09471 -216.586779) (xy 226.052662 -216.556229) (xy 226.015911 -216.519478)
			(xy 225.985361 -216.47743) (xy 225.961765 -216.43112) (xy 225.945704 -216.38169) (xy 225.937574 -216.330355)
			(xy 224.998024 -216.330355) (xy 224.989894 -216.38169) (xy 224.973833 -216.43112) (xy 224.950237 -216.47743)
			(xy 224.919687 -216.519478) (xy 224.882936 -216.556229) (xy 224.840888 -216.586779) (xy 224.794578 -216.610375)
			(xy 224.745148 -216.626436) (xy 224.693813 -216.634566) (xy 224.641839 -216.634566) (xy 224.590504 -216.626436)
			(xy 224.541074 -216.610375) (xy 224.494764 -216.586779) (xy 224.452716 -216.556229) (xy 224.415965 -216.519478)
			(xy 224.385415 -216.47743) (xy 224.361819 -216.43112) (xy 224.345758 -216.38169) (xy 224.337628 -216.330355)
			(xy 224.198178 -216.330355) (xy 224.190048 -216.38169) (xy 224.173987 -216.43112) (xy 224.150391 -216.47743)
			(xy 224.119841 -216.519478) (xy 224.08309 -216.556229) (xy 224.041042 -216.586779) (xy 223.994732 -216.610375)
			(xy 223.945302 -216.626436) (xy 223.893967 -216.634566) (xy 223.841993 -216.634566) (xy 223.790658 -216.626436)
			(xy 223.741228 -216.610375) (xy 223.694918 -216.586779) (xy 223.65287 -216.556229) (xy 223.616119 -216.519478)
			(xy 223.585569 -216.47743) (xy 223.561973 -216.43112) (xy 223.545912 -216.38169) (xy 223.537782 -216.330355)
			(xy 223.398078 -216.330355) (xy 223.389948 -216.38169) (xy 223.373887 -216.43112) (xy 223.350291 -216.47743)
			(xy 223.319741 -216.519478) (xy 223.28299 -216.556229) (xy 223.240942 -216.586779) (xy 223.194632 -216.610375)
			(xy 223.145202 -216.626436) (xy 223.093867 -216.634566) (xy 223.041893 -216.634566) (xy 222.990558 -216.626436)
			(xy 222.941128 -216.610375) (xy 222.894818 -216.586779) (xy 222.85277 -216.556229) (xy 222.816019 -216.519478)
			(xy 222.785469 -216.47743) (xy 222.761873 -216.43112) (xy 222.745812 -216.38169) (xy 222.737682 -216.330355)
			(xy 216.577035 -216.330355) (xy 216.573953 -216.351791) (xy 216.5586 -216.404081) (xy 216.535962 -216.453654)
			(xy 216.5065 -216.499501) (xy 216.470814 -216.540689) (xy 216.42963 -216.576379) (xy 216.383786 -216.605845)
			(xy 216.334215 -216.628487) (xy 216.281926 -216.643845) (xy 216.227985 -216.651605) (xy 216.200736 -216.652094)
			(xy 216.200482 -216.652094) (xy 216.174187 -216.651649) (xy 216.122097 -216.644401) (xy 216.071496 -216.630073)
			(xy 216.023339 -216.608935) (xy 215.97854 -216.581387) (xy 215.937946 -216.547952) (xy 215.919812 -216.528904)
			(xy 215.912287 -216.521506) (xy 215.89301 -216.51298) (xy 215.882474 -216.512394) (xy 215.807798 -216.512394)
			(xy 215.797247 -216.51291) (xy 215.777952 -216.521455) (xy 215.77046 -216.528904) (xy 215.752361 -216.547989)
			(xy 215.711772 -216.581443) (xy 215.66697 -216.608998) (xy 215.618804 -216.630132) (xy 215.56819 -216.644443)
			(xy 215.516089 -216.65166) (xy 215.48979 -216.652094) (xy 215.489536 -216.652094) (xy 215.46228 -216.651662)
			(xy 215.408324 -216.643908) (xy 215.356019 -216.628555) (xy 215.306433 -216.605914) (xy 215.260574 -216.576446)
			(xy 215.219375 -216.540751) (xy 215.183676 -216.499555) (xy 215.154204 -216.453699) (xy 215.131558 -216.404114)
			(xy 215.116199 -216.351812) (xy 215.108441 -216.297856) (xy 213.800407 -216.297856) (xy 213.792653 -216.351791)
			(xy 213.7773 -216.404081) (xy 213.754662 -216.453654) (xy 213.7252 -216.499501) (xy 213.689514 -216.540689)
			(xy 213.64833 -216.576379) (xy 213.602486 -216.605845) (xy 213.552915 -216.628487) (xy 213.500626 -216.643845)
			(xy 213.446685 -216.651605) (xy 213.419436 -216.652094) (xy 213.419182 -216.652094) (xy 213.392887 -216.651649)
			(xy 213.340797 -216.644401) (xy 213.290196 -216.630073) (xy 213.242039 -216.608935) (xy 213.19724 -216.581387)
			(xy 213.156646 -216.547952) (xy 213.138512 -216.528904) (xy 213.130987 -216.521506) (xy 213.11171 -216.51298)
			(xy 213.101174 -216.512394) (xy 213.026498 -216.512394) (xy 213.015947 -216.51291) (xy 212.996652 -216.521455)
			(xy 212.98916 -216.528904) (xy 212.971061 -216.547989) (xy 212.930472 -216.581443) (xy 212.88567 -216.608998)
			(xy 212.837504 -216.630132) (xy 212.78689 -216.644443) (xy 212.734789 -216.65166) (xy 212.70849 -216.652094)
			(xy 212.708236 -216.652094) (xy 212.68098 -216.651662) (xy 212.627024 -216.643908) (xy 212.574719 -216.628555)
			(xy 212.525133 -216.605914) (xy 212.479274 -216.576446) (xy 212.438075 -216.540751) (xy 212.402376 -216.499555)
			(xy 212.372904 -216.453699) (xy 212.350258 -216.404114) (xy 212.334899 -216.351812) (xy 212.327141 -216.297856)
			(xy 210.930897 -216.297856) (xy 210.937587 -216.319108) (xy 210.942428 -216.345516) (xy 210.944206 -216.356946)
			(xy 210.95081 -216.366344) (xy 210.95418 -216.370851) (xy 210.962507 -216.378415) (xy 210.96732 -216.38133)
			(xy 211.036154 -216.420192) (xy 211.045806 -216.42451) (xy 211.057998 -216.426796) (xy 211.069428 -216.427558)
			(xy 211.08035 -216.42324) (xy 211.102966 -216.414577) (xy 211.149832 -216.402368) (xy 211.197867 -216.3962)
			(xy 211.222082 -216.395808) (xy 211.249335 -216.396272) (xy 211.303287 -216.404027) (xy 211.355586 -216.419382)
			(xy 211.405167 -216.442023) (xy 211.451021 -216.471491) (xy 211.492214 -216.507185) (xy 211.527908 -216.548378)
			(xy 211.557376 -216.594231) (xy 211.580018 -216.643812) (xy 211.595373 -216.696111) (xy 211.603128 -216.750063)
			(xy 211.60359 -216.777316) (xy 211.603526 -216.787879) (xy 211.602383 -216.808973) (xy 211.601304 -216.81948)
			(xy 211.600034 -216.82964) (xy 211.603082 -216.8398) (xy 211.608416 -216.851484) (xy 211.612734 -216.85758)
			(xy 211.659216 -216.91346) (xy 211.662592 -216.917402) (xy 211.670663 -216.923925) (xy 211.675218 -216.926414)
			(xy 211.684108 -216.930986) (xy 211.694522 -216.931748) (xy 211.722899 -216.934511) (xy 211.778452 -216.94733)
			(xy 211.831478 -216.968272) (xy 211.880799 -216.996871) (xy 211.925315 -217.03249) (xy 211.964035 -217.074337)
			(xy 211.996099 -217.121478) (xy 212.020791 -217.172866) (xy 212.037562 -217.227355) (xy 212.046039 -217.283734)
			(xy 212.046092 -217.286586) (xy 212.262464 -217.286586) (xy 212.266535 -217.230964) (xy 212.278661 -217.176527)
			(xy 212.298584 -217.124436) (xy 212.32588 -217.075801) (xy 212.359966 -217.031658) (xy 212.400115 -216.992949)
			(xy 212.445473 -216.960498) (xy 212.495073 -216.934997) (xy 212.547857 -216.91699) (xy 212.6027 -216.90686)
			(xy 212.658434 -216.904823) (xy 212.713871 -216.910923) (xy 212.767828 -216.925029) (xy 212.819157 -216.946841)
			(xy 212.866763 -216.975895) (xy 212.909631 -217.01157) (xy 212.946848 -217.053107) (xy 212.977621 -217.09962)
			(xy 213.001293 -217.150117) (xy 213.017361 -217.203524) (xy 213.025481 -217.2587) (xy 213.02599 -217.286586)
			(xy 214.587326 -217.286586) (xy 214.591397 -217.230964) (xy 214.603523 -217.176527) (xy 214.623446 -217.124436)
			(xy 214.650742 -217.075801) (xy 214.684828 -217.031658) (xy 214.724977 -216.992949) (xy 214.770335 -216.960498)
			(xy 214.819935 -216.934997) (xy 214.872719 -216.91699) (xy 214.927562 -216.90686) (xy 214.983296 -216.904823)
			(xy 215.038733 -216.910923) (xy 215.09269 -216.925029) (xy 215.144019 -216.946841) (xy 215.191625 -216.975895)
			(xy 215.234493 -217.01157) (xy 215.27171 -217.053107) (xy 215.302483 -217.09962) (xy 215.326155 -217.150117)
			(xy 215.342223 -217.203524) (xy 215.344952 -217.22207) (xy 215.812876 -217.22207) (xy 215.816947 -217.166448)
			(xy 215.829073 -217.112011) (xy 215.848996 -217.05992) (xy 215.876292 -217.011285) (xy 215.910378 -216.967142)
			(xy 215.950527 -216.928433) (xy 215.995885 -216.895982) (xy 216.045485 -216.870481) (xy 216.098269 -216.852474)
			(xy 216.153112 -216.842344) (xy 216.208846 -216.840307) (xy 216.264283 -216.846407) (xy 216.31824 -216.860513)
			(xy 216.369569 -216.882325) (xy 216.417175 -216.911379) (xy 216.460043 -216.947054) (xy 216.49726 -216.988591)
			(xy 216.528033 -217.035104) (xy 216.551705 -217.085601) (xy 216.5652 -217.130455) (xy 224.337628 -217.130455)
			(xy 224.337628 -217.078481) (xy 224.345758 -217.027146) (xy 224.361819 -216.977716) (xy 224.385415 -216.931406)
			(xy 224.415965 -216.889358) (xy 224.452716 -216.852607) (xy 224.494764 -216.822057) (xy 224.541074 -216.798461)
			(xy 224.590504 -216.7824) (xy 224.641839 -216.77427) (xy 224.693813 -216.77427) (xy 224.745148 -216.7824)
			(xy 224.794578 -216.798461) (xy 224.840888 -216.822057) (xy 224.882936 -216.852607) (xy 224.919687 -216.889358)
			(xy 224.950237 -216.931406) (xy 224.973833 -216.977716) (xy 224.989894 -217.027146) (xy 224.998024 -217.078481)
			(xy 224.998534 -217.104468) (xy 224.998024 -217.130455) (xy 226.737674 -217.130455) (xy 226.737674 -217.078481)
			(xy 226.745804 -217.027146) (xy 226.761865 -216.977716) (xy 226.785461 -216.931406) (xy 226.816011 -216.889358)
			(xy 226.852762 -216.852607) (xy 226.89481 -216.822057) (xy 226.94112 -216.798461) (xy 226.99055 -216.7824)
			(xy 227.041885 -216.77427) (xy 227.093859 -216.77427) (xy 227.145194 -216.7824) (xy 227.194624 -216.798461)
			(xy 227.240934 -216.822057) (xy 227.282982 -216.852607) (xy 227.319733 -216.889358) (xy 227.350283 -216.931406)
			(xy 227.373879 -216.977716) (xy 227.38994 -217.027146) (xy 227.39807 -217.078481) (xy 227.39858 -217.104468)
			(xy 227.39807 -217.130455) (xy 227.537774 -217.130455) (xy 227.537774 -217.078481) (xy 227.545904 -217.027146)
			(xy 227.561965 -216.977716) (xy 227.585561 -216.931406) (xy 227.616111 -216.889358) (xy 227.652862 -216.852607)
			(xy 227.69491 -216.822057) (xy 227.74122 -216.798461) (xy 227.79065 -216.7824) (xy 227.841985 -216.77427)
			(xy 227.893959 -216.77427) (xy 227.945294 -216.7824) (xy 227.994724 -216.798461) (xy 228.041034 -216.822057)
			(xy 228.083082 -216.852607) (xy 228.119833 -216.889358) (xy 228.150383 -216.931406) (xy 228.173979 -216.977716)
			(xy 228.19004 -217.027146) (xy 228.19817 -217.078481) (xy 228.19868 -217.104468) (xy 228.19817 -217.130455)
			(xy 228.33762 -217.130455) (xy 228.33762 -217.078481) (xy 228.34575 -217.027146) (xy 228.361811 -216.977716)
			(xy 228.385407 -216.931406) (xy 228.415957 -216.889358) (xy 228.452708 -216.852607) (xy 228.494756 -216.822057)
			(xy 228.541066 -216.798461) (xy 228.590496 -216.7824) (xy 228.641831 -216.77427) (xy 228.693805 -216.77427)
			(xy 228.74514 -216.7824) (xy 228.79457 -216.798461) (xy 228.84088 -216.822057) (xy 228.882928 -216.852607)
			(xy 228.919679 -216.889358) (xy 228.950229 -216.931406) (xy 228.973825 -216.977716) (xy 228.989886 -217.027146)
			(xy 228.998016 -217.078481) (xy 228.998526 -217.104468) (xy 228.998016 -217.130455) (xy 229.937312 -217.130455)
			(xy 229.937312 -217.078481) (xy 229.945442 -217.027146) (xy 229.961503 -216.977716) (xy 229.985099 -216.931406)
			(xy 230.015649 -216.889358) (xy 230.0524 -216.852607) (xy 230.094448 -216.822057) (xy 230.140758 -216.798461)
			(xy 230.190188 -216.7824) (xy 230.241523 -216.77427) (xy 230.293497 -216.77427) (xy 230.344832 -216.7824)
			(xy 230.394262 -216.798461) (xy 230.440572 -216.822057) (xy 230.48262 -216.852607) (xy 230.519371 -216.889358)
			(xy 230.549921 -216.931406) (xy 230.573517 -216.977716) (xy 230.589578 -217.027146) (xy 230.597708 -217.078481)
			(xy 230.598218 -217.104468) (xy 230.597708 -217.130455) (xy 230.737158 -217.130455) (xy 230.737158 -217.078481)
			(xy 230.745288 -217.027146) (xy 230.761349 -216.977716) (xy 230.784945 -216.931406) (xy 230.815495 -216.889358)
			(xy 230.852246 -216.852607) (xy 230.894294 -216.822057) (xy 230.940604 -216.798461) (xy 230.990034 -216.7824)
			(xy 231.041369 -216.77427) (xy 231.093343 -216.77427) (xy 231.144678 -216.7824) (xy 231.194108 -216.798461)
			(xy 231.240418 -216.822057) (xy 231.282466 -216.852607) (xy 231.319217 -216.889358) (xy 231.349767 -216.931406)
			(xy 231.373363 -216.977716) (xy 231.389424 -217.027146) (xy 231.397554 -217.078481) (xy 231.398064 -217.104468)
			(xy 231.397554 -217.130455) (xy 231.537258 -217.130455) (xy 231.537258 -217.078481) (xy 231.545388 -217.027146)
			(xy 231.561449 -216.977716) (xy 231.585045 -216.931406) (xy 231.615595 -216.889358) (xy 231.652346 -216.852607)
			(xy 231.694394 -216.822057) (xy 231.740704 -216.798461) (xy 231.790134 -216.7824) (xy 231.841469 -216.77427)
			(xy 231.893443 -216.77427) (xy 231.944778 -216.7824) (xy 231.994208 -216.798461) (xy 232.040518 -216.822057)
			(xy 232.082566 -216.852607) (xy 232.119317 -216.889358) (xy 232.149867 -216.931406) (xy 232.173463 -216.977716)
			(xy 232.189524 -217.027146) (xy 232.197654 -217.078481) (xy 232.198164 -217.104468) (xy 232.197654 -217.130455)
			(xy 232.337358 -217.130455) (xy 232.337358 -217.078481) (xy 232.345488 -217.027146) (xy 232.361549 -216.977716)
			(xy 232.385145 -216.931406) (xy 232.415695 -216.889358) (xy 232.452446 -216.852607) (xy 232.494494 -216.822057)
			(xy 232.540804 -216.798461) (xy 232.590234 -216.7824) (xy 232.641569 -216.77427) (xy 232.693543 -216.77427)
			(xy 232.744878 -216.7824) (xy 232.794308 -216.798461) (xy 232.840618 -216.822057) (xy 232.882666 -216.852607)
			(xy 232.919417 -216.889358) (xy 232.949967 -216.931406) (xy 232.973563 -216.977716) (xy 232.989624 -217.027146)
			(xy 232.997754 -217.078481) (xy 232.998264 -217.104468) (xy 232.997754 -217.130455) (xy 233.937304 -217.130455)
			(xy 233.937304 -217.078481) (xy 233.945434 -217.027146) (xy 233.961495 -216.977716) (xy 233.985091 -216.931406)
			(xy 234.015641 -216.889358) (xy 234.052392 -216.852607) (xy 234.09444 -216.822057) (xy 234.14075 -216.798461)
			(xy 234.19018 -216.7824) (xy 234.241515 -216.77427) (xy 234.293489 -216.77427) (xy 234.344824 -216.7824)
			(xy 234.394254 -216.798461) (xy 234.440564 -216.822057) (xy 234.482612 -216.852607) (xy 234.519363 -216.889358)
			(xy 234.549913 -216.931406) (xy 234.573509 -216.977716) (xy 234.58957 -217.027146) (xy 234.5977 -217.078481)
			(xy 234.59821 -217.104468) (xy 234.5977 -217.130455) (xy 234.594052 -217.15349) (xy 240.342672 -217.15349)
			(xy 240.346743 -217.097868) (xy 240.358869 -217.043431) (xy 240.378792 -216.99134) (xy 240.406088 -216.942705)
			(xy 240.440174 -216.898562) (xy 240.480323 -216.859853) (xy 240.525681 -216.827402) (xy 240.575281 -216.801901)
			(xy 240.628065 -216.783894) (xy 240.682908 -216.773764) (xy 240.738642 -216.771727) (xy 240.794079 -216.777827)
			(xy 240.848036 -216.791933) (xy 240.899365 -216.813745) (xy 240.946971 -216.842799) (xy 240.965648 -216.858342)
			(xy 246.074438 -216.858342) (xy 246.07496 -216.831169) (xy 246.082654 -216.77737) (xy 246.097907 -216.725209)
			(xy 246.120409 -216.67574) (xy 246.149705 -216.629967) (xy 246.185202 -216.588815) (xy 246.22618 -216.553118)
			(xy 246.271811 -216.5236) (xy 246.321169 -216.500858) (xy 246.373256 -216.485352) (xy 246.400066 -216.480898)
			(xy 246.411496 -216.47912) (xy 246.42064 -216.473024) (xy 246.425291 -216.469777) (xy 246.433119 -216.461573)
			(xy 246.436134 -216.456768) (xy 246.47652 -216.389204) (xy 246.479064 -216.384713) (xy 246.482521 -216.37499)
			(xy 246.483378 -216.3699) (xy 246.483632 -216.367614) (xy 246.484648 -216.356692) (xy 246.480584 -216.34577)
			(xy 246.469939 -216.314382) (xy 246.458452 -216.249112) (xy 246.457724 -216.215976) (xy 246.457724 -216.215468)
			(xy 246.458148 -216.188215) (xy 246.46591 -216.134263) (xy 246.481271 -216.081965) (xy 246.503918 -216.032386)
			(xy 246.53339 -215.986534) (xy 246.569088 -215.945343) (xy 246.610285 -215.909652) (xy 246.656142 -215.880187)
			(xy 246.705725 -215.857548) (xy 246.758026 -215.842196) (xy 246.811978 -215.834444) (xy 246.839232 -215.83396)
			(xy 246.865423 -215.834405) (xy 246.917307 -215.841622) (xy 246.967717 -215.855862) (xy 246.991886 -215.865964)
			(xy 246.993918 -215.866726) (xy 246.999908 -215.868815) (xy 247.012494 -215.870366) (xy 247.01881 -215.869774)
			(xy 247.019064 -215.86952) (xy 247.025839 -215.868384) (xy 247.038458 -215.862971) (xy 247.043956 -215.858852)
			(xy 247.113806 -215.803226) (xy 247.11832 -215.799515) (xy 247.125624 -215.790396) (xy 247.128284 -215.785192)
			(xy 247.130062 -215.780874) (xy 247.132602 -215.77427) (xy 247.133618 -215.7603) (xy 247.132348 -215.753696)
			(xy 247.129155 -215.735897) (xy 247.125717 -215.699896) (xy 247.12549 -215.681814) (xy 247.12549 -215.68156)
			(xy 247.125941 -215.654308) (xy 247.133703 -215.600359) (xy 247.149063 -215.548064) (xy 247.171708 -215.498486)
			(xy 247.201179 -215.452636) (xy 247.236874 -215.411447) (xy 247.278067 -215.375756) (xy 247.32392 -215.34629)
			(xy 247.373499 -215.323649) (xy 247.425796 -215.308294) (xy 247.479746 -215.300538) (xy 247.506998 -215.300052)
			(xy 247.536106 -215.300639) (xy 247.593634 -215.309574) (xy 247.621552 -215.317832) (xy 247.62206 -215.317832)
			(xy 247.634252 -215.321642) (xy 247.646698 -215.319356) (xy 247.652808 -215.317953) (xy 247.664116 -215.312555)
			(xy 247.66905 -215.308688) (xy 247.73509 -215.25484) (xy 247.739804 -215.25082) (xy 247.747248 -215.240919)
			(xy 247.749822 -215.235282) (xy 247.754902 -215.223598) (xy 247.753632 -215.210644) (xy 247.7516 -215.17229)
			(xy 247.752089 -215.14504) (xy 247.759847 -215.091094) (xy 247.775202 -215.038802) (xy 247.797844 -214.989227)
			(xy 247.82731 -214.943379) (xy 247.863001 -214.902191) (xy 247.90419 -214.866501) (xy 247.950039 -214.837037)
			(xy 247.999615 -214.814397) (xy 248.051908 -214.799044) (xy 248.105854 -214.791288) (xy 248.160354 -214.791289)
			(xy 248.2143 -214.799045) (xy 248.266593 -214.8144) (xy 248.316168 -214.837041) (xy 248.362016 -214.866506)
			(xy 248.403205 -214.902197) (xy 248.438895 -214.943385) (xy 248.46836 -214.989234) (xy 248.491001 -215.038809)
			(xy 248.506355 -215.091102) (xy 248.514112 -215.145048) (xy 248.514112 -215.199548) (xy 248.506356 -215.253494)
			(xy 248.491002 -215.305787) (xy 248.468362 -215.355362) (xy 248.438897 -215.401212) (xy 248.403208 -215.442401)
			(xy 248.36202 -215.478091) (xy 248.316171 -215.507557) (xy 248.266596 -215.530198) (xy 248.214304 -215.545554)
			(xy 248.160358 -215.553311) (xy 248.133108 -215.553798) (xy 248.104 -215.553211) (xy 248.046472 -215.544276)
			(xy 248.018554 -215.536018) (xy 248.018046 -215.536018) (xy 248.005854 -215.532208) (xy 247.993408 -215.534494)
			(xy 247.987301 -215.535907) (xy 247.975992 -215.541299) (xy 247.971056 -215.545162) (xy 247.905016 -215.59901)
			(xy 247.900313 -215.603042) (xy 247.892862 -215.612935) (xy 247.890284 -215.618568) (xy 247.885204 -215.630252)
			(xy 247.885254 -215.63076) (xy 250.367292 -215.63076) (xy 250.367292 -215.630506) (xy 250.367787 -215.602526)
			(xy 250.375984 -215.547168) (xy 250.392173 -215.4936) (xy 250.416008 -215.442969) (xy 250.446979 -215.396359)
			(xy 250.465336 -215.375236) (xy 250.47194 -215.368124) (xy 250.475242 -215.359488) (xy 250.476004 -215.35771)
			(xy 250.477207 -215.353755) (xy 250.478478 -215.345587) (xy 250.478544 -215.341454) (xy 250.478544 -215.273128)
			(xy 250.478513 -215.268992) (xy 250.477236 -215.26082) (xy 250.476004 -215.256872) (xy 250.475242 -215.255094)
			(xy 250.47194 -215.246458) (xy 250.46559 -215.239346) (xy 250.447253 -215.21825) (xy 250.416346 -215.171677)
			(xy 250.392571 -215.121091) (xy 250.376435 -215.067575) (xy 250.368285 -215.012278) (xy 250.3678 -214.98433)
			(xy 250.368311 -214.956592) (xy 250.376355 -214.901702) (xy 250.392261 -214.848555) (xy 250.415696 -214.798272)
			(xy 250.446165 -214.751912) (xy 250.483026 -214.710453) (xy 250.503944 -214.69223) (xy 250.512072 -214.685372)
			(xy 250.516898 -214.675466) (xy 250.518494 -214.672072) (xy 250.520786 -214.66493) (xy 250.52147 -214.661242)
			(xy 250.521978 -214.6554) (xy 250.525026 -214.580216) (xy 250.525083 -214.575093) (xy 250.523421 -214.564984)
			(xy 250.521724 -214.56015) (xy 250.517914 -214.549736) (xy 250.510294 -214.54237) (xy 250.489321 -214.520738)
			(xy 250.453752 -214.472111) (xy 250.426271 -214.418496) (xy 250.407561 -214.361228) (xy 250.398088 -214.30173)
			(xy 250.397518 -214.271606) (xy 250.397961 -214.244352) (xy 250.405718 -214.190399) (xy 250.421074 -214.138099)
			(xy 250.443718 -214.088517) (xy 250.473188 -214.042663) (xy 250.508884 -214.00147) (xy 250.550079 -213.965776)
			(xy 250.595935 -213.936309) (xy 250.645518 -213.913667) (xy 250.697819 -213.898314) (xy 250.751772 -213.89056)
			(xy 250.779026 -213.890098) (xy 250.8058 -213.8906) (xy 250.85882 -213.898097) (xy 250.91027 -213.912938)
			(xy 250.959136 -213.934833) (xy 251.004459 -213.96335) (xy 251.045345 -213.997928) (xy 251.063506 -214.017606)
			(xy 251.069856 -214.024464) (xy 251.07773 -214.028528) (xy 251.078492 -214.029036) (xy 251.082527 -214.030952)
			(xy 251.091085 -214.033505) (xy 251.09551 -214.034116) (xy 251.16155 -214.042498) (xy 251.17171 -214.042752)
			(xy 251.179584 -214.041482) (xy 251.18822 -214.03945) (xy 251.196094 -214.034116) (xy 251.21984 -214.018757)
			(xy 251.270902 -213.994453) (xy 251.324992 -213.977948) (xy 251.380924 -213.969604) (xy 251.4092 -213.969092)
			(xy 251.436451 -213.969578) (xy 251.490399 -213.977334) (xy 251.542694 -213.992689) (xy 251.592271 -214.015331)
			(xy 251.638121 -214.044797) (xy 251.679312 -214.080488) (xy 251.715003 -214.121679) (xy 251.744469 -214.167529)
			(xy 251.767111 -214.217106) (xy 251.782466 -214.269401) (xy 251.790222 -214.323349) (xy 251.790708 -214.3506)
			(xy 251.790147 -214.380832) (xy 251.780597 -214.440538) (xy 251.761752 -214.49799) (xy 251.734083 -214.551753)
			(xy 251.698283 -214.60048) (xy 251.67717 -214.622126) (xy 251.670312 -214.628984) (xy 251.666502 -214.637366)
			(xy 251.662692 -214.650574) (xy 251.662184 -214.656162) (xy 251.659644 -214.725758) (xy 251.659534 -214.730605)
			(xy 251.660946 -214.740195) (xy 251.662438 -214.744808) (xy 251.665486 -214.753444) (xy 251.671836 -214.76081)
			(xy 251.68939 -214.781722) (xy 251.718946 -214.827629) (xy 251.741657 -214.877279) (xy 251.757061 -214.92966)
			(xy 251.764842 -214.983701) (xy 251.765308 -215.011) (xy 251.764822 -215.038251) (xy 251.757066 -215.092199)
			(xy 251.741711 -215.144494) (xy 251.719069 -215.194071) (xy 251.689603 -215.239921) (xy 251.653912 -215.281112)
			(xy 251.612721 -215.316803) (xy 251.566871 -215.346269) (xy 251.517294 -215.368911) (xy 251.464999 -215.384266)
			(xy 251.411051 -215.392022) (xy 251.3838 -215.392508) (xy 251.357907 -215.392084) (xy 251.306595 -215.385086)
			(xy 251.256705 -215.371203) (xy 251.209153 -215.350692) (xy 251.164817 -215.323932) (xy 251.124513 -215.291414)
			(xy 251.106432 -215.272874) (xy 251.099327 -215.266075) (xy 251.081431 -215.25797) (xy 251.071634 -215.257126)
			(xy 251.018294 -215.25484) (xy 251.017532 -215.255602) (xy 251.010703 -215.263011) (xy 251.002976 -215.281603)
			(xy 251.002546 -215.29167) (xy 251.002292 -215.323674) (xy 251.002736 -215.333772) (xy 251.010611 -215.352373)
			(xy 251.017532 -215.359742) (xy 251.038497 -215.381381) (xy 251.07407 -215.430005) (xy 251.101554 -215.483617)
			(xy 251.120266 -215.540885) (xy 251.129739 -215.600383) (xy 251.130308 -215.630506) (xy 251.130308 -215.63076)
			(xy 251.129822 -215.658011) (xy 251.122066 -215.711959) (xy 251.106711 -215.764254) (xy 251.084069 -215.813831)
			(xy 251.054603 -215.859681) (xy 251.018912 -215.900872) (xy 250.995294 -215.921336) (xy 253.91948 -215.921336)
			(xy 253.923551 -215.865714) (xy 253.935677 -215.811277) (xy 253.9556 -215.759186) (xy 253.982896 -215.710551)
			(xy 254.016982 -215.666408) (xy 254.057131 -215.627699) (xy 254.102489 -215.595248) (xy 254.152089 -215.569747)
			(xy 254.204873 -215.55174) (xy 254.259716 -215.54161) (xy 254.31545 -215.539573) (xy 254.370887 -215.545673)
			(xy 254.424844 -215.559779) (xy 254.455599 -215.572848) (xy 259.008116 -215.572848) (xy 259.012187 -215.517226)
			(xy 259.024313 -215.462789) (xy 259.044236 -215.410698) (xy 259.071532 -215.362063) (xy 259.105618 -215.31792)
			(xy 259.145767 -215.279211) (xy 259.191125 -215.24676) (xy 259.240725 -215.221259) (xy 259.293509 -215.203252)
			(xy 259.348352 -215.193122) (xy 259.404086 -215.191085) (xy 259.459523 -215.197185) (xy 259.51348 -215.211291)
			(xy 259.564809 -215.233103) (xy 259.612415 -215.262157) (xy 259.655283 -215.297832) (xy 259.6925 -215.339369)
			(xy 259.723273 -215.385882) (xy 259.746945 -215.436379) (xy 259.763013 -215.489786) (xy 259.771133 -215.544962)
			(xy 259.771642 -215.572848) (xy 259.771133 -215.600734) (xy 259.763013 -215.65591) (xy 259.746945 -215.709317)
			(xy 259.723273 -215.759814) (xy 259.6925 -215.806327) (xy 259.655283 -215.847864) (xy 259.612415 -215.883539)
			(xy 259.564809 -215.912593) (xy 259.51348 -215.934405) (xy 259.459523 -215.948511) (xy 259.404086 -215.954611)
			(xy 259.348352 -215.952574) (xy 259.293509 -215.942444) (xy 259.240725 -215.924437) (xy 259.191125 -215.898936)
			(xy 259.145767 -215.866485) (xy 259.105618 -215.827776) (xy 259.071532 -215.783633) (xy 259.044236 -215.734998)
			(xy 259.024313 -215.682907) (xy 259.012187 -215.62847) (xy 259.008116 -215.572848) (xy 254.455599 -215.572848)
			(xy 254.476173 -215.581591) (xy 254.523779 -215.610645) (xy 254.566647 -215.64632) (xy 254.603864 -215.687857)
			(xy 254.634637 -215.73437) (xy 254.658309 -215.784867) (xy 254.674377 -215.838274) (xy 254.682497 -215.89345)
			(xy 254.683006 -215.921336) (xy 254.682497 -215.949222) (xy 254.674377 -216.004398) (xy 254.658309 -216.057805)
			(xy 254.634637 -216.108302) (xy 254.603864 -216.154815) (xy 254.566647 -216.196352) (xy 254.524143 -216.231724)
			(xy 257.153154 -216.231724) (xy 257.157225 -216.176102) (xy 257.169351 -216.121665) (xy 257.189274 -216.069574)
			(xy 257.21657 -216.020939) (xy 257.250656 -215.976796) (xy 257.290805 -215.938087) (xy 257.336163 -215.905636)
			(xy 257.385763 -215.880135) (xy 257.438547 -215.862128) (xy 257.49339 -215.851998) (xy 257.549124 -215.849961)
			(xy 257.604561 -215.856061) (xy 257.658518 -215.870167) (xy 257.709847 -215.891979) (xy 257.757453 -215.921033)
			(xy 257.800321 -215.956708) (xy 257.837538 -215.998245) (xy 257.868311 -216.044758) (xy 257.891983 -216.095255)
			(xy 257.908051 -216.148662) (xy 257.916171 -216.203838) (xy 257.91668 -216.231724) (xy 257.916171 -216.25961)
			(xy 257.908051 -216.314786) (xy 257.891983 -216.368193) (xy 257.868311 -216.41869) (xy 257.837538 -216.465203)
			(xy 257.800321 -216.50674) (xy 257.757453 -216.542415) (xy 257.709847 -216.571469) (xy 257.658518 -216.593281)
			(xy 257.604561 -216.607387) (xy 257.549124 -216.613487) (xy 257.49339 -216.61145) (xy 257.438547 -216.60132)
			(xy 257.385763 -216.583313) (xy 257.336163 -216.557812) (xy 257.290805 -216.525361) (xy 257.250656 -216.486652)
			(xy 257.21657 -216.442509) (xy 257.189274 -216.393874) (xy 257.169351 -216.341783) (xy 257.157225 -216.287346)
			(xy 257.153154 -216.231724) (xy 254.524143 -216.231724) (xy 254.523779 -216.232027) (xy 254.476173 -216.261081)
			(xy 254.424844 -216.282893) (xy 254.370887 -216.296999) (xy 254.31545 -216.303099) (xy 254.259716 -216.301062)
			(xy 254.204873 -216.290932) (xy 254.152089 -216.272925) (xy 254.102489 -216.247424) (xy 254.057131 -216.214973)
			(xy 254.016982 -216.176264) (xy 253.982896 -216.132121) (xy 253.9556 -216.083486) (xy 253.935677 -216.031395)
			(xy 253.923551 -215.976958) (xy 253.91948 -215.921336) (xy 250.995294 -215.921336) (xy 250.977721 -215.936563)
			(xy 250.931871 -215.966029) (xy 250.882294 -215.988671) (xy 250.829999 -216.004026) (xy 250.776051 -216.011782)
			(xy 250.721549 -216.011782) (xy 250.667601 -216.004026) (xy 250.615306 -215.988671) (xy 250.565729 -215.966029)
			(xy 250.519879 -215.936563) (xy 250.478688 -215.900872) (xy 250.442997 -215.859681) (xy 250.413531 -215.813831)
			(xy 250.390889 -215.764254) (xy 250.375534 -215.711959) (xy 250.367778 -215.658011) (xy 250.367292 -215.63076)
			(xy 247.885254 -215.63076) (xy 247.886474 -215.643206) (xy 247.888506 -215.68156) (xy 247.888007 -215.708812)
			(xy 247.880256 -215.762762) (xy 247.864905 -215.815059) (xy 247.842267 -215.864639) (xy 247.812803 -215.910493)
			(xy 247.777113 -215.951686) (xy 247.735923 -215.98738) (xy 247.690073 -216.016849) (xy 247.640495 -216.039492)
			(xy 247.588199 -216.054848) (xy 247.53425 -216.062605) (xy 247.506998 -216.063068) (xy 247.480807 -216.062611)
			(xy 247.428924 -216.055398) (xy 247.378513 -216.041164) (xy 247.354344 -216.031064) (xy 247.352312 -216.030302)
			(xy 247.346329 -216.02819) (xy 247.333737 -216.026653) (xy 247.32742 -216.027254) (xy 247.327166 -216.027508)
			(xy 247.320393 -216.02865) (xy 247.307772 -216.034059) (xy 247.302274 -216.038176) (xy 247.232424 -216.093802)
			(xy 247.227928 -216.097533) (xy 247.220613 -216.106638) (xy 247.217946 -216.111836) (xy 247.216168 -216.116154)
			(xy 247.213628 -216.122758) (xy 247.212612 -216.136728) (xy 247.213882 -216.143332) (xy 247.217079 -216.161131)
			(xy 247.220514 -216.197132) (xy 247.22074 -216.215214) (xy 247.22074 -216.215468) (xy 247.220246 -216.242642)
			(xy 247.21255 -216.296443) (xy 247.197295 -216.348606) (xy 247.17479 -216.398076) (xy 247.161447 -216.418922)
			(xy 251.19406 -216.418922) (xy 251.198131 -216.3633) (xy 251.210257 -216.308863) (xy 251.23018 -216.256772)
			(xy 251.257476 -216.208137) (xy 251.291562 -216.163994) (xy 251.331711 -216.125285) (xy 251.377069 -216.092834)
			(xy 251.426669 -216.067333) (xy 251.479453 -216.049326) (xy 251.534296 -216.039196) (xy 251.59003 -216.037159)
			(xy 251.645467 -216.043259) (xy 251.699424 -216.057365) (xy 251.750753 -216.079177) (xy 251.798359 -216.108231)
			(xy 251.841227 -216.143906) (xy 251.878444 -216.185443) (xy 251.909217 -216.231956) (xy 251.932889 -216.282453)
			(xy 251.948957 -216.33586) (xy 251.957077 -216.391036) (xy 251.957586 -216.418922) (xy 251.957077 -216.446808)
			(xy 251.948957 -216.501984) (xy 251.932889 -216.555391) (xy 251.909217 -216.605888) (xy 251.878444 -216.652401)
			(xy 251.841227 -216.693938) (xy 251.798359 -216.729613) (xy 251.750753 -216.758667) (xy 251.699424 -216.780479)
			(xy 251.645467 -216.794585) (xy 251.59003 -216.800685) (xy 251.534296 -216.798648) (xy 251.479453 -216.788518)
			(xy 251.426669 -216.770511) (xy 251.377069 -216.74501) (xy 251.331711 -216.712559) (xy 251.291562 -216.67385)
			(xy 251.257476 -216.629707) (xy 251.23018 -216.581072) (xy 251.210257 -216.528981) (xy 251.198131 -216.474544)
			(xy 251.19406 -216.418922) (xy 247.161447 -216.418922) (xy 247.145491 -216.44385) (xy 247.109991 -216.485002)
			(xy 247.069009 -216.520698) (xy 247.023375 -216.550215) (xy 246.974013 -216.572956) (xy 246.921923 -216.58846)
			(xy 246.895112 -216.592912) (xy 246.883682 -216.59469) (xy 246.874538 -216.600786) (xy 246.869882 -216.604027)
			(xy 246.862057 -216.612236) (xy 246.859044 -216.617042) (xy 246.818658 -216.684606) (xy 246.81611 -216.689095)
			(xy 246.812655 -216.69882) (xy 246.8118 -216.70391) (xy 246.811546 -216.706196) (xy 246.81053 -216.717118)
			(xy 246.814594 -216.72804) (xy 246.825216 -216.759435) (xy 246.836719 -216.824699) (xy 246.837454 -216.857834)
			(xy 246.837454 -216.858342) (xy 246.836968 -216.885593) (xy 246.829212 -216.939541) (xy 246.813857 -216.991836)
			(xy 246.791215 -217.041413) (xy 246.761749 -217.087263) (xy 246.737818 -217.114882) (xy 247.502932 -217.114882)
			(xy 247.507003 -217.05926) (xy 247.519129 -217.004823) (xy 247.539052 -216.952732) (xy 247.566348 -216.904097)
			(xy 247.600434 -216.859954) (xy 247.640583 -216.821245) (xy 247.685941 -216.788794) (xy 247.735541 -216.763293)
			(xy 247.788325 -216.745286) (xy 247.843168 -216.735156) (xy 247.898902 -216.733119) (xy 247.954339 -216.739219)
			(xy 248.008296 -216.753325) (xy 248.059625 -216.775137) (xy 248.107231 -216.804191) (xy 248.150099 -216.839866)
			(xy 248.187316 -216.881403) (xy 248.218089 -216.927916) (xy 248.241761 -216.978413) (xy 248.257829 -217.03182)
			(xy 248.265949 -217.086996) (xy 248.266458 -217.114882) (xy 248.265949 -217.142768) (xy 248.257829 -217.197944)
			(xy 248.241761 -217.251351) (xy 248.218089 -217.301848) (xy 248.187316 -217.348361) (xy 248.150099 -217.389898)
			(xy 248.107231 -217.425573) (xy 248.059625 -217.454627) (xy 248.008296 -217.476439) (xy 247.954339 -217.490545)
			(xy 247.898902 -217.496645) (xy 247.843168 -217.494608) (xy 247.788325 -217.484478) (xy 247.735541 -217.466471)
			(xy 247.685941 -217.44097) (xy 247.640583 -217.408519) (xy 247.600434 -217.36981) (xy 247.566348 -217.325667)
			(xy 247.539052 -217.277032) (xy 247.519129 -217.224941) (xy 247.507003 -217.170504) (xy 247.502932 -217.114882)
			(xy 246.737818 -217.114882) (xy 246.726058 -217.128454) (xy 246.684867 -217.164145) (xy 246.639017 -217.193611)
			(xy 246.58944 -217.216253) (xy 246.537145 -217.231608) (xy 246.483197 -217.239364) (xy 246.428695 -217.239364)
			(xy 246.374747 -217.231608) (xy 246.322452 -217.216253) (xy 246.272875 -217.193611) (xy 246.227025 -217.164145)
			(xy 246.185834 -217.128454) (xy 246.150143 -217.087263) (xy 246.120677 -217.041413) (xy 246.098035 -216.991836)
			(xy 246.08268 -216.939541) (xy 246.074924 -216.885593) (xy 246.074438 -216.858342) (xy 240.965648 -216.858342)
			(xy 240.989839 -216.878474) (xy 241.027056 -216.920011) (xy 241.057829 -216.966524) (xy 241.081501 -217.017021)
			(xy 241.097569 -217.070428) (xy 241.105689 -217.125604) (xy 241.106198 -217.15349) (xy 241.105689 -217.181376)
			(xy 241.097569 -217.236552) (xy 241.081501 -217.289959) (xy 241.057829 -217.340456) (xy 241.027056 -217.386969)
			(xy 240.989839 -217.428506) (xy 240.946971 -217.464181) (xy 240.899365 -217.493235) (xy 240.848036 -217.515047)
			(xy 240.794079 -217.529153) (xy 240.738642 -217.535253) (xy 240.682908 -217.533216) (xy 240.628065 -217.523086)
			(xy 240.575281 -217.505079) (xy 240.525681 -217.479578) (xy 240.480323 -217.447127) (xy 240.440174 -217.408418)
			(xy 240.406088 -217.364275) (xy 240.378792 -217.31564) (xy 240.358869 -217.263549) (xy 240.346743 -217.209112)
			(xy 240.342672 -217.15349) (xy 234.594052 -217.15349) (xy 234.58957 -217.18179) (xy 234.573509 -217.23122)
			(xy 234.549913 -217.27753) (xy 234.519363 -217.319578) (xy 234.482612 -217.356329) (xy 234.440564 -217.386879)
			(xy 234.394254 -217.410475) (xy 234.344824 -217.426536) (xy 234.293489 -217.434666) (xy 234.241515 -217.434666)
			(xy 234.19018 -217.426536) (xy 234.14075 -217.410475) (xy 234.09444 -217.386879) (xy 234.052392 -217.356329)
			(xy 234.015641 -217.319578) (xy 233.985091 -217.27753) (xy 233.961495 -217.23122) (xy 233.945434 -217.18179)
			(xy 233.937304 -217.130455) (xy 232.997754 -217.130455) (xy 232.989624 -217.18179) (xy 232.973563 -217.23122)
			(xy 232.949967 -217.27753) (xy 232.919417 -217.319578) (xy 232.882666 -217.356329) (xy 232.840618 -217.386879)
			(xy 232.794308 -217.410475) (xy 232.744878 -217.426536) (xy 232.693543 -217.434666) (xy 232.641569 -217.434666)
			(xy 232.590234 -217.426536) (xy 232.540804 -217.410475) (xy 232.494494 -217.386879) (xy 232.452446 -217.356329)
			(xy 232.415695 -217.319578) (xy 232.385145 -217.27753) (xy 232.361549 -217.23122) (xy 232.345488 -217.18179)
			(xy 232.337358 -217.130455) (xy 232.197654 -217.130455) (xy 232.189524 -217.18179) (xy 232.173463 -217.23122)
			(xy 232.149867 -217.27753) (xy 232.119317 -217.319578) (xy 232.082566 -217.356329) (xy 232.040518 -217.386879)
			(xy 231.994208 -217.410475) (xy 231.944778 -217.426536) (xy 231.893443 -217.434666) (xy 231.841469 -217.434666)
			(xy 231.790134 -217.426536) (xy 231.740704 -217.410475) (xy 231.694394 -217.386879) (xy 231.652346 -217.356329)
			(xy 231.615595 -217.319578) (xy 231.585045 -217.27753) (xy 231.561449 -217.23122) (xy 231.545388 -217.18179)
			(xy 231.537258 -217.130455) (xy 231.397554 -217.130455) (xy 231.389424 -217.18179) (xy 231.373363 -217.23122)
			(xy 231.349767 -217.27753) (xy 231.319217 -217.319578) (xy 231.282466 -217.356329) (xy 231.240418 -217.386879)
			(xy 231.194108 -217.410475) (xy 231.144678 -217.426536) (xy 231.093343 -217.434666) (xy 231.041369 -217.434666)
			(xy 230.990034 -217.426536) (xy 230.940604 -217.410475) (xy 230.894294 -217.386879) (xy 230.852246 -217.356329)
			(xy 230.815495 -217.319578) (xy 230.784945 -217.27753) (xy 230.761349 -217.23122) (xy 230.745288 -217.18179)
			(xy 230.737158 -217.130455) (xy 230.597708 -217.130455) (xy 230.589578 -217.18179) (xy 230.573517 -217.23122)
			(xy 230.549921 -217.27753) (xy 230.519371 -217.319578) (xy 230.48262 -217.356329) (xy 230.440572 -217.386879)
			(xy 230.394262 -217.410475) (xy 230.344832 -217.426536) (xy 230.293497 -217.434666) (xy 230.241523 -217.434666)
			(xy 230.190188 -217.426536) (xy 230.140758 -217.410475) (xy 230.094448 -217.386879) (xy 230.0524 -217.356329)
			(xy 230.015649 -217.319578) (xy 229.985099 -217.27753) (xy 229.961503 -217.23122) (xy 229.945442 -217.18179)
			(xy 229.937312 -217.130455) (xy 228.998016 -217.130455) (xy 228.989886 -217.18179) (xy 228.973825 -217.23122)
			(xy 228.950229 -217.27753) (xy 228.919679 -217.319578) (xy 228.882928 -217.356329) (xy 228.84088 -217.386879)
			(xy 228.79457 -217.410475) (xy 228.74514 -217.426536) (xy 228.693805 -217.434666) (xy 228.641831 -217.434666)
			(xy 228.590496 -217.426536) (xy 228.541066 -217.410475) (xy 228.494756 -217.386879) (xy 228.452708 -217.356329)
			(xy 228.415957 -217.319578) (xy 228.385407 -217.27753) (xy 228.361811 -217.23122) (xy 228.34575 -217.18179)
			(xy 228.33762 -217.130455) (xy 228.19817 -217.130455) (xy 228.19004 -217.18179) (xy 228.173979 -217.23122)
			(xy 228.150383 -217.27753) (xy 228.119833 -217.319578) (xy 228.083082 -217.356329) (xy 228.041034 -217.386879)
			(xy 227.994724 -217.410475) (xy 227.945294 -217.426536) (xy 227.893959 -217.434666) (xy 227.841985 -217.434666)
			(xy 227.79065 -217.426536) (xy 227.74122 -217.410475) (xy 227.69491 -217.386879) (xy 227.652862 -217.356329)
			(xy 227.616111 -217.319578) (xy 227.585561 -217.27753) (xy 227.561965 -217.23122) (xy 227.545904 -217.18179)
			(xy 227.537774 -217.130455) (xy 227.39807 -217.130455) (xy 227.38994 -217.18179) (xy 227.373879 -217.23122)
			(xy 227.350283 -217.27753) (xy 227.319733 -217.319578) (xy 227.282982 -217.356329) (xy 227.240934 -217.386879)
			(xy 227.194624 -217.410475) (xy 227.145194 -217.426536) (xy 227.093859 -217.434666) (xy 227.041885 -217.434666)
			(xy 226.99055 -217.426536) (xy 226.94112 -217.410475) (xy 226.89481 -217.386879) (xy 226.852762 -217.356329)
			(xy 226.816011 -217.319578) (xy 226.785461 -217.27753) (xy 226.761865 -217.23122) (xy 226.745804 -217.18179)
			(xy 226.737674 -217.130455) (xy 224.998024 -217.130455) (xy 224.989894 -217.18179) (xy 224.973833 -217.23122)
			(xy 224.950237 -217.27753) (xy 224.919687 -217.319578) (xy 224.882936 -217.356329) (xy 224.840888 -217.386879)
			(xy 224.794578 -217.410475) (xy 224.745148 -217.426536) (xy 224.693813 -217.434666) (xy 224.641839 -217.434666)
			(xy 224.590504 -217.426536) (xy 224.541074 -217.410475) (xy 224.494764 -217.386879) (xy 224.452716 -217.356329)
			(xy 224.415965 -217.319578) (xy 224.385415 -217.27753) (xy 224.361819 -217.23122) (xy 224.345758 -217.18179)
			(xy 224.337628 -217.130455) (xy 216.5652 -217.130455) (xy 216.567773 -217.139008) (xy 216.575893 -217.194184)
			(xy 216.576402 -217.22207) (xy 216.575893 -217.249956) (xy 216.567773 -217.305132) (xy 216.551705 -217.358539)
			(xy 216.528033 -217.409036) (xy 216.49726 -217.455549) (xy 216.460043 -217.497086) (xy 216.417175 -217.532761)
			(xy 216.369569 -217.561815) (xy 216.31824 -217.583627) (xy 216.264283 -217.597733) (xy 216.208846 -217.603833)
			(xy 216.153112 -217.601796) (xy 216.098269 -217.591666) (xy 216.045485 -217.573659) (xy 215.995885 -217.548158)
			(xy 215.950527 -217.515707) (xy 215.910378 -217.476998) (xy 215.876292 -217.432855) (xy 215.848996 -217.38422)
			(xy 215.829073 -217.332129) (xy 215.816947 -217.277692) (xy 215.812876 -217.22207) (xy 215.344952 -217.22207)
			(xy 215.350343 -217.2587) (xy 215.350852 -217.286586) (xy 215.350343 -217.314472) (xy 215.342223 -217.369648)
			(xy 215.326155 -217.423055) (xy 215.302483 -217.473552) (xy 215.27171 -217.520065) (xy 215.234493 -217.561602)
			(xy 215.191625 -217.597277) (xy 215.144019 -217.626331) (xy 215.09269 -217.648143) (xy 215.038733 -217.662249)
			(xy 214.983296 -217.668349) (xy 214.927562 -217.666312) (xy 214.872719 -217.656182) (xy 214.819935 -217.638175)
			(xy 214.770335 -217.612674) (xy 214.724977 -217.580223) (xy 214.684828 -217.541514) (xy 214.650742 -217.497371)
			(xy 214.623446 -217.448736) (xy 214.603523 -217.396645) (xy 214.591397 -217.342208) (xy 214.587326 -217.286586)
			(xy 213.02599 -217.286586) (xy 213.025481 -217.314472) (xy 213.017361 -217.369648) (xy 213.001293 -217.423055)
			(xy 212.977621 -217.473552) (xy 212.946848 -217.520065) (xy 212.909631 -217.561602) (xy 212.866763 -217.597277)
			(xy 212.819157 -217.626331) (xy 212.767828 -217.648143) (xy 212.713871 -217.662249) (xy 212.658434 -217.668349)
			(xy 212.6027 -217.666312) (xy 212.547857 -217.656182) (xy 212.495073 -217.638175) (xy 212.445473 -217.612674)
			(xy 212.400115 -217.580223) (xy 212.359966 -217.541514) (xy 212.32588 -217.497371) (xy 212.298584 -217.448736)
			(xy 212.278661 -217.396645) (xy 212.266535 -217.342208) (xy 212.262464 -217.286586) (xy 212.046092 -217.286586)
			(xy 212.046566 -217.31224) (xy 212.04608 -217.339491) (xy 212.038324 -217.393439) (xy 212.022969 -217.445734)
			(xy 212.000327 -217.495311) (xy 211.970861 -217.541161) (xy 211.93517 -217.582352) (xy 211.893979 -217.618043)
			(xy 211.848129 -217.647509) (xy 211.798552 -217.670151) (xy 211.746257 -217.685506) (xy 211.692309 -217.693262)
			(xy 211.637807 -217.693262) (xy 211.583859 -217.685506) (xy 211.531564 -217.670151) (xy 211.481987 -217.647509)
			(xy 211.436137 -217.618043) (xy 211.394946 -217.582352) (xy 211.359255 -217.541161) (xy 211.329789 -217.495311)
			(xy 211.307147 -217.445734) (xy 211.291792 -217.393439) (xy 211.284036 -217.339491) (xy 211.28355 -217.31224)
			(xy 211.283611 -217.301677) (xy 211.284756 -217.280583) (xy 211.285836 -217.270076) (xy 211.287106 -217.259916)
			(xy 211.284058 -217.249756) (xy 211.278724 -217.238072) (xy 211.274406 -217.231976) (xy 211.227924 -217.176096)
			(xy 211.224534 -217.172167) (xy 211.216472 -217.165636) (xy 211.211922 -217.163142) (xy 211.203032 -217.15857)
			(xy 211.192618 -217.157808) (xy 211.164549 -217.15516) (xy 211.109592 -217.142569) (xy 211.057086 -217.122031)
			(xy 211.008172 -217.093992) (xy 210.963915 -217.059064) (xy 210.925277 -217.018005) (xy 210.8931 -216.971709)
			(xy 210.868082 -216.921183) (xy 210.850769 -216.867527) (xy 210.845654 -216.8398) (xy 210.843876 -216.82837)
			(xy 210.837272 -216.818972) (xy 210.833903 -216.814465) (xy 210.825575 -216.806901) (xy 210.820762 -216.803986)
			(xy 210.751928 -216.765124) (xy 210.742276 -216.760806) (xy 210.730084 -216.75852) (xy 210.718654 -216.757758)
			(xy 210.707732 -216.762076) (xy 210.685118 -216.770745) (xy 210.638251 -216.782952) (xy 210.590215 -216.789117)
			(xy 210.566 -216.789508) (xy 210.538749 -216.789022) (xy 210.484801 -216.781266) (xy 210.432506 -216.765911)
			(xy 210.382929 -216.743269) (xy 210.337079 -216.713803) (xy 210.295888 -216.678112) (xy 210.260197 -216.636921)
			(xy 210.230731 -216.591071) (xy 210.208089 -216.541494) (xy 210.192734 -216.489199) (xy 210.184978 -216.435251)
			(xy 209.382715 -216.435251) (xy 209.393543 -216.471242) (xy 209.401663 -216.526418) (xy 209.402172 -216.554304)
			(xy 209.401663 -216.58219) (xy 209.393543 -216.637366) (xy 209.377475 -216.690773) (xy 209.353803 -216.74127)
			(xy 209.32303 -216.787783) (xy 209.285813 -216.82932) (xy 209.242945 -216.864995) (xy 209.195339 -216.894049)
			(xy 209.14401 -216.915861) (xy 209.090053 -216.929967) (xy 209.034616 -216.936067) (xy 208.978882 -216.93403)
			(xy 208.924039 -216.9239) (xy 208.871255 -216.905893) (xy 208.821655 -216.880392) (xy 208.776297 -216.847941)
			(xy 208.736148 -216.809232) (xy 208.702062 -216.765089) (xy 208.674766 -216.716454) (xy 208.654843 -216.664363)
			(xy 208.642717 -216.609926) (xy 208.638646 -216.554304) (xy 206.924958 -216.554304) (xy 206.929227 -216.583314)
			(xy 206.929736 -216.6112) (xy 206.929227 -216.639086) (xy 206.921107 -216.694262) (xy 206.905039 -216.747669)
			(xy 206.881367 -216.798166) (xy 206.850594 -216.844679) (xy 206.813377 -216.886216) (xy 206.770509 -216.921891)
			(xy 206.722903 -216.950945) (xy 206.671574 -216.972757) (xy 206.617617 -216.986863) (xy 206.56218 -216.992963)
			(xy 206.506446 -216.990926) (xy 206.451603 -216.980796) (xy 206.398819 -216.962789) (xy 206.349219 -216.937288)
			(xy 206.303861 -216.904837) (xy 206.263712 -216.866128) (xy 206.229626 -216.821985) (xy 206.20233 -216.77335)
			(xy 206.182407 -216.721259) (xy 206.170281 -216.666822) (xy 206.16621 -216.6112) (xy 196.968618 -216.6112)
			(xy 196.968618 -217.920824) (xy 208.797142 -217.920824) (xy 208.801213 -217.865202) (xy 208.813339 -217.810765)
			(xy 208.833262 -217.758674) (xy 208.860558 -217.710039) (xy 208.894644 -217.665896) (xy 208.934793 -217.627187)
			(xy 208.980151 -217.594736) (xy 209.029751 -217.569235) (xy 209.082535 -217.551228) (xy 209.137378 -217.541098)
			(xy 209.193112 -217.539061) (xy 209.248549 -217.545161) (xy 209.302506 -217.559267) (xy 209.353835 -217.581079)
			(xy 209.401441 -217.610133) (xy 209.444309 -217.645808) (xy 209.481526 -217.687345) (xy 209.512299 -217.733858)
			(xy 209.535971 -217.784355) (xy 209.552039 -217.837762) (xy 209.560159 -217.892938) (xy 209.560668 -217.920824)
			(xy 209.560159 -217.94871) (xy 209.552039 -218.003886) (xy 209.535971 -218.057293) (xy 209.512299 -218.10779)
			(xy 209.481526 -218.154303) (xy 209.444309 -218.19584) (xy 209.401441 -218.231515) (xy 209.353835 -218.260569)
			(xy 209.302506 -218.282381) (xy 209.27477 -218.289632) (xy 212.858602 -218.289632) (xy 212.862673 -218.23401)
			(xy 212.874799 -218.179573) (xy 212.894722 -218.127482) (xy 212.922018 -218.078847) (xy 212.956104 -218.034704)
			(xy 212.996253 -217.995995) (xy 213.041611 -217.963544) (xy 213.091211 -217.938043) (xy 213.143995 -217.920036)
			(xy 213.198838 -217.909906) (xy 213.254572 -217.907869) (xy 213.310009 -217.913969) (xy 213.363966 -217.928075)
			(xy 213.415295 -217.949887) (xy 213.462901 -217.978941) (xy 213.505769 -218.014616) (xy 213.542986 -218.056153)
			(xy 213.573759 -218.102666) (xy 213.597431 -218.153163) (xy 213.613499 -218.20657) (xy 213.621619 -218.261746)
			(xy 213.622128 -218.289632) (xy 213.622058 -218.293442) (xy 213.885778 -218.293442) (xy 213.889849 -218.23782)
			(xy 213.901975 -218.183383) (xy 213.921898 -218.131292) (xy 213.949194 -218.082657) (xy 213.98328 -218.038514)
			(xy 214.023429 -217.999805) (xy 214.068787 -217.967354) (xy 214.118387 -217.941853) (xy 214.171171 -217.923846)
			(xy 214.226014 -217.913716) (xy 214.281748 -217.911679) (xy 214.337185 -217.917779) (xy 214.391142 -217.931885)
			(xy 214.442471 -217.953697) (xy 214.490077 -217.982751) (xy 214.532945 -218.018426) (xy 214.570162 -218.059963)
			(xy 214.600935 -218.106476) (xy 214.624607 -218.156973) (xy 214.640675 -218.21038) (xy 214.648795 -218.265556)
			(xy 214.649304 -218.293442) (xy 214.649137 -218.302586) (xy 214.791034 -218.302586) (xy 214.795105 -218.246964)
			(xy 214.807231 -218.192527) (xy 214.827154 -218.140436) (xy 214.85445 -218.091801) (xy 214.888536 -218.047658)
			(xy 214.928685 -218.008949) (xy 214.974043 -217.976498) (xy 215.023643 -217.950997) (xy 215.076427 -217.93299)
			(xy 215.13127 -217.92286) (xy 215.187004 -217.920823) (xy 215.242441 -217.926923) (xy 215.296398 -217.941029)
			(xy 215.347727 -217.962841) (xy 215.395333 -217.991895) (xy 215.438201 -218.02757) (xy 215.475418 -218.069107)
			(xy 215.506191 -218.11562) (xy 215.529863 -218.166117) (xy 215.545931 -218.219524) (xy 215.554051 -218.2747)
			(xy 215.55456 -218.302586) (xy 215.554062 -218.329852) (xy 217.922064 -218.329852) (xy 217.922064 -218.275348)
			(xy 217.92982 -218.221399) (xy 217.945176 -218.169103) (xy 217.967817 -218.119524) (xy 217.997284 -218.073672)
			(xy 218.032976 -218.032481) (xy 218.074167 -217.996788) (xy 218.120019 -217.96732) (xy 218.169597 -217.944678)
			(xy 218.221893 -217.929322) (xy 218.275842 -217.921564) (xy 218.303094 -217.921078) (xy 218.332857 -217.921643)
			(xy 218.391659 -217.9309) (xy 218.44831 -217.949174) (xy 218.501438 -217.976023) (xy 218.549752 -218.010794)
			(xy 218.571318 -218.031314) (xy 218.57843 -218.038172) (xy 218.587066 -218.041982) (xy 218.591756 -218.043772)
			(xy 218.601605 -218.045697) (xy 218.606624 -218.045792) (xy 218.676982 -218.046554) (xy 218.680652 -218.046513)
			(xy 218.687919 -218.045489) (xy 218.69146 -218.044522) (xy 218.696794 -218.042744) (xy 218.705684 -218.039188)
			(xy 218.71305 -218.03233) (xy 218.734501 -218.012565) (xy 218.782254 -217.979078) (xy 218.834544 -217.953241)
			(xy 218.890156 -217.935658) (xy 218.947794 -217.926736) (xy 218.976956 -217.926158) (xy 219.004208 -217.926686)
			(xy 219.02937 -217.930301) (xy 224.337628 -217.930301) (xy 224.337628 -217.878327) (xy 224.345758 -217.826992)
			(xy 224.361819 -217.777562) (xy 224.385415 -217.731252) (xy 224.415965 -217.689204) (xy 224.452716 -217.652453)
			(xy 224.494764 -217.621903) (xy 224.541074 -217.598307) (xy 224.590504 -217.582246) (xy 224.641839 -217.574116)
			(xy 224.693813 -217.574116) (xy 224.745148 -217.582246) (xy 224.794578 -217.598307) (xy 224.840888 -217.621903)
			(xy 224.882936 -217.652453) (xy 224.919687 -217.689204) (xy 224.950237 -217.731252) (xy 224.973833 -217.777562)
			(xy 224.989894 -217.826992) (xy 224.998024 -217.878327) (xy 224.998534 -217.904314) (xy 224.998024 -217.930301)
			(xy 225.137728 -217.930301) (xy 225.137728 -217.878327) (xy 225.145858 -217.826992) (xy 225.161919 -217.777562)
			(xy 225.185515 -217.731252) (xy 225.216065 -217.689204) (xy 225.252816 -217.652453) (xy 225.294864 -217.621903)
			(xy 225.341174 -217.598307) (xy 225.390604 -217.582246) (xy 225.441939 -217.574116) (xy 225.493913 -217.574116)
			(xy 225.545248 -217.582246) (xy 225.594678 -217.598307) (xy 225.640988 -217.621903) (xy 225.683036 -217.652453)
			(xy 225.719787 -217.689204) (xy 225.750337 -217.731252) (xy 225.773933 -217.777562) (xy 225.789994 -217.826992)
			(xy 225.798124 -217.878327) (xy 225.798634 -217.904314) (xy 225.798124 -217.930301) (xy 225.937574 -217.930301)
			(xy 225.937574 -217.878327) (xy 225.945704 -217.826992) (xy 225.961765 -217.777562) (xy 225.985361 -217.731252)
			(xy 226.015911 -217.689204) (xy 226.052662 -217.652453) (xy 226.09471 -217.621903) (xy 226.14102 -217.598307)
			(xy 226.19045 -217.582246) (xy 226.241785 -217.574116) (xy 226.293759 -217.574116) (xy 226.345094 -217.582246)
			(xy 226.394524 -217.598307) (xy 226.440834 -217.621903) (xy 226.482882 -217.652453) (xy 226.519633 -217.689204)
			(xy 226.550183 -217.731252) (xy 226.573779 -217.777562) (xy 226.58984 -217.826992) (xy 226.59797 -217.878327)
			(xy 226.59848 -217.904314) (xy 226.59797 -217.930301) (xy 226.737674 -217.930301) (xy 226.737674 -217.878327)
			(xy 226.745804 -217.826992) (xy 226.761865 -217.777562) (xy 226.785461 -217.731252) (xy 226.816011 -217.689204)
			(xy 226.852762 -217.652453) (xy 226.89481 -217.621903) (xy 226.94112 -217.598307) (xy 226.99055 -217.582246)
			(xy 227.041885 -217.574116) (xy 227.093859 -217.574116) (xy 227.145194 -217.582246) (xy 227.194624 -217.598307)
			(xy 227.240934 -217.621903) (xy 227.282982 -217.652453) (xy 227.319733 -217.689204) (xy 227.350283 -217.731252)
			(xy 227.373879 -217.777562) (xy 227.38994 -217.826992) (xy 227.39807 -217.878327) (xy 227.39858 -217.904314)
			(xy 227.39807 -217.930301) (xy 227.537774 -217.930301) (xy 227.537774 -217.878327) (xy 227.545904 -217.826992)
			(xy 227.561965 -217.777562) (xy 227.585561 -217.731252) (xy 227.616111 -217.689204) (xy 227.652862 -217.652453)
			(xy 227.69491 -217.621903) (xy 227.74122 -217.598307) (xy 227.79065 -217.582246) (xy 227.841985 -217.574116)
			(xy 227.893959 -217.574116) (xy 227.945294 -217.582246) (xy 227.994724 -217.598307) (xy 228.041034 -217.621903)
			(xy 228.083082 -217.652453) (xy 228.119833 -217.689204) (xy 228.150383 -217.731252) (xy 228.173979 -217.777562)
			(xy 228.19004 -217.826992) (xy 228.19817 -217.878327) (xy 228.19868 -217.904314) (xy 228.19817 -217.930301)
			(xy 228.33762 -217.930301) (xy 228.33762 -217.878327) (xy 228.34575 -217.826992) (xy 228.361811 -217.777562)
			(xy 228.385407 -217.731252) (xy 228.415957 -217.689204) (xy 228.452708 -217.652453) (xy 228.494756 -217.621903)
			(xy 228.541066 -217.598307) (xy 228.590496 -217.582246) (xy 228.641831 -217.574116) (xy 228.693805 -217.574116)
			(xy 228.74514 -217.582246) (xy 228.79457 -217.598307) (xy 228.84088 -217.621903) (xy 228.882928 -217.652453)
			(xy 228.919679 -217.689204) (xy 228.950229 -217.731252) (xy 228.973825 -217.777562) (xy 228.989886 -217.826992)
			(xy 228.998016 -217.878327) (xy 228.998526 -217.904314) (xy 228.998016 -217.930301) (xy 229.937312 -217.930301)
			(xy 229.937312 -217.878327) (xy 229.945442 -217.826992) (xy 229.961503 -217.777562) (xy 229.985099 -217.731252)
			(xy 230.015649 -217.689204) (xy 230.0524 -217.652453) (xy 230.094448 -217.621903) (xy 230.140758 -217.598307)
			(xy 230.190188 -217.582246) (xy 230.241523 -217.574116) (xy 230.293497 -217.574116) (xy 230.344832 -217.582246)
			(xy 230.394262 -217.598307) (xy 230.440572 -217.621903) (xy 230.48262 -217.652453) (xy 230.519371 -217.689204)
			(xy 230.549921 -217.731252) (xy 230.573517 -217.777562) (xy 230.589578 -217.826992) (xy 230.597708 -217.878327)
			(xy 230.598218 -217.904314) (xy 230.597708 -217.930301) (xy 230.737158 -217.930301) (xy 230.737158 -217.878327)
			(xy 230.745288 -217.826992) (xy 230.761349 -217.777562) (xy 230.784945 -217.731252) (xy 230.815495 -217.689204)
			(xy 230.852246 -217.652453) (xy 230.894294 -217.621903) (xy 230.940604 -217.598307) (xy 230.990034 -217.582246)
			(xy 231.041369 -217.574116) (xy 231.093343 -217.574116) (xy 231.144678 -217.582246) (xy 231.194108 -217.598307)
			(xy 231.240418 -217.621903) (xy 231.282466 -217.652453) (xy 231.319217 -217.689204) (xy 231.349767 -217.731252)
			(xy 231.373363 -217.777562) (xy 231.389424 -217.826992) (xy 231.397554 -217.878327) (xy 231.398064 -217.904314)
			(xy 231.397554 -217.930301) (xy 231.537258 -217.930301) (xy 231.537258 -217.878327) (xy 231.545388 -217.826992)
			(xy 231.561449 -217.777562) (xy 231.585045 -217.731252) (xy 231.615595 -217.689204) (xy 231.652346 -217.652453)
			(xy 231.694394 -217.621903) (xy 231.740704 -217.598307) (xy 231.790134 -217.582246) (xy 231.841469 -217.574116)
			(xy 231.893443 -217.574116) (xy 231.944778 -217.582246) (xy 231.994208 -217.598307) (xy 232.040518 -217.621903)
			(xy 232.082566 -217.652453) (xy 232.119317 -217.689204) (xy 232.149867 -217.731252) (xy 232.173463 -217.777562)
			(xy 232.189524 -217.826992) (xy 232.197654 -217.878327) (xy 232.198164 -217.904314) (xy 232.197654 -217.930301)
			(xy 232.337358 -217.930301) (xy 232.337358 -217.878327) (xy 232.345488 -217.826992) (xy 232.361549 -217.777562)
			(xy 232.385145 -217.731252) (xy 232.415695 -217.689204) (xy 232.452446 -217.652453) (xy 232.494494 -217.621903)
			(xy 232.540804 -217.598307) (xy 232.590234 -217.582246) (xy 232.641569 -217.574116) (xy 232.693543 -217.574116)
			(xy 232.744878 -217.582246) (xy 232.794308 -217.598307) (xy 232.840618 -217.621903) (xy 232.882666 -217.652453)
			(xy 232.919417 -217.689204) (xy 232.949967 -217.731252) (xy 232.973563 -217.777562) (xy 232.989624 -217.826992)
			(xy 232.997754 -217.878327) (xy 232.998264 -217.904314) (xy 232.997754 -217.930301) (xy 233.937304 -217.930301)
			(xy 233.937304 -217.878327) (xy 233.945434 -217.826992) (xy 233.961495 -217.777562) (xy 233.985091 -217.731252)
			(xy 234.015641 -217.689204) (xy 234.052392 -217.652453) (xy 234.09444 -217.621903) (xy 234.14075 -217.598307)
			(xy 234.19018 -217.582246) (xy 234.241515 -217.574116) (xy 234.293489 -217.574116) (xy 234.344824 -217.582246)
			(xy 234.394254 -217.598307) (xy 234.440564 -217.621903) (xy 234.482612 -217.652453) (xy 234.519363 -217.689204)
			(xy 234.549913 -217.731252) (xy 234.573509 -217.777562) (xy 234.58957 -217.826992) (xy 234.5977 -217.878327)
			(xy 234.59821 -217.904314) (xy 234.5977 -217.930301) (xy 234.73715 -217.930301) (xy 234.73715 -217.878327)
			(xy 234.74528 -217.826992) (xy 234.761341 -217.777562) (xy 234.784937 -217.731252) (xy 234.815487 -217.689204)
			(xy 234.852238 -217.652453) (xy 234.894286 -217.621903) (xy 234.940596 -217.598307) (xy 234.990026 -217.582246)
			(xy 235.041361 -217.574116) (xy 235.093335 -217.574116) (xy 235.14467 -217.582246) (xy 235.1941 -217.598307)
			(xy 235.24041 -217.621903) (xy 235.282458 -217.652453) (xy 235.319209 -217.689204) (xy 235.349759 -217.731252)
			(xy 235.373355 -217.777562) (xy 235.389416 -217.826992) (xy 235.397546 -217.878327) (xy 235.398056 -217.904314)
			(xy 235.397546 -217.930301) (xy 235.389416 -217.981636) (xy 235.373355 -218.031066) (xy 235.349759 -218.077376)
			(xy 235.319209 -218.119424) (xy 235.31072 -218.127913) (xy 235.790996 -218.127913) (xy 235.790996 -218.075939)
			(xy 235.799126 -218.024604) (xy 235.815187 -217.975174) (xy 235.838783 -217.928864) (xy 235.869333 -217.886816)
			(xy 235.906084 -217.850065) (xy 235.948132 -217.819515) (xy 235.994442 -217.795919) (xy 236.043872 -217.779858)
			(xy 236.095207 -217.771728) (xy 236.147181 -217.771728) (xy 236.198516 -217.779858) (xy 236.247946 -217.795919)
			(xy 236.294256 -217.819515) (xy 236.336304 -217.850065) (xy 236.373055 -217.886816) (xy 236.403605 -217.928864)
			(xy 236.427201 -217.975174) (xy 236.44016 -218.015058) (xy 237.476792 -218.015058) (xy 237.477278 -217.987807)
			(xy 237.485034 -217.933859) (xy 237.500389 -217.881564) (xy 237.523031 -217.831987) (xy 237.552497 -217.786137)
			(xy 237.588188 -217.744946) (xy 237.629379 -217.709255) (xy 237.675229 -217.679789) (xy 237.724806 -217.657147)
			(xy 237.777101 -217.641792) (xy 237.831049 -217.634036) (xy 237.885551 -217.634036) (xy 237.939499 -217.641792)
			(xy 237.991794 -217.657147) (xy 238.041371 -217.679789) (xy 238.087221 -217.709255) (xy 238.128412 -217.744946)
			(xy 238.164103 -217.786137) (xy 238.166431 -217.78976) (xy 241.703096 -217.78976) (xy 241.707167 -217.734138)
			(xy 241.719293 -217.679701) (xy 241.739216 -217.62761) (xy 241.766512 -217.578975) (xy 241.800598 -217.534832)
			(xy 241.840747 -217.496123) (xy 241.886105 -217.463672) (xy 241.935705 -217.438171) (xy 241.988489 -217.420164)
			(xy 242.043332 -217.410034) (xy 242.099066 -217.407997) (xy 242.154503 -217.414097) (xy 242.20846 -217.428203)
			(xy 242.259789 -217.450015) (xy 242.307395 -217.479069) (xy 242.332787 -217.5002) (xy 242.924582 -217.5002)
			(xy 242.928653 -217.444578) (xy 242.940779 -217.390141) (xy 242.960702 -217.33805) (xy 242.987998 -217.289415)
			(xy 243.022084 -217.245272) (xy 243.062233 -217.206563) (xy 243.107591 -217.174112) (xy 243.157191 -217.148611)
			(xy 243.209975 -217.130604) (xy 243.264818 -217.120474) (xy 243.320552 -217.118437) (xy 243.375989 -217.124537)
			(xy 243.429946 -217.138643) (xy 243.481275 -217.160455) (xy 243.528881 -217.189509) (xy 243.571749 -217.225184)
			(xy 243.608966 -217.266721) (xy 243.639739 -217.313234) (xy 243.663411 -217.363731) (xy 243.679479 -217.417138)
			(xy 243.687599 -217.472314) (xy 243.688108 -217.5002) (xy 248.970292 -217.5002) (xy 248.970814 -217.472815)
			(xy 248.978659 -217.418609) (xy 248.994174 -217.366083) (xy 249.01704 -217.316314) (xy 249.046787 -217.270326)
			(xy 249.082804 -217.229063) (xy 249.12435 -217.193375) (xy 249.170572 -217.163993) (xy 249.220521 -217.141522)
			(xy 249.273169 -217.126424) (xy 249.300238 -217.122248) (xy 249.314655 -217.11981) (xy 249.341335 -217.107883)
			(xy 249.363537 -217.088879) (xy 249.379438 -217.064359) (xy 249.387732 -217.036336) (xy 249.387739 -217.007111)
			(xy 249.384058 -216.992962) (xy 249.376928 -216.966871) (xy 249.369285 -216.913326) (xy 249.368818 -216.886282)
			(xy 249.369304 -216.859031) (xy 249.37706 -216.805083) (xy 249.392415 -216.752788) (xy 249.415057 -216.703211)
			(xy 249.444523 -216.657361) (xy 249.480214 -216.61617) (xy 249.521405 -216.580479) (xy 249.567255 -216.551013)
			(xy 249.616832 -216.528371) (xy 249.669127 -216.513016) (xy 249.723075 -216.50526) (xy 249.777577 -216.50526)
			(xy 249.831525 -216.513016) (xy 249.88382 -216.528371) (xy 249.933397 -216.551013) (xy 249.979247 -216.580479)
			(xy 250.020438 -216.61617) (xy 250.056129 -216.657361) (xy 250.085595 -216.703211) (xy 250.108237 -216.752788)
			(xy 250.123592 -216.805083) (xy 250.127816 -216.834466) (xy 254.78054 -216.834466) (xy 254.784611 -216.778844)
			(xy 254.796737 -216.724407) (xy 254.81666 -216.672316) (xy 254.843956 -216.623681) (xy 254.878042 -216.579538)
			(xy 254.918191 -216.540829) (xy 254.963549 -216.508378) (xy 255.013149 -216.482877) (xy 255.065933 -216.46487)
			(xy 255.120776 -216.45474) (xy 255.17651 -216.452703) (xy 255.231947 -216.458803) (xy 255.285904 -216.472909)
			(xy 255.337233 -216.494721) (xy 255.384839 -216.523775) (xy 255.427707 -216.55945) (xy 255.464924 -216.600987)
			(xy 255.495697 -216.6475) (xy 255.519369 -216.697997) (xy 255.535437 -216.751404) (xy 255.543557 -216.80658)
			(xy 255.544066 -216.834466) (xy 255.543557 -216.862352) (xy 255.535437 -216.917528) (xy 255.519369 -216.970935)
			(xy 255.495697 -217.021432) (xy 255.464924 -217.067945) (xy 255.427707 -217.109482) (xy 255.384839 -217.145157)
			(xy 255.337233 -217.174211) (xy 255.285904 -217.196023) (xy 255.231947 -217.210129) (xy 255.17651 -217.216229)
			(xy 255.120776 -217.214192) (xy 255.065933 -217.204062) (xy 255.013149 -217.186055) (xy 254.963549 -217.160554)
			(xy 254.918191 -217.128103) (xy 254.878042 -217.089394) (xy 254.843956 -217.045251) (xy 254.81666 -216.996616)
			(xy 254.796737 -216.944525) (xy 254.784611 -216.890088) (xy 254.78054 -216.834466) (xy 250.127816 -216.834466)
			(xy 250.131348 -216.859031) (xy 250.131834 -216.886282) (xy 250.131359 -216.913669) (xy 250.123515 -216.96788)
			(xy 250.107998 -217.020412) (xy 250.085129 -217.070184) (xy 250.055377 -217.116175) (xy 250.019355 -217.157439)
			(xy 249.977801 -217.193127) (xy 249.931571 -217.222506) (xy 249.881615 -217.244972) (xy 249.82896 -217.260063)
			(xy 249.801888 -217.264234) (xy 249.787468 -217.266643) (xy 249.760793 -217.278585) (xy 249.738597 -217.297597)
			(xy 249.722699 -217.32212) (xy 249.714404 -217.350144) (xy 249.714391 -217.379369) (xy 249.718068 -217.39352)
			(xy 249.725195 -217.419612) (xy 249.73284 -217.473156) (xy 249.733308 -217.5002) (xy 249.732822 -217.527451)
			(xy 249.725066 -217.581399) (xy 249.709711 -217.633694) (xy 249.687069 -217.683271) (xy 249.657603 -217.729121)
			(xy 249.621912 -217.770312) (xy 249.580721 -217.806003) (xy 249.534871 -217.835469) (xy 249.485294 -217.858111)
			(xy 249.432999 -217.873466) (xy 249.379051 -217.881222) (xy 249.324549 -217.881222) (xy 249.270601 -217.873466)
			(xy 249.218306 -217.858111) (xy 249.168729 -217.835469) (xy 249.122879 -217.806003) (xy 249.081688 -217.770312)
			(xy 249.045997 -217.729121) (xy 249.016531 -217.683271) (xy 248.993889 -217.633694) (xy 248.978534 -217.581399)
			(xy 248.970778 -217.527451) (xy 248.970292 -217.5002) (xy 243.688108 -217.5002) (xy 243.687599 -217.528086)
			(xy 243.679479 -217.583262) (xy 243.663411 -217.636669) (xy 243.639739 -217.687166) (xy 243.608966 -217.733679)
			(xy 243.571749 -217.775216) (xy 243.528881 -217.810891) (xy 243.481275 -217.839945) (xy 243.429946 -217.861757)
			(xy 243.375989 -217.875863) (xy 243.320552 -217.881963) (xy 243.264818 -217.879926) (xy 243.209975 -217.869796)
			(xy 243.157191 -217.851789) (xy 243.107591 -217.826288) (xy 243.062233 -217.793837) (xy 243.022084 -217.755128)
			(xy 242.987998 -217.710985) (xy 242.960702 -217.66235) (xy 242.940779 -217.610259) (xy 242.928653 -217.555822)
			(xy 242.924582 -217.5002) (xy 242.332787 -217.5002) (xy 242.350263 -217.514744) (xy 242.38748 -217.556281)
			(xy 242.418253 -217.602794) (xy 242.441925 -217.653291) (xy 242.457993 -217.706698) (xy 242.466113 -217.761874)
			(xy 242.466622 -217.78976) (xy 242.466113 -217.817646) (xy 242.457993 -217.872822) (xy 242.441925 -217.926229)
			(xy 242.418253 -217.976726) (xy 242.38748 -218.023239) (xy 242.350263 -218.064776) (xy 242.307395 -218.100451)
			(xy 242.259789 -218.129505) (xy 242.20846 -218.151317) (xy 242.154503 -218.165423) (xy 242.099066 -218.171523)
			(xy 242.043332 -218.169486) (xy 241.988489 -218.159356) (xy 241.935705 -218.141349) (xy 241.886105 -218.115848)
			(xy 241.840747 -218.083397) (xy 241.800598 -218.044688) (xy 241.766512 -218.000545) (xy 241.739216 -217.95191)
			(xy 241.719293 -217.899819) (xy 241.707167 -217.845382) (xy 241.703096 -217.78976) (xy 238.166431 -217.78976)
			(xy 238.193569 -217.831987) (xy 238.216211 -217.881564) (xy 238.231566 -217.933859) (xy 238.239322 -217.987807)
			(xy 238.239808 -218.015058) (xy 238.239411 -218.038816) (xy 238.233473 -218.085959) (xy 238.221735 -218.132002)
			(xy 238.213392 -218.15425) (xy 238.209836 -218.163902) (xy 238.209836 -218.173554) (xy 238.21006 -218.178737)
			(xy 238.212368 -218.18885) (xy 238.214408 -218.19362) (xy 238.243364 -218.259406) (xy 238.250476 -218.270582)
			(xy 238.255556 -218.27617) (xy 238.262668 -218.282774) (xy 238.27232 -218.28633) (xy 238.299168 -218.29701)
			(xy 238.349552 -218.325293) (xy 238.395097 -218.360846) (xy 238.434762 -218.402859) (xy 238.467642 -218.450371)
			(xy 238.492985 -218.502295) (xy 238.510211 -218.557447) (xy 238.518927 -218.614565) (xy 238.519462 -218.643454)
			(xy 238.518976 -218.670705) (xy 238.51122 -218.724653) (xy 238.495865 -218.776948) (xy 238.473223 -218.826525)
			(xy 238.469025 -218.833057) (xy 241.736015 -218.833057) (xy 241.736015 -218.778543) (xy 241.743773 -218.724585)
			(xy 241.759132 -218.67228) (xy 241.781778 -218.622694) (xy 241.811251 -218.576835) (xy 241.84695 -218.535637)
			(xy 241.888149 -218.49994) (xy 241.93401 -218.470469) (xy 241.983597 -218.447826) (xy 242.035903 -218.432469)
			(xy 242.089861 -218.424714) (xy 242.117118 -218.424252) (xy 242.141809 -218.424628) (xy 242.190775 -218.431013)
			(xy 242.238506 -218.443672) (xy 242.2842 -218.462395) (xy 242.30584 -218.47429) (xy 242.316 -218.480132)
			(xy 242.32743 -218.480894) (xy 242.332936 -218.481091) (xy 242.343826 -218.47943) (xy 242.34902 -218.477592)
			(xy 242.423188 -218.44889) (xy 242.428385 -218.446797) (xy 242.437739 -218.440632) (xy 242.44173 -218.436698)
			(xy 242.44935 -218.42857) (xy 242.452906 -218.417394) (xy 242.461591 -218.392215) (xy 242.484956 -218.344353)
			(xy 242.514753 -218.300207) (xy 242.550403 -218.260637) (xy 242.591211 -218.226411) (xy 242.636385 -218.198196)
			(xy 242.685045 -218.176541) (xy 242.736244 -218.161867) (xy 242.788988 -218.154459) (xy 242.815618 -218.153996)
			(xy 242.84287 -218.154461) (xy 242.890853 -218.161362) (xy 250.778262 -218.161362) (xy 250.782333 -218.10574)
			(xy 250.794459 -218.051303) (xy 250.814382 -217.999212) (xy 250.841678 -217.950577) (xy 250.875764 -217.906434)
			(xy 250.915913 -217.867725) (xy 250.961271 -217.835274) (xy 251.010871 -217.809773) (xy 251.063655 -217.791766)
			(xy 251.118498 -217.781636) (xy 251.174232 -217.779599) (xy 251.229669 -217.785699) (xy 251.283626 -217.799805)
			(xy 251.334955 -217.821617) (xy 251.382561 -217.850671) (xy 251.425429 -217.886346) (xy 251.462646 -217.927883)
			(xy 251.493419 -217.974396) (xy 251.517091 -218.024893) (xy 251.533159 -218.0783) (xy 251.541279 -218.133476)
			(xy 251.541788 -218.161362) (xy 251.541279 -218.189248) (xy 251.533159 -218.244424) (xy 251.517091 -218.297831)
			(xy 251.493419 -218.348328) (xy 251.462646 -218.394841) (xy 251.425429 -218.436378) (xy 251.382561 -218.472053)
			(xy 251.334955 -218.501107) (xy 251.283626 -218.522919) (xy 251.229669 -218.537025) (xy 251.174232 -218.543125)
			(xy 251.118498 -218.541088) (xy 251.063655 -218.530958) (xy 251.010871 -218.512951) (xy 250.961271 -218.48745)
			(xy 250.915913 -218.454999) (xy 250.875764 -218.41629) (xy 250.841678 -218.372147) (xy 250.814382 -218.323512)
			(xy 250.794459 -218.271421) (xy 250.782333 -218.216984) (xy 250.778262 -218.161362) (xy 242.890853 -218.161362)
			(xy 242.896819 -218.16222) (xy 242.949114 -218.177578) (xy 242.998691 -218.200221) (xy 243.044542 -218.22969)
			(xy 243.085732 -218.265383) (xy 243.121423 -218.306576) (xy 243.150889 -218.352428) (xy 243.17353 -218.402007)
			(xy 243.188885 -218.454303) (xy 243.196641 -218.508252) (xy 243.197126 -218.535504) (xy 243.196574 -218.565017)
			(xy 243.187483 -218.623338) (xy 243.169518 -218.679563) (xy 243.143109 -218.732351) (xy 243.108884 -218.780442)
			(xy 243.088668 -218.80195) (xy 243.082064 -218.808808) (xy 243.078508 -218.81719) (xy 243.076717 -218.821433)
			(xy 243.074536 -218.830378) (xy 243.07419 -218.83497) (xy 243.071142 -218.902534) (xy 243.071051 -218.907179)
			(xy 243.072322 -218.91638) (xy 243.073682 -218.920822) (xy 243.076476 -218.929712) (xy 243.082318 -218.937078)
			(xy 243.098304 -218.957553) (xy 243.125215 -219.001984) (xy 243.145859 -219.049652) (xy 243.159855 -219.099676)
			(xy 243.166945 -219.151136) (xy 243.167408 -219.177108) (xy 243.16693 -219.204359) (xy 243.159172 -219.258307)
			(xy 243.143816 -219.310602) (xy 243.121174 -219.36018) (xy 243.091707 -219.40603) (xy 243.056014 -219.44722)
			(xy 243.014824 -219.482912) (xy 242.968973 -219.512378) (xy 242.919395 -219.535019) (xy 242.8671 -219.550374)
			(xy 242.813151 -219.55813) (xy 242.7859 -219.558616) (xy 242.758794 -219.55812) (xy 242.705129 -219.550446)
			(xy 242.65309 -219.535252) (xy 242.603727 -219.512844) (xy 242.558032 -219.483674) (xy 242.516927 -219.448328)
			(xy 242.48124 -219.40752) (xy 242.451689 -219.362071) (xy 242.42887 -219.312896) (xy 242.413242 -219.260986)
			(xy 242.40871 -219.234258) (xy 242.406932 -219.22232) (xy 242.40109 -219.21343) (xy 242.397817 -219.208856)
			(xy 242.389605 -219.20117) (xy 242.384834 -219.19819) (xy 242.38331 -219.197428) (xy 242.312698 -219.158312)
			(xy 242.30749 -219.1556) (xy 242.296202 -219.152382) (xy 242.290346 -219.151962) (xy 242.27917 -219.151454)
			(xy 242.268502 -219.155772) (xy 242.265962 -219.156788) (xy 242.242341 -219.166414) (xy 242.193166 -219.179966)
			(xy 242.142622 -219.186831) (xy 242.117118 -219.187268) (xy 242.089861 -219.186886) (xy 242.035903 -219.179131)
			(xy 241.983597 -219.163774) (xy 241.93401 -219.141131) (xy 241.888149 -219.11166) (xy 241.84695 -219.075963)
			(xy 241.811251 -219.034765) (xy 241.781778 -218.988906) (xy 241.759132 -218.93932) (xy 241.743773 -218.887015)
			(xy 241.736015 -218.833057) (xy 238.469025 -218.833057) (xy 238.443757 -218.872375) (xy 238.408066 -218.913566)
			(xy 238.366875 -218.949257) (xy 238.321025 -218.978723) (xy 238.271448 -219.001365) (xy 238.219153 -219.01672)
			(xy 238.165205 -219.024476) (xy 238.110703 -219.024476) (xy 238.056755 -219.01672) (xy 238.00446 -219.001365)
			(xy 237.954883 -218.978723) (xy 237.909033 -218.949257) (xy 237.867842 -218.913566) (xy 237.832151 -218.872375)
			(xy 237.802685 -218.826525) (xy 237.780043 -218.776948) (xy 237.764688 -218.724653) (xy 237.756932 -218.670705)
			(xy 237.756446 -218.643454) (xy 237.756843 -218.619696) (xy 237.76278 -218.572553) (xy 237.774519 -218.52651)
			(xy 237.782862 -218.504262) (xy 237.786418 -218.49461) (xy 237.786418 -218.484958) (xy 237.786194 -218.479775)
			(xy 237.783886 -218.469662) (xy 237.781846 -218.464892) (xy 237.75289 -218.399106) (xy 237.745778 -218.38793)
			(xy 237.740698 -218.382342) (xy 237.733586 -218.375738) (xy 237.723934 -218.372182) (xy 237.69708 -218.361516)
			(xy 237.646698 -218.333229) (xy 237.601155 -218.297672) (xy 237.561491 -218.255657) (xy 237.528613 -218.208144)
			(xy 237.503271 -218.156218) (xy 237.486045 -218.101066) (xy 237.477328 -218.043948) (xy 237.476792 -218.015058)
			(xy 236.44016 -218.015058) (xy 236.443262 -218.024604) (xy 236.451392 -218.075939) (xy 236.451902 -218.101926)
			(xy 236.451392 -218.127913) (xy 236.443262 -218.179248) (xy 236.427201 -218.228678) (xy 236.403605 -218.274988)
			(xy 236.373055 -218.317036) (xy 236.336304 -218.353787) (xy 236.294256 -218.384337) (xy 236.247946 -218.407933)
			(xy 236.198516 -218.423994) (xy 236.147181 -218.432124) (xy 236.095207 -218.432124) (xy 236.043872 -218.423994)
			(xy 235.994442 -218.407933) (xy 235.948132 -218.384337) (xy 235.906084 -218.353787) (xy 235.869333 -218.317036)
			(xy 235.838783 -218.274988) (xy 235.815187 -218.228678) (xy 235.799126 -218.179248) (xy 235.790996 -218.127913)
			(xy 235.31072 -218.127913) (xy 235.282458 -218.156175) (xy 235.24041 -218.186725) (xy 235.1941 -218.210321)
			(xy 235.14467 -218.226382) (xy 235.093335 -218.234512) (xy 235.041361 -218.234512) (xy 234.990026 -218.226382)
			(xy 234.940596 -218.210321) (xy 234.894286 -218.186725) (xy 234.852238 -218.156175) (xy 234.815487 -218.119424)
			(xy 234.784937 -218.077376) (xy 234.761341 -218.031066) (xy 234.74528 -217.981636) (xy 234.73715 -217.930301)
			(xy 234.5977 -217.930301) (xy 234.58957 -217.981636) (xy 234.573509 -218.031066) (xy 234.549913 -218.077376)
			(xy 234.519363 -218.119424) (xy 234.482612 -218.156175) (xy 234.440564 -218.186725) (xy 234.394254 -218.210321)
			(xy 234.344824 -218.226382) (xy 234.293489 -218.234512) (xy 234.241515 -218.234512) (xy 234.19018 -218.226382)
			(xy 234.14075 -218.210321) (xy 234.09444 -218.186725) (xy 234.052392 -218.156175) (xy 234.015641 -218.119424)
			(xy 233.985091 -218.077376) (xy 233.961495 -218.031066) (xy 233.945434 -217.981636) (xy 233.937304 -217.930301)
			(xy 232.997754 -217.930301) (xy 232.989624 -217.981636) (xy 232.973563 -218.031066) (xy 232.949967 -218.077376)
			(xy 232.919417 -218.119424) (xy 232.882666 -218.156175) (xy 232.840618 -218.186725) (xy 232.794308 -218.210321)
			(xy 232.744878 -218.226382) (xy 232.693543 -218.234512) (xy 232.641569 -218.234512) (xy 232.590234 -218.226382)
			(xy 232.540804 -218.210321) (xy 232.494494 -218.186725) (xy 232.452446 -218.156175) (xy 232.415695 -218.119424)
			(xy 232.385145 -218.077376) (xy 232.361549 -218.031066) (xy 232.345488 -217.981636) (xy 232.337358 -217.930301)
			(xy 232.197654 -217.930301) (xy 232.189524 -217.981636) (xy 232.173463 -218.031066) (xy 232.149867 -218.077376)
			(xy 232.119317 -218.119424) (xy 232.082566 -218.156175) (xy 232.040518 -218.186725) (xy 231.994208 -218.210321)
			(xy 231.944778 -218.226382) (xy 231.893443 -218.234512) (xy 231.841469 -218.234512) (xy 231.790134 -218.226382)
			(xy 231.740704 -218.210321) (xy 231.694394 -218.186725) (xy 231.652346 -218.156175) (xy 231.615595 -218.119424)
			(xy 231.585045 -218.077376) (xy 231.561449 -218.031066) (xy 231.545388 -217.981636) (xy 231.537258 -217.930301)
			(xy 231.397554 -217.930301) (xy 231.389424 -217.981636) (xy 231.373363 -218.031066) (xy 231.349767 -218.077376)
			(xy 231.319217 -218.119424) (xy 231.282466 -218.156175) (xy 231.240418 -218.186725) (xy 231.194108 -218.210321)
			(xy 231.144678 -218.226382) (xy 231.093343 -218.234512) (xy 231.041369 -218.234512) (xy 230.990034 -218.226382)
			(xy 230.940604 -218.210321) (xy 230.894294 -218.186725) (xy 230.852246 -218.156175) (xy 230.815495 -218.119424)
			(xy 230.784945 -218.077376) (xy 230.761349 -218.031066) (xy 230.745288 -217.981636) (xy 230.737158 -217.930301)
			(xy 230.597708 -217.930301) (xy 230.589578 -217.981636) (xy 230.573517 -218.031066) (xy 230.549921 -218.077376)
			(xy 230.519371 -218.119424) (xy 230.48262 -218.156175) (xy 230.440572 -218.186725) (xy 230.394262 -218.210321)
			(xy 230.344832 -218.226382) (xy 230.293497 -218.234512) (xy 230.241523 -218.234512) (xy 230.190188 -218.226382)
			(xy 230.140758 -218.210321) (xy 230.094448 -218.186725) (xy 230.0524 -218.156175) (xy 230.015649 -218.119424)
			(xy 229.985099 -218.077376) (xy 229.961503 -218.031066) (xy 229.945442 -217.981636) (xy 229.937312 -217.930301)
			(xy 228.998016 -217.930301) (xy 228.989886 -217.981636) (xy 228.973825 -218.031066) (xy 228.950229 -218.077376)
			(xy 228.919679 -218.119424) (xy 228.882928 -218.156175) (xy 228.84088 -218.186725) (xy 228.79457 -218.210321)
			(xy 228.74514 -218.226382) (xy 228.693805 -218.234512) (xy 228.641831 -218.234512) (xy 228.590496 -218.226382)
			(xy 228.541066 -218.210321) (xy 228.494756 -218.186725) (xy 228.452708 -218.156175) (xy 228.415957 -218.119424)
			(xy 228.385407 -218.077376) (xy 228.361811 -218.031066) (xy 228.34575 -217.981636) (xy 228.33762 -217.930301)
			(xy 228.19817 -217.930301) (xy 228.19004 -217.981636) (xy 228.173979 -218.031066) (xy 228.150383 -218.077376)
			(xy 228.119833 -218.119424) (xy 228.083082 -218.156175) (xy 228.041034 -218.186725) (xy 227.994724 -218.210321)
			(xy 227.945294 -218.226382) (xy 227.893959 -218.234512) (xy 227.841985 -218.234512) (xy 227.79065 -218.226382)
			(xy 227.74122 -218.210321) (xy 227.69491 -218.186725) (xy 227.652862 -218.156175) (xy 227.616111 -218.119424)
			(xy 227.585561 -218.077376) (xy 227.561965 -218.031066) (xy 227.545904 -217.981636) (xy 227.537774 -217.930301)
			(xy 227.39807 -217.930301) (xy 227.38994 -217.981636) (xy 227.373879 -218.031066) (xy 227.350283 -218.077376)
			(xy 227.319733 -218.119424) (xy 227.282982 -218.156175) (xy 227.240934 -218.186725) (xy 227.194624 -218.210321)
			(xy 227.145194 -218.226382) (xy 227.093859 -218.234512) (xy 227.041885 -218.234512) (xy 226.99055 -218.226382)
			(xy 226.94112 -218.210321) (xy 226.89481 -218.186725) (xy 226.852762 -218.156175) (xy 226.816011 -218.119424)
			(xy 226.785461 -218.077376) (xy 226.761865 -218.031066) (xy 226.745804 -217.981636) (xy 226.737674 -217.930301)
			(xy 226.59797 -217.930301) (xy 226.58984 -217.981636) (xy 226.573779 -218.031066) (xy 226.550183 -218.077376)
			(xy 226.519633 -218.119424) (xy 226.482882 -218.156175) (xy 226.440834 -218.186725) (xy 226.394524 -218.210321)
			(xy 226.345094 -218.226382) (xy 226.293759 -218.234512) (xy 226.241785 -218.234512) (xy 226.19045 -218.226382)
			(xy 226.14102 -218.210321) (xy 226.09471 -218.186725) (xy 226.052662 -218.156175) (xy 226.015911 -218.119424)
			(xy 225.985361 -218.077376) (xy 225.961765 -218.031066) (xy 225.945704 -217.981636) (xy 225.937574 -217.930301)
			(xy 225.798124 -217.930301) (xy 225.789994 -217.981636) (xy 225.773933 -218.031066) (xy 225.750337 -218.077376)
			(xy 225.719787 -218.119424) (xy 225.683036 -218.156175) (xy 225.640988 -218.186725) (xy 225.594678 -218.210321)
			(xy 225.545248 -218.226382) (xy 225.493913 -218.234512) (xy 225.441939 -218.234512) (xy 225.390604 -218.226382)
			(xy 225.341174 -218.210321) (xy 225.294864 -218.186725) (xy 225.252816 -218.156175) (xy 225.216065 -218.119424)
			(xy 225.185515 -218.077376) (xy 225.161919 -218.031066) (xy 225.145858 -217.981636) (xy 225.137728 -217.930301)
			(xy 224.998024 -217.930301) (xy 224.989894 -217.981636) (xy 224.973833 -218.031066) (xy 224.950237 -218.077376)
			(xy 224.919687 -218.119424) (xy 224.882936 -218.156175) (xy 224.840888 -218.186725) (xy 224.794578 -218.210321)
			(xy 224.745148 -218.226382) (xy 224.693813 -218.234512) (xy 224.641839 -218.234512) (xy 224.590504 -218.226382)
			(xy 224.541074 -218.210321) (xy 224.494764 -218.186725) (xy 224.452716 -218.156175) (xy 224.415965 -218.119424)
			(xy 224.385415 -218.077376) (xy 224.361819 -218.031066) (xy 224.345758 -217.981636) (xy 224.337628 -217.930301)
			(xy 219.02937 -217.930301) (xy 219.058159 -217.934437) (xy 219.110458 -217.949788) (xy 219.160039 -217.972426)
			(xy 219.205894 -218.00189) (xy 219.247088 -218.037581) (xy 219.282783 -218.078771) (xy 219.312253 -218.124622)
			(xy 219.334896 -218.174201) (xy 219.350253 -218.226498) (xy 219.358011 -218.280448) (xy 219.358011 -218.334952)
			(xy 219.350253 -218.388902) (xy 219.334896 -218.441199) (xy 219.312253 -218.490778) (xy 219.282783 -218.536629)
			(xy 219.247088 -218.577819) (xy 219.205894 -218.61351) (xy 219.160039 -218.642974) (xy 219.110458 -218.665612)
			(xy 219.058159 -218.680963) (xy 219.004208 -218.688714) (xy 218.976956 -218.689174) (xy 218.947195 -218.688563)
			(xy 218.888396 -218.679315) (xy 218.831746 -218.661051) (xy 218.778618 -218.634213) (xy 218.7303 -218.599453)
			(xy 218.708732 -218.578938) (xy 218.70162 -218.57208) (xy 218.692984 -218.56827) (xy 218.6883 -218.566464)
			(xy 218.678446 -218.56455) (xy 218.673426 -218.56446) (xy 218.603068 -218.563698) (xy 218.599399 -218.563752)
			(xy 218.592131 -218.564767) (xy 218.58859 -218.56573) (xy 218.583256 -218.567508) (xy 218.574366 -218.571064)
			(xy 218.567 -218.577922) (xy 218.545578 -218.597719) (xy 218.497816 -218.631201) (xy 218.445518 -218.65703)
			(xy 218.389901 -218.674606) (xy 218.332258 -218.68352) (xy 218.303094 -218.684094) (xy 218.275842 -218.683636)
			(xy 218.221893 -218.675878) (xy 218.169597 -218.660522) (xy 218.120019 -218.63788) (xy 218.074167 -218.608412)
			(xy 218.032976 -218.572719) (xy 217.997284 -218.531528) (xy 217.967817 -218.485676) (xy 217.945176 -218.436097)
			(xy 217.92982 -218.383801) (xy 217.922064 -218.329852) (xy 215.554062 -218.329852) (xy 215.554051 -218.330472)
			(xy 215.545931 -218.385648) (xy 215.529863 -218.439055) (xy 215.506191 -218.489552) (xy 215.475418 -218.536065)
			(xy 215.438201 -218.577602) (xy 215.395333 -218.613277) (xy 215.347727 -218.642331) (xy 215.296398 -218.664143)
			(xy 215.242441 -218.678249) (xy 215.187004 -218.684349) (xy 215.13127 -218.682312) (xy 215.076427 -218.672182)
			(xy 215.023643 -218.654175) (xy 214.974043 -218.628674) (xy 214.928685 -218.596223) (xy 214.888536 -218.557514)
			(xy 214.85445 -218.513371) (xy 214.827154 -218.464736) (xy 214.807231 -218.412645) (xy 214.795105 -218.358208)
			(xy 214.791034 -218.302586) (xy 214.649137 -218.302586) (xy 214.648795 -218.321328) (xy 214.640675 -218.376504)
			(xy 214.624607 -218.429911) (xy 214.600935 -218.480408) (xy 214.570162 -218.526921) (xy 214.532945 -218.568458)
			(xy 214.490077 -218.604133) (xy 214.442471 -218.633187) (xy 214.391142 -218.654999) (xy 214.337185 -218.669105)
			(xy 214.281748 -218.675205) (xy 214.226014 -218.673168) (xy 214.171171 -218.663038) (xy 214.118387 -218.645031)
			(xy 214.068787 -218.61953) (xy 214.023429 -218.587079) (xy 213.98328 -218.54837) (xy 213.949194 -218.504227)
			(xy 213.921898 -218.455592) (xy 213.901975 -218.403501) (xy 213.889849 -218.349064) (xy 213.885778 -218.293442)
			(xy 213.622058 -218.293442) (xy 213.621619 -218.317518) (xy 213.613499 -218.372694) (xy 213.597431 -218.426101)
			(xy 213.573759 -218.476598) (xy 213.542986 -218.523111) (xy 213.505769 -218.564648) (xy 213.462901 -218.600323)
			(xy 213.415295 -218.629377) (xy 213.363966 -218.651189) (xy 213.310009 -218.665295) (xy 213.254572 -218.671395)
			(xy 213.198838 -218.669358) (xy 213.143995 -218.659228) (xy 213.091211 -218.641221) (xy 213.041611 -218.61572)
			(xy 212.996253 -218.583269) (xy 212.956104 -218.54456) (xy 212.922018 -218.500417) (xy 212.894722 -218.451782)
			(xy 212.874799 -218.399691) (xy 212.862673 -218.345254) (xy 212.858602 -218.289632) (xy 209.27477 -218.289632)
			(xy 209.248549 -218.296487) (xy 209.193112 -218.302587) (xy 209.137378 -218.30055) (xy 209.082535 -218.29042)
			(xy 209.029751 -218.272413) (xy 208.980151 -218.246912) (xy 208.934793 -218.214461) (xy 208.894644 -218.175752)
			(xy 208.860558 -218.131609) (xy 208.833262 -218.082974) (xy 208.813339 -218.030883) (xy 208.801213 -217.976446)
			(xy 208.797142 -217.920824) (xy 196.968618 -217.920824) (xy 196.968618 -219.052913) (xy 205.978816 -219.052913)
			(xy 205.978821 -218.998417) (xy 205.986581 -218.944476) (xy 206.001939 -218.892189) (xy 206.024582 -218.842619)
			(xy 206.054049 -218.796777) (xy 206.08974 -218.755594) (xy 206.130928 -218.71991) (xy 206.176776 -218.690451)
			(xy 206.226349 -218.667817) (xy 206.278639 -218.652467) (xy 206.332581 -218.644716) (xy 206.387077 -218.64472)
			(xy 206.441018 -218.65248) (xy 206.493306 -218.667837) (xy 206.542876 -218.690479) (xy 206.588719 -218.719946)
			(xy 206.629902 -218.755636) (xy 206.665586 -218.796824) (xy 206.695046 -218.842671) (xy 206.717681 -218.892244)
			(xy 206.733031 -218.944534) (xy 206.740784 -218.998476) (xy 206.741268 -219.025724) (xy 206.740827 -219.051578)
			(xy 206.73382 -219.10281) (xy 206.727298 -219.127832) (xy 206.72552 -219.13469) (xy 206.72552 -219.141548)
			(xy 206.725949 -219.151561) (xy 206.733628 -219.170058) (xy 206.747799 -219.18421) (xy 206.766306 -219.191864)
			(xy 206.77632 -219.192348) (xy 206.803572 -219.192877) (xy 206.85752 -219.200636) (xy 206.909815 -219.215995)
			(xy 206.959392 -219.238639) (xy 207.005242 -219.268109) (xy 207.04643 -219.303804) (xy 207.08212 -219.344997)
			(xy 207.089305 -219.356178) (xy 207.678018 -219.356178) (xy 207.682089 -219.300556) (xy 207.694215 -219.246119)
			(xy 207.714138 -219.194028) (xy 207.741434 -219.145393) (xy 207.77552 -219.10125) (xy 207.815669 -219.062541)
			(xy 207.861027 -219.03009) (xy 207.910627 -219.004589) (xy 207.963411 -218.986582) (xy 208.018254 -218.976452)
			(xy 208.073988 -218.974415) (xy 208.129425 -218.980515) (xy 208.183382 -218.994621) (xy 208.234711 -219.016433)
			(xy 208.282317 -219.045487) (xy 208.325185 -219.081162) (xy 208.362402 -219.122699) (xy 208.393175 -219.169212)
			(xy 208.416847 -219.219709) (xy 208.432915 -219.273116) (xy 208.4376 -219.30495) (xy 208.64527 -219.30495)
			(xy 208.64527 -219.25045) (xy 208.653025 -219.196506) (xy 208.668378 -219.144214) (xy 208.691016 -219.094639)
			(xy 208.720479 -219.04879) (xy 208.756166 -219.0076) (xy 208.797351 -218.971907) (xy 208.843196 -218.942439)
			(xy 208.892769 -218.919795) (xy 208.945059 -218.904435) (xy 208.999002 -218.896673) (xy 209.026252 -218.896184)
			(xy 209.055757 -218.896736) (xy 209.114063 -218.905836) (xy 209.170275 -218.923795) (xy 209.223055 -218.950187)
			(xy 209.271148 -218.984383) (xy 209.313409 -219.025569) (xy 209.33156 -219.048838) (xy 209.340838 -219.060392)
			(xy 209.364699 -219.077946) (xy 209.392591 -219.08792) (xy 209.422172 -219.089478) (xy 209.450958 -219.082488)
			(xy 209.476531 -219.067538) (xy 209.496743 -219.045883) (xy 209.503772 -219.032836) (xy 209.515942 -219.009268)
			(xy 209.545838 -218.965454) (xy 209.581511 -218.926199) (xy 209.622273 -218.89226) (xy 209.667342 -218.864291)
			(xy 209.715848 -218.842828) (xy 209.766857 -218.828287) (xy 209.819389 -218.820946) (xy 209.84591 -218.820492)
			(xy 209.873161 -218.820978) (xy 209.927107 -218.828736) (xy 209.979401 -218.844092) (xy 210.028977 -218.866734)
			(xy 210.074826 -218.8962) (xy 210.116015 -218.931892) (xy 210.151706 -218.973082) (xy 210.181171 -219.018932)
			(xy 210.203811 -219.068508) (xy 210.219166 -219.120802) (xy 210.226922 -219.174749) (xy 210.226922 -219.229251)
			(xy 210.219166 -219.283198) (xy 210.203811 -219.335492) (xy 210.181171 -219.385068) (xy 210.151706 -219.430918)
			(xy 210.116015 -219.472108) (xy 210.074826 -219.5078) (xy 210.028977 -219.537266) (xy 209.979401 -219.559908)
			(xy 209.927107 -219.575264) (xy 209.883911 -219.581476) (xy 210.858098 -219.581476) (xy 210.862169 -219.525854)
			(xy 210.874295 -219.471417) (xy 210.894218 -219.419326) (xy 210.921514 -219.370691) (xy 210.9556 -219.326548)
			(xy 210.995749 -219.287839) (xy 211.041107 -219.255388) (xy 211.090707 -219.229887) (xy 211.143491 -219.21188)
			(xy 211.198334 -219.20175) (xy 211.254068 -219.199713) (xy 211.309505 -219.205813) (xy 211.363462 -219.219919)
			(xy 211.414791 -219.241731) (xy 211.462397 -219.270785) (xy 211.505265 -219.30646) (xy 211.530075 -219.33415)
			(xy 214.45728 -219.33415) (xy 214.45728 -219.27965) (xy 214.465036 -219.225704) (xy 214.48039 -219.173411)
			(xy 214.503029 -219.123836) (xy 214.532494 -219.077986) (xy 214.568183 -219.036797) (xy 214.60937 -219.001106)
			(xy 214.655218 -218.971639) (xy 214.704792 -218.948997) (xy 214.757085 -218.93364) (xy 214.81103 -218.925881)
			(xy 214.83828 -218.925394) (xy 214.867198 -218.925918) (xy 214.92437 -218.934652) (xy 214.979566 -218.951921)
			(xy 215.031521 -218.977329) (xy 215.079042 -219.010295) (xy 215.100408 -219.029788) (xy 215.10752 -219.036392)
			(xy 215.11641 -219.039948) (xy 215.120739 -219.041614) (xy 215.129811 -219.043537) (xy 215.134444 -219.043758)
			(xy 215.20277 -219.044774) (xy 215.207498 -219.044756) (xy 215.216828 -219.043226) (xy 215.221312 -219.041726)
			(xy 215.230202 -219.038424) (xy 215.237314 -219.032328) (xy 215.258339 -219.01449) (xy 215.304523 -218.984377)
			(xy 215.354561 -218.961223) (xy 215.407409 -218.945511) (xy 215.461969 -218.937568) (xy 215.489536 -218.937078)
			(xy 215.48979 -218.937078) (xy 215.516084 -218.93755) (xy 215.568172 -218.944794) (xy 215.618773 -218.959118)
			(xy 215.666929 -218.980251) (xy 215.711729 -219.007793) (xy 215.752325 -219.041223) (xy 215.77046 -219.060268)
			(xy 215.777999 -219.067649) (xy 215.797266 -219.076187) (xy 215.807798 -219.076778) (xy 215.882474 -219.076778)
			(xy 215.893025 -219.076255) (xy 215.91232 -219.067716) (xy 215.919812 -219.060268) (xy 215.937939 -219.04121)
			(xy 215.97852 -219.007752) (xy 216.023316 -218.980191) (xy 216.071477 -218.959051) (xy 216.122086 -218.944735)
			(xy 216.174184 -218.937514) (xy 216.200482 -218.937078) (xy 216.200736 -218.937078) (xy 216.227985 -218.937595)
			(xy 216.281926 -218.945355) (xy 216.334215 -218.960713) (xy 216.383786 -218.983355) (xy 216.42963 -219.012821)
			(xy 216.470814 -219.048511) (xy 216.5065 -219.089699) (xy 216.535962 -219.135546) (xy 216.5586 -219.185119)
			(xy 216.573953 -219.237409) (xy 216.581708 -219.291351) (xy 216.581708 -219.345849) (xy 216.573953 -219.399791)
			(xy 216.5586 -219.452081) (xy 216.535962 -219.501654) (xy 216.5065 -219.547501) (xy 216.470814 -219.588689)
			(xy 216.42963 -219.624379) (xy 216.383786 -219.653845) (xy 216.334215 -219.676487) (xy 216.281926 -219.691845)
			(xy 216.227985 -219.699605) (xy 216.200736 -219.700094) (xy 216.200482 -219.700094) (xy 216.174187 -219.699649)
			(xy 216.122097 -219.692401) (xy 216.071496 -219.678073) (xy 216.023339 -219.656935) (xy 215.97854 -219.629387)
			(xy 215.937946 -219.595952) (xy 215.919812 -219.576904) (xy 215.912287 -219.569506) (xy 215.89301 -219.56098)
			(xy 215.882474 -219.560394) (xy 215.807798 -219.560394) (xy 215.797247 -219.56091) (xy 215.777952 -219.569455)
			(xy 215.77046 -219.576904) (xy 215.752361 -219.595989) (xy 215.711772 -219.629443) (xy 215.66697 -219.656998)
			(xy 215.618804 -219.678132) (xy 215.56819 -219.692443) (xy 215.516089 -219.69966) (xy 215.48979 -219.700094)
			(xy 215.489536 -219.700094) (xy 215.460619 -219.699563) (xy 215.403447 -219.690832) (xy 215.34825 -219.673564)
			(xy 215.296295 -219.648157) (xy 215.248774 -219.615193) (xy 215.227408 -219.5957) (xy 215.220296 -219.589096)
			(xy 215.211406 -219.58554) (xy 215.207085 -219.583852) (xy 215.198007 -219.581943) (xy 215.193372 -219.58173)
			(xy 215.125046 -219.580714) (xy 215.120318 -219.580737) (xy 215.110988 -219.582264) (xy 215.106504 -219.583762)
			(xy 215.097614 -219.587064) (xy 215.090502 -219.59316) (xy 215.069508 -219.611035) (xy 215.023315 -219.641143)
			(xy 214.97327 -219.66429) (xy 214.920415 -219.679993) (xy 214.865849 -219.687926) (xy 214.83828 -219.68841)
			(xy 214.81103 -219.687919) (xy 214.757085 -219.68016) (xy 214.704792 -219.664803) (xy 214.655218 -219.642161)
			(xy 214.60937 -219.612694) (xy 214.568183 -219.577003) (xy 214.532494 -219.535814) (xy 214.503029 -219.489964)
			(xy 214.48039 -219.440389) (xy 214.465036 -219.388096) (xy 214.45728 -219.33415) (xy 211.530075 -219.33415)
			(xy 211.542482 -219.347997) (xy 211.573255 -219.39451) (xy 211.596927 -219.445007) (xy 211.612995 -219.498414)
			(xy 211.621115 -219.55359) (xy 211.621624 -219.581476) (xy 211.621115 -219.609362) (xy 211.612995 -219.664538)
			(xy 211.596927 -219.717945) (xy 211.573255 -219.768442) (xy 211.542482 -219.814955) (xy 211.505265 -219.856492)
			(xy 211.462397 -219.892167) (xy 211.414791 -219.921221) (xy 211.363462 -219.943033) (xy 211.309505 -219.957139)
			(xy 211.254068 -219.963239) (xy 211.198334 -219.961202) (xy 211.143491 -219.951072) (xy 211.090707 -219.933065)
			(xy 211.041107 -219.907564) (xy 210.995749 -219.875113) (xy 210.9556 -219.836404) (xy 210.921514 -219.792261)
			(xy 210.894218 -219.743626) (xy 210.874295 -219.691535) (xy 210.862169 -219.637098) (xy 210.858098 -219.581476)
			(xy 209.883911 -219.581476) (xy 209.873161 -219.583022) (xy 209.84591 -219.583508) (xy 209.816399 -219.583007)
			(xy 209.758081 -219.573931) (xy 209.701857 -219.555978) (xy 209.64907 -219.529577) (xy 209.600981 -219.495359)
			(xy 209.558738 -219.45414) (xy 209.540602 -219.430854) (xy 209.531248 -219.419367) (xy 209.507405 -219.401815)
			(xy 209.47953 -219.391838) (xy 209.449965 -219.390271) (xy 209.421193 -219.397248) (xy 209.395628 -219.412182)
			(xy 209.37542 -219.433819) (xy 209.36839 -219.446856) (xy 209.356169 -219.470396) (xy 209.32628 -219.51421)
			(xy 209.290615 -219.553465) (xy 209.24986 -219.587406) (xy 209.204799 -219.615379) (xy 209.1563 -219.636846)
			(xy 209.105297 -219.651393) (xy 209.052771 -219.658741) (xy 209.026252 -219.6592) (xy 208.999002 -219.658727)
			(xy 208.945059 -219.650965) (xy 208.892769 -219.635605) (xy 208.843196 -219.612961) (xy 208.797351 -219.583493)
			(xy 208.756166 -219.5478) (xy 208.720479 -219.50661) (xy 208.691016 -219.460761) (xy 208.668378 -219.411186)
			(xy 208.653025 -219.358894) (xy 208.64527 -219.30495) (xy 208.4376 -219.30495) (xy 208.441035 -219.328292)
			(xy 208.441544 -219.356178) (xy 208.441035 -219.384064) (xy 208.432915 -219.43924) (xy 208.416847 -219.492647)
			(xy 208.393175 -219.543144) (xy 208.362402 -219.589657) (xy 208.325185 -219.631194) (xy 208.282317 -219.666869)
			(xy 208.234711 -219.695923) (xy 208.183382 -219.717735) (xy 208.129425 -219.731841) (xy 208.073988 -219.737941)
			(xy 208.018254 -219.735904) (xy 207.963411 -219.725774) (xy 207.910627 -219.707767) (xy 207.861027 -219.682266)
			(xy 207.815669 -219.649815) (xy 207.77552 -219.611106) (xy 207.741434 -219.566963) (xy 207.714138 -219.518328)
			(xy 207.694215 -219.466237) (xy 207.682089 -219.4118) (xy 207.678018 -219.356178) (xy 207.089305 -219.356178)
			(xy 207.111584 -219.39085) (xy 207.134222 -219.44043) (xy 207.149574 -219.492727) (xy 207.157327 -219.546676)
			(xy 207.157323 -219.60118) (xy 207.149562 -219.655128) (xy 207.134202 -219.707423) (xy 207.111557 -219.756999)
			(xy 207.082086 -219.802848) (xy 207.046391 -219.844036) (xy 207.005197 -219.879725) (xy 206.959343 -219.909188)
			(xy 206.909763 -219.931825) (xy 206.857465 -219.947176) (xy 206.803516 -219.954927) (xy 206.749012 -219.954922)
			(xy 206.695064 -219.94716) (xy 206.64277 -219.9318) (xy 206.593194 -219.909153) (xy 206.547346 -219.879682)
			(xy 206.506158 -219.843985) (xy 206.47047 -219.80279) (xy 206.441008 -219.756936) (xy 206.418372 -219.707355)
			(xy 206.403023 -219.655058) (xy 206.395272 -219.601108) (xy 206.394812 -219.573856) (xy 206.39525 -219.548002)
			(xy 206.402259 -219.49677) (xy 206.408782 -219.471748) (xy 206.41056 -219.46489) (xy 206.41056 -219.458032)
			(xy 206.410153 -219.448008) (xy 206.402486 -219.429484) (xy 206.388309 -219.415309) (xy 206.369784 -219.407645)
			(xy 206.35976 -219.407232) (xy 206.332512 -219.406679) (xy 206.278571 -219.398918) (xy 206.226284 -219.383559)
			(xy 206.176715 -219.360916) (xy 206.130873 -219.331448) (xy 206.089691 -219.295757) (xy 206.054007 -219.254568)
			(xy 206.024549 -219.20872) (xy 206.001915 -219.159146) (xy 205.986566 -219.106856) (xy 205.978816 -219.052913)
			(xy 196.968618 -219.052913) (xy 196.968618 -220.417953) (xy 208.720375 -220.417953) (xy 208.720375 -220.363447)
			(xy 208.728133 -220.309496) (xy 208.74349 -220.257198) (xy 208.766134 -220.207618) (xy 208.795604 -220.161765)
			(xy 208.831299 -220.120574) (xy 208.872494 -220.084882) (xy 208.918349 -220.055417) (xy 208.967931 -220.032777)
			(xy 209.020231 -220.017425) (xy 209.074183 -220.009673) (xy 209.101436 -220.009212) (xy 209.128643 -220.00964)
			(xy 209.182504 -220.017376) (xy 209.23472 -220.032685) (xy 209.284232 -220.055258) (xy 209.330034 -220.084635)
			(xy 209.371198 -220.120222) (xy 209.406888 -220.161297) (xy 209.436381 -220.207025) (xy 209.459078 -220.256479)
			(xy 209.474519 -220.308656) (xy 209.476602 -220.322902) (xy 212.215728 -220.322902) (xy 212.219799 -220.26728)
			(xy 212.231925 -220.212843) (xy 212.251848 -220.160752) (xy 212.279144 -220.112117) (xy 212.31323 -220.067974)
			(xy 212.353379 -220.029265) (xy 212.398737 -219.996814) (xy 212.448337 -219.971313) (xy 212.501121 -219.953306)
			(xy 212.555964 -219.943176) (xy 212.611698 -219.941139) (xy 212.667135 -219.947239) (xy 212.721092 -219.961345)
			(xy 212.772421 -219.983157) (xy 212.820027 -220.012211) (xy 212.862895 -220.047886) (xy 212.900112 -220.089423)
			(xy 212.930885 -220.135936) (xy 212.954557 -220.186433) (xy 212.970625 -220.23984) (xy 212.978745 -220.295016)
			(xy 212.979254 -220.322902) (xy 212.978757 -220.35015) (xy 214.45728 -220.35015) (xy 214.45728 -220.29565)
			(xy 214.465036 -220.241704) (xy 214.48039 -220.189411) (xy 214.503029 -220.139836) (xy 214.532494 -220.093986)
			(xy 214.568183 -220.052797) (xy 214.60937 -220.017106) (xy 214.655218 -219.987639) (xy 214.704792 -219.964997)
			(xy 214.757085 -219.94964) (xy 214.81103 -219.941881) (xy 214.83828 -219.941394) (xy 214.867198 -219.941918)
			(xy 214.92437 -219.950652) (xy 214.979566 -219.967921) (xy 215.031521 -219.993329) (xy 215.079042 -220.026295)
			(xy 215.100408 -220.045788) (xy 215.10752 -220.052392) (xy 215.11641 -220.055948) (xy 215.120739 -220.057614)
			(xy 215.129811 -220.059537) (xy 215.134444 -220.059758) (xy 215.20277 -220.060774) (xy 215.207498 -220.060756)
			(xy 215.216828 -220.059226) (xy 215.221312 -220.057726) (xy 215.230202 -220.054424) (xy 215.237314 -220.048328)
			(xy 215.258339 -220.03049) (xy 215.304523 -220.000377) (xy 215.354561 -219.977223) (xy 215.407409 -219.961511)
			(xy 215.461969 -219.953568) (xy 215.489536 -219.953078) (xy 215.48979 -219.953078) (xy 215.516084 -219.95355)
			(xy 215.568172 -219.960794) (xy 215.618773 -219.975118) (xy 215.666929 -219.996251) (xy 215.711729 -220.023793)
			(xy 215.752325 -220.057223) (xy 215.77046 -220.076268) (xy 215.777999 -220.083649) (xy 215.797266 -220.092187)
			(xy 215.807798 -220.092778) (xy 215.882474 -220.092778) (xy 215.893025 -220.092255) (xy 215.91232 -220.083716)
			(xy 215.919812 -220.076268) (xy 215.937939 -220.05721) (xy 215.97852 -220.023752) (xy 216.023316 -219.996191)
			(xy 216.071477 -219.975051) (xy 216.122086 -219.960735) (xy 216.174184 -219.953514) (xy 216.200482 -219.953078)
			(xy 216.200736 -219.953078) (xy 216.227985 -219.953595) (xy 216.281926 -219.961355) (xy 216.334215 -219.976713)
			(xy 216.375893 -219.99575) (xy 217.922094 -219.99575) (xy 217.922687 -219.965483) (xy 217.932252 -219.90571)
			(xy 217.951134 -219.848196) (xy 217.978859 -219.794384) (xy 218.014732 -219.745625) (xy 218.035886 -219.72397)
			(xy 218.04249 -219.717366) (xy 218.0463 -219.70873) (xy 218.048173 -219.704372) (xy 218.050471 -219.695169)
			(xy 218.050872 -219.690442) (xy 218.054682 -219.62237) (xy 218.054834 -219.617736) (xy 218.053681 -219.608537)
			(xy 218.052396 -219.604082) (xy 218.049348 -219.594938) (xy 218.043252 -219.587572) (xy 218.027122 -219.567086)
			(xy 218.000024 -219.522538) (xy 217.979247 -219.474715) (xy 217.965178 -219.424507) (xy 217.958078 -219.372851)
			(xy 217.957654 -219.34678) (xy 217.95814 -219.319529) (xy 217.965896 -219.265581) (xy 217.981251 -219.213286)
			(xy 218.003893 -219.163709) (xy 218.033359 -219.117859) (xy 218.06905 -219.076668) (xy 218.110241 -219.040977)
			(xy 218.156091 -219.011511) (xy 218.205668 -218.988869) (xy 218.257963 -218.973514) (xy 218.311911 -218.965758)
			(xy 218.366413 -218.965758) (xy 218.420361 -218.973514) (xy 218.472656 -218.988869) (xy 218.522233 -219.011511)
			(xy 218.568083 -219.040977) (xy 218.609274 -219.076668) (xy 218.644965 -219.117859) (xy 218.674431 -219.163709)
			(xy 218.697073 -219.213286) (xy 218.712428 -219.265581) (xy 218.720184 -219.319529) (xy 218.72067 -219.34678)
			(xy 218.720106 -219.377048) (xy 218.710536 -219.436824) (xy 218.691648 -219.494338) (xy 218.673273 -219.529993)
			(xy 225.137728 -219.529993) (xy 225.137728 -219.478019) (xy 225.145858 -219.426684) (xy 225.161919 -219.377254)
			(xy 225.185515 -219.330944) (xy 225.216065 -219.288896) (xy 225.252816 -219.252145) (xy 225.294864 -219.221595)
			(xy 225.341174 -219.197999) (xy 225.390604 -219.181938) (xy 225.441939 -219.173808) (xy 225.493913 -219.173808)
			(xy 225.545248 -219.181938) (xy 225.594678 -219.197999) (xy 225.640988 -219.221595) (xy 225.683036 -219.252145)
			(xy 225.719787 -219.288896) (xy 225.750337 -219.330944) (xy 225.773933 -219.377254) (xy 225.789994 -219.426684)
			(xy 225.798124 -219.478019) (xy 225.798634 -219.504006) (xy 225.798124 -219.529993) (xy 225.937574 -219.529993)
			(xy 225.937574 -219.478019) (xy 225.945704 -219.426684) (xy 225.961765 -219.377254) (xy 225.985361 -219.330944)
			(xy 226.015911 -219.288896) (xy 226.052662 -219.252145) (xy 226.09471 -219.221595) (xy 226.14102 -219.197999)
			(xy 226.19045 -219.181938) (xy 226.241785 -219.173808) (xy 226.293759 -219.173808) (xy 226.345094 -219.181938)
			(xy 226.394524 -219.197999) (xy 226.440834 -219.221595) (xy 226.482882 -219.252145) (xy 226.519633 -219.288896)
			(xy 226.550183 -219.330944) (xy 226.573779 -219.377254) (xy 226.58984 -219.426684) (xy 226.59797 -219.478019)
			(xy 226.59848 -219.504006) (xy 226.59797 -219.529993) (xy 226.737674 -219.529993) (xy 226.737674 -219.478019)
			(xy 226.745804 -219.426684) (xy 226.761865 -219.377254) (xy 226.785461 -219.330944) (xy 226.816011 -219.288896)
			(xy 226.852762 -219.252145) (xy 226.89481 -219.221595) (xy 226.94112 -219.197999) (xy 226.99055 -219.181938)
			(xy 227.041885 -219.173808) (xy 227.093859 -219.173808) (xy 227.145194 -219.181938) (xy 227.194624 -219.197999)
			(xy 227.240934 -219.221595) (xy 227.282982 -219.252145) (xy 227.319733 -219.288896) (xy 227.350283 -219.330944)
			(xy 227.373879 -219.377254) (xy 227.38994 -219.426684) (xy 227.39807 -219.478019) (xy 227.39858 -219.504006)
			(xy 227.39807 -219.529993) (xy 227.537774 -219.529993) (xy 227.537774 -219.478019) (xy 227.545904 -219.426684)
			(xy 227.561965 -219.377254) (xy 227.585561 -219.330944) (xy 227.616111 -219.288896) (xy 227.652862 -219.252145)
			(xy 227.69491 -219.221595) (xy 227.74122 -219.197999) (xy 227.79065 -219.181938) (xy 227.841985 -219.173808)
			(xy 227.893959 -219.173808) (xy 227.945294 -219.181938) (xy 227.994724 -219.197999) (xy 228.041034 -219.221595)
			(xy 228.083082 -219.252145) (xy 228.119833 -219.288896) (xy 228.150383 -219.330944) (xy 228.173979 -219.377254)
			(xy 228.19004 -219.426684) (xy 228.19817 -219.478019) (xy 228.19868 -219.504006) (xy 228.19817 -219.529993)
			(xy 228.33762 -219.529993) (xy 228.33762 -219.478019) (xy 228.34575 -219.426684) (xy 228.361811 -219.377254)
			(xy 228.385407 -219.330944) (xy 228.415957 -219.288896) (xy 228.452708 -219.252145) (xy 228.494756 -219.221595)
			(xy 228.541066 -219.197999) (xy 228.590496 -219.181938) (xy 228.641831 -219.173808) (xy 228.693805 -219.173808)
			(xy 228.74514 -219.181938) (xy 228.79457 -219.197999) (xy 228.84088 -219.221595) (xy 228.882928 -219.252145)
			(xy 228.919679 -219.288896) (xy 228.950229 -219.330944) (xy 228.973825 -219.377254) (xy 228.989886 -219.426684)
			(xy 228.998016 -219.478019) (xy 228.998526 -219.504006) (xy 228.998016 -219.529993) (xy 229.937312 -219.529993)
			(xy 229.937312 -219.478019) (xy 229.945442 -219.426684) (xy 229.961503 -219.377254) (xy 229.985099 -219.330944)
			(xy 230.015649 -219.288896) (xy 230.0524 -219.252145) (xy 230.094448 -219.221595) (xy 230.140758 -219.197999)
			(xy 230.190188 -219.181938) (xy 230.241523 -219.173808) (xy 230.293497 -219.173808) (xy 230.344832 -219.181938)
			(xy 230.394262 -219.197999) (xy 230.440572 -219.221595) (xy 230.48262 -219.252145) (xy 230.519371 -219.288896)
			(xy 230.549921 -219.330944) (xy 230.573517 -219.377254) (xy 230.589578 -219.426684) (xy 230.597708 -219.478019)
			(xy 230.598218 -219.504006) (xy 230.597708 -219.529993) (xy 230.737158 -219.529993) (xy 230.737158 -219.478019)
			(xy 230.745288 -219.426684) (xy 230.761349 -219.377254) (xy 230.784945 -219.330944) (xy 230.815495 -219.288896)
			(xy 230.852246 -219.252145) (xy 230.894294 -219.221595) (xy 230.940604 -219.197999) (xy 230.990034 -219.181938)
			(xy 231.041369 -219.173808) (xy 231.093343 -219.173808) (xy 231.144678 -219.181938) (xy 231.194108 -219.197999)
			(xy 231.240418 -219.221595) (xy 231.282466 -219.252145) (xy 231.319217 -219.288896) (xy 231.349767 -219.330944)
			(xy 231.373363 -219.377254) (xy 231.389424 -219.426684) (xy 231.397554 -219.478019) (xy 231.398064 -219.504006)
			(xy 231.397554 -219.529993) (xy 231.537258 -219.529993) (xy 231.537258 -219.478019) (xy 231.545388 -219.426684)
			(xy 231.561449 -219.377254) (xy 231.585045 -219.330944) (xy 231.615595 -219.288896) (xy 231.652346 -219.252145)
			(xy 231.694394 -219.221595) (xy 231.740704 -219.197999) (xy 231.790134 -219.181938) (xy 231.841469 -219.173808)
			(xy 231.893443 -219.173808) (xy 231.944778 -219.181938) (xy 231.994208 -219.197999) (xy 232.040518 -219.221595)
			(xy 232.082566 -219.252145) (xy 232.119317 -219.288896) (xy 232.149867 -219.330944) (xy 232.173463 -219.377254)
			(xy 232.189524 -219.426684) (xy 232.197654 -219.478019) (xy 232.198164 -219.504006) (xy 232.197654 -219.529993)
			(xy 232.337358 -219.529993) (xy 232.337358 -219.478019) (xy 232.345488 -219.426684) (xy 232.361549 -219.377254)
			(xy 232.385145 -219.330944) (xy 232.415695 -219.288896) (xy 232.452446 -219.252145) (xy 232.494494 -219.221595)
			(xy 232.540804 -219.197999) (xy 232.590234 -219.181938) (xy 232.641569 -219.173808) (xy 232.693543 -219.173808)
			(xy 232.744878 -219.181938) (xy 232.794308 -219.197999) (xy 232.840618 -219.221595) (xy 232.882666 -219.252145)
			(xy 232.919417 -219.288896) (xy 232.949967 -219.330944) (xy 232.973563 -219.377254) (xy 232.989624 -219.426684)
			(xy 232.997754 -219.478019) (xy 232.998264 -219.504006) (xy 232.997754 -219.529993) (xy 233.137204 -219.529993)
			(xy 233.137204 -219.478019) (xy 233.145334 -219.426684) (xy 233.161395 -219.377254) (xy 233.184991 -219.330944)
			(xy 233.215541 -219.288896) (xy 233.252292 -219.252145) (xy 233.29434 -219.221595) (xy 233.34065 -219.197999)
			(xy 233.39008 -219.181938) (xy 233.441415 -219.173808) (xy 233.493389 -219.173808) (xy 233.544724 -219.181938)
			(xy 233.594154 -219.197999) (xy 233.640464 -219.221595) (xy 233.682512 -219.252145) (xy 233.719263 -219.288896)
			(xy 233.749813 -219.330944) (xy 233.773409 -219.377254) (xy 233.78947 -219.426684) (xy 233.7976 -219.478019)
			(xy 233.79811 -219.504006) (xy 233.7976 -219.529993) (xy 233.937304 -219.529993) (xy 233.937304 -219.478019)
			(xy 233.945434 -219.426684) (xy 233.961495 -219.377254) (xy 233.985091 -219.330944) (xy 234.015641 -219.288896)
			(xy 234.052392 -219.252145) (xy 234.09444 -219.221595) (xy 234.14075 -219.197999) (xy 234.19018 -219.181938)
			(xy 234.241515 -219.173808) (xy 234.293489 -219.173808) (xy 234.344824 -219.181938) (xy 234.394254 -219.197999)
			(xy 234.440564 -219.221595) (xy 234.482612 -219.252145) (xy 234.519363 -219.288896) (xy 234.549913 -219.330944)
			(xy 234.573509 -219.377254) (xy 234.58957 -219.426684) (xy 234.5977 -219.478019) (xy 234.59821 -219.504006)
			(xy 234.5977 -219.529993) (xy 234.73715 -219.529993) (xy 234.73715 -219.478019) (xy 234.74528 -219.426684)
			(xy 234.761341 -219.377254) (xy 234.784937 -219.330944) (xy 234.815487 -219.288896) (xy 234.852238 -219.252145)
			(xy 234.894286 -219.221595) (xy 234.940596 -219.197999) (xy 234.990026 -219.181938) (xy 235.041361 -219.173808)
			(xy 235.093335 -219.173808) (xy 235.14467 -219.181938) (xy 235.1941 -219.197999) (xy 235.24041 -219.221595)
			(xy 235.282458 -219.252145) (xy 235.319209 -219.288896) (xy 235.349759 -219.330944) (xy 235.373355 -219.377254)
			(xy 235.389416 -219.426684) (xy 235.397546 -219.478019) (xy 235.398056 -219.504006) (xy 235.397546 -219.529993)
			(xy 235.53725 -219.529993) (xy 235.53725 -219.478019) (xy 235.54538 -219.426684) (xy 235.561441 -219.377254)
			(xy 235.585037 -219.330944) (xy 235.615587 -219.288896) (xy 235.652338 -219.252145) (xy 235.694386 -219.221595)
			(xy 235.740696 -219.197999) (xy 235.790126 -219.181938) (xy 235.841461 -219.173808) (xy 235.893435 -219.173808)
			(xy 235.94477 -219.181938) (xy 235.9942 -219.197999) (xy 236.04051 -219.221595) (xy 236.082558 -219.252145)
			(xy 236.119309 -219.288896) (xy 236.149859 -219.330944) (xy 236.173455 -219.377254) (xy 236.189516 -219.426684)
			(xy 236.197646 -219.478019) (xy 236.198156 -219.504006) (xy 236.197646 -219.529993) (xy 236.189516 -219.581328)
			(xy 236.173455 -219.630758) (xy 236.149859 -219.677068) (xy 236.119309 -219.719116) (xy 236.082558 -219.755867)
			(xy 236.04051 -219.786417) (xy 235.9942 -219.810013) (xy 235.94477 -219.826074) (xy 235.893435 -219.834204)
			(xy 235.841461 -219.834204) (xy 235.790126 -219.826074) (xy 235.740696 -219.810013) (xy 235.694386 -219.786417)
			(xy 235.652338 -219.755867) (xy 235.615587 -219.719116) (xy 235.585037 -219.677068) (xy 235.561441 -219.630758)
			(xy 235.54538 -219.581328) (xy 235.53725 -219.529993) (xy 235.397546 -219.529993) (xy 235.389416 -219.581328)
			(xy 235.373355 -219.630758) (xy 235.349759 -219.677068) (xy 235.319209 -219.719116) (xy 235.282458 -219.755867)
			(xy 235.24041 -219.786417) (xy 235.1941 -219.810013) (xy 235.14467 -219.826074) (xy 235.093335 -219.834204)
			(xy 235.041361 -219.834204) (xy 234.990026 -219.826074) (xy 234.940596 -219.810013) (xy 234.894286 -219.786417)
			(xy 234.852238 -219.755867) (xy 234.815487 -219.719116) (xy 234.784937 -219.677068) (xy 234.761341 -219.630758)
			(xy 234.74528 -219.581328) (xy 234.73715 -219.529993) (xy 234.5977 -219.529993) (xy 234.58957 -219.581328)
			(xy 234.573509 -219.630758) (xy 234.549913 -219.677068) (xy 234.519363 -219.719116) (xy 234.482612 -219.755867)
			(xy 234.440564 -219.786417) (xy 234.394254 -219.810013) (xy 234.344824 -219.826074) (xy 234.293489 -219.834204)
			(xy 234.241515 -219.834204) (xy 234.19018 -219.826074) (xy 234.14075 -219.810013) (xy 234.09444 -219.786417)
			(xy 234.052392 -219.755867) (xy 234.015641 -219.719116) (xy 233.985091 -219.677068) (xy 233.961495 -219.630758)
			(xy 233.945434 -219.581328) (xy 233.937304 -219.529993) (xy 233.7976 -219.529993) (xy 233.78947 -219.581328)
			(xy 233.773409 -219.630758) (xy 233.749813 -219.677068) (xy 233.719263 -219.719116) (xy 233.682512 -219.755867)
			(xy 233.640464 -219.786417) (xy 233.594154 -219.810013) (xy 233.544724 -219.826074) (xy 233.493389 -219.834204)
			(xy 233.441415 -219.834204) (xy 233.39008 -219.826074) (xy 233.34065 -219.810013) (xy 233.29434 -219.786417)
			(xy 233.252292 -219.755867) (xy 233.215541 -219.719116) (xy 233.184991 -219.677068) (xy 233.161395 -219.630758)
			(xy 233.145334 -219.581328) (xy 233.137204 -219.529993) (xy 232.997754 -219.529993) (xy 232.989624 -219.581328)
			(xy 232.973563 -219.630758) (xy 232.949967 -219.677068) (xy 232.919417 -219.719116) (xy 232.882666 -219.755867)
			(xy 232.840618 -219.786417) (xy 232.794308 -219.810013) (xy 232.744878 -219.826074) (xy 232.693543 -219.834204)
			(xy 232.641569 -219.834204) (xy 232.590234 -219.826074) (xy 232.540804 -219.810013) (xy 232.494494 -219.786417)
			(xy 232.452446 -219.755867) (xy 232.415695 -219.719116) (xy 232.385145 -219.677068) (xy 232.361549 -219.630758)
			(xy 232.345488 -219.581328) (xy 232.337358 -219.529993) (xy 232.197654 -219.529993) (xy 232.189524 -219.581328)
			(xy 232.173463 -219.630758) (xy 232.149867 -219.677068) (xy 232.119317 -219.719116) (xy 232.082566 -219.755867)
			(xy 232.040518 -219.786417) (xy 231.994208 -219.810013) (xy 231.944778 -219.826074) (xy 231.893443 -219.834204)
			(xy 231.841469 -219.834204) (xy 231.790134 -219.826074) (xy 231.740704 -219.810013) (xy 231.694394 -219.786417)
			(xy 231.652346 -219.755867) (xy 231.615595 -219.719116) (xy 231.585045 -219.677068) (xy 231.561449 -219.630758)
			(xy 231.545388 -219.581328) (xy 231.537258 -219.529993) (xy 231.397554 -219.529993) (xy 231.389424 -219.581328)
			(xy 231.373363 -219.630758) (xy 231.349767 -219.677068) (xy 231.319217 -219.719116) (xy 231.282466 -219.755867)
			(xy 231.240418 -219.786417) (xy 231.194108 -219.810013) (xy 231.144678 -219.826074) (xy 231.093343 -219.834204)
			(xy 231.041369 -219.834204) (xy 230.990034 -219.826074) (xy 230.940604 -219.810013) (xy 230.894294 -219.786417)
			(xy 230.852246 -219.755867) (xy 230.815495 -219.719116) (xy 230.784945 -219.677068) (xy 230.761349 -219.630758)
			(xy 230.745288 -219.581328) (xy 230.737158 -219.529993) (xy 230.597708 -219.529993) (xy 230.589578 -219.581328)
			(xy 230.573517 -219.630758) (xy 230.549921 -219.677068) (xy 230.519371 -219.719116) (xy 230.48262 -219.755867)
			(xy 230.440572 -219.786417) (xy 230.394262 -219.810013) (xy 230.344832 -219.826074) (xy 230.293497 -219.834204)
			(xy 230.241523 -219.834204) (xy 230.190188 -219.826074) (xy 230.140758 -219.810013) (xy 230.094448 -219.786417)
			(xy 230.0524 -219.755867) (xy 230.015649 -219.719116) (xy 229.985099 -219.677068) (xy 229.961503 -219.630758)
			(xy 229.945442 -219.581328) (xy 229.937312 -219.529993) (xy 228.998016 -219.529993) (xy 228.989886 -219.581328)
			(xy 228.973825 -219.630758) (xy 228.950229 -219.677068) (xy 228.919679 -219.719116) (xy 228.882928 -219.755867)
			(xy 228.84088 -219.786417) (xy 228.79457 -219.810013) (xy 228.74514 -219.826074) (xy 228.693805 -219.834204)
			(xy 228.641831 -219.834204) (xy 228.590496 -219.826074) (xy 228.541066 -219.810013) (xy 228.494756 -219.786417)
			(xy 228.452708 -219.755867) (xy 228.415957 -219.719116) (xy 228.385407 -219.677068) (xy 228.361811 -219.630758)
			(xy 228.34575 -219.581328) (xy 228.33762 -219.529993) (xy 228.19817 -219.529993) (xy 228.19004 -219.581328)
			(xy 228.173979 -219.630758) (xy 228.150383 -219.677068) (xy 228.119833 -219.719116) (xy 228.083082 -219.755867)
			(xy 228.041034 -219.786417) (xy 227.994724 -219.810013) (xy 227.945294 -219.826074) (xy 227.893959 -219.834204)
			(xy 227.841985 -219.834204) (xy 227.79065 -219.826074) (xy 227.74122 -219.810013) (xy 227.69491 -219.786417)
			(xy 227.652862 -219.755867) (xy 227.616111 -219.719116) (xy 227.585561 -219.677068) (xy 227.561965 -219.630758)
			(xy 227.545904 -219.581328) (xy 227.537774 -219.529993) (xy 227.39807 -219.529993) (xy 227.38994 -219.581328)
			(xy 227.373879 -219.630758) (xy 227.350283 -219.677068) (xy 227.319733 -219.719116) (xy 227.282982 -219.755867)
			(xy 227.240934 -219.786417) (xy 227.194624 -219.810013) (xy 227.145194 -219.826074) (xy 227.093859 -219.834204)
			(xy 227.041885 -219.834204) (xy 226.99055 -219.826074) (xy 226.94112 -219.810013) (xy 226.89481 -219.786417)
			(xy 226.852762 -219.755867) (xy 226.816011 -219.719116) (xy 226.785461 -219.677068) (xy 226.761865 -219.630758)
			(xy 226.745804 -219.581328) (xy 226.737674 -219.529993) (xy 226.59797 -219.529993) (xy 226.58984 -219.581328)
			(xy 226.573779 -219.630758) (xy 226.550183 -219.677068) (xy 226.519633 -219.719116) (xy 226.482882 -219.755867)
			(xy 226.440834 -219.786417) (xy 226.394524 -219.810013) (xy 226.345094 -219.826074) (xy 226.293759 -219.834204)
			(xy 226.241785 -219.834204) (xy 226.19045 -219.826074) (xy 226.14102 -219.810013) (xy 226.09471 -219.786417)
			(xy 226.052662 -219.755867) (xy 226.015911 -219.719116) (xy 225.985361 -219.677068) (xy 225.961765 -219.630758)
			(xy 225.945704 -219.581328) (xy 225.937574 -219.529993) (xy 225.798124 -219.529993) (xy 225.789994 -219.581328)
			(xy 225.773933 -219.630758) (xy 225.750337 -219.677068) (xy 225.719787 -219.719116) (xy 225.683036 -219.755867)
			(xy 225.640988 -219.786417) (xy 225.594678 -219.810013) (xy 225.545248 -219.826074) (xy 225.493913 -219.834204)
			(xy 225.441939 -219.834204) (xy 225.390604 -219.826074) (xy 225.341174 -219.810013) (xy 225.294864 -219.786417)
			(xy 225.252816 -219.755867) (xy 225.216065 -219.719116) (xy 225.185515 -219.677068) (xy 225.161919 -219.630758)
			(xy 225.145858 -219.581328) (xy 225.137728 -219.529993) (xy 218.673273 -219.529993) (xy 218.663916 -219.548149)
			(xy 218.628035 -219.596906) (xy 218.606878 -219.61856) (xy 218.600274 -219.625164) (xy 218.596464 -219.6338)
			(xy 218.594582 -219.638155) (xy 218.59229 -219.64736) (xy 218.591892 -219.652088) (xy 218.588082 -219.72016)
			(xy 218.587923 -219.724794) (xy 218.589081 -219.733993) (xy 218.590368 -219.738448) (xy 218.593416 -219.747592)
			(xy 218.599512 -219.754958) (xy 218.615651 -219.775438) (xy 218.642748 -219.819987) (xy 218.663524 -219.867812)
			(xy 218.677592 -219.918021) (xy 218.684688 -219.969679) (xy 218.68511 -219.99575) (xy 218.684624 -220.023001)
			(xy 218.676868 -220.076949) (xy 218.661513 -220.129244) (xy 218.638871 -220.178821) (xy 218.609405 -220.224671)
			(xy 218.573714 -220.265862) (xy 218.532523 -220.301553) (xy 218.488509 -220.329839) (xy 223.537782 -220.329839)
			(xy 223.537782 -220.277865) (xy 223.545912 -220.22653) (xy 223.561973 -220.1771) (xy 223.585569 -220.13079)
			(xy 223.616119 -220.088742) (xy 223.65287 -220.051991) (xy 223.694918 -220.021441) (xy 223.741228 -219.997845)
			(xy 223.790658 -219.981784) (xy 223.841993 -219.973654) (xy 223.893967 -219.973654) (xy 223.945302 -219.981784)
			(xy 223.994732 -219.997845) (xy 224.041042 -220.021441) (xy 224.08309 -220.051991) (xy 224.119841 -220.088742)
			(xy 224.150391 -220.13079) (xy 224.173987 -220.1771) (xy 224.190048 -220.22653) (xy 224.198178 -220.277865)
			(xy 224.198688 -220.303852) (xy 224.198178 -220.329839) (xy 224.337628 -220.329839) (xy 224.337628 -220.277865)
			(xy 224.345758 -220.22653) (xy 224.361819 -220.1771) (xy 224.385415 -220.13079) (xy 224.415965 -220.088742)
			(xy 224.452716 -220.051991) (xy 224.494764 -220.021441) (xy 224.541074 -219.997845) (xy 224.590504 -219.981784)
			(xy 224.641839 -219.973654) (xy 224.693813 -219.973654) (xy 224.745148 -219.981784) (xy 224.794578 -219.997845)
			(xy 224.840888 -220.021441) (xy 224.882936 -220.051991) (xy 224.919687 -220.088742) (xy 224.950237 -220.13079)
			(xy 224.973833 -220.1771) (xy 224.989894 -220.22653) (xy 224.998024 -220.277865) (xy 224.998534 -220.303852)
			(xy 224.998024 -220.329839) (xy 225.937574 -220.329839) (xy 225.937574 -220.277865) (xy 225.945704 -220.22653)
			(xy 225.961765 -220.1771) (xy 225.985361 -220.13079) (xy 226.015911 -220.088742) (xy 226.052662 -220.051991)
			(xy 226.09471 -220.021441) (xy 226.14102 -219.997845) (xy 226.19045 -219.981784) (xy 226.241785 -219.973654)
			(xy 226.293759 -219.973654) (xy 226.345094 -219.981784) (xy 226.394524 -219.997845) (xy 226.440834 -220.021441)
			(xy 226.482882 -220.051991) (xy 226.519633 -220.088742) (xy 226.550183 -220.13079) (xy 226.573779 -220.1771)
			(xy 226.58984 -220.22653) (xy 226.59797 -220.277865) (xy 226.59848 -220.303852) (xy 226.59797 -220.329839)
			(xy 226.737674 -220.329839) (xy 226.737674 -220.277865) (xy 226.745804 -220.22653) (xy 226.761865 -220.1771)
			(xy 226.785461 -220.13079) (xy 226.816011 -220.088742) (xy 226.852762 -220.051991) (xy 226.89481 -220.021441)
			(xy 226.94112 -219.997845) (xy 226.99055 -219.981784) (xy 227.041885 -219.973654) (xy 227.093859 -219.973654)
			(xy 227.145194 -219.981784) (xy 227.194624 -219.997845) (xy 227.240934 -220.021441) (xy 227.282982 -220.051991)
			(xy 227.319733 -220.088742) (xy 227.350283 -220.13079) (xy 227.373879 -220.1771) (xy 227.38994 -220.22653)
			(xy 227.39807 -220.277865) (xy 227.39858 -220.303852) (xy 227.39807 -220.329839) (xy 227.537774 -220.329839)
			(xy 227.537774 -220.277865) (xy 227.545904 -220.22653) (xy 227.561965 -220.1771) (xy 227.585561 -220.13079)
			(xy 227.616111 -220.088742) (xy 227.652862 -220.051991) (xy 227.69491 -220.021441) (xy 227.74122 -219.997845)
			(xy 227.79065 -219.981784) (xy 227.841985 -219.973654) (xy 227.893959 -219.973654) (xy 227.945294 -219.981784)
			(xy 227.994724 -219.997845) (xy 228.041034 -220.021441) (xy 228.083082 -220.051991) (xy 228.119833 -220.088742)
			(xy 228.150383 -220.13079) (xy 228.173979 -220.1771) (xy 228.19004 -220.22653) (xy 228.19817 -220.277865)
			(xy 228.19868 -220.303852) (xy 228.19817 -220.329839) (xy 228.33762 -220.329839) (xy 228.33762 -220.277865)
			(xy 228.34575 -220.22653) (xy 228.361811 -220.1771) (xy 228.385407 -220.13079) (xy 228.415957 -220.088742)
			(xy 228.452708 -220.051991) (xy 228.494756 -220.021441) (xy 228.541066 -219.997845) (xy 228.590496 -219.981784)
			(xy 228.641831 -219.973654) (xy 228.693805 -219.973654) (xy 228.74514 -219.981784) (xy 228.79457 -219.997845)
			(xy 228.84088 -220.021441) (xy 228.882928 -220.051991) (xy 228.919679 -220.088742) (xy 228.950229 -220.13079)
			(xy 228.973825 -220.1771) (xy 228.989886 -220.22653) (xy 228.998016 -220.277865) (xy 228.998526 -220.303852)
			(xy 228.998016 -220.329839) (xy 229.937312 -220.329839) (xy 229.937312 -220.277865) (xy 229.945442 -220.22653)
			(xy 229.961503 -220.1771) (xy 229.985099 -220.13079) (xy 230.015649 -220.088742) (xy 230.0524 -220.051991)
			(xy 230.094448 -220.021441) (xy 230.140758 -219.997845) (xy 230.190188 -219.981784) (xy 230.241523 -219.973654)
			(xy 230.293497 -219.973654) (xy 230.344832 -219.981784) (xy 230.394262 -219.997845) (xy 230.440572 -220.021441)
			(xy 230.48262 -220.051991) (xy 230.519371 -220.088742) (xy 230.549921 -220.13079) (xy 230.573517 -220.1771)
			(xy 230.589578 -220.22653) (xy 230.597708 -220.277865) (xy 230.598218 -220.303852) (xy 230.597708 -220.329839)
			(xy 230.737158 -220.329839) (xy 230.737158 -220.277865) (xy 230.745288 -220.22653) (xy 230.761349 -220.1771)
			(xy 230.784945 -220.13079) (xy 230.815495 -220.088742) (xy 230.852246 -220.051991) (xy 230.894294 -220.021441)
			(xy 230.940604 -219.997845) (xy 230.990034 -219.981784) (xy 231.041369 -219.973654) (xy 231.093343 -219.973654)
			(xy 231.144678 -219.981784) (xy 231.194108 -219.997845) (xy 231.240418 -220.021441) (xy 231.282466 -220.051991)
			(xy 231.319217 -220.088742) (xy 231.349767 -220.13079) (xy 231.373363 -220.1771) (xy 231.389424 -220.22653)
			(xy 231.397554 -220.277865) (xy 231.398064 -220.303852) (xy 231.397554 -220.329839) (xy 231.537258 -220.329839)
			(xy 231.537258 -220.277865) (xy 231.545388 -220.22653) (xy 231.561449 -220.1771) (xy 231.585045 -220.13079)
			(xy 231.615595 -220.088742) (xy 231.652346 -220.051991) (xy 231.694394 -220.021441) (xy 231.740704 -219.997845)
			(xy 231.790134 -219.981784) (xy 231.841469 -219.973654) (xy 231.893443 -219.973654) (xy 231.944778 -219.981784)
			(xy 231.994208 -219.997845) (xy 232.040518 -220.021441) (xy 232.082566 -220.051991) (xy 232.119317 -220.088742)
			(xy 232.149867 -220.13079) (xy 232.173463 -220.1771) (xy 232.189524 -220.22653) (xy 232.197654 -220.277865)
			(xy 232.198164 -220.303852) (xy 232.197654 -220.329839) (xy 232.337358 -220.329839) (xy 232.337358 -220.277865)
			(xy 232.345488 -220.22653) (xy 232.361549 -220.1771) (xy 232.385145 -220.13079) (xy 232.415695 -220.088742)
			(xy 232.452446 -220.051991) (xy 232.494494 -220.021441) (xy 232.540804 -219.997845) (xy 232.590234 -219.981784)
			(xy 232.641569 -219.973654) (xy 232.693543 -219.973654) (xy 232.744878 -219.981784) (xy 232.794308 -219.997845)
			(xy 232.840618 -220.021441) (xy 232.882666 -220.051991) (xy 232.919417 -220.088742) (xy 232.949967 -220.13079)
			(xy 232.973563 -220.1771) (xy 232.989624 -220.22653) (xy 232.997754 -220.277865) (xy 232.998264 -220.303852)
			(xy 232.997754 -220.329839) (xy 233.137204 -220.329839) (xy 233.137204 -220.277865) (xy 233.145334 -220.22653)
			(xy 233.161395 -220.1771) (xy 233.184991 -220.13079) (xy 233.215541 -220.088742) (xy 233.252292 -220.051991)
			(xy 233.29434 -220.021441) (xy 233.34065 -219.997845) (xy 233.39008 -219.981784) (xy 233.441415 -219.973654)
			(xy 233.493389 -219.973654) (xy 233.544724 -219.981784) (xy 233.594154 -219.997845) (xy 233.640464 -220.021441)
			(xy 233.682512 -220.051991) (xy 233.719263 -220.088742) (xy 233.749813 -220.13079) (xy 233.773409 -220.1771)
			(xy 233.78947 -220.22653) (xy 233.7976 -220.277865) (xy 233.79811 -220.303852) (xy 233.7976 -220.329839)
			(xy 233.937304 -220.329839) (xy 233.937304 -220.277865) (xy 233.945434 -220.22653) (xy 233.961495 -220.1771)
			(xy 233.985091 -220.13079) (xy 234.015641 -220.088742) (xy 234.052392 -220.051991) (xy 234.09444 -220.021441)
			(xy 234.14075 -219.997845) (xy 234.19018 -219.981784) (xy 234.241515 -219.973654) (xy 234.293489 -219.973654)
			(xy 234.344824 -219.981784) (xy 234.394254 -219.997845) (xy 234.440564 -220.021441) (xy 234.482612 -220.051991)
			(xy 234.519363 -220.088742) (xy 234.549913 -220.13079) (xy 234.573509 -220.1771) (xy 234.58957 -220.22653)
			(xy 234.5977 -220.277865) (xy 234.59821 -220.303852) (xy 234.5977 -220.329839) (xy 234.73715 -220.329839)
			(xy 234.73715 -220.277865) (xy 234.74528 -220.22653) (xy 234.761341 -220.1771) (xy 234.784937 -220.13079)
			(xy 234.815487 -220.088742) (xy 234.852238 -220.051991) (xy 234.894286 -220.021441) (xy 234.940596 -219.997845)
			(xy 234.990026 -219.981784) (xy 235.041361 -219.973654) (xy 235.093335 -219.973654) (xy 235.14467 -219.981784)
			(xy 235.1941 -219.997845) (xy 235.24041 -220.021441) (xy 235.245253 -220.02496) (xy 240.991896 -220.02496)
			(xy 240.995967 -219.969338) (xy 241.008093 -219.914901) (xy 241.028016 -219.86281) (xy 241.055312 -219.814175)
			(xy 241.089398 -219.770032) (xy 241.129547 -219.731323) (xy 241.174905 -219.698872) (xy 241.224505 -219.673371)
			(xy 241.277289 -219.655364) (xy 241.332132 -219.645234) (xy 241.387866 -219.643197) (xy 241.443303 -219.649297)
			(xy 241.482155 -219.659454) (xy 245.44985 -219.659454) (xy 245.453921 -219.603832) (xy 245.466047 -219.549395)
			(xy 245.48597 -219.497304) (xy 245.513266 -219.448669) (xy 245.547352 -219.404526) (xy 245.587501 -219.365817)
			(xy 245.632859 -219.333366) (xy 245.682459 -219.307865) (xy 245.735243 -219.289858) (xy 245.790086 -219.279728)
			(xy 245.84582 -219.277691) (xy 245.901257 -219.283791) (xy 245.955214 -219.297897) (xy 246.006543 -219.319709)
			(xy 246.054149 -219.348763) (xy 246.097017 -219.384438) (xy 246.134234 -219.425975) (xy 246.165007 -219.472488)
			(xy 246.188679 -219.522985) (xy 246.204747 -219.576392) (xy 246.212867 -219.631568) (xy 246.213376 -219.659454)
			(xy 246.212867 -219.68734) (xy 246.204747 -219.742516) (xy 246.188679 -219.795923) (xy 246.165007 -219.84642)
			(xy 246.134234 -219.892933) (xy 246.097017 -219.93447) (xy 246.054149 -219.970145) (xy 246.006543 -219.999199)
			(xy 245.955214 -220.021011) (xy 245.901257 -220.035117) (xy 245.84582 -220.041217) (xy 245.790086 -220.03918)
			(xy 245.735243 -220.02905) (xy 245.682459 -220.011043) (xy 245.632859 -219.985542) (xy 245.587501 -219.953091)
			(xy 245.547352 -219.914382) (xy 245.513266 -219.870239) (xy 245.48597 -219.821604) (xy 245.466047 -219.769513)
			(xy 245.453921 -219.715076) (xy 245.44985 -219.659454) (xy 241.482155 -219.659454) (xy 241.49726 -219.663403)
			(xy 241.548589 -219.685215) (xy 241.596195 -219.714269) (xy 241.639063 -219.749944) (xy 241.67628 -219.791481)
			(xy 241.707053 -219.837994) (xy 241.730725 -219.888491) (xy 241.746793 -219.941898) (xy 241.754913 -219.997074)
			(xy 241.755422 -220.02496) (xy 241.754913 -220.052846) (xy 241.746793 -220.108022) (xy 241.730725 -220.161429)
			(xy 241.722066 -220.1799) (xy 242.275104 -220.1799) (xy 242.279175 -220.124278) (xy 242.291301 -220.069841)
			(xy 242.311224 -220.01775) (xy 242.33852 -219.969115) (xy 242.372606 -219.924972) (xy 242.412755 -219.886263)
			(xy 242.458113 -219.853812) (xy 242.507713 -219.828311) (xy 242.560497 -219.810304) (xy 242.61534 -219.800174)
			(xy 242.671074 -219.798137) (xy 242.726511 -219.804237) (xy 242.780468 -219.818343) (xy 242.831797 -219.840155)
			(xy 242.879403 -219.869209) (xy 242.922271 -219.904884) (xy 242.959488 -219.946421) (xy 242.990261 -219.992934)
			(xy 243.013933 -220.043431) (xy 243.030001 -220.096838) (xy 243.038121 -220.152014) (xy 243.03863 -220.1799)
			(xy 243.038121 -220.207786) (xy 243.030001 -220.262962) (xy 243.013933 -220.316369) (xy 242.990261 -220.366866)
			(xy 242.959488 -220.413379) (xy 242.922271 -220.454916) (xy 242.879403 -220.490591) (xy 242.831797 -220.519645)
			(xy 242.780468 -220.541457) (xy 242.726511 -220.555563) (xy 242.671074 -220.561663) (xy 242.61534 -220.559626)
			(xy 242.560497 -220.549496) (xy 242.507713 -220.531489) (xy 242.458113 -220.505988) (xy 242.412755 -220.473537)
			(xy 242.372606 -220.434828) (xy 242.33852 -220.390685) (xy 242.311224 -220.34205) (xy 242.291301 -220.289959)
			(xy 242.279175 -220.235522) (xy 242.275104 -220.1799) (xy 241.722066 -220.1799) (xy 241.707053 -220.211926)
			(xy 241.67628 -220.258439) (xy 241.639063 -220.299976) (xy 241.596195 -220.335651) (xy 241.548589 -220.364705)
			(xy 241.49726 -220.386517) (xy 241.443303 -220.400623) (xy 241.387866 -220.406723) (xy 241.332132 -220.404686)
			(xy 241.277289 -220.394556) (xy 241.224505 -220.376549) (xy 241.174905 -220.351048) (xy 241.129547 -220.318597)
			(xy 241.089398 -220.279888) (xy 241.055312 -220.235745) (xy 241.028016 -220.18711) (xy 241.008093 -220.135019)
			(xy 240.995967 -220.080582) (xy 240.991896 -220.02496) (xy 235.245253 -220.02496) (xy 235.282458 -220.051991)
			(xy 235.319209 -220.088742) (xy 235.349759 -220.13079) (xy 235.373355 -220.1771) (xy 235.389416 -220.22653)
			(xy 235.397546 -220.277865) (xy 235.398056 -220.303852) (xy 235.397546 -220.329839) (xy 235.389416 -220.381174)
			(xy 235.373355 -220.430604) (xy 235.349759 -220.476914) (xy 235.319209 -220.518962) (xy 235.282458 -220.555713)
			(xy 235.24041 -220.586263) (xy 235.1941 -220.609859) (xy 235.14467 -220.62592) (xy 235.093335 -220.63405)
			(xy 235.041361 -220.63405) (xy 234.990026 -220.62592) (xy 234.940596 -220.609859) (xy 234.894286 -220.586263)
			(xy 234.852238 -220.555713) (xy 234.815487 -220.518962) (xy 234.784937 -220.476914) (xy 234.761341 -220.430604)
			(xy 234.74528 -220.381174) (xy 234.73715 -220.329839) (xy 234.5977 -220.329839) (xy 234.58957 -220.381174)
			(xy 234.573509 -220.430604) (xy 234.549913 -220.476914) (xy 234.519363 -220.518962) (xy 234.482612 -220.555713)
			(xy 234.440564 -220.586263) (xy 234.394254 -220.609859) (xy 234.344824 -220.62592) (xy 234.293489 -220.63405)
			(xy 234.241515 -220.63405) (xy 234.19018 -220.62592) (xy 234.14075 -220.609859) (xy 234.09444 -220.586263)
			(xy 234.052392 -220.555713) (xy 234.015641 -220.518962) (xy 233.985091 -220.476914) (xy 233.961495 -220.430604)
			(xy 233.945434 -220.381174) (xy 233.937304 -220.329839) (xy 233.7976 -220.329839) (xy 233.78947 -220.381174)
			(xy 233.773409 -220.430604) (xy 233.749813 -220.476914) (xy 233.719263 -220.518962) (xy 233.682512 -220.555713)
			(xy 233.640464 -220.586263) (xy 233.594154 -220.609859) (xy 233.544724 -220.62592) (xy 233.493389 -220.63405)
			(xy 233.441415 -220.63405) (xy 233.39008 -220.62592) (xy 233.34065 -220.609859) (xy 233.29434 -220.586263)
			(xy 233.252292 -220.555713) (xy 233.215541 -220.518962) (xy 233.184991 -220.476914) (xy 233.161395 -220.430604)
			(xy 233.145334 -220.381174) (xy 233.137204 -220.329839) (xy 232.997754 -220.329839) (xy 232.989624 -220.381174)
			(xy 232.973563 -220.430604) (xy 232.949967 -220.476914) (xy 232.919417 -220.518962) (xy 232.882666 -220.555713)
			(xy 232.840618 -220.586263) (xy 232.794308 -220.609859) (xy 232.744878 -220.62592) (xy 232.693543 -220.63405)
			(xy 232.641569 -220.63405) (xy 232.590234 -220.62592) (xy 232.540804 -220.609859) (xy 232.494494 -220.586263)
			(xy 232.452446 -220.555713) (xy 232.415695 -220.518962) (xy 232.385145 -220.476914) (xy 232.361549 -220.430604)
			(xy 232.345488 -220.381174) (xy 232.337358 -220.329839) (xy 232.197654 -220.329839) (xy 232.189524 -220.381174)
			(xy 232.173463 -220.430604) (xy 232.149867 -220.476914) (xy 232.119317 -220.518962) (xy 232.082566 -220.555713)
			(xy 232.040518 -220.586263) (xy 231.994208 -220.609859) (xy 231.944778 -220.62592) (xy 231.893443 -220.63405)
			(xy 231.841469 -220.63405) (xy 231.790134 -220.62592) (xy 231.740704 -220.609859) (xy 231.694394 -220.586263)
			(xy 231.652346 -220.555713) (xy 231.615595 -220.518962) (xy 231.585045 -220.476914) (xy 231.561449 -220.430604)
			(xy 231.545388 -220.381174) (xy 231.537258 -220.329839) (xy 231.397554 -220.329839) (xy 231.389424 -220.381174)
			(xy 231.373363 -220.430604) (xy 231.349767 -220.476914) (xy 231.319217 -220.518962) (xy 231.282466 -220.555713)
			(xy 231.240418 -220.586263) (xy 231.194108 -220.609859) (xy 231.144678 -220.62592) (xy 231.093343 -220.63405)
			(xy 231.041369 -220.63405) (xy 230.990034 -220.62592) (xy 230.940604 -220.609859) (xy 230.894294 -220.586263)
			(xy 230.852246 -220.555713) (xy 230.815495 -220.518962) (xy 230.784945 -220.476914) (xy 230.761349 -220.430604)
			(xy 230.745288 -220.381174) (xy 230.737158 -220.329839) (xy 230.597708 -220.329839) (xy 230.589578 -220.381174)
			(xy 230.573517 -220.430604) (xy 230.549921 -220.476914) (xy 230.519371 -220.518962) (xy 230.48262 -220.555713)
			(xy 230.440572 -220.586263) (xy 230.394262 -220.609859) (xy 230.344832 -220.62592) (xy 230.293497 -220.63405)
			(xy 230.241523 -220.63405) (xy 230.190188 -220.62592) (xy 230.140758 -220.609859) (xy 230.094448 -220.586263)
			(xy 230.0524 -220.555713) (xy 230.015649 -220.518962) (xy 229.985099 -220.476914) (xy 229.961503 -220.430604)
			(xy 229.945442 -220.381174) (xy 229.937312 -220.329839) (xy 228.998016 -220.329839) (xy 228.989886 -220.381174)
			(xy 228.973825 -220.430604) (xy 228.950229 -220.476914) (xy 228.919679 -220.518962) (xy 228.882928 -220.555713)
			(xy 228.84088 -220.586263) (xy 228.79457 -220.609859) (xy 228.74514 -220.62592) (xy 228.693805 -220.63405)
			(xy 228.641831 -220.63405) (xy 228.590496 -220.62592) (xy 228.541066 -220.609859) (xy 228.494756 -220.586263)
			(xy 228.452708 -220.555713) (xy 228.415957 -220.518962) (xy 228.385407 -220.476914) (xy 228.361811 -220.430604)
			(xy 228.34575 -220.381174) (xy 228.33762 -220.329839) (xy 228.19817 -220.329839) (xy 228.19004 -220.381174)
			(xy 228.173979 -220.430604) (xy 228.150383 -220.476914) (xy 228.119833 -220.518962) (xy 228.083082 -220.555713)
			(xy 228.041034 -220.586263) (xy 227.994724 -220.609859) (xy 227.945294 -220.62592) (xy 227.893959 -220.63405)
			(xy 227.841985 -220.63405) (xy 227.79065 -220.62592) (xy 227.74122 -220.609859) (xy 227.69491 -220.586263)
			(xy 227.652862 -220.555713) (xy 227.616111 -220.518962) (xy 227.585561 -220.476914) (xy 227.561965 -220.430604)
			(xy 227.545904 -220.381174) (xy 227.537774 -220.329839) (xy 227.39807 -220.329839) (xy 227.38994 -220.381174)
			(xy 227.373879 -220.430604) (xy 227.350283 -220.476914) (xy 227.319733 -220.518962) (xy 227.282982 -220.555713)
			(xy 227.240934 -220.586263) (xy 227.194624 -220.609859) (xy 227.145194 -220.62592) (xy 227.093859 -220.63405)
			(xy 227.041885 -220.63405) (xy 226.99055 -220.62592) (xy 226.94112 -220.609859) (xy 226.89481 -220.586263)
			(xy 226.852762 -220.555713) (xy 226.816011 -220.518962) (xy 226.785461 -220.476914) (xy 226.761865 -220.430604)
			(xy 226.745804 -220.381174) (xy 226.737674 -220.329839) (xy 226.59797 -220.329839) (xy 226.58984 -220.381174)
			(xy 226.573779 -220.430604) (xy 226.550183 -220.476914) (xy 226.519633 -220.518962) (xy 226.482882 -220.555713)
			(xy 226.440834 -220.586263) (xy 226.394524 -220.609859) (xy 226.345094 -220.62592) (xy 226.293759 -220.63405)
			(xy 226.241785 -220.63405) (xy 226.19045 -220.62592) (xy 226.14102 -220.609859) (xy 226.09471 -220.586263)
			(xy 226.052662 -220.555713) (xy 226.015911 -220.518962) (xy 225.985361 -220.476914) (xy 225.961765 -220.430604)
			(xy 225.945704 -220.381174) (xy 225.937574 -220.329839) (xy 224.998024 -220.329839) (xy 224.989894 -220.381174)
			(xy 224.973833 -220.430604) (xy 224.950237 -220.476914) (xy 224.919687 -220.518962) (xy 224.882936 -220.555713)
			(xy 224.840888 -220.586263) (xy 224.794578 -220.609859) (xy 224.745148 -220.62592) (xy 224.693813 -220.63405)
			(xy 224.641839 -220.63405) (xy 224.590504 -220.62592) (xy 224.541074 -220.609859) (xy 224.494764 -220.586263)
			(xy 224.452716 -220.555713) (xy 224.415965 -220.518962) (xy 224.385415 -220.476914) (xy 224.361819 -220.430604)
			(xy 224.345758 -220.381174) (xy 224.337628 -220.329839) (xy 224.198178 -220.329839) (xy 224.190048 -220.381174)
			(xy 224.173987 -220.430604) (xy 224.150391 -220.476914) (xy 224.119841 -220.518962) (xy 224.08309 -220.555713)
			(xy 224.041042 -220.586263) (xy 223.994732 -220.609859) (xy 223.945302 -220.62592) (xy 223.893967 -220.63405)
			(xy 223.841993 -220.63405) (xy 223.790658 -220.62592) (xy 223.741228 -220.609859) (xy 223.694918 -220.586263)
			(xy 223.65287 -220.555713) (xy 223.616119 -220.518962) (xy 223.585569 -220.476914) (xy 223.561973 -220.430604)
			(xy 223.545912 -220.381174) (xy 223.537782 -220.329839) (xy 218.488509 -220.329839) (xy 218.486673 -220.331019)
			(xy 218.437096 -220.353661) (xy 218.384801 -220.369016) (xy 218.330853 -220.376772) (xy 218.276351 -220.376772)
			(xy 218.222403 -220.369016) (xy 218.170108 -220.353661) (xy 218.120531 -220.331019) (xy 218.074681 -220.301553)
			(xy 218.03349 -220.265862) (xy 217.997799 -220.224671) (xy 217.968333 -220.178821) (xy 217.945691 -220.129244)
			(xy 217.930336 -220.076949) (xy 217.92258 -220.023001) (xy 217.922094 -219.99575) (xy 216.375893 -219.99575)
			(xy 216.383786 -219.999355) (xy 216.42963 -220.028821) (xy 216.470814 -220.064511) (xy 216.5065 -220.105699)
			(xy 216.535962 -220.151546) (xy 216.5586 -220.201119) (xy 216.573953 -220.253409) (xy 216.581708 -220.307351)
			(xy 216.581708 -220.361849) (xy 216.573953 -220.415791) (xy 216.5586 -220.468081) (xy 216.535962 -220.517654)
			(xy 216.5065 -220.563501) (xy 216.470814 -220.604689) (xy 216.42963 -220.640379) (xy 216.383786 -220.669845)
			(xy 216.334215 -220.692487) (xy 216.281926 -220.707845) (xy 216.227985 -220.715605) (xy 216.200736 -220.716094)
			(xy 216.200482 -220.716094) (xy 216.174187 -220.715649) (xy 216.122097 -220.708401) (xy 216.071496 -220.694073)
			(xy 216.023339 -220.672935) (xy 215.97854 -220.645387) (xy 215.937946 -220.611952) (xy 215.919812 -220.592904)
			(xy 215.912287 -220.585506) (xy 215.89301 -220.57698) (xy 215.882474 -220.576394) (xy 215.807798 -220.576394)
			(xy 215.797247 -220.57691) (xy 215.777952 -220.585455) (xy 215.77046 -220.592904) (xy 215.752361 -220.611989)
			(xy 215.711772 -220.645443) (xy 215.66697 -220.672998) (xy 215.618804 -220.694132) (xy 215.56819 -220.708443)
			(xy 215.516089 -220.71566) (xy 215.48979 -220.716094) (xy 215.489536 -220.716094) (xy 215.460619 -220.715563)
			(xy 215.403447 -220.706832) (xy 215.34825 -220.689564) (xy 215.296295 -220.664157) (xy 215.248774 -220.631193)
			(xy 215.227408 -220.6117) (xy 215.220296 -220.605096) (xy 215.211406 -220.60154) (xy 215.207085 -220.599852)
			(xy 215.198007 -220.597943) (xy 215.193372 -220.59773) (xy 215.125046 -220.596714) (xy 215.120318 -220.596737)
			(xy 215.110988 -220.598264) (xy 215.106504 -220.599762) (xy 215.097614 -220.603064) (xy 215.090502 -220.60916)
			(xy 215.069508 -220.627035) (xy 215.023315 -220.657143) (xy 214.97327 -220.68029) (xy 214.920415 -220.695993)
			(xy 214.865849 -220.703926) (xy 214.83828 -220.70441) (xy 214.81103 -220.703919) (xy 214.757085 -220.69616)
			(xy 214.704792 -220.680803) (xy 214.655218 -220.658161) (xy 214.60937 -220.628694) (xy 214.568183 -220.593003)
			(xy 214.532494 -220.551814) (xy 214.503029 -220.505964) (xy 214.48039 -220.456389) (xy 214.465036 -220.404096)
			(xy 214.45728 -220.35015) (xy 212.978757 -220.35015) (xy 212.978745 -220.350788) (xy 212.970625 -220.405964)
			(xy 212.954557 -220.459371) (xy 212.930885 -220.509868) (xy 212.900112 -220.556381) (xy 212.862895 -220.597918)
			(xy 212.820027 -220.633593) (xy 212.772421 -220.662647) (xy 212.721092 -220.684459) (xy 212.667135 -220.698565)
			(xy 212.611698 -220.704665) (xy 212.555964 -220.702628) (xy 212.501121 -220.692498) (xy 212.448337 -220.674491)
			(xy 212.398737 -220.64899) (xy 212.353379 -220.616539) (xy 212.31323 -220.57783) (xy 212.279144 -220.533687)
			(xy 212.251848 -220.485052) (xy 212.231925 -220.432961) (xy 212.219799 -220.378524) (xy 212.215728 -220.322902)
			(xy 209.476602 -220.322902) (xy 209.48239 -220.362498) (xy 209.482944 -220.389704) (xy 209.483342 -220.403251)
			(xy 209.490523 -220.429379) (xy 209.504324 -220.452697) (xy 209.523773 -220.471563) (xy 209.547501 -220.484648)
			(xy 209.573835 -220.49103) (xy 209.60092 -220.490259) (xy 209.614008 -220.486732) (xy 209.64093 -220.479127)
			(xy 209.696273 -220.470967) (xy 209.724244 -220.470476) (xy 209.751492 -220.470997) (xy 209.805433 -220.478759)
			(xy 209.85772 -220.494117) (xy 209.907289 -220.516759) (xy 209.953132 -220.546226) (xy 209.994316 -220.581916)
			(xy 210.030001 -220.623103) (xy 210.059462 -220.668949) (xy 210.082099 -220.718521) (xy 210.097451 -220.77081)
			(xy 210.105206 -220.824752) (xy 210.105206 -220.879248) (xy 210.097451 -220.93319) (xy 210.082099 -220.985479)
			(xy 210.059462 -221.035051) (xy 210.030001 -221.080897) (xy 209.994316 -221.122084) (xy 209.953132 -221.157774)
			(xy 209.907289 -221.187241) (xy 209.85772 -221.209883) (xy 209.805433 -221.225241) (xy 209.751492 -221.233003)
			(xy 209.724244 -221.233492) (xy 209.697039 -221.232985) (xy 209.643181 -221.225261) (xy 209.590966 -221.209961)
			(xy 209.541456 -221.187398) (xy 209.495653 -221.158029) (xy 209.454489 -221.12245) (xy 209.418797 -221.081383)
			(xy 209.389303 -221.035661) (xy 209.366605 -220.986213) (xy 209.351163 -220.93404) (xy 209.34329 -220.880203)
			(xy 209.342736 -220.853) (xy 209.342233 -220.839461) (xy 209.33506 -220.81335) (xy 209.321273 -220.790043)
			(xy 209.301843 -220.771183) (xy 209.278136 -220.758096) (xy 209.251822 -220.751703) (xy 209.224754 -220.752456)
			(xy 209.211672 -220.755972) (xy 209.184751 -220.763581) (xy 209.129407 -220.771738) (xy 209.101436 -220.772228)
			(xy 209.074183 -220.771727) (xy 209.020231 -220.763975) (xy 208.967931 -220.748623) (xy 208.918349 -220.725983)
			(xy 208.872494 -220.696518) (xy 208.831299 -220.660826) (xy 208.795604 -220.619635) (xy 208.766134 -220.573782)
			(xy 208.74349 -220.524202) (xy 208.728133 -220.471904) (xy 208.720375 -220.417953) (xy 196.968618 -220.417953)
			(xy 196.968618 -221.377856) (xy 215.108441 -221.377856) (xy 215.108441 -221.323344) (xy 215.116199 -221.269388)
			(xy 215.131558 -221.217086) (xy 215.154204 -221.167501) (xy 215.183676 -221.121645) (xy 215.219375 -221.080449)
			(xy 215.260574 -221.044754) (xy 215.306433 -221.015286) (xy 215.356019 -220.992645) (xy 215.408324 -220.977292)
			(xy 215.46228 -220.969538) (xy 215.489536 -220.969078) (xy 215.48979 -220.969078) (xy 215.516084 -220.96955)
			(xy 215.568172 -220.976794) (xy 215.618773 -220.991118) (xy 215.666929 -221.012251) (xy 215.711729 -221.039793)
			(xy 215.752325 -221.073223) (xy 215.77046 -221.092268) (xy 215.777999 -221.099649) (xy 215.797266 -221.108187)
			(xy 215.807798 -221.108778) (xy 215.882474 -221.108778) (xy 215.893025 -221.108255) (xy 215.91232 -221.099716)
			(xy 215.919812 -221.092268) (xy 215.937939 -221.07321) (xy 215.97852 -221.039752) (xy 216.023316 -221.012191)
			(xy 216.071477 -220.991051) (xy 216.122086 -220.976735) (xy 216.174184 -220.969514) (xy 216.200482 -220.969078)
			(xy 216.200736 -220.969078) (xy 216.227985 -220.969595) (xy 216.281926 -220.977355) (xy 216.334215 -220.992713)
			(xy 216.383786 -221.015355) (xy 216.42963 -221.044821) (xy 216.470814 -221.080511) (xy 216.5065 -221.121699)
			(xy 216.511795 -221.129939) (xy 223.537782 -221.129939) (xy 223.537782 -221.077965) (xy 223.545912 -221.02663)
			(xy 223.561973 -220.9772) (xy 223.585569 -220.93089) (xy 223.616119 -220.888842) (xy 223.65287 -220.852091)
			(xy 223.694918 -220.821541) (xy 223.741228 -220.797945) (xy 223.790658 -220.781884) (xy 223.841993 -220.773754)
			(xy 223.893967 -220.773754) (xy 223.945302 -220.781884) (xy 223.994732 -220.797945) (xy 224.041042 -220.821541)
			(xy 224.08309 -220.852091) (xy 224.119841 -220.888842) (xy 224.150391 -220.93089) (xy 224.173987 -220.9772)
			(xy 224.190048 -221.02663) (xy 224.198178 -221.077965) (xy 224.198688 -221.103952) (xy 224.198178 -221.129939)
			(xy 224.337628 -221.129939) (xy 224.337628 -221.077965) (xy 224.345758 -221.02663) (xy 224.361819 -220.9772)
			(xy 224.385415 -220.93089) (xy 224.415965 -220.888842) (xy 224.452716 -220.852091) (xy 224.494764 -220.821541)
			(xy 224.541074 -220.797945) (xy 224.590504 -220.781884) (xy 224.641839 -220.773754) (xy 224.693813 -220.773754)
			(xy 224.745148 -220.781884) (xy 224.794578 -220.797945) (xy 224.840888 -220.821541) (xy 224.882936 -220.852091)
			(xy 224.919687 -220.888842) (xy 224.950237 -220.93089) (xy 224.973833 -220.9772) (xy 224.989894 -221.02663)
			(xy 224.998024 -221.077965) (xy 224.998534 -221.103952) (xy 224.998024 -221.129939) (xy 226.737674 -221.129939)
			(xy 226.737674 -221.077965) (xy 226.745804 -221.02663) (xy 226.761865 -220.9772) (xy 226.785461 -220.93089)
			(xy 226.816011 -220.888842) (xy 226.852762 -220.852091) (xy 226.89481 -220.821541) (xy 226.94112 -220.797945)
			(xy 226.99055 -220.781884) (xy 227.041885 -220.773754) (xy 227.093859 -220.773754) (xy 227.145194 -220.781884)
			(xy 227.194624 -220.797945) (xy 227.240934 -220.821541) (xy 227.282982 -220.852091) (xy 227.319733 -220.888842)
			(xy 227.350283 -220.93089) (xy 227.373879 -220.9772) (xy 227.38994 -221.02663) (xy 227.39807 -221.077965)
			(xy 227.39858 -221.103952) (xy 227.39807 -221.129939) (xy 227.537774 -221.129939) (xy 227.537774 -221.077965)
			(xy 227.545904 -221.02663) (xy 227.561965 -220.9772) (xy 227.585561 -220.93089) (xy 227.616111 -220.888842)
			(xy 227.652862 -220.852091) (xy 227.69491 -220.821541) (xy 227.74122 -220.797945) (xy 227.79065 -220.781884)
			(xy 227.841985 -220.773754) (xy 227.893959 -220.773754) (xy 227.945294 -220.781884) (xy 227.994724 -220.797945)
			(xy 228.041034 -220.821541) (xy 228.083082 -220.852091) (xy 228.119833 -220.888842) (xy 228.150383 -220.93089)
			(xy 228.173979 -220.9772) (xy 228.19004 -221.02663) (xy 228.19817 -221.077965) (xy 228.19868 -221.103952)
			(xy 228.19817 -221.129939) (xy 228.33762 -221.129939) (xy 228.33762 -221.077965) (xy 228.34575 -221.02663)
			(xy 228.361811 -220.9772) (xy 228.385407 -220.93089) (xy 228.415957 -220.888842) (xy 228.452708 -220.852091)
			(xy 228.494756 -220.821541) (xy 228.541066 -220.797945) (xy 228.590496 -220.781884) (xy 228.641831 -220.773754)
			(xy 228.693805 -220.773754) (xy 228.74514 -220.781884) (xy 228.79457 -220.797945) (xy 228.84088 -220.821541)
			(xy 228.882928 -220.852091) (xy 228.919679 -220.888842) (xy 228.950229 -220.93089) (xy 228.973825 -220.9772)
			(xy 228.989886 -221.02663) (xy 228.998016 -221.077965) (xy 228.998526 -221.103952) (xy 228.998016 -221.129939)
			(xy 229.937312 -221.129939) (xy 229.937312 -221.077965) (xy 229.945442 -221.02663) (xy 229.961503 -220.9772)
			(xy 229.985099 -220.93089) (xy 230.015649 -220.888842) (xy 230.0524 -220.852091) (xy 230.094448 -220.821541)
			(xy 230.140758 -220.797945) (xy 230.190188 -220.781884) (xy 230.241523 -220.773754) (xy 230.293497 -220.773754)
			(xy 230.344832 -220.781884) (xy 230.394262 -220.797945) (xy 230.440572 -220.821541) (xy 230.48262 -220.852091)
			(xy 230.519371 -220.888842) (xy 230.549921 -220.93089) (xy 230.573517 -220.9772) (xy 230.589578 -221.02663)
			(xy 230.597708 -221.077965) (xy 230.598218 -221.103952) (xy 230.597708 -221.129939) (xy 230.737158 -221.129939)
			(xy 230.737158 -221.077965) (xy 230.745288 -221.02663) (xy 230.761349 -220.9772) (xy 230.784945 -220.93089)
			(xy 230.815495 -220.888842) (xy 230.852246 -220.852091) (xy 230.894294 -220.821541) (xy 230.940604 -220.797945)
			(xy 230.990034 -220.781884) (xy 231.041369 -220.773754) (xy 231.093343 -220.773754) (xy 231.144678 -220.781884)
			(xy 231.194108 -220.797945) (xy 231.240418 -220.821541) (xy 231.282466 -220.852091) (xy 231.319217 -220.888842)
			(xy 231.349767 -220.93089) (xy 231.373363 -220.9772) (xy 231.389424 -221.02663) (xy 231.397554 -221.077965)
			(xy 231.398064 -221.103952) (xy 231.397554 -221.129939) (xy 231.537258 -221.129939) (xy 231.537258 -221.077965)
			(xy 231.545388 -221.02663) (xy 231.561449 -220.9772) (xy 231.585045 -220.93089) (xy 231.615595 -220.888842)
			(xy 231.652346 -220.852091) (xy 231.694394 -220.821541) (xy 231.740704 -220.797945) (xy 231.790134 -220.781884)
			(xy 231.841469 -220.773754) (xy 231.893443 -220.773754) (xy 231.944778 -220.781884) (xy 231.994208 -220.797945)
			(xy 232.040518 -220.821541) (xy 232.082566 -220.852091) (xy 232.119317 -220.888842) (xy 232.149867 -220.93089)
			(xy 232.173463 -220.9772) (xy 232.189524 -221.02663) (xy 232.197654 -221.077965) (xy 232.198164 -221.103952)
			(xy 232.197654 -221.129939) (xy 233.137204 -221.129939) (xy 233.137204 -221.077965) (xy 233.145334 -221.02663)
			(xy 233.161395 -220.9772) (xy 233.184991 -220.93089) (xy 233.215541 -220.888842) (xy 233.252292 -220.852091)
			(xy 233.29434 -220.821541) (xy 233.34065 -220.797945) (xy 233.39008 -220.781884) (xy 233.441415 -220.773754)
			(xy 233.493389 -220.773754) (xy 233.544724 -220.781884) (xy 233.594154 -220.797945) (xy 233.640464 -220.821541)
			(xy 233.682512 -220.852091) (xy 233.719263 -220.888842) (xy 233.749813 -220.93089) (xy 233.773409 -220.9772)
			(xy 233.78947 -221.02663) (xy 233.7976 -221.077965) (xy 233.79811 -221.103952) (xy 233.7976 -221.129939)
			(xy 233.937304 -221.129939) (xy 233.937304 -221.077965) (xy 233.945434 -221.02663) (xy 233.961495 -220.9772)
			(xy 233.985091 -220.93089) (xy 234.015641 -220.888842) (xy 234.052392 -220.852091) (xy 234.09444 -220.821541)
			(xy 234.14075 -220.797945) (xy 234.19018 -220.781884) (xy 234.241515 -220.773754) (xy 234.293489 -220.773754)
			(xy 234.344824 -220.781884) (xy 234.394254 -220.797945) (xy 234.440564 -220.821541) (xy 234.482612 -220.852091)
			(xy 234.519363 -220.888842) (xy 234.549913 -220.93089) (xy 234.573509 -220.9772) (xy 234.58957 -221.02663)
			(xy 234.5977 -221.077965) (xy 234.59821 -221.103952) (xy 234.5977 -221.129939) (xy 234.73715 -221.129939)
			(xy 234.73715 -221.077965) (xy 234.74528 -221.02663) (xy 234.761341 -220.9772) (xy 234.784937 -220.93089)
			(xy 234.815487 -220.888842) (xy 234.852238 -220.852091) (xy 234.894286 -220.821541) (xy 234.940596 -220.797945)
			(xy 234.990026 -220.781884) (xy 235.041361 -220.773754) (xy 235.093335 -220.773754) (xy 235.14467 -220.781884)
			(xy 235.1941 -220.797945) (xy 235.24041 -220.821541) (xy 235.282458 -220.852091) (xy 235.319209 -220.888842)
			(xy 235.349759 -220.93089) (xy 235.373355 -220.9772) (xy 235.389416 -221.02663) (xy 235.397546 -221.077965)
			(xy 235.398056 -221.103952) (xy 235.397546 -221.129939) (xy 235.53725 -221.129939) (xy 235.53725 -221.077965)
			(xy 235.54538 -221.02663) (xy 235.561441 -220.9772) (xy 235.585037 -220.93089) (xy 235.615587 -220.888842)
			(xy 235.652338 -220.852091) (xy 235.694386 -220.821541) (xy 235.740696 -220.797945) (xy 235.790126 -220.781884)
			(xy 235.841461 -220.773754) (xy 235.893435 -220.773754) (xy 235.94477 -220.781884) (xy 235.9942 -220.797945)
			(xy 236.04051 -220.821541) (xy 236.082558 -220.852091) (xy 236.119309 -220.888842) (xy 236.149859 -220.93089)
			(xy 236.173455 -220.9772) (xy 236.189516 -221.02663) (xy 236.197646 -221.077965) (xy 236.198156 -221.103952)
			(xy 236.197646 -221.129939) (xy 236.189516 -221.181274) (xy 236.173455 -221.230704) (xy 236.149859 -221.277014)
			(xy 236.119309 -221.319062) (xy 236.082558 -221.355813) (xy 236.04051 -221.386363) (xy 235.9942 -221.409959)
			(xy 235.962516 -221.420254) (xy 236.427959 -221.420254) (xy 236.427959 -221.365746) (xy 236.435717 -221.311794)
			(xy 236.451074 -221.259494) (xy 236.473718 -221.209913) (xy 236.503188 -221.164059) (xy 236.538885 -221.122866)
			(xy 236.58008 -221.087173) (xy 236.625936 -221.057706) (xy 236.675519 -221.035065) (xy 236.727819 -221.019711)
			(xy 236.781772 -221.011958) (xy 236.809026 -221.011496) (xy 236.839365 -221.012104) (xy 236.899276 -221.02171)
			(xy 236.956913 -221.040677) (xy 237.010822 -221.068526) (xy 237.059644 -221.104555) (xy 237.081314 -221.125796)
			(xy 237.088172 -221.132908) (xy 237.097062 -221.136718) (xy 237.101487 -221.138561) (xy 237.11082 -221.140735)
			(xy 237.115604 -221.141036) (xy 237.1852 -221.14383) (xy 237.192058 -221.143576) (xy 237.203996 -221.141036)
			(xy 237.213394 -221.137734) (xy 237.22076 -221.131384) (xy 237.241702 -221.113701) (xy 237.287705 -221.083906)
			(xy 237.337501 -221.061005) (xy 237.390063 -221.045471) (xy 237.444307 -221.037624) (xy 237.471712 -221.03715)
			(xy 237.49896 -221.037721) (xy 237.521483 -221.04096) (xy 240.991896 -221.04096) (xy 240.995967 -220.985338)
			(xy 241.008093 -220.930901) (xy 241.028016 -220.87881) (xy 241.055312 -220.830175) (xy 241.089398 -220.786032)
			(xy 241.129547 -220.747323) (xy 241.174905 -220.714872) (xy 241.224505 -220.689371) (xy 241.277289 -220.671364)
			(xy 241.332132 -220.661234) (xy 241.387866 -220.659197) (xy 241.443303 -220.665297) (xy 241.49726 -220.679403)
			(xy 241.548589 -220.701215) (xy 241.577131 -220.718634) (xy 245.365522 -220.718634) (xy 245.369593 -220.663012)
			(xy 245.381719 -220.608575) (xy 245.401642 -220.556484) (xy 245.428938 -220.507849) (xy 245.463024 -220.463706)
			(xy 245.503173 -220.424997) (xy 245.548531 -220.392546) (xy 245.598131 -220.367045) (xy 245.650915 -220.349038)
			(xy 245.705758 -220.338908) (xy 245.761492 -220.336871) (xy 245.816929 -220.342971) (xy 245.870886 -220.357077)
			(xy 245.922215 -220.378889) (xy 245.969821 -220.407943) (xy 246.012689 -220.443618) (xy 246.049906 -220.485155)
			(xy 246.080679 -220.531668) (xy 246.104351 -220.582165) (xy 246.120419 -220.635572) (xy 246.128539 -220.690748)
			(xy 246.129048 -220.718634) (xy 246.128539 -220.74652) (xy 246.120419 -220.801696) (xy 246.104351 -220.855103)
			(xy 246.080679 -220.9056) (xy 246.049906 -220.952113) (xy 246.012689 -220.99365) (xy 245.969821 -221.029325)
			(xy 245.922215 -221.058379) (xy 245.870886 -221.080191) (xy 245.816929 -221.094297) (xy 245.761492 -221.100397)
			(xy 245.705758 -221.09836) (xy 245.650915 -221.08823) (xy 245.598131 -221.070223) (xy 245.548531 -221.044722)
			(xy 245.503173 -221.012271) (xy 245.463024 -220.973562) (xy 245.428938 -220.929419) (xy 245.401642 -220.880784)
			(xy 245.381719 -220.828693) (xy 245.369593 -220.774256) (xy 245.365522 -220.718634) (xy 241.577131 -220.718634)
			(xy 241.596195 -220.730269) (xy 241.639063 -220.765944) (xy 241.67628 -220.807481) (xy 241.707053 -220.853994)
			(xy 241.730725 -220.904491) (xy 241.746793 -220.957898) (xy 241.754913 -221.013074) (xy 241.755422 -221.04096)
			(xy 241.754913 -221.068846) (xy 241.746793 -221.124022) (xy 241.730725 -221.177429) (xy 241.707053 -221.227926)
			(xy 241.67628 -221.274439) (xy 241.639063 -221.315976) (xy 241.596195 -221.351651) (xy 241.548589 -221.380705)
			(xy 241.49726 -221.402517) (xy 241.443303 -221.416623) (xy 241.387866 -221.422723) (xy 241.332132 -221.420686)
			(xy 241.277289 -221.410556) (xy 241.224505 -221.392549) (xy 241.174905 -221.367048) (xy 241.129547 -221.334597)
			(xy 241.089398 -221.295888) (xy 241.055312 -221.251745) (xy 241.028016 -221.20311) (xy 241.008093 -221.151019)
			(xy 240.995967 -221.096582) (xy 240.991896 -221.04096) (xy 237.521483 -221.04096) (xy 237.5529 -221.045478)
			(xy 237.605188 -221.060832) (xy 237.654758 -221.083472) (xy 237.700602 -221.112935) (xy 237.741786 -221.148623)
			(xy 237.777472 -221.189808) (xy 237.806934 -221.235653) (xy 237.829572 -221.285224) (xy 237.844925 -221.337512)
			(xy 237.85268 -221.391452) (xy 237.85268 -221.445948) (xy 237.844925 -221.499888) (xy 237.829572 -221.552176)
			(xy 237.806934 -221.601747) (xy 237.777472 -221.647592) (xy 237.741786 -221.688777) (xy 237.700602 -221.724465)
			(xy 237.654758 -221.753928) (xy 237.605188 -221.776568) (xy 237.5529 -221.791922) (xy 237.49896 -221.799679)
			(xy 237.471712 -221.800166) (xy 237.441374 -221.799546) (xy 237.381462 -221.789944) (xy 237.323825 -221.770981)
			(xy 237.269916 -221.743134) (xy 237.221094 -221.707106) (xy 237.199424 -221.685866) (xy 237.192566 -221.678754)
			(xy 237.183676 -221.674944) (xy 237.179248 -221.673109) (xy 237.169917 -221.67093) (xy 237.165134 -221.670626)
			(xy 237.095538 -221.667832) (xy 237.08868 -221.668086) (xy 237.076742 -221.670626) (xy 237.067344 -221.673928)
			(xy 237.059978 -221.680278) (xy 237.03903 -221.697953) (xy 236.993028 -221.727747) (xy 236.943233 -221.750649)
			(xy 236.890673 -221.766185) (xy 236.83643 -221.774035) (xy 236.809026 -221.774512) (xy 236.781772 -221.774042)
			(xy 236.727819 -221.766289) (xy 236.675519 -221.750935) (xy 236.625936 -221.728294) (xy 236.58008 -221.698827)
			(xy 236.538885 -221.663134) (xy 236.503188 -221.621941) (xy 236.473718 -221.576087) (xy 236.451074 -221.526506)
			(xy 236.435717 -221.474206) (xy 236.427959 -221.420254) (xy 235.962516 -221.420254) (xy 235.94477 -221.42602)
			(xy 235.893435 -221.43415) (xy 235.841461 -221.43415) (xy 235.790126 -221.42602) (xy 235.740696 -221.409959)
			(xy 235.694386 -221.386363) (xy 235.652338 -221.355813) (xy 235.615587 -221.319062) (xy 235.585037 -221.277014)
			(xy 235.561441 -221.230704) (xy 235.54538 -221.181274) (xy 235.53725 -221.129939) (xy 235.397546 -221.129939)
			(xy 235.389416 -221.181274) (xy 235.373355 -221.230704) (xy 235.349759 -221.277014) (xy 235.319209 -221.319062)
			(xy 235.282458 -221.355813) (xy 235.24041 -221.386363) (xy 235.1941 -221.409959) (xy 235.14467 -221.42602)
			(xy 235.093335 -221.43415) (xy 235.041361 -221.43415) (xy 234.990026 -221.42602) (xy 234.940596 -221.409959)
			(xy 234.894286 -221.386363) (xy 234.852238 -221.355813) (xy 234.815487 -221.319062) (xy 234.784937 -221.277014)
			(xy 234.761341 -221.230704) (xy 234.74528 -221.181274) (xy 234.73715 -221.129939) (xy 234.5977 -221.129939)
			(xy 234.58957 -221.181274) (xy 234.573509 -221.230704) (xy 234.549913 -221.277014) (xy 234.519363 -221.319062)
			(xy 234.482612 -221.355813) (xy 234.440564 -221.386363) (xy 234.394254 -221.409959) (xy 234.344824 -221.42602)
			(xy 234.293489 -221.43415) (xy 234.241515 -221.43415) (xy 234.19018 -221.42602) (xy 234.14075 -221.409959)
			(xy 234.09444 -221.386363) (xy 234.052392 -221.355813) (xy 234.015641 -221.319062) (xy 233.985091 -221.277014)
			(xy 233.961495 -221.230704) (xy 233.945434 -221.181274) (xy 233.937304 -221.129939) (xy 233.7976 -221.129939)
			(xy 233.78947 -221.181274) (xy 233.773409 -221.230704) (xy 233.749813 -221.277014) (xy 233.719263 -221.319062)
			(xy 233.682512 -221.355813) (xy 233.640464 -221.386363) (xy 233.594154 -221.409959) (xy 233.544724 -221.42602)
			(xy 233.493389 -221.43415) (xy 233.441415 -221.43415) (xy 233.39008 -221.42602) (xy 233.34065 -221.409959)
			(xy 233.29434 -221.386363) (xy 233.252292 -221.355813) (xy 233.215541 -221.319062) (xy 233.184991 -221.277014)
			(xy 233.161395 -221.230704) (xy 233.145334 -221.181274) (xy 233.137204 -221.129939) (xy 232.197654 -221.129939)
			(xy 232.189524 -221.181274) (xy 232.173463 -221.230704) (xy 232.149867 -221.277014) (xy 232.119317 -221.319062)
			(xy 232.082566 -221.355813) (xy 232.040518 -221.386363) (xy 231.994208 -221.409959) (xy 231.944778 -221.42602)
			(xy 231.893443 -221.43415) (xy 231.841469 -221.43415) (xy 231.790134 -221.42602) (xy 231.740704 -221.409959)
			(xy 231.694394 -221.386363) (xy 231.652346 -221.355813) (xy 231.615595 -221.319062) (xy 231.585045 -221.277014)
			(xy 231.561449 -221.230704) (xy 231.545388 -221.181274) (xy 231.537258 -221.129939) (xy 231.397554 -221.129939)
			(xy 231.389424 -221.181274) (xy 231.373363 -221.230704) (xy 231.349767 -221.277014) (xy 231.319217 -221.319062)
			(xy 231.282466 -221.355813) (xy 231.240418 -221.386363) (xy 231.194108 -221.409959) (xy 231.144678 -221.42602)
			(xy 231.093343 -221.43415) (xy 231.041369 -221.43415) (xy 230.990034 -221.42602) (xy 230.940604 -221.409959)
			(xy 230.894294 -221.386363) (xy 230.852246 -221.355813) (xy 230.815495 -221.319062) (xy 230.784945 -221.277014)
			(xy 230.761349 -221.230704) (xy 230.745288 -221.181274) (xy 230.737158 -221.129939) (xy 230.597708 -221.129939)
			(xy 230.589578 -221.181274) (xy 230.573517 -221.230704) (xy 230.549921 -221.277014) (xy 230.519371 -221.319062)
			(xy 230.48262 -221.355813) (xy 230.440572 -221.386363) (xy 230.394262 -221.409959) (xy 230.344832 -221.42602)
			(xy 230.293497 -221.43415) (xy 230.241523 -221.43415) (xy 230.190188 -221.42602) (xy 230.140758 -221.409959)
			(xy 230.094448 -221.386363) (xy 230.0524 -221.355813) (xy 230.015649 -221.319062) (xy 229.985099 -221.277014)
			(xy 229.961503 -221.230704) (xy 229.945442 -221.181274) (xy 229.937312 -221.129939) (xy 228.998016 -221.129939)
			(xy 228.989886 -221.181274) (xy 228.973825 -221.230704) (xy 228.950229 -221.277014) (xy 228.919679 -221.319062)
			(xy 228.882928 -221.355813) (xy 228.84088 -221.386363) (xy 228.79457 -221.409959) (xy 228.74514 -221.42602)
			(xy 228.693805 -221.43415) (xy 228.641831 -221.43415) (xy 228.590496 -221.42602) (xy 228.541066 -221.409959)
			(xy 228.494756 -221.386363) (xy 228.452708 -221.355813) (xy 228.415957 -221.319062) (xy 228.385407 -221.277014)
			(xy 228.361811 -221.230704) (xy 228.34575 -221.181274) (xy 228.33762 -221.129939) (xy 228.19817 -221.129939)
			(xy 228.19004 -221.181274) (xy 228.173979 -221.230704) (xy 228.150383 -221.277014) (xy 228.119833 -221.319062)
			(xy 228.083082 -221.355813) (xy 228.041034 -221.386363) (xy 227.994724 -221.409959) (xy 227.945294 -221.42602)
			(xy 227.893959 -221.43415) (xy 227.841985 -221.43415) (xy 227.79065 -221.42602) (xy 227.74122 -221.409959)
			(xy 227.69491 -221.386363) (xy 227.652862 -221.355813) (xy 227.616111 -221.319062) (xy 227.585561 -221.277014)
			(xy 227.561965 -221.230704) (xy 227.545904 -221.181274) (xy 227.537774 -221.129939) (xy 227.39807 -221.129939)
			(xy 227.38994 -221.181274) (xy 227.373879 -221.230704) (xy 227.350283 -221.277014) (xy 227.319733 -221.319062)
			(xy 227.282982 -221.355813) (xy 227.240934 -221.386363) (xy 227.194624 -221.409959) (xy 227.145194 -221.42602)
			(xy 227.093859 -221.43415) (xy 227.041885 -221.43415) (xy 226.99055 -221.42602) (xy 226.94112 -221.409959)
			(xy 226.89481 -221.386363) (xy 226.852762 -221.355813) (xy 226.816011 -221.319062) (xy 226.785461 -221.277014)
			(xy 226.761865 -221.230704) (xy 226.745804 -221.181274) (xy 226.737674 -221.129939) (xy 224.998024 -221.129939)
			(xy 224.989894 -221.181274) (xy 224.973833 -221.230704) (xy 224.950237 -221.277014) (xy 224.919687 -221.319062)
			(xy 224.882936 -221.355813) (xy 224.840888 -221.386363) (xy 224.794578 -221.409959) (xy 224.745148 -221.42602)
			(xy 224.693813 -221.43415) (xy 224.641839 -221.43415) (xy 224.590504 -221.42602) (xy 224.541074 -221.409959)
			(xy 224.494764 -221.386363) (xy 224.452716 -221.355813) (xy 224.415965 -221.319062) (xy 224.385415 -221.277014)
			(xy 224.361819 -221.230704) (xy 224.345758 -221.181274) (xy 224.337628 -221.129939) (xy 224.198178 -221.129939)
			(xy 224.190048 -221.181274) (xy 224.173987 -221.230704) (xy 224.150391 -221.277014) (xy 224.119841 -221.319062)
			(xy 224.08309 -221.355813) (xy 224.041042 -221.386363) (xy 223.994732 -221.409959) (xy 223.945302 -221.42602)
			(xy 223.893967 -221.43415) (xy 223.841993 -221.43415) (xy 223.790658 -221.42602) (xy 223.741228 -221.409959)
			(xy 223.694918 -221.386363) (xy 223.65287 -221.355813) (xy 223.616119 -221.319062) (xy 223.585569 -221.277014)
			(xy 223.561973 -221.230704) (xy 223.545912 -221.181274) (xy 223.537782 -221.129939) (xy 216.511795 -221.129939)
			(xy 216.535962 -221.167546) (xy 216.5586 -221.217119) (xy 216.573953 -221.269409) (xy 216.581708 -221.323351)
			(xy 216.581708 -221.377849) (xy 216.573953 -221.431791) (xy 216.5586 -221.484081) (xy 216.535962 -221.533654)
			(xy 216.5065 -221.579501) (xy 216.470814 -221.620689) (xy 216.42963 -221.656379) (xy 216.383786 -221.685845)
			(xy 216.334215 -221.708487) (xy 216.281926 -221.723845) (xy 216.227985 -221.731605) (xy 216.200736 -221.732094)
			(xy 216.200482 -221.732094) (xy 216.174187 -221.731649) (xy 216.122097 -221.724401) (xy 216.071496 -221.710073)
			(xy 216.023339 -221.688935) (xy 215.97854 -221.661387) (xy 215.937946 -221.627952) (xy 215.919812 -221.608904)
			(xy 215.912287 -221.601506) (xy 215.89301 -221.59298) (xy 215.882474 -221.592394) (xy 215.807798 -221.592394)
			(xy 215.797247 -221.59291) (xy 215.777952 -221.601455) (xy 215.77046 -221.608904) (xy 215.752361 -221.627989)
			(xy 215.711772 -221.661443) (xy 215.66697 -221.688998) (xy 215.618804 -221.710132) (xy 215.56819 -221.724443)
			(xy 215.516089 -221.73166) (xy 215.48979 -221.732094) (xy 215.489536 -221.732094) (xy 215.46228 -221.731662)
			(xy 215.408324 -221.723908) (xy 215.356019 -221.708555) (xy 215.306433 -221.685914) (xy 215.260574 -221.656446)
			(xy 215.219375 -221.620751) (xy 215.183676 -221.579555) (xy 215.154204 -221.533699) (xy 215.131558 -221.484114)
			(xy 215.116199 -221.431812) (xy 215.108441 -221.377856) (xy 196.968618 -221.377856) (xy 196.968618 -222.023178)
			(xy 209.92795 -222.023178) (xy 209.932021 -221.967556) (xy 209.944147 -221.913119) (xy 209.96407 -221.861028)
			(xy 209.991366 -221.812393) (xy 210.025452 -221.76825) (xy 210.065601 -221.729541) (xy 210.110959 -221.69709)
			(xy 210.160559 -221.671589) (xy 210.213343 -221.653582) (xy 210.268186 -221.643452) (xy 210.32392 -221.641415)
			(xy 210.379357 -221.647515) (xy 210.433314 -221.661621) (xy 210.484643 -221.683433) (xy 210.532249 -221.712487)
			(xy 210.575117 -221.748162) (xy 210.612334 -221.789699) (xy 210.643107 -221.836212) (xy 210.665741 -221.884494)
			(xy 211.249258 -221.884494) (xy 211.253329 -221.828872) (xy 211.265455 -221.774435) (xy 211.285378 -221.722344)
			(xy 211.312674 -221.673709) (xy 211.34676 -221.629566) (xy 211.386909 -221.590857) (xy 211.432267 -221.558406)
			(xy 211.481867 -221.532905) (xy 211.534651 -221.514898) (xy 211.589494 -221.504768) (xy 211.645228 -221.502731)
			(xy 211.700665 -221.508831) (xy 211.754622 -221.522937) (xy 211.805951 -221.544749) (xy 211.853557 -221.573803)
			(xy 211.896425 -221.609478) (xy 211.933642 -221.651015) (xy 211.964415 -221.697528) (xy 211.988087 -221.748025)
			(xy 212.004155 -221.801432) (xy 212.012275 -221.856608) (xy 212.012784 -221.884494) (xy 212.012275 -221.91238)
			(xy 212.009676 -221.930039) (xy 224.337628 -221.930039) (xy 224.337628 -221.878065) (xy 224.345758 -221.82673)
			(xy 224.361819 -221.7773) (xy 224.385415 -221.73099) (xy 224.415965 -221.688942) (xy 224.452716 -221.652191)
			(xy 224.494764 -221.621641) (xy 224.541074 -221.598045) (xy 224.590504 -221.581984) (xy 224.641839 -221.573854)
			(xy 224.693813 -221.573854) (xy 224.745148 -221.581984) (xy 224.794578 -221.598045) (xy 224.840888 -221.621641)
			(xy 224.882936 -221.652191) (xy 224.919687 -221.688942) (xy 224.950237 -221.73099) (xy 224.973833 -221.7773)
			(xy 224.989894 -221.82673) (xy 224.998024 -221.878065) (xy 224.998534 -221.904052) (xy 224.998024 -221.930039)
			(xy 225.137728 -221.930039) (xy 225.137728 -221.878065) (xy 225.145858 -221.82673) (xy 225.161919 -221.7773)
			(xy 225.185515 -221.73099) (xy 225.216065 -221.688942) (xy 225.252816 -221.652191) (xy 225.294864 -221.621641)
			(xy 225.341174 -221.598045) (xy 225.390604 -221.581984) (xy 225.441939 -221.573854) (xy 225.493913 -221.573854)
			(xy 225.545248 -221.581984) (xy 225.594678 -221.598045) (xy 225.640988 -221.621641) (xy 225.683036 -221.652191)
			(xy 225.719787 -221.688942) (xy 225.750337 -221.73099) (xy 225.773933 -221.7773) (xy 225.789994 -221.82673)
			(xy 225.798124 -221.878065) (xy 225.798634 -221.904052) (xy 225.798124 -221.930039) (xy 225.937574 -221.930039)
			(xy 225.937574 -221.878065) (xy 225.945704 -221.82673) (xy 225.961765 -221.7773) (xy 225.985361 -221.73099)
			(xy 226.015911 -221.688942) (xy 226.052662 -221.652191) (xy 226.09471 -221.621641) (xy 226.14102 -221.598045)
			(xy 226.19045 -221.581984) (xy 226.241785 -221.573854) (xy 226.293759 -221.573854) (xy 226.345094 -221.581984)
			(xy 226.394524 -221.598045) (xy 226.440834 -221.621641) (xy 226.482882 -221.652191) (xy 226.519633 -221.688942)
			(xy 226.550183 -221.73099) (xy 226.573779 -221.7773) (xy 226.58984 -221.82673) (xy 226.59797 -221.878065)
			(xy 226.59848 -221.904052) (xy 226.59797 -221.930039) (xy 226.737674 -221.930039) (xy 226.737674 -221.878065)
			(xy 226.745804 -221.82673) (xy 226.761865 -221.7773) (xy 226.785461 -221.73099) (xy 226.816011 -221.688942)
			(xy 226.852762 -221.652191) (xy 226.89481 -221.621641) (xy 226.94112 -221.598045) (xy 226.99055 -221.581984)
			(xy 227.041885 -221.573854) (xy 227.093859 -221.573854) (xy 227.145194 -221.581984) (xy 227.194624 -221.598045)
			(xy 227.240934 -221.621641) (xy 227.282982 -221.652191) (xy 227.319733 -221.688942) (xy 227.350283 -221.73099)
			(xy 227.373879 -221.7773) (xy 227.38994 -221.82673) (xy 227.39807 -221.878065) (xy 227.39858 -221.904052)
			(xy 227.39807 -221.930039) (xy 227.537774 -221.930039) (xy 227.537774 -221.878065) (xy 227.545904 -221.82673)
			(xy 227.561965 -221.7773) (xy 227.585561 -221.73099) (xy 227.616111 -221.688942) (xy 227.652862 -221.652191)
			(xy 227.69491 -221.621641) (xy 227.74122 -221.598045) (xy 227.79065 -221.581984) (xy 227.841985 -221.573854)
			(xy 227.893959 -221.573854) (xy 227.945294 -221.581984) (xy 227.994724 -221.598045) (xy 228.041034 -221.621641)
			(xy 228.083082 -221.652191) (xy 228.119833 -221.688942) (xy 228.150383 -221.73099) (xy 228.173979 -221.7773)
			(xy 228.19004 -221.82673) (xy 228.19817 -221.878065) (xy 228.19868 -221.904052) (xy 228.19817 -221.930039)
			(xy 228.33762 -221.930039) (xy 228.33762 -221.878065) (xy 228.34575 -221.82673) (xy 228.361811 -221.7773)
			(xy 228.385407 -221.73099) (xy 228.415957 -221.688942) (xy 228.452708 -221.652191) (xy 228.494756 -221.621641)
			(xy 228.541066 -221.598045) (xy 228.590496 -221.581984) (xy 228.641831 -221.573854) (xy 228.693805 -221.573854)
			(xy 228.74514 -221.581984) (xy 228.79457 -221.598045) (xy 228.84088 -221.621641) (xy 228.882928 -221.652191)
			(xy 228.919679 -221.688942) (xy 228.950229 -221.73099) (xy 228.973825 -221.7773) (xy 228.989886 -221.82673)
			(xy 228.998016 -221.878065) (xy 228.998526 -221.904052) (xy 228.998016 -221.930039) (xy 229.937312 -221.930039)
			(xy 229.937312 -221.878065) (xy 229.945442 -221.82673) (xy 229.961503 -221.7773) (xy 229.985099 -221.73099)
			(xy 230.015649 -221.688942) (xy 230.0524 -221.652191) (xy 230.094448 -221.621641) (xy 230.140758 -221.598045)
			(xy 230.190188 -221.581984) (xy 230.241523 -221.573854) (xy 230.293497 -221.573854) (xy 230.344832 -221.581984)
			(xy 230.394262 -221.598045) (xy 230.440572 -221.621641) (xy 230.48262 -221.652191) (xy 230.519371 -221.688942)
			(xy 230.549921 -221.73099) (xy 230.573517 -221.7773) (xy 230.589578 -221.82673) (xy 230.597708 -221.878065)
			(xy 230.598218 -221.904052) (xy 230.597708 -221.930039) (xy 230.737158 -221.930039) (xy 230.737158 -221.878065)
			(xy 230.745288 -221.82673) (xy 230.761349 -221.7773) (xy 230.784945 -221.73099) (xy 230.815495 -221.688942)
			(xy 230.852246 -221.652191) (xy 230.894294 -221.621641) (xy 230.940604 -221.598045) (xy 230.990034 -221.581984)
			(xy 231.041369 -221.573854) (xy 231.093343 -221.573854) (xy 231.144678 -221.581984) (xy 231.194108 -221.598045)
			(xy 231.240418 -221.621641) (xy 231.282466 -221.652191) (xy 231.319217 -221.688942) (xy 231.349767 -221.73099)
			(xy 231.373363 -221.7773) (xy 231.389424 -221.82673) (xy 231.397554 -221.878065) (xy 231.398064 -221.904052)
			(xy 231.397554 -221.930039) (xy 231.537258 -221.930039) (xy 231.537258 -221.878065) (xy 231.545388 -221.82673)
			(xy 231.561449 -221.7773) (xy 231.585045 -221.73099) (xy 231.615595 -221.688942) (xy 231.652346 -221.652191)
			(xy 231.694394 -221.621641) (xy 231.740704 -221.598045) (xy 231.790134 -221.581984) (xy 231.841469 -221.573854)
			(xy 231.893443 -221.573854) (xy 231.944778 -221.581984) (xy 231.994208 -221.598045) (xy 232.040518 -221.621641)
			(xy 232.082566 -221.652191) (xy 232.119317 -221.688942) (xy 232.149867 -221.73099) (xy 232.173463 -221.7773)
			(xy 232.189524 -221.82673) (xy 232.197654 -221.878065) (xy 232.198164 -221.904052) (xy 232.197654 -221.930039)
			(xy 232.337358 -221.930039) (xy 232.337358 -221.878065) (xy 232.345488 -221.82673) (xy 232.361549 -221.7773)
			(xy 232.385145 -221.73099) (xy 232.415695 -221.688942) (xy 232.452446 -221.652191) (xy 232.494494 -221.621641)
			(xy 232.540804 -221.598045) (xy 232.590234 -221.581984) (xy 232.641569 -221.573854) (xy 232.693543 -221.573854)
			(xy 232.744878 -221.581984) (xy 232.794308 -221.598045) (xy 232.840618 -221.621641) (xy 232.882666 -221.652191)
			(xy 232.919417 -221.688942) (xy 232.949967 -221.73099) (xy 232.973563 -221.7773) (xy 232.989624 -221.82673)
			(xy 232.997754 -221.878065) (xy 232.998264 -221.904052) (xy 232.997754 -221.930039) (xy 233.137204 -221.930039)
			(xy 233.137204 -221.878065) (xy 233.145334 -221.82673) (xy 233.161395 -221.7773) (xy 233.184991 -221.73099)
			(xy 233.215541 -221.688942) (xy 233.252292 -221.652191) (xy 233.29434 -221.621641) (xy 233.34065 -221.598045)
			(xy 233.39008 -221.581984) (xy 233.441415 -221.573854) (xy 233.493389 -221.573854) (xy 233.544724 -221.581984)
			(xy 233.594154 -221.598045) (xy 233.640464 -221.621641) (xy 233.682512 -221.652191) (xy 233.719263 -221.688942)
			(xy 233.749813 -221.73099) (xy 233.773409 -221.7773) (xy 233.78947 -221.82673) (xy 233.7976 -221.878065)
			(xy 233.79811 -221.904052) (xy 233.7976 -221.930039) (xy 233.937304 -221.930039) (xy 233.937304 -221.878065)
			(xy 233.945434 -221.82673) (xy 233.961495 -221.7773) (xy 233.985091 -221.73099) (xy 234.015641 -221.688942)
			(xy 234.052392 -221.652191) (xy 234.09444 -221.621641) (xy 234.14075 -221.598045) (xy 234.19018 -221.581984)
			(xy 234.241515 -221.573854) (xy 234.293489 -221.573854) (xy 234.344824 -221.581984) (xy 234.394254 -221.598045)
			(xy 234.440564 -221.621641) (xy 234.482612 -221.652191) (xy 234.519363 -221.688942) (xy 234.549913 -221.73099)
			(xy 234.573509 -221.7773) (xy 234.58957 -221.82673) (xy 234.5977 -221.878065) (xy 234.59821 -221.904052)
			(xy 234.5977 -221.930039) (xy 234.73715 -221.930039) (xy 234.73715 -221.878065) (xy 234.74528 -221.82673)
			(xy 234.761341 -221.7773) (xy 234.784937 -221.73099) (xy 234.815487 -221.688942) (xy 234.852238 -221.652191)
			(xy 234.894286 -221.621641) (xy 234.940596 -221.598045) (xy 234.990026 -221.581984) (xy 235.041361 -221.573854)
			(xy 235.093335 -221.573854) (xy 235.14467 -221.581984) (xy 235.1941 -221.598045) (xy 235.24041 -221.621641)
			(xy 235.282458 -221.652191) (xy 235.319209 -221.688942) (xy 235.349759 -221.73099) (xy 235.373355 -221.7773)
			(xy 235.389416 -221.82673) (xy 235.397546 -221.878065) (xy 235.398056 -221.904052) (xy 235.397546 -221.930039)
			(xy 235.53725 -221.930039) (xy 235.53725 -221.878065) (xy 235.54538 -221.82673) (xy 235.561441 -221.7773)
			(xy 235.585037 -221.73099) (xy 235.615587 -221.688942) (xy 235.652338 -221.652191) (xy 235.694386 -221.621641)
			(xy 235.740696 -221.598045) (xy 235.790126 -221.581984) (xy 235.841461 -221.573854) (xy 235.893435 -221.573854)
			(xy 235.94477 -221.581984) (xy 235.9942 -221.598045) (xy 236.04051 -221.621641) (xy 236.082558 -221.652191)
			(xy 236.119309 -221.688942) (xy 236.149859 -221.73099) (xy 236.173455 -221.7773) (xy 236.189516 -221.82673)
			(xy 236.197646 -221.878065) (xy 236.198156 -221.904052) (xy 236.197646 -221.930039) (xy 236.189516 -221.981374)
			(xy 236.173455 -222.030804) (xy 236.149859 -222.077114) (xy 236.135713 -222.096584) (xy 238.055148 -222.096584)
			(xy 238.059219 -222.040962) (xy 238.071345 -221.986525) (xy 238.091268 -221.934434) (xy 238.118564 -221.885799)
			(xy 238.15265 -221.841656) (xy 238.192799 -221.802947) (xy 238.238157 -221.770496) (xy 238.287757 -221.744995)
			(xy 238.340541 -221.726988) (xy 238.395384 -221.716858) (xy 238.451118 -221.714821) (xy 238.506555 -221.720921)
			(xy 238.560512 -221.735027) (xy 238.611841 -221.756839) (xy 238.659447 -221.785893) (xy 238.702315 -221.821568)
			(xy 238.739532 -221.863105) (xy 238.770305 -221.909618) (xy 238.793977 -221.960115) (xy 238.810045 -222.013522)
			(xy 238.818165 -222.068698) (xy 238.818578 -222.091351) (xy 240.98275 -222.091351) (xy 240.98275 -222.036849)
			(xy 240.990506 -221.982901) (xy 241.00586 -221.930606) (xy 241.028499 -221.881028) (xy 241.057963 -221.835177)
			(xy 241.093652 -221.793985) (xy 241.13484 -221.758291) (xy 241.180688 -221.728821) (xy 241.230263 -221.706176)
			(xy 241.282556 -221.690815) (xy 241.336503 -221.683053) (xy 241.363754 -221.682564) (xy 241.390937 -221.683028)
			(xy 241.444753 -221.690752) (xy 241.496927 -221.706038) (xy 241.546403 -221.728574) (xy 241.592179 -221.757905)
			(xy 241.633329 -221.793437) (xy 241.651536 -221.813628) (xy 241.658902 -221.822264) (xy 241.669316 -221.826836)
			(xy 241.673032 -221.828378) (xy 241.680816 -221.830417) (xy 241.68481 -221.8309) (xy 241.690398 -221.831154)
			(xy 241.773456 -221.830392) (xy 241.784124 -221.827852) (xy 241.789204 -221.825312) (xy 241.793879 -221.822918)
			(xy 241.802203 -221.816517) (xy 241.805714 -221.812612) (xy 241.805968 -221.812358) (xy 241.806476 -221.81185)
			(xy 241.824677 -221.79087) (xy 241.86616 -221.753937) (xy 241.91256 -221.723409) (xy 241.962895 -221.69993)
			(xy 242.016103 -221.683999) (xy 242.071059 -221.67595) (xy 242.09883 -221.675452) (xy 242.12608 -221.67595)
			(xy 242.180025 -221.683709) (xy 242.232317 -221.699066) (xy 242.281892 -221.721708) (xy 242.32774 -221.751174)
			(xy 242.368929 -221.786864) (xy 242.40462 -221.828052) (xy 242.434087 -221.873899) (xy 242.45673 -221.923473)
			(xy 242.472089 -221.975765) (xy 242.47985 -222.02971) (xy 242.480338 -222.05696) (xy 242.479823 -222.08422)
			(xy 242.472061 -222.138186) (xy 242.456704 -222.190499) (xy 242.434062 -222.240097) (xy 242.404598 -222.28597)
			(xy 242.38712 -222.306896) (xy 242.380516 -222.314262) (xy 242.377468 -222.323406) (xy 242.376062 -222.327776)
			(xy 242.374662 -222.336849) (xy 242.374674 -222.34144) (xy 242.377214 -222.41129) (xy 242.377488 -222.416139)
			(xy 242.379665 -222.425603) (xy 242.381532 -222.430086) (xy 242.385088 -222.438468) (xy 242.3922 -222.44558)
			(xy 242.413105 -222.467179) (xy 242.448514 -222.515748) (xy 242.475866 -222.56927) (xy 242.494484 -222.62642)
			(xy 242.503907 -222.685783) (xy 242.504468 -222.715836) (xy 242.504078 -222.743092) (xy 242.496316 -222.797047)
			(xy 242.480953 -222.849349) (xy 242.458303 -222.898932) (xy 242.428828 -222.944787) (xy 242.393126 -222.98598)
			(xy 242.351926 -223.021673) (xy 242.306065 -223.05114) (xy 242.256478 -223.07378) (xy 242.204173 -223.089132)
			(xy 242.150216 -223.096884) (xy 242.12296 -223.097344) (xy 242.092776 -223.096726) (xy 242.033165 -223.087183)
			(xy 241.975796 -223.068388) (xy 241.922094 -223.040809) (xy 241.897408 -223.02343) (xy 241.887248 -223.016064)
			(xy 241.875564 -223.014286) (xy 241.869564 -223.013503) (xy 241.857502 -223.01439) (xy 241.851688 -223.016064)
			(xy 241.772948 -223.041972) (xy 241.767256 -223.044046) (xy 241.756988 -223.050466) (xy 241.752628 -223.054672)
			(xy 241.74831 -223.05899) (xy 241.742214 -223.06915) (xy 241.740436 -223.074992) (xy 241.731982 -223.100523)
			(xy 241.70889 -223.149095) (xy 241.679205 -223.193943) (xy 241.643516 -223.234177) (xy 241.60253 -223.269)
			(xy 241.557059 -223.297721) (xy 241.508006 -223.319772) (xy 241.456342 -223.334716) (xy 241.403091 -223.342255)
			(xy 241.3762 -223.342708) (xy 241.348949 -223.342222) (xy 241.295001 -223.334466) (xy 241.242706 -223.319111)
			(xy 241.193129 -223.296469) (xy 241.147279 -223.267003) (xy 241.106088 -223.231312) (xy 241.070397 -223.190121)
			(xy 241.040931 -223.144271) (xy 241.018289 -223.094694) (xy 241.002934 -223.042399) (xy 240.995178 -222.988451)
			(xy 240.995178 -222.933949) (xy 241.002934 -222.880001) (xy 241.018289 -222.827706) (xy 241.040931 -222.778129)
			(xy 241.070397 -222.732279) (xy 241.106088 -222.691088) (xy 241.147279 -222.655397) (xy 241.193129 -222.625931)
			(xy 241.242706 -222.603289) (xy 241.295001 -222.587934) (xy 241.348949 -222.580178) (xy 241.3762 -222.579692)
			(xy 241.406386 -222.580273) (xy 241.465998 -222.589826) (xy 241.523368 -222.608631) (xy 241.577067 -222.636222)
			(xy 241.601752 -222.653606) (xy 241.611912 -222.660972) (xy 241.623596 -222.66275) (xy 241.629594 -222.663556)
			(xy 241.641659 -222.662654) (xy 241.647472 -222.660972) (xy 241.726212 -222.635064) (xy 241.731896 -222.632973)
			(xy 241.742169 -222.626564) (xy 241.746532 -222.622364) (xy 241.75085 -222.618046) (xy 241.756946 -222.607886)
			(xy 241.758724 -222.602044) (xy 241.766961 -222.577193) (xy 241.789283 -222.529836) (xy 241.817852 -222.485964)
			(xy 241.83467 -222.4659) (xy 241.841274 -222.458534) (xy 241.844322 -222.44939) (xy 241.845729 -222.44502)
			(xy 241.847127 -222.435947) (xy 241.847116 -222.431356) (xy 241.844576 -222.361506) (xy 241.844304 -222.356657)
			(xy 241.842126 -222.347193) (xy 241.840258 -222.34271) (xy 241.836702 -222.334328) (xy 241.82959 -222.327216)
			(xy 241.811048 -222.307404) (xy 241.803682 -222.298768) (xy 241.793268 -222.294196) (xy 241.789552 -222.292652)
			(xy 241.781769 -222.290614) (xy 241.777774 -222.290132) (xy 241.772186 -222.289878) (xy 241.689128 -222.29064)
			(xy 241.67846 -222.29318) (xy 241.67338 -222.29572) (xy 241.66871 -222.298123) (xy 241.660384 -222.304518)
			(xy 241.65687 -222.30842) (xy 241.656616 -222.308674) (xy 241.656108 -222.309182) (xy 241.6379 -222.330156)
			(xy 241.59642 -222.367092) (xy 241.550022 -222.397623) (xy 241.499688 -222.421103) (xy 241.44648 -222.437035)
			(xy 241.391525 -222.445083) (xy 241.363754 -222.44558) (xy 241.336503 -222.445147) (xy 241.282556 -222.437385)
			(xy 241.230263 -222.422024) (xy 241.180688 -222.399379) (xy 241.13484 -222.369909) (xy 241.093652 -222.334215)
			(xy 241.057963 -222.293023) (xy 241.028499 -222.247172) (xy 241.00586 -222.197594) (xy 240.990506 -222.145299)
			(xy 240.98275 -222.091351) (xy 238.818578 -222.091351) (xy 238.818674 -222.096584) (xy 238.818165 -222.12447)
			(xy 238.810045 -222.179646) (xy 238.793977 -222.233053) (xy 238.770305 -222.28355) (xy 238.739532 -222.330063)
			(xy 238.702315 -222.3716) (xy 238.659447 -222.407275) (xy 238.611841 -222.436329) (xy 238.560512 -222.458141)
			(xy 238.506555 -222.472247) (xy 238.451118 -222.478347) (xy 238.395384 -222.47631) (xy 238.340541 -222.46618)
			(xy 238.287757 -222.448173) (xy 238.238157 -222.422672) (xy 238.192799 -222.390221) (xy 238.15265 -222.351512)
			(xy 238.118564 -222.307369) (xy 238.091268 -222.258734) (xy 238.071345 -222.206643) (xy 238.059219 -222.152206)
			(xy 238.055148 -222.096584) (xy 236.135713 -222.096584) (xy 236.119309 -222.119162) (xy 236.082558 -222.155913)
			(xy 236.04051 -222.186463) (xy 235.9942 -222.210059) (xy 235.94477 -222.22612) (xy 235.893435 -222.23425)
			(xy 235.841461 -222.23425) (xy 235.790126 -222.22612) (xy 235.740696 -222.210059) (xy 235.694386 -222.186463)
			(xy 235.652338 -222.155913) (xy 235.615587 -222.119162) (xy 235.585037 -222.077114) (xy 235.561441 -222.030804)
			(xy 235.54538 -221.981374) (xy 235.53725 -221.930039) (xy 235.397546 -221.930039) (xy 235.389416 -221.981374)
			(xy 235.373355 -222.030804) (xy 235.349759 -222.077114) (xy 235.319209 -222.119162) (xy 235.282458 -222.155913)
			(xy 235.24041 -222.186463) (xy 235.1941 -222.210059) (xy 235.14467 -222.22612) (xy 235.093335 -222.23425)
			(xy 235.041361 -222.23425) (xy 234.990026 -222.22612) (xy 234.940596 -222.210059) (xy 234.894286 -222.186463)
			(xy 234.852238 -222.155913) (xy 234.815487 -222.119162) (xy 234.784937 -222.077114) (xy 234.761341 -222.030804)
			(xy 234.74528 -221.981374) (xy 234.73715 -221.930039) (xy 234.5977 -221.930039) (xy 234.58957 -221.981374)
			(xy 234.573509 -222.030804) (xy 234.549913 -222.077114) (xy 234.519363 -222.119162) (xy 234.482612 -222.155913)
			(xy 234.440564 -222.186463) (xy 234.394254 -222.210059) (xy 234.344824 -222.22612) (xy 234.293489 -222.23425)
			(xy 234.241515 -222.23425) (xy 234.19018 -222.22612) (xy 234.14075 -222.210059) (xy 234.09444 -222.186463)
			(xy 234.052392 -222.155913) (xy 234.015641 -222.119162) (xy 233.985091 -222.077114) (xy 233.961495 -222.030804)
			(xy 233.945434 -221.981374) (xy 233.937304 -221.930039) (xy 233.7976 -221.930039) (xy 233.78947 -221.981374)
			(xy 233.773409 -222.030804) (xy 233.749813 -222.077114) (xy 233.719263 -222.119162) (xy 233.682512 -222.155913)
			(xy 233.640464 -222.186463) (xy 233.594154 -222.210059) (xy 233.544724 -222.22612) (xy 233.493389 -222.23425)
			(xy 233.441415 -222.23425) (xy 233.39008 -222.22612) (xy 233.34065 -222.210059) (xy 233.29434 -222.186463)
			(xy 233.252292 -222.155913) (xy 233.215541 -222.119162) (xy 233.184991 -222.077114) (xy 233.161395 -222.030804)
			(xy 233.145334 -221.981374) (xy 233.137204 -221.930039) (xy 232.997754 -221.930039) (xy 232.989624 -221.981374)
			(xy 232.973563 -222.030804) (xy 232.949967 -222.077114) (xy 232.919417 -222.119162) (xy 232.882666 -222.155913)
			(xy 232.840618 -222.186463) (xy 232.794308 -222.210059) (xy 232.744878 -222.22612) (xy 232.693543 -222.23425)
			(xy 232.641569 -222.23425) (xy 232.590234 -222.22612) (xy 232.540804 -222.210059) (xy 232.494494 -222.186463)
			(xy 232.452446 -222.155913) (xy 232.415695 -222.119162) (xy 232.385145 -222.077114) (xy 232.361549 -222.030804)
			(xy 232.345488 -221.981374) (xy 232.337358 -221.930039) (xy 232.197654 -221.930039) (xy 232.189524 -221.981374)
			(xy 232.173463 -222.030804) (xy 232.149867 -222.077114) (xy 232.119317 -222.119162) (xy 232.082566 -222.155913)
			(xy 232.040518 -222.186463) (xy 231.994208 -222.210059) (xy 231.944778 -222.22612) (xy 231.893443 -222.23425)
			(xy 231.841469 -222.23425) (xy 231.790134 -222.22612) (xy 231.740704 -222.210059) (xy 231.694394 -222.186463)
			(xy 231.652346 -222.155913) (xy 231.615595 -222.119162) (xy 231.585045 -222.077114) (xy 231.561449 -222.030804)
			(xy 231.545388 -221.981374) (xy 231.537258 -221.930039) (xy 231.397554 -221.930039) (xy 231.389424 -221.981374)
			(xy 231.373363 -222.030804) (xy 231.349767 -222.077114) (xy 231.319217 -222.119162) (xy 231.282466 -222.155913)
			(xy 231.240418 -222.186463) (xy 231.194108 -222.210059) (xy 231.144678 -222.22612) (xy 231.093343 -222.23425)
			(xy 231.041369 -222.23425) (xy 230.990034 -222.22612) (xy 230.940604 -222.210059) (xy 230.894294 -222.186463)
			(xy 230.852246 -222.155913) (xy 230.815495 -222.119162) (xy 230.784945 -222.077114) (xy 230.761349 -222.030804)
			(xy 230.745288 -221.981374) (xy 230.737158 -221.930039) (xy 230.597708 -221.930039) (xy 230.589578 -221.981374)
			(xy 230.573517 -222.030804) (xy 230.549921 -222.077114) (xy 230.519371 -222.119162) (xy 230.48262 -222.155913)
			(xy 230.440572 -222.186463) (xy 230.394262 -222.210059) (xy 230.344832 -222.22612) (xy 230.293497 -222.23425)
			(xy 230.241523 -222.23425) (xy 230.190188 -222.22612) (xy 230.140758 -222.210059) (xy 230.094448 -222.186463)
			(xy 230.0524 -222.155913) (xy 230.015649 -222.119162) (xy 229.985099 -222.077114) (xy 229.961503 -222.030804)
			(xy 229.945442 -221.981374) (xy 229.937312 -221.930039) (xy 228.998016 -221.930039) (xy 228.989886 -221.981374)
			(xy 228.973825 -222.030804) (xy 228.950229 -222.077114) (xy 228.919679 -222.119162) (xy 228.882928 -222.155913)
			(xy 228.84088 -222.186463) (xy 228.79457 -222.210059) (xy 228.74514 -222.22612) (xy 228.693805 -222.23425)
			(xy 228.641831 -222.23425) (xy 228.590496 -222.22612) (xy 228.541066 -222.210059) (xy 228.494756 -222.186463)
			(xy 228.452708 -222.155913) (xy 228.415957 -222.119162) (xy 228.385407 -222.077114) (xy 228.361811 -222.030804)
			(xy 228.34575 -221.981374) (xy 228.33762 -221.930039) (xy 228.19817 -221.930039) (xy 228.19004 -221.981374)
			(xy 228.173979 -222.030804) (xy 228.150383 -222.077114) (xy 228.119833 -222.119162) (xy 228.083082 -222.155913)
			(xy 228.041034 -222.186463) (xy 227.994724 -222.210059) (xy 227.945294 -222.22612) (xy 227.893959 -222.23425)
			(xy 227.841985 -222.23425) (xy 227.79065 -222.22612) (xy 227.74122 -222.210059) (xy 227.69491 -222.186463)
			(xy 227.652862 -222.155913) (xy 227.616111 -222.119162) (xy 227.585561 -222.077114) (xy 227.561965 -222.030804)
			(xy 227.545904 -221.981374) (xy 227.537774 -221.930039) (xy 227.39807 -221.930039) (xy 227.38994 -221.981374)
			(xy 227.373879 -222.030804) (xy 227.350283 -222.077114) (xy 227.319733 -222.119162) (xy 227.282982 -222.155913)
			(xy 227.240934 -222.186463) (xy 227.194624 -222.210059) (xy 227.145194 -222.22612) (xy 227.093859 -222.23425)
			(xy 227.041885 -222.23425) (xy 226.99055 -222.22612) (xy 226.94112 -222.210059) (xy 226.89481 -222.186463)
			(xy 226.852762 -222.155913) (xy 226.816011 -222.119162) (xy 226.785461 -222.077114) (xy 226.761865 -222.030804)
			(xy 226.745804 -221.981374) (xy 226.737674 -221.930039) (xy 226.59797 -221.930039) (xy 226.58984 -221.981374)
			(xy 226.573779 -222.030804) (xy 226.550183 -222.077114) (xy 226.519633 -222.119162) (xy 226.482882 -222.155913)
			(xy 226.440834 -222.186463) (xy 226.394524 -222.210059) (xy 226.345094 -222.22612) (xy 226.293759 -222.23425)
			(xy 226.241785 -222.23425) (xy 226.19045 -222.22612) (xy 226.14102 -222.210059) (xy 226.09471 -222.186463)
			(xy 226.052662 -222.155913) (xy 226.015911 -222.119162) (xy 225.985361 -222.077114) (xy 225.961765 -222.030804)
			(xy 225.945704 -221.981374) (xy 225.937574 -221.930039) (xy 225.798124 -221.930039) (xy 225.789994 -221.981374)
			(xy 225.773933 -222.030804) (xy 225.750337 -222.077114) (xy 225.719787 -222.119162) (xy 225.683036 -222.155913)
			(xy 225.640988 -222.186463) (xy 225.594678 -222.210059) (xy 225.545248 -222.22612) (xy 225.493913 -222.23425)
			(xy 225.441939 -222.23425) (xy 225.390604 -222.22612) (xy 225.341174 -222.210059) (xy 225.294864 -222.186463)
			(xy 225.252816 -222.155913) (xy 225.216065 -222.119162) (xy 225.185515 -222.077114) (xy 225.161919 -222.030804)
			(xy 225.145858 -221.981374) (xy 225.137728 -221.930039) (xy 224.998024 -221.930039) (xy 224.989894 -221.981374)
			(xy 224.973833 -222.030804) (xy 224.950237 -222.077114) (xy 224.919687 -222.119162) (xy 224.882936 -222.155913)
			(xy 224.840888 -222.186463) (xy 224.794578 -222.210059) (xy 224.745148 -222.22612) (xy 224.693813 -222.23425)
			(xy 224.641839 -222.23425) (xy 224.590504 -222.22612) (xy 224.541074 -222.210059) (xy 224.494764 -222.186463)
			(xy 224.452716 -222.155913) (xy 224.415965 -222.119162) (xy 224.385415 -222.077114) (xy 224.361819 -222.030804)
			(xy 224.345758 -221.981374) (xy 224.337628 -221.930039) (xy 212.009676 -221.930039) (xy 212.004155 -221.967556)
			(xy 211.988087 -222.020963) (xy 211.964415 -222.07146) (xy 211.933642 -222.117973) (xy 211.896425 -222.15951)
			(xy 211.853557 -222.195185) (xy 211.805951 -222.224239) (xy 211.754622 -222.246051) (xy 211.700665 -222.260157)
			(xy 211.645228 -222.266257) (xy 211.589494 -222.26422) (xy 211.534651 -222.25409) (xy 211.481867 -222.236083)
			(xy 211.432267 -222.210582) (xy 211.386909 -222.178131) (xy 211.34676 -222.139422) (xy 211.312674 -222.095279)
			(xy 211.285378 -222.046644) (xy 211.265455 -221.994553) (xy 211.253329 -221.940116) (xy 211.249258 -221.884494)
			(xy 210.665741 -221.884494) (xy 210.666779 -221.886709) (xy 210.682847 -221.940116) (xy 210.690967 -221.995292)
			(xy 210.691476 -222.023178) (xy 210.690967 -222.051064) (xy 210.682847 -222.10624) (xy 210.666779 -222.159647)
			(xy 210.643107 -222.210144) (xy 210.612334 -222.256657) (xy 210.575117 -222.298194) (xy 210.532249 -222.333869)
			(xy 210.484643 -222.362923) (xy 210.433314 -222.384735) (xy 210.398425 -222.393856) (xy 215.108441 -222.393856)
			(xy 215.108441 -222.339344) (xy 215.116199 -222.285388) (xy 215.131558 -222.233086) (xy 215.154204 -222.183501)
			(xy 215.183676 -222.137645) (xy 215.219375 -222.096449) (xy 215.260574 -222.060754) (xy 215.306433 -222.031286)
			(xy 215.356019 -222.008645) (xy 215.408324 -221.993292) (xy 215.46228 -221.985538) (xy 215.489536 -221.985078)
			(xy 215.48979 -221.985078) (xy 215.516084 -221.98555) (xy 215.568172 -221.992794) (xy 215.618773 -222.007118)
			(xy 215.666929 -222.028251) (xy 215.711729 -222.055793) (xy 215.752325 -222.089223) (xy 215.77046 -222.108268)
			(xy 215.777999 -222.115649) (xy 215.797266 -222.124187) (xy 215.807798 -222.124778) (xy 215.882474 -222.124778)
			(xy 215.893025 -222.124255) (xy 215.91232 -222.115716) (xy 215.919812 -222.108268) (xy 215.937939 -222.08921)
			(xy 215.97852 -222.055752) (xy 216.023316 -222.028191) (xy 216.071477 -222.007051) (xy 216.122086 -221.992735)
			(xy 216.174184 -221.985514) (xy 216.200482 -221.985078) (xy 216.200736 -221.985078) (xy 216.227985 -221.985595)
			(xy 216.281926 -221.993355) (xy 216.334215 -222.008713) (xy 216.383786 -222.031355) (xy 216.42963 -222.060821)
			(xy 216.470814 -222.096511) (xy 216.5065 -222.137699) (xy 216.535962 -222.183546) (xy 216.5586 -222.233119)
			(xy 216.573953 -222.285409) (xy 216.581708 -222.339351) (xy 216.581708 -222.393849) (xy 216.573953 -222.447791)
			(xy 216.5586 -222.500081) (xy 216.535962 -222.549654) (xy 216.5065 -222.595501) (xy 216.470814 -222.636689)
			(xy 216.447391 -222.656987) (xy 222.631002 -222.656987) (xy 222.631002 -222.605013) (xy 222.639132 -222.553678)
			(xy 222.655193 -222.504248) (xy 222.678789 -222.457938) (xy 222.709339 -222.41589) (xy 222.74609 -222.379139)
			(xy 222.788138 -222.348589) (xy 222.834448 -222.324993) (xy 222.883878 -222.308932) (xy 222.935213 -222.300802)
			(xy 222.987187 -222.300802) (xy 223.038522 -222.308932) (xy 223.087952 -222.324993) (xy 223.134262 -222.348589)
			(xy 223.17631 -222.379139) (xy 223.213061 -222.41589) (xy 223.243611 -222.457938) (xy 223.267207 -222.504248)
			(xy 223.283268 -222.553678) (xy 223.291398 -222.605013) (xy 223.291908 -222.631) (xy 223.291398 -222.656987)
			(xy 223.283268 -222.708322) (xy 223.276262 -222.729885) (xy 223.537782 -222.729885) (xy 223.537782 -222.677911)
			(xy 223.545912 -222.626576) (xy 223.561973 -222.577146) (xy 223.585569 -222.530836) (xy 223.616119 -222.488788)
			(xy 223.65287 -222.452037) (xy 223.694918 -222.421487) (xy 223.741228 -222.397891) (xy 223.790658 -222.38183)
			(xy 223.841993 -222.3737) (xy 223.893967 -222.3737) (xy 223.945302 -222.38183) (xy 223.994732 -222.397891)
			(xy 224.041042 -222.421487) (xy 224.08309 -222.452037) (xy 224.119841 -222.488788) (xy 224.150391 -222.530836)
			(xy 224.173987 -222.577146) (xy 224.190048 -222.626576) (xy 224.198178 -222.677911) (xy 224.198688 -222.703898)
			(xy 224.198178 -222.729885) (xy 224.337628 -222.729885) (xy 224.337628 -222.677911) (xy 224.345758 -222.626576)
			(xy 224.361819 -222.577146) (xy 224.385415 -222.530836) (xy 224.415965 -222.488788) (xy 224.452716 -222.452037)
			(xy 224.494764 -222.421487) (xy 224.541074 -222.397891) (xy 224.590504 -222.38183) (xy 224.641839 -222.3737)
			(xy 224.693813 -222.3737) (xy 224.745148 -222.38183) (xy 224.794578 -222.397891) (xy 224.840888 -222.421487)
			(xy 224.882936 -222.452037) (xy 224.919687 -222.488788) (xy 224.950237 -222.530836) (xy 224.973833 -222.577146)
			(xy 224.989894 -222.626576) (xy 224.998024 -222.677911) (xy 224.998534 -222.703898) (xy 224.998024 -222.729885)
			(xy 225.137728 -222.729885) (xy 225.137728 -222.677911) (xy 225.145858 -222.626576) (xy 225.161919 -222.577146)
			(xy 225.185515 -222.530836) (xy 225.216065 -222.488788) (xy 225.252816 -222.452037) (xy 225.294864 -222.421487)
			(xy 225.341174 -222.397891) (xy 225.390604 -222.38183) (xy 225.441939 -222.3737) (xy 225.493913 -222.3737)
			(xy 225.545248 -222.38183) (xy 225.594678 -222.397891) (xy 225.640988 -222.421487) (xy 225.683036 -222.452037)
			(xy 225.719787 -222.488788) (xy 225.750337 -222.530836) (xy 225.773933 -222.577146) (xy 225.789994 -222.626576)
			(xy 225.798124 -222.677911) (xy 225.798634 -222.703898) (xy 225.798124 -222.729885) (xy 225.937574 -222.729885)
			(xy 225.937574 -222.677911) (xy 225.945704 -222.626576) (xy 225.961765 -222.577146) (xy 225.985361 -222.530836)
			(xy 226.015911 -222.488788) (xy 226.052662 -222.452037) (xy 226.09471 -222.421487) (xy 226.14102 -222.397891)
			(xy 226.19045 -222.38183) (xy 226.241785 -222.3737) (xy 226.293759 -222.3737) (xy 226.345094 -222.38183)
			(xy 226.394524 -222.397891) (xy 226.440834 -222.421487) (xy 226.482882 -222.452037) (xy 226.519633 -222.488788)
			(xy 226.550183 -222.530836) (xy 226.573779 -222.577146) (xy 226.58984 -222.626576) (xy 226.59797 -222.677911)
			(xy 226.59848 -222.703898) (xy 226.59797 -222.729885) (xy 226.737674 -222.729885) (xy 226.737674 -222.677911)
			(xy 226.745804 -222.626576) (xy 226.761865 -222.577146) (xy 226.785461 -222.530836) (xy 226.816011 -222.488788)
			(xy 226.852762 -222.452037) (xy 226.89481 -222.421487) (xy 226.94112 -222.397891) (xy 226.99055 -222.38183)
			(xy 227.041885 -222.3737) (xy 227.093859 -222.3737) (xy 227.145194 -222.38183) (xy 227.194624 -222.397891)
			(xy 227.240934 -222.421487) (xy 227.282982 -222.452037) (xy 227.319733 -222.488788) (xy 227.350283 -222.530836)
			(xy 227.373879 -222.577146) (xy 227.38994 -222.626576) (xy 227.39807 -222.677911) (xy 227.39858 -222.703898)
			(xy 227.39807 -222.729885) (xy 228.33762 -222.729885) (xy 228.33762 -222.677911) (xy 228.34575 -222.626576)
			(xy 228.361811 -222.577146) (xy 228.385407 -222.530836) (xy 228.415957 -222.488788) (xy 228.452708 -222.452037)
			(xy 228.494756 -222.421487) (xy 228.541066 -222.397891) (xy 228.590496 -222.38183) (xy 228.641831 -222.3737)
			(xy 228.693805 -222.3737) (xy 228.74514 -222.38183) (xy 228.79457 -222.397891) (xy 228.84088 -222.421487)
			(xy 228.882928 -222.452037) (xy 228.919679 -222.488788) (xy 228.950229 -222.530836) (xy 228.973825 -222.577146)
			(xy 228.989886 -222.626576) (xy 228.998016 -222.677911) (xy 228.998526 -222.703898) (xy 228.998016 -222.729885)
			(xy 229.937312 -222.729885) (xy 229.937312 -222.677911) (xy 229.945442 -222.626576) (xy 229.961503 -222.577146)
			(xy 229.985099 -222.530836) (xy 230.015649 -222.488788) (xy 230.0524 -222.452037) (xy 230.094448 -222.421487)
			(xy 230.140758 -222.397891) (xy 230.190188 -222.38183) (xy 230.241523 -222.3737) (xy 230.293497 -222.3737)
			(xy 230.344832 -222.38183) (xy 230.394262 -222.397891) (xy 230.440572 -222.421487) (xy 230.48262 -222.452037)
			(xy 230.519371 -222.488788) (xy 230.549921 -222.530836) (xy 230.573517 -222.577146) (xy 230.589578 -222.626576)
			(xy 230.597708 -222.677911) (xy 230.598218 -222.703898) (xy 230.597708 -222.729885) (xy 231.537258 -222.729885)
			(xy 231.537258 -222.677911) (xy 231.545388 -222.626576) (xy 231.561449 -222.577146) (xy 231.585045 -222.530836)
			(xy 231.615595 -222.488788) (xy 231.652346 -222.452037) (xy 231.694394 -222.421487) (xy 231.740704 -222.397891)
			(xy 231.790134 -222.38183) (xy 231.841469 -222.3737) (xy 231.893443 -222.3737) (xy 231.944778 -222.38183)
			(xy 231.994208 -222.397891) (xy 232.040518 -222.421487) (xy 232.082566 -222.452037) (xy 232.119317 -222.488788)
			(xy 232.149867 -222.530836) (xy 232.173463 -222.577146) (xy 232.189524 -222.626576) (xy 232.197654 -222.677911)
			(xy 232.198164 -222.703898) (xy 232.197654 -222.729885) (xy 232.337358 -222.729885) (xy 232.337358 -222.677911)
			(xy 232.345488 -222.626576) (xy 232.361549 -222.577146) (xy 232.385145 -222.530836) (xy 232.415695 -222.488788)
			(xy 232.452446 -222.452037) (xy 232.494494 -222.421487) (xy 232.540804 -222.397891) (xy 232.590234 -222.38183)
			(xy 232.641569 -222.3737) (xy 232.693543 -222.3737) (xy 232.744878 -222.38183) (xy 232.794308 -222.397891)
			(xy 232.840618 -222.421487) (xy 232.882666 -222.452037) (xy 232.919417 -222.488788) (xy 232.949967 -222.530836)
			(xy 232.973563 -222.577146) (xy 232.989624 -222.626576) (xy 232.997754 -222.677911) (xy 232.998264 -222.703898)
			(xy 232.997754 -222.729885) (xy 233.137204 -222.729885) (xy 233.137204 -222.677911) (xy 233.145334 -222.626576)
			(xy 233.161395 -222.577146) (xy 233.184991 -222.530836) (xy 233.215541 -222.488788) (xy 233.252292 -222.452037)
			(xy 233.29434 -222.421487) (xy 233.34065 -222.397891) (xy 233.39008 -222.38183) (xy 233.441415 -222.3737)
			(xy 233.493389 -222.3737) (xy 233.544724 -222.38183) (xy 233.594154 -222.397891) (xy 233.640464 -222.421487)
			(xy 233.682512 -222.452037) (xy 233.719263 -222.488788) (xy 233.749813 -222.530836) (xy 233.773409 -222.577146)
			(xy 233.78947 -222.626576) (xy 233.7976 -222.677911) (xy 233.79811 -222.703898) (xy 233.7976 -222.729885)
			(xy 233.937304 -222.729885) (xy 233.937304 -222.677911) (xy 233.945434 -222.626576) (xy 233.961495 -222.577146)
			(xy 233.985091 -222.530836) (xy 234.015641 -222.488788) (xy 234.052392 -222.452037) (xy 234.09444 -222.421487)
			(xy 234.14075 -222.397891) (xy 234.19018 -222.38183) (xy 234.241515 -222.3737) (xy 234.293489 -222.3737)
			(xy 234.344824 -222.38183) (xy 234.394254 -222.397891) (xy 234.440564 -222.421487) (xy 234.482612 -222.452037)
			(xy 234.519363 -222.488788) (xy 234.549913 -222.530836) (xy 234.573509 -222.577146) (xy 234.58957 -222.626576)
			(xy 234.5977 -222.677911) (xy 234.59821 -222.703898) (xy 234.5977 -222.729885) (xy 234.73715 -222.729885)
			(xy 234.73715 -222.677911) (xy 234.74528 -222.626576) (xy 234.761341 -222.577146) (xy 234.784937 -222.530836)
			(xy 234.815487 -222.488788) (xy 234.852238 -222.452037) (xy 234.894286 -222.421487) (xy 234.940596 -222.397891)
			(xy 234.990026 -222.38183) (xy 235.041361 -222.3737) (xy 235.093335 -222.3737) (xy 235.14467 -222.38183)
			(xy 235.1941 -222.397891) (xy 235.24041 -222.421487) (xy 235.282458 -222.452037) (xy 235.319209 -222.488788)
			(xy 235.349759 -222.530836) (xy 235.373355 -222.577146) (xy 235.389416 -222.626576) (xy 235.397546 -222.677911)
			(xy 235.398056 -222.703898) (xy 235.397546 -222.729885) (xy 235.53725 -222.729885) (xy 235.53725 -222.677911)
			(xy 235.54538 -222.626576) (xy 235.561441 -222.577146) (xy 235.585037 -222.530836) (xy 235.615587 -222.488788)
			(xy 235.652338 -222.452037) (xy 235.694386 -222.421487) (xy 235.740696 -222.397891) (xy 235.790126 -222.38183)
			(xy 235.841461 -222.3737) (xy 235.893435 -222.3737) (xy 235.94477 -222.38183) (xy 235.9942 -222.397891)
			(xy 236.04051 -222.421487) (xy 236.082558 -222.452037) (xy 236.119309 -222.488788) (xy 236.149859 -222.530836)
			(xy 236.173455 -222.577146) (xy 236.189516 -222.626576) (xy 236.197646 -222.677911) (xy 236.198156 -222.703898)
			(xy 236.197646 -222.729885) (xy 236.189516 -222.78122) (xy 236.173455 -222.83065) (xy 236.149859 -222.87696)
			(xy 236.119309 -222.919008) (xy 236.082558 -222.955759) (xy 236.04051 -222.986309) (xy 235.9942 -223.009905)
			(xy 235.94477 -223.025966) (xy 235.893435 -223.034096) (xy 235.841461 -223.034096) (xy 235.790126 -223.025966)
			(xy 235.740696 -223.009905) (xy 235.694386 -222.986309) (xy 235.652338 -222.955759) (xy 235.615587 -222.919008)
			(xy 235.585037 -222.87696) (xy 235.561441 -222.83065) (xy 235.54538 -222.78122) (xy 235.53725 -222.729885)
			(xy 235.397546 -222.729885) (xy 235.389416 -222.78122) (xy 235.373355 -222.83065) (xy 235.349759 -222.87696)
			(xy 235.319209 -222.919008) (xy 235.282458 -222.955759) (xy 235.24041 -222.986309) (xy 235.1941 -223.009905)
			(xy 235.14467 -223.025966) (xy 235.093335 -223.034096) (xy 235.041361 -223.034096) (xy 234.990026 -223.025966)
			(xy 234.940596 -223.009905) (xy 234.894286 -222.986309) (xy 234.852238 -222.955759) (xy 234.815487 -222.919008)
			(xy 234.784937 -222.87696) (xy 234.761341 -222.83065) (xy 234.74528 -222.78122) (xy 234.73715 -222.729885)
			(xy 234.5977 -222.729885) (xy 234.58957 -222.78122) (xy 234.573509 -222.83065) (xy 234.549913 -222.87696)
			(xy 234.519363 -222.919008) (xy 234.482612 -222.955759) (xy 234.440564 -222.986309) (xy 234.394254 -223.009905)
			(xy 234.344824 -223.025966) (xy 234.293489 -223.034096) (xy 234.241515 -223.034096) (xy 234.19018 -223.025966)
			(xy 234.14075 -223.009905) (xy 234.09444 -222.986309) (xy 234.052392 -222.955759) (xy 234.015641 -222.919008)
			(xy 233.985091 -222.87696) (xy 233.961495 -222.83065) (xy 233.945434 -222.78122) (xy 233.937304 -222.729885)
			(xy 233.7976 -222.729885) (xy 233.78947 -222.78122) (xy 233.773409 -222.83065) (xy 233.749813 -222.87696)
			(xy 233.719263 -222.919008) (xy 233.682512 -222.955759) (xy 233.640464 -222.986309) (xy 233.594154 -223.009905)
			(xy 233.544724 -223.025966) (xy 233.493389 -223.034096) (xy 233.441415 -223.034096) (xy 233.39008 -223.025966)
			(xy 233.34065 -223.009905) (xy 233.29434 -222.986309) (xy 233.252292 -222.955759) (xy 233.215541 -222.919008)
			(xy 233.184991 -222.87696) (xy 233.161395 -222.83065) (xy 233.145334 -222.78122) (xy 233.137204 -222.729885)
			(xy 232.997754 -222.729885) (xy 232.989624 -222.78122) (xy 232.973563 -222.83065) (xy 232.949967 -222.87696)
			(xy 232.919417 -222.919008) (xy 232.882666 -222.955759) (xy 232.840618 -222.986309) (xy 232.794308 -223.009905)
			(xy 232.744878 -223.025966) (xy 232.693543 -223.034096) (xy 232.641569 -223.034096) (xy 232.590234 -223.025966)
			(xy 232.540804 -223.009905) (xy 232.494494 -222.986309) (xy 232.452446 -222.955759) (xy 232.415695 -222.919008)
			(xy 232.385145 -222.87696) (xy 232.361549 -222.83065) (xy 232.345488 -222.78122) (xy 232.337358 -222.729885)
			(xy 232.197654 -222.729885) (xy 232.189524 -222.78122) (xy 232.173463 -222.83065) (xy 232.149867 -222.87696)
			(xy 232.119317 -222.919008) (xy 232.082566 -222.955759) (xy 232.040518 -222.986309) (xy 231.994208 -223.009905)
			(xy 231.944778 -223.025966) (xy 231.893443 -223.034096) (xy 231.841469 -223.034096) (xy 231.790134 -223.025966)
			(xy 231.740704 -223.009905) (xy 231.694394 -222.986309) (xy 231.652346 -222.955759) (xy 231.615595 -222.919008)
			(xy 231.585045 -222.87696) (xy 231.561449 -222.83065) (xy 231.545388 -222.78122) (xy 231.537258 -222.729885)
			(xy 230.597708 -222.729885) (xy 230.589578 -222.78122) (xy 230.573517 -222.83065) (xy 230.549921 -222.87696)
			(xy 230.519371 -222.919008) (xy 230.48262 -222.955759) (xy 230.440572 -222.986309) (xy 230.394262 -223.009905)
			(xy 230.344832 -223.025966) (xy 230.293497 -223.034096) (xy 230.241523 -223.034096) (xy 230.190188 -223.025966)
			(xy 230.140758 -223.009905) (xy 230.094448 -222.986309) (xy 230.0524 -222.955759) (xy 230.015649 -222.919008)
			(xy 229.985099 -222.87696) (xy 229.961503 -222.83065) (xy 229.945442 -222.78122) (xy 229.937312 -222.729885)
			(xy 228.998016 -222.729885) (xy 228.989886 -222.78122) (xy 228.973825 -222.83065) (xy 228.950229 -222.87696)
			(xy 228.919679 -222.919008) (xy 228.882928 -222.955759) (xy 228.84088 -222.986309) (xy 228.79457 -223.009905)
			(xy 228.74514 -223.025966) (xy 228.693805 -223.034096) (xy 228.641831 -223.034096) (xy 228.590496 -223.025966)
			(xy 228.541066 -223.009905) (xy 228.494756 -222.986309) (xy 228.452708 -222.955759) (xy 228.415957 -222.919008)
			(xy 228.385407 -222.87696) (xy 228.361811 -222.83065) (xy 228.34575 -222.78122) (xy 228.33762 -222.729885)
			(xy 227.39807 -222.729885) (xy 227.38994 -222.78122) (xy 227.373879 -222.83065) (xy 227.350283 -222.87696)
			(xy 227.319733 -222.919008) (xy 227.282982 -222.955759) (xy 227.240934 -222.986309) (xy 227.194624 -223.009905)
			(xy 227.145194 -223.025966) (xy 227.093859 -223.034096) (xy 227.041885 -223.034096) (xy 226.99055 -223.025966)
			(xy 226.94112 -223.009905) (xy 226.89481 -222.986309) (xy 226.852762 -222.955759) (xy 226.816011 -222.919008)
			(xy 226.785461 -222.87696) (xy 226.761865 -222.83065) (xy 226.745804 -222.78122) (xy 226.737674 -222.729885)
			(xy 226.59797 -222.729885) (xy 226.58984 -222.78122) (xy 226.573779 -222.83065) (xy 226.550183 -222.87696)
			(xy 226.519633 -222.919008) (xy 226.482882 -222.955759) (xy 226.440834 -222.986309) (xy 226.394524 -223.009905)
			(xy 226.345094 -223.025966) (xy 226.293759 -223.034096) (xy 226.241785 -223.034096) (xy 226.19045 -223.025966)
			(xy 226.14102 -223.009905) (xy 226.09471 -222.986309) (xy 226.052662 -222.955759) (xy 226.015911 -222.919008)
			(xy 225.985361 -222.87696) (xy 225.961765 -222.83065) (xy 225.945704 -222.78122) (xy 225.937574 -222.729885)
			(xy 225.798124 -222.729885) (xy 225.789994 -222.78122) (xy 225.773933 -222.83065) (xy 225.750337 -222.87696)
			(xy 225.719787 -222.919008) (xy 225.683036 -222.955759) (xy 225.640988 -222.986309) (xy 225.594678 -223.009905)
			(xy 225.545248 -223.025966) (xy 225.493913 -223.034096) (xy 225.441939 -223.034096) (xy 225.390604 -223.025966)
			(xy 225.341174 -223.009905) (xy 225.294864 -222.986309) (xy 225.252816 -222.955759) (xy 225.216065 -222.919008)
			(xy 225.185515 -222.87696) (xy 225.161919 -222.83065) (xy 225.145858 -222.78122) (xy 225.137728 -222.729885)
			(xy 224.998024 -222.729885) (xy 224.989894 -222.78122) (xy 224.973833 -222.83065) (xy 224.950237 -222.87696)
			(xy 224.919687 -222.919008) (xy 224.882936 -222.955759) (xy 224.840888 -222.986309) (xy 224.794578 -223.009905)
			(xy 224.745148 -223.025966) (xy 224.693813 -223.034096) (xy 224.641839 -223.034096) (xy 224.590504 -223.025966)
			(xy 224.541074 -223.009905) (xy 224.494764 -222.986309) (xy 224.452716 -222.955759) (xy 224.415965 -222.919008)
			(xy 224.385415 -222.87696) (xy 224.361819 -222.83065) (xy 224.345758 -222.78122) (xy 224.337628 -222.729885)
			(xy 224.198178 -222.729885) (xy 224.190048 -222.78122) (xy 224.173987 -222.83065) (xy 224.150391 -222.87696)
			(xy 224.119841 -222.919008) (xy 224.08309 -222.955759) (xy 224.041042 -222.986309) (xy 223.994732 -223.009905)
			(xy 223.945302 -223.025966) (xy 223.893967 -223.034096) (xy 223.841993 -223.034096) (xy 223.790658 -223.025966)
			(xy 223.741228 -223.009905) (xy 223.694918 -222.986309) (xy 223.65287 -222.955759) (xy 223.616119 -222.919008)
			(xy 223.585569 -222.87696) (xy 223.561973 -222.83065) (xy 223.545912 -222.78122) (xy 223.537782 -222.729885)
			(xy 223.276262 -222.729885) (xy 223.267207 -222.757752) (xy 223.243611 -222.804062) (xy 223.213061 -222.84611)
			(xy 223.17631 -222.882861) (xy 223.134262 -222.913411) (xy 223.087952 -222.937007) (xy 223.038522 -222.953068)
			(xy 222.987187 -222.961198) (xy 222.935213 -222.961198) (xy 222.883878 -222.953068) (xy 222.834448 -222.937007)
			(xy 222.788138 -222.913411) (xy 222.74609 -222.882861) (xy 222.709339 -222.84611) (xy 222.678789 -222.804062)
			(xy 222.655193 -222.757752) (xy 222.639132 -222.708322) (xy 222.631002 -222.656987) (xy 216.447391 -222.656987)
			(xy 216.42963 -222.672379) (xy 216.383786 -222.701845) (xy 216.334215 -222.724487) (xy 216.281926 -222.739845)
			(xy 216.227985 -222.747605) (xy 216.200736 -222.748094) (xy 216.200482 -222.748094) (xy 216.174187 -222.747649)
			(xy 216.122097 -222.740401) (xy 216.071496 -222.726073) (xy 216.023339 -222.704935) (xy 215.97854 -222.677387)
			(xy 215.937946 -222.643952) (xy 215.919812 -222.624904) (xy 215.912287 -222.617506) (xy 215.89301 -222.60898)
			(xy 215.882474 -222.608394) (xy 215.807798 -222.608394) (xy 215.797247 -222.60891) (xy 215.777952 -222.617455)
			(xy 215.77046 -222.624904) (xy 215.752361 -222.643989) (xy 215.711772 -222.677443) (xy 215.66697 -222.704998)
			(xy 215.618804 -222.726132) (xy 215.56819 -222.740443) (xy 215.516089 -222.74766) (xy 215.48979 -222.748094)
			(xy 215.489536 -222.748094) (xy 215.46228 -222.747662) (xy 215.408324 -222.739908) (xy 215.356019 -222.724555)
			(xy 215.306433 -222.701914) (xy 215.260574 -222.672446) (xy 215.219375 -222.636751) (xy 215.183676 -222.595555)
			(xy 215.154204 -222.549699) (xy 215.131558 -222.500114) (xy 215.116199 -222.447812) (xy 215.108441 -222.393856)
			(xy 210.398425 -222.393856) (xy 210.379357 -222.398841) (xy 210.32392 -222.404941) (xy 210.268186 -222.402904)
			(xy 210.213343 -222.392774) (xy 210.160559 -222.374767) (xy 210.110959 -222.349266) (xy 210.065601 -222.316815)
			(xy 210.025452 -222.278106) (xy 209.991366 -222.233963) (xy 209.96407 -222.185328) (xy 209.944147 -222.133237)
			(xy 209.932021 -222.0788) (xy 209.92795 -222.023178) (xy 196.968618 -222.023178) (xy 196.968618 -224.430844)
			(xy 205.922118 -224.430844) (xy 205.922586 -224.405054) (xy 205.929546 -224.353946) (xy 205.943331 -224.304243)
			(xy 205.96369 -224.256851) (xy 205.990251 -224.212636) (xy 206.02253 -224.172405) (xy 206.059937 -224.136892)
			(xy 206.080614 -224.121472) (xy 206.088996 -224.115122) (xy 206.09433 -224.106232) (xy 206.096933 -224.101632)
			(xy 206.100391 -224.091645) (xy 206.101188 -224.08642) (xy 206.11084 -224.013014) (xy 206.111305 -224.007831)
			(xy 206.11041 -223.997466) (xy 206.109062 -223.99244) (xy 206.106268 -223.982534) (xy 206.099664 -223.974406)
			(xy 206.083285 -223.953821) (xy 206.05571 -223.909022) (xy 206.034555 -223.860858) (xy 206.020223 -223.810243)
			(xy 206.012986 -223.758138) (xy 206.012542 -223.731836) (xy 206.013028 -223.704585) (xy 206.020784 -223.650637)
			(xy 206.036139 -223.598342) (xy 206.058781 -223.548765) (xy 206.088247 -223.502915) (xy 206.123938 -223.461724)
			(xy 206.165129 -223.426033) (xy 206.210979 -223.396567) (xy 206.260556 -223.373925) (xy 206.312851 -223.35857)
			(xy 206.366799 -223.350814) (xy 206.421301 -223.350814) (xy 206.475249 -223.35857) (xy 206.527544 -223.373925)
			(xy 206.577121 -223.396567) (xy 206.597796 -223.409854) (xy 214.471441 -223.409854) (xy 214.471441 -223.355346)
			(xy 214.479198 -223.301393) (xy 214.494555 -223.249092) (xy 214.517199 -223.19951) (xy 214.546668 -223.153655)
			(xy 214.582364 -223.112461) (xy 214.623558 -223.076766) (xy 214.669414 -223.047297) (xy 214.718996 -223.024654)
			(xy 214.771297 -223.009297) (xy 214.82525 -223.001541) (xy 214.852504 -223.001078) (xy 214.879978 -223.001567)
			(xy 214.934358 -223.009459) (xy 214.98704 -223.025079) (xy 215.036933 -223.048103) (xy 215.083002 -223.078053)
			(xy 215.103964 -223.09582) (xy 215.111076 -223.101916) (xy 215.119458 -223.104964) (xy 215.123746 -223.106483)
			(xy 215.13269 -223.108143) (xy 215.137238 -223.108266) (xy 215.204802 -223.108266) (xy 215.20935 -223.108142)
			(xy 215.218294 -223.106483) (xy 215.222582 -223.104964) (xy 215.230964 -223.101916) (xy 215.238076 -223.09582)
			(xy 215.259052 -223.078074) (xy 215.305131 -223.048149) (xy 215.355022 -223.025134) (xy 215.407696 -223.009504)
			(xy 215.462065 -223.001581) (xy 215.489536 -223.001078) (xy 215.48979 -223.001078) (xy 215.516084 -223.00155)
			(xy 215.568172 -223.008794) (xy 215.618773 -223.023118) (xy 215.666929 -223.044251) (xy 215.711729 -223.071793)
			(xy 215.752325 -223.105223) (xy 215.77046 -223.124268) (xy 215.777999 -223.131649) (xy 215.797266 -223.140187)
			(xy 215.807798 -223.140778) (xy 215.882474 -223.140778) (xy 215.893025 -223.140255) (xy 215.91232 -223.131716)
			(xy 215.919812 -223.124268) (xy 215.937939 -223.10521) (xy 215.97852 -223.071752) (xy 216.023316 -223.044191)
			(xy 216.071477 -223.023051) (xy 216.122086 -223.008735) (xy 216.174184 -223.001514) (xy 216.200482 -223.001078)
			(xy 216.200736 -223.001078) (xy 216.227985 -223.001595) (xy 216.281926 -223.009355) (xy 216.334215 -223.024713)
			(xy 216.383786 -223.047355) (xy 216.42963 -223.076821) (xy 216.470814 -223.112511) (xy 216.5065 -223.153699)
			(xy 216.535962 -223.199546) (xy 216.5586 -223.249119) (xy 216.573953 -223.301409) (xy 216.581708 -223.355351)
			(xy 216.581708 -223.409849) (xy 216.580479 -223.4184) (xy 217.863418 -223.4184) (xy 217.867489 -223.362778)
			(xy 217.879615 -223.308341) (xy 217.899538 -223.25625) (xy 217.926834 -223.207615) (xy 217.96092 -223.163472)
			(xy 218.001069 -223.124763) (xy 218.046427 -223.092312) (xy 218.096027 -223.066811) (xy 218.148811 -223.048804)
			(xy 218.203654 -223.038674) (xy 218.259388 -223.036637) (xy 218.314825 -223.042737) (xy 218.368782 -223.056843)
			(xy 218.420111 -223.078655) (xy 218.467717 -223.107709) (xy 218.510585 -223.143384) (xy 218.547802 -223.184921)
			(xy 218.578575 -223.231434) (xy 218.602247 -223.281931) (xy 218.618315 -223.335338) (xy 218.626435 -223.390514)
			(xy 218.626944 -223.4184) (xy 218.626435 -223.446286) (xy 218.618315 -223.501462) (xy 218.609734 -223.529985)
			(xy 224.337628 -223.529985) (xy 224.337628 -223.478011) (xy 224.345758 -223.426676) (xy 224.361819 -223.377246)
			(xy 224.385415 -223.330936) (xy 224.415965 -223.288888) (xy 224.452716 -223.252137) (xy 224.494764 -223.221587)
			(xy 224.541074 -223.197991) (xy 224.590504 -223.18193) (xy 224.641839 -223.1738) (xy 224.693813 -223.1738)
			(xy 224.745148 -223.18193) (xy 224.794578 -223.197991) (xy 224.840888 -223.221587) (xy 224.882936 -223.252137)
			(xy 224.919687 -223.288888) (xy 224.950237 -223.330936) (xy 224.973833 -223.377246) (xy 224.989894 -223.426676)
			(xy 224.998024 -223.478011) (xy 224.998534 -223.503998) (xy 224.998024 -223.529985) (xy 225.137728 -223.529985)
			(xy 225.137728 -223.478011) (xy 225.145858 -223.426676) (xy 225.161919 -223.377246) (xy 225.185515 -223.330936)
			(xy 225.216065 -223.288888) (xy 225.252816 -223.252137) (xy 225.294864 -223.221587) (xy 225.341174 -223.197991)
			(xy 225.390604 -223.18193) (xy 225.441939 -223.1738) (xy 225.493913 -223.1738) (xy 225.545248 -223.18193)
			(xy 225.594678 -223.197991) (xy 225.640988 -223.221587) (xy 225.683036 -223.252137) (xy 225.719787 -223.288888)
			(xy 225.750337 -223.330936) (xy 225.773933 -223.377246) (xy 225.789994 -223.426676) (xy 225.798124 -223.478011)
			(xy 225.798634 -223.503998) (xy 225.798124 -223.529985) (xy 225.937574 -223.529985) (xy 225.937574 -223.478011)
			(xy 225.945704 -223.426676) (xy 225.961765 -223.377246) (xy 225.985361 -223.330936) (xy 226.015911 -223.288888)
			(xy 226.052662 -223.252137) (xy 226.09471 -223.221587) (xy 226.14102 -223.197991) (xy 226.19045 -223.18193)
			(xy 226.241785 -223.1738) (xy 226.293759 -223.1738) (xy 226.345094 -223.18193) (xy 226.394524 -223.197991)
			(xy 226.440834 -223.221587) (xy 226.482882 -223.252137) (xy 226.519633 -223.288888) (xy 226.550183 -223.330936)
			(xy 226.573779 -223.377246) (xy 226.58984 -223.426676) (xy 226.59797 -223.478011) (xy 226.59848 -223.503998)
			(xy 226.59797 -223.529985) (xy 226.737674 -223.529985) (xy 226.737674 -223.478011) (xy 226.745804 -223.426676)
			(xy 226.761865 -223.377246) (xy 226.785461 -223.330936) (xy 226.816011 -223.288888) (xy 226.852762 -223.252137)
			(xy 226.89481 -223.221587) (xy 226.94112 -223.197991) (xy 226.99055 -223.18193) (xy 227.041885 -223.1738)
			(xy 227.093859 -223.1738) (xy 227.145194 -223.18193) (xy 227.194624 -223.197991) (xy 227.240934 -223.221587)
			(xy 227.282982 -223.252137) (xy 227.319733 -223.288888) (xy 227.350283 -223.330936) (xy 227.373879 -223.377246)
			(xy 227.38994 -223.426676) (xy 227.39807 -223.478011) (xy 227.39858 -223.503998) (xy 227.39807 -223.529985)
			(xy 227.537774 -223.529985) (xy 227.537774 -223.478011) (xy 227.545904 -223.426676) (xy 227.561965 -223.377246)
			(xy 227.585561 -223.330936) (xy 227.616111 -223.288888) (xy 227.652862 -223.252137) (xy 227.69491 -223.221587)
			(xy 227.74122 -223.197991) (xy 227.79065 -223.18193) (xy 227.841985 -223.1738) (xy 227.893959 -223.1738)
			(xy 227.945294 -223.18193) (xy 227.994724 -223.197991) (xy 228.041034 -223.221587) (xy 228.083082 -223.252137)
			(xy 228.119833 -223.288888) (xy 228.150383 -223.330936) (xy 228.173979 -223.377246) (xy 228.19004 -223.426676)
			(xy 228.19817 -223.478011) (xy 228.19868 -223.503998) (xy 228.19817 -223.529985) (xy 229.937312 -223.529985)
			(xy 229.937312 -223.478011) (xy 229.945442 -223.426676) (xy 229.961503 -223.377246) (xy 229.985099 -223.330936)
			(xy 230.015649 -223.288888) (xy 230.0524 -223.252137) (xy 230.094448 -223.221587) (xy 230.140758 -223.197991)
			(xy 230.190188 -223.18193) (xy 230.241523 -223.1738) (xy 230.293497 -223.1738) (xy 230.344832 -223.18193)
			(xy 230.394262 -223.197991) (xy 230.440572 -223.221587) (xy 230.48262 -223.252137) (xy 230.519371 -223.288888)
			(xy 230.549921 -223.330936) (xy 230.573517 -223.377246) (xy 230.589578 -223.426676) (xy 230.597708 -223.478011)
			(xy 230.598218 -223.503998) (xy 230.597708 -223.529985) (xy 230.737158 -223.529985) (xy 230.737158 -223.478011)
			(xy 230.745288 -223.426676) (xy 230.761349 -223.377246) (xy 230.784945 -223.330936) (xy 230.815495 -223.288888)
			(xy 230.852246 -223.252137) (xy 230.894294 -223.221587) (xy 230.940604 -223.197991) (xy 230.990034 -223.18193)
			(xy 231.041369 -223.1738) (xy 231.093343 -223.1738) (xy 231.144678 -223.18193) (xy 231.194108 -223.197991)
			(xy 231.240418 -223.221587) (xy 231.282466 -223.252137) (xy 231.319217 -223.288888) (xy 231.349767 -223.330936)
			(xy 231.373363 -223.377246) (xy 231.389424 -223.426676) (xy 231.397554 -223.478011) (xy 231.398064 -223.503998)
			(xy 231.397554 -223.529985) (xy 231.537258 -223.529985) (xy 231.537258 -223.478011) (xy 231.545388 -223.426676)
			(xy 231.561449 -223.377246) (xy 231.585045 -223.330936) (xy 231.615595 -223.288888) (xy 231.652346 -223.252137)
			(xy 231.694394 -223.221587) (xy 231.740704 -223.197991) (xy 231.790134 -223.18193) (xy 231.841469 -223.1738)
			(xy 231.893443 -223.1738) (xy 231.944778 -223.18193) (xy 231.994208 -223.197991) (xy 232.040518 -223.221587)
			(xy 232.082566 -223.252137) (xy 232.119317 -223.288888) (xy 232.149867 -223.330936) (xy 232.173463 -223.377246)
			(xy 232.189524 -223.426676) (xy 232.197654 -223.478011) (xy 232.198164 -223.503998) (xy 232.197654 -223.529985)
			(xy 232.337358 -223.529985) (xy 232.337358 -223.478011) (xy 232.345488 -223.426676) (xy 232.361549 -223.377246)
			(xy 232.385145 -223.330936) (xy 232.415695 -223.288888) (xy 232.452446 -223.252137) (xy 232.494494 -223.221587)
			(xy 232.540804 -223.197991) (xy 232.590234 -223.18193) (xy 232.641569 -223.1738) (xy 232.693543 -223.1738)
			(xy 232.744878 -223.18193) (xy 232.794308 -223.197991) (xy 232.840618 -223.221587) (xy 232.882666 -223.252137)
			(xy 232.919417 -223.288888) (xy 232.949967 -223.330936) (xy 232.973563 -223.377246) (xy 232.989624 -223.426676)
			(xy 232.997754 -223.478011) (xy 232.998264 -223.503998) (xy 232.997754 -223.529985) (xy 233.137204 -223.529985)
			(xy 233.137204 -223.478011) (xy 233.145334 -223.426676) (xy 233.161395 -223.377246) (xy 233.184991 -223.330936)
			(xy 233.215541 -223.288888) (xy 233.252292 -223.252137) (xy 233.29434 -223.221587) (xy 233.34065 -223.197991)
			(xy 233.39008 -223.18193) (xy 233.441415 -223.1738) (xy 233.493389 -223.1738) (xy 233.544724 -223.18193)
			(xy 233.594154 -223.197991) (xy 233.640464 -223.221587) (xy 233.682512 -223.252137) (xy 233.719263 -223.288888)
			(xy 233.749813 -223.330936) (xy 233.773409 -223.377246) (xy 233.78947 -223.426676) (xy 233.7976 -223.478011)
			(xy 233.79811 -223.503998) (xy 233.7976 -223.529985) (xy 233.937304 -223.529985) (xy 233.937304 -223.478011)
			(xy 233.945434 -223.426676) (xy 233.961495 -223.377246) (xy 233.985091 -223.330936) (xy 234.015641 -223.288888)
			(xy 234.052392 -223.252137) (xy 234.09444 -223.221587) (xy 234.14075 -223.197991) (xy 234.19018 -223.18193)
			(xy 234.241515 -223.1738) (xy 234.293489 -223.1738) (xy 234.344824 -223.18193) (xy 234.394254 -223.197991)
			(xy 234.440564 -223.221587) (xy 234.482612 -223.252137) (xy 234.519363 -223.288888) (xy 234.549913 -223.330936)
			(xy 234.573509 -223.377246) (xy 234.58957 -223.426676) (xy 234.5977 -223.478011) (xy 234.59821 -223.503998)
			(xy 234.5977 -223.529985) (xy 234.73715 -223.529985) (xy 234.73715 -223.478011) (xy 234.74528 -223.426676)
			(xy 234.761341 -223.377246) (xy 234.784937 -223.330936) (xy 234.815487 -223.288888) (xy 234.852238 -223.252137)
			(xy 234.894286 -223.221587) (xy 234.940596 -223.197991) (xy 234.990026 -223.18193) (xy 235.041361 -223.1738)
			(xy 235.093335 -223.1738) (xy 235.14467 -223.18193) (xy 235.1941 -223.197991) (xy 235.24041 -223.221587)
			(xy 235.282458 -223.252137) (xy 235.319209 -223.288888) (xy 235.349759 -223.330936) (xy 235.373355 -223.377246)
			(xy 235.389416 -223.426676) (xy 235.397546 -223.478011) (xy 235.398056 -223.503998) (xy 235.397546 -223.529985)
			(xy 235.53725 -223.529985) (xy 235.53725 -223.478011) (xy 235.54538 -223.426676) (xy 235.561441 -223.377246)
			(xy 235.585037 -223.330936) (xy 235.615587 -223.288888) (xy 235.652338 -223.252137) (xy 235.694386 -223.221587)
			(xy 235.740696 -223.197991) (xy 235.790126 -223.18193) (xy 235.841461 -223.1738) (xy 235.893435 -223.1738)
			(xy 235.94477 -223.18193) (xy 235.9942 -223.197991) (xy 236.04051 -223.221587) (xy 236.082558 -223.252137)
			(xy 236.119309 -223.288888) (xy 236.149859 -223.330936) (xy 236.173455 -223.377246) (xy 236.189516 -223.426676)
			(xy 236.197646 -223.478011) (xy 236.198156 -223.503998) (xy 236.197646 -223.529985) (xy 236.189516 -223.58132)
			(xy 236.173455 -223.63075) (xy 236.149859 -223.67706) (xy 236.119309 -223.719108) (xy 236.082558 -223.755859)
			(xy 236.04051 -223.786409) (xy 235.9942 -223.810005) (xy 235.94477 -223.826066) (xy 235.893435 -223.834196)
			(xy 235.841461 -223.834196) (xy 235.790126 -223.826066) (xy 235.740696 -223.810005) (xy 235.694386 -223.786409)
			(xy 235.652338 -223.755859) (xy 235.615587 -223.719108) (xy 235.585037 -223.67706) (xy 235.561441 -223.63075)
			(xy 235.54538 -223.58132) (xy 235.53725 -223.529985) (xy 235.397546 -223.529985) (xy 235.389416 -223.58132)
			(xy 235.373355 -223.63075) (xy 235.349759 -223.67706) (xy 235.319209 -223.719108) (xy 235.282458 -223.755859)
			(xy 235.24041 -223.786409) (xy 235.1941 -223.810005) (xy 235.14467 -223.826066) (xy 235.093335 -223.834196)
			(xy 235.041361 -223.834196) (xy 234.990026 -223.826066) (xy 234.940596 -223.810005) (xy 234.894286 -223.786409)
			(xy 234.852238 -223.755859) (xy 234.815487 -223.719108) (xy 234.784937 -223.67706) (xy 234.761341 -223.63075)
			(xy 234.74528 -223.58132) (xy 234.73715 -223.529985) (xy 234.5977 -223.529985) (xy 234.58957 -223.58132)
			(xy 234.573509 -223.63075) (xy 234.549913 -223.67706) (xy 234.519363 -223.719108) (xy 234.482612 -223.755859)
			(xy 234.440564 -223.786409) (xy 234.394254 -223.810005) (xy 234.344824 -223.826066) (xy 234.293489 -223.834196)
			(xy 234.241515 -223.834196) (xy 234.19018 -223.826066) (xy 234.14075 -223.810005) (xy 234.09444 -223.786409)
			(xy 234.052392 -223.755859) (xy 234.015641 -223.719108) (xy 233.985091 -223.67706) (xy 233.961495 -223.63075)
			(xy 233.945434 -223.58132) (xy 233.937304 -223.529985) (xy 233.7976 -223.529985) (xy 233.78947 -223.58132)
			(xy 233.773409 -223.63075) (xy 233.749813 -223.67706) (xy 233.719263 -223.719108) (xy 233.682512 -223.755859)
			(xy 233.640464 -223.786409) (xy 233.594154 -223.810005) (xy 233.544724 -223.826066) (xy 233.493389 -223.834196)
			(xy 233.441415 -223.834196) (xy 233.39008 -223.826066) (xy 233.34065 -223.810005) (xy 233.29434 -223.786409)
			(xy 233.252292 -223.755859) (xy 233.215541 -223.719108) (xy 233.184991 -223.67706) (xy 233.161395 -223.63075)
			(xy 233.145334 -223.58132) (xy 233.137204 -223.529985) (xy 232.997754 -223.529985) (xy 232.989624 -223.58132)
			(xy 232.973563 -223.63075) (xy 232.949967 -223.67706) (xy 232.919417 -223.719108) (xy 232.882666 -223.755859)
			(xy 232.840618 -223.786409) (xy 232.794308 -223.810005) (xy 232.744878 -223.826066) (xy 232.693543 -223.834196)
			(xy 232.641569 -223.834196) (xy 232.590234 -223.826066) (xy 232.540804 -223.810005) (xy 232.494494 -223.786409)
			(xy 232.452446 -223.755859) (xy 232.415695 -223.719108) (xy 232.385145 -223.67706) (xy 232.361549 -223.63075)
			(xy 232.345488 -223.58132) (xy 232.337358 -223.529985) (xy 232.197654 -223.529985) (xy 232.189524 -223.58132)
			(xy 232.173463 -223.63075) (xy 232.149867 -223.67706) (xy 232.119317 -223.719108) (xy 232.082566 -223.755859)
			(xy 232.040518 -223.786409) (xy 231.994208 -223.810005) (xy 231.944778 -223.826066) (xy 231.893443 -223.834196)
			(xy 231.841469 -223.834196) (xy 231.790134 -223.826066) (xy 231.740704 -223.810005) (xy 231.694394 -223.786409)
			(xy 231.652346 -223.755859) (xy 231.615595 -223.719108) (xy 231.585045 -223.67706) (xy 231.561449 -223.63075)
			(xy 231.545388 -223.58132) (xy 231.537258 -223.529985) (xy 231.397554 -223.529985) (xy 231.389424 -223.58132)
			(xy 231.373363 -223.63075) (xy 231.349767 -223.67706) (xy 231.319217 -223.719108) (xy 231.282466 -223.755859)
			(xy 231.240418 -223.786409) (xy 231.194108 -223.810005) (xy 231.144678 -223.826066) (xy 231.093343 -223.834196)
			(xy 231.041369 -223.834196) (xy 230.990034 -223.826066) (xy 230.940604 -223.810005) (xy 230.894294 -223.786409)
			(xy 230.852246 -223.755859) (xy 230.815495 -223.719108) (xy 230.784945 -223.67706) (xy 230.761349 -223.63075)
			(xy 230.745288 -223.58132) (xy 230.737158 -223.529985) (xy 230.597708 -223.529985) (xy 230.589578 -223.58132)
			(xy 230.573517 -223.63075) (xy 230.549921 -223.67706) (xy 230.519371 -223.719108) (xy 230.48262 -223.755859)
			(xy 230.440572 -223.786409) (xy 230.394262 -223.810005) (xy 230.344832 -223.826066) (xy 230.293497 -223.834196)
			(xy 230.241523 -223.834196) (xy 230.190188 -223.826066) (xy 230.140758 -223.810005) (xy 230.094448 -223.786409)
			(xy 230.0524 -223.755859) (xy 230.015649 -223.719108) (xy 229.985099 -223.67706) (xy 229.961503 -223.63075)
			(xy 229.945442 -223.58132) (xy 229.937312 -223.529985) (xy 228.19817 -223.529985) (xy 228.19004 -223.58132)
			(xy 228.173979 -223.63075) (xy 228.150383 -223.67706) (xy 228.119833 -223.719108) (xy 228.083082 -223.755859)
			(xy 228.041034 -223.786409) (xy 227.994724 -223.810005) (xy 227.945294 -223.826066) (xy 227.893959 -223.834196)
			(xy 227.841985 -223.834196) (xy 227.79065 -223.826066) (xy 227.74122 -223.810005) (xy 227.69491 -223.786409)
			(xy 227.652862 -223.755859) (xy 227.616111 -223.719108) (xy 227.585561 -223.67706) (xy 227.561965 -223.63075)
			(xy 227.545904 -223.58132) (xy 227.537774 -223.529985) (xy 227.39807 -223.529985) (xy 227.38994 -223.58132)
			(xy 227.373879 -223.63075) (xy 227.350283 -223.67706) (xy 227.319733 -223.719108) (xy 227.282982 -223.755859)
			(xy 227.240934 -223.786409) (xy 227.194624 -223.810005) (xy 227.145194 -223.826066) (xy 227.093859 -223.834196)
			(xy 227.041885 -223.834196) (xy 226.99055 -223.826066) (xy 226.94112 -223.810005) (xy 226.89481 -223.786409)
			(xy 226.852762 -223.755859) (xy 226.816011 -223.719108) (xy 226.785461 -223.67706) (xy 226.761865 -223.63075)
			(xy 226.745804 -223.58132) (xy 226.737674 -223.529985) (xy 226.59797 -223.529985) (xy 226.58984 -223.58132)
			(xy 226.573779 -223.63075) (xy 226.550183 -223.67706) (xy 226.519633 -223.719108) (xy 226.482882 -223.755859)
			(xy 226.440834 -223.786409) (xy 226.394524 -223.810005) (xy 226.345094 -223.826066) (xy 226.293759 -223.834196)
			(xy 226.241785 -223.834196) (xy 226.19045 -223.826066) (xy 226.14102 -223.810005) (xy 226.09471 -223.786409)
			(xy 226.052662 -223.755859) (xy 226.015911 -223.719108) (xy 225.985361 -223.67706) (xy 225.961765 -223.63075)
			(xy 225.945704 -223.58132) (xy 225.937574 -223.529985) (xy 225.798124 -223.529985) (xy 225.789994 -223.58132)
			(xy 225.773933 -223.63075) (xy 225.750337 -223.67706) (xy 225.719787 -223.719108) (xy 225.683036 -223.755859)
			(xy 225.640988 -223.786409) (xy 225.594678 -223.810005) (xy 225.545248 -223.826066) (xy 225.493913 -223.834196)
			(xy 225.441939 -223.834196) (xy 225.390604 -223.826066) (xy 225.341174 -223.810005) (xy 225.294864 -223.786409)
			(xy 225.252816 -223.755859) (xy 225.216065 -223.719108) (xy 225.185515 -223.67706) (xy 225.161919 -223.63075)
			(xy 225.145858 -223.58132) (xy 225.137728 -223.529985) (xy 224.998024 -223.529985) (xy 224.989894 -223.58132)
			(xy 224.973833 -223.63075) (xy 224.950237 -223.67706) (xy 224.919687 -223.719108) (xy 224.882936 -223.755859)
			(xy 224.840888 -223.786409) (xy 224.794578 -223.810005) (xy 224.745148 -223.826066) (xy 224.693813 -223.834196)
			(xy 224.641839 -223.834196) (xy 224.590504 -223.826066) (xy 224.541074 -223.810005) (xy 224.494764 -223.786409)
			(xy 224.452716 -223.755859) (xy 224.415965 -223.719108) (xy 224.385415 -223.67706) (xy 224.361819 -223.63075)
			(xy 224.345758 -223.58132) (xy 224.337628 -223.529985) (xy 218.609734 -223.529985) (xy 218.602247 -223.554869)
			(xy 218.578575 -223.605366) (xy 218.547802 -223.651879) (xy 218.510585 -223.693416) (xy 218.467717 -223.729091)
			(xy 218.420111 -223.758145) (xy 218.368782 -223.779957) (xy 218.314825 -223.794063) (xy 218.259388 -223.800163)
			(xy 218.203654 -223.798126) (xy 218.148811 -223.787996) (xy 218.096027 -223.769989) (xy 218.046427 -223.744488)
			(xy 218.001069 -223.712037) (xy 217.96092 -223.673328) (xy 217.926834 -223.629185) (xy 217.899538 -223.58055)
			(xy 217.879615 -223.528459) (xy 217.867489 -223.474022) (xy 217.863418 -223.4184) (xy 216.580479 -223.4184)
			(xy 216.573953 -223.463791) (xy 216.5586 -223.516081) (xy 216.535962 -223.565654) (xy 216.5065 -223.611501)
			(xy 216.470814 -223.652689) (xy 216.42963 -223.688379) (xy 216.383786 -223.717845) (xy 216.334215 -223.740487)
			(xy 216.281926 -223.755845) (xy 216.227985 -223.763605) (xy 216.200736 -223.764094) (xy 216.200482 -223.764094)
			(xy 216.174187 -223.763649) (xy 216.122097 -223.756401) (xy 216.071496 -223.742073) (xy 216.023339 -223.720935)
			(xy 215.97854 -223.693387) (xy 215.937946 -223.659952) (xy 215.919812 -223.640904) (xy 215.912287 -223.633506)
			(xy 215.89301 -223.62498) (xy 215.882474 -223.624394) (xy 215.807798 -223.624394) (xy 215.797247 -223.62491)
			(xy 215.777952 -223.633455) (xy 215.77046 -223.640904) (xy 215.752361 -223.659989) (xy 215.711772 -223.693443)
			(xy 215.66697 -223.720998) (xy 215.618804 -223.742132) (xy 215.56819 -223.756443) (xy 215.516089 -223.76366)
			(xy 215.48979 -223.764094) (xy 215.489536 -223.764094) (xy 215.462062 -223.763588) (xy 215.407683 -223.755701)
			(xy 215.355001 -223.740086) (xy 215.305108 -223.717065) (xy 215.259038 -223.687118) (xy 215.238076 -223.669352)
			(xy 215.230964 -223.663256) (xy 215.222582 -223.660208) (xy 215.218291 -223.658698) (xy 215.209349 -223.657033)
			(xy 215.204802 -223.656906) (xy 215.137238 -223.656906) (xy 215.132691 -223.657042) (xy 215.123747 -223.658693)
			(xy 215.119458 -223.660208) (xy 215.111076 -223.663256) (xy 215.103964 -223.669352) (xy 215.083007 -223.687122)
			(xy 215.036923 -223.717044) (xy 214.987027 -223.740055) (xy 214.93435 -223.755679) (xy 214.879977 -223.763595)
			(xy 214.852504 -223.764094) (xy 214.82525 -223.763659) (xy 214.771297 -223.755903) (xy 214.718996 -223.740546)
			(xy 214.669414 -223.717903) (xy 214.623558 -223.688434) (xy 214.582364 -223.652739) (xy 214.546668 -223.611545)
			(xy 214.517199 -223.56569) (xy 214.494555 -223.516108) (xy 214.479198 -223.463807) (xy 214.471441 -223.409854)
			(xy 206.597796 -223.409854) (xy 206.622971 -223.426033) (xy 206.664162 -223.461724) (xy 206.699853 -223.502915)
			(xy 206.729319 -223.548765) (xy 206.751961 -223.598342) (xy 206.767316 -223.650637) (xy 206.775072 -223.704585)
			(xy 206.775558 -223.731836) (xy 206.77516 -223.757628) (xy 206.768189 -223.80874) (xy 206.754392 -223.858445)
			(xy 206.734022 -223.905837) (xy 206.70745 -223.950051) (xy 206.67516 -223.990281) (xy 206.637744 -224.025791)
			(xy 206.617062 -224.041208) (xy 206.60868 -224.047558) (xy 206.603346 -224.056448) (xy 206.600746 -224.06105)
			(xy 206.597287 -224.071035) (xy 206.596488 -224.07626) (xy 206.596476 -224.076353) (xy 208.88956 -224.076353)
			(xy 208.88956 -224.021847) (xy 208.897317 -223.967897) (xy 208.912673 -223.9156) (xy 208.935315 -223.86602)
			(xy 208.964782 -223.820168) (xy 209.000476 -223.778976) (xy 209.041668 -223.743282) (xy 209.08752 -223.713815)
			(xy 209.1371 -223.691173) (xy 209.189397 -223.675817) (xy 209.243347 -223.66806) (xy 209.2706 -223.667574)
			(xy 209.297839 -223.668077) (xy 209.351763 -223.675826) (xy 209.404036 -223.691168) (xy 209.453595 -223.713789)
			(xy 209.499432 -223.74323) (xy 209.540615 -223.778892) (xy 209.576307 -223.82005) (xy 209.60578 -223.865866)
			(xy 209.628437 -223.915409) (xy 209.643816 -223.967671) (xy 209.647394 -223.99244) (xy 211.421472 -223.99244)
			(xy 211.421958 -223.965189) (xy 211.429714 -223.911241) (xy 211.445069 -223.858946) (xy 211.467711 -223.809369)
			(xy 211.497177 -223.763519) (xy 211.532868 -223.722328) (xy 211.574059 -223.686637) (xy 211.619909 -223.657171)
			(xy 211.669486 -223.634529) (xy 211.721781 -223.619174) (xy 211.775729 -223.611418) (xy 211.830231 -223.611418)
			(xy 211.884179 -223.619174) (xy 211.936474 -223.634529) (xy 211.986051 -223.657171) (xy 212.031901 -223.686637)
			(xy 212.073092 -223.722328) (xy 212.108783 -223.763519) (xy 212.138249 -223.809369) (xy 212.160891 -223.858946)
			(xy 212.176246 -223.911241) (xy 212.184002 -223.965189) (xy 212.184488 -223.99244) (xy 212.184488 -223.992694)
			(xy 212.183991 -224.020668) (xy 212.1758 -224.076013) (xy 212.159622 -224.12957) (xy 212.135802 -224.180194)
			(xy 212.120734 -224.203768) (xy 212.114892 -224.212404) (xy 212.113114 -224.222564) (xy 212.112293 -224.227617)
			(xy 212.112419 -224.237853) (xy 212.113368 -224.242884) (xy 212.129116 -224.314258) (xy 212.131656 -224.322132)
			(xy 212.137752 -224.333308) (xy 212.143594 -224.341182) (xy 212.152484 -224.34677) (xy 212.162644 -224.35312)
			(xy 212.174328 -224.354136) (xy 212.18009 -224.35447) (xy 212.191508 -224.352801) (xy 212.196934 -224.350834)
			(xy 212.272118 -224.322132) (xy 212.278468 -224.319338) (xy 212.28558 -224.314512) (xy 212.291676 -224.308924)
			(xy 212.299296 -224.300542) (xy 212.302598 -224.289112) (xy 212.310807 -224.263241) (xy 212.333605 -224.213983)
			(xy 212.363152 -224.168452) (xy 212.398852 -224.127567) (xy 212.439985 -224.092153) (xy 212.48572 -224.062924)
			(xy 212.535136 -224.040471) (xy 212.587235 -224.025245) (xy 212.640965 -224.017555) (xy 212.668104 -224.017078)
			(xy 212.695354 -224.017593) (xy 212.749299 -224.025349) (xy 212.801592 -224.040704) (xy 212.851166 -224.063345)
			(xy 212.897015 -224.09281) (xy 212.938203 -224.1285) (xy 212.973893 -224.169689) (xy 213.003357 -224.215537)
			(xy 213.025997 -224.265112) (xy 213.041352 -224.317405) (xy 213.049108 -224.37135) (xy 213.049108 -224.42585)
			(xy 213.0479 -224.434253) (xy 214.409746 -224.434253) (xy 214.409746 -224.379747) (xy 214.417503 -224.325797)
			(xy 214.432858 -224.273499) (xy 214.4555 -224.223919) (xy 214.484967 -224.178065) (xy 214.520659 -224.136872)
			(xy 214.561851 -224.101178) (xy 214.607703 -224.071708) (xy 214.657282 -224.049064) (xy 214.709579 -224.033706)
			(xy 214.763529 -224.025947) (xy 214.790782 -224.02546) (xy 214.817717 -224.025911) (xy 214.871049 -224.033503)
			(xy 214.922782 -224.048525) (xy 214.971886 -224.070678) (xy 215.017384 -224.09952) (xy 215.038178 -224.116646)
			(xy 215.045544 -224.122742) (xy 215.05418 -224.12579) (xy 215.058498 -224.12706) (xy 215.062234 -224.128004)
			(xy 215.069886 -224.128899) (xy 215.073738 -224.128838) (xy 215.14181 -224.126044) (xy 215.146377 -224.125788)
			(xy 215.15532 -224.123874) (xy 215.15959 -224.122234) (xy 215.16848 -224.118424) (xy 215.175338 -224.111566)
			(xy 215.196887 -224.091184) (xy 215.2451 -224.056641) (xy 215.29808 -224.029977) (xy 215.354549 -224.011836)
			(xy 215.413145 -224.002655) (xy 215.4428 -224.002092) (xy 215.473032 -224.002653) (xy 215.532738 -224.012203)
			(xy 215.59019 -224.031048) (xy 215.643953 -224.058717) (xy 215.69268 -224.094517) (xy 215.714326 -224.11563)
			(xy 215.721184 -224.122488) (xy 215.729566 -224.126298) (xy 215.742774 -224.130108) (xy 215.748362 -224.130616)
			(xy 215.817958 -224.133156) (xy 215.822805 -224.133266) (xy 215.832395 -224.131854) (xy 215.837008 -224.130362)
			(xy 215.845644 -224.127314) (xy 215.85301 -224.120964) (xy 215.873922 -224.10341) (xy 215.919829 -224.073854)
			(xy 215.969479 -224.051143) (xy 216.02186 -224.035739) (xy 216.075901 -224.027958) (xy 216.1032 -224.027492)
			(xy 216.130451 -224.027978) (xy 216.184399 -224.035734) (xy 216.236694 -224.051089) (xy 216.286271 -224.073731)
			(xy 216.332121 -224.103197) (xy 216.373312 -224.138888) (xy 216.409003 -224.180079) (xy 216.438469 -224.225929)
			(xy 216.461111 -224.275506) (xy 216.476466 -224.327801) (xy 216.484222 -224.381749) (xy 216.484222 -224.436251)
			(xy 216.477185 -224.4852) (xy 217.959938 -224.4852) (xy 217.964009 -224.429578) (xy 217.976135 -224.375141)
			(xy 217.996058 -224.32305) (xy 218.023354 -224.274415) (xy 218.05744 -224.230272) (xy 218.097589 -224.191563)
			(xy 218.142947 -224.159112) (xy 218.192547 -224.133611) (xy 218.245331 -224.115604) (xy 218.300174 -224.105474)
			(xy 218.355908 -224.103437) (xy 218.411345 -224.109537) (xy 218.465302 -224.123643) (xy 218.516631 -224.145455)
			(xy 218.564237 -224.174509) (xy 218.607105 -224.210184) (xy 218.644322 -224.251721) (xy 218.675095 -224.298234)
			(xy 218.689907 -224.329831) (xy 223.537782 -224.329831) (xy 223.537782 -224.277857) (xy 223.545912 -224.226522)
			(xy 223.561973 -224.177092) (xy 223.585569 -224.130782) (xy 223.616119 -224.088734) (xy 223.65287 -224.051983)
			(xy 223.694918 -224.021433) (xy 223.741228 -223.997837) (xy 223.790658 -223.981776) (xy 223.841993 -223.973646)
			(xy 223.893967 -223.973646) (xy 223.945302 -223.981776) (xy 223.994732 -223.997837) (xy 224.041042 -224.021433)
			(xy 224.08309 -224.051983) (xy 224.119841 -224.088734) (xy 224.150391 -224.130782) (xy 224.173987 -224.177092)
			(xy 224.190048 -224.226522) (xy 224.198178 -224.277857) (xy 224.198688 -224.303844) (xy 224.198178 -224.329831)
			(xy 233.137204 -224.329831) (xy 233.137204 -224.277857) (xy 233.145334 -224.226522) (xy 233.161395 -224.177092)
			(xy 233.184991 -224.130782) (xy 233.215541 -224.088734) (xy 233.252292 -224.051983) (xy 233.29434 -224.021433)
			(xy 233.34065 -223.997837) (xy 233.39008 -223.981776) (xy 233.441415 -223.973646) (xy 233.493389 -223.973646)
			(xy 233.544724 -223.981776) (xy 233.594154 -223.997837) (xy 233.640464 -224.021433) (xy 233.682512 -224.051983)
			(xy 233.719263 -224.088734) (xy 233.749813 -224.130782) (xy 233.773409 -224.177092) (xy 233.78947 -224.226522)
			(xy 233.7976 -224.277857) (xy 233.79811 -224.303844) (xy 233.7976 -224.329831) (xy 233.937304 -224.329831)
			(xy 233.937304 -224.277857) (xy 233.945434 -224.226522) (xy 233.961495 -224.177092) (xy 233.985091 -224.130782)
			(xy 234.015641 -224.088734) (xy 234.052392 -224.051983) (xy 234.09444 -224.021433) (xy 234.14075 -223.997837)
			(xy 234.19018 -223.981776) (xy 234.241515 -223.973646) (xy 234.293489 -223.973646) (xy 234.344824 -223.981776)
			(xy 234.394254 -223.997837) (xy 234.440564 -224.021433) (xy 234.482612 -224.051983) (xy 234.519363 -224.088734)
			(xy 234.549913 -224.130782) (xy 234.573509 -224.177092) (xy 234.58957 -224.226522) (xy 234.5977 -224.277857)
			(xy 234.59821 -224.303844) (xy 234.5977 -224.329831) (xy 234.73715 -224.329831) (xy 234.73715 -224.277857)
			(xy 234.74528 -224.226522) (xy 234.761341 -224.177092) (xy 234.784937 -224.130782) (xy 234.815487 -224.088734)
			(xy 234.852238 -224.051983) (xy 234.894286 -224.021433) (xy 234.940596 -223.997837) (xy 234.990026 -223.981776)
			(xy 235.041361 -223.973646) (xy 235.093335 -223.973646) (xy 235.14467 -223.981776) (xy 235.1941 -223.997837)
			(xy 235.24041 -224.021433) (xy 235.282458 -224.051983) (xy 235.319209 -224.088734) (xy 235.349759 -224.130782)
			(xy 235.373355 -224.177092) (xy 235.389416 -224.226522) (xy 235.397546 -224.277857) (xy 235.398056 -224.303844)
			(xy 235.397546 -224.329831) (xy 235.53725 -224.329831) (xy 235.53725 -224.277857) (xy 235.54538 -224.226522)
			(xy 235.561441 -224.177092) (xy 235.585037 -224.130782) (xy 235.615587 -224.088734) (xy 235.652338 -224.051983)
			(xy 235.694386 -224.021433) (xy 235.740696 -223.997837) (xy 235.790126 -223.981776) (xy 235.841461 -223.973646)
			(xy 235.893435 -223.973646) (xy 235.94477 -223.981776) (xy 235.9942 -223.997837) (xy 236.04051 -224.021433)
			(xy 236.082558 -224.051983) (xy 236.119309 -224.088734) (xy 236.149859 -224.130782) (xy 236.173455 -224.177092)
			(xy 236.189516 -224.226522) (xy 236.197646 -224.277857) (xy 236.198156 -224.303844) (xy 236.197646 -224.329831)
			(xy 236.189516 -224.381166) (xy 236.173455 -224.430596) (xy 236.149859 -224.476906) (xy 236.119309 -224.518954)
			(xy 236.082558 -224.555705) (xy 236.04051 -224.586255) (xy 235.9942 -224.609851) (xy 235.94477 -224.625912)
			(xy 235.893435 -224.634042) (xy 235.841461 -224.634042) (xy 235.790126 -224.625912) (xy 235.740696 -224.609851)
			(xy 235.694386 -224.586255) (xy 235.652338 -224.555705) (xy 235.615587 -224.518954) (xy 235.585037 -224.476906)
			(xy 235.561441 -224.430596) (xy 235.54538 -224.381166) (xy 235.53725 -224.329831) (xy 235.397546 -224.329831)
			(xy 235.389416 -224.381166) (xy 235.373355 -224.430596) (xy 235.349759 -224.476906) (xy 235.319209 -224.518954)
			(xy 235.282458 -224.555705) (xy 235.24041 -224.586255) (xy 235.1941 -224.609851) (xy 235.14467 -224.625912)
			(xy 235.093335 -224.634042) (xy 235.041361 -224.634042) (xy 234.990026 -224.625912) (xy 234.940596 -224.609851)
			(xy 234.894286 -224.586255) (xy 234.852238 -224.555705) (xy 234.815487 -224.518954) (xy 234.784937 -224.476906)
			(xy 234.761341 -224.430596) (xy 234.74528 -224.381166) (xy 234.73715 -224.329831) (xy 234.5977 -224.329831)
			(xy 234.58957 -224.381166) (xy 234.573509 -224.430596) (xy 234.549913 -224.476906) (xy 234.519363 -224.518954)
			(xy 234.482612 -224.555705) (xy 234.440564 -224.586255) (xy 234.394254 -224.609851) (xy 234.344824 -224.625912)
			(xy 234.293489 -224.634042) (xy 234.241515 -224.634042) (xy 234.19018 -224.625912) (xy 234.14075 -224.609851)
			(xy 234.09444 -224.586255) (xy 234.052392 -224.555705) (xy 234.015641 -224.518954) (xy 233.985091 -224.476906)
			(xy 233.961495 -224.430596) (xy 233.945434 -224.381166) (xy 233.937304 -224.329831) (xy 233.7976 -224.329831)
			(xy 233.78947 -224.381166) (xy 233.773409 -224.430596) (xy 233.749813 -224.476906) (xy 233.719263 -224.518954)
			(xy 233.682512 -224.555705) (xy 233.640464 -224.586255) (xy 233.594154 -224.609851) (xy 233.544724 -224.625912)
			(xy 233.493389 -224.634042) (xy 233.441415 -224.634042) (xy 233.39008 -224.625912) (xy 233.34065 -224.609851)
			(xy 233.29434 -224.586255) (xy 233.252292 -224.555705) (xy 233.215541 -224.518954) (xy 233.184991 -224.476906)
			(xy 233.161395 -224.430596) (xy 233.145334 -224.381166) (xy 233.137204 -224.329831) (xy 224.198178 -224.329831)
			(xy 224.190048 -224.381166) (xy 224.173987 -224.430596) (xy 224.150391 -224.476906) (xy 224.119841 -224.518954)
			(xy 224.08309 -224.555705) (xy 224.041042 -224.586255) (xy 223.994732 -224.609851) (xy 223.945302 -224.625912)
			(xy 223.893967 -224.634042) (xy 223.841993 -224.634042) (xy 223.790658 -224.625912) (xy 223.741228 -224.609851)
			(xy 223.694918 -224.586255) (xy 223.65287 -224.555705) (xy 223.616119 -224.518954) (xy 223.585569 -224.476906)
			(xy 223.561973 -224.430596) (xy 223.545912 -224.381166) (xy 223.537782 -224.329831) (xy 218.689907 -224.329831)
			(xy 218.698767 -224.348731) (xy 218.714835 -224.402138) (xy 218.722955 -224.457314) (xy 218.723464 -224.4852)
			(xy 218.722955 -224.513086) (xy 218.714835 -224.568262) (xy 218.698767 -224.621669) (xy 218.675095 -224.672166)
			(xy 218.644322 -224.718679) (xy 218.607105 -224.760216) (xy 218.564237 -224.795891) (xy 218.516631 -224.824945)
			(xy 218.465302 -224.846757) (xy 218.411345 -224.860863) (xy 218.355908 -224.866963) (xy 218.300174 -224.864926)
			(xy 218.245331 -224.854796) (xy 218.192547 -224.836789) (xy 218.142947 -224.811288) (xy 218.097589 -224.778837)
			(xy 218.05744 -224.740128) (xy 218.023354 -224.695985) (xy 217.996058 -224.64735) (xy 217.976135 -224.595259)
			(xy 217.964009 -224.540822) (xy 217.959938 -224.4852) (xy 216.477185 -224.4852) (xy 216.476466 -224.490199)
			(xy 216.461111 -224.542494) (xy 216.438469 -224.592071) (xy 216.409003 -224.637921) (xy 216.373312 -224.679112)
			(xy 216.332121 -224.714803) (xy 216.286271 -224.744269) (xy 216.236694 -224.766911) (xy 216.184399 -224.782266)
			(xy 216.130451 -224.790022) (xy 216.1032 -224.790508) (xy 216.072968 -224.789947) (xy 216.013262 -224.780397)
			(xy 215.95581 -224.761552) (xy 215.902047 -224.733883) (xy 215.85332 -224.698083) (xy 215.831674 -224.67697)
			(xy 215.824816 -224.670112) (xy 215.816434 -224.666302) (xy 215.803226 -224.662492) (xy 215.797638 -224.661984)
			(xy 215.728042 -224.659444) (xy 215.723195 -224.659334) (xy 215.713605 -224.660746) (xy 215.708992 -224.662238)
			(xy 215.700356 -224.665286) (xy 215.69299 -224.671636) (xy 215.672078 -224.68919) (xy 215.626171 -224.718746)
			(xy 215.576521 -224.741457) (xy 215.52414 -224.756861) (xy 215.470099 -224.764642) (xy 215.4428 -224.765108)
			(xy 215.415865 -224.764675) (xy 215.362531 -224.75708) (xy 215.310798 -224.742054) (xy 215.261694 -224.719897)
			(xy 215.216197 -224.69105) (xy 215.195404 -224.673922) (xy 215.188038 -224.667826) (xy 215.179402 -224.664778)
			(xy 215.177878 -224.66427) (xy 215.1735 -224.662916) (xy 215.164426 -224.661642) (xy 215.159844 -224.66173)
			(xy 215.091772 -224.664524) (xy 215.087205 -224.664778) (xy 215.078262 -224.666694) (xy 215.073992 -224.668334)
			(xy 215.065102 -224.672144) (xy 215.058244 -224.679002) (xy 215.036698 -224.699387) (xy 214.988484 -224.733931)
			(xy 214.935504 -224.760595) (xy 214.879035 -224.778735) (xy 214.820438 -224.787914) (xy 214.790782 -224.788476)
			(xy 214.763529 -224.788053) (xy 214.709579 -224.780294) (xy 214.657282 -224.764936) (xy 214.607703 -224.742292)
			(xy 214.561851 -224.712822) (xy 214.520659 -224.677128) (xy 214.484967 -224.635935) (xy 214.4555 -224.590081)
			(xy 214.432858 -224.540501) (xy 214.417503 -224.488203) (xy 214.409746 -224.434253) (xy 213.0479 -224.434253)
			(xy 213.041352 -224.479795) (xy 213.025997 -224.532088) (xy 213.003357 -224.581663) (xy 212.973893 -224.627511)
			(xy 212.938203 -224.6687) (xy 212.897015 -224.70439) (xy 212.851166 -224.733855) (xy 212.801592 -224.756496)
			(xy 212.749299 -224.771851) (xy 212.695354 -224.779607) (xy 212.668104 -224.780094) (xy 212.642015 -224.779672)
			(xy 212.590325 -224.772562) (xy 212.540086 -224.758473) (xy 212.492236 -224.73767) (xy 212.46973 -224.724468)
			(xy 212.45957 -224.718118) (xy 212.447886 -224.717102) (xy 212.442124 -224.71677) (xy 212.430706 -224.718437)
			(xy 212.42528 -224.720404) (xy 212.350096 -224.749106) (xy 212.343746 -224.7519) (xy 212.336634 -224.756726)
			(xy 212.330538 -224.762314) (xy 212.322918 -224.770696) (xy 212.319616 -224.782126) (xy 212.311418 -224.808001)
			(xy 212.288617 -224.857257) (xy 212.259067 -224.902786) (xy 212.223365 -224.94367) (xy 212.182231 -224.979083)
			(xy 212.136494 -225.008311) (xy 212.087078 -225.030765) (xy 212.034979 -225.045991) (xy 211.981249 -225.053682)
			(xy 211.95411 -225.05416) (xy 211.926855 -225.053735) (xy 211.8729 -225.045978) (xy 211.820599 -225.030621)
			(xy 211.771016 -225.007976) (xy 211.72516 -224.978505) (xy 211.683966 -224.942807) (xy 211.648272 -224.901609)
			(xy 211.618805 -224.855751) (xy 211.596166 -224.806165) (xy 211.580814 -224.753862) (xy 211.573062 -224.699907)
			(xy 211.572602 -224.672652) (xy 211.572602 -224.672398) (xy 211.573097 -224.644424) (xy 211.581289 -224.589079)
			(xy 211.597468 -224.535522) (xy 211.621288 -224.484898) (xy 211.636356 -224.461324) (xy 211.642198 -224.452688)
			(xy 211.643976 -224.442528) (xy 211.644798 -224.437475) (xy 211.644671 -224.427239) (xy 211.643722 -224.422208)
			(xy 211.627974 -224.350834) (xy 211.625434 -224.34296) (xy 211.619338 -224.331784) (xy 211.613496 -224.32391)
			(xy 211.604606 -224.318322) (xy 211.581027 -224.303366) (xy 211.538074 -224.267694) (xy 211.50078 -224.226141)
			(xy 211.469939 -224.179597) (xy 211.446212 -224.129055) (xy 211.430105 -224.075595) (xy 211.421961 -224.020357)
			(xy 211.421472 -223.99244) (xy 209.647394 -223.99244) (xy 209.651604 -224.021589) (xy 209.652108 -224.048828)
			(xy 209.652108 -224.049336) (xy 209.651854 -224.059242) (xy 209.651854 -224.05975) (xy 209.652017 -224.073429)
			(xy 209.658584 -224.099968) (xy 209.671958 -224.123812) (xy 209.691182 -224.143251) (xy 209.714876 -224.156891)
			(xy 209.74134 -224.163754) (xy 209.768676 -224.163346) (xy 209.794924 -224.155698) (xy 209.806794 -224.148904)
			(xy 209.829425 -224.135551) (xy 209.877553 -224.114462) (xy 209.928118 -224.100175) (xy 209.980165 -224.092958)
			(xy 210.006438 -224.092516) (xy 210.033689 -224.092956) (xy 210.087636 -224.100718) (xy 210.13993 -224.116077)
			(xy 210.189505 -224.138722) (xy 210.235354 -224.168191) (xy 210.276542 -224.203885) (xy 210.312232 -224.245077)
			(xy 210.341696 -224.290928) (xy 210.364336 -224.340506) (xy 210.37969 -224.392801) (xy 210.387446 -224.446749)
			(xy 210.387446 -224.501251) (xy 210.37969 -224.555199) (xy 210.364336 -224.607494) (xy 210.341696 -224.657072)
			(xy 210.312232 -224.702923) (xy 210.276542 -224.744115) (xy 210.235354 -224.779809) (xy 210.189505 -224.809278)
			(xy 210.13993 -224.831923) (xy 210.087636 -224.847282) (xy 210.033689 -224.855044) (xy 210.006438 -224.855532)
			(xy 209.9792 -224.854987) (xy 209.925278 -224.847243) (xy 209.873006 -224.831907) (xy 209.823448 -224.809291)
			(xy 209.777611 -224.779854) (xy 209.736427 -224.744196) (xy 209.700736 -224.703042) (xy 209.671261 -224.65723)
			(xy 209.648604 -224.60769) (xy 209.633224 -224.555431) (xy 209.625435 -224.501515) (xy 209.62493 -224.474278)
			(xy 209.62493 -224.47377) (xy 209.625184 -224.463864) (xy 209.625184 -224.463356) (xy 209.625111 -224.449672)
			(xy 209.61854 -224.423118) (xy 209.605156 -224.399262) (xy 209.585919 -224.379815) (xy 209.562208 -224.366173)
			(xy 209.535727 -224.359315) (xy 209.508376 -224.359733) (xy 209.482117 -224.367398) (xy 209.470244 -224.374202)
			(xy 209.447627 -224.387581) (xy 209.399495 -224.408663) (xy 209.348925 -224.422943) (xy 209.296874 -224.430152)
			(xy 209.2706 -224.43059) (xy 209.243347 -224.43014) (xy 209.189397 -224.422383) (xy 209.1371 -224.407027)
			(xy 209.08752 -224.384385) (xy 209.041668 -224.354918) (xy 209.000476 -224.319224) (xy 208.964782 -224.278032)
			(xy 208.935315 -224.23218) (xy 208.912673 -224.1826) (xy 208.897317 -224.130303) (xy 208.88956 -224.076353)
			(xy 206.596476 -224.076353) (xy 206.586836 -224.149666) (xy 206.586378 -224.154849) (xy 206.587268 -224.165214)
			(xy 206.588614 -224.17024) (xy 206.591408 -224.180146) (xy 206.598012 -224.188274) (xy 206.614425 -224.208834)
			(xy 206.641995 -224.253639) (xy 206.663144 -224.301809) (xy 206.677468 -224.35243) (xy 206.684695 -224.40454)
			(xy 206.685134 -224.430844) (xy 206.684648 -224.458095) (xy 206.676892 -224.512043) (xy 206.661537 -224.564338)
			(xy 206.638895 -224.613915) (xy 206.609429 -224.659765) (xy 206.573738 -224.700956) (xy 206.532547 -224.736647)
			(xy 206.486697 -224.766113) (xy 206.43712 -224.788755) (xy 206.384825 -224.80411) (xy 206.330877 -224.811866)
			(xy 206.276375 -224.811866) (xy 206.222427 -224.80411) (xy 206.170132 -224.788755) (xy 206.120555 -224.766113)
			(xy 206.074705 -224.736647) (xy 206.033514 -224.700956) (xy 205.997823 -224.659765) (xy 205.968357 -224.613915)
			(xy 205.945715 -224.564338) (xy 205.93036 -224.512043) (xy 205.922604 -224.458095) (xy 205.922118 -224.430844)
			(xy 196.968618 -224.430844) (xy 196.968618 -225.449752) (xy 214.493838 -225.449752) (xy 214.493838 -225.395248)
			(xy 214.501594 -225.341298) (xy 214.516948 -225.289002) (xy 214.539589 -225.239422) (xy 214.569054 -225.193569)
			(xy 214.604745 -225.152376) (xy 214.645934 -225.11668) (xy 214.691784 -225.08721) (xy 214.74136 -225.064564)
			(xy 214.793655 -225.049203) (xy 214.847604 -225.041441) (xy 214.874856 -225.040952) (xy 214.90122 -225.04141)
			(xy 214.953443 -225.04869) (xy 215.004167 -225.06309) (xy 215.052425 -225.084335) (xy 215.0973 -225.112022)
			(xy 215.118959 -225.129931) (xy 223.537782 -225.129931) (xy 223.537782 -225.077957) (xy 223.545912 -225.026622)
			(xy 223.561973 -224.977192) (xy 223.585569 -224.930882) (xy 223.616119 -224.888834) (xy 223.65287 -224.852083)
			(xy 223.694918 -224.821533) (xy 223.741228 -224.797937) (xy 223.790658 -224.781876) (xy 223.841993 -224.773746)
			(xy 223.893967 -224.773746) (xy 223.945302 -224.781876) (xy 223.994732 -224.797937) (xy 224.041042 -224.821533)
			(xy 224.08309 -224.852083) (xy 224.119841 -224.888834) (xy 224.150391 -224.930882) (xy 224.173987 -224.977192)
			(xy 224.190048 -225.026622) (xy 224.198178 -225.077957) (xy 224.198688 -225.103944) (xy 224.198178 -225.129931)
			(xy 224.193431 -225.159903) (xy 224.354392 -225.159903) (xy 224.354392 -225.107929) (xy 224.362522 -225.056594)
			(xy 224.378583 -225.007164) (xy 224.402179 -224.960854) (xy 224.432729 -224.918806) (xy 224.46948 -224.882055)
			(xy 224.511528 -224.851505) (xy 224.557838 -224.827909) (xy 224.607268 -224.811848) (xy 224.658603 -224.803718)
			(xy 224.710577 -224.803718) (xy 224.761912 -224.811848) (xy 224.811342 -224.827909) (xy 224.857652 -224.851505)
			(xy 224.8997 -224.882055) (xy 224.936451 -224.918806) (xy 224.967001 -224.960854) (xy 224.990597 -225.007164)
			(xy 225.006658 -225.056594) (xy 225.014788 -225.107929) (xy 225.01522 -225.129931) (xy 233.937304 -225.129931)
			(xy 233.937304 -225.077957) (xy 233.945434 -225.026622) (xy 233.961495 -224.977192) (xy 233.985091 -224.930882)
			(xy 234.015641 -224.888834) (xy 234.052392 -224.852083) (xy 234.09444 -224.821533) (xy 234.14075 -224.797937)
			(xy 234.19018 -224.781876) (xy 234.241515 -224.773746) (xy 234.293489 -224.773746) (xy 234.344824 -224.781876)
			(xy 234.394254 -224.797937) (xy 234.440564 -224.821533) (xy 234.482612 -224.852083) (xy 234.519363 -224.888834)
			(xy 234.549913 -224.930882) (xy 234.573509 -224.977192) (xy 234.58957 -225.026622) (xy 234.5977 -225.077957)
			(xy 234.59821 -225.103944) (xy 234.5977 -225.129931) (xy 234.73715 -225.129931) (xy 234.73715 -225.077957)
			(xy 234.74528 -225.026622) (xy 234.761341 -224.977192) (xy 234.784937 -224.930882) (xy 234.815487 -224.888834)
			(xy 234.852238 -224.852083) (xy 234.894286 -224.821533) (xy 234.940596 -224.797937) (xy 234.990026 -224.781876)
			(xy 235.041361 -224.773746) (xy 235.093335 -224.773746) (xy 235.14467 -224.781876) (xy 235.1941 -224.797937)
			(xy 235.24041 -224.821533) (xy 235.282458 -224.852083) (xy 235.319209 -224.888834) (xy 235.349759 -224.930882)
			(xy 235.373355 -224.977192) (xy 235.389416 -225.026622) (xy 235.397546 -225.077957) (xy 235.398056 -225.103944)
			(xy 235.397546 -225.129931) (xy 235.53725 -225.129931) (xy 235.53725 -225.077957) (xy 235.54538 -225.026622)
			(xy 235.561441 -224.977192) (xy 235.585037 -224.930882) (xy 235.615587 -224.888834) (xy 235.652338 -224.852083)
			(xy 235.694386 -224.821533) (xy 235.740696 -224.797937) (xy 235.790126 -224.781876) (xy 235.841461 -224.773746)
			(xy 235.893435 -224.773746) (xy 235.94477 -224.781876) (xy 235.9942 -224.797937) (xy 236.04051 -224.821533)
			(xy 236.082558 -224.852083) (xy 236.119309 -224.888834) (xy 236.149859 -224.930882) (xy 236.173455 -224.977192)
			(xy 236.189516 -225.026622) (xy 236.197646 -225.077957) (xy 236.198156 -225.103944) (xy 236.197646 -225.129931)
			(xy 236.189516 -225.181266) (xy 236.173455 -225.230696) (xy 236.149859 -225.277006) (xy 236.119309 -225.319054)
			(xy 236.082558 -225.355805) (xy 236.04051 -225.386355) (xy 235.9942 -225.409951) (xy 235.94477 -225.426012)
			(xy 235.893435 -225.434142) (xy 235.841461 -225.434142) (xy 235.790126 -225.426012) (xy 235.740696 -225.409951)
			(xy 235.694386 -225.386355) (xy 235.652338 -225.355805) (xy 235.615587 -225.319054) (xy 235.585037 -225.277006)
			(xy 235.561441 -225.230696) (xy 235.54538 -225.181266) (xy 235.53725 -225.129931) (xy 235.397546 -225.129931)
			(xy 235.389416 -225.181266) (xy 235.373355 -225.230696) (xy 235.349759 -225.277006) (xy 235.319209 -225.319054)
			(xy 235.282458 -225.355805) (xy 235.24041 -225.386355) (xy 235.1941 -225.409951) (xy 235.14467 -225.426012)
			(xy 235.093335 -225.434142) (xy 235.041361 -225.434142) (xy 234.990026 -225.426012) (xy 234.940596 -225.409951)
			(xy 234.894286 -225.386355) (xy 234.852238 -225.355805) (xy 234.815487 -225.319054) (xy 234.784937 -225.277006)
			(xy 234.761341 -225.230696) (xy 234.74528 -225.181266) (xy 234.73715 -225.129931) (xy 234.5977 -225.129931)
			(xy 234.58957 -225.181266) (xy 234.573509 -225.230696) (xy 234.549913 -225.277006) (xy 234.519363 -225.319054)
			(xy 234.482612 -225.355805) (xy 234.440564 -225.386355) (xy 234.394254 -225.409951) (xy 234.344824 -225.426012)
			(xy 234.293489 -225.434142) (xy 234.241515 -225.434142) (xy 234.19018 -225.426012) (xy 234.14075 -225.409951)
			(xy 234.09444 -225.386355) (xy 234.052392 -225.355805) (xy 234.015641 -225.319054) (xy 233.985091 -225.277006)
			(xy 233.961495 -225.230696) (xy 233.945434 -225.181266) (xy 233.937304 -225.129931) (xy 225.01522 -225.129931)
			(xy 225.015298 -225.133916) (xy 225.014788 -225.159903) (xy 225.006658 -225.211238) (xy 224.990597 -225.260668)
			(xy 224.967001 -225.306978) (xy 224.936451 -225.349026) (xy 224.8997 -225.385777) (xy 224.857652 -225.416327)
			(xy 224.811342 -225.439923) (xy 224.761912 -225.455984) (xy 224.710577 -225.464114) (xy 224.658603 -225.464114)
			(xy 224.607268 -225.455984) (xy 224.557838 -225.439923) (xy 224.511528 -225.416327) (xy 224.46948 -225.385777)
			(xy 224.432729 -225.349026) (xy 224.402179 -225.306978) (xy 224.378583 -225.260668) (xy 224.362522 -225.211238)
			(xy 224.354392 -225.159903) (xy 224.193431 -225.159903) (xy 224.190048 -225.181266) (xy 224.173987 -225.230696)
			(xy 224.150391 -225.277006) (xy 224.119841 -225.319054) (xy 224.08309 -225.355805) (xy 224.041042 -225.386355)
			(xy 223.994732 -225.409951) (xy 223.945302 -225.426012) (xy 223.893967 -225.434142) (xy 223.841993 -225.434142)
			(xy 223.790658 -225.426012) (xy 223.741228 -225.409951) (xy 223.694918 -225.386355) (xy 223.65287 -225.355805)
			(xy 223.616119 -225.319054) (xy 223.585569 -225.277006) (xy 223.561973 -225.230696) (xy 223.545912 -225.181266)
			(xy 223.537782 -225.129931) (xy 215.118959 -225.129931) (xy 215.137935 -225.145622) (xy 215.173558 -225.184497)
			(xy 215.203491 -225.227906) (xy 215.215724 -225.251264) (xy 215.220042 -225.259646) (xy 215.226646 -225.265742)
			(xy 215.237314 -225.273362) (xy 215.242648 -225.275902) (xy 215.30564 -225.300794) (xy 215.309985 -225.302374)
			(xy 215.319054 -225.304168) (xy 215.323674 -225.30435) (xy 215.332818 -225.30435) (xy 215.341708 -225.301048)
			(xy 215.37361 -225.290027) (xy 215.440044 -225.278145) (xy 215.473788 -225.277426) (xy 215.501297 -225.277929)
			(xy 215.555741 -225.285849) (xy 215.608481 -225.301513) (xy 215.658423 -225.324595) (xy 215.704528 -225.354616)
			(xy 215.725502 -225.372422) (xy 215.732868 -225.378772) (xy 215.741758 -225.382074) (xy 215.746193 -225.383488)
			(xy 215.755392 -225.384899) (xy 215.760046 -225.384868) (xy 215.829134 -225.383344) (xy 215.83391 -225.383134)
			(xy 215.843246 -225.381079) (xy 215.847676 -225.37928) (xy 215.856312 -225.375724) (xy 215.863424 -225.36912)
			(xy 215.884894 -225.349111) (xy 215.932809 -225.315223) (xy 215.985347 -225.28907) (xy 216.041269 -225.271269)
			(xy 216.099257 -225.262239) (xy 216.1286 -225.261678) (xy 216.15585 -225.262192) (xy 216.209796 -225.269948)
			(xy 216.262089 -225.285303) (xy 216.311664 -225.307943) (xy 216.357513 -225.337408) (xy 216.398701 -225.373099)
			(xy 216.434392 -225.414287) (xy 216.463857 -225.460136) (xy 216.486497 -225.509711) (xy 216.487429 -225.512884)
			(xy 217.959938 -225.512884) (xy 217.964009 -225.457262) (xy 217.976135 -225.402825) (xy 217.996058 -225.350734)
			(xy 218.023354 -225.302099) (xy 218.05744 -225.257956) (xy 218.097589 -225.219247) (xy 218.142947 -225.186796)
			(xy 218.192547 -225.161295) (xy 218.245331 -225.143288) (xy 218.300174 -225.133158) (xy 218.355908 -225.131121)
			(xy 218.411345 -225.137221) (xy 218.465302 -225.151327) (xy 218.516631 -225.173139) (xy 218.564237 -225.202193)
			(xy 218.607105 -225.237868) (xy 218.644322 -225.279405) (xy 218.675095 -225.325918) (xy 218.698767 -225.376415)
			(xy 218.714835 -225.429822) (xy 218.722955 -225.484998) (xy 218.723464 -225.512884) (xy 218.722955 -225.54077)
			(xy 218.714835 -225.595946) (xy 218.698767 -225.649353) (xy 218.675095 -225.69985) (xy 218.644322 -225.746363)
			(xy 218.607105 -225.7879) (xy 218.564237 -225.823575) (xy 218.516631 -225.852629) (xy 218.465302 -225.874441)
			(xy 218.411345 -225.888547) (xy 218.355908 -225.894647) (xy 218.300174 -225.89261) (xy 218.245331 -225.88248)
			(xy 218.192547 -225.864473) (xy 218.142947 -225.838972) (xy 218.097589 -225.806521) (xy 218.05744 -225.767812)
			(xy 218.023354 -225.723669) (xy 217.996058 -225.675034) (xy 217.976135 -225.622943) (xy 217.964009 -225.568506)
			(xy 217.959938 -225.512884) (xy 216.487429 -225.512884) (xy 216.501852 -225.562004) (xy 216.509608 -225.61595)
			(xy 216.509608 -225.67045) (xy 216.501852 -225.724396) (xy 216.486497 -225.776689) (xy 216.463857 -225.826264)
			(xy 216.434392 -225.872113) (xy 216.398701 -225.913301) (xy 216.357513 -225.948992) (xy 216.311664 -225.978457)
			(xy 216.262089 -226.001097) (xy 216.209796 -226.016452) (xy 216.177349 -226.021117) (xy 224.466394 -226.021117)
			(xy 224.466394 -225.967819) (xy 224.474337 -225.915115) (xy 224.490047 -225.864185) (xy 224.513173 -225.816164)
			(xy 224.543197 -225.772127) (xy 224.579449 -225.733056) (xy 224.62112 -225.699825) (xy 224.667278 -225.673176)
			(xy 224.716892 -225.653704) (xy 224.768854 -225.641844) (xy 224.822004 -225.637861) (xy 224.875154 -225.641844)
			(xy 224.927116 -225.653704) (xy 224.97673 -225.673176) (xy 225.022888 -225.699825) (xy 225.064559 -225.733056)
			(xy 225.100811 -225.772127) (xy 225.130835 -225.816164) (xy 225.153961 -225.864185) (xy 225.169671 -225.915115)
			(xy 225.177614 -225.967819) (xy 225.178112 -225.994468) (xy 225.177614 -226.021117) (xy 225.169671 -226.073821)
			(xy 225.158264 -226.1108) (xy 236.422692 -226.1108) (xy 236.423206 -226.084027) (xy 236.43068 -226.031006)
			(xy 236.445497 -225.979552) (xy 236.467363 -225.930675) (xy 236.495851 -225.885336) (xy 236.530399 -225.844428)
			(xy 236.570329 -225.808753) (xy 236.614856 -225.779012) (xy 236.663104 -225.755792) (xy 236.714126 -225.739547)
			(xy 236.740446 -225.734626) (xy 236.753612 -225.731992) (xy 236.777984 -225.720742) (xy 236.79859 -225.703538)
			(xy 236.81401 -225.681567) (xy 236.823184 -225.65634) (xy 236.825478 -225.629595) (xy 236.820735 -225.603174)
			(xy 236.815376 -225.590862) (xy 236.803681 -225.565151) (xy 236.787179 -225.511133) (xy 236.778819 -225.455273)
			(xy 236.778292 -225.427032) (xy 236.778778 -225.399781) (xy 236.786534 -225.345833) (xy 236.801889 -225.293538)
			(xy 236.824531 -225.243961) (xy 236.853997 -225.198111) (xy 236.889688 -225.15692) (xy 236.930879 -225.121229)
			(xy 236.976729 -225.091763) (xy 237.026306 -225.069121) (xy 237.078601 -225.053766) (xy 237.132549 -225.04601)
			(xy 237.187051 -225.04601) (xy 237.240999 -225.053766) (xy 237.293294 -225.069121) (xy 237.342871 -225.091763)
			(xy 237.388721 -225.121229) (xy 237.429912 -225.15692) (xy 237.465603 -225.198111) (xy 237.468974 -225.203356)
			(xy 239.047935 -225.203356) (xy 239.047935 -225.148844) (xy 239.055693 -225.094887) (xy 239.071052 -225.042584)
			(xy 239.093698 -224.992998) (xy 239.123171 -224.947141) (xy 239.158871 -224.905945) (xy 239.20007 -224.87025)
			(xy 239.24593 -224.840781) (xy 239.295517 -224.818139) (xy 239.347822 -224.802786) (xy 239.40178 -224.795032)
			(xy 239.429036 -224.794572) (xy 239.455442 -224.795027) (xy 239.507747 -224.802321) (xy 239.558548 -224.816753)
			(xy 239.606876 -224.838046) (xy 239.65181 -224.865795) (xy 239.692492 -224.89947) (xy 239.728147 -224.938429)
			(xy 239.743488 -224.959926) (xy 239.747044 -224.96526) (xy 239.755934 -224.973134) (xy 239.761014 -224.975928)
			(xy 239.764843 -224.977934) (xy 239.773017 -224.980744) (xy 239.77727 -224.981516) (xy 239.784636 -224.982024)
			(xy 239.874044 -224.98304) (xy 239.885474 -224.980246) (xy 239.890808 -224.977706) (xy 239.896072 -224.974807)
			(xy 239.905186 -224.96698) (xy 239.908842 -224.962212) (xy 239.909096 -224.961958) (xy 239.927637 -224.937392)
			(xy 239.970223 -224.892957) (xy 240.018376 -224.854626) (xy 240.07123 -224.82309) (xy 240.127831 -224.798917)
			(xy 240.18716 -224.782542) (xy 240.248147 -224.774262) (xy 240.27892 -224.773744) (xy 241.143028 -224.773744)
			(xy 241.174891 -224.774269) (xy 241.238001 -224.783096) (xy 241.299278 -224.800589) (xy 241.357538 -224.82641)
			(xy 241.411653 -224.860061) (xy 241.46058 -224.90089) (xy 241.503372 -224.94811) (xy 241.521742 -224.97415)
			(xy 241.525298 -224.979484) (xy 241.534188 -224.987612) (xy 241.539268 -224.990152) (xy 241.544707 -224.992964)
			(xy 241.556522 -224.996169) (xy 241.562636 -224.996502) (xy 241.652298 -224.998026) (xy 241.663728 -224.995232)
			(xy 241.669062 -224.992692) (xy 241.674481 -224.989782) (xy 241.683853 -224.981819) (xy 241.687604 -224.976944)
			(xy 241.687604 -224.97669) (xy 241.705696 -224.952943) (xy 241.748095 -224.910916) (xy 241.796523 -224.876007)
			(xy 241.849799 -224.84907) (xy 241.906621 -224.830762) (xy 241.965602 -224.821531) (xy 241.995452 -224.820988)
			(xy 242.022707 -224.821456) (xy 242.076662 -224.829207) (xy 242.128965 -224.844559) (xy 242.178551 -224.867199)
			(xy 242.22441 -224.896665) (xy 242.265608 -224.932358) (xy 242.301306 -224.973552) (xy 242.330778 -225.019407)
			(xy 242.353424 -225.06899) (xy 242.368782 -225.121291) (xy 242.376541 -225.175245) (xy 242.376541 -225.229755)
			(xy 242.368782 -225.283709) (xy 242.353424 -225.33601) (xy 242.330778 -225.385593) (xy 242.301306 -225.431448)
			(xy 242.265608 -225.472642) (xy 242.22441 -225.508335) (xy 242.178551 -225.537801) (xy 242.128965 -225.560441)
			(xy 242.076662 -225.575793) (xy 242.022707 -225.583544) (xy 241.995452 -225.584004) (xy 241.967755 -225.583507)
			(xy 241.912942 -225.575508) (xy 241.859861 -225.559669) (xy 241.809627 -225.536324) (xy 241.763296 -225.505962)
			(xy 241.721839 -225.469222) (xy 241.703606 -225.448368) (xy 241.699288 -225.443288) (xy 241.68989 -225.43643)
			(xy 241.68481 -225.434144) (xy 241.679763 -225.432186) (xy 241.66914 -225.430128) (xy 241.663728 -225.43008)
			(xy 241.66068 -225.430334) (xy 241.571272 -225.438208) (xy 241.560096 -225.442018) (xy 241.55527 -225.445066)
			(xy 241.55013 -225.448494) (xy 241.541519 -225.457348) (xy 241.538252 -225.462592) (xy 241.522779 -225.488077)
			(xy 241.486227 -225.53518) (xy 241.443872 -225.577143) (xy 241.396431 -225.613255) (xy 241.344705 -225.642906)
			(xy 241.28957 -225.665596) (xy 241.231956 -225.68094) (xy 241.172839 -225.68868) (xy 241.143028 -225.68916)
			(xy 240.27892 -225.68916) (xy 240.248273 -225.688637) (xy 240.187531 -225.680431) (xy 240.128428 -225.664192)
			(xy 240.072021 -225.640208) (xy 240.01932 -225.60891) (xy 239.971268 -225.570858) (xy 239.928726 -225.526732)
			(xy 239.892454 -225.477323) (xy 239.877346 -225.450654) (xy 239.874552 -225.445066) (xy 239.86617 -225.435922)
			(xy 239.861344 -225.43262) (xy 239.853216 -225.428048) (xy 239.849671 -225.426624) (xy 239.842274 -225.424714)
			(xy 239.838484 -225.424238) (xy 239.750092 -225.414078) (xy 239.738408 -225.415348) (xy 239.732566 -225.417634)
			(xy 239.727204 -225.419803) (xy 239.717583 -225.42622) (xy 239.713516 -225.430334) (xy 239.7125 -225.43135)
			(xy 239.694337 -225.450846) (xy 239.653521 -225.485097) (xy 239.608335 -225.513335) (xy 239.55966 -225.535011)
			(xy 239.508442 -225.549701) (xy 239.455678 -225.557121) (xy 239.429036 -225.557588) (xy 239.40178 -225.557168)
			(xy 239.347822 -225.549414) (xy 239.295517 -225.534061) (xy 239.24593 -225.511419) (xy 239.20007 -225.48195)
			(xy 239.158871 -225.446255) (xy 239.123171 -225.405059) (xy 239.093698 -225.359202) (xy 239.071052 -225.309616)
			(xy 239.055693 -225.257313) (xy 239.047935 -225.203356) (xy 237.468974 -225.203356) (xy 237.495069 -225.243961)
			(xy 237.517711 -225.293538) (xy 237.533066 -225.345833) (xy 237.540822 -225.399781) (xy 237.541308 -225.427032)
			(xy 237.540823 -225.453806) (xy 237.533345 -225.506828) (xy 237.518524 -225.558283) (xy 237.496654 -225.60716)
			(xy 237.468163 -225.652498) (xy 237.433611 -225.693407) (xy 237.393679 -225.729081) (xy 237.34915 -225.758821)
			(xy 237.300899 -225.782041) (xy 237.249875 -225.798285) (xy 237.223554 -225.803206) (xy 237.210377 -225.805797)
			(xy 237.186 -225.817052) (xy 237.165391 -225.834263) (xy 237.14997 -225.856242) (xy 237.140798 -225.881478)
			(xy 237.138509 -225.90823) (xy 237.14326 -225.934656) (xy 237.148624 -225.94697) (xy 237.160297 -225.97269)
			(xy 237.176807 -226.026703) (xy 237.185176 -226.08256) (xy 237.185708 -226.1108) (xy 237.185222 -226.138051)
			(xy 237.177466 -226.191999) (xy 237.162111 -226.244294) (xy 237.139469 -226.293871) (xy 237.110003 -226.339721)
			(xy 237.084751 -226.368864) (xy 238.935258 -226.368864) (xy 238.939329 -226.313242) (xy 238.951455 -226.258805)
			(xy 238.971378 -226.206714) (xy 238.998674 -226.158079) (xy 239.03276 -226.113936) (xy 239.072909 -226.075227)
			(xy 239.118267 -226.042776) (xy 239.167867 -226.017275) (xy 239.220651 -225.999268) (xy 239.275494 -225.989138)
			(xy 239.331228 -225.987101) (xy 239.386665 -225.993201) (xy 239.440622 -226.007307) (xy 239.491951 -226.029119)
			(xy 239.539557 -226.058173) (xy 239.582425 -226.093848) (xy 239.619642 -226.135385) (xy 239.650415 -226.181898)
			(xy 239.674087 -226.232395) (xy 239.690155 -226.285802) (xy 239.698275 -226.340978) (xy 239.698784 -226.368864)
			(xy 239.698275 -226.39675) (xy 239.690155 -226.451926) (xy 239.674087 -226.505333) (xy 239.650415 -226.55583)
			(xy 239.619642 -226.602343) (xy 239.582425 -226.64388) (xy 239.539557 -226.679555) (xy 239.491951 -226.708609)
			(xy 239.440622 -226.730421) (xy 239.386665 -226.744527) (xy 239.331228 -226.750627) (xy 239.275494 -226.74859)
			(xy 239.220651 -226.73846) (xy 239.167867 -226.720453) (xy 239.118267 -226.694952) (xy 239.072909 -226.662501)
			(xy 239.03276 -226.623792) (xy 238.998674 -226.579649) (xy 238.971378 -226.531014) (xy 238.951455 -226.478923)
			(xy 238.939329 -226.424486) (xy 238.935258 -226.368864) (xy 237.084751 -226.368864) (xy 237.074312 -226.380912)
			(xy 237.033121 -226.416603) (xy 236.987271 -226.446069) (xy 236.937694 -226.468711) (xy 236.885399 -226.484066)
			(xy 236.831451 -226.491822) (xy 236.776949 -226.491822) (xy 236.723001 -226.484066) (xy 236.670706 -226.468711)
			(xy 236.621129 -226.446069) (xy 236.575279 -226.416603) (xy 236.534088 -226.380912) (xy 236.498397 -226.339721)
			(xy 236.468931 -226.293871) (xy 236.446289 -226.244294) (xy 236.430934 -226.191999) (xy 236.423178 -226.138051)
			(xy 236.422692 -226.1108) (xy 225.158264 -226.1108) (xy 225.153961 -226.124751) (xy 225.130835 -226.172772)
			(xy 225.100811 -226.216809) (xy 225.064559 -226.25588) (xy 225.022888 -226.289111) (xy 224.97673 -226.31576)
			(xy 224.927116 -226.335232) (xy 224.875154 -226.347092) (xy 224.822004 -226.351076) (xy 224.768854 -226.347092)
			(xy 224.716892 -226.335232) (xy 224.667278 -226.31576) (xy 224.62112 -226.289111) (xy 224.579449 -226.25588)
			(xy 224.543197 -226.216809) (xy 224.513173 -226.172772) (xy 224.490047 -226.124751) (xy 224.474337 -226.073821)
			(xy 224.466394 -226.021117) (xy 216.177349 -226.021117) (xy 216.15585 -226.024208) (xy 216.1286 -226.024694)
			(xy 216.101091 -226.024194) (xy 216.046647 -226.016272) (xy 215.993907 -226.000607) (xy 215.943965 -225.977524)
			(xy 215.89786 -225.947504) (xy 215.876886 -225.929698) (xy 215.86952 -225.923348) (xy 215.86063 -225.920046)
			(xy 215.856197 -225.918627) (xy 215.846997 -225.91722) (xy 215.842342 -225.917252) (xy 215.773254 -225.918776)
			(xy 215.76848 -225.919016) (xy 215.759144 -225.921051) (xy 215.754712 -225.92284) (xy 215.746076 -225.926396)
			(xy 215.738964 -225.933) (xy 215.720118 -225.950643) (xy 215.678523 -225.981219) (xy 215.633187 -226.005913)
			(xy 215.584939 -226.024274) (xy 215.559894 -226.030536) (xy 215.547956 -226.03333) (xy 215.539066 -226.040696)
			(xy 215.53297 -226.046792) (xy 215.52662 -226.05619) (xy 215.525096 -226.059238) (xy 215.48725 -226.145344)
			(xy 215.487758 -226.157028) (xy 215.488313 -226.162909) (xy 215.491784 -226.174196) (xy 215.494616 -226.17938)
			(xy 215.494616 -226.179634) (xy 215.505645 -226.199793) (xy 215.523351 -226.242197) (xy 215.529922 -226.264216)
			(xy 215.532716 -226.273614) (xy 215.537796 -226.280726) (xy 215.540752 -226.284448) (xy 215.547775 -226.290847)
			(xy 215.551766 -226.293426) (xy 215.610186 -226.329748) (xy 215.614134 -226.332143) (xy 215.6227 -226.335588)
			(xy 215.627204 -226.336606) (xy 215.636348 -226.338384) (xy 215.645746 -226.336606) (xy 215.662553 -226.333738)
			(xy 215.696515 -226.33069) (xy 215.713564 -226.33051) (xy 215.713818 -226.33051) (xy 215.74107 -226.330961)
			(xy 215.795018 -226.33872) (xy 215.847313 -226.354077) (xy 215.89689 -226.376721) (xy 215.942741 -226.406189)
			(xy 215.983931 -226.441882) (xy 216.019622 -226.483074) (xy 216.049088 -226.528925) (xy 216.071729 -226.578504)
			(xy 216.087084 -226.6308) (xy 216.09484 -226.684748) (xy 216.09484 -226.739252) (xy 216.087084 -226.7932)
			(xy 216.071729 -226.845496) (xy 216.049088 -226.895075) (xy 216.019622 -226.940926) (xy 215.983931 -226.982118)
			(xy 215.942741 -227.017811) (xy 215.89689 -227.047279) (xy 215.847313 -227.069923) (xy 215.795018 -227.08528)
			(xy 215.74107 -227.093039) (xy 215.713818 -227.093526) (xy 215.686364 -227.092977) (xy 215.632025 -227.085095)
			(xy 215.579377 -227.069505) (xy 215.529508 -227.04653) (xy 215.483446 -227.016644) (xy 215.442144 -226.980464)
			(xy 215.406455 -226.938737) (xy 215.377115 -226.892326) (xy 215.35473 -226.842188) (xy 215.346788 -226.815904)
			(xy 215.343994 -226.806506) (xy 215.338914 -226.799394) (xy 215.335968 -226.795665) (xy 215.328937 -226.789271)
			(xy 215.324944 -226.786694) (xy 215.266524 -226.750372) (xy 215.262574 -226.747981) (xy 215.254009 -226.744534)
			(xy 215.249506 -226.743514) (xy 215.240362 -226.741736) (xy 215.230964 -226.743514) (xy 215.214157 -226.746381)
			(xy 215.180195 -226.74943) (xy 215.163146 -226.74961) (xy 215.162892 -226.74961) (xy 215.135641 -226.74913)
			(xy 215.081693 -226.741372) (xy 215.029398 -226.726016) (xy 214.979821 -226.703374) (xy 214.933971 -226.673907)
			(xy 214.892781 -226.638215) (xy 214.857089 -226.597024) (xy 214.827623 -226.551174) (xy 214.804982 -226.501596)
			(xy 214.789627 -226.449301) (xy 214.78187 -226.395353) (xy 214.781384 -226.368102) (xy 214.781967 -226.339627)
			(xy 214.790446 -226.283313) (xy 214.807201 -226.228884) (xy 214.831859 -226.177549) (xy 214.863872 -226.13045)
			(xy 214.902531 -226.088632) (xy 214.946976 -226.053024) (xy 214.996219 -226.024418) (xy 215.049167 -226.003448)
			(xy 215.076786 -225.9965) (xy 215.088724 -225.993706) (xy 215.097614 -225.98634) (xy 215.10371 -225.980244)
			(xy 215.11006 -225.970846) (xy 215.111584 -225.967798) (xy 215.14943 -225.881692) (xy 215.148922 -225.870008)
			(xy 215.148358 -225.864129) (xy 215.144894 -225.85284) (xy 215.142064 -225.847656) (xy 215.142064 -225.847402)
			(xy 215.13292 -225.83013) (xy 215.128602 -225.821748) (xy 215.121998 -225.815652) (xy 215.11133 -225.808032)
			(xy 215.105996 -225.805492) (xy 215.043004 -225.7806) (xy 215.038663 -225.779006) (xy 215.029591 -225.777221)
			(xy 215.02497 -225.777044) (xy 215.015826 -225.777044) (xy 215.006936 -225.780346) (xy 214.975031 -225.791356)
			(xy 214.908599 -225.803245) (xy 214.874856 -225.803968) (xy 214.847604 -225.803559) (xy 214.793655 -225.795797)
			(xy 214.74136 -225.780436) (xy 214.691784 -225.75779) (xy 214.645934 -225.72832) (xy 214.604745 -225.692624)
			(xy 214.569054 -225.651431) (xy 214.539589 -225.605578) (xy 214.516948 -225.555998) (xy 214.501594 -225.503702)
			(xy 214.493838 -225.449752) (xy 196.968618 -225.449752) (xy 196.968618 -225.925949) (xy 206.560688 -225.925949)
			(xy 206.560688 -225.871451) (xy 206.568444 -225.817507) (xy 206.583797 -225.765215) (xy 206.606436 -225.715641)
			(xy 206.635899 -225.669793) (xy 206.671587 -225.628605) (xy 206.712773 -225.592914) (xy 206.758618 -225.563448)
			(xy 206.808191 -225.540806) (xy 206.860481 -225.525449) (xy 206.914425 -225.51769) (xy 206.941674 -225.517202)
			(xy 206.968655 -225.5177) (xy 207.022077 -225.525325) (xy 207.073891 -225.540398) (xy 207.123067 -225.56262)
			(xy 207.168622 -225.591546) (xy 207.209648 -225.6266) (xy 207.245329 -225.667083) (xy 207.274951 -225.712188)
			(xy 207.28686 -225.736404) (xy 207.291178 -225.745294) (xy 207.297782 -225.751644) (xy 207.303878 -225.756724)
			(xy 207.314546 -225.762566) (xy 207.378046 -225.787966) (xy 207.384904 -225.789998) (xy 207.39735 -225.791522)
			(xy 207.406494 -225.791522) (xy 207.415638 -225.787966) (xy 207.437657 -225.779799) (xy 207.48321 -225.768369)
			(xy 207.529823 -225.762636) (xy 207.553306 -225.762312) (xy 207.579538 -225.762745) (xy 207.631511 -225.769914)
			(xy 207.682012 -225.784131) (xy 207.730093 -225.805127) (xy 207.752696 -225.818446) (xy 207.762602 -225.824542)
			(xy 207.773524 -225.825812) (xy 207.779184 -225.826276) (xy 207.790465 -225.824996) (xy 207.795876 -225.823272)
			(xy 207.870298 -225.797364) (xy 207.8736 -225.796094) (xy 207.877865 -225.794125) (xy 207.885661 -225.788887)
			(xy 207.889094 -225.78568) (xy 207.897222 -225.777806) (xy 207.901032 -225.766884) (xy 207.911588 -225.739799)
			(xy 207.939722 -225.688934) (xy 207.975246 -225.642924) (xy 208.017336 -225.602834) (xy 208.06502 -225.569591)
			(xy 208.117194 -225.543964) (xy 208.172651 -225.526547) (xy 208.230108 -225.517742) (xy 208.259172 -225.517202)
			(xy 208.286427 -225.517643) (xy 208.340382 -225.525397) (xy 208.392685 -225.540751) (xy 208.44227 -225.563392)
			(xy 208.488128 -225.592861) (xy 208.529325 -225.628555) (xy 208.565023 -225.66975) (xy 208.594494 -225.715605)
			(xy 208.617139 -225.765189) (xy 208.632497 -225.81749) (xy 208.640255 -225.871445) (xy 208.640255 -225.925955)
			(xy 208.632497 -225.97991) (xy 208.617139 -226.032211) (xy 208.594494 -226.081795) (xy 208.565023 -226.12765)
			(xy 208.529325 -226.168845) (xy 208.488128 -226.204539) (xy 208.44227 -226.234008) (xy 208.392685 -226.256649)
			(xy 208.340382 -226.272003) (xy 208.286427 -226.279757) (xy 208.259172 -226.280218) (xy 208.258918 -226.280218)
			(xy 208.232717 -226.279775) (xy 208.180811 -226.272586) (xy 208.130376 -226.258369) (xy 208.082357 -226.237389)
			(xy 208.059782 -226.224084) (xy 208.049876 -226.217988) (xy 208.038954 -226.216718) (xy 208.033294 -226.21625)
			(xy 208.022013 -226.217534) (xy 208.016602 -226.219258) (xy 207.94218 -226.245166) (xy 207.938878 -226.246436)
			(xy 207.934616 -226.24841) (xy 207.926818 -226.253645) (xy 207.923384 -226.25685) (xy 207.915256 -226.264724)
			(xy 207.911446 -226.275646) (xy 207.900841 -226.30271) (xy 207.87271 -226.353571) (xy 207.837192 -226.399579)
			(xy 207.834772 -226.401884) (xy 211.795866 -226.401884) (xy 211.799937 -226.346262) (xy 211.812063 -226.291825)
			(xy 211.831986 -226.239734) (xy 211.859282 -226.191099) (xy 211.893368 -226.146956) (xy 211.933517 -226.108247)
			(xy 211.978875 -226.075796) (xy 212.028475 -226.050295) (xy 212.081259 -226.032288) (xy 212.136102 -226.022158)
			(xy 212.191836 -226.020121) (xy 212.247273 -226.026221) (xy 212.30123 -226.040327) (xy 212.352559 -226.062139)
			(xy 212.400165 -226.091193) (xy 212.443033 -226.126868) (xy 212.48025 -226.168405) (xy 212.511023 -226.214918)
			(xy 212.534695 -226.265415) (xy 212.550763 -226.318822) (xy 212.558883 -226.373998) (xy 212.559392 -226.401884)
			(xy 212.558883 -226.42977) (xy 212.550763 -226.484946) (xy 212.534695 -226.538353) (xy 212.511023 -226.58885)
			(xy 212.48025 -226.635363) (xy 212.443033 -226.6769) (xy 212.400165 -226.712575) (xy 212.352559 -226.741629)
			(xy 212.30123 -226.763441) (xy 212.247273 -226.777547) (xy 212.191836 -226.783647) (xy 212.136102 -226.78161)
			(xy 212.081259 -226.77148) (xy 212.028475 -226.753473) (xy 211.978875 -226.727972) (xy 211.933517 -226.695521)
			(xy 211.893368 -226.656812) (xy 211.859282 -226.612669) (xy 211.831986 -226.564034) (xy 211.812063 -226.511943)
			(xy 211.799937 -226.457506) (xy 211.795866 -226.401884) (xy 207.834772 -226.401884) (xy 207.795109 -226.439668)
			(xy 207.747433 -226.472913) (xy 207.695267 -226.498544) (xy 207.639817 -226.515968) (xy 207.582367 -226.524783)
			(xy 207.553306 -226.525328) (xy 207.526322 -226.524887) (xy 207.472897 -226.517257) (xy 207.421079 -226.502178)
			(xy 207.371901 -226.47995) (xy 207.326346 -226.451016) (xy 207.28532 -226.415953) (xy 207.249643 -226.37546)
			(xy 207.220026 -226.330346) (xy 207.20812 -226.306126) (xy 207.203802 -226.297236) (xy 207.197198 -226.290886)
			(xy 207.191102 -226.285806) (xy 207.180434 -226.279964) (xy 207.116934 -226.254564) (xy 207.110076 -226.252532)
			(xy 207.09763 -226.251008) (xy 207.088486 -226.251008) (xy 207.079342 -226.254564) (xy 207.057354 -226.262692)
			(xy 207.011891 -226.274122) (xy 206.965367 -226.279876) (xy 206.941928 -226.280218) (xy 206.941674 -226.280218)
			(xy 206.914425 -226.27971) (xy 206.860481 -226.271951) (xy 206.808191 -226.256594) (xy 206.758618 -226.233952)
			(xy 206.712773 -226.204486) (xy 206.671587 -226.168795) (xy 206.635899 -226.127607) (xy 206.606436 -226.081759)
			(xy 206.583797 -226.032185) (xy 206.568444 -225.979893) (xy 206.560688 -225.925949) (xy 196.968618 -225.925949)
			(xy 196.968618 -228.19233) (xy 209.118708 -228.19233) (xy 209.119141 -228.166065) (xy 209.126332 -228.114031)
			(xy 209.140596 -228.063476) (xy 209.161663 -228.015357) (xy 209.189134 -227.970585) (xy 209.22249 -227.930006)
			(xy 209.261099 -227.894388) (xy 209.304231 -227.864407) (xy 209.35107 -227.840628) (xy 209.375756 -227.83165)
			(xy 209.381344 -227.829872) (xy 209.391504 -227.823522) (xy 209.395314 -227.819458) (xy 209.399217 -227.815335)
			(xy 209.405245 -227.805719) (xy 209.407252 -227.800408) (xy 209.437224 -227.712778) (xy 209.4357 -227.701348)
			(xy 209.434808 -227.695735) (xy 209.430832 -227.68509) (xy 209.427826 -227.680266) (xy 209.427572 -227.679758)
			(xy 209.412778 -227.656331) (xy 209.389427 -227.606085) (xy 209.373583 -227.552991) (xy 209.36558 -227.498166)
			(xy 209.365088 -227.470462) (xy 209.365574 -227.443211) (xy 209.37333 -227.389263) (xy 209.388685 -227.336968)
			(xy 209.411327 -227.287391) (xy 209.440793 -227.241541) (xy 209.476484 -227.20035) (xy 209.517675 -227.164659)
			(xy 209.563525 -227.135193) (xy 209.613102 -227.112551) (xy 209.665397 -227.097196) (xy 209.719345 -227.08944)
			(xy 209.773847 -227.08944) (xy 209.827795 -227.097196) (xy 209.88009 -227.112551) (xy 209.929667 -227.135193)
			(xy 209.975517 -227.164659) (xy 210.016708 -227.20035) (xy 210.052399 -227.241541) (xy 210.081865 -227.287391)
			(xy 210.096105 -227.31857) (xy 211.978746 -227.31857) (xy 211.982817 -227.262948) (xy 211.994943 -227.208511)
			(xy 212.014866 -227.15642) (xy 212.042162 -227.107785) (xy 212.076248 -227.063642) (xy 212.116397 -227.024933)
			(xy 212.161755 -226.992482) (xy 212.211355 -226.966981) (xy 212.264139 -226.948974) (xy 212.318982 -226.938844)
			(xy 212.374716 -226.936807) (xy 212.430153 -226.942907) (xy 212.48411 -226.957013) (xy 212.535439 -226.978825)
			(xy 212.583045 -227.007879) (xy 212.625913 -227.043554) (xy 212.66313 -227.085091) (xy 212.693903 -227.131604)
			(xy 212.717575 -227.182101) (xy 212.733643 -227.235508) (xy 212.741763 -227.290684) (xy 212.742272 -227.31857)
			(xy 212.741763 -227.346456) (xy 212.733643 -227.401632) (xy 212.717575 -227.455039) (xy 212.71138 -227.468254)
			(xy 214.415053 -227.468254) (xy 214.415053 -227.413746) (xy 214.422811 -227.359794) (xy 214.438168 -227.307494)
			(xy 214.460812 -227.257913) (xy 214.490281 -227.212059) (xy 214.525977 -227.170865) (xy 214.567172 -227.135172)
			(xy 214.613027 -227.105704) (xy 214.662609 -227.083062) (xy 214.714909 -227.067707) (xy 214.768862 -227.059952)
			(xy 214.796116 -227.05949) (xy 214.82519 -227.059968) (xy 214.882664 -227.068808) (xy 214.938131 -227.086266)
			(xy 214.990307 -227.111937) (xy 215.037983 -227.145227) (xy 215.080058 -227.185366) (xy 215.115555 -227.231424)
			(xy 215.143653 -227.282334) (xy 215.163701 -227.336917) (xy 215.170004 -227.365306) (xy 215.173077 -227.378352)
			(xy 215.18501 -227.40234) (xy 215.202775 -227.422394) (xy 215.225149 -227.437132) (xy 215.250587 -227.445537)
			(xy 215.277337 -227.447031) (xy 215.303554 -227.441509) (xy 215.327429 -227.429353) (xy 215.337644 -227.420678)
			(xy 215.358774 -227.402274) (xy 215.40541 -227.371213) (xy 215.45609 -227.34731) (xy 215.509722 -227.331082)
			(xy 215.565151 -227.322877) (xy 215.593168 -227.32238) (xy 215.620421 -227.322865) (xy 215.674374 -227.330618)
			(xy 215.726674 -227.345971) (xy 215.776257 -227.368611) (xy 215.797993 -227.382578) (xy 228.140004 -227.382578)
			(xy 228.144075 -227.326956) (xy 228.156201 -227.272519) (xy 228.176124 -227.220428) (xy 228.20342 -227.171793)
			(xy 228.237506 -227.12765) (xy 228.277655 -227.088941) (xy 228.323013 -227.05649) (xy 228.372613 -227.030989)
			(xy 228.425397 -227.012982) (xy 228.48024 -227.002852) (xy 228.535974 -227.000815) (xy 228.591411 -227.006915)
			(xy 228.645368 -227.021021) (xy 228.696697 -227.042833) (xy 228.744303 -227.071887) (xy 228.787171 -227.107562)
			(xy 228.824388 -227.149099) (xy 228.855161 -227.195612) (xy 228.878833 -227.246109) (xy 228.894901 -227.299516)
			(xy 228.900471 -227.337366) (xy 235.629956 -227.337366) (xy 235.634027 -227.281744) (xy 235.646153 -227.227307)
			(xy 235.666076 -227.175216) (xy 235.693372 -227.126581) (xy 235.727458 -227.082438) (xy 235.767607 -227.043729)
			(xy 235.812965 -227.011278) (xy 235.862565 -226.985777) (xy 235.915349 -226.96777) (xy 235.970192 -226.95764)
			(xy 236.025926 -226.955603) (xy 236.081363 -226.961703) (xy 236.13532 -226.975809) (xy 236.186649 -226.997621)
			(xy 236.234255 -227.026675) (xy 236.277123 -227.06235) (xy 236.31434 -227.103887) (xy 236.345113 -227.1504)
			(xy 236.368785 -227.200897) (xy 236.384853 -227.254304) (xy 236.392973 -227.30948) (xy 236.393482 -227.337366)
			(xy 236.392973 -227.365252) (xy 236.384853 -227.420428) (xy 236.368785 -227.473835) (xy 236.345113 -227.524332)
			(xy 236.31434 -227.570845) (xy 236.277123 -227.612382) (xy 236.234255 -227.648057) (xy 236.186649 -227.677111)
			(xy 236.13532 -227.698923) (xy 236.081363 -227.713029) (xy 236.025926 -227.719129) (xy 235.970192 -227.717092)
			(xy 235.915349 -227.706962) (xy 235.862565 -227.688955) (xy 235.812965 -227.663454) (xy 235.767607 -227.631003)
			(xy 235.727458 -227.592294) (xy 235.693372 -227.548151) (xy 235.666076 -227.499516) (xy 235.646153 -227.447425)
			(xy 235.634027 -227.392988) (xy 235.629956 -227.337366) (xy 228.900471 -227.337366) (xy 228.903021 -227.354692)
			(xy 228.90353 -227.382578) (xy 228.903021 -227.410464) (xy 228.894901 -227.46564) (xy 228.878833 -227.519047)
			(xy 228.855161 -227.569544) (xy 228.824388 -227.616057) (xy 228.787171 -227.657594) (xy 228.744303 -227.693269)
			(xy 228.696697 -227.722323) (xy 228.645368 -227.744135) (xy 228.591411 -227.758241) (xy 228.535974 -227.764341)
			(xy 228.48024 -227.762304) (xy 228.425397 -227.752174) (xy 228.372613 -227.734167) (xy 228.323013 -227.708666)
			(xy 228.277655 -227.676215) (xy 228.237506 -227.637506) (xy 228.20342 -227.593363) (xy 228.176124 -227.544728)
			(xy 228.156201 -227.492637) (xy 228.144075 -227.4382) (xy 228.140004 -227.382578) (xy 215.797993 -227.382578)
			(xy 215.822113 -227.398077) (xy 215.863308 -227.43377) (xy 215.899004 -227.474962) (xy 215.928474 -227.520815)
			(xy 215.951118 -227.570396) (xy 215.966475 -227.622695) (xy 215.974233 -227.676647) (xy 215.974233 -227.731153)
			(xy 215.966475 -227.785105) (xy 215.951118 -227.837404) (xy 215.928474 -227.886985) (xy 215.899004 -227.932838)
			(xy 215.863308 -227.97403) (xy 215.822113 -228.009723) (xy 215.776257 -228.039189) (xy 215.726674 -228.061829)
			(xy 215.674374 -228.077182) (xy 215.620421 -228.084935) (xy 215.593168 -228.085396) (xy 215.564099 -228.084773)
			(xy 215.506636 -228.075948) (xy 215.451176 -228.058507) (xy 215.399005 -228.032853) (xy 215.35133 -227.999581)
			(xy 215.309254 -227.959461) (xy 215.273753 -227.913421) (xy 215.245647 -227.862529) (xy 215.225589 -227.807961)
			(xy 215.21928 -227.77958) (xy 215.216237 -227.766526) (xy 215.2043 -227.742537) (xy 215.186529 -227.722482)
			(xy 215.164151 -227.707744) (xy 215.138708 -227.69934) (xy 215.111954 -227.697849) (xy 215.085734 -227.703373)
			(xy 215.061857 -227.715532) (xy 215.05164 -227.724208) (xy 215.030514 -227.742617) (xy 214.983877 -227.773678)
			(xy 214.933196 -227.79758) (xy 214.879563 -227.813807) (xy 214.824133 -227.82201) (xy 214.796116 -227.822506)
			(xy 214.768862 -227.822048) (xy 214.714909 -227.814293) (xy 214.662609 -227.798938) (xy 214.613027 -227.776296)
			(xy 214.567172 -227.746828) (xy 214.525977 -227.711135) (xy 214.490281 -227.669941) (xy 214.460812 -227.624087)
			(xy 214.438168 -227.574506) (xy 214.422811 -227.522206) (xy 214.415053 -227.468254) (xy 212.71138 -227.468254)
			(xy 212.693903 -227.505536) (xy 212.66313 -227.552049) (xy 212.625913 -227.593586) (xy 212.583045 -227.629261)
			(xy 212.535439 -227.658315) (xy 212.48411 -227.680127) (xy 212.430153 -227.694233) (xy 212.374716 -227.700333)
			(xy 212.318982 -227.698296) (xy 212.264139 -227.688166) (xy 212.211355 -227.670159) (xy 212.161755 -227.644658)
			(xy 212.116397 -227.612207) (xy 212.076248 -227.573498) (xy 212.042162 -227.529355) (xy 212.014866 -227.48072)
			(xy 211.994943 -227.428629) (xy 211.982817 -227.374192) (xy 211.978746 -227.31857) (xy 210.096105 -227.31857)
			(xy 210.104507 -227.336968) (xy 210.119862 -227.389263) (xy 210.127618 -227.443211) (xy 210.128104 -227.470462)
			(xy 210.127656 -227.496726) (xy 210.120466 -227.548759) (xy 210.106204 -227.599313) (xy 210.085139 -227.647432)
			(xy 210.057669 -227.692204) (xy 210.024315 -227.732783) (xy 209.985708 -227.768401) (xy 209.942578 -227.798384)
			(xy 209.895741 -227.822164) (xy 209.871056 -227.831142) (xy 209.865468 -227.83292) (xy 209.855308 -227.83927)
			(xy 209.851498 -227.843334) (xy 209.847599 -227.84746) (xy 209.841568 -227.857074) (xy 209.83956 -227.862384)
			(xy 209.809588 -227.950014) (xy 209.811112 -227.961444) (xy 209.812005 -227.967057) (xy 209.81598 -227.977702)
			(xy 209.818986 -227.982526) (xy 209.81924 -227.983034) (xy 209.834032 -228.006463) (xy 209.857384 -228.056708)
			(xy 209.873228 -228.109801) (xy 209.881232 -228.164627) (xy 209.881724 -228.19233) (xy 209.881248 -228.219)
			(xy 210.453984 -228.219) (xy 210.458055 -228.163378) (xy 210.470181 -228.108941) (xy 210.490104 -228.05685)
			(xy 210.5174 -228.008215) (xy 210.551486 -227.964072) (xy 210.591635 -227.925363) (xy 210.636993 -227.892912)
			(xy 210.686593 -227.867411) (xy 210.739377 -227.849404) (xy 210.79422 -227.839274) (xy 210.849954 -227.837237)
			(xy 210.905391 -227.843337) (xy 210.959348 -227.857443) (xy 211.010677 -227.879255) (xy 211.058283 -227.908309)
			(xy 211.101151 -227.943984) (xy 211.138368 -227.985521) (xy 211.169141 -228.032034) (xy 211.192813 -228.082531)
			(xy 211.208881 -228.135938) (xy 211.217001 -228.191114) (xy 211.21751 -228.219) (xy 211.217487 -228.22027)
			(xy 216.921078 -228.22027) (xy 216.925149 -228.164648) (xy 216.937275 -228.110211) (xy 216.957198 -228.05812)
			(xy 216.984494 -228.009485) (xy 217.01858 -227.965342) (xy 217.058729 -227.926633) (xy 217.104087 -227.894182)
			(xy 217.153687 -227.868681) (xy 217.206471 -227.850674) (xy 217.261314 -227.840544) (xy 217.317048 -227.838507)
			(xy 217.372485 -227.844607) (xy 217.426442 -227.858713) (xy 217.477771 -227.880525) (xy 217.525377 -227.909579)
			(xy 217.568245 -227.945254) (xy 217.605462 -227.986791) (xy 217.636235 -228.033304) (xy 217.659907 -228.083801)
			(xy 217.675975 -228.137208) (xy 217.680798 -228.169978) (xy 217.800934 -228.169978) (xy 217.805005 -228.114356)
			(xy 217.817131 -228.059919) (xy 217.837054 -228.007828) (xy 217.86435 -227.959193) (xy 217.898436 -227.91505)
			(xy 217.938585 -227.876341) (xy 217.983943 -227.84389) (xy 218.033543 -227.818389) (xy 218.086327 -227.800382)
			(xy 218.14117 -227.790252) (xy 218.196904 -227.788215) (xy 218.252341 -227.794315) (xy 218.306298 -227.808421)
			(xy 218.357627 -227.830233) (xy 218.405233 -227.859287) (xy 218.448101 -227.894962) (xy 218.485318 -227.936499)
			(xy 218.516091 -227.983012) (xy 218.539763 -228.033509) (xy 218.555831 -228.086916) (xy 218.563951 -228.142092)
			(xy 218.56446 -228.169978) (xy 218.563951 -228.197864) (xy 218.557701 -228.240336) (xy 221.004382 -228.240336)
			(xy 221.008453 -228.184714) (xy 221.020579 -228.130277) (xy 221.040502 -228.078186) (xy 221.067798 -228.029551)
			(xy 221.101884 -227.985408) (xy 221.142033 -227.946699) (xy 221.187391 -227.914248) (xy 221.236991 -227.888747)
			(xy 221.289775 -227.87074) (xy 221.344618 -227.86061) (xy 221.400352 -227.858573) (xy 221.455789 -227.864673)
			(xy 221.509746 -227.878779) (xy 221.561075 -227.900591) (xy 221.608681 -227.929645) (xy 221.651549 -227.96532)
			(xy 221.688766 -228.006857) (xy 221.719539 -228.05337) (xy 221.743211 -228.103867) (xy 221.759279 -228.157274)
			(xy 221.767399 -228.21245) (xy 221.767908 -228.240336) (xy 221.767399 -228.268222) (xy 221.759279 -228.323398)
			(xy 221.743211 -228.376805) (xy 221.719539 -228.427302) (xy 221.688766 -228.473815) (xy 221.651549 -228.515352)
			(xy 221.608681 -228.551027) (xy 221.561075 -228.580081) (xy 221.509746 -228.601893) (xy 221.455789 -228.615999)
			(xy 221.400352 -228.622099) (xy 221.344618 -228.620062) (xy 221.289775 -228.609932) (xy 221.236991 -228.591925)
			(xy 221.187391 -228.566424) (xy 221.142033 -228.533973) (xy 221.101884 -228.495264) (xy 221.067798 -228.451121)
			(xy 221.040502 -228.402486) (xy 221.020579 -228.350395) (xy 221.008453 -228.295958) (xy 221.004382 -228.240336)
			(xy 218.557701 -228.240336) (xy 218.555831 -228.25304) (xy 218.539763 -228.306447) (xy 218.516091 -228.356944)
			(xy 218.485318 -228.403457) (xy 218.448101 -228.444994) (xy 218.405233 -228.480669) (xy 218.357627 -228.509723)
			(xy 218.306298 -228.531535) (xy 218.252341 -228.545641) (xy 218.196904 -228.551741) (xy 218.14117 -228.549704)
			(xy 218.086327 -228.539574) (xy 218.033543 -228.521567) (xy 217.983943 -228.496066) (xy 217.938585 -228.463615)
			(xy 217.898436 -228.424906) (xy 217.86435 -228.380763) (xy 217.837054 -228.332128) (xy 217.817131 -228.280037)
			(xy 217.805005 -228.2256) (xy 217.800934 -228.169978) (xy 217.680798 -228.169978) (xy 217.684095 -228.192384)
			(xy 217.684604 -228.22027) (xy 217.684095 -228.248156) (xy 217.675975 -228.303332) (xy 217.659907 -228.356739)
			(xy 217.636235 -228.407236) (xy 217.605462 -228.453749) (xy 217.568245 -228.495286) (xy 217.525377 -228.530961)
			(xy 217.477771 -228.560015) (xy 217.426442 -228.581827) (xy 217.372485 -228.595933) (xy 217.317048 -228.602033)
			(xy 217.261314 -228.599996) (xy 217.206471 -228.589866) (xy 217.153687 -228.571859) (xy 217.104087 -228.546358)
			(xy 217.058729 -228.513907) (xy 217.01858 -228.475198) (xy 216.984494 -228.431055) (xy 216.957198 -228.38242)
			(xy 216.937275 -228.330329) (xy 216.925149 -228.275892) (xy 216.921078 -228.22027) (xy 211.217487 -228.22027)
			(xy 211.217001 -228.246886) (xy 211.208881 -228.302062) (xy 211.192813 -228.355469) (xy 211.169141 -228.405966)
			(xy 211.138368 -228.452479) (xy 211.101151 -228.494016) (xy 211.058283 -228.529691) (xy 211.010677 -228.558745)
			(xy 210.959348 -228.580557) (xy 210.905391 -228.594663) (xy 210.849954 -228.600763) (xy 210.79422 -228.598726)
			(xy 210.739377 -228.588596) (xy 210.686593 -228.570589) (xy 210.636993 -228.545088) (xy 210.591635 -228.512637)
			(xy 210.551486 -228.473928) (xy 210.5174 -228.429785) (xy 210.490104 -228.38115) (xy 210.470181 -228.329059)
			(xy 210.458055 -228.274622) (xy 210.453984 -228.219) (xy 209.881248 -228.219) (xy 209.881238 -228.219581)
			(xy 209.873482 -228.273529) (xy 209.858127 -228.325824) (xy 209.835485 -228.375401) (xy 209.806019 -228.421251)
			(xy 209.770328 -228.462442) (xy 209.729137 -228.498133) (xy 209.683287 -228.527599) (xy 209.63371 -228.550241)
			(xy 209.581415 -228.565596) (xy 209.527467 -228.573352) (xy 209.472965 -228.573352) (xy 209.419017 -228.565596)
			(xy 209.366722 -228.550241) (xy 209.317145 -228.527599) (xy 209.271295 -228.498133) (xy 209.230104 -228.462442)
			(xy 209.194413 -228.421251) (xy 209.164947 -228.375401) (xy 209.142305 -228.325824) (xy 209.12695 -228.273529)
			(xy 209.119194 -228.219581) (xy 209.118708 -228.19233) (xy 196.968618 -228.19233) (xy 196.968618 -228.816662)
			(xy 237.917734 -228.816662) (xy 237.921805 -228.76104) (xy 237.933931 -228.706603) (xy 237.953854 -228.654512)
			(xy 237.98115 -228.605877) (xy 238.015236 -228.561734) (xy 238.055385 -228.523025) (xy 238.100743 -228.490574)
			(xy 238.150343 -228.465073) (xy 238.203127 -228.447066) (xy 238.25797 -228.436936) (xy 238.313704 -228.434899)
			(xy 238.369141 -228.440999) (xy 238.423098 -228.455105) (xy 238.474427 -228.476917) (xy 238.522033 -228.505971)
			(xy 238.564901 -228.541646) (xy 238.602118 -228.583183) (xy 238.632891 -228.629696) (xy 238.656563 -228.680193)
			(xy 238.672631 -228.7336) (xy 238.680751 -228.788776) (xy 238.68126 -228.816662) (xy 238.681005 -228.830632)
			(xy 238.78235 -228.830632) (xy 238.786421 -228.77501) (xy 238.798547 -228.720573) (xy 238.81847 -228.668482)
			(xy 238.845766 -228.619847) (xy 238.879852 -228.575704) (xy 238.920001 -228.536995) (xy 238.965359 -228.504544)
			(xy 239.014959 -228.479043) (xy 239.067743 -228.461036) (xy 239.122586 -228.450906) (xy 239.17832 -228.448869)
			(xy 239.233757 -228.454969) (xy 239.287714 -228.469075) (xy 239.339043 -228.490887) (xy 239.386649 -228.519941)
			(xy 239.429517 -228.555616) (xy 239.466734 -228.597153) (xy 239.497507 -228.643666) (xy 239.521179 -228.694163)
			(xy 239.537247 -228.74757) (xy 239.545367 -228.802746) (xy 239.545876 -228.830632) (xy 239.545367 -228.858518)
			(xy 239.537247 -228.913694) (xy 239.521179 -228.967101) (xy 239.497507 -229.017598) (xy 239.466734 -229.064111)
			(xy 239.429517 -229.105648) (xy 239.386649 -229.141323) (xy 239.339043 -229.170377) (xy 239.287714 -229.192189)
			(xy 239.233757 -229.206295) (xy 239.203721 -229.2096) (xy 239.607088 -229.2096) (xy 239.611159 -229.153978)
			(xy 239.623285 -229.099541) (xy 239.643208 -229.04745) (xy 239.670504 -228.998815) (xy 239.70459 -228.954672)
			(xy 239.744739 -228.915963) (xy 239.790097 -228.883512) (xy 239.839697 -228.858011) (xy 239.892481 -228.840004)
			(xy 239.947324 -228.829874) (xy 240.003058 -228.827837) (xy 240.058495 -228.833937) (xy 240.112452 -228.848043)
			(xy 240.163781 -228.869855) (xy 240.211387 -228.898909) (xy 240.254255 -228.934584) (xy 240.291472 -228.976121)
			(xy 240.322245 -229.022634) (xy 240.345917 -229.073131) (xy 240.361985 -229.126538) (xy 240.370105 -229.181714)
			(xy 240.370614 -229.2096) (xy 240.370105 -229.237486) (xy 240.361985 -229.292662) (xy 240.355338 -229.314756)
			(xy 241.82908 -229.314756) (xy 241.833151 -229.259134) (xy 241.845277 -229.204697) (xy 241.8652 -229.152606)
			(xy 241.892496 -229.103971) (xy 241.926582 -229.059828) (xy 241.966731 -229.021119) (xy 242.012089 -228.988668)
			(xy 242.061689 -228.963167) (xy 242.114473 -228.94516) (xy 242.169316 -228.93503) (xy 242.22505 -228.932993)
			(xy 242.280487 -228.939093) (xy 242.334444 -228.953199) (xy 242.385773 -228.975011) (xy 242.433379 -229.004065)
			(xy 242.476247 -229.03974) (xy 242.513464 -229.081277) (xy 242.544237 -229.12779) (xy 242.567909 -229.178287)
			(xy 242.583977 -229.231694) (xy 242.592097 -229.28687) (xy 242.592606 -229.314756) (xy 242.592097 -229.342642)
			(xy 242.583977 -229.397818) (xy 242.567909 -229.451225) (xy 242.544237 -229.501722) (xy 242.513464 -229.548235)
			(xy 242.476247 -229.589772) (xy 242.433379 -229.625447) (xy 242.385773 -229.654501) (xy 242.334444 -229.676313)
			(xy 242.280487 -229.690419) (xy 242.22505 -229.696519) (xy 242.169316 -229.694482) (xy 242.114473 -229.684352)
			(xy 242.061689 -229.666345) (xy 242.012089 -229.640844) (xy 241.966731 -229.608393) (xy 241.926582 -229.569684)
			(xy 241.892496 -229.525541) (xy 241.8652 -229.476906) (xy 241.845277 -229.424815) (xy 241.833151 -229.370378)
			(xy 241.82908 -229.314756) (xy 240.355338 -229.314756) (xy 240.345917 -229.346069) (xy 240.322245 -229.396566)
			(xy 240.291472 -229.443079) (xy 240.254255 -229.484616) (xy 240.211387 -229.520291) (xy 240.163781 -229.549345)
			(xy 240.112452 -229.571157) (xy 240.058495 -229.585263) (xy 240.003058 -229.591363) (xy 239.947324 -229.589326)
			(xy 239.892481 -229.579196) (xy 239.839697 -229.561189) (xy 239.790097 -229.535688) (xy 239.744739 -229.503237)
			(xy 239.70459 -229.464528) (xy 239.670504 -229.420385) (xy 239.643208 -229.37175) (xy 239.623285 -229.319659)
			(xy 239.611159 -229.265222) (xy 239.607088 -229.2096) (xy 239.203721 -229.2096) (xy 239.17832 -229.212395)
			(xy 239.122586 -229.210358) (xy 239.067743 -229.200228) (xy 239.014959 -229.182221) (xy 238.965359 -229.15672)
			(xy 238.920001 -229.124269) (xy 238.879852 -229.08556) (xy 238.845766 -229.041417) (xy 238.81847 -228.992782)
			(xy 238.798547 -228.940691) (xy 238.786421 -228.886254) (xy 238.78235 -228.830632) (xy 238.681005 -228.830632)
			(xy 238.680751 -228.844548) (xy 238.672631 -228.899724) (xy 238.656563 -228.953131) (xy 238.632891 -229.003628)
			(xy 238.602118 -229.050141) (xy 238.564901 -229.091678) (xy 238.522033 -229.127353) (xy 238.474427 -229.156407)
			(xy 238.423098 -229.178219) (xy 238.369141 -229.192325) (xy 238.313704 -229.198425) (xy 238.25797 -229.196388)
			(xy 238.203127 -229.186258) (xy 238.150343 -229.168251) (xy 238.100743 -229.14275) (xy 238.055385 -229.110299)
			(xy 238.015236 -229.07159) (xy 237.98115 -229.027447) (xy 237.953854 -228.978812) (xy 237.933931 -228.926721)
			(xy 237.921805 -228.872284) (xy 237.917734 -228.816662) (xy 196.968618 -228.816662) (xy 196.968618 -229.5652)
			(xy 233.666536 -229.5652) (xy 233.670607 -229.509578) (xy 233.682733 -229.455141) (xy 233.702656 -229.40305)
			(xy 233.729952 -229.354415) (xy 233.764038 -229.310272) (xy 233.804187 -229.271563) (xy 233.849545 -229.239112)
			(xy 233.899145 -229.213611) (xy 233.951929 -229.195604) (xy 234.006772 -229.185474) (xy 234.062506 -229.183437)
			(xy 234.117943 -229.189537) (xy 234.1719 -229.203643) (xy 234.223229 -229.225455) (xy 234.270835 -229.254509)
			(xy 234.313703 -229.290184) (xy 234.35092 -229.331721) (xy 234.381693 -229.378234) (xy 234.405365 -229.428731)
			(xy 234.421433 -229.482138) (xy 234.429553 -229.537314) (xy 234.430062 -229.5652) (xy 234.429553 -229.593086)
			(xy 234.421433 -229.648262) (xy 234.405365 -229.701669) (xy 234.381693 -229.752166) (xy 234.35092 -229.798679)
			(xy 234.32343 -229.82936) (xy 236.041182 -229.82936) (xy 236.045253 -229.773738) (xy 236.057379 -229.719301)
			(xy 236.077302 -229.66721) (xy 236.104598 -229.618575) (xy 236.138684 -229.574432) (xy 236.178833 -229.535723)
			(xy 236.224191 -229.503272) (xy 236.273791 -229.477771) (xy 236.326575 -229.459764) (xy 236.381418 -229.449634)
			(xy 236.437152 -229.447597) (xy 236.492589 -229.453697) (xy 236.546546 -229.467803) (xy 236.597875 -229.489615)
			(xy 236.645481 -229.518669) (xy 236.688349 -229.554344) (xy 236.725566 -229.595881) (xy 236.756339 -229.642394)
			(xy 236.780011 -229.692891) (xy 236.796079 -229.746298) (xy 236.797687 -229.757224) (xy 245.188484 -229.757224)
			(xy 245.192555 -229.701602) (xy 245.204681 -229.647165) (xy 245.224604 -229.595074) (xy 245.2519 -229.546439)
			(xy 245.285986 -229.502296) (xy 245.326135 -229.463587) (xy 245.371493 -229.431136) (xy 245.421093 -229.405635)
			(xy 245.473877 -229.387628) (xy 245.52872 -229.377498) (xy 245.584454 -229.375461) (xy 245.639891 -229.381561)
			(xy 245.693848 -229.395667) (xy 245.745177 -229.417479) (xy 245.792783 -229.446533) (xy 245.835651 -229.482208)
			(xy 245.872868 -229.523745) (xy 245.903641 -229.570258) (xy 245.927313 -229.620755) (xy 245.943381 -229.674162)
			(xy 245.951501 -229.729338) (xy 245.95201 -229.757224) (xy 245.951501 -229.78511) (xy 245.943381 -229.840286)
			(xy 245.927313 -229.893693) (xy 245.903641 -229.94419) (xy 245.872868 -229.990703) (xy 245.835651 -230.03224)
			(xy 245.792783 -230.067915) (xy 245.745177 -230.096969) (xy 245.693848 -230.118781) (xy 245.639891 -230.132887)
			(xy 245.584454 -230.138987) (xy 245.52872 -230.13695) (xy 245.473877 -230.12682) (xy 245.421093 -230.108813)
			(xy 245.371493 -230.083312) (xy 245.326135 -230.050861) (xy 245.285986 -230.012152) (xy 245.2519 -229.968009)
			(xy 245.224604 -229.919374) (xy 245.204681 -229.867283) (xy 245.192555 -229.812846) (xy 245.188484 -229.757224)
			(xy 236.797687 -229.757224) (xy 236.804199 -229.801474) (xy 236.804708 -229.82936) (xy 236.804199 -229.857246)
			(xy 236.796079 -229.912422) (xy 236.780011 -229.965829) (xy 236.756339 -230.016326) (xy 236.725566 -230.062839)
			(xy 236.688349 -230.104376) (xy 236.645481 -230.140051) (xy 236.597875 -230.169105) (xy 236.546546 -230.190917)
			(xy 236.492589 -230.205023) (xy 236.437152 -230.211123) (xy 236.381418 -230.209086) (xy 236.326575 -230.198956)
			(xy 236.273791 -230.180949) (xy 236.224191 -230.155448) (xy 236.178833 -230.122997) (xy 236.138684 -230.084288)
			(xy 236.104598 -230.040145) (xy 236.077302 -229.99151) (xy 236.057379 -229.939419) (xy 236.045253 -229.884982)
			(xy 236.041182 -229.82936) (xy 234.32343 -229.82936) (xy 234.313703 -229.840216) (xy 234.270835 -229.875891)
			(xy 234.223229 -229.904945) (xy 234.1719 -229.926757) (xy 234.117943 -229.940863) (xy 234.062506 -229.946963)
			(xy 234.006772 -229.944926) (xy 233.951929 -229.934796) (xy 233.899145 -229.916789) (xy 233.849545 -229.891288)
			(xy 233.804187 -229.858837) (xy 233.764038 -229.820128) (xy 233.729952 -229.775985) (xy 233.702656 -229.72735)
			(xy 233.682733 -229.675259) (xy 233.670607 -229.620822) (xy 233.666536 -229.5652) (xy 196.968618 -229.5652)
			(xy 196.968618 -230.027226) (xy 225.469194 -230.027226) (xy 225.473265 -229.971604) (xy 225.485391 -229.917167)
			(xy 225.505314 -229.865076) (xy 225.53261 -229.816441) (xy 225.566696 -229.772298) (xy 225.606845 -229.733589)
			(xy 225.652203 -229.701138) (xy 225.701803 -229.675637) (xy 225.754587 -229.65763) (xy 225.80943 -229.6475)
			(xy 225.865164 -229.645463) (xy 225.920601 -229.651563) (xy 225.974558 -229.665669) (xy 226.025887 -229.687481)
			(xy 226.073493 -229.716535) (xy 226.116361 -229.75221) (xy 226.153578 -229.793747) (xy 226.184351 -229.84026)
			(xy 226.208023 -229.890757) (xy 226.224091 -229.944164) (xy 226.232211 -229.99934) (xy 226.23272 -230.027226)
			(xy 226.232669 -230.03002) (xy 230.483662 -230.03002) (xy 230.487733 -229.974398) (xy 230.499859 -229.919961)
			(xy 230.519782 -229.86787) (xy 230.547078 -229.819235) (xy 230.581164 -229.775092) (xy 230.621313 -229.736383)
			(xy 230.666671 -229.703932) (xy 230.716271 -229.678431) (xy 230.769055 -229.660424) (xy 230.823898 -229.650294)
			(xy 230.879632 -229.648257) (xy 230.935069 -229.654357) (xy 230.989026 -229.668463) (xy 231.040355 -229.690275)
			(xy 231.087961 -229.719329) (xy 231.130829 -229.755004) (xy 231.168046 -229.796541) (xy 231.198819 -229.843054)
			(xy 231.222491 -229.893551) (xy 231.238559 -229.946958) (xy 231.246679 -230.002134) (xy 231.247188 -230.03002)
			(xy 231.246679 -230.057906) (xy 231.238559 -230.113082) (xy 231.222491 -230.166489) (xy 231.198819 -230.216986)
			(xy 231.168046 -230.263499) (xy 231.130829 -230.305036) (xy 231.087961 -230.340711) (xy 231.040355 -230.369765)
			(xy 230.989026 -230.391577) (xy 230.935069 -230.405683) (xy 230.879632 -230.411783) (xy 230.823898 -230.409746)
			(xy 230.769055 -230.399616) (xy 230.716271 -230.381609) (xy 230.666671 -230.356108) (xy 230.621313 -230.323657)
			(xy 230.581164 -230.284948) (xy 230.547078 -230.240805) (xy 230.519782 -230.19217) (xy 230.499859 -230.140079)
			(xy 230.487733 -230.085642) (xy 230.483662 -230.03002) (xy 226.232669 -230.03002) (xy 226.232211 -230.055112)
			(xy 226.224091 -230.110288) (xy 226.208023 -230.163695) (xy 226.184351 -230.214192) (xy 226.153578 -230.260705)
			(xy 226.116361 -230.302242) (xy 226.073493 -230.337917) (xy 226.025887 -230.366971) (xy 225.974558 -230.388783)
			(xy 225.920601 -230.402889) (xy 225.865164 -230.408989) (xy 225.80943 -230.406952) (xy 225.754587 -230.396822)
			(xy 225.701803 -230.378815) (xy 225.652203 -230.353314) (xy 225.606845 -230.320863) (xy 225.566696 -230.282154)
			(xy 225.53261 -230.238011) (xy 225.505314 -230.189376) (xy 225.485391 -230.137285) (xy 225.473265 -230.082848)
			(xy 225.469194 -230.027226) (xy 196.968618 -230.027226) (xy 196.968618 -230.673148) (xy 206.071976 -230.673148)
			(xy 206.076047 -230.617526) (xy 206.088173 -230.563089) (xy 206.108096 -230.510998) (xy 206.135392 -230.462363)
			(xy 206.169478 -230.41822) (xy 206.209627 -230.379511) (xy 206.254985 -230.34706) (xy 206.304585 -230.321559)
			(xy 206.357369 -230.303552) (xy 206.412212 -230.293422) (xy 206.467946 -230.291385) (xy 206.523383 -230.297485)
			(xy 206.57734 -230.311591) (xy 206.628669 -230.333403) (xy 206.676275 -230.362457) (xy 206.719143 -230.398132)
			(xy 206.75636 -230.439669) (xy 206.787133 -230.486182) (xy 206.810805 -230.536679) (xy 206.820149 -230.567738)
			(xy 207.397856 -230.567738) (xy 207.401927 -230.512116) (xy 207.414053 -230.457679) (xy 207.433976 -230.405588)
			(xy 207.461272 -230.356953) (xy 207.495358 -230.31281) (xy 207.535507 -230.274101) (xy 207.580865 -230.24165)
			(xy 207.630465 -230.216149) (xy 207.683249 -230.198142) (xy 207.738092 -230.188012) (xy 207.793826 -230.185975)
			(xy 207.849263 -230.192075) (xy 207.90322 -230.206181) (xy 207.954549 -230.227993) (xy 208.002155 -230.257047)
			(xy 208.045023 -230.292722) (xy 208.08224 -230.334259) (xy 208.113013 -230.380772) (xy 208.136685 -230.431269)
			(xy 208.152753 -230.484676) (xy 208.160873 -230.539852) (xy 208.161382 -230.567738) (xy 208.160873 -230.595624)
			(xy 208.152753 -230.6508) (xy 208.136685 -230.704207) (xy 208.113013 -230.754704) (xy 208.08224 -230.801217)
			(xy 208.045023 -230.842754) (xy 208.002155 -230.878429) (xy 207.954549 -230.907483) (xy 207.90322 -230.929295)
			(xy 207.849263 -230.943401) (xy 207.793826 -230.949501) (xy 207.738092 -230.947464) (xy 207.683249 -230.937334)
			(xy 207.630465 -230.919327) (xy 207.580865 -230.893826) (xy 207.535507 -230.861375) (xy 207.495358 -230.822666)
			(xy 207.461272 -230.778523) (xy 207.433976 -230.729888) (xy 207.414053 -230.677797) (xy 207.401927 -230.62336)
			(xy 207.397856 -230.567738) (xy 206.820149 -230.567738) (xy 206.826873 -230.590086) (xy 206.834993 -230.645262)
			(xy 206.835502 -230.673148) (xy 206.834993 -230.701034) (xy 206.826873 -230.75621) (xy 206.810805 -230.809617)
			(xy 206.787133 -230.860114) (xy 206.75636 -230.906627) (xy 206.719143 -230.948164) (xy 206.676275 -230.983839)
			(xy 206.628669 -231.012893) (xy 206.57734 -231.034705) (xy 206.523383 -231.048811) (xy 206.467946 -231.054911)
			(xy 206.412212 -231.052874) (xy 206.357369 -231.042744) (xy 206.304585 -231.024737) (xy 206.254985 -230.999236)
			(xy 206.209627 -230.966785) (xy 206.169478 -230.928076) (xy 206.135392 -230.883933) (xy 206.108096 -230.835298)
			(xy 206.088173 -230.783207) (xy 206.076047 -230.72877) (xy 206.071976 -230.673148) (xy 196.968618 -230.673148)
			(xy 196.968618 -232.51795) (xy 207.360518 -232.51795) (xy 207.364589 -232.462328) (xy 207.376715 -232.407891)
			(xy 207.396638 -232.3558) (xy 207.423934 -232.307165) (xy 207.45802 -232.263022) (xy 207.498169 -232.224313)
			(xy 207.543527 -232.191862) (xy 207.593127 -232.166361) (xy 207.645911 -232.148354) (xy 207.700754 -232.138224)
			(xy 207.756488 -232.136187) (xy 207.811925 -232.142287) (xy 207.865882 -232.156393) (xy 207.917211 -232.178205)
			(xy 207.964817 -232.207259) (xy 208.007685 -232.242934) (xy 208.044902 -232.284471) (xy 208.075675 -232.330984)
			(xy 208.099347 -232.381481) (xy 208.115415 -232.434888) (xy 208.11931 -232.461353) (xy 208.524285 -232.461353)
			(xy 208.524285 -232.406847) (xy 208.532043 -232.352896) (xy 208.5474 -232.300599) (xy 208.570044 -232.251019)
			(xy 208.599515 -232.205167) (xy 208.635211 -232.163977) (xy 208.676406 -232.128286) (xy 208.722261 -232.098821)
			(xy 208.771844 -232.076183) (xy 208.824143 -232.060833) (xy 208.878095 -232.053082) (xy 208.905348 -232.052622)
			(xy 208.905856 -232.052622) (xy 208.930958 -232.053059) (xy 208.980725 -232.059677) (xy 209.029194 -232.072765)
			(xy 209.075529 -232.092096) (xy 209.118927 -232.117336) (xy 209.139028 -232.132378) (xy 209.149696 -232.14076)
			(xy 209.162904 -232.142538) (xy 209.169534 -232.143331) (xy 209.182792 -232.141778) (xy 209.189066 -232.13949)
			(xy 209.2706 -232.10647) (xy 209.281776 -232.100374) (xy 209.287364 -232.09631) (xy 209.291428 -232.090976)
			(xy 209.295285 -232.085728) (xy 209.300423 -232.073763) (xy 209.301588 -232.067354) (xy 209.301588 -232.0671)
			(xy 209.305952 -232.040262) (xy 209.321447 -231.988143) (xy 209.344183 -231.93875) (xy 209.3737 -231.893085)
			(xy 209.409401 -231.852073) (xy 209.450562 -231.816544) (xy 209.496349 -231.787217) (xy 209.545836 -231.764687)
			(xy 209.598021 -231.749411) (xy 209.651845 -231.741697) (xy 209.679032 -231.741218) (xy 209.706285 -231.741648)
			(xy 209.760236 -231.74941) (xy 209.812534 -231.76477) (xy 209.862113 -231.787417) (xy 209.907964 -231.816889)
			(xy 209.949155 -231.852586) (xy 209.984846 -231.893782) (xy 210.014311 -231.939638) (xy 210.03695 -231.989221)
			(xy 210.052303 -232.04152) (xy 210.060056 -232.095473) (xy 210.06054 -232.122726) (xy 210.059991 -232.152308)
			(xy 210.051037 -232.209594) (xy 210.399884 -232.209594) (xy 210.40037 -232.182343) (xy 210.408126 -232.128395)
			(xy 210.423481 -232.0761) (xy 210.446123 -232.026523) (xy 210.475589 -231.980673) (xy 210.51128 -231.939482)
			(xy 210.552471 -231.903791) (xy 210.598321 -231.874325) (xy 210.647898 -231.851683) (xy 210.700193 -231.836328)
			(xy 210.754141 -231.828572) (xy 210.808643 -231.828572) (xy 210.862591 -231.836328) (xy 210.914886 -231.851683)
			(xy 210.964463 -231.874325) (xy 211.010313 -231.903791) (xy 211.051504 -231.939482) (xy 211.087195 -231.980673)
			(xy 211.116661 -232.026523) (xy 211.139303 -232.0761) (xy 211.154658 -232.128395) (xy 211.162414 -232.182343)
			(xy 211.1629 -232.209594) (xy 211.162516 -232.23408) (xy 211.156246 -232.282649) (xy 211.14381 -232.330016)
			(xy 211.13496 -232.35285) (xy 211.130896 -232.362756) (xy 211.131404 -232.373678) (xy 211.131748 -232.378804)
			(xy 211.13417 -232.388784) (xy 211.13623 -232.39349) (xy 211.168488 -232.461562) (xy 211.170863 -232.466303)
			(xy 211.177271 -232.474751) (xy 211.181188 -232.478326) (xy 211.189316 -232.485184) (xy 211.199476 -232.488232)
			(xy 211.225223 -232.496534) (xy 211.274237 -232.519426) (xy 211.319526 -232.549012) (xy 211.360182 -232.5847)
			(xy 211.395388 -232.625773) (xy 211.424439 -232.671407) (xy 211.446751 -232.720688) (xy 211.461878 -232.772627)
			(xy 211.468773 -232.820972) (xy 212.193378 -232.820972) (xy 212.193891 -232.792233) (xy 212.202517 -232.735405)
			(xy 212.21957 -232.680515) (xy 212.244664 -232.628803) (xy 212.277231 -232.581441) (xy 212.296502 -232.560114)
			(xy 212.303106 -232.553002) (xy 212.306408 -232.54462) (xy 212.308159 -232.540052) (xy 212.31008 -232.53046)
			(xy 212.310218 -232.52557) (xy 212.310218 -232.455974) (xy 212.310072 -232.451084) (xy 212.30816 -232.441492)
			(xy 212.306408 -232.436924) (xy 212.303106 -232.428542) (xy 212.296502 -232.42143) (xy 212.277229 -232.400105)
			(xy 212.244661 -232.352743) (xy 212.219568 -232.301031) (xy 212.202518 -232.24614) (xy 212.193898 -232.189311)
			(xy 212.193378 -232.160572) (xy 212.193864 -232.133321) (xy 212.20162 -232.079373) (xy 212.216975 -232.027078)
			(xy 212.239617 -231.977501) (xy 212.269083 -231.931651) (xy 212.304774 -231.89046) (xy 212.345965 -231.854769)
			(xy 212.391815 -231.825303) (xy 212.441392 -231.802661) (xy 212.493687 -231.787306) (xy 212.547635 -231.77955)
			(xy 212.602137 -231.77955) (xy 212.656085 -231.787306) (xy 212.70838 -231.802661) (xy 212.757957 -231.825303)
			(xy 212.803807 -231.854769) (xy 212.844998 -231.89046) (xy 212.880689 -231.931651) (xy 212.910155 -231.977501)
			(xy 212.932797 -232.027078) (xy 212.948152 -232.079373) (xy 212.955908 -232.133321) (xy 212.956394 -232.160572)
			(xy 212.956394 -232.174288) (xy 212.96122 -232.184194) (xy 212.963151 -232.188044) (xy 212.968127 -232.195073)
			(xy 212.971126 -232.198164) (xy 212.976968 -232.20299) (xy 213.043262 -232.251758) (xy 213.048127 -232.255142)
			(xy 213.059036 -232.259766) (xy 213.064852 -232.260902) (xy 213.07044 -232.261918) (xy 213.082886 -232.260902)
			(xy 213.088474 -232.259124) (xy 213.116092 -232.251007) (xy 213.172978 -232.242202) (xy 213.201758 -232.241598)
			(xy 213.211664 -232.241598) (xy 213.220554 -232.238042) (xy 213.224188 -232.236491) (xy 213.230951 -232.232408)
			(xy 213.234016 -232.229914) (xy 213.236048 -232.228136) (xy 213.287356 -232.18013) (xy 213.29068 -232.176782)
			(xy 213.296172 -232.169112) (xy 213.298278 -232.16489) (xy 213.302342 -232.156508) (xy 213.30285 -232.146602)
			(xy 213.305213 -232.117948) (xy 213.317501 -232.061781) (xy 213.338076 -232.008094) (xy 213.366473 -231.958102)
			(xy 213.402049 -231.912936) (xy 213.443999 -231.873618) (xy 213.491373 -231.84104) (xy 213.543099 -231.815938)
			(xy 213.598005 -231.79888) (xy 213.654849 -231.790254) (xy 213.683596 -231.789732) (xy 213.710851 -231.790159)
			(xy 213.764805 -231.797917) (xy 213.817106 -231.813274) (xy 213.866689 -231.835919) (xy 213.912544 -231.86539)
			(xy 213.953737 -231.901088) (xy 213.989431 -231.942285) (xy 214.018898 -231.988143) (xy 214.041538 -232.037728)
			(xy 214.056891 -232.09003) (xy 214.064643 -232.143985) (xy 214.065104 -232.17124) (xy 214.064347 -232.205324)
			(xy 214.052208 -232.272402) (xy 214.040974 -232.30459) (xy 214.040466 -232.305606) (xy 214.036148 -232.318052)
			(xy 214.03818 -232.330752) (xy 214.040974 -232.341674) (xy 214.042478 -232.34529) (xy 214.046437 -232.352049)
			(xy 214.048848 -232.355136) (xy 214.103712 -232.423462) (xy 214.112856 -232.432352) (xy 214.117936 -232.436162)
			(xy 214.124032 -232.438448) (xy 214.130079 -232.440576) (xy 214.142799 -232.442123) (xy 214.149178 -232.441496)
			(xy 214.150194 -232.441496) (xy 214.163021 -232.43985) (xy 214.188824 -232.438069) (xy 214.201756 -232.43794)
			(xy 214.20201 -232.43794) (xy 214.22926 -232.438389) (xy 214.283204 -232.446146) (xy 214.335495 -232.461501)
			(xy 214.385069 -232.484142) (xy 214.430917 -232.513607) (xy 214.472104 -232.549296) (xy 214.507794 -232.590484)
			(xy 214.537259 -232.636331) (xy 214.559899 -232.685905) (xy 214.575254 -232.738197) (xy 214.583011 -232.792141)
			(xy 214.583012 -232.84664) (xy 214.575258 -232.900585) (xy 214.559906 -232.952877) (xy 214.537268 -233.002452)
			(xy 214.507805 -233.048301) (xy 214.472118 -233.089491) (xy 214.430932 -233.125182) (xy 214.385086 -233.154649)
			(xy 214.335513 -233.177292) (xy 214.329316 -233.179112) (xy 215.416892 -233.179112) (xy 215.416892 -233.178858)
			(xy 215.417354 -233.153029) (xy 215.42435 -233.101848) (xy 215.438182 -233.052076) (xy 215.458596 -233.004623)
			(xy 215.485221 -232.960356) (xy 215.517571 -232.920081) (xy 215.536018 -232.901998) (xy 215.543198 -232.894515)
			(xy 215.551468 -232.875522) (xy 215.55202 -232.865168) (xy 215.55202 -232.791508) (xy 215.551527 -232.78114)
			(xy 215.543252 -232.762124) (xy 215.536018 -232.754678) (xy 215.51755 -232.73661) (xy 215.48517 -232.69635)
			(xy 215.458526 -232.652085) (xy 215.438106 -232.604626) (xy 215.424285 -232.554844) (xy 215.417316 -232.503651)
			(xy 215.416892 -232.477818) (xy 215.416892 -232.477564) (xy 215.417378 -232.450313) (xy 215.425134 -232.396365)
			(xy 215.440489 -232.34407) (xy 215.463131 -232.294493) (xy 215.492597 -232.248643) (xy 215.528288 -232.207452)
			(xy 215.569479 -232.171761) (xy 215.615329 -232.142295) (xy 215.664906 -232.119653) (xy 215.717201 -232.104298)
			(xy 215.771149 -232.096542) (xy 215.825651 -232.096542) (xy 215.879599 -232.104298) (xy 215.931894 -232.119653)
			(xy 215.981471 -232.142295) (xy 216.027321 -232.171761) (xy 216.068512 -232.207452) (xy 216.104203 -232.248643)
			(xy 216.133669 -232.294493) (xy 216.156311 -232.34407) (xy 216.171666 -232.396365) (xy 216.179422 -232.450313)
			(xy 216.179799 -232.471468) (xy 217.201494 -232.471468) (xy 217.205565 -232.415846) (xy 217.217691 -232.361409)
			(xy 217.237614 -232.309318) (xy 217.26491 -232.260683) (xy 217.298996 -232.21654) (xy 217.339145 -232.177831)
			(xy 217.384503 -232.14538) (xy 217.434103 -232.119879) (xy 217.486887 -232.101872) (xy 217.54173 -232.091742)
			(xy 217.597464 -232.089705) (xy 217.652901 -232.095805) (xy 217.706858 -232.109911) (xy 217.758187 -232.131723)
			(xy 217.805793 -232.160777) (xy 217.848661 -232.196452) (xy 217.885878 -232.237989) (xy 217.916651 -232.284502)
			(xy 217.940323 -232.334999) (xy 217.956391 -232.388406) (xy 217.964511 -232.443582) (xy 217.96502 -232.471468)
			(xy 219.138244 -232.471468) (xy 219.142315 -232.415846) (xy 219.154441 -232.361409) (xy 219.174364 -232.309318)
			(xy 219.20166 -232.260683) (xy 219.235746 -232.21654) (xy 219.275895 -232.177831) (xy 219.321253 -232.14538)
			(xy 219.370853 -232.119879) (xy 219.423637 -232.101872) (xy 219.47848 -232.091742) (xy 219.534214 -232.089705)
			(xy 219.589651 -232.095805) (xy 219.643608 -232.109911) (xy 219.694937 -232.131723) (xy 219.742543 -232.160777)
			(xy 219.785411 -232.196452) (xy 219.822628 -232.237989) (xy 219.853401 -232.284502) (xy 219.877073 -232.334999)
			(xy 219.893141 -232.388406) (xy 219.901261 -232.443582) (xy 219.90177 -232.471468) (xy 221.265494 -232.471468)
			(xy 221.269565 -232.415846) (xy 221.281691 -232.361409) (xy 221.301614 -232.309318) (xy 221.32891 -232.260683)
			(xy 221.362996 -232.21654) (xy 221.403145 -232.177831) (xy 221.448503 -232.14538) (xy 221.498103 -232.119879)
			(xy 221.550887 -232.101872) (xy 221.60573 -232.091742) (xy 221.661464 -232.089705) (xy 221.716901 -232.095805)
			(xy 221.770858 -232.109911) (xy 221.822187 -232.131723) (xy 221.869793 -232.160777) (xy 221.912661 -232.196452)
			(xy 221.949878 -232.237989) (xy 221.980651 -232.284502) (xy 222.004323 -232.334999) (xy 222.020391 -232.388406)
			(xy 222.028511 -232.443582) (xy 222.02902 -232.471468) (xy 222.028511 -232.499354) (xy 222.020391 -232.55453)
			(xy 222.004323 -232.607937) (xy 221.980651 -232.658434) (xy 221.949878 -232.704947) (xy 221.912661 -232.746484)
			(xy 221.869793 -232.782159) (xy 221.822187 -232.811213) (xy 221.770858 -232.833025) (xy 221.716901 -232.847131)
			(xy 221.661464 -232.853231) (xy 221.60573 -232.851194) (xy 221.550887 -232.841064) (xy 221.498103 -232.823057)
			(xy 221.448503 -232.797556) (xy 221.403145 -232.765105) (xy 221.362996 -232.726396) (xy 221.32891 -232.682253)
			(xy 221.301614 -232.633618) (xy 221.281691 -232.581527) (xy 221.269565 -232.52709) (xy 221.265494 -232.471468)
			(xy 219.90177 -232.471468) (xy 219.901261 -232.499354) (xy 219.893141 -232.55453) (xy 219.877073 -232.607937)
			(xy 219.853401 -232.658434) (xy 219.822628 -232.704947) (xy 219.785411 -232.746484) (xy 219.742543 -232.782159)
			(xy 219.694937 -232.811213) (xy 219.643608 -232.833025) (xy 219.589651 -232.847131) (xy 219.534214 -232.853231)
			(xy 219.47848 -232.851194) (xy 219.423637 -232.841064) (xy 219.370853 -232.823057) (xy 219.321253 -232.797556)
			(xy 219.275895 -232.765105) (xy 219.235746 -232.726396) (xy 219.20166 -232.682253) (xy 219.174364 -232.633618)
			(xy 219.154441 -232.581527) (xy 219.142315 -232.52709) (xy 219.138244 -232.471468) (xy 217.96502 -232.471468)
			(xy 217.964511 -232.499354) (xy 217.956391 -232.55453) (xy 217.940323 -232.607937) (xy 217.916651 -232.658434)
			(xy 217.885878 -232.704947) (xy 217.848661 -232.746484) (xy 217.805793 -232.782159) (xy 217.758187 -232.811213)
			(xy 217.706858 -232.833025) (xy 217.652901 -232.847131) (xy 217.597464 -232.853231) (xy 217.54173 -232.851194)
			(xy 217.486887 -232.841064) (xy 217.434103 -232.823057) (xy 217.384503 -232.797556) (xy 217.339145 -232.765105)
			(xy 217.298996 -232.726396) (xy 217.26491 -232.682253) (xy 217.237614 -232.633618) (xy 217.217691 -232.581527)
			(xy 217.205565 -232.52709) (xy 217.201494 -232.471468) (xy 216.179799 -232.471468) (xy 216.179908 -232.477564)
			(xy 216.179908 -232.477818) (xy 216.17943 -232.503646) (xy 216.172437 -232.554827) (xy 216.158609 -232.604598)
			(xy 216.138197 -232.652051) (xy 216.111575 -232.696319) (xy 216.079228 -232.736594) (xy 216.060782 -232.754678)
			(xy 216.053569 -232.762133) (xy 216.045318 -232.781147) (xy 216.04478 -232.791508) (xy 216.04478 -232.865168)
			(xy 216.045286 -232.875535) (xy 216.053551 -232.894551) (xy 216.060782 -232.901998) (xy 216.079238 -232.920077)
			(xy 216.111619 -232.960335) (xy 216.138265 -233.004597) (xy 216.158687 -233.052054) (xy 216.17251 -233.101834)
			(xy 216.179482 -233.153026) (xy 216.179908 -233.178858) (xy 216.179908 -233.179112) (xy 216.179845 -233.182668)
			(xy 222.281494 -233.182668) (xy 222.285565 -233.127046) (xy 222.297691 -233.072609) (xy 222.317614 -233.020518)
			(xy 222.34491 -232.971883) (xy 222.378996 -232.92774) (xy 222.419145 -232.889031) (xy 222.464503 -232.85658)
			(xy 222.514103 -232.831079) (xy 222.566887 -232.813072) (xy 222.62173 -232.802942) (xy 222.677464 -232.800905)
			(xy 222.732901 -232.807005) (xy 222.786858 -232.821111) (xy 222.838187 -232.842923) (xy 222.885793 -232.871977)
			(xy 222.928661 -232.907652) (xy 222.965878 -232.949189) (xy 222.996651 -232.995702) (xy 223.020323 -233.046199)
			(xy 223.036391 -233.099606) (xy 223.044511 -233.154782) (xy 223.04502 -233.182668) (xy 223.298004 -233.182668)
			(xy 223.298004 -233.182414) (xy 223.298471 -233.156119) (xy 223.305714 -233.104031) (xy 223.320039 -233.05343)
			(xy 223.341173 -233.005274) (xy 223.368716 -232.960474) (xy 223.402148 -232.919879) (xy 223.421194 -232.901744)
			(xy 223.428577 -232.894207) (xy 223.437112 -232.874939) (xy 223.437704 -232.864406) (xy 223.437704 -232.78973)
			(xy 223.437171 -232.779181) (xy 223.428638 -232.759885) (xy 223.421194 -232.752392) (xy 223.402124 -232.734278)
			(xy 223.368669 -232.693692) (xy 223.341112 -232.648893) (xy 223.319975 -232.60073) (xy 223.305661 -232.550119)
			(xy 223.29844 -232.49802) (xy 223.298004 -232.471722) (xy 223.298004 -232.471468) (xy 223.29849 -232.444217)
			(xy 223.306246 -232.390269) (xy 223.321601 -232.337974) (xy 223.344243 -232.288397) (xy 223.373709 -232.242547)
			(xy 223.4094 -232.201356) (xy 223.450591 -232.165665) (xy 223.496441 -232.136199) (xy 223.546018 -232.113557)
			(xy 223.598313 -232.098202) (xy 223.652261 -232.090446) (xy 223.706763 -232.090446) (xy 223.760711 -232.098202)
			(xy 223.813006 -232.113557) (xy 223.862583 -232.136199) (xy 223.908433 -232.165665) (xy 223.949624 -232.201356)
			(xy 223.985315 -232.242547) (xy 224.014781 -232.288397) (xy 224.037423 -232.337974) (xy 224.052778 -232.390269)
			(xy 224.060534 -232.444217) (xy 224.06102 -232.471468) (xy 224.06102 -232.471722) (xy 224.06057 -232.498017)
			(xy 224.053322 -232.550106) (xy 224.038994 -232.600707) (xy 224.017857 -232.648863) (xy 223.99031 -232.693662)
			(xy 223.956877 -232.734258) (xy 223.93783 -232.752392) (xy 223.930434 -232.759919) (xy 223.921905 -232.779195)
			(xy 223.92132 -232.78973) (xy 223.92132 -232.864406) (xy 223.921827 -232.874958) (xy 223.930377 -232.894254)
			(xy 223.93783 -232.901744) (xy 223.956903 -232.919856) (xy 223.99036 -232.96044) (xy 224.017919 -233.005239)
			(xy 224.039056 -233.053403) (xy 224.053369 -233.104015) (xy 224.060586 -233.156115) (xy 224.06102 -233.182414)
			(xy 224.06102 -233.182668) (xy 224.313494 -233.182668) (xy 224.317565 -233.127046) (xy 224.329691 -233.072609)
			(xy 224.349614 -233.020518) (xy 224.37691 -232.971883) (xy 224.410996 -232.92774) (xy 224.451145 -232.889031)
			(xy 224.496503 -232.85658) (xy 224.546103 -232.831079) (xy 224.598887 -232.813072) (xy 224.65373 -232.802942)
			(xy 224.709464 -232.800905) (xy 224.764901 -232.807005) (xy 224.818858 -232.821111) (xy 224.870187 -232.842923)
			(xy 224.917793 -232.871977) (xy 224.960661 -232.907652) (xy 224.997878 -232.949189) (xy 225.028651 -232.995702)
			(xy 225.052323 -233.046199) (xy 225.068391 -233.099606) (xy 225.076511 -233.154782) (xy 225.07702 -233.182668)
			(xy 225.330004 -233.182668) (xy 225.330004 -233.182414) (xy 225.330471 -233.156119) (xy 225.337714 -233.104031)
			(xy 225.352039 -233.05343) (xy 225.373173 -233.005274) (xy 225.400716 -232.960474) (xy 225.434148 -232.919879)
			(xy 225.453194 -232.901744) (xy 225.460577 -232.894207) (xy 225.469112 -232.874939) (xy 225.469704 -232.864406)
			(xy 225.469704 -232.78973) (xy 225.469171 -232.779181) (xy 225.460638 -232.759885) (xy 225.453194 -232.752392)
			(xy 225.434124 -232.734278) (xy 225.400669 -232.693692) (xy 225.373112 -232.648893) (xy 225.351975 -232.60073)
			(xy 225.337661 -232.550119) (xy 225.33044 -232.49802) (xy 225.330004 -232.471722) (xy 225.330004 -232.471468)
			(xy 225.33049 -232.444217) (xy 225.338246 -232.390269) (xy 225.353601 -232.337974) (xy 225.376243 -232.288397)
			(xy 225.405709 -232.242547) (xy 225.4414 -232.201356) (xy 225.482591 -232.165665) (xy 225.528441 -232.136199)
			(xy 225.578018 -232.113557) (xy 225.630313 -232.098202) (xy 225.684261 -232.090446) (xy 225.738763 -232.090446)
			(xy 225.792711 -232.098202) (xy 225.845006 -232.113557) (xy 225.894583 -232.136199) (xy 225.940433 -232.165665)
			(xy 225.981624 -232.201356) (xy 226.017315 -232.242547) (xy 226.046781 -232.288397) (xy 226.069423 -232.337974)
			(xy 226.084778 -232.390269) (xy 226.092534 -232.444217) (xy 226.09302 -232.471468) (xy 226.345494 -232.471468)
			(xy 226.349565 -232.415846) (xy 226.361691 -232.361409) (xy 226.381614 -232.309318) (xy 226.40891 -232.260683)
			(xy 226.442996 -232.21654) (xy 226.483145 -232.177831) (xy 226.528503 -232.14538) (xy 226.578103 -232.119879)
			(xy 226.630887 -232.101872) (xy 226.68573 -232.091742) (xy 226.741464 -232.089705) (xy 226.796901 -232.095805)
			(xy 226.850858 -232.109911) (xy 226.902187 -232.131723) (xy 226.949793 -232.160777) (xy 226.992661 -232.196452)
			(xy 227.029878 -232.237989) (xy 227.060651 -232.284502) (xy 227.084323 -232.334999) (xy 227.100391 -232.388406)
			(xy 227.108511 -232.443582) (xy 227.10902 -232.471468) (xy 228.377494 -232.471468) (xy 228.381565 -232.415846)
			(xy 228.393691 -232.361409) (xy 228.413614 -232.309318) (xy 228.44091 -232.260683) (xy 228.474996 -232.21654)
			(xy 228.515145 -232.177831) (xy 228.560503 -232.14538) (xy 228.610103 -232.119879) (xy 228.662887 -232.101872)
			(xy 228.71773 -232.091742) (xy 228.773464 -232.089705) (xy 228.828901 -232.095805) (xy 228.882858 -232.109911)
			(xy 228.934187 -232.131723) (xy 228.981793 -232.160777) (xy 229.024661 -232.196452) (xy 229.061878 -232.237989)
			(xy 229.092651 -232.284502) (xy 229.116323 -232.334999) (xy 229.132391 -232.388406) (xy 229.140511 -232.443582)
			(xy 229.14102 -232.471468) (xy 229.140566 -232.49636) (xy 229.446074 -232.49636) (xy 229.44656 -232.469109)
			(xy 229.454316 -232.415161) (xy 229.469671 -232.362866) (xy 229.492313 -232.313289) (xy 229.521779 -232.267439)
			(xy 229.55747 -232.226248) (xy 229.598661 -232.190557) (xy 229.644511 -232.161091) (xy 229.694088 -232.138449)
			(xy 229.746383 -232.123094) (xy 229.800331 -232.115338) (xy 229.854833 -232.115338) (xy 229.908781 -232.123094)
			(xy 229.961076 -232.138449) (xy 230.010653 -232.161091) (xy 230.056503 -232.190557) (xy 230.097694 -232.226248)
			(xy 230.133385 -232.267439) (xy 230.162851 -232.313289) (xy 230.185493 -232.362866) (xy 230.200848 -232.415161)
			(xy 230.208604 -232.469109) (xy 230.20909 -232.49636) (xy 230.208484 -232.526446) (xy 230.199033 -232.585871)
			(xy 230.180374 -232.643077) (xy 230.15297 -232.696646) (xy 230.117499 -232.745251) (xy 230.096568 -232.76687)
			(xy 230.089456 -232.773982) (xy 230.085646 -232.78338) (xy 230.083774 -232.788053) (xy 230.081724 -232.797906)
			(xy 230.081582 -232.802938) (xy 230.081836 -232.875328) (xy 230.082017 -232.880356) (xy 230.084058 -232.890205)
			(xy 230.0859 -232.894886) (xy 230.08971 -232.90403) (xy 230.096822 -232.911142) (xy 230.117954 -232.932771)
			(xy 230.153757 -232.981498) (xy 230.181422 -233.035265) (xy 230.200256 -233.092724) (xy 230.209788 -233.152435)
			(xy 230.21036 -233.182668) (xy 230.410004 -233.182668) (xy 230.410004 -233.182414) (xy 230.410471 -233.156119)
			(xy 230.417714 -233.104031) (xy 230.432039 -233.05343) (xy 230.453173 -233.005274) (xy 230.480716 -232.960474)
			(xy 230.514148 -232.919879) (xy 230.533194 -232.901744) (xy 230.540577 -232.894207) (xy 230.549112 -232.874939)
			(xy 230.549704 -232.864406) (xy 230.549704 -232.78973) (xy 230.549171 -232.779181) (xy 230.540638 -232.759885)
			(xy 230.533194 -232.752392) (xy 230.514124 -232.734278) (xy 230.480669 -232.693692) (xy 230.453112 -232.648893)
			(xy 230.431975 -232.60073) (xy 230.417661 -232.550119) (xy 230.41044 -232.49802) (xy 230.410004 -232.471722)
			(xy 230.410004 -232.471468) (xy 230.41049 -232.444217) (xy 230.418246 -232.390269) (xy 230.433601 -232.337974)
			(xy 230.456243 -232.288397) (xy 230.485709 -232.242547) (xy 230.5214 -232.201356) (xy 230.562591 -232.165665)
			(xy 230.608441 -232.136199) (xy 230.658018 -232.113557) (xy 230.710313 -232.098202) (xy 230.764261 -232.090446)
			(xy 230.818763 -232.090446) (xy 230.872711 -232.098202) (xy 230.925006 -232.113557) (xy 230.974583 -232.136199)
			(xy 231.020433 -232.165665) (xy 231.061624 -232.201356) (xy 231.097315 -232.242547) (xy 231.126781 -232.288397)
			(xy 231.149423 -232.337974) (xy 231.164778 -232.390269) (xy 231.172534 -232.444217) (xy 231.17302 -232.471468)
			(xy 231.17302 -232.471722) (xy 231.17257 -232.498017) (xy 231.165322 -232.550106) (xy 231.150994 -232.600707)
			(xy 231.129857 -232.648863) (xy 231.10231 -232.693662) (xy 231.068877 -232.734258) (xy 231.04983 -232.752392)
			(xy 231.042434 -232.759919) (xy 231.033905 -232.779195) (xy 231.03332 -232.78973) (xy 231.03332 -232.864406)
			(xy 231.033827 -232.874958) (xy 231.042377 -232.894254) (xy 231.04983 -232.901744) (xy 231.068903 -232.919856)
			(xy 231.10236 -232.96044) (xy 231.129919 -233.005239) (xy 231.151056 -233.053403) (xy 231.165369 -233.104015)
			(xy 231.172586 -233.156115) (xy 231.17302 -233.182414) (xy 231.17302 -233.182668) (xy 231.426004 -233.182668)
			(xy 231.426004 -233.182414) (xy 231.426471 -233.156119) (xy 231.433714 -233.104031) (xy 231.448039 -233.05343)
			(xy 231.469173 -233.005274) (xy 231.496716 -232.960474) (xy 231.530148 -232.919879) (xy 231.549194 -232.901744)
			(xy 231.556577 -232.894207) (xy 231.565112 -232.874939) (xy 231.565704 -232.864406) (xy 231.565704 -232.78973)
			(xy 231.565171 -232.779181) (xy 231.556638 -232.759885) (xy 231.549194 -232.752392) (xy 231.530124 -232.734278)
			(xy 231.496669 -232.693692) (xy 231.469112 -232.648893) (xy 231.447975 -232.60073) (xy 231.433661 -232.550119)
			(xy 231.42644 -232.49802) (xy 231.426004 -232.471722) (xy 231.426004 -232.471468) (xy 231.42649 -232.444217)
			(xy 231.434246 -232.390269) (xy 231.449601 -232.337974) (xy 231.472243 -232.288397) (xy 231.501709 -232.242547)
			(xy 231.5374 -232.201356) (xy 231.578591 -232.165665) (xy 231.624441 -232.136199) (xy 231.674018 -232.113557)
			(xy 231.726313 -232.098202) (xy 231.780261 -232.090446) (xy 231.834763 -232.090446) (xy 231.888711 -232.098202)
			(xy 231.941006 -232.113557) (xy 231.990583 -232.136199) (xy 232.036433 -232.165665) (xy 232.077624 -232.201356)
			(xy 232.113315 -232.242547) (xy 232.142781 -232.288397) (xy 232.165423 -232.337974) (xy 232.180778 -232.390269)
			(xy 232.188534 -232.444217) (xy 232.18902 -232.471468) (xy 232.18902 -232.471722) (xy 232.18857 -232.498017)
			(xy 232.181322 -232.550106) (xy 232.166994 -232.600707) (xy 232.145857 -232.648863) (xy 232.11831 -232.693662)
			(xy 232.084877 -232.734258) (xy 232.06583 -232.752392) (xy 232.058434 -232.759919) (xy 232.049905 -232.779195)
			(xy 232.04932 -232.78973) (xy 232.04932 -232.864406) (xy 232.049827 -232.874958) (xy 232.058377 -232.894254)
			(xy 232.06583 -232.901744) (xy 232.084903 -232.919856) (xy 232.11836 -232.96044) (xy 232.145919 -233.005239)
			(xy 232.167056 -233.053403) (xy 232.181369 -233.104015) (xy 232.188586 -233.156115) (xy 232.18902 -233.182414)
			(xy 232.18902 -233.182668) (xy 232.442004 -233.182668) (xy 232.442004 -233.182414) (xy 232.442471 -233.156119)
			(xy 232.449714 -233.104031) (xy 232.464039 -233.05343) (xy 232.485173 -233.005274) (xy 232.512716 -232.960474)
			(xy 232.546148 -232.919879) (xy 232.565194 -232.901744) (xy 232.572577 -232.894207) (xy 232.581112 -232.874939)
			(xy 232.581704 -232.864406) (xy 232.581704 -232.78973) (xy 232.581171 -232.779181) (xy 232.572638 -232.759885)
			(xy 232.565194 -232.752392) (xy 232.546124 -232.734278) (xy 232.512669 -232.693692) (xy 232.485112 -232.648893)
			(xy 232.463975 -232.60073) (xy 232.449661 -232.550119) (xy 232.44244 -232.49802) (xy 232.442004 -232.471722)
			(xy 232.442004 -232.471468) (xy 232.44249 -232.444217) (xy 232.450246 -232.390269) (xy 232.465601 -232.337974)
			(xy 232.488243 -232.288397) (xy 232.517709 -232.242547) (xy 232.5534 -232.201356) (xy 232.594591 -232.165665)
			(xy 232.640441 -232.136199) (xy 232.690018 -232.113557) (xy 232.742313 -232.098202) (xy 232.796261 -232.090446)
			(xy 232.850763 -232.090446) (xy 232.904711 -232.098202) (xy 232.957006 -232.113557) (xy 233.006583 -232.136199)
			(xy 233.052433 -232.165665) (xy 233.093624 -232.201356) (xy 233.129315 -232.242547) (xy 233.158781 -232.288397)
			(xy 233.181423 -232.337974) (xy 233.196778 -232.390269) (xy 233.204534 -232.444217) (xy 233.20502 -232.471468)
			(xy 233.20502 -232.471722) (xy 233.20457 -232.498017) (xy 233.197322 -232.550106) (xy 233.182994 -232.600707)
			(xy 233.161857 -232.648863) (xy 233.13431 -232.693662) (xy 233.100877 -232.734258) (xy 233.08183 -232.752392)
			(xy 233.074434 -232.759919) (xy 233.065905 -232.779195) (xy 233.06532 -232.78973) (xy 233.06532 -232.864406)
			(xy 233.065827 -232.874958) (xy 233.074377 -232.894254) (xy 233.08183 -232.901744) (xy 233.100903 -232.919856)
			(xy 233.13436 -232.96044) (xy 233.161919 -233.005239) (xy 233.183056 -233.053403) (xy 233.197369 -233.104015)
			(xy 233.204586 -233.156115) (xy 233.20502 -233.182414) (xy 233.20502 -233.182668) (xy 233.458004 -233.182668)
			(xy 233.458004 -233.182414) (xy 233.458471 -233.156119) (xy 233.465714 -233.104031) (xy 233.480039 -233.05343)
			(xy 233.501173 -233.005274) (xy 233.528716 -232.960474) (xy 233.562148 -232.919879) (xy 233.581194 -232.901744)
			(xy 233.588577 -232.894207) (xy 233.597112 -232.874939) (xy 233.597704 -232.864406) (xy 233.597704 -232.78973)
			(xy 233.597171 -232.779181) (xy 233.588638 -232.759885) (xy 233.581194 -232.752392) (xy 233.562124 -232.734278)
			(xy 233.528669 -232.693692) (xy 233.501112 -232.648893) (xy 233.479975 -232.60073) (xy 233.465661 -232.550119)
			(xy 233.45844 -232.49802) (xy 233.458004 -232.471722) (xy 233.458004 -232.471468) (xy 233.45849 -232.444217)
			(xy 233.466246 -232.390269) (xy 233.481601 -232.337974) (xy 233.504243 -232.288397) (xy 233.533709 -232.242547)
			(xy 233.5694 -232.201356) (xy 233.610591 -232.165665) (xy 233.656441 -232.136199) (xy 233.706018 -232.113557)
			(xy 233.758313 -232.098202) (xy 233.812261 -232.090446) (xy 233.866763 -232.090446) (xy 233.920711 -232.098202)
			(xy 233.973006 -232.113557) (xy 234.022583 -232.136199) (xy 234.068433 -232.165665) (xy 234.109624 -232.201356)
			(xy 234.145315 -232.242547) (xy 234.174781 -232.288397) (xy 234.197423 -232.337974) (xy 234.212778 -232.390269)
			(xy 234.220534 -232.444217) (xy 234.22102 -232.471468) (xy 234.22102 -232.471722) (xy 234.22057 -232.498017)
			(xy 234.213322 -232.550106) (xy 234.198994 -232.600707) (xy 234.177857 -232.648863) (xy 234.15031 -232.693662)
			(xy 234.116877 -232.734258) (xy 234.09783 -232.752392) (xy 234.090434 -232.759919) (xy 234.081905 -232.779195)
			(xy 234.08132 -232.78973) (xy 234.08132 -232.864406) (xy 234.081827 -232.874958) (xy 234.090377 -232.894254)
			(xy 234.09783 -232.901744) (xy 234.116903 -232.919856) (xy 234.15036 -232.96044) (xy 234.177919 -233.005239)
			(xy 234.199056 -233.053403) (xy 234.213369 -233.104015) (xy 234.220586 -233.156115) (xy 234.22102 -233.182414)
			(xy 234.22102 -233.182668) (xy 234.474004 -233.182668) (xy 234.474004 -233.182414) (xy 234.474471 -233.156119)
			(xy 234.481714 -233.104031) (xy 234.496039 -233.05343) (xy 234.517173 -233.005274) (xy 234.544716 -232.960474)
			(xy 234.578148 -232.919879) (xy 234.597194 -232.901744) (xy 234.604577 -232.894207) (xy 234.613112 -232.874939)
			(xy 234.613704 -232.864406) (xy 234.613704 -232.78973) (xy 234.613171 -232.779181) (xy 234.604638 -232.759885)
			(xy 234.597194 -232.752392) (xy 234.578124 -232.734278) (xy 234.544669 -232.693692) (xy 234.517112 -232.648893)
			(xy 234.495975 -232.60073) (xy 234.481661 -232.550119) (xy 234.47444 -232.49802) (xy 234.474004 -232.471722)
			(xy 234.474004 -232.471468) (xy 234.47449 -232.444217) (xy 234.482246 -232.390269) (xy 234.497601 -232.337974)
			(xy 234.520243 -232.288397) (xy 234.549709 -232.242547) (xy 234.5854 -232.201356) (xy 234.626591 -232.165665)
			(xy 234.672441 -232.136199) (xy 234.722018 -232.113557) (xy 234.774313 -232.098202) (xy 234.828261 -232.090446)
			(xy 234.882763 -232.090446) (xy 234.936711 -232.098202) (xy 234.989006 -232.113557) (xy 235.038583 -232.136199)
			(xy 235.084433 -232.165665) (xy 235.125624 -232.201356) (xy 235.161315 -232.242547) (xy 235.190781 -232.288397)
			(xy 235.213423 -232.337974) (xy 235.228778 -232.390269) (xy 235.236534 -232.444217) (xy 235.23702 -232.471468)
			(xy 235.23702 -232.471722) (xy 235.23657 -232.498017) (xy 235.229322 -232.550106) (xy 235.214994 -232.600707)
			(xy 235.193857 -232.648863) (xy 235.16631 -232.693662) (xy 235.132877 -232.734258) (xy 235.11383 -232.752392)
			(xy 235.106434 -232.759919) (xy 235.097905 -232.779195) (xy 235.09732 -232.78973) (xy 235.09732 -232.864406)
			(xy 235.097827 -232.874958) (xy 235.106377 -232.894254) (xy 235.11383 -232.901744) (xy 235.132903 -232.919856)
			(xy 235.16636 -232.96044) (xy 235.193919 -233.005239) (xy 235.215056 -233.053403) (xy 235.229369 -233.104015)
			(xy 235.236586 -233.156115) (xy 235.23702 -233.182414) (xy 235.23702 -233.182668) (xy 235.490004 -233.182668)
			(xy 235.490004 -233.182414) (xy 235.490471 -233.156119) (xy 235.497714 -233.104031) (xy 235.512039 -233.05343)
			(xy 235.533173 -233.005274) (xy 235.560716 -232.960474) (xy 235.594148 -232.919879) (xy 235.613194 -232.901744)
			(xy 235.620577 -232.894207) (xy 235.629112 -232.874939) (xy 235.629704 -232.864406) (xy 235.629704 -232.78973)
			(xy 235.629171 -232.779181) (xy 235.620638 -232.759885) (xy 235.613194 -232.752392) (xy 235.594124 -232.734278)
			(xy 235.560669 -232.693692) (xy 235.533112 -232.648893) (xy 235.511975 -232.60073) (xy 235.497661 -232.550119)
			(xy 235.49044 -232.49802) (xy 235.490004 -232.471722) (xy 235.490004 -232.471468) (xy 235.49049 -232.444217)
			(xy 235.498246 -232.390269) (xy 235.513601 -232.337974) (xy 235.536243 -232.288397) (xy 235.565709 -232.242547)
			(xy 235.6014 -232.201356) (xy 235.642591 -232.165665) (xy 235.688441 -232.136199) (xy 235.738018 -232.113557)
			(xy 235.790313 -232.098202) (xy 235.844261 -232.090446) (xy 235.898763 -232.090446) (xy 235.952711 -232.098202)
			(xy 236.005006 -232.113557) (xy 236.054583 -232.136199) (xy 236.100433 -232.165665) (xy 236.141624 -232.201356)
			(xy 236.177315 -232.242547) (xy 236.206781 -232.288397) (xy 236.229423 -232.337974) (xy 236.244778 -232.390269)
			(xy 236.252534 -232.444217) (xy 236.25302 -232.471468) (xy 236.25302 -232.471722) (xy 236.25257 -232.498017)
			(xy 236.245322 -232.550106) (xy 236.230994 -232.600707) (xy 236.209857 -232.648863) (xy 236.18231 -232.693662)
			(xy 236.148877 -232.734258) (xy 236.12983 -232.752392) (xy 236.122434 -232.759919) (xy 236.113905 -232.779195)
			(xy 236.11332 -232.78973) (xy 236.11332 -232.864406) (xy 236.113827 -232.874958) (xy 236.122377 -232.894254)
			(xy 236.12983 -232.901744) (xy 236.148903 -232.919856) (xy 236.18236 -232.96044) (xy 236.209919 -233.005239)
			(xy 236.231056 -233.053403) (xy 236.245369 -233.104015) (xy 236.252586 -233.156115) (xy 236.25302 -233.182414)
			(xy 236.25302 -233.182668) (xy 236.506004 -233.182668) (xy 236.506004 -233.182414) (xy 236.506471 -233.156119)
			(xy 236.513714 -233.104031) (xy 236.528039 -233.05343) (xy 236.549173 -233.005274) (xy 236.576716 -232.960474)
			(xy 236.610148 -232.919879) (xy 236.629194 -232.901744) (xy 236.636577 -232.894207) (xy 236.645112 -232.874939)
			(xy 236.645704 -232.864406) (xy 236.645704 -232.78973) (xy 236.645171 -232.779181) (xy 236.636638 -232.759885)
			(xy 236.629194 -232.752392) (xy 236.610124 -232.734278) (xy 236.576669 -232.693692) (xy 236.549112 -232.648893)
			(xy 236.527975 -232.60073) (xy 236.513661 -232.550119) (xy 236.50644 -232.49802) (xy 236.506004 -232.471722)
			(xy 236.506004 -232.471468) (xy 236.50649 -232.444217) (xy 236.514246 -232.390269) (xy 236.529601 -232.337974)
			(xy 236.552243 -232.288397) (xy 236.581709 -232.242547) (xy 236.6174 -232.201356) (xy 236.658591 -232.165665)
			(xy 236.704441 -232.136199) (xy 236.754018 -232.113557) (xy 236.806313 -232.098202) (xy 236.860261 -232.090446)
			(xy 236.914763 -232.090446) (xy 236.968711 -232.098202) (xy 237.021006 -232.113557) (xy 237.070583 -232.136199)
			(xy 237.116433 -232.165665) (xy 237.157624 -232.201356) (xy 237.193315 -232.242547) (xy 237.222781 -232.288397)
			(xy 237.245423 -232.337974) (xy 237.260778 -232.390269) (xy 237.268534 -232.444217) (xy 237.26902 -232.471468)
			(xy 237.26902 -232.471722) (xy 237.26857 -232.498017) (xy 237.261322 -232.550106) (xy 237.246994 -232.600707)
			(xy 237.225857 -232.648863) (xy 237.19831 -232.693662) (xy 237.164877 -232.734258) (xy 237.14583 -232.752392)
			(xy 237.138434 -232.759919) (xy 237.129905 -232.779195) (xy 237.12932 -232.78973) (xy 237.12932 -232.864406)
			(xy 237.129827 -232.874958) (xy 237.138377 -232.894254) (xy 237.14583 -232.901744) (xy 237.164903 -232.919856)
			(xy 237.19836 -232.96044) (xy 237.225919 -233.005239) (xy 237.247056 -233.053403) (xy 237.261369 -233.104015)
			(xy 237.268586 -233.156115) (xy 237.26902 -233.182414) (xy 237.26902 -233.182668) (xy 237.522004 -233.182668)
			(xy 237.522004 -233.182414) (xy 237.522471 -233.156119) (xy 237.529714 -233.104031) (xy 237.544039 -233.05343)
			(xy 237.565173 -233.005274) (xy 237.592716 -232.960474) (xy 237.626148 -232.919879) (xy 237.645194 -232.901744)
			(xy 237.652577 -232.894207) (xy 237.661112 -232.874939) (xy 237.661704 -232.864406) (xy 237.661704 -232.78973)
			(xy 237.661171 -232.779181) (xy 237.652638 -232.759885) (xy 237.645194 -232.752392) (xy 237.626124 -232.734278)
			(xy 237.592669 -232.693692) (xy 237.565112 -232.648893) (xy 237.543975 -232.60073) (xy 237.529661 -232.550119)
			(xy 237.52244 -232.49802) (xy 237.522004 -232.471722) (xy 237.522004 -232.471468) (xy 237.52249 -232.444217)
			(xy 237.530246 -232.390269) (xy 237.545601 -232.337974) (xy 237.568243 -232.288397) (xy 237.597709 -232.242547)
			(xy 237.6334 -232.201356) (xy 237.674591 -232.165665) (xy 237.720441 -232.136199) (xy 237.770018 -232.113557)
			(xy 237.822313 -232.098202) (xy 237.876261 -232.090446) (xy 237.930763 -232.090446) (xy 237.984711 -232.098202)
			(xy 238.037006 -232.113557) (xy 238.086583 -232.136199) (xy 238.132433 -232.165665) (xy 238.173624 -232.201356)
			(xy 238.209315 -232.242547) (xy 238.238781 -232.288397) (xy 238.261423 -232.337974) (xy 238.276778 -232.390269)
			(xy 238.284534 -232.444217) (xy 238.28502 -232.471468) (xy 238.537494 -232.471468) (xy 238.541565 -232.415846)
			(xy 238.553691 -232.361409) (xy 238.573614 -232.309318) (xy 238.60091 -232.260683) (xy 238.634996 -232.21654)
			(xy 238.675145 -232.177831) (xy 238.720503 -232.14538) (xy 238.770103 -232.119879) (xy 238.822887 -232.101872)
			(xy 238.87773 -232.091742) (xy 238.933464 -232.089705) (xy 238.988901 -232.095805) (xy 239.042858 -232.109911)
			(xy 239.094187 -232.131723) (xy 239.141793 -232.160777) (xy 239.184661 -232.196452) (xy 239.221878 -232.237989)
			(xy 239.252651 -232.284502) (xy 239.276323 -232.334999) (xy 239.292391 -232.388406) (xy 239.300511 -232.443582)
			(xy 239.30102 -232.471468) (xy 240.163348 -232.471468) (xy 240.167419 -232.415846) (xy 240.179545 -232.361409)
			(xy 240.199468 -232.309318) (xy 240.226764 -232.260683) (xy 240.26085 -232.21654) (xy 240.300999 -232.177831)
			(xy 240.346357 -232.14538) (xy 240.395957 -232.119879) (xy 240.448741 -232.101872) (xy 240.503584 -232.091742)
			(xy 240.559318 -232.089705) (xy 240.614755 -232.095805) (xy 240.668712 -232.109911) (xy 240.720041 -232.131723)
			(xy 240.767647 -232.160777) (xy 240.810515 -232.196452) (xy 240.847732 -232.237989) (xy 240.878505 -232.284502)
			(xy 240.902177 -232.334999) (xy 240.918245 -232.388406) (xy 240.926365 -232.443582) (xy 240.926874 -232.471468)
			(xy 240.926365 -232.499354) (xy 240.918245 -232.55453) (xy 240.902177 -232.607937) (xy 240.878505 -232.658434)
			(xy 240.847732 -232.704947) (xy 240.810515 -232.746484) (xy 240.767647 -232.782159) (xy 240.720041 -232.811213)
			(xy 240.668712 -232.833025) (xy 240.614755 -232.847131) (xy 240.559318 -232.853231) (xy 240.503584 -232.851194)
			(xy 240.448741 -232.841064) (xy 240.395957 -232.823057) (xy 240.346357 -232.797556) (xy 240.300999 -232.765105)
			(xy 240.26085 -232.726396) (xy 240.226764 -232.682253) (xy 240.199468 -232.633618) (xy 240.179545 -232.581527)
			(xy 240.167419 -232.52709) (xy 240.163348 -232.471468) (xy 239.30102 -232.471468) (xy 239.300511 -232.499354)
			(xy 239.292391 -232.55453) (xy 239.276323 -232.607937) (xy 239.252651 -232.658434) (xy 239.221878 -232.704947)
			(xy 239.184661 -232.746484) (xy 239.141793 -232.782159) (xy 239.094187 -232.811213) (xy 239.042858 -232.833025)
			(xy 238.988901 -232.847131) (xy 238.933464 -232.853231) (xy 238.87773 -232.851194) (xy 238.822887 -232.841064)
			(xy 238.770103 -232.823057) (xy 238.720503 -232.797556) (xy 238.675145 -232.765105) (xy 238.634996 -232.726396)
			(xy 238.60091 -232.682253) (xy 238.573614 -232.633618) (xy 238.553691 -232.581527) (xy 238.541565 -232.52709)
			(xy 238.537494 -232.471468) (xy 238.28502 -232.471468) (xy 238.28502 -232.471722) (xy 238.28457 -232.498017)
			(xy 238.277322 -232.550106) (xy 238.262994 -232.600707) (xy 238.241857 -232.648863) (xy 238.21431 -232.693662)
			(xy 238.180877 -232.734258) (xy 238.16183 -232.752392) (xy 238.154434 -232.759919) (xy 238.145905 -232.779195)
			(xy 238.14532 -232.78973) (xy 238.14532 -232.864406) (xy 238.145827 -232.874958) (xy 238.154377 -232.894254)
			(xy 238.16183 -232.901744) (xy 238.180903 -232.919856) (xy 238.21436 -232.96044) (xy 238.241919 -233.005239)
			(xy 238.263056 -233.053403) (xy 238.277369 -233.104015) (xy 238.284586 -233.156115) (xy 238.28502 -233.182414)
			(xy 238.28502 -233.182668) (xy 238.284534 -233.209919) (xy 238.278811 -233.249724) (xy 243.342412 -233.249724)
			(xy 243.346483 -233.194102) (xy 243.358609 -233.139665) (xy 243.378532 -233.087574) (xy 243.405828 -233.038939)
			(xy 243.439914 -232.994796) (xy 243.480063 -232.956087) (xy 243.525421 -232.923636) (xy 243.575021 -232.898135)
			(xy 243.627805 -232.880128) (xy 243.682648 -232.869998) (xy 243.738382 -232.867961) (xy 243.793819 -232.874061)
			(xy 243.847776 -232.888167) (xy 243.899105 -232.909979) (xy 243.946711 -232.939033) (xy 243.989579 -232.974708)
			(xy 244.026796 -233.016245) (xy 244.057569 -233.062758) (xy 244.081241 -233.113255) (xy 244.097309 -233.166662)
			(xy 244.105429 -233.221838) (xy 244.105938 -233.249724) (xy 244.105429 -233.27761) (xy 244.097309 -233.332786)
			(xy 244.081241 -233.386193) (xy 244.057569 -233.43669) (xy 244.026796 -233.483203) (xy 243.989579 -233.52474)
			(xy 243.946711 -233.560415) (xy 243.899105 -233.589469) (xy 243.847776 -233.611281) (xy 243.793819 -233.625387)
			(xy 243.738382 -233.631487) (xy 243.682648 -233.62945) (xy 243.627805 -233.61932) (xy 243.575021 -233.601313)
			(xy 243.525421 -233.575812) (xy 243.480063 -233.543361) (xy 243.439914 -233.504652) (xy 243.405828 -233.460509)
			(xy 243.378532 -233.411874) (xy 243.358609 -233.359783) (xy 243.346483 -233.305346) (xy 243.342412 -233.249724)
			(xy 238.278811 -233.249724) (xy 238.276778 -233.263867) (xy 238.261423 -233.316162) (xy 238.238781 -233.365739)
			(xy 238.209315 -233.411589) (xy 238.173624 -233.45278) (xy 238.132433 -233.488471) (xy 238.086583 -233.517937)
			(xy 238.037006 -233.540579) (xy 237.984711 -233.555934) (xy 237.930763 -233.56369) (xy 237.876261 -233.56369)
			(xy 237.822313 -233.555934) (xy 237.770018 -233.540579) (xy 237.720441 -233.517937) (xy 237.674591 -233.488471)
			(xy 237.6334 -233.45278) (xy 237.597709 -233.411589) (xy 237.568243 -233.365739) (xy 237.545601 -233.316162)
			(xy 237.530246 -233.263867) (xy 237.52249 -233.209919) (xy 237.522004 -233.182668) (xy 237.26902 -233.182668)
			(xy 237.268534 -233.209919) (xy 237.260778 -233.263867) (xy 237.245423 -233.316162) (xy 237.222781 -233.365739)
			(xy 237.193315 -233.411589) (xy 237.157624 -233.45278) (xy 237.116433 -233.488471) (xy 237.070583 -233.517937)
			(xy 237.021006 -233.540579) (xy 236.968711 -233.555934) (xy 236.914763 -233.56369) (xy 236.860261 -233.56369)
			(xy 236.806313 -233.555934) (xy 236.754018 -233.540579) (xy 236.704441 -233.517937) (xy 236.658591 -233.488471)
			(xy 236.6174 -233.45278) (xy 236.581709 -233.411589) (xy 236.552243 -233.365739) (xy 236.529601 -233.316162)
			(xy 236.514246 -233.263867) (xy 236.50649 -233.209919) (xy 236.506004 -233.182668) (xy 236.25302 -233.182668)
			(xy 236.252534 -233.209919) (xy 236.244778 -233.263867) (xy 236.229423 -233.316162) (xy 236.206781 -233.365739)
			(xy 236.177315 -233.411589) (xy 236.141624 -233.45278) (xy 236.100433 -233.488471) (xy 236.054583 -233.517937)
			(xy 236.005006 -233.540579) (xy 235.952711 -233.555934) (xy 235.898763 -233.56369) (xy 235.844261 -233.56369)
			(xy 235.790313 -233.555934) (xy 235.738018 -233.540579) (xy 235.688441 -233.517937) (xy 235.642591 -233.488471)
			(xy 235.6014 -233.45278) (xy 235.565709 -233.411589) (xy 235.536243 -233.365739) (xy 235.513601 -233.316162)
			(xy 235.498246 -233.263867) (xy 235.49049 -233.209919) (xy 235.490004 -233.182668) (xy 235.23702 -233.182668)
			(xy 235.236534 -233.209919) (xy 235.228778 -233.263867) (xy 235.213423 -233.316162) (xy 235.190781 -233.365739)
			(xy 235.161315 -233.411589) (xy 235.125624 -233.45278) (xy 235.084433 -233.488471) (xy 235.038583 -233.517937)
			(xy 234.989006 -233.540579) (xy 234.936711 -233.555934) (xy 234.882763 -233.56369) (xy 234.828261 -233.56369)
			(xy 234.774313 -233.555934) (xy 234.722018 -233.540579) (xy 234.672441 -233.517937) (xy 234.626591 -233.488471)
			(xy 234.5854 -233.45278) (xy 234.549709 -233.411589) (xy 234.520243 -233.365739) (xy 234.497601 -233.316162)
			(xy 234.482246 -233.263867) (xy 234.47449 -233.209919) (xy 234.474004 -233.182668) (xy 234.22102 -233.182668)
			(xy 234.220534 -233.209919) (xy 234.212778 -233.263867) (xy 234.197423 -233.316162) (xy 234.174781 -233.365739)
			(xy 234.145315 -233.411589) (xy 234.109624 -233.45278) (xy 234.068433 -233.488471) (xy 234.022583 -233.517937)
			(xy 233.973006 -233.540579) (xy 233.920711 -233.555934) (xy 233.866763 -233.56369) (xy 233.812261 -233.56369)
			(xy 233.758313 -233.555934) (xy 233.706018 -233.540579) (xy 233.656441 -233.517937) (xy 233.610591 -233.488471)
			(xy 233.5694 -233.45278) (xy 233.533709 -233.411589) (xy 233.504243 -233.365739) (xy 233.481601 -233.316162)
			(xy 233.466246 -233.263867) (xy 233.45849 -233.209919) (xy 233.458004 -233.182668) (xy 233.20502 -233.182668)
			(xy 233.204534 -233.209919) (xy 233.196778 -233.263867) (xy 233.181423 -233.316162) (xy 233.158781 -233.365739)
			(xy 233.129315 -233.411589) (xy 233.093624 -233.45278) (xy 233.052433 -233.488471) (xy 233.006583 -233.517937)
			(xy 232.957006 -233.540579) (xy 232.904711 -233.555934) (xy 232.850763 -233.56369) (xy 232.796261 -233.56369)
			(xy 232.742313 -233.555934) (xy 232.690018 -233.540579) (xy 232.640441 -233.517937) (xy 232.594591 -233.488471)
			(xy 232.5534 -233.45278) (xy 232.517709 -233.411589) (xy 232.488243 -233.365739) (xy 232.465601 -233.316162)
			(xy 232.450246 -233.263867) (xy 232.44249 -233.209919) (xy 232.442004 -233.182668) (xy 232.18902 -233.182668)
			(xy 232.188534 -233.209919) (xy 232.180778 -233.263867) (xy 232.165423 -233.316162) (xy 232.142781 -233.365739)
			(xy 232.113315 -233.411589) (xy 232.077624 -233.45278) (xy 232.036433 -233.488471) (xy 231.990583 -233.517937)
			(xy 231.941006 -233.540579) (xy 231.888711 -233.555934) (xy 231.834763 -233.56369) (xy 231.780261 -233.56369)
			(xy 231.726313 -233.555934) (xy 231.674018 -233.540579) (xy 231.624441 -233.517937) (xy 231.578591 -233.488471)
			(xy 231.5374 -233.45278) (xy 231.501709 -233.411589) (xy 231.472243 -233.365739) (xy 231.449601 -233.316162)
			(xy 231.434246 -233.263867) (xy 231.42649 -233.209919) (xy 231.426004 -233.182668) (xy 231.17302 -233.182668)
			(xy 231.172534 -233.209919) (xy 231.164778 -233.263867) (xy 231.149423 -233.316162) (xy 231.126781 -233.365739)
			(xy 231.097315 -233.411589) (xy 231.061624 -233.45278) (xy 231.020433 -233.488471) (xy 230.974583 -233.517937)
			(xy 230.925006 -233.540579) (xy 230.872711 -233.555934) (xy 230.818763 -233.56369) (xy 230.764261 -233.56369)
			(xy 230.710313 -233.555934) (xy 230.658018 -233.540579) (xy 230.608441 -233.517937) (xy 230.562591 -233.488471)
			(xy 230.5214 -233.45278) (xy 230.485709 -233.411589) (xy 230.456243 -233.365739) (xy 230.433601 -233.316162)
			(xy 230.418246 -233.263867) (xy 230.41049 -233.209919) (xy 230.410004 -233.182668) (xy 230.21036 -233.182668)
			(xy 230.209874 -233.209919) (xy 230.202118 -233.263867) (xy 230.186763 -233.316162) (xy 230.164121 -233.365739)
			(xy 230.134655 -233.411589) (xy 230.098964 -233.45278) (xy 230.057773 -233.488471) (xy 230.011923 -233.517937)
			(xy 229.962346 -233.540579) (xy 229.910051 -233.555934) (xy 229.856103 -233.56369) (xy 229.801601 -233.56369)
			(xy 229.747653 -233.555934) (xy 229.695358 -233.540579) (xy 229.645781 -233.517937) (xy 229.599931 -233.488471)
			(xy 229.55874 -233.45278) (xy 229.523049 -233.411589) (xy 229.493583 -233.365739) (xy 229.470941 -233.316162)
			(xy 229.455586 -233.263867) (xy 229.44783 -233.209919) (xy 229.447344 -233.182668) (xy 229.447895 -233.15258)
			(xy 229.457358 -233.093152) (xy 229.476029 -233.035945) (xy 229.503446 -232.982377) (xy 229.538929 -232.933775)
			(xy 229.559866 -232.912158) (xy 229.566978 -232.905046) (xy 229.570788 -232.895648) (xy 229.572654 -232.890973)
			(xy 229.574707 -232.881121) (xy 229.574852 -232.87609) (xy 229.574598 -232.8037) (xy 229.574435 -232.798671)
			(xy 229.572382 -232.788822) (xy 229.570534 -232.784142) (xy 229.566724 -232.774998) (xy 229.559612 -232.767886)
			(xy 229.538482 -232.746256) (xy 229.502681 -232.697527) (xy 229.475017 -232.643761) (xy 229.456182 -232.586303)
			(xy 229.446648 -232.526593) (xy 229.446074 -232.49636) (xy 229.140566 -232.49636) (xy 229.140511 -232.499354)
			(xy 229.132391 -232.55453) (xy 229.116323 -232.607937) (xy 229.092651 -232.658434) (xy 229.061878 -232.704947)
			(xy 229.024661 -232.746484) (xy 228.981793 -232.782159) (xy 228.934187 -232.811213) (xy 228.882858 -232.833025)
			(xy 228.828901 -232.847131) (xy 228.773464 -232.853231) (xy 228.71773 -232.851194) (xy 228.662887 -232.841064)
			(xy 228.610103 -232.823057) (xy 228.560503 -232.797556) (xy 228.515145 -232.765105) (xy 228.474996 -232.726396)
			(xy 228.44091 -232.682253) (xy 228.413614 -232.633618) (xy 228.393691 -232.581527) (xy 228.381565 -232.52709)
			(xy 228.377494 -232.471468) (xy 227.10902 -232.471468) (xy 227.108511 -232.499354) (xy 227.100391 -232.55453)
			(xy 227.084323 -232.607937) (xy 227.060651 -232.658434) (xy 227.029878 -232.704947) (xy 226.992661 -232.746484)
			(xy 226.949793 -232.782159) (xy 226.902187 -232.811213) (xy 226.850858 -232.833025) (xy 226.796901 -232.847131)
			(xy 226.741464 -232.853231) (xy 226.68573 -232.851194) (xy 226.630887 -232.841064) (xy 226.578103 -232.823057)
			(xy 226.528503 -232.797556) (xy 226.483145 -232.765105) (xy 226.442996 -232.726396) (xy 226.40891 -232.682253)
			(xy 226.381614 -232.633618) (xy 226.361691 -232.581527) (xy 226.349565 -232.52709) (xy 226.345494 -232.471468)
			(xy 226.09302 -232.471468) (xy 226.09302 -232.471722) (xy 226.09257 -232.498017) (xy 226.085322 -232.550106)
			(xy 226.070994 -232.600707) (xy 226.049857 -232.648863) (xy 226.02231 -232.693662) (xy 225.988877 -232.734258)
			(xy 225.96983 -232.752392) (xy 225.962434 -232.759919) (xy 225.953905 -232.779195) (xy 225.95332 -232.78973)
			(xy 225.95332 -232.864406) (xy 225.953827 -232.874958) (xy 225.962377 -232.894254) (xy 225.96983 -232.901744)
			(xy 225.988903 -232.919856) (xy 226.02236 -232.96044) (xy 226.049919 -233.005239) (xy 226.071056 -233.053403)
			(xy 226.085369 -233.104015) (xy 226.092586 -233.156115) (xy 226.09302 -233.182414) (xy 226.09302 -233.182668)
			(xy 227.342444 -233.182668) (xy 227.346515 -233.127046) (xy 227.358641 -233.072609) (xy 227.378564 -233.020518)
			(xy 227.40586 -232.971883) (xy 227.439946 -232.92774) (xy 227.480095 -232.889031) (xy 227.525453 -232.85658)
			(xy 227.575053 -232.831079) (xy 227.627837 -232.813072) (xy 227.68268 -232.802942) (xy 227.738414 -232.800905)
			(xy 227.793851 -232.807005) (xy 227.847808 -232.821111) (xy 227.899137 -232.842923) (xy 227.946743 -232.871977)
			(xy 227.989611 -232.907652) (xy 228.026828 -232.949189) (xy 228.057601 -232.995702) (xy 228.081273 -233.046199)
			(xy 228.097341 -233.099606) (xy 228.105461 -233.154782) (xy 228.10597 -233.182668) (xy 228.105461 -233.210554)
			(xy 228.097341 -233.26573) (xy 228.081273 -233.319137) (xy 228.057601 -233.369634) (xy 228.026828 -233.416147)
			(xy 227.989611 -233.457684) (xy 227.946743 -233.493359) (xy 227.899137 -233.522413) (xy 227.847808 -233.544225)
			(xy 227.793851 -233.558331) (xy 227.738414 -233.564431) (xy 227.68268 -233.562394) (xy 227.627837 -233.552264)
			(xy 227.575053 -233.534257) (xy 227.525453 -233.508756) (xy 227.480095 -233.476305) (xy 227.439946 -233.437596)
			(xy 227.40586 -233.393453) (xy 227.378564 -233.344818) (xy 227.358641 -233.292727) (xy 227.346515 -233.23829)
			(xy 227.342444 -233.182668) (xy 226.09302 -233.182668) (xy 226.092534 -233.209919) (xy 226.084778 -233.263867)
			(xy 226.069423 -233.316162) (xy 226.046781 -233.365739) (xy 226.017315 -233.411589) (xy 225.981624 -233.45278)
			(xy 225.940433 -233.488471) (xy 225.894583 -233.517937) (xy 225.845006 -233.540579) (xy 225.792711 -233.555934)
			(xy 225.738763 -233.56369) (xy 225.684261 -233.56369) (xy 225.630313 -233.555934) (xy 225.578018 -233.540579)
			(xy 225.528441 -233.517937) (xy 225.482591 -233.488471) (xy 225.4414 -233.45278) (xy 225.405709 -233.411589)
			(xy 225.376243 -233.365739) (xy 225.353601 -233.316162) (xy 225.338246 -233.263867) (xy 225.33049 -233.209919)
			(xy 225.330004 -233.182668) (xy 225.07702 -233.182668) (xy 225.076511 -233.210554) (xy 225.068391 -233.26573)
			(xy 225.052323 -233.319137) (xy 225.028651 -233.369634) (xy 224.997878 -233.416147) (xy 224.960661 -233.457684)
			(xy 224.917793 -233.493359) (xy 224.870187 -233.522413) (xy 224.818858 -233.544225) (xy 224.764901 -233.558331)
			(xy 224.709464 -233.564431) (xy 224.65373 -233.562394) (xy 224.598887 -233.552264) (xy 224.546103 -233.534257)
			(xy 224.496503 -233.508756) (xy 224.451145 -233.476305) (xy 224.410996 -233.437596) (xy 224.37691 -233.393453)
			(xy 224.349614 -233.344818) (xy 224.329691 -233.292727) (xy 224.317565 -233.23829) (xy 224.313494 -233.182668)
			(xy 224.06102 -233.182668) (xy 224.060534 -233.209919) (xy 224.052778 -233.263867) (xy 224.037423 -233.316162)
			(xy 224.014781 -233.365739) (xy 223.985315 -233.411589) (xy 223.949624 -233.45278) (xy 223.908433 -233.488471)
			(xy 223.862583 -233.517937) (xy 223.813006 -233.540579) (xy 223.760711 -233.555934) (xy 223.706763 -233.56369)
			(xy 223.652261 -233.56369) (xy 223.598313 -233.555934) (xy 223.546018 -233.540579) (xy 223.496441 -233.517937)
			(xy 223.450591 -233.488471) (xy 223.4094 -233.45278) (xy 223.373709 -233.411589) (xy 223.344243 -233.365739)
			(xy 223.321601 -233.316162) (xy 223.306246 -233.263867) (xy 223.29849 -233.209919) (xy 223.298004 -233.182668)
			(xy 223.04502 -233.182668) (xy 223.044511 -233.210554) (xy 223.036391 -233.26573) (xy 223.020323 -233.319137)
			(xy 222.996651 -233.369634) (xy 222.965878 -233.416147) (xy 222.928661 -233.457684) (xy 222.885793 -233.493359)
			(xy 222.838187 -233.522413) (xy 222.786858 -233.544225) (xy 222.732901 -233.558331) (xy 222.677464 -233.564431)
			(xy 222.62173 -233.562394) (xy 222.566887 -233.552264) (xy 222.514103 -233.534257) (xy 222.464503 -233.508756)
			(xy 222.419145 -233.476305) (xy 222.378996 -233.437596) (xy 222.34491 -233.393453) (xy 222.317614 -233.344818)
			(xy 222.297691 -233.292727) (xy 222.285565 -233.23829) (xy 222.281494 -233.182668) (xy 216.179845 -233.182668)
			(xy 216.179422 -233.206363) (xy 216.171666 -233.260311) (xy 216.156311 -233.312606) (xy 216.133669 -233.362183)
			(xy 216.104203 -233.408033) (xy 216.068512 -233.449224) (xy 216.027321 -233.484915) (xy 215.981471 -233.514381)
			(xy 215.931894 -233.537023) (xy 215.879599 -233.552378) (xy 215.825651 -233.560134) (xy 215.771149 -233.560134)
			(xy 215.717201 -233.552378) (xy 215.664906 -233.537023) (xy 215.615329 -233.514381) (xy 215.569479 -233.484915)
			(xy 215.528288 -233.449224) (xy 215.492597 -233.408033) (xy 215.463131 -233.362183) (xy 215.440489 -233.312606)
			(xy 215.425134 -233.260311) (xy 215.417378 -233.206363) (xy 215.416892 -233.179112) (xy 214.329316 -233.179112)
			(xy 214.283222 -233.19265) (xy 214.229278 -233.20041) (xy 214.174779 -233.200414) (xy 214.120834 -233.192662)
			(xy 214.068541 -233.177312) (xy 214.018965 -233.154677) (xy 213.973114 -233.125217) (xy 213.931923 -233.089531)
			(xy 213.896229 -233.048347) (xy 213.86676 -233.002503) (xy 213.844115 -232.952931) (xy 213.828754 -232.900641)
			(xy 213.820992 -232.846698) (xy 213.820502 -232.819448) (xy 213.821255 -232.785364) (xy 213.833397 -232.718286)
			(xy 213.844632 -232.686098) (xy 213.84514 -232.685082) (xy 213.849458 -232.672636) (xy 213.847426 -232.659936)
			(xy 213.844632 -232.649014) (xy 213.843112 -232.645405) (xy 213.839164 -232.638642) (xy 213.836758 -232.635552)
			(xy 213.781894 -232.567226) (xy 213.77275 -232.558336) (xy 213.76767 -232.554526) (xy 213.761574 -232.55224)
			(xy 213.755527 -232.550114) (xy 213.742807 -232.548566) (xy 213.736428 -232.549192) (xy 213.735412 -232.549192)
			(xy 213.722775 -232.550824) (xy 213.697353 -232.552601) (xy 213.684612 -232.552748) (xy 213.674706 -232.552748)
			(xy 213.665816 -232.556304) (xy 213.662182 -232.557856) (xy 213.655419 -232.561939) (xy 213.652354 -232.564432)
			(xy 213.650322 -232.56621) (xy 213.599014 -232.614216) (xy 213.59569 -232.617564) (xy 213.590197 -232.625234)
			(xy 213.588092 -232.629456) (xy 213.584028 -232.637838) (xy 213.58352 -232.647744) (xy 213.581127 -232.676394)
			(xy 213.568836 -232.732556) (xy 213.54826 -232.786238) (xy 213.519864 -232.836226) (xy 213.48429 -232.881389)
			(xy 213.442345 -232.920705) (xy 213.394977 -232.953284) (xy 213.343258 -232.97839) (xy 213.288358 -232.995453)
			(xy 213.231519 -233.004087) (xy 213.202774 -233.004614) (xy 213.174491 -233.004087) (xy 213.118545 -232.995743)
			(xy 213.064445 -232.979228) (xy 213.03869 -232.96753) (xy 213.0298 -232.963466) (xy 213.02091 -232.962704)
			(xy 213.016021 -232.962459) (xy 213.006301 -232.963605) (xy 213.001606 -232.96499) (xy 212.935312 -232.986072)
			(xy 212.930836 -232.987577) (xy 212.922524 -232.992056) (xy 212.918802 -232.994962) (xy 212.91169 -233.00055)
			(xy 212.906864 -233.009186) (xy 212.8922 -233.033942) (xy 212.856613 -233.079153) (xy 212.814644 -233.11851)
			(xy 212.767243 -233.151122) (xy 212.715483 -233.17625) (xy 212.660539 -233.193325) (xy 212.603654 -233.201958)
			(xy 212.574886 -233.20248) (xy 212.547631 -233.202058) (xy 212.493678 -233.194298) (xy 212.441377 -233.178939)
			(xy 212.391795 -233.156293) (xy 212.345941 -233.126821) (xy 212.304747 -233.091123) (xy 212.269054 -233.049926)
			(xy 212.239587 -233.004068) (xy 212.216946 -232.954483) (xy 212.201593 -232.902181) (xy 212.193839 -232.848227)
			(xy 212.193378 -232.820972) (xy 211.468773 -232.820972) (xy 211.469516 -232.826182) (xy 211.469986 -232.85323)
			(xy 211.4695 -232.880481) (xy 211.461744 -232.934429) (xy 211.446389 -232.986724) (xy 211.423747 -233.036301)
			(xy 211.394281 -233.082151) (xy 211.35859 -233.123342) (xy 211.317399 -233.159033) (xy 211.271549 -233.188499)
			(xy 211.221972 -233.211141) (xy 211.169677 -233.226496) (xy 211.115729 -233.234252) (xy 211.061227 -233.234252)
			(xy 211.007279 -233.226496) (xy 210.954984 -233.211141) (xy 210.905407 -233.188499) (xy 210.859557 -233.159033)
			(xy 210.818366 -233.123342) (xy 210.782675 -233.082151) (xy 210.753209 -233.036301) (xy 210.730567 -232.986724)
			(xy 210.715212 -232.934429) (xy 210.707456 -232.880481) (xy 210.70697 -232.85323) (xy 210.707364 -232.828744)
			(xy 210.71363 -232.780175) (xy 210.726062 -232.732808) (xy 210.73491 -232.709974) (xy 210.738974 -232.700068)
			(xy 210.738466 -232.689146) (xy 210.738146 -232.684018) (xy 210.735708 -232.674038) (xy 210.73364 -232.669334)
			(xy 210.701382 -232.601262) (xy 210.699007 -232.596521) (xy 210.692599 -232.588073) (xy 210.688682 -232.584498)
			(xy 210.680554 -232.57764) (xy 210.670394 -232.574592) (xy 210.644649 -232.566287) (xy 210.595636 -232.543394)
			(xy 210.550348 -232.513807) (xy 210.509694 -232.478119) (xy 210.474488 -232.437046) (xy 210.445438 -232.391413)
			(xy 210.423124 -232.342133) (xy 210.407995 -232.290196) (xy 210.400355 -232.236642) (xy 210.399884 -232.209594)
			(xy 210.051037 -232.209594) (xy 210.050854 -232.210762) (xy 210.032805 -232.267105) (xy 210.006274 -232.319987)
			(xy 209.971899 -232.368139) (xy 209.930503 -232.410409) (xy 209.907124 -232.428542) (xy 209.89798 -232.4354)
			(xy 209.892646 -232.445052) (xy 209.890351 -232.449585) (xy 209.88741 -232.459311) (xy 209.886804 -232.464356)
			(xy 209.88655 -232.466388) (xy 209.88147 -232.555288) (xy 209.885534 -232.565194) (xy 209.887712 -232.570394)
			(xy 209.89399 -232.579753) (xy 209.89798 -232.583736) (xy 209.916425 -232.60181) (xy 209.948727 -232.642103)
			(xy 209.975306 -232.686381) (xy 209.995676 -232.733836) (xy 210.009466 -232.783603) (xy 210.016425 -232.834775)
			(xy 210.016852 -232.860596) (xy 210.016366 -232.887847) (xy 210.00861 -232.941795) (xy 209.993255 -232.99409)
			(xy 209.970613 -233.043667) (xy 209.941147 -233.089517) (xy 209.905456 -233.130708) (xy 209.864265 -233.166399)
			(xy 209.818415 -233.195865) (xy 209.768838 -233.218507) (xy 209.716543 -233.233862) (xy 209.662595 -233.241618)
			(xy 209.608093 -233.241618) (xy 209.554145 -233.233862) (xy 209.50185 -233.218507) (xy 209.452273 -233.195865)
			(xy 209.406423 -233.166399) (xy 209.365232 -233.130708) (xy 209.329541 -233.089517) (xy 209.300075 -233.043667)
			(xy 209.277433 -232.99409) (xy 209.262078 -232.941795) (xy 209.254322 -232.887847) (xy 209.253836 -232.860596)
			(xy 209.253836 -232.851706) (xy 209.254344 -232.837736) (xy 209.24774 -232.825798) (xy 209.244828 -232.820816)
			(xy 209.237135 -232.812217) (xy 209.2325 -232.80878) (xy 209.228944 -232.806494) (xy 209.140044 -232.754678)
			(xy 209.126074 -232.754932) (xy 209.119399 -232.755243) (xy 209.106534 -232.758833) (xy 209.100674 -232.762044)
			(xy 209.10042 -232.762044) (xy 209.078191 -232.774754) (xy 209.031072 -232.794802) (xy 208.981697 -232.808373)
			(xy 208.930951 -232.815222) (xy 208.905348 -232.815638) (xy 208.878095 -232.815118) (xy 208.824143 -232.807367)
			(xy 208.771844 -232.792017) (xy 208.722261 -232.769379) (xy 208.676406 -232.739914) (xy 208.635211 -232.704223)
			(xy 208.599515 -232.663033) (xy 208.570044 -232.617181) (xy 208.5474 -232.567601) (xy 208.532043 -232.515304)
			(xy 208.524285 -232.461353) (xy 208.11931 -232.461353) (xy 208.123535 -232.490064) (xy 208.124044 -232.51795)
			(xy 208.123535 -232.545836) (xy 208.115415 -232.601012) (xy 208.099347 -232.654419) (xy 208.075675 -232.704916)
			(xy 208.044902 -232.751429) (xy 208.007685 -232.792966) (xy 207.964817 -232.828641) (xy 207.917211 -232.857695)
			(xy 207.865882 -232.879507) (xy 207.811925 -232.893613) (xy 207.756488 -232.899713) (xy 207.700754 -232.897676)
			(xy 207.645911 -232.887546) (xy 207.593127 -232.869539) (xy 207.543527 -232.844038) (xy 207.498169 -232.811587)
			(xy 207.45802 -232.772878) (xy 207.423934 -232.728735) (xy 207.396638 -232.6801) (xy 207.376715 -232.628009)
			(xy 207.364589 -232.573572) (xy 207.360518 -232.51795) (xy 196.968618 -232.51795) (xy 196.968618 -236.511338)
			(xy 207.013808 -236.511338) (xy 207.017879 -236.455716) (xy 207.030005 -236.401279) (xy 207.049928 -236.349188)
			(xy 207.077224 -236.300553) (xy 207.11131 -236.25641) (xy 207.151459 -236.217701) (xy 207.196817 -236.18525)
			(xy 207.246417 -236.159749) (xy 207.299201 -236.141742) (xy 207.354044 -236.131612) (xy 207.409778 -236.129575)
			(xy 207.465215 -236.135675) (xy 207.519172 -236.149781) (xy 207.570501 -236.171593) (xy 207.618107 -236.200647)
			(xy 207.660975 -236.236322) (xy 207.698192 -236.277859) (xy 207.728965 -236.324372) (xy 207.752637 -236.374869)
			(xy 207.768705 -236.428276) (xy 207.776825 -236.483452) (xy 207.777334 -236.511338) (xy 207.776825 -236.539224)
			(xy 207.768705 -236.5944) (xy 207.752637 -236.647807) (xy 207.728965 -236.698304) (xy 207.698192 -236.744817)
			(xy 207.660975 -236.786354) (xy 207.618107 -236.822029) (xy 207.570501 -236.851083) (xy 207.519172 -236.872895)
			(xy 207.465215 -236.887001) (xy 207.409778 -236.893101) (xy 207.354044 -236.891064) (xy 207.299201 -236.880934)
			(xy 207.246417 -236.862927) (xy 207.196817 -236.837426) (xy 207.151459 -236.804975) (xy 207.11131 -236.766266)
			(xy 207.077224 -236.722123) (xy 207.049928 -236.673488) (xy 207.030005 -236.621397) (xy 207.017879 -236.56696)
			(xy 207.013808 -236.511338) (xy 196.968618 -236.511338) (xy 196.968618 -244.2464) (xy 219.538802 -244.2464)
			(xy 219.542873 -244.190778) (xy 219.554999 -244.136341) (xy 219.574922 -244.08425) (xy 219.602218 -244.035615)
			(xy 219.636304 -243.991472) (xy 219.676453 -243.952763) (xy 219.721811 -243.920312) (xy 219.771411 -243.894811)
			(xy 219.824195 -243.876804) (xy 219.879038 -243.866674) (xy 219.934772 -243.864637) (xy 219.990209 -243.870737)
			(xy 220.044166 -243.884843) (xy 220.095495 -243.906655) (xy 220.143101 -243.935709) (xy 220.185969 -243.971384)
			(xy 220.223186 -244.012921) (xy 220.253959 -244.059434) (xy 220.277631 -244.109931) (xy 220.293699 -244.163338)
			(xy 220.301819 -244.218514) (xy 220.302328 -244.2464) (xy 220.301819 -244.274286) (xy 220.293699 -244.329462)
			(xy 220.277631 -244.382869) (xy 220.253959 -244.433366) (xy 220.223186 -244.479879) (xy 220.218368 -244.485256)
			(xy 229.923237 -244.485256) (xy 229.923237 -244.430744) (xy 229.930995 -244.376787) (xy 229.946354 -244.324483)
			(xy 229.969001 -244.274898) (xy 229.998474 -244.229041) (xy 230.034174 -244.187845) (xy 230.075373 -244.15215)
			(xy 230.121233 -244.122682) (xy 230.170821 -244.10004) (xy 230.223126 -244.084687) (xy 230.277084 -244.076934)
			(xy 230.30434 -244.076474) (xy 230.33003 -244.076878) (xy 230.380945 -244.083779) (xy 230.430473 -244.09745)
			(xy 230.477718 -244.117644) (xy 230.521826 -244.143997) (xy 230.561999 -244.17603) (xy 230.597509 -244.213164)
			(xy 230.61295 -244.2337) (xy 230.621458 -244.244635) (xy 230.643186 -244.26181) (xy 230.668729 -244.272519)
			(xy 230.696209 -244.275975) (xy 230.723608 -244.271923) (xy 230.748912 -244.260663) (xy 230.770262 -244.24302)
			(xy 230.778558 -244.231922) (xy 230.793933 -244.210608) (xy 230.829565 -244.171979) (xy 230.870159 -244.138603)
			(xy 230.914949 -244.111112) (xy 230.963086 -244.090025) (xy 231.013661 -244.075741) (xy 231.065717 -244.068531)
			(xy 231.091994 -244.068092) (xy 231.119247 -244.068555) (xy 231.173199 -244.076311) (xy 231.225497 -244.091667)
			(xy 231.275078 -244.114309) (xy 231.320932 -244.143777) (xy 231.362125 -244.17947) (xy 231.39782 -244.220663)
			(xy 231.427288 -244.266517) (xy 231.449931 -244.316097) (xy 231.465288 -244.368395) (xy 231.473045 -244.422347)
			(xy 231.473045 -244.476853) (xy 231.465288 -244.530805) (xy 231.464893 -244.53215) (xy 237.172752 -244.53215)
			(xy 237.176823 -244.476528) (xy 237.188949 -244.422091) (xy 237.208872 -244.37) (xy 237.236168 -244.321365)
			(xy 237.270254 -244.277222) (xy 237.310403 -244.238513) (xy 237.355761 -244.206062) (xy 237.405361 -244.180561)
			(xy 237.458145 -244.162554) (xy 237.512988 -244.152424) (xy 237.568722 -244.150387) (xy 237.624159 -244.156487)
			(xy 237.678116 -244.170593) (xy 237.729445 -244.192405) (xy 237.777051 -244.221459) (xy 237.819919 -244.257134)
			(xy 237.857136 -244.298671) (xy 237.887909 -244.345184) (xy 237.911581 -244.395681) (xy 237.927649 -244.449088)
			(xy 237.935769 -244.504264) (xy 237.936278 -244.53215) (xy 237.935769 -244.560036) (xy 237.927649 -244.615212)
			(xy 237.911581 -244.668619) (xy 237.887909 -244.719116) (xy 237.857136 -244.765629) (xy 237.819919 -244.807166)
			(xy 237.777051 -244.842841) (xy 237.729445 -244.871895) (xy 237.678116 -244.893707) (xy 237.624159 -244.907813)
			(xy 237.568722 -244.913913) (xy 237.512988 -244.911876) (xy 237.458145 -244.901746) (xy 237.405361 -244.883739)
			(xy 237.355761 -244.858238) (xy 237.310403 -244.825787) (xy 237.270254 -244.787078) (xy 237.236168 -244.742935)
			(xy 237.208872 -244.6943) (xy 237.188949 -244.642209) (xy 237.176823 -244.587772) (xy 237.172752 -244.53215)
			(xy 231.464893 -244.53215) (xy 231.449931 -244.583103) (xy 231.427288 -244.632683) (xy 231.39782 -244.678537)
			(xy 231.362125 -244.71973) (xy 231.320932 -244.755423) (xy 231.275078 -244.784891) (xy 231.225497 -244.807533)
			(xy 231.173199 -244.822889) (xy 231.119247 -244.830645) (xy 231.091994 -244.831108) (xy 231.066304 -244.830685)
			(xy 231.01539 -244.823789) (xy 230.965862 -244.810121) (xy 230.918617 -244.78993) (xy 230.874509 -244.763581)
			(xy 230.834336 -244.73155) (xy 230.798826 -244.694417) (xy 230.783384 -244.673882) (xy 230.774835 -244.662982)
			(xy 230.753115 -244.645811) (xy 230.727582 -244.635102) (xy 230.700111 -244.631643) (xy 230.67272 -244.635687)
			(xy 230.647421 -244.646937) (xy 230.626072 -244.664568) (xy 230.617776 -244.67566) (xy 230.602375 -244.696954)
			(xy 230.566748 -244.735585) (xy 230.526158 -244.768963) (xy 230.481373 -244.796457) (xy 230.43324 -244.817547)
			(xy 230.382669 -244.831834) (xy 230.330615 -244.839049) (xy 230.30434 -244.83949) (xy 230.277084 -244.839066)
			(xy 230.223126 -244.831313) (xy 230.170821 -244.81596) (xy 230.121233 -244.793318) (xy 230.075373 -244.76385)
			(xy 230.034174 -244.728155) (xy 229.998474 -244.686959) (xy 229.969001 -244.641102) (xy 229.946354 -244.591517)
			(xy 229.930995 -244.539213) (xy 229.923237 -244.485256) (xy 220.218368 -244.485256) (xy 220.185969 -244.521416)
			(xy 220.143101 -244.557091) (xy 220.095495 -244.586145) (xy 220.044166 -244.607957) (xy 219.990209 -244.622063)
			(xy 219.934772 -244.628163) (xy 219.879038 -244.626126) (xy 219.824195 -244.615996) (xy 219.771411 -244.597989)
			(xy 219.721811 -244.572488) (xy 219.676453 -244.540037) (xy 219.636304 -244.501328) (xy 219.602218 -244.457185)
			(xy 219.574922 -244.40855) (xy 219.554999 -244.356459) (xy 219.542873 -244.302022) (xy 219.538802 -244.2464)
			(xy 196.968618 -244.2464) (xy 196.968618 -245.041674) (xy 210.037424 -245.041674) (xy 210.041495 -244.986052)
			(xy 210.053621 -244.931615) (xy 210.073544 -244.879524) (xy 210.10084 -244.830889) (xy 210.134926 -244.786746)
			(xy 210.175075 -244.748037) (xy 210.220433 -244.715586) (xy 210.270033 -244.690085) (xy 210.322817 -244.672078)
			(xy 210.37766 -244.661948) (xy 210.433394 -244.659911) (xy 210.488831 -244.666011) (xy 210.542788 -244.680117)
			(xy 210.594117 -244.701929) (xy 210.641723 -244.730983) (xy 210.684591 -244.766658) (xy 210.721808 -244.808195)
			(xy 210.752581 -244.854708) (xy 210.776253 -244.905205) (xy 210.792321 -244.958612) (xy 210.800441 -245.013788)
			(xy 210.800663 -245.025926) (xy 211.053424 -245.025926) (xy 211.057495 -244.970304) (xy 211.069621 -244.915867)
			(xy 211.089544 -244.863776) (xy 211.11684 -244.815141) (xy 211.150926 -244.770998) (xy 211.191075 -244.732289)
			(xy 211.236433 -244.699838) (xy 211.286033 -244.674337) (xy 211.338817 -244.65633) (xy 211.39366 -244.6462)
			(xy 211.449394 -244.644163) (xy 211.504831 -244.650263) (xy 211.558788 -244.664369) (xy 211.610117 -244.686181)
			(xy 211.657723 -244.715235) (xy 211.700591 -244.75091) (xy 211.737808 -244.792447) (xy 211.768581 -244.83896)
			(xy 211.792253 -244.889457) (xy 211.808321 -244.942864) (xy 211.816441 -244.99804) (xy 211.81695 -245.025926)
			(xy 211.816727 -245.038118) (xy 232.954574 -245.038118) (xy 232.958645 -244.982496) (xy 232.970771 -244.928059)
			(xy 232.990694 -244.875968) (xy 233.01799 -244.827333) (xy 233.052076 -244.78319) (xy 233.092225 -244.744481)
			(xy 233.137583 -244.71203) (xy 233.187183 -244.686529) (xy 233.239967 -244.668522) (xy 233.29481 -244.658392)
			(xy 233.350544 -244.656355) (xy 233.405981 -244.662455) (xy 233.459938 -244.676561) (xy 233.511267 -244.698373)
			(xy 233.558873 -244.727427) (xy 233.601741 -244.763102) (xy 233.638958 -244.804639) (xy 233.669731 -244.851152)
			(xy 233.693403 -244.901649) (xy 233.709471 -244.955056) (xy 233.717591 -245.010232) (xy 233.7181 -245.038118)
			(xy 233.717591 -245.066004) (xy 233.709471 -245.12118) (xy 233.693403 -245.174587) (xy 233.669731 -245.225084)
			(xy 233.638958 -245.271597) (xy 233.606234 -245.30812) (xy 234.133388 -245.30812) (xy 234.137459 -245.252498)
			(xy 234.149585 -245.198061) (xy 234.169508 -245.14597) (xy 234.196804 -245.097335) (xy 234.23089 -245.053192)
			(xy 234.271039 -245.014483) (xy 234.316397 -244.982032) (xy 234.365997 -244.956531) (xy 234.418781 -244.938524)
			(xy 234.473624 -244.928394) (xy 234.529358 -244.926357) (xy 234.584795 -244.932457) (xy 234.638752 -244.946563)
			(xy 234.690081 -244.968375) (xy 234.737687 -244.997429) (xy 234.780555 -245.033104) (xy 234.817772 -245.074641)
			(xy 234.848545 -245.121154) (xy 234.872217 -245.171651) (xy 234.888285 -245.225058) (xy 234.896405 -245.280234)
			(xy 234.896914 -245.30812) (xy 234.896405 -245.336006) (xy 234.888285 -245.391182) (xy 234.872217 -245.444589)
			(xy 234.861876 -245.466648) (xy 235.025216 -245.466648) (xy 235.025216 -245.412152) (xy 235.032971 -245.358211)
			(xy 235.048324 -245.305923) (xy 235.070962 -245.256352) (xy 235.100424 -245.210507) (xy 235.13611 -245.169321)
			(xy 235.177294 -245.133633) (xy 235.223138 -245.10417) (xy 235.272708 -245.08153) (xy 235.324996 -245.066175)
			(xy 235.378936 -245.058417) (xy 235.406184 -245.05793) (xy 235.433792 -245.05844) (xy 235.488431 -245.066403)
			(xy 235.54135 -245.082165) (xy 235.591442 -245.105396) (xy 235.637658 -245.135611) (xy 235.679032 -245.172176)
			(xy 235.714699 -245.214327) (xy 235.743912 -245.261183) (xy 235.755434 -245.286276) (xy 235.761218 -245.29837)
			(xy 235.778028 -245.319242) (xy 235.799682 -245.335032) (xy 235.824695 -245.344654) (xy 235.851348 -245.34745)
			(xy 235.877813 -245.343227) (xy 235.902272 -245.332274) (xy 235.912914 -245.324122) (xy 235.933425 -245.307911)
			(xy 235.978037 -245.280653) (xy 236.025957 -245.259748) (xy 236.076284 -245.245591) (xy 236.128074 -245.238446)
			(xy 236.154214 -245.238016) (xy 236.181466 -245.238455) (xy 236.235416 -245.246213) (xy 236.287712 -245.261571)
			(xy 236.337291 -245.284214) (xy 236.383142 -245.313683) (xy 236.424334 -245.349376) (xy 236.460026 -245.390569)
			(xy 236.489493 -245.436421) (xy 236.512134 -245.486001) (xy 236.52749 -245.538298) (xy 236.535246 -245.592248)
			(xy 236.535246 -245.646752) (xy 236.52749 -245.700702) (xy 236.512134 -245.752999) (xy 236.489493 -245.802579)
			(xy 236.460026 -245.848431) (xy 236.424334 -245.889624) (xy 236.383142 -245.925317) (xy 236.337291 -245.954786)
			(xy 236.287712 -245.977429) (xy 236.235416 -245.992787) (xy 236.181466 -246.000545) (xy 236.154214 -246.001032)
			(xy 236.126605 -246.000546) (xy 236.071964 -245.992582) (xy 236.019043 -245.976818) (xy 235.96895 -245.953584)
			(xy 235.922734 -245.923366) (xy 235.88136 -245.886797) (xy 235.845695 -245.844641) (xy 235.816485 -245.797782)
			(xy 235.804964 -245.772686) (xy 235.799192 -245.760587) (xy 235.782376 -245.73972) (xy 235.760719 -245.723934)
			(xy 235.735706 -245.714314) (xy 235.709053 -245.711519) (xy 235.682588 -245.715741) (xy 235.658128 -245.72669)
			(xy 235.647484 -245.73484) (xy 235.626969 -245.751046) (xy 235.582358 -245.778306) (xy 235.53444 -245.799212)
			(xy 235.484114 -245.81337) (xy 235.432324 -245.820516) (xy 235.406184 -245.820946) (xy 235.378936 -245.820383)
			(xy 235.324996 -245.812625) (xy 235.272708 -245.79727) (xy 235.223138 -245.77463) (xy 235.177294 -245.745167)
			(xy 235.13611 -245.709479) (xy 235.100424 -245.668293) (xy 235.070962 -245.622448) (xy 235.048324 -245.572877)
			(xy 235.032971 -245.520589) (xy 235.025216 -245.466648) (xy 234.861876 -245.466648) (xy 234.848545 -245.495086)
			(xy 234.817772 -245.541599) (xy 234.780555 -245.583136) (xy 234.737687 -245.618811) (xy 234.690081 -245.647865)
			(xy 234.638752 -245.669677) (xy 234.584795 -245.683783) (xy 234.529358 -245.689883) (xy 234.473624 -245.687846)
			(xy 234.418781 -245.677716) (xy 234.365997 -245.659709) (xy 234.316397 -245.634208) (xy 234.271039 -245.601757)
			(xy 234.23089 -245.563048) (xy 234.196804 -245.518905) (xy 234.169508 -245.47027) (xy 234.149585 -245.418179)
			(xy 234.137459 -245.363742) (xy 234.133388 -245.30812) (xy 233.606234 -245.30812) (xy 233.601741 -245.313134)
			(xy 233.558873 -245.348809) (xy 233.511267 -245.377863) (xy 233.459938 -245.399675) (xy 233.405981 -245.413781)
			(xy 233.350544 -245.419881) (xy 233.29481 -245.417844) (xy 233.239967 -245.407714) (xy 233.187183 -245.389707)
			(xy 233.137583 -245.364206) (xy 233.092225 -245.331755) (xy 233.052076 -245.293046) (xy 233.01799 -245.248903)
			(xy 232.990694 -245.200268) (xy 232.970771 -245.148177) (xy 232.958645 -245.09374) (xy 232.954574 -245.038118)
			(xy 211.816727 -245.038118) (xy 211.816441 -245.053812) (xy 211.808321 -245.108988) (xy 211.792253 -245.162395)
			(xy 211.768581 -245.212892) (xy 211.737808 -245.259405) (xy 211.700591 -245.300942) (xy 211.657723 -245.336617)
			(xy 211.610117 -245.365671) (xy 211.558788 -245.387483) (xy 211.504831 -245.401589) (xy 211.449394 -245.407689)
			(xy 211.39366 -245.405652) (xy 211.338817 -245.395522) (xy 211.286033 -245.377515) (xy 211.236433 -245.352014)
			(xy 211.191075 -245.319563) (xy 211.150926 -245.280854) (xy 211.11684 -245.236711) (xy 211.089544 -245.188076)
			(xy 211.069621 -245.135985) (xy 211.057495 -245.081548) (xy 211.053424 -245.025926) (xy 210.800663 -245.025926)
			(xy 210.80095 -245.041674) (xy 210.800441 -245.06956) (xy 210.792321 -245.124736) (xy 210.776253 -245.178143)
			(xy 210.752581 -245.22864) (xy 210.721808 -245.275153) (xy 210.684591 -245.31669) (xy 210.641723 -245.352365)
			(xy 210.594117 -245.381419) (xy 210.542788 -245.403231) (xy 210.488831 -245.417337) (xy 210.433394 -245.423437)
			(xy 210.37766 -245.4214) (xy 210.322817 -245.41127) (xy 210.270033 -245.393263) (xy 210.220433 -245.367762)
			(xy 210.175075 -245.335311) (xy 210.134926 -245.296602) (xy 210.10084 -245.252459) (xy 210.073544 -245.203824)
			(xy 210.053621 -245.151733) (xy 210.041495 -245.097296) (xy 210.037424 -245.041674) (xy 196.968618 -245.041674)
			(xy 196.968618 -246.306952) (xy 231.522248 -246.306952) (xy 231.522248 -246.252448) (xy 231.530004 -246.198499)
			(xy 231.545359 -246.146202) (xy 231.568 -246.096623) (xy 231.597465 -246.05077) (xy 231.633157 -246.009578)
			(xy 231.674346 -245.973883) (xy 231.720197 -245.944414) (xy 231.769774 -245.921769) (xy 231.822069 -245.90641)
			(xy 231.876018 -245.89865) (xy 231.90327 -245.898162) (xy 231.929659 -245.898584) (xy 231.981931 -245.905867)
			(xy 232.032701 -245.920285) (xy 232.080999 -245.941562) (xy 232.125904 -245.969292) (xy 232.166558 -246.002947)
			(xy 232.184702 -246.022114) (xy 232.191052 -246.029226) (xy 232.19918 -246.03329) (xy 232.21061 -246.037354)
			(xy 232.216198 -246.03837) (xy 232.283 -246.04599) (xy 232.287658 -246.046414) (xy 232.296987 -246.045782)
			(xy 232.301542 -246.04472) (xy 232.309924 -246.042434) (xy 232.317544 -246.0371) (xy 232.341551 -246.021144)
			(xy 232.393367 -245.995888) (xy 232.448397 -245.978729) (xy 232.505384 -245.970058) (xy 232.534206 -245.969536)
			(xy 232.53446 -245.969536) (xy 232.563794 -245.970093) (xy 232.621774 -245.979057) (xy 232.677696 -245.996795)
			(xy 232.730241 -246.022889) (xy 232.778171 -246.056724) (xy 232.799636 -246.076724) (xy 232.807256 -246.08409)
			(xy 232.816908 -246.087646) (xy 232.821868 -246.089368) (xy 232.832232 -246.091037) (xy 232.837482 -246.090948)
			(xy 232.911396 -246.087138) (xy 232.916615 -246.08673) (xy 232.926729 -246.08404) (xy 232.931462 -246.081804)
			(xy 232.94086 -246.077232) (xy 232.947718 -246.069104) (xy 232.96595 -246.04829) (xy 233.007385 -246.011618)
			(xy 233.05368 -245.981314) (xy 233.103867 -245.958012) (xy 233.156892 -245.942202) (xy 233.211644 -245.934213)
			(xy 233.23931 -245.933722) (xy 233.266563 -245.934149) (xy 233.320514 -245.941907) (xy 233.372811 -245.957264)
			(xy 233.422391 -245.979908) (xy 233.468244 -246.009376) (xy 233.509436 -246.045071) (xy 233.54513 -246.086264)
			(xy 233.574597 -246.132117) (xy 233.597239 -246.181698) (xy 233.612595 -246.233996) (xy 233.620352 -246.287947)
			(xy 233.620352 -246.342453) (xy 233.612595 -246.396404) (xy 233.597239 -246.448702) (xy 233.574597 -246.498283)
			(xy 233.54513 -246.544136) (xy 233.509436 -246.585329) (xy 233.468244 -246.621024) (xy 233.422391 -246.650492)
			(xy 233.372811 -246.673136) (xy 233.320514 -246.688493) (xy 233.266563 -246.696251) (xy 233.23931 -246.696738)
			(xy 233.209975 -246.696207) (xy 233.151994 -246.687238) (xy 233.096071 -246.669494) (xy 233.043526 -246.643394)
			(xy 232.995598 -246.609553) (xy 232.974134 -246.58955) (xy 232.966514 -246.582184) (xy 232.956862 -246.578628)
			(xy 232.951904 -246.576897) (xy 232.941538 -246.575234) (xy 232.936288 -246.575326) (xy 232.862374 -246.579136)
			(xy 232.857154 -246.579529) (xy 232.847039 -246.582228) (xy 232.842308 -246.58447) (xy 232.83291 -246.589042)
			(xy 232.826052 -246.59717) (xy 232.80783 -246.617994) (xy 232.766394 -246.654666) (xy 232.720096 -246.684969)
			(xy 232.669908 -246.708269) (xy 232.616881 -246.724078) (xy 232.562127 -246.732063) (xy 232.53446 -246.732552)
			(xy 232.508072 -246.732106) (xy 232.455801 -246.724827) (xy 232.405032 -246.710414) (xy 232.356734 -246.689141)
			(xy 232.311828 -246.661415) (xy 232.271173 -246.627765) (xy 232.253028 -246.6086) (xy 232.246678 -246.601488)
			(xy 232.23855 -246.597424) (xy 232.22712 -246.59336) (xy 232.221532 -246.592344) (xy 232.15473 -246.584724)
			(xy 232.150073 -246.58428) (xy 232.140742 -246.584926) (xy 232.136188 -246.585994) (xy 232.127806 -246.58828)
			(xy 232.120186 -246.593614) (xy 232.096172 -246.609559) (xy 232.044358 -246.634817) (xy 231.989331 -246.651979)
			(xy 231.932345 -246.660654) (xy 231.903524 -246.661178) (xy 231.90327 -246.661178) (xy 231.876018 -246.66075)
			(xy 231.822069 -246.65299) (xy 231.769774 -246.637631) (xy 231.720197 -246.614986) (xy 231.674346 -246.585517)
			(xy 231.633157 -246.549822) (xy 231.597465 -246.50863) (xy 231.568 -246.462777) (xy 231.545359 -246.413198)
			(xy 231.530004 -246.360901) (xy 231.522248 -246.306952) (xy 196.968618 -246.306952) (xy 196.968618 -246.997982)
			(xy 236.805722 -246.997982) (xy 236.809793 -246.94236) (xy 236.821919 -246.887923) (xy 236.841842 -246.835832)
			(xy 236.869138 -246.787197) (xy 236.903224 -246.743054) (xy 236.943373 -246.704345) (xy 236.988731 -246.671894)
			(xy 237.038331 -246.646393) (xy 237.091115 -246.628386) (xy 237.145958 -246.618256) (xy 237.201692 -246.616219)
			(xy 237.257129 -246.622319) (xy 237.311086 -246.636425) (xy 237.362415 -246.658237) (xy 237.410021 -246.687291)
			(xy 237.452889 -246.722966) (xy 237.490106 -246.764503) (xy 237.520879 -246.811016) (xy 237.544551 -246.861513)
			(xy 237.560619 -246.91492) (xy 237.568739 -246.970096) (xy 237.569248 -246.997982) (xy 237.568739 -247.025868)
			(xy 237.560619 -247.081044) (xy 237.544551 -247.134451) (xy 237.520879 -247.184948) (xy 237.490106 -247.231461)
			(xy 237.452889 -247.272998) (xy 237.410021 -247.308673) (xy 237.362415 -247.337727) (xy 237.311086 -247.359539)
			(xy 237.257129 -247.373645) (xy 237.201692 -247.379745) (xy 237.145958 -247.377708) (xy 237.091115 -247.367578)
			(xy 237.038331 -247.349571) (xy 236.988731 -247.32407) (xy 236.943373 -247.291619) (xy 236.903224 -247.25291)
			(xy 236.869138 -247.208767) (xy 236.841842 -247.160132) (xy 236.821919 -247.108041) (xy 236.809793 -247.053604)
			(xy 236.805722 -246.997982) (xy 196.968618 -246.997982) (xy 196.968618 -248.35612) (xy 210.174838 -248.35612)
			(xy 210.178909 -248.300498) (xy 210.191035 -248.246061) (xy 210.210958 -248.19397) (xy 210.238254 -248.145335)
			(xy 210.27234 -248.101192) (xy 210.312489 -248.062483) (xy 210.357847 -248.030032) (xy 210.407447 -248.004531)
			(xy 210.460231 -247.986524) (xy 210.515074 -247.976394) (xy 210.570808 -247.974357) (xy 210.626245 -247.980457)
			(xy 210.680202 -247.994563) (xy 210.731531 -248.016375) (xy 210.779137 -248.045429) (xy 210.822005 -248.081104)
			(xy 210.859222 -248.122641) (xy 210.889995 -248.169154) (xy 210.913667 -248.219651) (xy 210.929735 -248.273058)
			(xy 210.937855 -248.328234) (xy 210.938364 -248.35612) (xy 210.937855 -248.384006) (xy 210.930402 -248.434652)
			(xy 211.056683 -248.434652) (xy 211.056683 -248.380148) (xy 211.06444 -248.326198) (xy 211.079797 -248.273902)
			(xy 211.10244 -248.224324) (xy 211.131908 -248.178473) (xy 211.167602 -248.137282) (xy 211.208795 -248.101591)
			(xy 211.254648 -248.072126) (xy 211.304228 -248.049487) (xy 211.356526 -248.034135) (xy 211.410476 -248.026381)
			(xy 211.437728 -248.02592) (xy 211.464523 -248.026356) (xy 211.517584 -248.033865) (xy 211.569073 -248.048719)
			(xy 211.617981 -248.070625) (xy 211.663346 -248.099153) (xy 211.704278 -248.133743) (xy 211.722462 -248.153428)
			(xy 211.733096 -248.164655) (xy 211.759619 -248.180534) (xy 211.789678 -248.187747) (xy 211.820519 -248.185634)
			(xy 211.849313 -248.174389) (xy 211.873423 -248.155041) (xy 211.882482 -248.142506) (xy 211.897731 -248.120542)
			(xy 211.933409 -248.080718) (xy 211.974296 -248.046263) (xy 212.019592 -248.017853) (xy 212.06841 -247.996042)
			(xy 212.119795 -247.981259) (xy 212.17274 -247.973793) (xy 212.199474 -247.973342) (xy 212.226732 -247.973703)
			(xy 212.280693 -247.981458) (xy 212.333 -247.996814) (xy 212.38259 -248.019458) (xy 212.428453 -248.048929)
			(xy 212.469654 -248.084628) (xy 212.505355 -248.125826) (xy 212.53483 -248.171687) (xy 212.557477 -248.221275)
			(xy 212.572836 -248.273582) (xy 212.580595 -248.327542) (xy 212.580595 -248.382058) (xy 212.572836 -248.436018)
			(xy 212.565942 -248.459498) (xy 219.575124 -248.459498) (xy 219.579195 -248.403876) (xy 219.591321 -248.349439)
			(xy 219.611244 -248.297348) (xy 219.63854 -248.248713) (xy 219.672626 -248.20457) (xy 219.712775 -248.165861)
			(xy 219.758133 -248.13341) (xy 219.807733 -248.107909) (xy 219.860517 -248.089902) (xy 219.91536 -248.079772)
			(xy 219.971094 -248.077735) (xy 220.026531 -248.083835) (xy 220.080488 -248.097941) (xy 220.131817 -248.119753)
			(xy 220.179423 -248.148807) (xy 220.222291 -248.184482) (xy 220.259508 -248.226019) (xy 220.290281 -248.272532)
			(xy 220.313953 -248.323029) (xy 220.330021 -248.376436) (xy 220.335367 -248.412762) (xy 220.443042 -248.412762)
			(xy 220.447113 -248.35714) (xy 220.459239 -248.302703) (xy 220.479162 -248.250612) (xy 220.506458 -248.201977)
			(xy 220.540544 -248.157834) (xy 220.580693 -248.119125) (xy 220.626051 -248.086674) (xy 220.675651 -248.061173)
			(xy 220.728435 -248.043166) (xy 220.783278 -248.033036) (xy 220.839012 -248.030999) (xy 220.894449 -248.037099)
			(xy 220.948406 -248.051205) (xy 220.999735 -248.073017) (xy 221.047341 -248.102071) (xy 221.090209 -248.137746)
			(xy 221.127426 -248.179283) (xy 221.158199 -248.225796) (xy 221.181871 -248.276293) (xy 221.197939 -248.3297)
			(xy 221.206059 -248.384876) (xy 221.20622 -248.393712) (xy 221.630746 -248.393712) (xy 221.634817 -248.33809)
			(xy 221.646943 -248.283653) (xy 221.666866 -248.231562) (xy 221.694162 -248.182927) (xy 221.728248 -248.138784)
			(xy 221.768397 -248.100075) (xy 221.813755 -248.067624) (xy 221.863355 -248.042123) (xy 221.916139 -248.024116)
			(xy 221.970982 -248.013986) (xy 222.026716 -248.011949) (xy 222.082153 -248.018049) (xy 222.13611 -248.032155)
			(xy 222.187439 -248.053967) (xy 222.235045 -248.083021) (xy 222.277913 -248.118696) (xy 222.31513 -248.160233)
			(xy 222.345903 -248.206746) (xy 222.369575 -248.257243) (xy 222.385643 -248.31065) (xy 222.393763 -248.365826)
			(xy 222.39424 -248.391934) (xy 240.834416 -248.391934) (xy 240.838487 -248.336312) (xy 240.850613 -248.281875)
			(xy 240.870536 -248.229784) (xy 240.897832 -248.181149) (xy 240.931918 -248.137006) (xy 240.972067 -248.098297)
			(xy 241.017425 -248.065846) (xy 241.067025 -248.040345) (xy 241.119809 -248.022338) (xy 241.174652 -248.012208)
			(xy 241.230386 -248.010171) (xy 241.285823 -248.016271) (xy 241.33978 -248.030377) (xy 241.391109 -248.052189)
			(xy 241.438715 -248.081243) (xy 241.481583 -248.116918) (xy 241.5188 -248.158455) (xy 241.549573 -248.204968)
			(xy 241.573245 -248.255465) (xy 241.589313 -248.308872) (xy 241.597433 -248.364048) (xy 241.597942 -248.391934)
			(xy 242.866416 -248.391934) (xy 242.870487 -248.336312) (xy 242.882613 -248.281875) (xy 242.902536 -248.229784)
			(xy 242.929832 -248.181149) (xy 242.963918 -248.137006) (xy 243.004067 -248.098297) (xy 243.049425 -248.065846)
			(xy 243.099025 -248.040345) (xy 243.151809 -248.022338) (xy 243.206652 -248.012208) (xy 243.262386 -248.010171)
			(xy 243.317823 -248.016271) (xy 243.37178 -248.030377) (xy 243.423109 -248.052189) (xy 243.470715 -248.081243)
			(xy 243.513583 -248.116918) (xy 243.5508 -248.158455) (xy 243.581573 -248.204968) (xy 243.605245 -248.255465)
			(xy 243.621313 -248.308872) (xy 243.629433 -248.364048) (xy 243.629942 -248.391934) (xy 243.629433 -248.41982)
			(xy 243.621313 -248.474996) (xy 243.605245 -248.528403) (xy 243.581573 -248.5789) (xy 243.5508 -248.625413)
			(xy 243.513583 -248.66695) (xy 243.470715 -248.702625) (xy 243.423109 -248.731679) (xy 243.37178 -248.753491)
			(xy 243.317823 -248.767597) (xy 243.262386 -248.773697) (xy 243.206652 -248.77166) (xy 243.151809 -248.76153)
			(xy 243.099025 -248.743523) (xy 243.049425 -248.718022) (xy 243.004067 -248.685571) (xy 242.963918 -248.646862)
			(xy 242.929832 -248.602719) (xy 242.902536 -248.554084) (xy 242.882613 -248.501993) (xy 242.870487 -248.447556)
			(xy 242.866416 -248.391934) (xy 241.597942 -248.391934) (xy 241.597433 -248.41982) (xy 241.589313 -248.474996)
			(xy 241.573245 -248.528403) (xy 241.549573 -248.5789) (xy 241.5188 -248.625413) (xy 241.481583 -248.66695)
			(xy 241.438715 -248.702625) (xy 241.391109 -248.731679) (xy 241.33978 -248.753491) (xy 241.285823 -248.767597)
			(xy 241.230386 -248.773697) (xy 241.174652 -248.77166) (xy 241.119809 -248.76153) (xy 241.067025 -248.743523)
			(xy 241.017425 -248.718022) (xy 240.972067 -248.685571) (xy 240.931918 -248.646862) (xy 240.897832 -248.602719)
			(xy 240.870536 -248.554084) (xy 240.850613 -248.501993) (xy 240.838487 -248.447556) (xy 240.834416 -248.391934)
			(xy 222.39424 -248.391934) (xy 222.394272 -248.393712) (xy 222.393763 -248.421598) (xy 222.385643 -248.476774)
			(xy 222.369575 -248.530181) (xy 222.345903 -248.580678) (xy 222.31513 -248.627191) (xy 222.277913 -248.668728)
			(xy 222.235045 -248.704403) (xy 222.187439 -248.733457) (xy 222.13611 -248.755269) (xy 222.082153 -248.769375)
			(xy 222.026716 -248.775475) (xy 221.970982 -248.773438) (xy 221.916139 -248.763308) (xy 221.863355 -248.745301)
			(xy 221.813755 -248.7198) (xy 221.768397 -248.687349) (xy 221.728248 -248.64864) (xy 221.694162 -248.604497)
			(xy 221.666866 -248.555862) (xy 221.646943 -248.503771) (xy 221.634817 -248.449334) (xy 221.630746 -248.393712)
			(xy 221.20622 -248.393712) (xy 221.206568 -248.412762) (xy 221.206059 -248.440648) (xy 221.197939 -248.495824)
			(xy 221.181871 -248.549231) (xy 221.158199 -248.599728) (xy 221.127426 -248.646241) (xy 221.090209 -248.687778)
			(xy 221.047341 -248.723453) (xy 220.999735 -248.752507) (xy 220.948406 -248.774319) (xy 220.894449 -248.788425)
			(xy 220.839012 -248.794525) (xy 220.783278 -248.792488) (xy 220.728435 -248.782358) (xy 220.675651 -248.764351)
			(xy 220.626051 -248.73885) (xy 220.580693 -248.706399) (xy 220.540544 -248.66769) (xy 220.506458 -248.623547)
			(xy 220.479162 -248.574912) (xy 220.459239 -248.522821) (xy 220.447113 -248.468384) (xy 220.443042 -248.412762)
			(xy 220.335367 -248.412762) (xy 220.338141 -248.431612) (xy 220.33865 -248.459498) (xy 220.338141 -248.487384)
			(xy 220.330021 -248.54256) (xy 220.313953 -248.595967) (xy 220.290281 -248.646464) (xy 220.259508 -248.692977)
			(xy 220.222291 -248.734514) (xy 220.179423 -248.770189) (xy 220.131817 -248.799243) (xy 220.080488 -248.821055)
			(xy 220.026531 -248.835161) (xy 219.971094 -248.841261) (xy 219.91536 -248.839224) (xy 219.860517 -248.829094)
			(xy 219.807733 -248.811087) (xy 219.758133 -248.785586) (xy 219.712775 -248.753135) (xy 219.672626 -248.714426)
			(xy 219.63854 -248.670283) (xy 219.611244 -248.621648) (xy 219.591321 -248.569557) (xy 219.579195 -248.51512)
			(xy 219.575124 -248.459498) (xy 212.565942 -248.459498) (xy 212.557477 -248.488325) (xy 212.53483 -248.537913)
			(xy 212.505355 -248.583774) (xy 212.469654 -248.624972) (xy 212.428453 -248.660671) (xy 212.38259 -248.690142)
			(xy 212.333 -248.712786) (xy 212.280693 -248.728142) (xy 212.226732 -248.735897) (xy 212.199474 -248.736358)
			(xy 212.172681 -248.735895) (xy 212.119622 -248.728387) (xy 212.068134 -248.713537) (xy 212.019226 -248.691636)
			(xy 211.97386 -248.663114) (xy 211.932926 -248.628532) (xy 211.91474 -248.60885) (xy 211.904101 -248.597629)
			(xy 211.877579 -248.581754) (xy 211.847522 -248.574542) (xy 211.816684 -248.576654) (xy 211.787891 -248.587897)
			(xy 211.763781 -248.60724) (xy 211.75472 -248.619772) (xy 211.739463 -248.64173) (xy 211.703787 -248.681555)
			(xy 211.662902 -248.716011) (xy 211.617607 -248.744423) (xy 211.56879 -248.766234) (xy 211.517406 -248.781018)
			(xy 211.464462 -248.788485) (xy 211.437728 -248.788936) (xy 211.410476 -248.788419) (xy 211.356526 -248.780665)
			(xy 211.304228 -248.765313) (xy 211.254648 -248.742674) (xy 211.208795 -248.713209) (xy 211.167602 -248.677518)
			(xy 211.131908 -248.636327) (xy 211.10244 -248.590476) (xy 211.079797 -248.540898) (xy 211.06444 -248.488602)
			(xy 211.056683 -248.434652) (xy 210.930402 -248.434652) (xy 210.929735 -248.439182) (xy 210.913667 -248.492589)
			(xy 210.889995 -248.543086) (xy 210.859222 -248.589599) (xy 210.822005 -248.631136) (xy 210.779137 -248.666811)
			(xy 210.731531 -248.695865) (xy 210.680202 -248.717677) (xy 210.626245 -248.731783) (xy 210.570808 -248.737883)
			(xy 210.515074 -248.735846) (xy 210.460231 -248.725716) (xy 210.407447 -248.707709) (xy 210.357847 -248.682208)
			(xy 210.312489 -248.649757) (xy 210.27234 -248.611048) (xy 210.238254 -248.566905) (xy 210.210958 -248.51827)
			(xy 210.191035 -248.466179) (xy 210.178909 -248.411742) (xy 210.174838 -248.35612) (xy 196.968618 -248.35612)
			(xy 196.968618 -249.476514) (xy 239.818416 -249.476514) (xy 239.822487 -249.420892) (xy 239.834613 -249.366455)
			(xy 239.854536 -249.314364) (xy 239.881832 -249.265729) (xy 239.915918 -249.221586) (xy 239.956067 -249.182877)
			(xy 240.001425 -249.150426) (xy 240.051025 -249.124925) (xy 240.103809 -249.106918) (xy 240.158652 -249.096788)
			(xy 240.214386 -249.094751) (xy 240.269823 -249.100851) (xy 240.32378 -249.114957) (xy 240.375109 -249.136769)
			(xy 240.422715 -249.165823) (xy 240.465583 -249.201498) (xy 240.5028 -249.243035) (xy 240.533573 -249.289548)
			(xy 240.557245 -249.340045) (xy 240.573313 -249.393452) (xy 240.581433 -249.448628) (xy 240.581942 -249.476514)
			(xy 241.850416 -249.476514) (xy 241.854487 -249.420892) (xy 241.866613 -249.366455) (xy 241.886536 -249.314364)
			(xy 241.913832 -249.265729) (xy 241.947918 -249.221586) (xy 241.988067 -249.182877) (xy 242.033425 -249.150426)
			(xy 242.083025 -249.124925) (xy 242.135809 -249.106918) (xy 242.190652 -249.096788) (xy 242.246386 -249.094751)
			(xy 242.301823 -249.100851) (xy 242.35578 -249.114957) (xy 242.407109 -249.136769) (xy 242.454715 -249.165823)
			(xy 242.497583 -249.201498) (xy 242.5348 -249.243035) (xy 242.565573 -249.289548) (xy 242.589245 -249.340045)
			(xy 242.605313 -249.393452) (xy 242.613433 -249.448628) (xy 242.613942 -249.476514) (xy 242.613433 -249.5044)
			(xy 242.605313 -249.559576) (xy 242.589245 -249.612983) (xy 242.565573 -249.66348) (xy 242.5348 -249.709993)
			(xy 242.497583 -249.75153) (xy 242.454715 -249.787205) (xy 242.407109 -249.816259) (xy 242.35578 -249.838071)
			(xy 242.301823 -249.852177) (xy 242.246386 -249.858277) (xy 242.190652 -249.85624) (xy 242.135809 -249.84611)
			(xy 242.083025 -249.828103) (xy 242.033425 -249.802602) (xy 241.988067 -249.770151) (xy 241.947918 -249.731442)
			(xy 241.913832 -249.687299) (xy 241.886536 -249.638664) (xy 241.866613 -249.586573) (xy 241.854487 -249.532136)
			(xy 241.850416 -249.476514) (xy 240.581942 -249.476514) (xy 240.581433 -249.5044) (xy 240.573313 -249.559576)
			(xy 240.557245 -249.612983) (xy 240.533573 -249.66348) (xy 240.5028 -249.709993) (xy 240.465583 -249.75153)
			(xy 240.422715 -249.787205) (xy 240.375109 -249.816259) (xy 240.32378 -249.838071) (xy 240.269823 -249.852177)
			(xy 240.214386 -249.858277) (xy 240.158652 -249.85624) (xy 240.103809 -249.84611) (xy 240.051025 -249.828103)
			(xy 240.001425 -249.802602) (xy 239.956067 -249.770151) (xy 239.915918 -249.731442) (xy 239.881832 -249.687299)
			(xy 239.854536 -249.638664) (xy 239.834613 -249.586573) (xy 239.822487 -249.532136) (xy 239.818416 -249.476514)
			(xy 196.968618 -249.476514) (xy 196.968618 -249.63755) (xy 196.968935 -249.64574) (xy 196.974131 -249.661276)
			(xy 196.978778 -249.66803) (xy 196.983604 -249.673618) (xy 199.600058 -252.290072) (xy 211.126576 -252.290072)
			(xy 211.130647 -252.23445) (xy 211.142773 -252.180013) (xy 211.162696 -252.127922) (xy 211.189992 -252.079287)
			(xy 211.224078 -252.035144) (xy 211.264227 -251.996435) (xy 211.309585 -251.963984) (xy 211.359185 -251.938483)
			(xy 211.411969 -251.920476) (xy 211.466812 -251.910346) (xy 211.522546 -251.908309) (xy 211.577983 -251.914409)
			(xy 211.63194 -251.928515) (xy 211.683269 -251.950327) (xy 211.730875 -251.979381) (xy 211.773743 -252.015056)
			(xy 211.81096 -252.056593) (xy 211.841733 -252.103106) (xy 211.865405 -252.153603) (xy 211.881473 -252.20701)
			(xy 211.889593 -252.262186) (xy 211.890102 -252.290072) (xy 211.889593 -252.317958) (xy 211.881473 -252.373134)
			(xy 211.865405 -252.426541) (xy 211.841733 -252.477038) (xy 211.81096 -252.523551) (xy 211.773743 -252.565088)
			(xy 211.730875 -252.600763) (xy 211.683269 -252.629817) (xy 211.63194 -252.651629) (xy 211.577983 -252.665735)
			(xy 211.522546 -252.671835) (xy 211.466812 -252.669798) (xy 211.411969 -252.659668) (xy 211.359185 -252.641661)
			(xy 211.309585 -252.61616) (xy 211.264227 -252.583709) (xy 211.224078 -252.545) (xy 211.189992 -252.500857)
			(xy 211.162696 -252.452222) (xy 211.142773 -252.400131) (xy 211.130647 -252.345694) (xy 211.126576 -252.290072)
			(xy 199.600058 -252.290072) (xy 200.084944 -252.774958) (xy 200.090532 -252.779784) (xy 200.097274 -252.784448)
			(xy 200.11282 -252.789622) (xy 200.121012 -252.789944)
		)
		(stroke
			(width 0)
			(type solid)
		)
		(fill yes)
		(layer "In11.Cu")
		(net "P3V3_AUX")
	)
	(gr_poly
		(pts
			(xy 140.97254 -415.995358) (xy 140.982553 -415.994931) (xy 141.001049 -415.987252) (xy 141.015198 -415.97308)
			(xy 141.022847 -415.954572) (xy 141.02334 -415.944558) (xy 141.02334 -394.305282) (xy 141.023816 -394.293169)
			(xy 141.031307 -394.270131) (xy 141.045549 -394.250535) (xy 141.065149 -394.236298) (xy 141.088189 -394.228813)
			(xy 141.100302 -394.22832) (xy 150.86965 -394.22832) (xy 150.879653 -394.227824) (xy 150.898131 -394.220156)
			(xy 150.912273 -394.206006) (xy 150.91993 -394.187523) (xy 150.92045 -394.17752) (xy 150.92045 -386.526532)
			(xy 150.919688 -386.517642) (xy 150.917656 -386.505704) (xy 150.916132 -386.50164) (xy 150.900454 -386.455442)
			(xy 150.87722 -386.360683) (xy 150.86345 -386.264094) (xy 150.86076 -386.215382) (xy 150.812246 -385.120388)
			(xy 150.734522 -383.35204) (xy 150.734268 -383.350008) (xy 150.697692 -382.928876) (xy 150.695992 -382.907391)
			(xy 150.694215 -382.864323) (xy 150.694136 -382.84277) (xy 150.694136 -382.830578) (xy 150.697946 -382.522984)
			(xy 150.697692 -382.52019) (xy 150.673054 -381.958088) (xy 150.66518 -381.780288) (xy 150.664336 -381.770685)
			(xy 150.656458 -381.753107) (xy 150.642676 -381.73965) (xy 150.633938 -381.735584) (xy 150.553928 -381.70231)
			(xy 150.545097 -381.699087) (xy 150.526315 -381.698711) (xy 150.517352 -381.701548) (xy 150.51659 -381.701802)
			(xy 150.495254 -381.70993) (xy 150.48865 -381.715772) (xy 150.467707 -381.733455) (xy 150.421706 -381.763254)
			(xy 150.371911 -381.786159) (xy 150.319349 -381.801696) (xy 150.265103 -381.809545) (xy 150.237698 -381.810006)
			(xy 150.214076 -381.810006) (xy 150.206964 -381.809498) (xy 150.183342 -381.806196) (xy 150.156431 -381.801859)
			(xy 150.10413 -381.786502) (xy 150.054549 -381.763855) (xy 150.008697 -381.734379) (xy 149.967509 -381.698676)
			(xy 149.931823 -381.657473) (xy 149.902367 -381.611608) (xy 149.879741 -381.562017) (xy 149.864406 -381.50971)
			(xy 149.856674 -381.455753) (xy 149.85619 -381.428498) (xy 149.856676 -381.401247) (xy 149.864433 -381.347299)
			(xy 149.879788 -381.295005) (xy 149.902429 -381.245427) (xy 149.931895 -381.199577) (xy 149.967587 -381.158387)
			(xy 150.008777 -381.122695) (xy 150.054627 -381.093229) (xy 150.104205 -381.070588) (xy 150.156499 -381.055233)
			(xy 150.210447 -381.047476) (xy 150.237698 -381.04699) (xy 150.26263 -381.047394) (xy 150.312069 -381.053883)
			(xy 150.360244 -381.066752) (xy 150.406333 -381.085781) (xy 150.449555 -381.110646) (xy 150.4696 -381.125476)
			(xy 150.469854 -381.125476) (xy 150.477742 -381.131035) (xy 150.496282 -381.136329) (xy 150.515465 -381.134381)
			(xy 150.52421 -381.130302) (xy 150.60549 -381.08763) (xy 150.613811 -381.082784) (xy 150.626352 -381.068191)
			(xy 150.632665 -381.050015) (xy 150.632668 -381.040386) (xy 150.622 -380.796038) (xy 150.546562 -379.088396)
			(xy 150.546054 -379.074934) (xy 150.234142 -371.99062) (xy 150.233634 -371.975888) (xy 150.233634 -371.94871)
			(xy 150.23338 -371.948456) (xy 150.23338 -371.946678) (xy 150.233497 -371.924996) (xy 150.235403 -371.881673)
			(xy 150.23719 -371.860064) (xy 150.379938 -370.248434) (xy 150.920196 -364.141258) (xy 150.92045 -364.13694)
			(xy 150.92045 -347.399864) (xy 150.920019 -347.389798) (xy 150.91229 -347.371208) (xy 150.905464 -347.363796)
			(xy 138.34745 -334.805782) (xy 138.340338 -334.798416) (xy 138.321542 -334.790796) (xy 106.973878 -334.790796)
			(xy 106.964453 -334.791179) (xy 106.946883 -334.798008) (xy 106.932975 -334.810732) (xy 106.928412 -334.81899)
			(xy 106.925618 -334.824324) (xy 106.924602 -334.827372) (xy 106.914955 -334.853439) (xy 106.889189 -334.902687)
			(xy 106.856551 -334.947676) (xy 106.817732 -334.987454) (xy 106.773553 -335.02118) (xy 106.724949 -335.04814)
			(xy 106.672947 -335.067763) (xy 106.618649 -335.079634) (xy 106.563203 -335.083503) (xy 106.507783 -335.079287)
			(xy 106.45356 -335.067076) (xy 106.401682 -335.047127) (xy 106.353248 -335.019864) (xy 106.309281 -334.985862)
			(xy 106.270712 -334.945841) (xy 106.238357 -334.900649) (xy 106.2129 -334.85124) (xy 106.203496 -334.825086)
			(xy 106.198162 -334.809592) (xy 106.172 -334.790796) (xy 105.380536 -334.790796) (xy 105.371431 -334.79117)
			(xy 105.354377 -334.797549) (xy 105.347262 -334.803242) (xy 105.318306 -334.828388) (xy 105.309924 -334.842612)
			(xy 105.308146 -334.850994) (xy 105.302193 -334.877878) (xy 105.283589 -334.929701) (xy 105.257729 -334.978312)
			(xy 105.22515 -335.022701) (xy 105.186527 -335.061945) (xy 105.142665 -335.09523) (xy 105.094474 -335.121863)
			(xy 105.042954 -335.141292) (xy 104.989176 -335.153114) (xy 104.934258 -335.157082) (xy 104.87934 -335.153114)
			(xy 104.825562 -335.141292) (xy 104.774042 -335.121863) (xy 104.725851 -335.09523) (xy 104.681989 -335.061945)
			(xy 104.643366 -335.022701) (xy 104.610787 -334.978312) (xy 104.584927 -334.929701) (xy 104.566323 -334.877878)
			(xy 104.56037 -334.850994) (xy 104.558592 -334.842612) (xy 104.55021 -334.828388) (xy 104.521254 -334.803242)
			(xy 104.51413 -334.797568) (xy 104.497079 -334.791202) (xy 104.48798 -334.790796) (xy 102.696264 -334.790796)
			(xy 102.686272 -334.791299) (xy 102.667805 -334.798942) (xy 102.653628 -334.813029) (xy 102.649274 -334.822038)
			(xy 102.613206 -334.908398) (xy 102.60711 -334.922622) (xy 102.613206 -334.952848) (xy 102.624128 -334.96377)
			(xy 102.644798 -334.985378) (xy 102.679833 -335.033833) (xy 102.706884 -335.087157) (xy 102.725288 -335.144048)
			(xy 102.734596 -335.203113) (xy 102.735126 -335.23301) (xy 102.734618 -335.251552) (xy 102.734618 -335.256124)
			(xy 102.73506 -335.265913) (xy 102.742365 -335.284078) (xy 102.748842 -335.29143) (xy 102.781862 -335.325466)
			(xy 102.808278 -335.352898) (xy 102.82809 -335.361026) (xy 102.838758 -335.360772) (xy 102.845616 -335.360518)
			(xy 102.846124 -335.360518) (xy 102.850188 -335.360518) (xy 102.877425 -335.361024) (xy 102.93134 -335.368814)
			(xy 102.983599 -335.384194) (xy 103.033138 -335.406852) (xy 103.07895 -335.436327) (xy 103.120104 -335.472018)
			(xy 103.155762 -335.513201) (xy 103.185199 -335.559038) (xy 103.207816 -335.608596) (xy 103.223153 -335.660867)
			(xy 103.230899 -335.714788) (xy 103.23132 -335.73593) (xy 103.44988 -335.73593) (xy 103.453951 -335.680308)
			(xy 103.466077 -335.625871) (xy 103.486 -335.57378) (xy 103.513296 -335.525145) (xy 103.547382 -335.481002)
			(xy 103.587531 -335.442293) (xy 103.632889 -335.409842) (xy 103.682489 -335.384341) (xy 103.735273 -335.366334)
			(xy 103.790116 -335.356204) (xy 103.84585 -335.354167) (xy 103.901287 -335.360267) (xy 103.955244 -335.374373)
			(xy 104.006573 -335.396185) (xy 104.054179 -335.425239) (xy 104.097047 -335.460914) (xy 104.134264 -335.502451)
			(xy 104.165037 -335.548964) (xy 104.188709 -335.599461) (xy 104.204777 -335.652868) (xy 104.212897 -335.708044)
			(xy 104.213406 -335.73593) (xy 104.212897 -335.763816) (xy 104.204777 -335.818992) (xy 104.188709 -335.872399)
			(xy 104.184337 -335.881726) (xy 111.234218 -335.881726) (xy 111.238289 -335.826104) (xy 111.250415 -335.771667)
			(xy 111.270338 -335.719576) (xy 111.297634 -335.670941) (xy 111.33172 -335.626798) (xy 111.371869 -335.588089)
			(xy 111.417227 -335.555638) (xy 111.466827 -335.530137) (xy 111.519611 -335.51213) (xy 111.574454 -335.502)
			(xy 111.630188 -335.499963) (xy 111.685625 -335.506063) (xy 111.739582 -335.520169) (xy 111.790911 -335.541981)
			(xy 111.838517 -335.571035) (xy 111.881385 -335.60671) (xy 111.918602 -335.648247) (xy 111.949375 -335.69476)
			(xy 111.973047 -335.745257) (xy 111.989115 -335.798664) (xy 111.997235 -335.85384) (xy 111.997744 -335.881726)
			(xy 111.997235 -335.909612) (xy 111.989115 -335.964788) (xy 111.973047 -336.018195) (xy 111.949375 -336.068692)
			(xy 111.918602 -336.115205) (xy 111.881385 -336.156742) (xy 111.838517 -336.192417) (xy 111.790911 -336.221471)
			(xy 111.739582 -336.243283) (xy 111.685625 -336.257389) (xy 111.630188 -336.263489) (xy 111.574454 -336.261452)
			(xy 111.519611 -336.251322) (xy 111.466827 -336.233315) (xy 111.417227 -336.207814) (xy 111.371869 -336.175363)
			(xy 111.33172 -336.136654) (xy 111.297634 -336.092511) (xy 111.270338 -336.043876) (xy 111.250415 -335.991785)
			(xy 111.238289 -335.937348) (xy 111.234218 -335.881726) (xy 104.184337 -335.881726) (xy 104.165037 -335.922896)
			(xy 104.134264 -335.969409) (xy 104.097047 -336.010946) (xy 104.054179 -336.046621) (xy 104.006573 -336.075675)
			(xy 103.955244 -336.097487) (xy 103.901287 -336.111593) (xy 103.84585 -336.117693) (xy 103.790116 -336.115656)
			(xy 103.735273 -336.105526) (xy 103.682489 -336.087519) (xy 103.632889 -336.062018) (xy 103.587531 -336.029567)
			(xy 103.547382 -335.990858) (xy 103.513296 -335.946715) (xy 103.486 -335.89808) (xy 103.466077 -335.845989)
			(xy 103.453951 -335.791552) (xy 103.44988 -335.73593) (xy 103.23132 -335.73593) (xy 103.231442 -335.742026)
			(xy 103.230956 -335.769277) (xy 103.2232 -335.823225) (xy 103.207845 -335.87552) (xy 103.185203 -335.925097)
			(xy 103.155737 -335.970947) (xy 103.120046 -336.012138) (xy 103.078855 -336.047829) (xy 103.033005 -336.077295)
			(xy 102.983428 -336.099937) (xy 102.931133 -336.115292) (xy 102.877185 -336.123048) (xy 102.822683 -336.123048)
			(xy 102.768735 -336.115292) (xy 102.71644 -336.099937) (xy 102.666863 -336.077295) (xy 102.621013 -336.047829)
			(xy 102.579822 -336.012138) (xy 102.544131 -335.970947) (xy 102.514665 -335.925097) (xy 102.492023 -335.87552)
			(xy 102.476668 -335.823225) (xy 102.468912 -335.769277) (xy 102.468426 -335.742026) (xy 102.468934 -335.723484)
			(xy 102.468934 -335.718912) (xy 102.46848 -335.709129) (xy 102.461153 -335.690984) (xy 102.45471 -335.683606)
			(xy 102.42169 -335.64957) (xy 102.395274 -335.622138) (xy 102.375462 -335.61401) (xy 102.364794 -335.614264)
			(xy 102.357936 -335.614518) (xy 102.357428 -335.614518) (xy 102.353364 -335.614518) (xy 102.326124 -335.614016)
			(xy 102.272201 -335.606232) (xy 102.219934 -335.590857) (xy 102.170386 -335.568203) (xy 102.124564 -335.53873)
			(xy 102.083401 -335.503039) (xy 102.047734 -335.461855) (xy 102.018289 -335.416016) (xy 101.995664 -335.366454)
			(xy 101.980319 -335.314178) (xy 101.972568 -335.260251) (xy 101.97211 -335.23301) (xy 101.972668 -335.203112)
			(xy 101.981952 -335.144042) (xy 102.00034 -335.087145) (xy 102.027382 -335.033814) (xy 102.062416 -334.985357)
			(xy 102.083108 -334.96377) (xy 102.09403 -334.952848) (xy 102.100126 -334.922622) (xy 102.09403 -334.908398)
			(xy 102.057962 -334.822038) (xy 102.053734 -334.81294) (xy 102.03954 -334.798785) (xy 102.020997 -334.791169)
			(xy 102.010972 -334.790796) (xy 83.16087 -334.790796) (xy 83.156524 -334.790909) (xy 83.147969 -334.792448)
			(xy 83.143852 -334.793844) (xy 80.617203 -335.69783) (xy 97.767392 -335.69783) (xy 97.771463 -335.642208)
			(xy 97.783589 -335.587771) (xy 97.803512 -335.53568) (xy 97.830808 -335.487045) (xy 97.864894 -335.442902)
			(xy 97.905043 -335.404193) (xy 97.950401 -335.371742) (xy 98.000001 -335.346241) (xy 98.052785 -335.328234)
			(xy 98.107628 -335.318104) (xy 98.163362 -335.316067) (xy 98.218799 -335.322167) (xy 98.272756 -335.336273)
			(xy 98.324085 -335.358085) (xy 98.371691 -335.387139) (xy 98.414559 -335.422814) (xy 98.451776 -335.464351)
			(xy 98.482549 -335.510864) (xy 98.506221 -335.561361) (xy 98.522289 -335.614768) (xy 98.530409 -335.669944)
			(xy 98.530918 -335.69783) (xy 98.530409 -335.725716) (xy 98.522289 -335.780892) (xy 98.506221 -335.834299)
			(xy 98.482549 -335.884796) (xy 98.451776 -335.931309) (xy 98.414559 -335.972846) (xy 98.371691 -336.008521)
			(xy 98.324085 -336.037575) (xy 98.272756 -336.059387) (xy 98.218799 -336.073493) (xy 98.163362 -336.079593)
			(xy 98.107628 -336.077556) (xy 98.052785 -336.067426) (xy 98.000001 -336.049419) (xy 97.950401 -336.023918)
			(xy 97.905043 -335.991467) (xy 97.864894 -335.952758) (xy 97.830808 -335.908615) (xy 97.803512 -335.85998)
			(xy 97.783589 -335.807889) (xy 97.771463 -335.753452) (xy 97.767392 -335.69783) (xy 80.617203 -335.69783)
			(xy 79.303118 -336.167984) (xy 79.268416 -336.180037) (xy 79.197605 -336.199615) (xy 79.16164 -336.2071)
			(xy 78.008226 -336.436462) (xy 78.001622 -336.43824) (xy 77.639459 -336.562954) (xy 108.718602 -336.562954)
			(xy 108.722673 -336.507332) (xy 108.734799 -336.452895) (xy 108.754722 -336.400804) (xy 108.782018 -336.352169)
			(xy 108.816104 -336.308026) (xy 108.856253 -336.269317) (xy 108.901611 -336.236866) (xy 108.951211 -336.211365)
			(xy 109.003995 -336.193358) (xy 109.058838 -336.183228) (xy 109.114572 -336.181191) (xy 109.170009 -336.187291)
			(xy 109.223966 -336.201397) (xy 109.275295 -336.223209) (xy 109.322901 -336.252263) (xy 109.365769 -336.287938)
			(xy 109.402986 -336.329475) (xy 109.433759 -336.375988) (xy 109.457431 -336.426485) (xy 109.473499 -336.479892)
			(xy 109.481619 -336.535068) (xy 109.482128 -336.562954) (xy 109.481619 -336.59084) (xy 109.473499 -336.646016)
			(xy 109.457431 -336.699423) (xy 109.433759 -336.74992) (xy 109.402986 -336.796433) (xy 109.365769 -336.83797)
			(xy 109.322901 -336.873645) (xy 109.275295 -336.902699) (xy 109.223966 -336.924511) (xy 109.170009 -336.938617)
			(xy 109.114572 -336.944717) (xy 109.058838 -336.94268) (xy 109.003995 -336.93255) (xy 108.951211 -336.914543)
			(xy 108.901611 -336.889042) (xy 108.856253 -336.856591) (xy 108.816104 -336.817882) (xy 108.782018 -336.773739)
			(xy 108.754722 -336.725104) (xy 108.734799 -336.673013) (xy 108.722673 -336.618576) (xy 108.718602 -336.562954)
			(xy 77.639459 -336.562954) (xy 76.412088 -336.98561) (xy 99.107496 -336.98561) (xy 99.111567 -336.929988)
			(xy 99.123693 -336.875551) (xy 99.143616 -336.82346) (xy 99.170912 -336.774825) (xy 99.204998 -336.730682)
			(xy 99.245147 -336.691973) (xy 99.290505 -336.659522) (xy 99.340105 -336.634021) (xy 99.392889 -336.616014)
			(xy 99.447732 -336.605884) (xy 99.503466 -336.603847) (xy 99.558903 -336.609947) (xy 99.61286 -336.624053)
			(xy 99.664189 -336.645865) (xy 99.711795 -336.674919) (xy 99.754663 -336.710594) (xy 99.79188 -336.752131)
			(xy 99.822653 -336.798644) (xy 99.846325 -336.849141) (xy 99.862393 -336.902548) (xy 99.870513 -336.957724)
			(xy 99.871022 -336.98561) (xy 99.870513 -337.013496) (xy 99.862393 -337.068672) (xy 99.846325 -337.122079)
			(xy 99.822653 -337.172576) (xy 99.79188 -337.219089) (xy 99.754663 -337.260626) (xy 99.711795 -337.296301)
			(xy 99.664189 -337.325355) (xy 99.61286 -337.347167) (xy 99.558903 -337.361273) (xy 99.503466 -337.367373)
			(xy 99.447732 -337.365336) (xy 99.392889 -337.355206) (xy 99.340105 -337.337199) (xy 99.290505 -337.311698)
			(xy 99.245147 -337.279247) (xy 99.204998 -337.240538) (xy 99.170912 -337.196395) (xy 99.143616 -337.14776)
			(xy 99.123693 -337.095669) (xy 99.111567 -337.041232) (xy 99.107496 -336.98561) (xy 76.412088 -336.98561)
			(xy 62.005972 -341.946484) (xy 61.999876 -341.950802) (xy 61.978794 -341.965534) (xy 61.97039 -341.972223)
			(xy 61.959508 -341.990711) (xy 61.957075 -342.012025) (xy 61.959744 -342.02243) (xy 61.964824 -342.038178)
			(xy 61.991494 -342.057736) (xy 62.235842 -342.057736) (xy 62.267628 -342.058416) (xy 62.330311 -342.069016)
			(xy 62.360556 -342.078818) (xy 62.364563 -342.080104) (xy 62.372859 -342.081511) (xy 62.377066 -342.081612)
			(xy 62.404263 -342.082205) (xy 62.458078 -342.090147) (xy 62.510222 -342.105647) (xy 62.559637 -342.128392)
			(xy 62.605324 -342.15792) (xy 62.646356 -342.193634) (xy 62.681905 -342.23481) (xy 62.711248 -342.280616)
			(xy 62.733793 -342.330122) (xy 62.749083 -342.382328) (xy 62.756808 -342.436175) (xy 62.757304 -342.463374)
			(xy 62.757244 -342.466771) (xy 64.099899 -342.466771) (xy 64.099899 -342.412229) (xy 64.107662 -342.358241)
			(xy 64.123028 -342.305908) (xy 64.145686 -342.256295) (xy 64.175174 -342.210411) (xy 64.210892 -342.16919)
			(xy 64.252112 -342.133473) (xy 64.297997 -342.103985) (xy 64.34761 -342.081327) (xy 64.399943 -342.065961)
			(xy 64.453931 -342.058199) (xy 64.481202 -342.057736) (xy 65.344802 -342.057736) (xy 65.372071 -342.058227)
			(xy 65.426054 -342.065988) (xy 65.478383 -342.081354) (xy 65.527993 -342.10401) (xy 65.573873 -342.133496)
			(xy 65.615091 -342.169211) (xy 65.650805 -342.210428) (xy 65.680291 -342.256309) (xy 65.702947 -342.305919)
			(xy 65.718312 -342.358248) (xy 65.726074 -342.412231) (xy 65.726074 -342.466768) (xy 67.208922 -342.466768)
			(xy 67.208922 -342.412232) (xy 67.216683 -342.358252) (xy 67.232047 -342.305925) (xy 67.2547 -342.256317)
			(xy 67.284183 -342.210438) (xy 67.319894 -342.169221) (xy 67.361107 -342.133505) (xy 67.406984 -342.104018)
			(xy 67.456589 -342.08136) (xy 67.508914 -342.065991) (xy 67.562894 -342.058225) (xy 67.590162 -342.057736)
			(xy 68.453762 -342.057736) (xy 68.481035 -342.058201) (xy 68.535025 -342.065959) (xy 68.587362 -342.081321)
			(xy 68.63698 -342.103977) (xy 68.682868 -342.133463) (xy 68.724093 -342.16918) (xy 68.759814 -342.210401)
			(xy 68.789305 -342.256287) (xy 68.811965 -342.305902) (xy 68.827333 -342.358237) (xy 68.835096 -342.412227)
			(xy 68.835096 -342.466772) (xy 70.3178 -342.466772) (xy 70.3178 -342.412228) (xy 70.325562 -342.358239)
			(xy 70.34093 -342.305904) (xy 70.363589 -342.256289) (xy 70.393079 -342.210404) (xy 70.428799 -342.169183)
			(xy 70.470022 -342.133466) (xy 70.515909 -342.103979) (xy 70.565525 -342.081322) (xy 70.61786 -342.065958)
			(xy 70.67185 -342.058198) (xy 70.699122 -342.057736) (xy 71.562722 -342.057736) (xy 71.58999 -342.058228)
			(xy 71.643971 -342.065992) (xy 71.696298 -342.081359) (xy 71.745905 -342.104017) (xy 71.791783 -342.133503)
			(xy 71.832998 -342.169218) (xy 71.86871 -342.210435) (xy 71.898194 -342.256314) (xy 71.920848 -342.305923)
			(xy 71.936213 -342.35825) (xy 71.943974 -342.412232) (xy 71.943974 -342.466768) (xy 71.943974 -342.466769)
			(xy 73.426822 -342.466769) (xy 73.426822 -342.412231) (xy 73.434584 -342.358249) (xy 73.449948 -342.305921)
			(xy 73.472603 -342.256311) (xy 73.502087 -342.210431) (xy 73.537801 -342.169214) (xy 73.579017 -342.133498)
			(xy 73.624896 -342.104012) (xy 73.674504 -342.081354) (xy 73.726831 -342.065987) (xy 73.780813 -342.058224)
			(xy 73.808082 -342.057736) (xy 74.671682 -342.057736) (xy 74.698954 -342.058202) (xy 74.752942 -342.065962)
			(xy 74.805277 -342.081327) (xy 74.854892 -342.103983) (xy 74.900778 -342.13347) (xy 74.942 -342.169188)
			(xy 74.977719 -342.210408) (xy 75.007208 -342.256292) (xy 75.029867 -342.305906) (xy 75.045234 -342.35824)
			(xy 75.052996 -342.412228) (xy 75.052996 -342.466772) (xy 75.052996 -342.466773) (xy 76.5357 -342.466773)
			(xy 76.5357 -342.412227) (xy 76.543463 -342.358236) (xy 76.558831 -342.3059) (xy 76.581492 -342.256284)
			(xy 76.610984 -342.210398) (xy 76.646706 -342.169176) (xy 76.687931 -342.133459) (xy 76.73382 -342.103972)
			(xy 76.783439 -342.081317) (xy 76.835777 -342.065954) (xy 76.889769 -342.058197) (xy 76.917042 -342.057736)
			(xy 77.780642 -342.057736) (xy 77.807909 -342.058229) (xy 77.861888 -342.065996) (xy 77.914212 -342.081365)
			(xy 77.963817 -342.104023) (xy 78.009692 -342.13351) (xy 78.050905 -342.169225) (xy 78.086615 -342.210441)
			(xy 78.116097 -342.25632) (xy 78.13875 -342.305927) (xy 78.154113 -342.358253) (xy 78.161874 -342.412233)
			(xy 78.161874 -342.466767) (xy 78.161873 -342.466771) (xy 79.644699 -342.466771) (xy 79.644699 -342.412229)
			(xy 79.652462 -342.358241) (xy 79.667828 -342.305908) (xy 79.690486 -342.256295) (xy 79.719974 -342.210411)
			(xy 79.755692 -342.16919) (xy 79.796912 -342.133473) (xy 79.842797 -342.103985) (xy 79.89241 -342.081327)
			(xy 79.944743 -342.065961) (xy 79.998731 -342.058199) (xy 80.026002 -342.057736) (xy 80.889602 -342.057736)
			(xy 80.916871 -342.058227) (xy 80.970854 -342.065988) (xy 81.023183 -342.081354) (xy 81.072793 -342.10401)
			(xy 81.118673 -342.133496) (xy 81.159891 -342.169211) (xy 81.195605 -342.210428) (xy 81.225091 -342.256309)
			(xy 81.247747 -342.305919) (xy 81.263112 -342.358248) (xy 81.270874 -342.412231) (xy 81.270874 -342.466768)
			(xy 82.753722 -342.466768) (xy 82.753722 -342.412232) (xy 82.761483 -342.358252) (xy 82.776847 -342.305925)
			(xy 82.7995 -342.256317) (xy 82.828983 -342.210438) (xy 82.864694 -342.169221) (xy 82.905907 -342.133505)
			(xy 82.951784 -342.104018) (xy 83.001389 -342.08136) (xy 83.053714 -342.065991) (xy 83.107694 -342.058225)
			(xy 83.134962 -342.057736) (xy 83.998562 -342.057736) (xy 84.025835 -342.058201) (xy 84.079825 -342.065959)
			(xy 84.132162 -342.081321) (xy 84.18178 -342.103977) (xy 84.227668 -342.133463) (xy 84.268893 -342.16918)
			(xy 84.304614 -342.210401) (xy 84.334105 -342.256287) (xy 84.356765 -342.305902) (xy 84.372133 -342.358237)
			(xy 84.379896 -342.412227) (xy 84.379896 -342.466772) (xy 85.8626 -342.466772) (xy 85.8626 -342.412228)
			(xy 85.870362 -342.358239) (xy 85.88573 -342.305904) (xy 85.908389 -342.256289) (xy 85.937879 -342.210404)
			(xy 85.973599 -342.169183) (xy 86.014822 -342.133466) (xy 86.060709 -342.103979) (xy 86.110325 -342.081322)
			(xy 86.16266 -342.065958) (xy 86.21665 -342.058198) (xy 86.243922 -342.057736) (xy 87.107522 -342.057736)
			(xy 87.13479 -342.058228) (xy 87.188771 -342.065992) (xy 87.241098 -342.081359) (xy 87.290705 -342.104017)
			(xy 87.336583 -342.133503) (xy 87.377798 -342.169218) (xy 87.41351 -342.210435) (xy 87.442994 -342.256314)
			(xy 87.465648 -342.305923) (xy 87.481013 -342.35825) (xy 87.488774 -342.412232) (xy 87.488774 -342.466768)
			(xy 87.488774 -342.466769) (xy 88.971622 -342.466769) (xy 88.971622 -342.412231) (xy 88.979384 -342.358249)
			(xy 88.994748 -342.305921) (xy 89.017403 -342.256311) (xy 89.046887 -342.210431) (xy 89.082601 -342.169214)
			(xy 89.123817 -342.133498) (xy 89.169696 -342.104012) (xy 89.219304 -342.081354) (xy 89.271631 -342.065987)
			(xy 89.325613 -342.058224) (xy 89.352882 -342.057736) (xy 90.216482 -342.057736) (xy 90.243754 -342.058202)
			(xy 90.297742 -342.065962) (xy 90.350077 -342.081327) (xy 90.399692 -342.103983) (xy 90.445578 -342.13347)
			(xy 90.4868 -342.169188) (xy 90.522519 -342.210408) (xy 90.552008 -342.256292) (xy 90.574667 -342.305906)
			(xy 90.590034 -342.35824) (xy 90.597796 -342.412228) (xy 90.597796 -342.466772) (xy 90.597796 -342.466773)
			(xy 92.0805 -342.466773) (xy 92.0805 -342.412227) (xy 92.088263 -342.358236) (xy 92.103631 -342.3059)
			(xy 92.126292 -342.256284) (xy 92.155784 -342.210398) (xy 92.191506 -342.169176) (xy 92.232731 -342.133459)
			(xy 92.27862 -342.103972) (xy 92.328239 -342.081317) (xy 92.380577 -342.065954) (xy 92.434569 -342.058197)
			(xy 92.461842 -342.057736) (xy 93.325442 -342.057736) (xy 93.352709 -342.058229) (xy 93.406688 -342.065996)
			(xy 93.459012 -342.081365) (xy 93.508617 -342.104023) (xy 93.554492 -342.13351) (xy 93.595705 -342.169225)
			(xy 93.631415 -342.210441) (xy 93.660897 -342.25632) (xy 93.68355 -342.305927) (xy 93.698913 -342.358253)
			(xy 93.706674 -342.412233) (xy 93.706674 -342.466767) (xy 93.698913 -342.520747) (xy 93.68355 -342.573073)
			(xy 93.660897 -342.62268) (xy 93.631415 -342.668559) (xy 93.60914 -342.694268) (xy 102.35157 -342.694268)
			(xy 102.35157 -342.634332) (xy 102.359393 -342.574909) (xy 102.374905 -342.517016) (xy 102.397841 -342.461642)
			(xy 102.427809 -342.409736) (xy 102.464294 -342.362185) (xy 102.506675 -342.319804) (xy 102.554224 -342.283316)
			(xy 102.60613 -342.253347) (xy 102.661502 -342.23041) (xy 102.719395 -342.214896) (xy 102.778818 -342.207071)
			(xy 102.808786 -342.20658) (xy 103.672386 -342.20658) (xy 103.702355 -342.207072) (xy 103.76178 -342.214894)
			(xy 103.819676 -342.230405) (xy 103.875051 -342.253341) (xy 103.926959 -342.283309) (xy 103.974512 -342.319796)
			(xy 104.016895 -342.362178) (xy 104.053383 -342.409729) (xy 104.083352 -342.461636) (xy 104.085479 -342.466772)
			(xy 111.4808 -342.466772) (xy 111.4808 -342.412228) (xy 111.488562 -342.358241) (xy 111.503929 -342.305907)
			(xy 111.526587 -342.256293) (xy 111.556075 -342.210409) (xy 111.591794 -342.169188) (xy 111.633015 -342.133471)
			(xy 111.6789 -342.103983) (xy 111.728515 -342.081326) (xy 111.780848 -342.06596) (xy 111.834836 -342.058199)
			(xy 111.862108 -342.057736) (xy 112.725708 -342.057736) (xy 112.752977 -342.058227) (xy 112.806959 -342.06599)
			(xy 112.859288 -342.081355) (xy 112.908897 -342.104012) (xy 112.954776 -342.133498) (xy 112.995993 -342.169213)
			(xy 113.031707 -342.21043) (xy 113.061192 -342.256311) (xy 113.083847 -342.30592) (xy 113.099212 -342.358249)
			(xy 113.106974 -342.412231) (xy 113.106974 -342.466768) (xy 114.589822 -342.466768) (xy 114.589822 -342.412232)
			(xy 114.597583 -342.358251) (xy 114.612947 -342.305924) (xy 114.635601 -342.256315) (xy 114.665084 -342.210436)
			(xy 114.700796 -342.169219) (xy 114.74201 -342.133503) (xy 114.787887 -342.104016) (xy 114.837494 -342.081358)
			(xy 114.88982 -342.06599) (xy 114.9438 -342.058225) (xy 114.971068 -342.057736) (xy 115.834668 -342.057736)
			(xy 115.86194 -342.058201) (xy 115.91593 -342.06596) (xy 115.968267 -342.081323) (xy 116.017884 -342.103979)
			(xy 116.063771 -342.133465) (xy 116.104995 -342.169183) (xy 116.140715 -342.210403) (xy 116.170206 -342.256288)
			(xy 116.192866 -342.305903) (xy 116.208233 -342.358238) (xy 116.215996 -342.412228) (xy 116.215996 -342.466772)
			(xy 117.6987 -342.466772) (xy 117.6987 -342.412228) (xy 117.706462 -342.358238) (xy 117.72183 -342.305903)
			(xy 117.74449 -342.256288) (xy 117.77398 -342.210402) (xy 117.809701 -342.169181) (xy 117.850925 -342.133464)
			(xy 117.896812 -342.103977) (xy 117.946429 -342.08132) (xy 117.998765 -342.065957) (xy 118.052756 -342.058198)
			(xy 118.080028 -342.057736) (xy 118.943628 -342.057736) (xy 118.970896 -342.058228) (xy 119.024876 -342.065993)
			(xy 119.077202 -342.081361) (xy 119.126809 -342.104019) (xy 119.172686 -342.133505) (xy 119.2139 -342.16922)
			(xy 119.249612 -342.210437) (xy 119.279095 -342.256316) (xy 119.301749 -342.305924) (xy 119.317113 -342.358251)
			(xy 119.324874 -342.412232) (xy 119.324874 -342.466768) (xy 119.324874 -342.466769) (xy 120.807722 -342.466769)
			(xy 120.807722 -342.412231) (xy 120.815484 -342.358248) (xy 120.830849 -342.305919) (xy 120.853504 -342.25631)
			(xy 120.882989 -342.210429) (xy 120.918703 -342.169212) (xy 120.95992 -342.133496) (xy 121.005799 -342.10401)
			(xy 121.055408 -342.081353) (xy 121.107736 -342.065986) (xy 121.161719 -342.058223) (xy 121.188988 -342.057736)
			(xy 122.052588 -342.057736) (xy 122.079859 -342.058203) (xy 122.133847 -342.065963) (xy 122.186181 -342.081329)
			(xy 122.235796 -342.103985) (xy 122.28168 -342.133472) (xy 122.322902 -342.16919) (xy 122.35862 -342.21041)
			(xy 122.388109 -342.256294) (xy 122.410767 -342.305908) (xy 122.426134 -342.358241) (xy 122.433896 -342.412229)
			(xy 122.433896 -342.466771) (xy 122.433896 -342.466773) (xy 123.9166 -342.466773) (xy 123.9166 -342.412227)
			(xy 123.924363 -342.358235) (xy 123.939732 -342.305899) (xy 123.962393 -342.256282) (xy 123.991885 -342.210396)
			(xy 124.027608 -342.169174) (xy 124.068834 -342.133456) (xy 124.114724 -342.10397) (xy 124.164344 -342.081315)
			(xy 124.216682 -342.065953) (xy 124.270675 -342.058196) (xy 124.297948 -342.057736) (xy 125.161548 -342.057736)
			(xy 125.188815 -342.05823) (xy 125.242793 -342.065997) (xy 125.295117 -342.081366) (xy 125.34472 -342.104025)
			(xy 125.390595 -342.133512) (xy 125.431807 -342.169227) (xy 125.467517 -342.210443) (xy 125.496998 -342.256322)
			(xy 125.519651 -342.305928) (xy 125.535013 -342.358254) (xy 125.542774 -342.412233) (xy 125.542774 -342.466767)
			(xy 125.542773 -342.466772) (xy 127.0256 -342.466772) (xy 127.0256 -342.412228) (xy 127.033362 -342.358241)
			(xy 127.048729 -342.305907) (xy 127.071387 -342.256293) (xy 127.100875 -342.210409) (xy 127.136594 -342.169188)
			(xy 127.177815 -342.133471) (xy 127.2237 -342.103983) (xy 127.273315 -342.081326) (xy 127.325648 -342.06596)
			(xy 127.379636 -342.058199) (xy 127.406908 -342.057736) (xy 128.270508 -342.057736) (xy 128.297777 -342.058227)
			(xy 128.351759 -342.06599) (xy 128.404088 -342.081355) (xy 128.453697 -342.104012) (xy 128.499576 -342.133498)
			(xy 128.540793 -342.169213) (xy 128.576507 -342.21043) (xy 128.605992 -342.256311) (xy 128.628647 -342.30592)
			(xy 128.644012 -342.358249) (xy 128.651774 -342.412231) (xy 128.651774 -342.466768) (xy 130.134622 -342.466768)
			(xy 130.134622 -342.412232) (xy 130.142383 -342.358251) (xy 130.157747 -342.305924) (xy 130.180401 -342.256315)
			(xy 130.209884 -342.210436) (xy 130.245596 -342.169219) (xy 130.28681 -342.133503) (xy 130.332687 -342.104016)
			(xy 130.382294 -342.081358) (xy 130.43462 -342.06599) (xy 130.4886 -342.058225) (xy 130.515868 -342.057736)
			(xy 131.379468 -342.057736) (xy 131.40674 -342.058201) (xy 131.46073 -342.06596) (xy 131.513067 -342.081323)
			(xy 131.562684 -342.103979) (xy 131.608571 -342.133465) (xy 131.649795 -342.169183) (xy 131.685515 -342.210403)
			(xy 131.715006 -342.256288) (xy 131.737666 -342.305903) (xy 131.753033 -342.358238) (xy 131.760796 -342.412228)
			(xy 131.760796 -342.466772) (xy 133.2435 -342.466772) (xy 133.2435 -342.412228) (xy 133.251262 -342.358238)
			(xy 133.26663 -342.305903) (xy 133.28929 -342.256288) (xy 133.31878 -342.210402) (xy 133.354501 -342.169181)
			(xy 133.395725 -342.133464) (xy 133.441612 -342.103977) (xy 133.491229 -342.08132) (xy 133.543565 -342.065957)
			(xy 133.597556 -342.058198) (xy 133.624828 -342.057736) (xy 134.488428 -342.057736) (xy 134.515696 -342.058228)
			(xy 134.569676 -342.065993) (xy 134.622002 -342.081361) (xy 134.671609 -342.104019) (xy 134.717486 -342.133505)
			(xy 134.7587 -342.16922) (xy 134.794412 -342.210437) (xy 134.823895 -342.256316) (xy 134.846549 -342.305924)
			(xy 134.861913 -342.358251) (xy 134.869674 -342.412232) (xy 134.869674 -342.466768) (xy 134.869674 -342.466769)
			(xy 136.352522 -342.466769) (xy 136.352522 -342.412231) (xy 136.360284 -342.358248) (xy 136.375649 -342.305919)
			(xy 136.398304 -342.25631) (xy 136.427789 -342.210429) (xy 136.463503 -342.169212) (xy 136.50472 -342.133496)
			(xy 136.550599 -342.10401) (xy 136.600208 -342.081353) (xy 136.652536 -342.065986) (xy 136.706519 -342.058223)
			(xy 136.733788 -342.057736) (xy 137.597388 -342.057736) (xy 137.624659 -342.058203) (xy 137.678647 -342.065963)
			(xy 137.730981 -342.081329) (xy 137.780596 -342.103985) (xy 137.82648 -342.133472) (xy 137.867702 -342.16919)
			(xy 137.90342 -342.21041) (xy 137.932909 -342.256294) (xy 137.955567 -342.305908) (xy 137.970934 -342.358241)
			(xy 137.978696 -342.412229) (xy 137.978696 -342.466771) (xy 137.978696 -342.466773) (xy 139.4614 -342.466773)
			(xy 139.4614 -342.412227) (xy 139.469163 -342.358235) (xy 139.484532 -342.305899) (xy 139.507193 -342.256282)
			(xy 139.536685 -342.210396) (xy 139.572408 -342.169174) (xy 139.613634 -342.133456) (xy 139.659524 -342.10397)
			(xy 139.709144 -342.081315) (xy 139.761482 -342.065953) (xy 139.815475 -342.058196) (xy 139.842748 -342.057736)
			(xy 140.706348 -342.057736) (xy 140.733615 -342.05823) (xy 140.787593 -342.065997) (xy 140.839917 -342.081366)
			(xy 140.88952 -342.104025) (xy 140.935395 -342.133512) (xy 140.976607 -342.169227) (xy 141.012317 -342.210443)
			(xy 141.041798 -342.256322) (xy 141.064451 -342.305928) (xy 141.079813 -342.358254) (xy 141.087574 -342.412233)
			(xy 141.087574 -342.466767) (xy 141.087573 -342.466772) (xy 142.5704 -342.466772) (xy 142.5704 -342.412228)
			(xy 142.578162 -342.358241) (xy 142.593529 -342.305907) (xy 142.616187 -342.256293) (xy 142.645675 -342.210409)
			(xy 142.681394 -342.169188) (xy 142.722615 -342.133471) (xy 142.7685 -342.103983) (xy 142.818115 -342.081326)
			(xy 142.870448 -342.06596) (xy 142.924436 -342.058199) (xy 142.951708 -342.057736) (xy 143.815308 -342.057736)
			(xy 143.842577 -342.058227) (xy 143.896559 -342.06599) (xy 143.948888 -342.081355) (xy 143.998497 -342.104012)
			(xy 144.044376 -342.133498) (xy 144.085593 -342.169213) (xy 144.121307 -342.21043) (xy 144.150792 -342.256311)
			(xy 144.173447 -342.30592) (xy 144.188812 -342.358249) (xy 144.196574 -342.412231) (xy 144.196574 -342.466769)
			(xy 144.188812 -342.520751) (xy 144.173447 -342.57308) (xy 144.150792 -342.622689) (xy 144.121307 -342.66857)
			(xy 144.085593 -342.709787) (xy 144.044376 -342.745502) (xy 143.998497 -342.774988) (xy 143.948888 -342.797645)
			(xy 143.896559 -342.81301) (xy 143.842577 -342.820773) (xy 143.815308 -342.82126) (xy 142.951708 -342.82126)
			(xy 142.924436 -342.820801) (xy 142.870448 -342.81304) (xy 142.818115 -342.797674) (xy 142.7685 -342.775017)
			(xy 142.722615 -342.745529) (xy 142.681394 -342.709812) (xy 142.645675 -342.668591) (xy 142.616187 -342.622707)
			(xy 142.593529 -342.573093) (xy 142.578162 -342.520759) (xy 142.5704 -342.466772) (xy 141.087573 -342.466772)
			(xy 141.079813 -342.520746) (xy 141.064451 -342.573072) (xy 141.041798 -342.622678) (xy 141.012317 -342.668557)
			(xy 140.976607 -342.709773) (xy 140.935395 -342.745488) (xy 140.88952 -342.774975) (xy 140.839917 -342.797634)
			(xy 140.787593 -342.813003) (xy 140.733615 -342.82077) (xy 140.706348 -342.82126) (xy 139.842748 -342.82126)
			(xy 139.815475 -342.820804) (xy 139.761482 -342.813047) (xy 139.709144 -342.797685) (xy 139.659524 -342.77503)
			(xy 139.613634 -342.745544) (xy 139.572408 -342.709826) (xy 139.536685 -342.668604) (xy 139.507193 -342.622718)
			(xy 139.484532 -342.573101) (xy 139.469163 -342.520765) (xy 139.4614 -342.466773) (xy 137.978696 -342.466773)
			(xy 137.970934 -342.520759) (xy 137.955567 -342.573092) (xy 137.932909 -342.622706) (xy 137.90342 -342.66859)
			(xy 137.867702 -342.70981) (xy 137.82648 -342.745528) (xy 137.780596 -342.775015) (xy 137.730981 -342.797671)
			(xy 137.678647 -342.813037) (xy 137.624659 -342.820797) (xy 137.597388 -342.82126) (xy 136.733788 -342.82126)
			(xy 136.706519 -342.820777) (xy 136.652536 -342.813014) (xy 136.600208 -342.797647) (xy 136.550599 -342.77499)
			(xy 136.50472 -342.745504) (xy 136.463503 -342.709788) (xy 136.427789 -342.668571) (xy 136.398304 -342.62269)
			(xy 136.375649 -342.573081) (xy 136.360284 -342.520752) (xy 136.352522 -342.466769) (xy 134.869674 -342.466769)
			(xy 134.861913 -342.520749) (xy 134.846549 -342.573076) (xy 134.823895 -342.622684) (xy 134.794412 -342.668563)
			(xy 134.7587 -342.70978) (xy 134.717486 -342.745495) (xy 134.671609 -342.774981) (xy 134.622002 -342.797639)
			(xy 134.569676 -342.813007) (xy 134.515696 -342.820772) (xy 134.488428 -342.82126) (xy 133.624828 -342.82126)
			(xy 133.597556 -342.820802) (xy 133.543565 -342.813043) (xy 133.491229 -342.79768) (xy 133.441612 -342.775023)
			(xy 133.395725 -342.745536) (xy 133.354501 -342.709819) (xy 133.31878 -342.668598) (xy 133.28929 -342.622712)
			(xy 133.26663 -342.573097) (xy 133.251262 -342.520762) (xy 133.2435 -342.466772) (xy 131.760796 -342.466772)
			(xy 131.753033 -342.520762) (xy 131.737666 -342.573097) (xy 131.715006 -342.622712) (xy 131.685515 -342.668597)
			(xy 131.649795 -342.709817) (xy 131.608571 -342.745535) (xy 131.562684 -342.775021) (xy 131.513067 -342.797677)
			(xy 131.46073 -342.81304) (xy 131.40674 -342.820799) (xy 131.379468 -342.82126) (xy 130.515868 -342.82126)
			(xy 130.4886 -342.820775) (xy 130.43462 -342.81301) (xy 130.382294 -342.797642) (xy 130.332687 -342.774984)
			(xy 130.28681 -342.745497) (xy 130.245596 -342.709781) (xy 130.209884 -342.668564) (xy 130.180401 -342.622685)
			(xy 130.157747 -342.573076) (xy 130.142383 -342.520749) (xy 130.134622 -342.466768) (xy 128.651774 -342.466768)
			(xy 128.651774 -342.466769) (xy 128.644012 -342.520751) (xy 128.628647 -342.57308) (xy 128.605992 -342.622689)
			(xy 128.576507 -342.66857) (xy 128.540793 -342.709787) (xy 128.499576 -342.745502) (xy 128.453697 -342.774988)
			(xy 128.404088 -342.797645) (xy 128.351759 -342.81301) (xy 128.297777 -342.820773) (xy 128.270508 -342.82126)
			(xy 127.406908 -342.82126) (xy 127.379636 -342.820801) (xy 127.325648 -342.81304) (xy 127.273315 -342.797674)
			(xy 127.2237 -342.775017) (xy 127.177815 -342.745529) (xy 127.136594 -342.709812) (xy 127.100875 -342.668591)
			(xy 127.071387 -342.622707) (xy 127.048729 -342.573093) (xy 127.033362 -342.520759) (xy 127.0256 -342.466772)
			(xy 125.542773 -342.466772) (xy 125.535013 -342.520746) (xy 125.519651 -342.573072) (xy 125.496998 -342.622678)
			(xy 125.467517 -342.668557) (xy 125.431807 -342.709773) (xy 125.390595 -342.745488) (xy 125.34472 -342.774975)
			(xy 125.295117 -342.797634) (xy 125.242793 -342.813003) (xy 125.188815 -342.82077) (xy 125.161548 -342.82126)
			(xy 124.297948 -342.82126) (xy 124.270675 -342.820804) (xy 124.216682 -342.813047) (xy 124.164344 -342.797685)
			(xy 124.114724 -342.77503) (xy 124.068834 -342.745544) (xy 124.027608 -342.709826) (xy 123.991885 -342.668604)
			(xy 123.962393 -342.622718) (xy 123.939732 -342.573101) (xy 123.924363 -342.520765) (xy 123.9166 -342.466773)
			(xy 122.433896 -342.466773) (xy 122.426134 -342.520759) (xy 122.410767 -342.573092) (xy 122.388109 -342.622706)
			(xy 122.35862 -342.66859) (xy 122.322902 -342.70981) (xy 122.28168 -342.745528) (xy 122.235796 -342.775015)
			(xy 122.186181 -342.797671) (xy 122.133847 -342.813037) (xy 122.079859 -342.820797) (xy 122.052588 -342.82126)
			(xy 121.188988 -342.82126) (xy 121.161719 -342.820777) (xy 121.107736 -342.813014) (xy 121.055408 -342.797647)
			(xy 121.005799 -342.77499) (xy 120.95992 -342.745504) (xy 120.918703 -342.709788) (xy 120.882989 -342.668571)
			(xy 120.853504 -342.62269) (xy 120.830849 -342.573081) (xy 120.815484 -342.520752) (xy 120.807722 -342.466769)
			(xy 119.324874 -342.466769) (xy 119.317113 -342.520749) (xy 119.301749 -342.573076) (xy 119.279095 -342.622684)
			(xy 119.249612 -342.668563) (xy 119.2139 -342.70978) (xy 119.172686 -342.745495) (xy 119.126809 -342.774981)
			(xy 119.077202 -342.797639) (xy 119.024876 -342.813007) (xy 118.970896 -342.820772) (xy 118.943628 -342.82126)
			(xy 118.080028 -342.82126) (xy 118.052756 -342.820802) (xy 117.998765 -342.813043) (xy 117.946429 -342.79768)
			(xy 117.896812 -342.775023) (xy 117.850925 -342.745536) (xy 117.809701 -342.709819) (xy 117.77398 -342.668598)
			(xy 117.74449 -342.622712) (xy 117.72183 -342.573097) (xy 117.706462 -342.520762) (xy 117.6987 -342.466772)
			(xy 116.215996 -342.466772) (xy 116.208233 -342.520762) (xy 116.192866 -342.573097) (xy 116.170206 -342.622712)
			(xy 116.140715 -342.668597) (xy 116.104995 -342.709817) (xy 116.063771 -342.745535) (xy 116.017884 -342.775021)
			(xy 115.968267 -342.797677) (xy 115.91593 -342.81304) (xy 115.86194 -342.820799) (xy 115.834668 -342.82126)
			(xy 114.971068 -342.82126) (xy 114.9438 -342.820775) (xy 114.88982 -342.81301) (xy 114.837494 -342.797642)
			(xy 114.787887 -342.774984) (xy 114.74201 -342.745497) (xy 114.700796 -342.709781) (xy 114.665084 -342.668564)
			(xy 114.635601 -342.622685) (xy 114.612947 -342.573076) (xy 114.597583 -342.520749) (xy 114.589822 -342.466768)
			(xy 113.106974 -342.466768) (xy 113.106974 -342.466769) (xy 113.099212 -342.520751) (xy 113.083847 -342.57308)
			(xy 113.061192 -342.622689) (xy 113.031707 -342.66857) (xy 112.995993 -342.709787) (xy 112.954776 -342.745502)
			(xy 112.908897 -342.774988) (xy 112.859288 -342.797645) (xy 112.806959 -342.81301) (xy 112.752977 -342.820773)
			(xy 112.725708 -342.82126) (xy 111.862108 -342.82126) (xy 111.834836 -342.820801) (xy 111.780848 -342.81304)
			(xy 111.728515 -342.797674) (xy 111.6789 -342.775017) (xy 111.633015 -342.745529) (xy 111.591794 -342.709812)
			(xy 111.556075 -342.668591) (xy 111.526587 -342.622707) (xy 111.503929 -342.573093) (xy 111.488562 -342.520759)
			(xy 111.4808 -342.466772) (xy 104.085479 -342.466772) (xy 104.10629 -342.517011) (xy 104.121803 -342.574906)
			(xy 104.129627 -342.634331) (xy 104.129627 -342.694269) (xy 104.121803 -342.753694) (xy 104.10629 -342.811589)
			(xy 104.083352 -342.866964) (xy 104.053383 -342.918871) (xy 104.016895 -342.966422) (xy 103.974512 -343.008804)
			(xy 103.926959 -343.045291) (xy 103.875051 -343.075259) (xy 103.819676 -343.098195) (xy 103.76178 -343.113706)
			(xy 103.702355 -343.121528) (xy 103.672386 -343.121996) (xy 102.808786 -343.121996) (xy 102.778818 -343.121529)
			(xy 102.719395 -343.113704) (xy 102.661502 -343.09819) (xy 102.60613 -343.075253) (xy 102.554224 -343.045284)
			(xy 102.506675 -343.008796) (xy 102.464294 -342.966415) (xy 102.427809 -342.918864) (xy 102.397841 -342.866958)
			(xy 102.374905 -342.811584) (xy 102.359393 -342.753691) (xy 102.35157 -342.694268) (xy 93.60914 -342.694268)
			(xy 93.595705 -342.709775) (xy 93.554492 -342.74549) (xy 93.508617 -342.774977) (xy 93.459012 -342.797635)
			(xy 93.406688 -342.813004) (xy 93.352709 -342.820771) (xy 93.325442 -342.82126) (xy 92.461842 -342.82126)
			(xy 92.434569 -342.820803) (xy 92.380577 -342.813046) (xy 92.328239 -342.797683) (xy 92.278621 -342.775028)
			(xy 92.232731 -342.745541) (xy 92.191506 -342.709824) (xy 92.155784 -342.668602) (xy 92.126292 -342.622716)
			(xy 92.103631 -342.5731) (xy 92.088263 -342.520764) (xy 92.0805 -342.466773) (xy 90.597796 -342.466773)
			(xy 90.590034 -342.52076) (xy 90.574667 -342.573094) (xy 90.552008 -342.622708) (xy 90.522519 -342.668592)
			(xy 90.4868 -342.709812) (xy 90.445578 -342.74553) (xy 90.399692 -342.775017) (xy 90.350077 -342.797673)
			(xy 90.297742 -342.813038) (xy 90.243754 -342.820798) (xy 90.216482 -342.82126) (xy 89.352882 -342.82126)
			(xy 89.325613 -342.820776) (xy 89.271631 -342.813013) (xy 89.219304 -342.797646) (xy 89.169696 -342.774988)
			(xy 89.123817 -342.745502) (xy 89.082601 -342.709786) (xy 89.046887 -342.668569) (xy 89.017403 -342.622689)
			(xy 88.994748 -342.573079) (xy 88.979384 -342.520751) (xy 88.971622 -342.466769) (xy 87.488774 -342.466769)
			(xy 87.481013 -342.52075) (xy 87.465648 -342.573077) (xy 87.442994 -342.622686) (xy 87.41351 -342.668565)
			(xy 87.377798 -342.709782) (xy 87.336583 -342.745497) (xy 87.290705 -342.774983) (xy 87.241098 -342.797641)
			(xy 87.188771 -342.813008) (xy 87.13479 -342.820772) (xy 87.107522 -342.82126) (xy 86.243922 -342.82126)
			(xy 86.21665 -342.820802) (xy 86.16266 -342.813042) (xy 86.110325 -342.797678) (xy 86.060709 -342.775021)
			(xy 86.014822 -342.745534) (xy 85.973599 -342.709817) (xy 85.937879 -342.668596) (xy 85.908389 -342.622711)
			(xy 85.88573 -342.573096) (xy 85.870362 -342.520761) (xy 85.8626 -342.466772) (xy 84.379896 -342.466772)
			(xy 84.379896 -342.466773) (xy 84.372133 -342.520763) (xy 84.356765 -342.573098) (xy 84.334105 -342.622713)
			(xy 84.304614 -342.668599) (xy 84.268893 -342.70982) (xy 84.227668 -342.745537) (xy 84.18178 -342.775023)
			(xy 84.132162 -342.797679) (xy 84.079825 -342.813041) (xy 84.025835 -342.820799) (xy 83.998562 -342.82126)
			(xy 83.134962 -342.82126) (xy 83.107694 -342.820775) (xy 83.053714 -342.813009) (xy 83.001389 -342.79764)
			(xy 82.951784 -342.774982) (xy 82.905907 -342.745495) (xy 82.864694 -342.709779) (xy 82.828983 -342.668562)
			(xy 82.7995 -342.622683) (xy 82.776847 -342.573075) (xy 82.761483 -342.520748) (xy 82.753722 -342.466768)
			(xy 81.270874 -342.466768) (xy 81.270874 -342.466769) (xy 81.263112 -342.520752) (xy 81.247747 -342.573081)
			(xy 81.225091 -342.622691) (xy 81.195605 -342.668572) (xy 81.159891 -342.709789) (xy 81.118673 -342.745504)
			(xy 81.072793 -342.77499) (xy 81.023183 -342.797646) (xy 80.970854 -342.813012) (xy 80.916871 -342.820773)
			(xy 80.889602 -342.82126) (xy 80.026002 -342.82126) (xy 79.998731 -342.820801) (xy 79.944743 -342.813039)
			(xy 79.89241 -342.797673) (xy 79.842797 -342.775015) (xy 79.796912 -342.745527) (xy 79.755692 -342.70981)
			(xy 79.719974 -342.668589) (xy 79.690486 -342.622705) (xy 79.667828 -342.573092) (xy 79.652462 -342.520759)
			(xy 79.644699 -342.466771) (xy 78.161873 -342.466771) (xy 78.154113 -342.520747) (xy 78.13875 -342.573073)
			(xy 78.116097 -342.62268) (xy 78.086615 -342.668559) (xy 78.050905 -342.709775) (xy 78.009692 -342.74549)
			(xy 77.963817 -342.774977) (xy 77.914212 -342.797635) (xy 77.861888 -342.813004) (xy 77.807909 -342.820771)
			(xy 77.780642 -342.82126) (xy 76.917042 -342.82126) (xy 76.889769 -342.820803) (xy 76.835777 -342.813046)
			(xy 76.783439 -342.797683) (xy 76.733821 -342.775028) (xy 76.687931 -342.745541) (xy 76.646706 -342.709824)
			(xy 76.610984 -342.668602) (xy 76.581492 -342.622716) (xy 76.558831 -342.5731) (xy 76.543463 -342.520764)
			(xy 76.5357 -342.466773) (xy 75.052996 -342.466773) (xy 75.045234 -342.52076) (xy 75.029867 -342.573094)
			(xy 75.007208 -342.622708) (xy 74.977719 -342.668592) (xy 74.942 -342.709812) (xy 74.900778 -342.74553)
			(xy 74.854892 -342.775017) (xy 74.805277 -342.797673) (xy 74.752942 -342.813038) (xy 74.698954 -342.820798)
			(xy 74.671682 -342.82126) (xy 73.808082 -342.82126) (xy 73.780813 -342.820776) (xy 73.726831 -342.813013)
			(xy 73.674504 -342.797646) (xy 73.624896 -342.774988) (xy 73.579017 -342.745502) (xy 73.537801 -342.709786)
			(xy 73.502087 -342.668569) (xy 73.472603 -342.622689) (xy 73.449948 -342.573079) (xy 73.434584 -342.520751)
			(xy 73.426822 -342.466769) (xy 71.943974 -342.466769) (xy 71.936213 -342.52075) (xy 71.920848 -342.573077)
			(xy 71.898194 -342.622686) (xy 71.86871 -342.668565) (xy 71.832998 -342.709782) (xy 71.791783 -342.745497)
			(xy 71.745905 -342.774983) (xy 71.696298 -342.797641) (xy 71.643971 -342.813008) (xy 71.58999 -342.820772)
			(xy 71.562722 -342.82126) (xy 70.699122 -342.82126) (xy 70.67185 -342.820802) (xy 70.61786 -342.813042)
			(xy 70.565525 -342.797678) (xy 70.515909 -342.775021) (xy 70.470022 -342.745534) (xy 70.428799 -342.709817)
			(xy 70.393079 -342.668596) (xy 70.363589 -342.622711) (xy 70.34093 -342.573096) (xy 70.325562 -342.520761)
			(xy 70.3178 -342.466772) (xy 68.835096 -342.466772) (xy 68.835096 -342.466773) (xy 68.827333 -342.520763)
			(xy 68.811965 -342.573098) (xy 68.789305 -342.622713) (xy 68.759814 -342.668599) (xy 68.724093 -342.70982)
			(xy 68.682868 -342.745537) (xy 68.63698 -342.775023) (xy 68.587362 -342.797679) (xy 68.535025 -342.813041)
			(xy 68.481035 -342.820799) (xy 68.453762 -342.82126) (xy 67.590162 -342.82126) (xy 67.562894 -342.820775)
			(xy 67.508914 -342.813009) (xy 67.456589 -342.79764) (xy 67.406984 -342.774982) (xy 67.361107 -342.745495)
			(xy 67.319894 -342.709779) (xy 67.284183 -342.668562) (xy 67.2547 -342.622683) (xy 67.232047 -342.573075)
			(xy 67.216683 -342.520748) (xy 67.208922 -342.466768) (xy 65.726074 -342.466768) (xy 65.726074 -342.466769)
			(xy 65.718312 -342.520752) (xy 65.702947 -342.573081) (xy 65.680291 -342.622691) (xy 65.650805 -342.668572)
			(xy 65.615091 -342.709789) (xy 65.573873 -342.745504) (xy 65.527993 -342.77499) (xy 65.478383 -342.797646)
			(xy 65.426054 -342.813012) (xy 65.372071 -342.820773) (xy 65.344802 -342.82126) (xy 64.481202 -342.82126)
			(xy 64.453931 -342.820801) (xy 64.399943 -342.813039) (xy 64.34761 -342.797673) (xy 64.297997 -342.775015)
			(xy 64.252112 -342.745527) (xy 64.210892 -342.70981) (xy 64.175174 -342.668589) (xy 64.145686 -342.622705)
			(xy 64.123028 -342.573092) (xy 64.107662 -342.520759) (xy 64.099899 -342.466771) (xy 62.757244 -342.466771)
			(xy 62.756819 -342.490646) (xy 62.749061 -342.544634) (xy 62.733698 -342.596969) (xy 62.711044 -342.646585)
			(xy 62.68156 -342.692473) (xy 62.645845 -342.733697) (xy 62.604627 -342.769419) (xy 62.558745 -342.798912)
			(xy 62.509133 -342.821574) (xy 62.456801 -342.836946) (xy 62.402814 -342.844715) (xy 62.375542 -342.845136)
			(xy 61.511942 -342.845136) (xy 61.480029 -342.844486) (xy 61.41709 -342.83388) (xy 61.38672 -342.824054)
			(xy 61.382723 -342.822703) (xy 61.374426 -342.821171) (xy 61.37021 -342.821006) (xy 61.349197 -342.820605)
			(xy 61.307446 -342.815768) (xy 61.286898 -342.811354) (xy 61.279278 -342.80983) (xy 61.2648 -342.810592)
			(xy 61.223652 -342.82634) (xy 61.213758 -342.830562) (xy 61.198497 -342.845694) (xy 61.194188 -342.85555)
			(xy 60.966582 -343.446862) (xy 101.207568 -343.446862) (xy 101.211639 -343.39124) (xy 101.223765 -343.336803)
			(xy 101.243688 -343.284712) (xy 101.270984 -343.236077) (xy 101.30507 -343.191934) (xy 101.345219 -343.153225)
			(xy 101.390577 -343.120774) (xy 101.440177 -343.095273) (xy 101.492961 -343.077266) (xy 101.547804 -343.067136)
			(xy 101.603538 -343.065099) (xy 101.658975 -343.071199) (xy 101.712932 -343.085305) (xy 101.764261 -343.107117)
			(xy 101.811867 -343.136171) (xy 101.854735 -343.171846) (xy 101.891952 -343.213383) (xy 101.922725 -343.259896)
			(xy 101.946397 -343.310393) (xy 101.962465 -343.3638) (xy 101.970585 -343.418976) (xy 101.971094 -343.446862)
			(xy 101.970585 -343.474748) (xy 101.962465 -343.529924) (xy 101.946397 -343.583331) (xy 101.922725 -343.633828)
			(xy 101.891952 -343.680341) (xy 101.854735 -343.721878) (xy 101.811867 -343.757553) (xy 101.764261 -343.786607)
			(xy 101.712932 -343.808419) (xy 101.658975 -343.822525) (xy 101.603538 -343.828625) (xy 101.547804 -343.826588)
			(xy 101.492961 -343.816458) (xy 101.440177 -343.798451) (xy 101.390577 -343.77295) (xy 101.345219 -343.740499)
			(xy 101.30507 -343.70179) (xy 101.270984 -343.657647) (xy 101.243688 -343.609012) (xy 101.223765 -343.556921)
			(xy 101.211639 -343.502484) (xy 101.207568 -343.446862) (xy 60.966582 -343.446862) (xy 60.179231 -345.49237)
			(xy 60.990948 -345.49237) (xy 60.990948 -345.43783) (xy 60.99871 -345.383846) (xy 61.014076 -345.331517)
			(xy 61.036734 -345.281907) (xy 61.066222 -345.236026) (xy 61.10194 -345.19481) (xy 61.14316 -345.159097)
			(xy 61.189044 -345.129614) (xy 61.238656 -345.106962) (xy 61.290987 -345.091601) (xy 61.344972 -345.083845)
			(xy 61.372242 -345.083384) (xy 62.235842 -345.083384) (xy 62.263113 -345.083781) (xy 62.317098 -345.091549)
			(xy 62.369429 -345.10692) (xy 62.41904 -345.129581) (xy 62.464921 -345.159072) (xy 62.506139 -345.194791)
			(xy 62.541854 -345.236013) (xy 62.571339 -345.281897) (xy 62.593995 -345.33151) (xy 62.60936 -345.383843)
			(xy 62.617122 -345.437829) (xy 62.617122 -345.492368) (xy 64.099947 -345.492368) (xy 64.099947 -345.437832)
			(xy 64.107709 -345.383852) (xy 64.123073 -345.331525) (xy 64.145728 -345.281918) (xy 64.175212 -345.23604)
			(xy 64.210926 -345.194824) (xy 64.252141 -345.159111) (xy 64.29802 -345.129627) (xy 64.347627 -345.106972)
			(xy 64.399954 -345.091608) (xy 64.453934 -345.083847) (xy 64.481202 -345.083384) (xy 65.344802 -345.083384)
			(xy 65.372075 -345.083779) (xy 65.426064 -345.091542) (xy 65.4784 -345.106909) (xy 65.528016 -345.129568)
			(xy 65.573902 -345.159057) (xy 65.615124 -345.194777) (xy 65.650844 -345.236) (xy 65.680333 -345.281886)
			(xy 65.702992 -345.331502) (xy 65.718359 -345.383838) (xy 65.726121 -345.437827) (xy 65.726121 -345.492364)
			(xy 67.20897 -345.492364) (xy 67.20897 -345.437836) (xy 67.21673 -345.383862) (xy 67.232092 -345.331542)
			(xy 67.254742 -345.28194) (xy 67.284221 -345.236066) (xy 67.319928 -345.194855) (xy 67.361136 -345.159144)
			(xy 67.407007 -345.12966) (xy 67.456606 -345.107005) (xy 67.508925 -345.091638) (xy 67.562898 -345.083873)
			(xy 67.590162 -345.083384) (xy 68.453762 -345.083384) (xy 68.481038 -345.083753) (xy 68.535036 -345.091512)
			(xy 68.587379 -345.106877) (xy 68.637003 -345.129535) (xy 68.682897 -345.159025) (xy 68.724127 -345.194747)
			(xy 68.759852 -345.235973) (xy 68.789347 -345.281864) (xy 68.81201 -345.331485) (xy 68.82738 -345.383827)
			(xy 68.835144 -345.437824) (xy 68.835144 -345.492369) (xy 70.317847 -345.492369) (xy 70.317847 -345.437831)
			(xy 70.325609 -345.383849) (xy 70.340975 -345.331521) (xy 70.363631 -345.281912) (xy 70.393117 -345.236033)
			(xy 70.428833 -345.194817) (xy 70.470051 -345.159104) (xy 70.515932 -345.129621) (xy 70.565541 -345.106967)
			(xy 70.617871 -345.091605) (xy 70.671853 -345.083846) (xy 70.699122 -345.083384) (xy 71.562722 -345.083384)
			(xy 71.589994 -345.08378) (xy 71.643981 -345.091545) (xy 71.696315 -345.106914) (xy 71.745928 -345.129574)
			(xy 71.791812 -345.159064) (xy 71.833032 -345.194784) (xy 71.868749 -345.236006) (xy 71.898236 -345.281891)
			(xy 71.920893 -345.331506) (xy 71.936259 -345.38384) (xy 71.944022 -345.437828) (xy 71.944022 -345.492365)
			(xy 73.42687 -345.492365) (xy 73.42687 -345.437835) (xy 73.434631 -345.383859) (xy 73.449993 -345.331537)
			(xy 73.472645 -345.281934) (xy 73.502126 -345.23606) (xy 73.537835 -345.194848) (xy 73.579045 -345.159137)
			(xy 73.624919 -345.129654) (xy 73.674521 -345.106999) (xy 73.726842 -345.091634) (xy 73.780817 -345.083872)
			(xy 73.808082 -345.083384) (xy 74.671682 -345.083384) (xy 74.698957 -345.083754) (xy 74.752952 -345.091515)
			(xy 74.805294 -345.106882) (xy 74.854915 -345.129541) (xy 74.900806 -345.159032) (xy 74.942034 -345.194754)
			(xy 74.977757 -345.235979) (xy 75.00725 -345.281869) (xy 75.029912 -345.33149) (xy 75.045281 -345.38383)
			(xy 75.053044 -345.437825) (xy 75.053044 -345.49237) (xy 76.535748 -345.49237) (xy 76.535748 -345.43783)
			(xy 76.54351 -345.383846) (xy 76.558876 -345.331517) (xy 76.581534 -345.281907) (xy 76.611022 -345.236026)
			(xy 76.64674 -345.19481) (xy 76.68796 -345.159097) (xy 76.733844 -345.129614) (xy 76.783456 -345.106962)
			(xy 76.835787 -345.091601) (xy 76.889772 -345.083845) (xy 76.917042 -345.083384) (xy 77.780642 -345.083384)
			(xy 77.807913 -345.083781) (xy 77.861898 -345.091549) (xy 77.914229 -345.10692) (xy 77.96384 -345.129581)
			(xy 78.009721 -345.159072) (xy 78.050939 -345.194791) (xy 78.086654 -345.236013) (xy 78.116139 -345.281897)
			(xy 78.138795 -345.33151) (xy 78.15416 -345.383843) (xy 78.161922 -345.437829) (xy 78.161922 -345.492368)
			(xy 79.644747 -345.492368) (xy 79.644747 -345.437832) (xy 79.652509 -345.383852) (xy 79.667873 -345.331525)
			(xy 79.690528 -345.281918) (xy 79.720012 -345.23604) (xy 79.755726 -345.194824) (xy 79.796941 -345.159111)
			(xy 79.84282 -345.129627) (xy 79.892427 -345.106972) (xy 79.944754 -345.091608) (xy 79.998734 -345.083847)
			(xy 80.026002 -345.083384) (xy 80.889602 -345.083384) (xy 80.916875 -345.083779) (xy 80.970864 -345.091542)
			(xy 81.0232 -345.106909) (xy 81.072816 -345.129568) (xy 81.118702 -345.159057) (xy 81.159924 -345.194777)
			(xy 81.195644 -345.236) (xy 81.225133 -345.281886) (xy 81.247792 -345.331502) (xy 81.263159 -345.383838)
			(xy 81.270921 -345.437827) (xy 81.270921 -345.492364) (xy 82.75377 -345.492364) (xy 82.75377 -345.437836)
			(xy 82.76153 -345.383862) (xy 82.776892 -345.331542) (xy 82.799542 -345.28194) (xy 82.829021 -345.236066)
			(xy 82.864728 -345.194855) (xy 82.905936 -345.159144) (xy 82.951807 -345.12966) (xy 83.001406 -345.107005)
			(xy 83.053725 -345.091638) (xy 83.107698 -345.083873) (xy 83.134962 -345.083384) (xy 83.998562 -345.083384)
			(xy 84.025838 -345.083753) (xy 84.079836 -345.091512) (xy 84.132179 -345.106877) (xy 84.181803 -345.129535)
			(xy 84.227697 -345.159025) (xy 84.268927 -345.194747) (xy 84.304652 -345.235973) (xy 84.334147 -345.281864)
			(xy 84.35681 -345.331485) (xy 84.37218 -345.383827) (xy 84.379944 -345.437824) (xy 84.379944 -345.492369)
			(xy 85.862647 -345.492369) (xy 85.862647 -345.437831) (xy 85.870409 -345.383849) (xy 85.885775 -345.331521)
			(xy 85.908431 -345.281912) (xy 85.937917 -345.236033) (xy 85.973633 -345.194817) (xy 86.014851 -345.159104)
			(xy 86.060732 -345.129621) (xy 86.110341 -345.106967) (xy 86.162671 -345.091605) (xy 86.216653 -345.083846)
			(xy 86.243922 -345.083384) (xy 87.107522 -345.083384) (xy 87.134794 -345.08378) (xy 87.188781 -345.091545)
			(xy 87.241115 -345.106914) (xy 87.290728 -345.129574) (xy 87.336612 -345.159064) (xy 87.377832 -345.194784)
			(xy 87.413549 -345.236006) (xy 87.443036 -345.281891) (xy 87.465693 -345.331506) (xy 87.481059 -345.38384)
			(xy 87.488822 -345.437828) (xy 87.488822 -345.492365) (xy 88.97167 -345.492365) (xy 88.97167 -345.437835)
			(xy 88.979431 -345.383859) (xy 88.994793 -345.331537) (xy 89.017445 -345.281934) (xy 89.046926 -345.23606)
			(xy 89.082635 -345.194848) (xy 89.123845 -345.159137) (xy 89.169719 -345.129654) (xy 89.219321 -345.106999)
			(xy 89.271642 -345.091634) (xy 89.325617 -345.083872) (xy 89.352882 -345.083384) (xy 90.216482 -345.083384)
			(xy 90.243757 -345.083754) (xy 90.297752 -345.091515) (xy 90.350094 -345.106882) (xy 90.399715 -345.129541)
			(xy 90.445606 -345.159032) (xy 90.486834 -345.194754) (xy 90.522557 -345.235979) (xy 90.55205 -345.281869)
			(xy 90.574712 -345.33149) (xy 90.590081 -345.38383) (xy 90.597844 -345.437825) (xy 90.597844 -345.49237)
			(xy 92.080548 -345.49237) (xy 92.080548 -345.43783) (xy 92.08831 -345.383846) (xy 92.103676 -345.331517)
			(xy 92.126334 -345.281907) (xy 92.155822 -345.236026) (xy 92.19154 -345.19481) (xy 92.23276 -345.159097)
			(xy 92.278644 -345.129614) (xy 92.328256 -345.106962) (xy 92.380587 -345.091601) (xy 92.434572 -345.083845)
			(xy 92.461842 -345.083384) (xy 93.325442 -345.083384) (xy 93.352713 -345.083781) (xy 93.406698 -345.091549)
			(xy 93.459029 -345.10692) (xy 93.50864 -345.129581) (xy 93.554521 -345.159072) (xy 93.595739 -345.194791)
			(xy 93.625314 -345.228926) (xy 105.613452 -345.228926) (xy 105.617523 -345.173304) (xy 105.629649 -345.118867)
			(xy 105.649572 -345.066776) (xy 105.676868 -345.018141) (xy 105.710954 -344.973998) (xy 105.751103 -344.935289)
			(xy 105.796461 -344.902838) (xy 105.846061 -344.877337) (xy 105.898845 -344.85933) (xy 105.953688 -344.8492)
			(xy 106.009422 -344.847163) (xy 106.064859 -344.853263) (xy 106.118816 -344.867369) (xy 106.170145 -344.889181)
			(xy 106.217751 -344.918235) (xy 106.260619 -344.95391) (xy 106.297836 -344.995447) (xy 106.328609 -345.04196)
			(xy 106.352281 -345.092457) (xy 106.368349 -345.145864) (xy 106.376469 -345.20104) (xy 106.376978 -345.228926)
			(xy 106.376469 -345.256812) (xy 106.368349 -345.311988) (xy 106.352281 -345.365395) (xy 106.328609 -345.415892)
			(xy 106.297836 -345.462405) (xy 106.260619 -345.503942) (xy 106.217751 -345.539617) (xy 106.174964 -345.56573)
			(xy 107.785662 -345.56573) (xy 107.786148 -345.539579) (xy 107.793301 -345.487769) (xy 107.807463 -345.437422)
			(xy 107.828368 -345.38948) (xy 107.855624 -345.344842) (xy 107.888722 -345.304345) (xy 107.927041 -345.268749)
			(xy 107.969862 -345.238719) (xy 107.992926 -345.226386) (xy 108.004967 -345.21971) (xy 108.025252 -345.201113)
			(xy 108.039828 -345.177771) (xy 108.047635 -345.151382) (xy 108.048105 -345.123867) (xy 108.041203 -345.097227)
			(xy 108.027431 -345.073401) (xy 108.007792 -345.054123) (xy 107.995974 -345.047062) (xy 107.970936 -345.032486)
			(xy 107.925169 -344.996967) (xy 107.885299 -344.954935) (xy 107.852244 -344.907358) (xy 107.826763 -344.85533)
			(xy 107.809442 -344.800047) (xy 107.800679 -344.74278) (xy 107.80014 -344.713814) (xy 107.800626 -344.686563)
			(xy 107.808382 -344.632615) (xy 107.823737 -344.58032) (xy 107.846379 -344.530743) (xy 107.875845 -344.484893)
			(xy 107.911536 -344.443702) (xy 107.952727 -344.408011) (xy 107.998577 -344.378545) (xy 108.048154 -344.355903)
			(xy 108.100449 -344.340548) (xy 108.154397 -344.332792) (xy 108.208899 -344.332792) (xy 108.262847 -344.340548)
			(xy 108.315142 -344.355903) (xy 108.364719 -344.378545) (xy 108.410569 -344.408011) (xy 108.45176 -344.443702)
			(xy 108.487451 -344.484893) (xy 108.516917 -344.530743) (xy 108.539559 -344.58032) (xy 108.554914 -344.632615)
			(xy 108.56267 -344.686563) (xy 108.563156 -344.713814) (xy 108.562696 -344.739965) (xy 108.555538 -344.791776)
			(xy 108.541371 -344.842124) (xy 108.520462 -344.890066) (xy 108.493202 -344.934703) (xy 108.460101 -344.975199)
			(xy 108.42178 -345.010796) (xy 108.378957 -345.040825) (xy 108.355892 -345.053158) (xy 108.343811 -345.059769)
			(xy 108.323518 -345.078376) (xy 108.308939 -345.10173) (xy 108.301132 -345.128132) (xy 108.300668 -345.155659)
			(xy 108.30758 -345.182309) (xy 108.321364 -345.206141) (xy 108.341018 -345.225421) (xy 108.352844 -345.232482)
			(xy 108.377882 -345.247058) (xy 108.423653 -345.282574) (xy 108.463526 -345.324604) (xy 108.496584 -345.372181)
			(xy 108.522065 -345.42421) (xy 108.539383 -345.479495) (xy 108.541352 -345.492368) (xy 111.480847 -345.492368)
			(xy 111.480847 -345.437832) (xy 111.488609 -345.383851) (xy 111.503974 -345.331524) (xy 111.526629 -345.281916)
			(xy 111.556114 -345.236038) (xy 111.591828 -345.194822) (xy 111.633044 -345.159109) (xy 111.678923 -345.129625)
			(xy 111.728531 -345.106971) (xy 111.780859 -345.091607) (xy 111.83484 -345.083847) (xy 111.862108 -345.083384)
			(xy 112.725708 -345.083384) (xy 112.75298 -345.083779) (xy 112.80697 -345.091543) (xy 112.859304 -345.106911)
			(xy 112.90892 -345.12957) (xy 112.954805 -345.15906) (xy 112.996027 -345.194779) (xy 113.031745 -345.236001)
			(xy 113.061234 -345.281888) (xy 113.083892 -345.331503) (xy 113.099259 -345.383838) (xy 113.107021 -345.437828)
			(xy 113.107021 -345.492365) (xy 114.58987 -345.492365) (xy 114.58987 -345.437835) (xy 114.59763 -345.383861)
			(xy 114.612992 -345.33154) (xy 114.635643 -345.281938) (xy 114.665122 -345.236064) (xy 114.70083 -345.194853)
			(xy 114.742039 -345.159142) (xy 114.78791 -345.129658) (xy 114.83751 -345.107003) (xy 114.88983 -345.091637)
			(xy 114.943803 -345.083872) (xy 114.971068 -345.083384) (xy 115.834668 -345.083384) (xy 115.861944 -345.083753)
			(xy 115.915941 -345.091513) (xy 115.968283 -345.106878) (xy 116.017907 -345.129537) (xy 116.0638 -345.159027)
			(xy 116.105029 -345.194749) (xy 116.140754 -345.235975) (xy 116.170248 -345.281865) (xy 116.192911 -345.331487)
			(xy 116.20828 -345.383828) (xy 116.216044 -345.437824) (xy 116.216044 -345.492369) (xy 117.698747 -345.492369)
			(xy 117.698747 -345.437831) (xy 117.706509 -345.383848) (xy 117.721875 -345.33152) (xy 117.744532 -345.281911)
			(xy 117.774019 -345.236031) (xy 117.809735 -345.194815) (xy 117.850953 -345.159102) (xy 117.896835 -345.129619)
			(xy 117.946446 -345.106965) (xy 117.998776 -345.091603) (xy 118.052759 -345.083845) (xy 118.080028 -345.083384)
			(xy 118.943628 -345.083384) (xy 118.970899 -345.08378) (xy 119.024886 -345.091546) (xy 119.077219 -345.106916)
			(xy 119.126832 -345.129576) (xy 119.172714 -345.159067) (xy 119.213934 -345.194786) (xy 119.24965 -345.236008)
			(xy 119.279137 -345.281893) (xy 119.301794 -345.331507) (xy 119.31716 -345.383841) (xy 119.324922 -345.437829)
			(xy 119.324922 -345.492366) (xy 120.80777 -345.492366) (xy 120.80777 -345.437834) (xy 120.815531 -345.383858)
			(xy 120.830894 -345.331536) (xy 120.853546 -345.281933) (xy 120.883027 -345.236058) (xy 120.918737 -345.194846)
			(xy 120.959948 -345.159135) (xy 121.005822 -345.129652) (xy 121.055425 -345.106998) (xy 121.107747 -345.091633)
			(xy 121.161722 -345.083871) (xy 121.188988 -345.083384) (xy 122.052588 -345.083384) (xy 122.079863 -345.083755)
			(xy 122.133857 -345.091516) (xy 122.186198 -345.106884) (xy 122.235819 -345.129543) (xy 122.281709 -345.159034)
			(xy 122.322936 -345.194756) (xy 122.358659 -345.235981) (xy 122.388151 -345.281871) (xy 122.410812 -345.331491)
			(xy 122.426181 -345.383831) (xy 122.433944 -345.437825) (xy 122.433944 -345.49237) (xy 123.916648 -345.49237)
			(xy 123.916648 -345.43783) (xy 123.92441 -345.383846) (xy 123.939777 -345.331515) (xy 123.962435 -345.281905)
			(xy 123.991924 -345.236024) (xy 124.027642 -345.194808) (xy 124.068863 -345.159095) (xy 124.114747 -345.129612)
			(xy 124.16436 -345.10696) (xy 124.216692 -345.0916) (xy 124.270678 -345.083844) (xy 124.297948 -345.083384)
			(xy 125.161548 -345.083384) (xy 125.188818 -345.083782) (xy 125.242803 -345.09155) (xy 125.295133 -345.106921)
			(xy 125.344744 -345.129583) (xy 125.390624 -345.159074) (xy 125.431841 -345.194793) (xy 125.467555 -345.236015)
			(xy 125.49704 -345.281899) (xy 125.519695 -345.331512) (xy 125.53506 -345.383844) (xy 125.542822 -345.43783)
			(xy 125.542822 -345.492368) (xy 127.025647 -345.492368) (xy 127.025647 -345.437832) (xy 127.033409 -345.383851)
			(xy 127.048774 -345.331524) (xy 127.071429 -345.281916) (xy 127.100914 -345.236038) (xy 127.136628 -345.194822)
			(xy 127.177844 -345.159109) (xy 127.223723 -345.129625) (xy 127.273331 -345.106971) (xy 127.325659 -345.091607)
			(xy 127.37964 -345.083847) (xy 127.406908 -345.083384) (xy 128.270508 -345.083384) (xy 128.29778 -345.083779)
			(xy 128.35177 -345.091543) (xy 128.404104 -345.106911) (xy 128.45372 -345.12957) (xy 128.499605 -345.15906)
			(xy 128.540827 -345.194779) (xy 128.576545 -345.236001) (xy 128.606034 -345.281888) (xy 128.628692 -345.331503)
			(xy 128.644059 -345.383838) (xy 128.651821 -345.437828) (xy 128.651821 -345.492365) (xy 130.13467 -345.492365)
			(xy 130.13467 -345.437835) (xy 130.14243 -345.383861) (xy 130.157792 -345.33154) (xy 130.180443 -345.281938)
			(xy 130.209922 -345.236064) (xy 130.24563 -345.194853) (xy 130.286839 -345.159142) (xy 130.33271 -345.129658)
			(xy 130.38231 -345.107003) (xy 130.43463 -345.091637) (xy 130.488603 -345.083872) (xy 130.515868 -345.083384)
			(xy 131.379468 -345.083384) (xy 131.406744 -345.083753) (xy 131.460741 -345.091513) (xy 131.513083 -345.106878)
			(xy 131.562707 -345.129537) (xy 131.6086 -345.159027) (xy 131.649829 -345.194749) (xy 131.685554 -345.235975)
			(xy 131.715048 -345.281865) (xy 131.737711 -345.331487) (xy 131.75308 -345.383828) (xy 131.760844 -345.437824)
			(xy 131.760844 -345.492369) (xy 133.243547 -345.492369) (xy 133.243547 -345.437831) (xy 133.251309 -345.383848)
			(xy 133.266675 -345.33152) (xy 133.289332 -345.281911) (xy 133.318819 -345.236031) (xy 133.354535 -345.194815)
			(xy 133.395753 -345.159102) (xy 133.441635 -345.129619) (xy 133.491246 -345.106965) (xy 133.543576 -345.091603)
			(xy 133.597559 -345.083845) (xy 133.624828 -345.083384) (xy 134.488428 -345.083384) (xy 134.515699 -345.08378)
			(xy 134.569686 -345.091546) (xy 134.622019 -345.106916) (xy 134.671632 -345.129576) (xy 134.717514 -345.159067)
			(xy 134.758734 -345.194786) (xy 134.79445 -345.236008) (xy 134.823937 -345.281893) (xy 134.846594 -345.331507)
			(xy 134.86196 -345.383841) (xy 134.869722 -345.437829) (xy 134.869722 -345.492366) (xy 136.35257 -345.492366)
			(xy 136.35257 -345.437834) (xy 136.360331 -345.383858) (xy 136.375694 -345.331536) (xy 136.398346 -345.281933)
			(xy 136.427827 -345.236058) (xy 136.463537 -345.194846) (xy 136.504748 -345.159135) (xy 136.550622 -345.129652)
			(xy 136.600225 -345.106998) (xy 136.652547 -345.091633) (xy 136.706522 -345.083871) (xy 136.733788 -345.083384)
			(xy 137.597388 -345.083384) (xy 137.624663 -345.083755) (xy 137.678657 -345.091516) (xy 137.730998 -345.106884)
			(xy 137.780619 -345.129543) (xy 137.826509 -345.159034) (xy 137.867736 -345.194756) (xy 137.903459 -345.235981)
			(xy 137.932951 -345.281871) (xy 137.955612 -345.331491) (xy 137.970981 -345.383831) (xy 137.978744 -345.437825)
			(xy 137.978744 -345.49237) (xy 139.461448 -345.49237) (xy 139.461448 -345.43783) (xy 139.46921 -345.383846)
			(xy 139.484577 -345.331515) (xy 139.507235 -345.281905) (xy 139.536724 -345.236024) (xy 139.572442 -345.194808)
			(xy 139.613663 -345.159095) (xy 139.659547 -345.129612) (xy 139.70916 -345.10696) (xy 139.761492 -345.0916)
			(xy 139.815478 -345.083844) (xy 139.842748 -345.083384) (xy 140.706348 -345.083384) (xy 140.733618 -345.083782)
			(xy 140.787603 -345.09155) (xy 140.839933 -345.106921) (xy 140.889544 -345.129583) (xy 140.935424 -345.159074)
			(xy 140.976641 -345.194793) (xy 141.012355 -345.236015) (xy 141.04184 -345.281899) (xy 141.064495 -345.331512)
			(xy 141.07986 -345.383844) (xy 141.087622 -345.43783) (xy 141.087622 -345.492368) (xy 142.570447 -345.492368)
			(xy 142.570447 -345.437832) (xy 142.578209 -345.383851) (xy 142.593574 -345.331524) (xy 142.616229 -345.281916)
			(xy 142.645714 -345.236038) (xy 142.681428 -345.194822) (xy 142.722644 -345.159109) (xy 142.768523 -345.129625)
			(xy 142.818131 -345.106971) (xy 142.870459 -345.091607) (xy 142.92444 -345.083847) (xy 142.951708 -345.083384)
			(xy 143.815308 -345.083384) (xy 143.84258 -345.083779) (xy 143.89657 -345.091543) (xy 143.948904 -345.106911)
			(xy 143.99852 -345.12957) (xy 144.044405 -345.15906) (xy 144.085627 -345.194779) (xy 144.121345 -345.236001)
			(xy 144.150834 -345.281888) (xy 144.173492 -345.331503) (xy 144.188859 -345.383838) (xy 144.196621 -345.437828)
			(xy 144.196621 -345.492372) (xy 144.188859 -345.546362) (xy 144.173492 -345.598697) (xy 144.150834 -345.648312)
			(xy 144.121345 -345.694199) (xy 144.085627 -345.735421) (xy 144.044405 -345.77114) (xy 143.99852 -345.80063)
			(xy 143.948904 -345.82329) (xy 143.89657 -345.838657) (xy 143.84258 -345.846421) (xy 143.815308 -345.846908)
			(xy 142.951708 -345.846908) (xy 142.92444 -345.846353) (xy 142.870459 -345.838593) (xy 142.818131 -345.823229)
			(xy 142.768523 -345.800575) (xy 142.722644 -345.771091) (xy 142.681428 -345.735378) (xy 142.645714 -345.694162)
			(xy 142.616229 -345.648284) (xy 142.593574 -345.598676) (xy 142.578209 -345.546349) (xy 142.570447 -345.492368)
			(xy 141.087622 -345.492368) (xy 141.087622 -345.49237) (xy 141.07986 -345.546356) (xy 141.064495 -345.598688)
			(xy 141.04184 -345.648301) (xy 141.012355 -345.694185) (xy 140.976641 -345.735407) (xy 140.935424 -345.771126)
			(xy 140.889543 -345.800617) (xy 140.839933 -345.823279) (xy 140.787603 -345.83865) (xy 140.733618 -345.846418)
			(xy 140.706348 -345.846908) (xy 139.842748 -345.846908) (xy 139.815478 -345.846356) (xy 139.761492 -345.8386)
			(xy 139.70916 -345.82324) (xy 139.659547 -345.800588) (xy 139.613663 -345.771105) (xy 139.572442 -345.735392)
			(xy 139.536724 -345.694176) (xy 139.507235 -345.648295) (xy 139.484577 -345.598685) (xy 139.46921 -345.546354)
			(xy 139.461448 -345.49237) (xy 137.978744 -345.49237) (xy 137.978744 -345.492375) (xy 137.970981 -345.546369)
			(xy 137.955612 -345.598709) (xy 137.932951 -345.648329) (xy 137.903459 -345.694219) (xy 137.867736 -345.735444)
			(xy 137.826509 -345.771166) (xy 137.780619 -345.800657) (xy 137.730998 -345.823316) (xy 137.678658 -345.838684)
			(xy 137.624663 -345.846445) (xy 137.597388 -345.846908) (xy 136.733788 -345.846908) (xy 136.706522 -345.846329)
			(xy 136.652547 -345.838567) (xy 136.600225 -345.823202) (xy 136.550622 -345.800548) (xy 136.504748 -345.771065)
			(xy 136.463537 -345.735354) (xy 136.427827 -345.694142) (xy 136.398346 -345.648267) (xy 136.375694 -345.598664)
			(xy 136.360331 -345.546342) (xy 136.35257 -345.492366) (xy 134.869722 -345.492366) (xy 134.869722 -345.492371)
			(xy 134.86196 -345.546359) (xy 134.846594 -345.598693) (xy 134.823937 -345.648307) (xy 134.79445 -345.694192)
			(xy 134.758734 -345.735414) (xy 134.717514 -345.771133) (xy 134.671632 -345.800624) (xy 134.622019 -345.823284)
			(xy 134.569686 -345.838654) (xy 134.515699 -345.84642) (xy 134.488428 -345.846908) (xy 133.624828 -345.846908)
			(xy 133.597559 -345.846355) (xy 133.543576 -345.838597) (xy 133.491246 -345.823235) (xy 133.441635 -345.800581)
			(xy 133.395753 -345.771098) (xy 133.354535 -345.735385) (xy 133.318819 -345.694169) (xy 133.289332 -345.648289)
			(xy 133.266675 -345.59868) (xy 133.251309 -345.546352) (xy 133.243547 -345.492369) (xy 131.760844 -345.492369)
			(xy 131.760844 -345.492376) (xy 131.75308 -345.546372) (xy 131.737711 -345.598713) (xy 131.715048 -345.648335)
			(xy 131.685554 -345.694225) (xy 131.649829 -345.735451) (xy 131.6086 -345.771173) (xy 131.562707 -345.800663)
			(xy 131.513083 -345.823322) (xy 131.460741 -345.838687) (xy 131.406744 -345.846447) (xy 131.379468 -345.846908)
			(xy 130.515868 -345.846908) (xy 130.488603 -345.846328) (xy 130.43463 -345.838563) (xy 130.38231 -345.823197)
			(xy 130.33271 -345.800542) (xy 130.286839 -345.771058) (xy 130.24563 -345.735347) (xy 130.209922 -345.694136)
			(xy 130.180443 -345.648262) (xy 130.157792 -345.59866) (xy 130.14243 -345.546339) (xy 130.13467 -345.492365)
			(xy 128.651821 -345.492365) (xy 128.651821 -345.492372) (xy 128.644059 -345.546362) (xy 128.628692 -345.598697)
			(xy 128.606034 -345.648312) (xy 128.576545 -345.694199) (xy 128.540827 -345.735421) (xy 128.499605 -345.77114)
			(xy 128.45372 -345.80063) (xy 128.404104 -345.82329) (xy 128.35177 -345.838657) (xy 128.29778 -345.846421)
			(xy 128.270508 -345.846908) (xy 127.406908 -345.846908) (xy 127.37964 -345.846353) (xy 127.325659 -345.838593)
			(xy 127.273331 -345.823229) (xy 127.223723 -345.800575) (xy 127.177844 -345.771091) (xy 127.136628 -345.735378)
			(xy 127.100914 -345.694162) (xy 127.071429 -345.648284) (xy 127.048774 -345.598676) (xy 127.033409 -345.546349)
			(xy 127.025647 -345.492368) (xy 125.542822 -345.492368) (xy 125.542822 -345.49237) (xy 125.53506 -345.546356)
			(xy 125.519695 -345.598688) (xy 125.49704 -345.648301) (xy 125.467555 -345.694185) (xy 125.431841 -345.735407)
			(xy 125.390624 -345.771126) (xy 125.344743 -345.800617) (xy 125.295133 -345.823279) (xy 125.242803 -345.83865)
			(xy 125.188818 -345.846418) (xy 125.161548 -345.846908) (xy 124.297948 -345.846908) (xy 124.270678 -345.846356)
			(xy 124.216692 -345.8386) (xy 124.16436 -345.82324) (xy 124.114747 -345.800588) (xy 124.068863 -345.771105)
			(xy 124.027642 -345.735392) (xy 123.991924 -345.694176) (xy 123.962435 -345.648295) (xy 123.939777 -345.598685)
			(xy 123.92441 -345.546354) (xy 123.916648 -345.49237) (xy 122.433944 -345.49237) (xy 122.433944 -345.492375)
			(xy 122.426181 -345.546369) (xy 122.410812 -345.598709) (xy 122.388151 -345.648329) (xy 122.358659 -345.694219)
			(xy 122.322936 -345.735444) (xy 122.281709 -345.771166) (xy 122.235819 -345.800657) (xy 122.186198 -345.823316)
			(xy 122.133858 -345.838684) (xy 122.079863 -345.846445) (xy 122.052588 -345.846908) (xy 121.188988 -345.846908)
			(xy 121.161722 -345.846329) (xy 121.107747 -345.838567) (xy 121.055425 -345.823202) (xy 121.005822 -345.800548)
			(xy 120.959948 -345.771065) (xy 120.918737 -345.735354) (xy 120.883027 -345.694142) (xy 120.853546 -345.648267)
			(xy 120.830894 -345.598664) (xy 120.815531 -345.546342) (xy 120.80777 -345.492366) (xy 119.324922 -345.492366)
			(xy 119.324922 -345.492371) (xy 119.31716 -345.546359) (xy 119.301794 -345.598693) (xy 119.279137 -345.648307)
			(xy 119.24965 -345.694192) (xy 119.213934 -345.735414) (xy 119.172714 -345.771133) (xy 119.126832 -345.800624)
			(xy 119.077219 -345.823284) (xy 119.024886 -345.838654) (xy 118.970899 -345.84642) (xy 118.943628 -345.846908)
			(xy 118.080028 -345.846908) (xy 118.052759 -345.846355) (xy 117.998776 -345.838597) (xy 117.946446 -345.823235)
			(xy 117.896835 -345.800581) (xy 117.850953 -345.771098) (xy 117.809735 -345.735385) (xy 117.774019 -345.694169)
			(xy 117.744532 -345.648289) (xy 117.721875 -345.59868) (xy 117.706509 -345.546352) (xy 117.698747 -345.492369)
			(xy 116.216044 -345.492369) (xy 116.216044 -345.492376) (xy 116.20828 -345.546372) (xy 116.192911 -345.598713)
			(xy 116.170248 -345.648335) (xy 116.140754 -345.694225) (xy 116.105029 -345.735451) (xy 116.0638 -345.771173)
			(xy 116.017907 -345.800663) (xy 115.968283 -345.823322) (xy 115.915941 -345.838687) (xy 115.861944 -345.846447)
			(xy 115.834668 -345.846908) (xy 114.971068 -345.846908) (xy 114.943803 -345.846328) (xy 114.88983 -345.838563)
			(xy 114.83751 -345.823197) (xy 114.78791 -345.800542) (xy 114.742039 -345.771058) (xy 114.70083 -345.735347)
			(xy 114.665122 -345.694136) (xy 114.635643 -345.648262) (xy 114.612992 -345.59866) (xy 114.59763 -345.546339)
			(xy 114.58987 -345.492365) (xy 113.107021 -345.492365) (xy 113.107021 -345.492372) (xy 113.099259 -345.546362)
			(xy 113.083892 -345.598697) (xy 113.061234 -345.648312) (xy 113.031745 -345.694199) (xy 112.996027 -345.735421)
			(xy 112.954805 -345.77114) (xy 112.90892 -345.80063) (xy 112.859304 -345.82329) (xy 112.80697 -345.838657)
			(xy 112.75298 -345.846421) (xy 112.725708 -345.846908) (xy 111.862108 -345.846908) (xy 111.83484 -345.846353)
			(xy 111.780859 -345.838593) (xy 111.728531 -345.823229) (xy 111.678923 -345.800575) (xy 111.633044 -345.771091)
			(xy 111.591828 -345.735378) (xy 111.556114 -345.694162) (xy 111.526629 -345.648284) (xy 111.503974 -345.598676)
			(xy 111.488609 -345.546349) (xy 111.480847 -345.492368) (xy 108.541352 -345.492368) (xy 108.548141 -345.536763)
			(xy 108.548678 -345.56573) (xy 108.548192 -345.592981) (xy 108.540436 -345.646929) (xy 108.525081 -345.699224)
			(xy 108.502439 -345.748801) (xy 108.472973 -345.794651) (xy 108.437282 -345.835842) (xy 108.396091 -345.871533)
			(xy 108.350241 -345.900999) (xy 108.300664 -345.923641) (xy 108.248369 -345.938996) (xy 108.194421 -345.946752)
			(xy 108.139919 -345.946752) (xy 108.085971 -345.938996) (xy 108.033676 -345.923641) (xy 107.984099 -345.900999)
			(xy 107.938249 -345.871533) (xy 107.897058 -345.835842) (xy 107.861367 -345.794651) (xy 107.831901 -345.748801)
			(xy 107.809259 -345.699224) (xy 107.793904 -345.646929) (xy 107.786148 -345.592981) (xy 107.785662 -345.56573)
			(xy 106.174964 -345.56573) (xy 106.170145 -345.568671) (xy 106.118816 -345.590483) (xy 106.064859 -345.604589)
			(xy 106.009422 -345.610689) (xy 105.953688 -345.608652) (xy 105.898845 -345.598522) (xy 105.846061 -345.580515)
			(xy 105.796461 -345.555014) (xy 105.751103 -345.522563) (xy 105.710954 -345.483854) (xy 105.676868 -345.439711)
			(xy 105.649572 -345.391076) (xy 105.629649 -345.338985) (xy 105.617523 -345.284548) (xy 105.613452 -345.228926)
			(xy 93.625314 -345.228926) (xy 93.631454 -345.236013) (xy 93.660939 -345.281897) (xy 93.683595 -345.33151)
			(xy 93.69896 -345.383843) (xy 93.706722 -345.437829) (xy 93.706722 -345.492371) (xy 93.69896 -345.546357)
			(xy 93.683595 -345.59869) (xy 93.660939 -345.648303) (xy 93.631454 -345.694187) (xy 93.595739 -345.735409)
			(xy 93.554521 -345.771128) (xy 93.50864 -345.800619) (xy 93.459029 -345.82328) (xy 93.406698 -345.838651)
			(xy 93.352713 -345.846419) (xy 93.325442 -345.846908) (xy 92.461842 -345.846908) (xy 92.434572 -345.846355)
			(xy 92.380587 -345.838599) (xy 92.328256 -345.823238) (xy 92.278643 -345.800586) (xy 92.23276 -345.771103)
			(xy 92.19154 -345.73539) (xy 92.155822 -345.694174) (xy 92.126334 -345.648293) (xy 92.103676 -345.598683)
			(xy 92.08831 -345.546354) (xy 92.080548 -345.49237) (xy 90.597844 -345.49237) (xy 90.597844 -345.492375)
			(xy 90.590081 -345.54637) (xy 90.574712 -345.59871) (xy 90.55205 -345.648331) (xy 90.522557 -345.694221)
			(xy 90.486834 -345.735446) (xy 90.445606 -345.771168) (xy 90.399715 -345.800659) (xy 90.350094 -345.823318)
			(xy 90.297752 -345.838685) (xy 90.243757 -345.846446) (xy 90.216482 -345.846908) (xy 89.352882 -345.846908)
			(xy 89.325617 -345.846328) (xy 89.271642 -345.838566) (xy 89.219321 -345.823201) (xy 89.169719 -345.800546)
			(xy 89.123845 -345.771063) (xy 89.082635 -345.735352) (xy 89.046926 -345.69414) (xy 89.017445 -345.648266)
			(xy 88.994793 -345.598663) (xy 88.979431 -345.546341) (xy 88.97167 -345.492365) (xy 87.488822 -345.492365)
			(xy 87.488822 -345.492372) (xy 87.481059 -345.54636) (xy 87.465693 -345.598694) (xy 87.443036 -345.648309)
			(xy 87.413549 -345.694194) (xy 87.377832 -345.735416) (xy 87.336612 -345.771136) (xy 87.290728 -345.800626)
			(xy 87.241115 -345.823286) (xy 87.188781 -345.838655) (xy 87.134794 -345.84642) (xy 87.107522 -345.846908)
			(xy 86.243922 -345.846908) (xy 86.216653 -345.846354) (xy 86.16267 -345.838595) (xy 86.110341 -345.823233)
			(xy 86.060732 -345.800579) (xy 86.014851 -345.771096) (xy 85.973633 -345.735383) (xy 85.937917 -345.694167)
			(xy 85.908431 -345.648288) (xy 85.885775 -345.598679) (xy 85.870409 -345.546351) (xy 85.862647 -345.492369)
			(xy 84.379944 -345.492369) (xy 84.379944 -345.492376) (xy 84.37218 -345.546373) (xy 84.35681 -345.598715)
			(xy 84.334147 -345.648336) (xy 84.304652 -345.694227) (xy 84.268927 -345.735453) (xy 84.227697 -345.771175)
			(xy 84.181803 -345.800665) (xy 84.132179 -345.823323) (xy 84.079836 -345.838688) (xy 84.025838 -345.846447)
			(xy 83.998562 -345.846908) (xy 83.134962 -345.846908) (xy 83.107698 -345.846327) (xy 83.053725 -345.838562)
			(xy 83.001406 -345.823195) (xy 82.951807 -345.80054) (xy 82.905936 -345.771056) (xy 82.864728 -345.735345)
			(xy 82.829021 -345.694134) (xy 82.799542 -345.64826) (xy 82.776892 -345.598658) (xy 82.76153 -345.546338)
			(xy 82.75377 -345.492364) (xy 81.270921 -345.492364) (xy 81.270921 -345.492373) (xy 81.263159 -345.546362)
			(xy 81.247792 -345.598698) (xy 81.225133 -345.648314) (xy 81.195644 -345.6942) (xy 81.159924 -345.735423)
			(xy 81.118702 -345.771143) (xy 81.072816 -345.800632) (xy 81.0232 -345.823291) (xy 80.970864 -345.838658)
			(xy 80.916875 -345.846421) (xy 80.889602 -345.846908) (xy 80.026002 -345.846908) (xy 79.998734 -345.846353)
			(xy 79.944754 -345.838592) (xy 79.892427 -345.823228) (xy 79.84282 -345.800573) (xy 79.796941 -345.771089)
			(xy 79.755726 -345.735376) (xy 79.720012 -345.69416) (xy 79.690528 -345.648282) (xy 79.667873 -345.598675)
			(xy 79.652509 -345.546348) (xy 79.644747 -345.492368) (xy 78.161922 -345.492368) (xy 78.161922 -345.492371)
			(xy 78.15416 -345.546357) (xy 78.138795 -345.59869) (xy 78.116139 -345.648303) (xy 78.086654 -345.694187)
			(xy 78.050939 -345.735409) (xy 78.009721 -345.771128) (xy 77.96384 -345.800619) (xy 77.914229 -345.82328)
			(xy 77.861898 -345.838651) (xy 77.807913 -345.846419) (xy 77.780642 -345.846908) (xy 76.917042 -345.846908)
			(xy 76.889772 -345.846355) (xy 76.835787 -345.838599) (xy 76.783456 -345.823238) (xy 76.733843 -345.800586)
			(xy 76.68796 -345.771103) (xy 76.64674 -345.73539) (xy 76.611022 -345.694174) (xy 76.581534 -345.648293)
			(xy 76.558876 -345.598683) (xy 76.54351 -345.546354) (xy 76.535748 -345.49237) (xy 75.053044 -345.49237)
			(xy 75.053044 -345.492375) (xy 75.045281 -345.54637) (xy 75.029912 -345.59871) (xy 75.00725 -345.648331)
			(xy 74.977757 -345.694221) (xy 74.942034 -345.735446) (xy 74.900806 -345.771168) (xy 74.854915 -345.800659)
			(xy 74.805294 -345.823318) (xy 74.752952 -345.838685) (xy 74.698957 -345.846446) (xy 74.671682 -345.846908)
			(xy 73.808082 -345.846908) (xy 73.780817 -345.846328) (xy 73.726842 -345.838566) (xy 73.674521 -345.823201)
			(xy 73.624919 -345.800546) (xy 73.579045 -345.771063) (xy 73.537835 -345.735352) (xy 73.502126 -345.69414)
			(xy 73.472645 -345.648266) (xy 73.449993 -345.598663) (xy 73.434631 -345.546341) (xy 73.42687 -345.492365)
			(xy 71.944022 -345.492365) (xy 71.944022 -345.492372) (xy 71.936259 -345.54636) (xy 71.920893 -345.598694)
			(xy 71.898236 -345.648309) (xy 71.868749 -345.694194) (xy 71.833032 -345.735416) (xy 71.791812 -345.771136)
			(xy 71.745928 -345.800626) (xy 71.696315 -345.823286) (xy 71.643981 -345.838655) (xy 71.589994 -345.84642)
			(xy 71.562722 -345.846908) (xy 70.699122 -345.846908) (xy 70.671853 -345.846354) (xy 70.61787 -345.838595)
			(xy 70.565541 -345.823233) (xy 70.515932 -345.800579) (xy 70.470051 -345.771096) (xy 70.428833 -345.735383)
			(xy 70.393117 -345.694167) (xy 70.363631 -345.648288) (xy 70.340975 -345.598679) (xy 70.325609 -345.546351)
			(xy 70.317847 -345.492369) (xy 68.835144 -345.492369) (xy 68.835144 -345.492376) (xy 68.82738 -345.546373)
			(xy 68.81201 -345.598715) (xy 68.789347 -345.648336) (xy 68.759852 -345.694227) (xy 68.724127 -345.735453)
			(xy 68.682897 -345.771175) (xy 68.637003 -345.800665) (xy 68.587379 -345.823323) (xy 68.535036 -345.838688)
			(xy 68.481038 -345.846447) (xy 68.453762 -345.846908) (xy 67.590162 -345.846908) (xy 67.562898 -345.846327)
			(xy 67.508925 -345.838562) (xy 67.456606 -345.823195) (xy 67.407007 -345.80054) (xy 67.361136 -345.771056)
			(xy 67.319928 -345.735345) (xy 67.284221 -345.694134) (xy 67.254742 -345.64826) (xy 67.232092 -345.598658)
			(xy 67.21673 -345.546338) (xy 67.20897 -345.492364) (xy 65.726121 -345.492364) (xy 65.726121 -345.492373)
			(xy 65.718359 -345.546362) (xy 65.702992 -345.598698) (xy 65.680333 -345.648314) (xy 65.650844 -345.6942)
			(xy 65.615124 -345.735423) (xy 65.573902 -345.771143) (xy 65.528016 -345.800632) (xy 65.4784 -345.823291)
			(xy 65.426064 -345.838658) (xy 65.372075 -345.846421) (xy 65.344802 -345.846908) (xy 64.481202 -345.846908)
			(xy 64.453934 -345.846353) (xy 64.399954 -345.838592) (xy 64.347627 -345.823228) (xy 64.29802 -345.800573)
			(xy 64.252141 -345.771089) (xy 64.210926 -345.735376) (xy 64.175212 -345.69416) (xy 64.145728 -345.648282)
			(xy 64.123073 -345.598675) (xy 64.107709 -345.546348) (xy 64.099947 -345.492368) (xy 62.617122 -345.492368)
			(xy 62.617122 -345.492371) (xy 62.60936 -345.546357) (xy 62.593995 -345.59869) (xy 62.571339 -345.648303)
			(xy 62.541854 -345.694187) (xy 62.506139 -345.735409) (xy 62.464921 -345.771128) (xy 62.41904 -345.800619)
			(xy 62.369429 -345.82328) (xy 62.317098 -345.838651) (xy 62.263113 -345.846419) (xy 62.235842 -345.846908)
			(xy 61.372242 -345.846908) (xy 61.344972 -345.846355) (xy 61.290987 -345.838599) (xy 61.238656 -345.823238)
			(xy 61.189043 -345.800586) (xy 61.14316 -345.771103) (xy 61.10194 -345.73539) (xy 61.066222 -345.694174)
			(xy 61.036734 -345.648293) (xy 61.014076 -345.598683) (xy 60.99871 -345.546354) (xy 60.990948 -345.49237)
			(xy 60.179231 -345.49237) (xy 59.759331 -346.583254) (xy 99.245418 -346.583254) (xy 99.249489 -346.527632)
			(xy 99.261615 -346.473195) (xy 99.281538 -346.421104) (xy 99.308834 -346.372469) (xy 99.34292 -346.328326)
			(xy 99.383069 -346.289617) (xy 99.428427 -346.257166) (xy 99.478027 -346.231665) (xy 99.530811 -346.213658)
			(xy 99.585654 -346.203528) (xy 99.641388 -346.201491) (xy 99.696825 -346.207591) (xy 99.750782 -346.221697)
			(xy 99.802111 -346.243509) (xy 99.849717 -346.272563) (xy 99.892585 -346.308238) (xy 99.929802 -346.349775)
			(xy 99.960575 -346.396288) (xy 99.984247 -346.446785) (xy 99.988777 -346.461842) (xy 107.639864 -346.461842)
			(xy 107.643935 -346.40622) (xy 107.656061 -346.351783) (xy 107.675984 -346.299692) (xy 107.70328 -346.251057)
			(xy 107.737366 -346.206914) (xy 107.777515 -346.168205) (xy 107.822873 -346.135754) (xy 107.872473 -346.110253)
			(xy 107.925257 -346.092246) (xy 107.9801 -346.082116) (xy 108.035834 -346.080079) (xy 108.091271 -346.086179)
			(xy 108.145228 -346.100285) (xy 108.196557 -346.122097) (xy 108.244163 -346.151151) (xy 108.287031 -346.186826)
			(xy 108.324248 -346.228363) (xy 108.355021 -346.274876) (xy 108.378693 -346.325373) (xy 108.394761 -346.37878)
			(xy 108.402881 -346.433956) (xy 108.40339 -346.461842) (xy 108.402881 -346.489728) (xy 108.394761 -346.544904)
			(xy 108.378693 -346.598311) (xy 108.355021 -346.648808) (xy 108.324248 -346.695321) (xy 108.287031 -346.736858)
			(xy 108.244163 -346.772533) (xy 108.196557 -346.801587) (xy 108.145228 -346.823399) (xy 108.091271 -346.837505)
			(xy 108.035834 -346.843605) (xy 107.9801 -346.841568) (xy 107.925257 -346.831438) (xy 107.872473 -346.813431)
			(xy 107.822873 -346.78793) (xy 107.777515 -346.755479) (xy 107.737366 -346.71677) (xy 107.70328 -346.672627)
			(xy 107.675984 -346.623992) (xy 107.656061 -346.571901) (xy 107.643935 -346.517464) (xy 107.639864 -346.461842)
			(xy 99.988777 -346.461842) (xy 100.000315 -346.500192) (xy 100.008435 -346.555368) (xy 100.008944 -346.583254)
			(xy 100.008435 -346.61114) (xy 100.000315 -346.666316) (xy 99.984247 -346.719723) (xy 99.960575 -346.77022)
			(xy 99.929802 -346.816733) (xy 99.892585 -346.85827) (xy 99.849717 -346.893945) (xy 99.802111 -346.922999)
			(xy 99.750782 -346.944811) (xy 99.696825 -346.958917) (xy 99.641388 -346.965017) (xy 99.585654 -346.96298)
			(xy 99.530811 -346.95285) (xy 99.478027 -346.934843) (xy 99.428427 -346.909342) (xy 99.383069 -346.876891)
			(xy 99.34292 -346.838182) (xy 99.308834 -346.794039) (xy 99.281538 -346.745404) (xy 99.261615 -346.693313)
			(xy 99.249489 -346.638876) (xy 99.245418 -346.583254) (xy 59.759331 -346.583254) (xy 59.262861 -347.873066)
			(xy 99.245418 -347.873066) (xy 99.249489 -347.817444) (xy 99.261615 -347.763007) (xy 99.281538 -347.710916)
			(xy 99.308834 -347.662281) (xy 99.34292 -347.618138) (xy 99.383069 -347.579429) (xy 99.428427 -347.546978)
			(xy 99.478027 -347.521477) (xy 99.530811 -347.50347) (xy 99.585654 -347.49334) (xy 99.641388 -347.491303)
			(xy 99.696825 -347.497403) (xy 99.750782 -347.511509) (xy 99.802111 -347.533321) (xy 99.849717 -347.562375)
			(xy 99.892585 -347.59805) (xy 99.929802 -347.639587) (xy 99.960575 -347.6861) (xy 99.984247 -347.736597)
			(xy 100.000315 -347.790004) (xy 100.008435 -347.84518) (xy 100.008944 -347.873066) (xy 100.008435 -347.900952)
			(xy 100.000315 -347.956128) (xy 99.984247 -348.009535) (xy 99.960575 -348.060032) (xy 99.929802 -348.106545)
			(xy 99.892585 -348.148082) (xy 99.849717 -348.183757) (xy 99.802111 -348.212811) (xy 99.750782 -348.234623)
			(xy 99.696825 -348.248729) (xy 99.641388 -348.254829) (xy 99.585654 -348.252792) (xy 99.530811 -348.242662)
			(xy 99.478027 -348.224655) (xy 99.428427 -348.199154) (xy 99.383069 -348.166703) (xy 99.34292 -348.127994)
			(xy 99.308834 -348.083851) (xy 99.281538 -348.035216) (xy 99.261615 -347.983125) (xy 99.249489 -347.928688)
			(xy 99.245418 -347.873066) (xy 59.262861 -347.873066) (xy 58.978019 -348.613074) (xy 60.990892 -348.613074)
			(xy 60.990892 -348.558526) (xy 60.998655 -348.504534) (xy 61.014024 -348.452197) (xy 61.036685 -348.40258)
			(xy 61.066177 -348.356693) (xy 61.1019 -348.315471) (xy 61.143127 -348.279752) (xy 61.189017 -348.250265)
			(xy 61.238636 -348.227609) (xy 61.290976 -348.212246) (xy 61.344968 -348.204489) (xy 61.372242 -348.204028)
			(xy 62.235842 -348.204028) (xy 62.263109 -348.204537) (xy 62.317086 -348.212304) (xy 62.369409 -348.227672)
			(xy 62.419013 -348.25033) (xy 62.464887 -348.279816) (xy 62.506099 -348.315531) (xy 62.541809 -348.356746)
			(xy 62.57129 -348.402624) (xy 62.593943 -348.45223) (xy 62.609305 -348.504555) (xy 62.617066 -348.558533)
			(xy 62.617066 -348.613067) (xy 62.617065 -348.613072) (xy 64.099892 -348.613072) (xy 64.099892 -348.558528)
			(xy 64.107654 -348.50454) (xy 64.123021 -348.452206) (xy 64.145679 -348.402591) (xy 64.175168 -348.356706)
			(xy 64.210886 -348.315485) (xy 64.252108 -348.279766) (xy 64.297993 -348.250278) (xy 64.347607 -348.22762)
			(xy 64.399942 -348.212253) (xy 64.45393 -348.204491) (xy 64.481202 -348.204028) (xy 65.344802 -348.204028)
			(xy 65.372071 -348.204535) (xy 65.426053 -348.212296) (xy 65.47838 -348.227661) (xy 65.527989 -348.250317)
			(xy 65.573869 -348.279802) (xy 65.615085 -348.315517) (xy 65.650799 -348.356733) (xy 65.680284 -348.402613)
			(xy 65.702939 -348.452221) (xy 65.718304 -348.504549) (xy 65.726066 -348.558531) (xy 65.726066 -348.613068)
			(xy 67.208914 -348.613068) (xy 67.208914 -348.558532) (xy 67.216675 -348.50455) (xy 67.232039 -348.452222)
			(xy 67.254693 -348.402613) (xy 67.284176 -348.356733) (xy 67.319888 -348.315515) (xy 67.361102 -348.279799)
			(xy 67.40698 -348.250311) (xy 67.456586 -348.227652) (xy 67.508913 -348.212283) (xy 67.562894 -348.204517)
			(xy 67.590162 -348.204028) (xy 68.453762 -348.204028) (xy 68.481034 -348.204509) (xy 68.535024 -348.212266)
			(xy 68.58736 -348.227629) (xy 68.636976 -348.250284) (xy 68.682863 -348.27977) (xy 68.724087 -348.315486)
			(xy 68.759808 -348.356706) (xy 68.789298 -348.40259) (xy 68.811958 -348.452205) (xy 68.827326 -348.504539)
			(xy 68.835088 -348.558528) (xy 68.835088 -348.613072) (xy 68.835088 -348.613073) (xy 70.317792 -348.613073)
			(xy 70.317792 -348.558527) (xy 70.325554 -348.504537) (xy 70.340922 -348.452201) (xy 70.363582 -348.402585)
			(xy 70.393072 -348.356699) (xy 70.428793 -348.315478) (xy 70.470017 -348.279759) (xy 70.515905 -348.250271)
			(xy 70.565522 -348.227615) (xy 70.617859 -348.21225) (xy 70.671849 -348.20449) (xy 70.699122 -348.204028)
			(xy 71.562722 -348.204028) (xy 71.58999 -348.204536) (xy 71.643969 -348.2123) (xy 71.696295 -348.227667)
			(xy 71.745901 -348.250324) (xy 71.791778 -348.279809) (xy 71.832992 -348.315524) (xy 71.868704 -348.35674)
			(xy 71.898187 -348.402618) (xy 71.920841 -348.452226) (xy 71.936205 -348.504552) (xy 71.943966 -348.558532)
			(xy 71.943966 -348.613068) (xy 71.943966 -348.613069) (xy 73.426814 -348.613069) (xy 73.426814 -348.558531)
			(xy 73.434576 -348.504547) (xy 73.449941 -348.452218) (xy 73.472596 -348.402608) (xy 73.502081 -348.356726)
			(xy 73.537795 -348.315508) (xy 73.579012 -348.279792) (xy 73.624892 -348.250305) (xy 73.674501 -348.227647)
			(xy 73.72683 -348.21228) (xy 73.780813 -348.204516) (xy 73.808082 -348.204028) (xy 74.671682 -348.204028)
			(xy 74.698953 -348.20451) (xy 74.752941 -348.21227) (xy 74.805274 -348.227634) (xy 74.854888 -348.25029)
			(xy 74.900773 -348.279777) (xy 74.941994 -348.315493) (xy 74.977712 -348.356713) (xy 75.007201 -348.402596)
			(xy 75.029859 -348.452209) (xy 75.045226 -348.504542) (xy 75.052988 -348.558529) (xy 75.052988 -348.613071)
			(xy 75.052988 -348.613074) (xy 76.535692 -348.613074) (xy 76.535692 -348.558526) (xy 76.543455 -348.504534)
			(xy 76.558824 -348.452197) (xy 76.581485 -348.40258) (xy 76.610977 -348.356693) (xy 76.6467 -348.315471)
			(xy 76.687927 -348.279752) (xy 76.733817 -348.250265) (xy 76.783436 -348.227609) (xy 76.835776 -348.212246)
			(xy 76.889768 -348.204489) (xy 76.917042 -348.204028) (xy 77.780642 -348.204028) (xy 77.807909 -348.204537)
			(xy 77.861886 -348.212304) (xy 77.914209 -348.227672) (xy 77.963813 -348.25033) (xy 78.009687 -348.279816)
			(xy 78.050899 -348.315531) (xy 78.086609 -348.356746) (xy 78.11609 -348.402624) (xy 78.138743 -348.45223)
			(xy 78.154105 -348.504555) (xy 78.161866 -348.558533) (xy 78.161866 -348.613067) (xy 78.161865 -348.613072)
			(xy 79.644692 -348.613072) (xy 79.644692 -348.558528) (xy 79.652454 -348.50454) (xy 79.667821 -348.452206)
			(xy 79.690479 -348.402591) (xy 79.719968 -348.356706) (xy 79.755686 -348.315485) (xy 79.796908 -348.279766)
			(xy 79.842793 -348.250278) (xy 79.892407 -348.22762) (xy 79.944742 -348.212253) (xy 79.99873 -348.204491)
			(xy 80.026002 -348.204028) (xy 80.889602 -348.204028) (xy 80.916871 -348.204535) (xy 80.970853 -348.212296)
			(xy 81.02318 -348.227661) (xy 81.072789 -348.250317) (xy 81.118669 -348.279802) (xy 81.159885 -348.315517)
			(xy 81.195599 -348.356733) (xy 81.225084 -348.402613) (xy 81.247739 -348.452221) (xy 81.263104 -348.504549)
			(xy 81.270866 -348.558531) (xy 81.270866 -348.613068) (xy 82.753714 -348.613068) (xy 82.753714 -348.558532)
			(xy 82.761475 -348.50455) (xy 82.776839 -348.452222) (xy 82.799493 -348.402613) (xy 82.828976 -348.356733)
			(xy 82.864688 -348.315515) (xy 82.905902 -348.279799) (xy 82.95178 -348.250311) (xy 83.001386 -348.227652)
			(xy 83.053713 -348.212283) (xy 83.107694 -348.204517) (xy 83.134962 -348.204028) (xy 83.998562 -348.204028)
			(xy 84.025834 -348.204509) (xy 84.079824 -348.212266) (xy 84.13216 -348.227629) (xy 84.181776 -348.250284)
			(xy 84.227663 -348.27977) (xy 84.268887 -348.315486) (xy 84.304608 -348.356706) (xy 84.334098 -348.40259)
			(xy 84.356758 -348.452205) (xy 84.372126 -348.504539) (xy 84.379888 -348.558528) (xy 84.379888 -348.613072)
			(xy 84.379888 -348.613073) (xy 85.862592 -348.613073) (xy 85.862592 -348.558527) (xy 85.870354 -348.504537)
			(xy 85.885722 -348.452201) (xy 85.908382 -348.402585) (xy 85.937872 -348.356699) (xy 85.973593 -348.315478)
			(xy 86.014817 -348.279759) (xy 86.060705 -348.250271) (xy 86.110322 -348.227615) (xy 86.162659 -348.21225)
			(xy 86.216649 -348.20449) (xy 86.243922 -348.204028) (xy 87.107522 -348.204028) (xy 87.13479 -348.204536)
			(xy 87.188769 -348.2123) (xy 87.241095 -348.227667) (xy 87.290701 -348.250324) (xy 87.336578 -348.279809)
			(xy 87.377792 -348.315524) (xy 87.413504 -348.35674) (xy 87.442987 -348.402618) (xy 87.465641 -348.452226)
			(xy 87.481005 -348.504552) (xy 87.488766 -348.558532) (xy 87.488766 -348.613068) (xy 87.488766 -348.613069)
			(xy 88.971614 -348.613069) (xy 88.971614 -348.558531) (xy 88.979376 -348.504547) (xy 88.994741 -348.452218)
			(xy 89.017396 -348.402608) (xy 89.046881 -348.356726) (xy 89.082595 -348.315508) (xy 89.123812 -348.279792)
			(xy 89.169692 -348.250305) (xy 89.219301 -348.227647) (xy 89.27163 -348.21228) (xy 89.325613 -348.204516)
			(xy 89.352882 -348.204028) (xy 90.216482 -348.204028) (xy 90.243753 -348.20451) (xy 90.297741 -348.21227)
			(xy 90.350074 -348.227634) (xy 90.399688 -348.25029) (xy 90.445573 -348.279777) (xy 90.486794 -348.315493)
			(xy 90.522512 -348.356713) (xy 90.552001 -348.402596) (xy 90.574659 -348.452209) (xy 90.590026 -348.504542)
			(xy 90.597788 -348.558529) (xy 90.597788 -348.613071) (xy 90.597788 -348.613074) (xy 92.080492 -348.613074)
			(xy 92.080492 -348.558526) (xy 92.088255 -348.504534) (xy 92.103624 -348.452197) (xy 92.126285 -348.40258)
			(xy 92.155777 -348.356693) (xy 92.1915 -348.315471) (xy 92.232727 -348.279752) (xy 92.278617 -348.250265)
			(xy 92.328236 -348.227609) (xy 92.380576 -348.212246) (xy 92.434568 -348.204489) (xy 92.461842 -348.204028)
			(xy 93.325442 -348.204028) (xy 93.352709 -348.204537) (xy 93.406686 -348.212304) (xy 93.459009 -348.227672)
			(xy 93.508613 -348.25033) (xy 93.554487 -348.279816) (xy 93.595699 -348.315531) (xy 93.631409 -348.356746)
			(xy 93.66089 -348.402624) (xy 93.662683 -348.406551) (xy 105.290366 -348.406551) (xy 105.290366 -348.352049)
			(xy 105.298122 -348.298103) (xy 105.313475 -348.245809) (xy 105.336115 -348.196233) (xy 105.365579 -348.150383)
			(xy 105.401268 -348.109192) (xy 105.442455 -348.073499) (xy 105.488303 -348.044031) (xy 105.537877 -348.021387)
			(xy 105.59017 -348.006029) (xy 105.644115 -347.998268) (xy 105.671366 -347.99778) (xy 105.700106 -347.998269)
			(xy 105.756935 -348.006901) (xy 105.811826 -348.023959) (xy 105.863537 -348.049058) (xy 105.910898 -348.08163)
			(xy 105.932224 -348.100904) (xy 105.939336 -348.107508) (xy 105.956862 -348.11462) (xy 106.045254 -348.115128)
			(xy 106.06278 -348.10827) (xy 106.070146 -348.10192) (xy 106.091316 -348.083296) (xy 106.138126 -348.051863)
			(xy 106.189051 -348.027659) (xy 106.242983 -348.011211) (xy 106.298748 -348.002877) (xy 106.32694 -348.002352)
			(xy 106.354186 -348.002921) (xy 106.408124 -348.010681) (xy 106.460409 -348.026038) (xy 106.509976 -348.048679)
			(xy 106.555816 -348.078143) (xy 106.596997 -348.113831) (xy 106.632681 -348.155016) (xy 106.66214 -348.20086)
			(xy 106.684776 -348.250429) (xy 106.700127 -348.302715) (xy 106.707882 -348.356653) (xy 106.707882 -348.411147)
			(xy 106.700127 -348.465085) (xy 106.684776 -348.517371) (xy 106.66214 -348.56694) (xy 106.632681 -348.612784)
			(xy 106.632431 -348.613072) (xy 111.480792 -348.613072) (xy 111.480792 -348.558528) (xy 111.488554 -348.504539)
			(xy 111.503921 -348.452204) (xy 111.52658 -348.402589) (xy 111.556069 -348.356704) (xy 111.591788 -348.315483)
			(xy 111.63301 -348.279764) (xy 111.678896 -348.250276) (xy 111.728512 -348.227618) (xy 111.780847 -348.212252)
			(xy 111.834836 -348.204491) (xy 111.862108 -348.204028) (xy 112.725708 -348.204028) (xy 112.752976 -348.204535)
			(xy 112.806958 -348.212297) (xy 112.859285 -348.227663) (xy 112.908893 -348.250319) (xy 112.954771 -348.279804)
			(xy 112.995987 -348.315519) (xy 113.0317 -348.356735) (xy 113.061185 -348.402614) (xy 113.08384 -348.452223)
			(xy 113.099204 -348.50455) (xy 113.106966 -348.558532) (xy 113.106966 -348.613068) (xy 113.106966 -348.613069)
			(xy 114.589814 -348.613069) (xy 114.589814 -348.558531) (xy 114.597575 -348.504549) (xy 114.61294 -348.452221)
			(xy 114.635594 -348.402611) (xy 114.665078 -348.356731) (xy 114.70079 -348.315513) (xy 114.742005 -348.279797)
			(xy 114.787883 -348.250309) (xy 114.837491 -348.227651) (xy 114.889818 -348.212282) (xy 114.943799 -348.204517)
			(xy 114.971068 -348.204028) (xy 115.834668 -348.204028) (xy 115.86194 -348.204509) (xy 115.915929 -348.212268)
			(xy 115.968264 -348.227631) (xy 116.01788 -348.250286) (xy 116.063766 -348.279772) (xy 116.104989 -348.315488)
			(xy 116.140709 -348.356708) (xy 116.170199 -348.402592) (xy 116.192858 -348.452206) (xy 116.208226 -348.50454)
			(xy 116.215988 -348.558528) (xy 116.215988 -348.613072) (xy 116.215988 -348.613073) (xy 117.698692 -348.613073)
			(xy 117.698692 -348.558527) (xy 117.706455 -348.504536) (xy 117.721823 -348.4522) (xy 117.744483 -348.402584)
			(xy 117.773974 -348.356697) (xy 117.809695 -348.315476) (xy 117.85092 -348.279757) (xy 117.896808 -348.25027)
			(xy 117.946426 -348.227613) (xy 117.998764 -348.212249) (xy 118.052755 -348.20449) (xy 118.080028 -348.204028)
			(xy 118.943628 -348.204028) (xy 118.970895 -348.204536) (xy 119.024875 -348.212301) (xy 119.077199 -348.227668)
			(xy 119.126805 -348.250326) (xy 119.172681 -348.279811) (xy 119.213894 -348.315526) (xy 119.249605 -348.356742)
			(xy 119.279088 -348.40262) (xy 119.301741 -348.452227) (xy 119.317105 -348.504553) (xy 119.324866 -348.558533)
			(xy 119.324866 -348.613067) (xy 119.324866 -348.61307) (xy 120.807714 -348.61307) (xy 120.807714 -348.55853)
			(xy 120.815476 -348.504546) (xy 120.830841 -348.452217) (xy 120.853497 -348.402606) (xy 120.882983 -348.356724)
			(xy 120.918697 -348.315506) (xy 120.959915 -348.27979) (xy 121.005795 -348.250303) (xy 121.055405 -348.227645)
			(xy 121.107735 -348.212279) (xy 121.161718 -348.204515) (xy 121.188988 -348.204028) (xy 122.052588 -348.204028)
			(xy 122.079859 -348.204511) (xy 122.133846 -348.212271) (xy 122.186178 -348.227636) (xy 122.235792 -348.250292)
			(xy 122.281676 -348.279779) (xy 122.322896 -348.315495) (xy 122.358614 -348.356715) (xy 122.388102 -348.402598)
			(xy 122.41076 -348.45221) (xy 122.426126 -348.504543) (xy 122.433889 -348.558529) (xy 122.433889 -348.613071)
			(xy 122.433889 -348.613074) (xy 123.916592 -348.613074) (xy 123.916592 -348.558526) (xy 123.924355 -348.504534)
			(xy 123.939724 -348.452196) (xy 123.962386 -348.402578) (xy 123.991879 -348.356691) (xy 124.027602 -348.315468)
			(xy 124.068829 -348.27975) (xy 124.11472 -348.250263) (xy 124.164341 -348.227608) (xy 124.216681 -348.212245)
			(xy 124.270674 -348.204488) (xy 124.297948 -348.204028) (xy 125.161548 -348.204028) (xy 125.188814 -348.204538)
			(xy 125.242791 -348.212305) (xy 125.295114 -348.227674) (xy 125.344717 -348.250332) (xy 125.39059 -348.279819)
			(xy 125.431801 -348.315533) (xy 125.46751 -348.356748) (xy 125.496991 -348.402626) (xy 125.519643 -348.452231)
			(xy 125.535006 -348.504556) (xy 125.542766 -348.558534) (xy 125.542766 -348.613066) (xy 125.542765 -348.613072)
			(xy 127.025592 -348.613072) (xy 127.025592 -348.558528) (xy 127.033354 -348.504539) (xy 127.048721 -348.452204)
			(xy 127.07138 -348.402589) (xy 127.100869 -348.356704) (xy 127.136588 -348.315483) (xy 127.17781 -348.279764)
			(xy 127.223696 -348.250276) (xy 127.273312 -348.227618) (xy 127.325647 -348.212252) (xy 127.379636 -348.204491)
			(xy 127.406908 -348.204028) (xy 128.270508 -348.204028) (xy 128.297776 -348.204535) (xy 128.351758 -348.212297)
			(xy 128.404085 -348.227663) (xy 128.453693 -348.250319) (xy 128.499571 -348.279804) (xy 128.540787 -348.315519)
			(xy 128.5765 -348.356735) (xy 128.605985 -348.402614) (xy 128.62864 -348.452223) (xy 128.644004 -348.50455)
			(xy 128.651766 -348.558532) (xy 128.651766 -348.613068) (xy 128.651766 -348.613069) (xy 130.134614 -348.613069)
			(xy 130.134614 -348.558531) (xy 130.142375 -348.504549) (xy 130.15774 -348.452221) (xy 130.180394 -348.402611)
			(xy 130.209878 -348.356731) (xy 130.24559 -348.315513) (xy 130.286805 -348.279797) (xy 130.332683 -348.250309)
			(xy 130.382291 -348.227651) (xy 130.434618 -348.212282) (xy 130.488599 -348.204517) (xy 130.515868 -348.204028)
			(xy 131.379468 -348.204028) (xy 131.40674 -348.204509) (xy 131.460729 -348.212268) (xy 131.513064 -348.227631)
			(xy 131.56268 -348.250286) (xy 131.608566 -348.279772) (xy 131.649789 -348.315488) (xy 131.685509 -348.356708)
			(xy 131.714999 -348.402592) (xy 131.737658 -348.452206) (xy 131.753026 -348.50454) (xy 131.760788 -348.558528)
			(xy 131.760788 -348.613072) (xy 131.760788 -348.613073) (xy 133.243492 -348.613073) (xy 133.243492 -348.558527)
			(xy 133.251255 -348.504536) (xy 133.266623 -348.4522) (xy 133.289283 -348.402584) (xy 133.318774 -348.356697)
			(xy 133.354495 -348.315476) (xy 133.39572 -348.279757) (xy 133.441608 -348.25027) (xy 133.491226 -348.227613)
			(xy 133.543564 -348.212249) (xy 133.597555 -348.20449) (xy 133.624828 -348.204028) (xy 134.488428 -348.204028)
			(xy 134.515695 -348.204536) (xy 134.569675 -348.212301) (xy 134.621999 -348.227668) (xy 134.671605 -348.250326)
			(xy 134.717481 -348.279811) (xy 134.758694 -348.315526) (xy 134.794405 -348.356742) (xy 134.823888 -348.40262)
			(xy 134.846541 -348.452227) (xy 134.861905 -348.504553) (xy 134.869666 -348.558533) (xy 134.869666 -348.613067)
			(xy 134.869666 -348.61307) (xy 136.352514 -348.61307) (xy 136.352514 -348.55853) (xy 136.360276 -348.504546)
			(xy 136.375641 -348.452217) (xy 136.398297 -348.402606) (xy 136.427783 -348.356724) (xy 136.463497 -348.315506)
			(xy 136.504715 -348.27979) (xy 136.550595 -348.250303) (xy 136.600205 -348.227645) (xy 136.652535 -348.212279)
			(xy 136.706518 -348.204515) (xy 136.733788 -348.204028) (xy 137.597388 -348.204028) (xy 137.624659 -348.204511)
			(xy 137.678646 -348.212271) (xy 137.730978 -348.227636) (xy 137.780592 -348.250292) (xy 137.826476 -348.279779)
			(xy 137.867696 -348.315495) (xy 137.903414 -348.356715) (xy 137.932902 -348.402598) (xy 137.95556 -348.45221)
			(xy 137.970926 -348.504543) (xy 137.978689 -348.558529) (xy 137.978689 -348.613071) (xy 137.978689 -348.613074)
			(xy 139.461392 -348.613074) (xy 139.461392 -348.558526) (xy 139.469155 -348.504534) (xy 139.484524 -348.452196)
			(xy 139.507186 -348.402578) (xy 139.536679 -348.356691) (xy 139.572402 -348.315468) (xy 139.613629 -348.27975)
			(xy 139.65952 -348.250263) (xy 139.709141 -348.227608) (xy 139.761481 -348.212245) (xy 139.815474 -348.204488)
			(xy 139.842748 -348.204028) (xy 140.706348 -348.204028) (xy 140.733614 -348.204538) (xy 140.787591 -348.212305)
			(xy 140.839914 -348.227674) (xy 140.889517 -348.250332) (xy 140.93539 -348.279819) (xy 140.976601 -348.315533)
			(xy 141.01231 -348.356748) (xy 141.041791 -348.402626) (xy 141.064443 -348.452231) (xy 141.079806 -348.504556)
			(xy 141.087566 -348.558534) (xy 141.087566 -348.613066) (xy 141.087565 -348.613072) (xy 142.570392 -348.613072)
			(xy 142.570392 -348.558528) (xy 142.578154 -348.504539) (xy 142.593521 -348.452204) (xy 142.61618 -348.402589)
			(xy 142.645669 -348.356704) (xy 142.681388 -348.315483) (xy 142.72261 -348.279764) (xy 142.768496 -348.250276)
			(xy 142.818112 -348.227618) (xy 142.870447 -348.212252) (xy 142.924436 -348.204491) (xy 142.951708 -348.204028)
			(xy 143.815308 -348.204028) (xy 143.842576 -348.204535) (xy 143.896558 -348.212297) (xy 143.948885 -348.227663)
			(xy 143.998493 -348.250319) (xy 144.044371 -348.279804) (xy 144.085587 -348.315519) (xy 144.1213 -348.356735)
			(xy 144.150785 -348.402614) (xy 144.17344 -348.452223) (xy 144.188804 -348.50455) (xy 144.196566 -348.558532)
			(xy 144.196566 -348.613068) (xy 144.188804 -348.66705) (xy 144.17344 -348.719377) (xy 144.150785 -348.768986)
			(xy 144.1213 -348.814865) (xy 144.085587 -348.856081) (xy 144.044371 -348.891796) (xy 143.998493 -348.921281)
			(xy 143.948885 -348.943937) (xy 143.896558 -348.959303) (xy 143.842576 -348.967065) (xy 143.815308 -348.967552)
			(xy 142.951708 -348.967552) (xy 142.924436 -348.967109) (xy 142.870447 -348.959348) (xy 142.818112 -348.943982)
			(xy 142.768496 -348.921324) (xy 142.72261 -348.891836) (xy 142.681388 -348.856117) (xy 142.645669 -348.814896)
			(xy 142.61618 -348.769011) (xy 142.593521 -348.719396) (xy 142.578154 -348.667061) (xy 142.570392 -348.613072)
			(xy 141.087565 -348.613072) (xy 141.079806 -348.667044) (xy 141.064443 -348.719369) (xy 141.041791 -348.768974)
			(xy 141.01231 -348.814852) (xy 140.976601 -348.856067) (xy 140.93539 -348.891781) (xy 140.889517 -348.921268)
			(xy 140.839914 -348.943926) (xy 140.787591 -348.959295) (xy 140.733614 -348.967062) (xy 140.706348 -348.967552)
			(xy 139.842748 -348.967552) (xy 139.815474 -348.967112) (xy 139.761481 -348.959355) (xy 139.709141 -348.943992)
			(xy 139.65952 -348.921337) (xy 139.613629 -348.89185) (xy 139.572402 -348.856132) (xy 139.536679 -348.814909)
			(xy 139.507186 -348.769022) (xy 139.484524 -348.719404) (xy 139.469155 -348.667066) (xy 139.461392 -348.613074)
			(xy 137.978689 -348.613074) (xy 137.970926 -348.667057) (xy 137.95556 -348.71939) (xy 137.932902 -348.769002)
			(xy 137.903414 -348.814885) (xy 137.867696 -348.856105) (xy 137.826476 -348.891821) (xy 137.780592 -348.921308)
			(xy 137.730978 -348.943964) (xy 137.678646 -348.959329) (xy 137.624659 -348.967089) (xy 137.597388 -348.967552)
			(xy 136.733788 -348.967552) (xy 136.706518 -348.967085) (xy 136.652535 -348.959321) (xy 136.600205 -348.943955)
			(xy 136.550595 -348.921297) (xy 136.504715 -348.89181) (xy 136.463497 -348.856094) (xy 136.427783 -348.814876)
			(xy 136.398297 -348.768994) (xy 136.375641 -348.719383) (xy 136.360276 -348.667053) (xy 136.352514 -348.61307)
			(xy 134.869666 -348.61307) (xy 134.861905 -348.667047) (xy 134.846541 -348.719373) (xy 134.823888 -348.76898)
			(xy 134.794405 -348.814858) (xy 134.758694 -348.856074) (xy 134.717481 -348.891789) (xy 134.671605 -348.921274)
			(xy 134.621999 -348.943932) (xy 134.569675 -348.959299) (xy 134.515695 -348.967064) (xy 134.488428 -348.967552)
			(xy 133.624828 -348.967552) (xy 133.597555 -348.96711) (xy 133.543564 -348.959351) (xy 133.491226 -348.943987)
			(xy 133.441608 -348.92133) (xy 133.39572 -348.891843) (xy 133.354495 -348.856124) (xy 133.318774 -348.814903)
			(xy 133.289283 -348.769016) (xy 133.266623 -348.7194) (xy 133.251255 -348.667064) (xy 133.243492 -348.613073)
			(xy 131.760788 -348.613073) (xy 131.753026 -348.66706) (xy 131.737658 -348.719394) (xy 131.714999 -348.769008)
			(xy 131.685509 -348.814892) (xy 131.649789 -348.856112) (xy 131.608566 -348.891828) (xy 131.56268 -348.921314)
			(xy 131.513064 -348.943969) (xy 131.460729 -348.959332) (xy 131.40674 -348.967091) (xy 131.379468 -348.967552)
			(xy 130.515868 -348.967552) (xy 130.488599 -348.967083) (xy 130.434618 -348.959318) (xy 130.382291 -348.943949)
			(xy 130.332683 -348.921291) (xy 130.286805 -348.891803) (xy 130.24559 -348.856087) (xy 130.209878 -348.814869)
			(xy 130.180394 -348.768989) (xy 130.15774 -348.719379) (xy 130.142375 -348.667051) (xy 130.134614 -348.613069)
			(xy 128.651766 -348.613069) (xy 128.644004 -348.66705) (xy 128.62864 -348.719377) (xy 128.605985 -348.768986)
			(xy 128.5765 -348.814865) (xy 128.540787 -348.856081) (xy 128.499571 -348.891796) (xy 128.453693 -348.921281)
			(xy 128.404085 -348.943937) (xy 128.351758 -348.959303) (xy 128.297776 -348.967065) (xy 128.270508 -348.967552)
			(xy 127.406908 -348.967552) (xy 127.379636 -348.967109) (xy 127.325647 -348.959348) (xy 127.273312 -348.943982)
			(xy 127.223696 -348.921324) (xy 127.17781 -348.891836) (xy 127.136588 -348.856117) (xy 127.100869 -348.814896)
			(xy 127.07138 -348.769011) (xy 127.048721 -348.719396) (xy 127.033354 -348.667061) (xy 127.025592 -348.613072)
			(xy 125.542765 -348.613072) (xy 125.535006 -348.667044) (xy 125.519643 -348.719369) (xy 125.496991 -348.768974)
			(xy 125.46751 -348.814852) (xy 125.431801 -348.856067) (xy 125.39059 -348.891781) (xy 125.344717 -348.921268)
			(xy 125.295114 -348.943926) (xy 125.242791 -348.959295) (xy 125.188814 -348.967062) (xy 125.161548 -348.967552)
			(xy 124.297948 -348.967552) (xy 124.270674 -348.967112) (xy 124.216681 -348.959355) (xy 124.164341 -348.943992)
			(xy 124.11472 -348.921337) (xy 124.068829 -348.89185) (xy 124.027602 -348.856132) (xy 123.991879 -348.814909)
			(xy 123.962386 -348.769022) (xy 123.939724 -348.719404) (xy 123.924355 -348.667066) (xy 123.916592 -348.613074)
			(xy 122.433889 -348.613074) (xy 122.426126 -348.667057) (xy 122.41076 -348.71939) (xy 122.388102 -348.769002)
			(xy 122.358614 -348.814885) (xy 122.322896 -348.856105) (xy 122.281676 -348.891821) (xy 122.235792 -348.921308)
			(xy 122.186178 -348.943964) (xy 122.133846 -348.959329) (xy 122.079859 -348.967089) (xy 122.052588 -348.967552)
			(xy 121.188988 -348.967552) (xy 121.161718 -348.967085) (xy 121.107735 -348.959321) (xy 121.055405 -348.943955)
			(xy 121.005795 -348.921297) (xy 120.959915 -348.89181) (xy 120.918697 -348.856094) (xy 120.882983 -348.814876)
			(xy 120.853497 -348.768994) (xy 120.830841 -348.719383) (xy 120.815476 -348.667053) (xy 120.807714 -348.61307)
			(xy 119.324866 -348.61307) (xy 119.317105 -348.667047) (xy 119.301741 -348.719373) (xy 119.279088 -348.76898)
			(xy 119.249605 -348.814858) (xy 119.213894 -348.856074) (xy 119.172681 -348.891789) (xy 119.126805 -348.921274)
			(xy 119.077199 -348.943932) (xy 119.024875 -348.959299) (xy 118.970895 -348.967064) (xy 118.943628 -348.967552)
			(xy 118.080028 -348.967552) (xy 118.052755 -348.96711) (xy 117.998764 -348.959351) (xy 117.946426 -348.943987)
			(xy 117.896808 -348.92133) (xy 117.85092 -348.891843) (xy 117.809695 -348.856124) (xy 117.773974 -348.814903)
			(xy 117.744483 -348.769016) (xy 117.721823 -348.7194) (xy 117.706455 -348.667064) (xy 117.698692 -348.613073)
			(xy 116.215988 -348.613073) (xy 116.208226 -348.66706) (xy 116.192858 -348.719394) (xy 116.170199 -348.769008)
			(xy 116.140709 -348.814892) (xy 116.104989 -348.856112) (xy 116.063766 -348.891828) (xy 116.01788 -348.921314)
			(xy 115.968264 -348.943969) (xy 115.915929 -348.959332) (xy 115.86194 -348.967091) (xy 115.834668 -348.967552)
			(xy 114.971068 -348.967552) (xy 114.943799 -348.967083) (xy 114.889818 -348.959318) (xy 114.837491 -348.943949)
			(xy 114.787883 -348.921291) (xy 114.742005 -348.891803) (xy 114.70079 -348.856087) (xy 114.665078 -348.814869)
			(xy 114.635594 -348.768989) (xy 114.61294 -348.719379) (xy 114.597575 -348.667051) (xy 114.589814 -348.613069)
			(xy 113.106966 -348.613069) (xy 113.099204 -348.66705) (xy 113.08384 -348.719377) (xy 113.061185 -348.768986)
			(xy 113.0317 -348.814865) (xy 112.995987 -348.856081) (xy 112.954771 -348.891796) (xy 112.908893 -348.921281)
			(xy 112.859285 -348.943937) (xy 112.806958 -348.959303) (xy 112.752976 -348.967065) (xy 112.725708 -348.967552)
			(xy 111.862108 -348.967552) (xy 111.834836 -348.967109) (xy 111.780847 -348.959348) (xy 111.728512 -348.943982)
			(xy 111.678896 -348.921324) (xy 111.63301 -348.891836) (xy 111.591788 -348.856117) (xy 111.556069 -348.814896)
			(xy 111.52658 -348.769011) (xy 111.503921 -348.719396) (xy 111.488554 -348.667061) (xy 111.480792 -348.613072)
			(xy 106.632431 -348.613072) (xy 106.596997 -348.653969) (xy 106.555816 -348.689657) (xy 106.509976 -348.719121)
			(xy 106.460409 -348.741762) (xy 106.408124 -348.757119) (xy 106.354186 -348.764879) (xy 106.32694 -348.765368)
			(xy 106.298201 -348.764863) (xy 106.241373 -348.756233) (xy 106.186483 -348.739177) (xy 106.134772 -348.714082)
			(xy 106.087409 -348.681515) (xy 106.066082 -348.662244) (xy 106.05897 -348.65564) (xy 106.041444 -348.648528)
			(xy 105.953052 -348.64802) (xy 105.935526 -348.654878) (xy 105.92816 -348.661228) (xy 105.906994 -348.679857)
			(xy 105.860182 -348.711288) (xy 105.809256 -348.73549) (xy 105.755323 -348.751936) (xy 105.699558 -348.76027)
			(xy 105.671366 -348.760796) (xy 105.644115 -348.760332) (xy 105.59017 -348.752571) (xy 105.537877 -348.737213)
			(xy 105.488303 -348.714569) (xy 105.442455 -348.685101) (xy 105.401268 -348.649408) (xy 105.365579 -348.608217)
			(xy 105.336115 -348.562367) (xy 105.313475 -348.512791) (xy 105.298122 -348.460497) (xy 105.290366 -348.406551)
			(xy 93.662683 -348.406551) (xy 93.683543 -348.45223) (xy 93.698905 -348.504555) (xy 93.706666 -348.558533)
			(xy 93.706666 -348.613067) (xy 93.698905 -348.667045) (xy 93.683543 -348.71937) (xy 93.66089 -348.768976)
			(xy 93.631409 -348.814854) (xy 93.595699 -348.856069) (xy 93.554487 -348.891784) (xy 93.508613 -348.92127)
			(xy 93.459009 -348.943928) (xy 93.406686 -348.959296) (xy 93.352709 -348.967063) (xy 93.325442 -348.967552)
			(xy 92.461842 -348.967552) (xy 92.434568 -348.967111) (xy 92.380576 -348.959354) (xy 92.328236 -348.943991)
			(xy 92.278617 -348.921335) (xy 92.232727 -348.891848) (xy 92.1915 -348.856129) (xy 92.155777 -348.814907)
			(xy 92.126285 -348.76902) (xy 92.103624 -348.719403) (xy 92.088255 -348.667066) (xy 92.080492 -348.613074)
			(xy 90.597788 -348.613074) (xy 90.590026 -348.667058) (xy 90.574659 -348.719391) (xy 90.552001 -348.769004)
			(xy 90.522512 -348.814887) (xy 90.486794 -348.856107) (xy 90.445573 -348.891823) (xy 90.399688 -348.92131)
			(xy 90.350074 -348.943966) (xy 90.297741 -348.95933) (xy 90.243753 -348.96709) (xy 90.216482 -348.967552)
			(xy 89.352882 -348.967552) (xy 89.325613 -348.967084) (xy 89.27163 -348.95932) (xy 89.219301 -348.943953)
			(xy 89.169692 -348.921295) (xy 89.123812 -348.891808) (xy 89.082595 -348.856092) (xy 89.046881 -348.814874)
			(xy 89.017396 -348.768992) (xy 88.994741 -348.719382) (xy 88.979376 -348.667053) (xy 88.971614 -348.613069)
			(xy 87.488766 -348.613069) (xy 87.481005 -348.667048) (xy 87.465641 -348.719374) (xy 87.442987 -348.768982)
			(xy 87.413504 -348.81486) (xy 87.377792 -348.856076) (xy 87.336578 -348.891791) (xy 87.290701 -348.921276)
			(xy 87.241095 -348.943933) (xy 87.188769 -348.9593) (xy 87.13479 -348.967064) (xy 87.107522 -348.967552)
			(xy 86.243922 -348.967552) (xy 86.216649 -348.96711) (xy 86.162659 -348.95935) (xy 86.110322 -348.943985)
			(xy 86.060705 -348.921329) (xy 86.014817 -348.891841) (xy 85.973593 -348.856122) (xy 85.937872 -348.814901)
			(xy 85.908382 -348.769015) (xy 85.885722 -348.719399) (xy 85.870354 -348.667063) (xy 85.862592 -348.613073)
			(xy 84.379888 -348.613073) (xy 84.372126 -348.667061) (xy 84.356758 -348.719395) (xy 84.334098 -348.76901)
			(xy 84.304608 -348.814894) (xy 84.268887 -348.856114) (xy 84.227663 -348.89183) (xy 84.181776 -348.921316)
			(xy 84.13216 -348.943971) (xy 84.079824 -348.959334) (xy 84.025834 -348.967091) (xy 83.998562 -348.967552)
			(xy 83.134962 -348.967552) (xy 83.107694 -348.967083) (xy 83.053713 -348.959317) (xy 83.001386 -348.943948)
			(xy 82.95178 -348.921289) (xy 82.905902 -348.891801) (xy 82.864688 -348.856085) (xy 82.828976 -348.814867)
			(xy 82.799493 -348.768987) (xy 82.776839 -348.719378) (xy 82.761475 -348.66705) (xy 82.753714 -348.613068)
			(xy 81.270866 -348.613068) (xy 81.270866 -348.613069) (xy 81.263104 -348.667051) (xy 81.247739 -348.719379)
			(xy 81.225084 -348.768987) (xy 81.195599 -348.814867) (xy 81.159885 -348.856083) (xy 81.118669 -348.891798)
			(xy 81.072789 -348.921283) (xy 81.02318 -348.943939) (xy 80.970853 -348.959304) (xy 80.916871 -348.967065)
			(xy 80.889602 -348.967552) (xy 80.026002 -348.967552) (xy 79.99873 -348.967109) (xy 79.944742 -348.959347)
			(xy 79.892407 -348.94398) (xy 79.842793 -348.921322) (xy 79.796908 -348.891834) (xy 79.755686 -348.856115)
			(xy 79.719968 -348.814894) (xy 79.690479 -348.769009) (xy 79.667821 -348.719394) (xy 79.652454 -348.66706)
			(xy 79.644692 -348.613072) (xy 78.161865 -348.613072) (xy 78.154105 -348.667045) (xy 78.138743 -348.71937)
			(xy 78.11609 -348.768976) (xy 78.086609 -348.814854) (xy 78.050899 -348.856069) (xy 78.009687 -348.891784)
			(xy 77.963813 -348.92127) (xy 77.914209 -348.943928) (xy 77.861886 -348.959296) (xy 77.807909 -348.967063)
			(xy 77.780642 -348.967552) (xy 76.917042 -348.967552) (xy 76.889768 -348.967111) (xy 76.835776 -348.959354)
			(xy 76.783436 -348.943991) (xy 76.733817 -348.921335) (xy 76.687927 -348.891848) (xy 76.6467 -348.856129)
			(xy 76.610977 -348.814907) (xy 76.581485 -348.76902) (xy 76.558824 -348.719403) (xy 76.543455 -348.667066)
			(xy 76.535692 -348.613074) (xy 75.052988 -348.613074) (xy 75.045226 -348.667058) (xy 75.029859 -348.719391)
			(xy 75.007201 -348.769004) (xy 74.977712 -348.814887) (xy 74.941994 -348.856107) (xy 74.900773 -348.891823)
			(xy 74.854888 -348.92131) (xy 74.805274 -348.943966) (xy 74.752941 -348.95933) (xy 74.698953 -348.96709)
			(xy 74.671682 -348.967552) (xy 73.808082 -348.967552) (xy 73.780813 -348.967084) (xy 73.72683 -348.95932)
			(xy 73.674501 -348.943953) (xy 73.624892 -348.921295) (xy 73.579012 -348.891808) (xy 73.537795 -348.856092)
			(xy 73.502081 -348.814874) (xy 73.472596 -348.768992) (xy 73.449941 -348.719382) (xy 73.434576 -348.667053)
			(xy 73.426814 -348.613069) (xy 71.943966 -348.613069) (xy 71.936205 -348.667048) (xy 71.920841 -348.719374)
			(xy 71.898187 -348.768982) (xy 71.868704 -348.81486) (xy 71.832992 -348.856076) (xy 71.791778 -348.891791)
			(xy 71.745901 -348.921276) (xy 71.696295 -348.943933) (xy 71.643969 -348.9593) (xy 71.58999 -348.967064)
			(xy 71.562722 -348.967552) (xy 70.699122 -348.967552) (xy 70.671849 -348.96711) (xy 70.617859 -348.95935)
			(xy 70.565522 -348.943985) (xy 70.515905 -348.921329) (xy 70.470017 -348.891841) (xy 70.428793 -348.856122)
			(xy 70.393072 -348.814901) (xy 70.363582 -348.769015) (xy 70.340922 -348.719399) (xy 70.325554 -348.667063)
			(xy 70.317792 -348.613073) (xy 68.835088 -348.613073) (xy 68.827326 -348.667061) (xy 68.811958 -348.719395)
			(xy 68.789298 -348.76901) (xy 68.759808 -348.814894) (xy 68.724087 -348.856114) (xy 68.682863 -348.89183)
			(xy 68.636976 -348.921316) (xy 68.58736 -348.943971) (xy 68.535024 -348.959334) (xy 68.481034 -348.967091)
			(xy 68.453762 -348.967552) (xy 67.590162 -348.967552) (xy 67.562894 -348.967083) (xy 67.508913 -348.959317)
			(xy 67.456586 -348.943948) (xy 67.40698 -348.921289) (xy 67.361102 -348.891801) (xy 67.319888 -348.856085)
			(xy 67.284176 -348.814867) (xy 67.254693 -348.768987) (xy 67.232039 -348.719378) (xy 67.216675 -348.66705)
			(xy 67.208914 -348.613068) (xy 65.726066 -348.613068) (xy 65.726066 -348.613069) (xy 65.718304 -348.667051)
			(xy 65.702939 -348.719379) (xy 65.680284 -348.768987) (xy 65.650799 -348.814867) (xy 65.615085 -348.856083)
			(xy 65.573869 -348.891798) (xy 65.527989 -348.921283) (xy 65.47838 -348.943939) (xy 65.426053 -348.959304)
			(xy 65.372071 -348.967065) (xy 65.344802 -348.967552) (xy 64.481202 -348.967552) (xy 64.45393 -348.967109)
			(xy 64.399942 -348.959347) (xy 64.347607 -348.94398) (xy 64.297993 -348.921322) (xy 64.252108 -348.891834)
			(xy 64.210886 -348.856115) (xy 64.175168 -348.814894) (xy 64.145679 -348.769009) (xy 64.123021 -348.719394)
			(xy 64.107654 -348.66706) (xy 64.099892 -348.613072) (xy 62.617065 -348.613072) (xy 62.609305 -348.667045)
			(xy 62.593943 -348.71937) (xy 62.57129 -348.768976) (xy 62.541809 -348.814854) (xy 62.506099 -348.856069)
			(xy 62.464887 -348.891784) (xy 62.419013 -348.92127) (xy 62.369409 -348.943928) (xy 62.317086 -348.959296)
			(xy 62.263109 -348.967063) (xy 62.235842 -348.967552) (xy 61.372242 -348.967552) (xy 61.344968 -348.967111)
			(xy 61.290976 -348.959354) (xy 61.238636 -348.943991) (xy 61.189017 -348.921335) (xy 61.143127 -348.891848)
			(xy 61.1019 -348.856129) (xy 61.066177 -348.814907) (xy 61.036685 -348.76902) (xy 61.014024 -348.719403)
			(xy 60.998655 -348.667066) (xy 60.990892 -348.613074) (xy 58.978019 -348.613074) (xy 57.813415 -351.63867)
			(xy 60.99094 -351.63867) (xy 60.99094 -351.58413) (xy 60.998702 -351.530145) (xy 61.014069 -351.477814)
			(xy 61.036727 -351.428203) (xy 61.066216 -351.382322) (xy 61.101934 -351.341105) (xy 61.143155 -351.305391)
			(xy 61.18904 -351.275907) (xy 61.238653 -351.253254) (xy 61.290986 -351.237893) (xy 61.344972 -351.230137)
			(xy 61.372242 -351.229676) (xy 62.235842 -351.229676) (xy 62.263112 -351.230089) (xy 62.317097 -351.237857)
			(xy 62.369426 -351.253227) (xy 62.419036 -351.275888) (xy 62.464916 -351.305378) (xy 62.506133 -351.341097)
			(xy 62.541847 -351.382317) (xy 62.571332 -351.428201) (xy 62.593988 -351.477813) (xy 62.609352 -351.530145)
			(xy 62.617114 -351.58413) (xy 62.617114 -351.638668) (xy 64.099939 -351.638668) (xy 64.099939 -351.584132)
			(xy 64.107701 -351.53015) (xy 64.123066 -351.477822) (xy 64.145721 -351.428214) (xy 64.175206 -351.382335)
			(xy 64.21092 -351.341119) (xy 64.252136 -351.305405) (xy 64.298016 -351.27592) (xy 64.347624 -351.253265)
			(xy 64.399952 -351.2379) (xy 64.453934 -351.230139) (xy 64.481202 -351.229676) (xy 65.344802 -351.229676)
			(xy 65.372074 -351.230087) (xy 65.426063 -351.237849) (xy 65.478397 -351.253216) (xy 65.528012 -351.275875)
			(xy 65.573897 -351.305364) (xy 65.615119 -351.341083) (xy 65.650837 -351.382304) (xy 65.680326 -351.42819)
			(xy 65.702984 -351.477805) (xy 65.718351 -351.530139) (xy 65.726113 -351.584128) (xy 65.726113 -351.638665)
			(xy 67.208962 -351.638665) (xy 67.208962 -351.584135) (xy 67.216722 -351.53016) (xy 67.232084 -351.477839)
			(xy 67.254735 -351.428236) (xy 67.284215 -351.382362) (xy 67.319922 -351.341149) (xy 67.361131 -351.305437)
			(xy 67.407003 -351.275953) (xy 67.456603 -351.253297) (xy 67.508923 -351.23793) (xy 67.562897 -351.230165)
			(xy 67.590162 -351.229676) (xy 68.453762 -351.229676) (xy 68.481037 -351.230061) (xy 68.535034 -351.23782)
			(xy 68.587376 -351.253184) (xy 68.636999 -351.275842) (xy 68.682892 -351.305331) (xy 68.724121 -351.341052)
			(xy 68.759846 -351.382277) (xy 68.78934 -351.428167) (xy 68.812003 -351.477788) (xy 68.827372 -351.530129)
			(xy 68.835136 -351.584125) (xy 68.835136 -351.638669) (xy 70.317839 -351.638669) (xy 70.317839 -351.584131)
			(xy 70.325601 -351.530147) (xy 70.340967 -351.477818) (xy 70.363624 -351.428208) (xy 70.393111 -351.382328)
			(xy 70.428827 -351.341112) (xy 70.470046 -351.305398) (xy 70.515928 -351.275914) (xy 70.565539 -351.25326)
			(xy 70.617869 -351.237897) (xy 70.671853 -351.230138) (xy 70.699122 -351.229676) (xy 71.562722 -351.229676)
			(xy 71.589993 -351.230088) (xy 71.64398 -351.237853) (xy 71.696312 -351.253222) (xy 71.745924 -351.275881)
			(xy 71.791807 -351.305371) (xy 71.833026 -351.34109) (xy 71.868742 -351.382311) (xy 71.898229 -351.428195)
			(xy 71.920886 -351.477809) (xy 71.936252 -351.530142) (xy 71.944014 -351.584129) (xy 71.944014 -351.638666)
			(xy 73.426862 -351.638666) (xy 73.426862 -351.584134) (xy 73.434623 -351.530158) (xy 73.449986 -351.477835)
			(xy 73.472638 -351.428231) (xy 73.50212 -351.382355) (xy 73.537829 -351.341142) (xy 73.579041 -351.30543)
			(xy 73.624915 -351.275947) (xy 73.674518 -351.253292) (xy 73.72684 -351.237927) (xy 73.780816 -351.230164)
			(xy 73.808082 -351.229676) (xy 74.671682 -351.229676) (xy 74.698957 -351.230062) (xy 74.752951 -351.237823)
			(xy 74.805291 -351.253189) (xy 74.854911 -351.275848) (xy 74.900802 -351.305338) (xy 74.942028 -351.341059)
			(xy 74.977751 -351.382284) (xy 75.007243 -351.428173) (xy 75.029904 -351.477792) (xy 75.045273 -351.530132)
			(xy 75.053036 -351.584125) (xy 75.053036 -351.63867) (xy 76.53574 -351.63867) (xy 76.53574 -351.58413)
			(xy 76.543502 -351.530145) (xy 76.558869 -351.477814) (xy 76.581527 -351.428203) (xy 76.611016 -351.382322)
			(xy 76.646734 -351.341105) (xy 76.687955 -351.305391) (xy 76.73384 -351.275907) (xy 76.783453 -351.253254)
			(xy 76.835786 -351.237893) (xy 76.889772 -351.230137) (xy 76.917042 -351.229676) (xy 77.780642 -351.229676)
			(xy 77.807912 -351.230089) (xy 77.861897 -351.237857) (xy 77.914226 -351.253227) (xy 77.963836 -351.275888)
			(xy 78.009716 -351.305378) (xy 78.050933 -351.341097) (xy 78.086647 -351.382317) (xy 78.116132 -351.428201)
			(xy 78.138788 -351.477813) (xy 78.154152 -351.530145) (xy 78.161914 -351.58413) (xy 78.161914 -351.638668)
			(xy 79.644739 -351.638668) (xy 79.644739 -351.584132) (xy 79.652501 -351.53015) (xy 79.667866 -351.477822)
			(xy 79.690521 -351.428214) (xy 79.720006 -351.382335) (xy 79.75572 -351.341119) (xy 79.796936 -351.305405)
			(xy 79.842816 -351.27592) (xy 79.892424 -351.253265) (xy 79.944752 -351.2379) (xy 79.998734 -351.230139)
			(xy 80.026002 -351.229676) (xy 80.889602 -351.229676) (xy 80.916874 -351.230087) (xy 80.970863 -351.237849)
			(xy 81.023197 -351.253216) (xy 81.072812 -351.275875) (xy 81.118697 -351.305364) (xy 81.159919 -351.341083)
			(xy 81.195637 -351.382304) (xy 81.225126 -351.42819) (xy 81.247784 -351.477805) (xy 81.263151 -351.530139)
			(xy 81.270913 -351.584128) (xy 81.270913 -351.638665) (xy 82.753762 -351.638665) (xy 82.753762 -351.584135)
			(xy 82.761522 -351.53016) (xy 82.776884 -351.477839) (xy 82.799535 -351.428236) (xy 82.829015 -351.382362)
			(xy 82.864722 -351.341149) (xy 82.905931 -351.305437) (xy 82.951803 -351.275953) (xy 83.001403 -351.253297)
			(xy 83.053723 -351.23793) (xy 83.107697 -351.230165) (xy 83.134962 -351.229676) (xy 83.998562 -351.229676)
			(xy 84.025837 -351.230061) (xy 84.079834 -351.23782) (xy 84.132176 -351.253184) (xy 84.181799 -351.275842)
			(xy 84.227692 -351.305331) (xy 84.268921 -351.341052) (xy 84.304646 -351.382277) (xy 84.33414 -351.428167)
			(xy 84.356803 -351.477788) (xy 84.372172 -351.530129) (xy 84.379936 -351.584125) (xy 84.379936 -351.638669)
			(xy 85.862639 -351.638669) (xy 85.862639 -351.584131) (xy 85.870401 -351.530147) (xy 85.885767 -351.477818)
			(xy 85.908424 -351.428208) (xy 85.937911 -351.382328) (xy 85.973627 -351.341112) (xy 86.014846 -351.305398)
			(xy 86.060728 -351.275914) (xy 86.110339 -351.25326) (xy 86.162669 -351.237897) (xy 86.216653 -351.230138)
			(xy 86.243922 -351.229676) (xy 87.107522 -351.229676) (xy 87.134793 -351.230088) (xy 87.18878 -351.237853)
			(xy 87.241112 -351.253222) (xy 87.290724 -351.275881) (xy 87.336607 -351.305371) (xy 87.377826 -351.34109)
			(xy 87.413542 -351.382311) (xy 87.443029 -351.428195) (xy 87.465686 -351.477809) (xy 87.481052 -351.530142)
			(xy 87.488814 -351.584129) (xy 87.488814 -351.638666) (xy 88.971662 -351.638666) (xy 88.971662 -351.584134)
			(xy 88.979423 -351.530158) (xy 88.994786 -351.477835) (xy 89.017438 -351.428231) (xy 89.04692 -351.382355)
			(xy 89.082629 -351.341142) (xy 89.123841 -351.30543) (xy 89.169715 -351.275947) (xy 89.219318 -351.253292)
			(xy 89.27164 -351.237927) (xy 89.325616 -351.230164) (xy 89.352882 -351.229676) (xy 90.216482 -351.229676)
			(xy 90.243757 -351.230062) (xy 90.297751 -351.237823) (xy 90.350091 -351.253189) (xy 90.399711 -351.275848)
			(xy 90.445602 -351.305338) (xy 90.486828 -351.341059) (xy 90.522551 -351.382284) (xy 90.552043 -351.428173)
			(xy 90.574704 -351.477792) (xy 90.590073 -351.530132) (xy 90.597836 -351.584125) (xy 90.597836 -351.63867)
			(xy 92.08054 -351.63867) (xy 92.08054 -351.58413) (xy 92.088302 -351.530145) (xy 92.103669 -351.477814)
			(xy 92.126327 -351.428203) (xy 92.155816 -351.382322) (xy 92.191534 -351.341105) (xy 92.232755 -351.305391)
			(xy 92.27864 -351.275907) (xy 92.328253 -351.253254) (xy 92.380586 -351.237893) (xy 92.434572 -351.230137)
			(xy 92.461842 -351.229676) (xy 93.325442 -351.229676) (xy 93.352712 -351.230089) (xy 93.406697 -351.237857)
			(xy 93.459026 -351.253227) (xy 93.508636 -351.275888) (xy 93.554516 -351.305378) (xy 93.595733 -351.341097)
			(xy 93.631447 -351.382317) (xy 93.645329 -351.40392) (xy 99.12426 -351.40392) (xy 99.128331 -351.348298)
			(xy 99.140457 -351.293861) (xy 99.16038 -351.24177) (xy 99.187676 -351.193135) (xy 99.221762 -351.148992)
			(xy 99.261911 -351.110283) (xy 99.307269 -351.077832) (xy 99.356869 -351.052331) (xy 99.409653 -351.034324)
			(xy 99.464496 -351.024194) (xy 99.52023 -351.022157) (xy 99.575667 -351.028257) (xy 99.629624 -351.042363)
			(xy 99.680953 -351.064175) (xy 99.728559 -351.093229) (xy 99.771427 -351.128904) (xy 99.808644 -351.170441)
			(xy 99.839417 -351.216954) (xy 99.863089 -351.267451) (xy 99.879157 -351.320858) (xy 99.887277 -351.376034)
			(xy 99.887786 -351.40392) (xy 99.887277 -351.431806) (xy 99.879157 -351.486982) (xy 99.871134 -351.513648)
			(xy 106.459526 -351.513648) (xy 106.463597 -351.458026) (xy 106.475723 -351.403589) (xy 106.495646 -351.351498)
			(xy 106.522942 -351.302863) (xy 106.557028 -351.25872) (xy 106.597177 -351.220011) (xy 106.642535 -351.18756)
			(xy 106.692135 -351.162059) (xy 106.744919 -351.144052) (xy 106.799762 -351.133922) (xy 106.855496 -351.131885)
			(xy 106.910933 -351.137985) (xy 106.96489 -351.152091) (xy 107.016219 -351.173903) (xy 107.063825 -351.202957)
			(xy 107.106693 -351.238632) (xy 107.14391 -351.280169) (xy 107.174683 -351.326682) (xy 107.198355 -351.377179)
			(xy 107.214423 -351.430586) (xy 107.222543 -351.485762) (xy 107.223052 -351.513648) (xy 107.222543 -351.541534)
			(xy 107.214423 -351.59671) (xy 107.201799 -351.638669) (xy 111.480839 -351.638669) (xy 111.480839 -351.584131)
			(xy 111.488601 -351.530149) (xy 111.503966 -351.477821) (xy 111.526622 -351.428212) (xy 111.556107 -351.382333)
			(xy 111.591822 -351.341117) (xy 111.633039 -351.305403) (xy 111.678919 -351.275918) (xy 111.728529 -351.253263)
			(xy 111.780857 -351.237899) (xy 111.834839 -351.230139) (xy 111.862108 -351.229676) (xy 112.725708 -351.229676)
			(xy 112.75298 -351.230087) (xy 112.806968 -351.23785) (xy 112.859302 -351.253218) (xy 112.908916 -351.275877)
			(xy 112.9548 -351.305366) (xy 112.996021 -351.341085) (xy 113.031739 -351.382306) (xy 113.061227 -351.428191)
			(xy 113.083885 -351.477806) (xy 113.099251 -351.53014) (xy 113.107014 -351.584128) (xy 113.107014 -351.638665)
			(xy 114.589862 -351.638665) (xy 114.589862 -351.584135) (xy 114.597622 -351.530159) (xy 114.612984 -351.477838)
			(xy 114.635636 -351.428234) (xy 114.665116 -351.38236) (xy 114.700824 -351.341147) (xy 114.742034 -351.305435)
			(xy 114.787906 -351.275951) (xy 114.837508 -351.253296) (xy 114.889828 -351.237929) (xy 114.943803 -351.230165)
			(xy 114.971068 -351.229676) (xy 115.834668 -351.229676) (xy 115.861943 -351.230061) (xy 115.915939 -351.237821)
			(xy 115.968281 -351.253186) (xy 116.017903 -351.275844) (xy 116.063795 -351.305333) (xy 116.105023 -351.341054)
			(xy 116.140747 -351.382279) (xy 116.170241 -351.428169) (xy 116.192903 -351.477789) (xy 116.208273 -351.53013)
			(xy 116.216036 -351.584125) (xy 116.216036 -351.63867) (xy 117.698739 -351.63867) (xy 117.698739 -351.58413)
			(xy 117.706502 -351.530146) (xy 117.721868 -351.477817) (xy 117.744525 -351.428207) (xy 117.774012 -351.382326)
			(xy 117.809729 -351.341109) (xy 117.850949 -351.305396) (xy 117.896831 -351.275912) (xy 117.946443 -351.253258)
			(xy 117.998774 -351.237896) (xy 118.052758 -351.230137) (xy 118.080028 -351.229676) (xy 118.943628 -351.229676)
			(xy 118.970899 -351.230088) (xy 119.024885 -351.237854) (xy 119.077216 -351.253223) (xy 119.126828 -351.275883)
			(xy 119.17271 -351.305373) (xy 119.213928 -351.341092) (xy 119.249644 -351.382313) (xy 119.27913 -351.428197)
			(xy 119.301786 -351.47781) (xy 119.317152 -351.530143) (xy 119.324914 -351.584129) (xy 119.324914 -351.638666)
			(xy 120.807762 -351.638666) (xy 120.807762 -351.584134) (xy 120.815523 -351.530157) (xy 120.830886 -351.477833)
			(xy 120.853539 -351.428229) (xy 120.883021 -351.382353) (xy 120.918731 -351.34114) (xy 120.959943 -351.305428)
			(xy 121.005818 -351.275945) (xy 121.055422 -351.25329) (xy 121.107745 -351.237925) (xy 121.161722 -351.230163)
			(xy 121.188988 -351.229676) (xy 122.052588 -351.229676) (xy 122.079862 -351.230063) (xy 122.133856 -351.237824)
			(xy 122.186195 -351.253191) (xy 122.235815 -351.27585) (xy 122.281704 -351.30534) (xy 122.32293 -351.341061)
			(xy 122.358652 -351.382286) (xy 122.388144 -351.428175) (xy 122.410805 -351.477794) (xy 122.426173 -351.530132)
			(xy 122.433936 -351.584126) (xy 122.433936 -351.63867) (xy 123.91664 -351.63867) (xy 123.91664 -351.58413)
			(xy 123.924402 -351.530144) (xy 123.939769 -351.477812) (xy 123.962428 -351.428201) (xy 123.991917 -351.38232)
			(xy 124.027636 -351.341102) (xy 124.068858 -351.305388) (xy 124.114743 -351.275905) (xy 124.164358 -351.253253)
			(xy 124.216691 -351.237892) (xy 124.270677 -351.230136) (xy 124.297948 -351.229676) (xy 125.161548 -351.229676)
			(xy 125.188818 -351.23009) (xy 125.242802 -351.237858) (xy 125.295131 -351.253229) (xy 125.34474 -351.27589)
			(xy 125.390619 -351.30538) (xy 125.431835 -351.341099) (xy 125.467549 -351.382319) (xy 125.497033 -351.428203)
			(xy 125.519688 -351.477814) (xy 125.535052 -351.530145) (xy 125.542814 -351.58413) (xy 125.542814 -351.638669)
			(xy 127.025639 -351.638669) (xy 127.025639 -351.584131) (xy 127.033401 -351.530149) (xy 127.048766 -351.477821)
			(xy 127.071422 -351.428212) (xy 127.100907 -351.382333) (xy 127.136622 -351.341117) (xy 127.177839 -351.305403)
			(xy 127.223719 -351.275918) (xy 127.273329 -351.253263) (xy 127.325657 -351.237899) (xy 127.379639 -351.230139)
			(xy 127.406908 -351.229676) (xy 128.270508 -351.229676) (xy 128.29778 -351.230087) (xy 128.351768 -351.23785)
			(xy 128.404102 -351.253218) (xy 128.453716 -351.275877) (xy 128.4996 -351.305366) (xy 128.540821 -351.341085)
			(xy 128.576539 -351.382306) (xy 128.606027 -351.428191) (xy 128.628685 -351.477806) (xy 128.644051 -351.53014)
			(xy 128.651814 -351.584128) (xy 128.651814 -351.638665) (xy 130.134662 -351.638665) (xy 130.134662 -351.584135)
			(xy 130.142422 -351.530159) (xy 130.157784 -351.477838) (xy 130.180436 -351.428234) (xy 130.209916 -351.38236)
			(xy 130.245624 -351.341147) (xy 130.286834 -351.305435) (xy 130.332706 -351.275951) (xy 130.382308 -351.253296)
			(xy 130.434628 -351.237929) (xy 130.488603 -351.230165) (xy 130.515868 -351.229676) (xy 131.379468 -351.229676)
			(xy 131.406743 -351.230061) (xy 131.460739 -351.237821) (xy 131.513081 -351.253186) (xy 131.562703 -351.275844)
			(xy 131.608595 -351.305333) (xy 131.649823 -351.341054) (xy 131.685547 -351.382279) (xy 131.715041 -351.428169)
			(xy 131.737703 -351.477789) (xy 131.753073 -351.53013) (xy 131.760836 -351.584125) (xy 131.760836 -351.63867)
			(xy 133.243539 -351.63867) (xy 133.243539 -351.58413) (xy 133.251302 -351.530146) (xy 133.266668 -351.477817)
			(xy 133.289325 -351.428207) (xy 133.318812 -351.382326) (xy 133.354529 -351.341109) (xy 133.395749 -351.305396)
			(xy 133.441631 -351.275912) (xy 133.491243 -351.253258) (xy 133.543574 -351.237896) (xy 133.597558 -351.230137)
			(xy 133.624828 -351.229676) (xy 134.488428 -351.229676) (xy 134.515699 -351.230088) (xy 134.569685 -351.237854)
			(xy 134.622016 -351.253223) (xy 134.671628 -351.275883) (xy 134.71751 -351.305373) (xy 134.758728 -351.341092)
			(xy 134.794444 -351.382313) (xy 134.82393 -351.428197) (xy 134.846586 -351.47781) (xy 134.861952 -351.530143)
			(xy 134.869714 -351.584129) (xy 134.869714 -351.638666) (xy 136.352562 -351.638666) (xy 136.352562 -351.584134)
			(xy 136.360323 -351.530157) (xy 136.375686 -351.477833) (xy 136.398339 -351.428229) (xy 136.427821 -351.382353)
			(xy 136.463531 -351.34114) (xy 136.504743 -351.305428) (xy 136.550618 -351.275945) (xy 136.600222 -351.25329)
			(xy 136.652545 -351.237925) (xy 136.706522 -351.230163) (xy 136.733788 -351.229676) (xy 137.597388 -351.229676)
			(xy 137.624662 -351.230063) (xy 137.678656 -351.237824) (xy 137.730995 -351.253191) (xy 137.780615 -351.27585)
			(xy 137.826504 -351.30534) (xy 137.86773 -351.341061) (xy 137.903452 -351.382286) (xy 137.932944 -351.428175)
			(xy 137.955605 -351.477794) (xy 137.970973 -351.530132) (xy 137.978736 -351.584126) (xy 137.978736 -351.63867)
			(xy 139.46144 -351.63867) (xy 139.46144 -351.58413) (xy 139.469202 -351.530144) (xy 139.484569 -351.477812)
			(xy 139.507228 -351.428201) (xy 139.536717 -351.38232) (xy 139.572436 -351.341102) (xy 139.613658 -351.305388)
			(xy 139.659543 -351.275905) (xy 139.709158 -351.253253) (xy 139.761491 -351.237892) (xy 139.815477 -351.230136)
			(xy 139.842748 -351.229676) (xy 140.706348 -351.229676) (xy 140.733618 -351.23009) (xy 140.787602 -351.237858)
			(xy 140.839931 -351.253229) (xy 140.88954 -351.27589) (xy 140.935419 -351.30538) (xy 140.976635 -351.341099)
			(xy 141.012349 -351.382319) (xy 141.041833 -351.428203) (xy 141.064488 -351.477814) (xy 141.079852 -351.530145)
			(xy 141.087614 -351.58413) (xy 141.087614 -351.638669) (xy 142.570439 -351.638669) (xy 142.570439 -351.584131)
			(xy 142.578201 -351.530149) (xy 142.593566 -351.477821) (xy 142.616222 -351.428212) (xy 142.645707 -351.382333)
			(xy 142.681422 -351.341117) (xy 142.722639 -351.305403) (xy 142.768519 -351.275918) (xy 142.818129 -351.253263)
			(xy 142.870457 -351.237899) (xy 142.924439 -351.230139) (xy 142.951708 -351.229676) (xy 143.815308 -351.229676)
			(xy 143.84258 -351.230087) (xy 143.896568 -351.23785) (xy 143.948902 -351.253218) (xy 143.998516 -351.275877)
			(xy 144.0444 -351.305366) (xy 144.085621 -351.341085) (xy 144.121339 -351.382306) (xy 144.150827 -351.428191)
			(xy 144.173485 -351.477806) (xy 144.188851 -351.53014) (xy 144.196614 -351.584128) (xy 144.196614 -351.638672)
			(xy 144.188851 -351.69266) (xy 144.173485 -351.744994) (xy 144.150827 -351.794609) (xy 144.121339 -351.840494)
			(xy 144.085621 -351.881715) (xy 144.0444 -351.917434) (xy 143.998516 -351.946923) (xy 143.948902 -351.969582)
			(xy 143.896568 -351.98495) (xy 143.84258 -351.992713) (xy 143.815308 -351.9932) (xy 142.951708 -351.9932)
			(xy 142.924439 -351.992661) (xy 142.870457 -351.984901) (xy 142.818129 -351.969537) (xy 142.768519 -351.946882)
			(xy 142.722639 -351.917397) (xy 142.681422 -351.881683) (xy 142.645707 -351.840467) (xy 142.616222 -351.794588)
			(xy 142.593566 -351.744979) (xy 142.578201 -351.692651) (xy 142.570439 -351.638669) (xy 141.087614 -351.638669)
			(xy 141.087614 -351.63867) (xy 141.079852 -351.692655) (xy 141.064488 -351.744986) (xy 141.041833 -351.794597)
			(xy 141.012349 -351.840481) (xy 140.976635 -351.881701) (xy 140.935419 -351.91742) (xy 140.88954 -351.94691)
			(xy 140.839931 -351.969571) (xy 140.787602 -351.984942) (xy 140.733618 -351.99271) (xy 140.706348 -351.9932)
			(xy 139.842748 -351.9932) (xy 139.815477 -351.992664) (xy 139.761491 -351.984908) (xy 139.709158 -351.969547)
			(xy 139.659543 -351.946895) (xy 139.613658 -351.917411) (xy 139.572436 -351.881698) (xy 139.536717 -351.84048)
			(xy 139.507228 -351.794599) (xy 139.484569 -351.744987) (xy 139.469202 -351.692656) (xy 139.46144 -351.63867)
			(xy 137.978736 -351.63867) (xy 137.978736 -351.638674) (xy 137.970973 -351.692668) (xy 137.955605 -351.745006)
			(xy 137.932944 -351.794625) (xy 137.903452 -351.840514) (xy 137.86773 -351.881739) (xy 137.826504 -351.91746)
			(xy 137.780615 -351.94695) (xy 137.730995 -351.969609) (xy 137.678656 -351.984976) (xy 137.624662 -351.992737)
			(xy 137.597388 -351.9932) (xy 136.733788 -351.9932) (xy 136.706522 -351.992637) (xy 136.652545 -351.984875)
			(xy 136.600222 -351.96951) (xy 136.550618 -351.946855) (xy 136.504744 -351.917372) (xy 136.463531 -351.88166)
			(xy 136.427821 -351.840447) (xy 136.398339 -351.794571) (xy 136.375686 -351.744967) (xy 136.360323 -351.692643)
			(xy 136.352562 -351.638666) (xy 134.869714 -351.638666) (xy 134.869714 -351.638671) (xy 134.861952 -351.692657)
			(xy 134.846586 -351.74499) (xy 134.82393 -351.794603) (xy 134.794444 -351.840487) (xy 134.758728 -351.881708)
			(xy 134.71751 -351.917427) (xy 134.671628 -351.946917) (xy 134.622016 -351.969577) (xy 134.569685 -351.984946)
			(xy 134.515699 -351.992712) (xy 134.488428 -351.9932) (xy 133.624828 -351.9932) (xy 133.597558 -351.992663)
			(xy 133.543574 -351.984904) (xy 133.491243 -351.969542) (xy 133.441631 -351.946888) (xy 133.395749 -351.917404)
			(xy 133.354529 -351.881691) (xy 133.318812 -351.840474) (xy 133.289325 -351.794593) (xy 133.266668 -351.744983)
			(xy 133.251302 -351.692654) (xy 133.243539 -351.63867) (xy 131.760836 -351.63867) (xy 131.760836 -351.638675)
			(xy 131.753073 -351.69267) (xy 131.737703 -351.745011) (xy 131.715041 -351.794631) (xy 131.685547 -351.840521)
			(xy 131.649823 -351.881746) (xy 131.608595 -351.917467) (xy 131.562703 -351.946956) (xy 131.513081 -351.969614)
			(xy 131.460739 -351.984979) (xy 131.406743 -351.992739) (xy 131.379468 -351.9932) (xy 130.515868 -351.9932)
			(xy 130.488603 -351.992635) (xy 130.434628 -351.984871) (xy 130.382308 -351.969504) (xy 130.332706 -351.946849)
			(xy 130.286834 -351.917365) (xy 130.245624 -351.881653) (xy 130.209916 -351.84044) (xy 130.180436 -351.794566)
			(xy 130.157784 -351.744962) (xy 130.142422 -351.692641) (xy 130.134662 -351.638665) (xy 128.651814 -351.638665)
			(xy 128.651814 -351.638672) (xy 128.644051 -351.69266) (xy 128.628685 -351.744994) (xy 128.606027 -351.794609)
			(xy 128.576539 -351.840494) (xy 128.540821 -351.881715) (xy 128.4996 -351.917434) (xy 128.453716 -351.946923)
			(xy 128.404102 -351.969582) (xy 128.351768 -351.98495) (xy 128.29778 -351.992713) (xy 128.270508 -351.9932)
			(xy 127.406908 -351.9932) (xy 127.379639 -351.992661) (xy 127.325657 -351.984901) (xy 127.273329 -351.969537)
			(xy 127.223719 -351.946882) (xy 127.177839 -351.917397) (xy 127.136622 -351.881683) (xy 127.100907 -351.840467)
			(xy 127.071422 -351.794588) (xy 127.048766 -351.744979) (xy 127.033401 -351.692651) (xy 127.025639 -351.638669)
			(xy 125.542814 -351.638669) (xy 125.542814 -351.63867) (xy 125.535052 -351.692655) (xy 125.519688 -351.744986)
			(xy 125.497033 -351.794597) (xy 125.467549 -351.840481) (xy 125.431835 -351.881701) (xy 125.390619 -351.91742)
			(xy 125.34474 -351.94691) (xy 125.295131 -351.969571) (xy 125.242802 -351.984942) (xy 125.188818 -351.99271)
			(xy 125.161548 -351.9932) (xy 124.297948 -351.9932) (xy 124.270677 -351.992664) (xy 124.216691 -351.984908)
			(xy 124.164358 -351.969547) (xy 124.114743 -351.946895) (xy 124.068858 -351.917411) (xy 124.027636 -351.881698)
			(xy 123.991917 -351.84048) (xy 123.962428 -351.794599) (xy 123.939769 -351.744987) (xy 123.924402 -351.692656)
			(xy 123.91664 -351.63867) (xy 122.433936 -351.63867) (xy 122.433936 -351.638674) (xy 122.426173 -351.692668)
			(xy 122.410805 -351.745006) (xy 122.388144 -351.794625) (xy 122.358652 -351.840514) (xy 122.32293 -351.881739)
			(xy 122.281704 -351.91746) (xy 122.235815 -351.94695) (xy 122.186195 -351.969609) (xy 122.133856 -351.984976)
			(xy 122.079862 -351.992737) (xy 122.052588 -351.9932) (xy 121.188988 -351.9932) (xy 121.161722 -351.992637)
			(xy 121.107745 -351.984875) (xy 121.055422 -351.96951) (xy 121.005818 -351.946855) (xy 120.959944 -351.917372)
			(xy 120.918731 -351.88166) (xy 120.883021 -351.840447) (xy 120.853539 -351.794571) (xy 120.830886 -351.744967)
			(xy 120.815523 -351.692643) (xy 120.807762 -351.638666) (xy 119.324914 -351.638666) (xy 119.324914 -351.638671)
			(xy 119.317152 -351.692657) (xy 119.301786 -351.74499) (xy 119.27913 -351.794603) (xy 119.249644 -351.840487)
			(xy 119.213928 -351.881708) (xy 119.17271 -351.917427) (xy 119.126828 -351.946917) (xy 119.077216 -351.969577)
			(xy 119.024885 -351.984946) (xy 118.970899 -351.992712) (xy 118.943628 -351.9932) (xy 118.080028 -351.9932)
			(xy 118.052758 -351.992663) (xy 117.998774 -351.984904) (xy 117.946443 -351.969542) (xy 117.896831 -351.946888)
			(xy 117.850949 -351.917404) (xy 117.809729 -351.881691) (xy 117.774012 -351.840474) (xy 117.744525 -351.794593)
			(xy 117.721868 -351.744983) (xy 117.706502 -351.692654) (xy 117.698739 -351.63867) (xy 116.216036 -351.63867)
			(xy 116.216036 -351.638675) (xy 116.208273 -351.69267) (xy 116.192903 -351.745011) (xy 116.170241 -351.794631)
			(xy 116.140747 -351.840521) (xy 116.105023 -351.881746) (xy 116.063795 -351.917467) (xy 116.017903 -351.946956)
			(xy 115.968281 -351.969614) (xy 115.915939 -351.984979) (xy 115.861943 -351.992739) (xy 115.834668 -351.9932)
			(xy 114.971068 -351.9932) (xy 114.943803 -351.992635) (xy 114.889828 -351.984871) (xy 114.837508 -351.969504)
			(xy 114.787906 -351.946849) (xy 114.742034 -351.917365) (xy 114.700824 -351.881653) (xy 114.665116 -351.84044)
			(xy 114.635636 -351.794566) (xy 114.612984 -351.744962) (xy 114.597622 -351.692641) (xy 114.589862 -351.638665)
			(xy 113.107014 -351.638665) (xy 113.107014 -351.638672) (xy 113.099251 -351.69266) (xy 113.083885 -351.744994)
			(xy 113.061227 -351.794609) (xy 113.031739 -351.840494) (xy 112.996021 -351.881715) (xy 112.9548 -351.917434)
			(xy 112.908916 -351.946923) (xy 112.859302 -351.969582) (xy 112.806968 -351.98495) (xy 112.75298 -351.992713)
			(xy 112.725708 -351.9932) (xy 111.862108 -351.9932) (xy 111.834839 -351.992661) (xy 111.780857 -351.984901)
			(xy 111.728529 -351.969537) (xy 111.678919 -351.946882) (xy 111.633039 -351.917397) (xy 111.591822 -351.881683)
			(xy 111.556107 -351.840467) (xy 111.526622 -351.794588) (xy 111.503966 -351.744979) (xy 111.488601 -351.692651)
			(xy 111.480839 -351.638669) (xy 107.201799 -351.638669) (xy 107.198355 -351.650117) (xy 107.174683 -351.700614)
			(xy 107.14391 -351.747127) (xy 107.106693 -351.788664) (xy 107.063825 -351.824339) (xy 107.016219 -351.853393)
			(xy 106.96489 -351.875205) (xy 106.910933 -351.889311) (xy 106.855496 -351.895411) (xy 106.799762 -351.893374)
			(xy 106.744919 -351.883244) (xy 106.692135 -351.865237) (xy 106.642535 -351.839736) (xy 106.597177 -351.807285)
			(xy 106.557028 -351.768576) (xy 106.522942 -351.724433) (xy 106.495646 -351.675798) (xy 106.475723 -351.623707)
			(xy 106.463597 -351.56927) (xy 106.459526 -351.513648) (xy 99.871134 -351.513648) (xy 99.863089 -351.540389)
			(xy 99.839417 -351.590886) (xy 99.808644 -351.637399) (xy 99.771427 -351.678936) (xy 99.728559 -351.714611)
			(xy 99.680953 -351.743665) (xy 99.629624 -351.765477) (xy 99.575667 -351.779583) (xy 99.52023 -351.785683)
			(xy 99.464496 -351.783646) (xy 99.409653 -351.773516) (xy 99.356869 -351.755509) (xy 99.307269 -351.730008)
			(xy 99.261911 -351.697557) (xy 99.221762 -351.658848) (xy 99.187676 -351.614705) (xy 99.16038 -351.56607)
			(xy 99.140457 -351.513979) (xy 99.128331 -351.459542) (xy 99.12426 -351.40392) (xy 93.645329 -351.40392)
			(xy 93.660932 -351.428201) (xy 93.683588 -351.477813) (xy 93.698952 -351.530145) (xy 93.706714 -351.58413)
			(xy 93.706714 -351.63867) (xy 93.698952 -351.692655) (xy 93.683588 -351.744987) (xy 93.660932 -351.794599)
			(xy 93.631447 -351.840483) (xy 93.595733 -351.881703) (xy 93.554516 -351.917422) (xy 93.508636 -351.946912)
			(xy 93.459026 -351.969573) (xy 93.406697 -351.984943) (xy 93.352712 -351.992711) (xy 93.325442 -351.9932)
			(xy 92.461842 -351.9932) (xy 92.434572 -351.992663) (xy 92.380586 -351.984907) (xy 92.328253 -351.969546)
			(xy 92.27864 -351.946893) (xy 92.232755 -351.917409) (xy 92.191534 -351.881695) (xy 92.155816 -351.840478)
			(xy 92.126327 -351.794597) (xy 92.103669 -351.744986) (xy 92.088302 -351.692655) (xy 92.08054 -351.63867)
			(xy 90.597836 -351.63867) (xy 90.597836 -351.638675) (xy 90.590073 -351.692668) (xy 90.574704 -351.745008)
			(xy 90.552043 -351.794627) (xy 90.522551 -351.840516) (xy 90.486828 -351.881741) (xy 90.445602 -351.917462)
			(xy 90.399711 -351.946952) (xy 90.350091 -351.969611) (xy 90.297751 -351.984977) (xy 90.243757 -351.992738)
			(xy 90.216482 -351.9932) (xy 89.352882 -351.9932) (xy 89.325616 -351.992636) (xy 89.27164 -351.984873)
			(xy 89.219318 -351.969508) (xy 89.169715 -351.946853) (xy 89.123841 -351.91737) (xy 89.082629 -351.881658)
			(xy 89.04692 -351.840445) (xy 89.017438 -351.794569) (xy 88.994786 -351.744965) (xy 88.979423 -351.692642)
			(xy 88.971662 -351.638666) (xy 87.488814 -351.638666) (xy 87.488814 -351.638671) (xy 87.481052 -351.692658)
			(xy 87.465686 -351.744991) (xy 87.443029 -351.794605) (xy 87.413542 -351.840489) (xy 87.377826 -351.88171)
			(xy 87.336607 -351.917429) (xy 87.290724 -351.946919) (xy 87.241112 -351.969578) (xy 87.18878 -351.984947)
			(xy 87.134793 -351.992712) (xy 87.107522 -351.9932) (xy 86.243922 -351.9932) (xy 86.216653 -351.992662)
			(xy 86.162669 -351.984903) (xy 86.110339 -351.96954) (xy 86.060728 -351.946886) (xy 86.014846 -351.917402)
			(xy 85.973627 -351.881688) (xy 85.937911 -351.840472) (xy 85.908424 -351.794592) (xy 85.885767 -351.744982)
			(xy 85.870401 -351.692653) (xy 85.862639 -351.638669) (xy 84.379936 -351.638669) (xy 84.379936 -351.638675)
			(xy 84.372172 -351.692671) (xy 84.356803 -351.745012) (xy 84.33414 -351.794633) (xy 84.304646 -351.840523)
			(xy 84.268921 -351.881748) (xy 84.227692 -351.917469) (xy 84.181799 -351.946958) (xy 84.132176 -351.969616)
			(xy 84.079834 -351.98498) (xy 84.025837 -351.992739) (xy 83.998562 -351.9932) (xy 83.134962 -351.9932)
			(xy 83.107697 -351.992635) (xy 83.053723 -351.98487) (xy 83.001403 -351.969503) (xy 82.951803 -351.946847)
			(xy 82.905931 -351.917363) (xy 82.864722 -351.881651) (xy 82.829015 -351.840438) (xy 82.799535 -351.794564)
			(xy 82.776884 -351.744961) (xy 82.761522 -351.69264) (xy 82.753762 -351.638665) (xy 81.270913 -351.638665)
			(xy 81.270913 -351.638672) (xy 81.263151 -351.692661) (xy 81.247784 -351.744995) (xy 81.225126 -351.79461)
			(xy 81.195637 -351.840496) (xy 81.159919 -351.881717) (xy 81.118697 -351.917436) (xy 81.072812 -351.946925)
			(xy 81.023197 -351.969584) (xy 80.970863 -351.984951) (xy 80.916874 -351.992713) (xy 80.889602 -351.9932)
			(xy 80.026002 -351.9932) (xy 79.998734 -351.992661) (xy 79.944752 -351.9849) (xy 79.892424 -351.969535)
			(xy 79.842816 -351.94688) (xy 79.796936 -351.917395) (xy 79.75572 -351.881681) (xy 79.720006 -351.840465)
			(xy 79.690521 -351.794586) (xy 79.667866 -351.744978) (xy 79.652501 -351.69265) (xy 79.644739 -351.638668)
			(xy 78.161914 -351.638668) (xy 78.161914 -351.63867) (xy 78.154152 -351.692655) (xy 78.138788 -351.744987)
			(xy 78.116132 -351.794599) (xy 78.086647 -351.840483) (xy 78.050933 -351.881703) (xy 78.009716 -351.917422)
			(xy 77.963836 -351.946912) (xy 77.914226 -351.969573) (xy 77.861897 -351.984943) (xy 77.807912 -351.992711)
			(xy 77.780642 -351.9932) (xy 76.917042 -351.9932) (xy 76.889772 -351.992663) (xy 76.835786 -351.984907)
			(xy 76.783453 -351.969546) (xy 76.73384 -351.946893) (xy 76.687955 -351.917409) (xy 76.646734 -351.881695)
			(xy 76.611016 -351.840478) (xy 76.581527 -351.794597) (xy 76.558869 -351.744986) (xy 76.543502 -351.692655)
			(xy 76.53574 -351.63867) (xy 75.053036 -351.63867) (xy 75.053036 -351.638675) (xy 75.045273 -351.692668)
			(xy 75.029904 -351.745008) (xy 75.007243 -351.794627) (xy 74.977751 -351.840516) (xy 74.942028 -351.881741)
			(xy 74.900802 -351.917462) (xy 74.854911 -351.946952) (xy 74.805291 -351.969611) (xy 74.752951 -351.984977)
			(xy 74.698957 -351.992738) (xy 74.671682 -351.9932) (xy 73.808082 -351.9932) (xy 73.780816 -351.992636)
			(xy 73.72684 -351.984873) (xy 73.674518 -351.969508) (xy 73.624915 -351.946853) (xy 73.579041 -351.91737)
			(xy 73.537829 -351.881658) (xy 73.50212 -351.840445) (xy 73.472638 -351.794569) (xy 73.449986 -351.744965)
			(xy 73.434623 -351.692642) (xy 73.426862 -351.638666) (xy 71.944014 -351.638666) (xy 71.944014 -351.638671)
			(xy 71.936252 -351.692658) (xy 71.920886 -351.744991) (xy 71.898229 -351.794605) (xy 71.868742 -351.840489)
			(xy 71.833026 -351.88171) (xy 71.791807 -351.917429) (xy 71.745924 -351.946919) (xy 71.696312 -351.969578)
			(xy 71.64398 -351.984947) (xy 71.589993 -351.992712) (xy 71.562722 -351.9932) (xy 70.699122 -351.9932)
			(xy 70.671853 -351.992662) (xy 70.617869 -351.984903) (xy 70.565539 -351.96954) (xy 70.515928 -351.946886)
			(xy 70.470046 -351.917402) (xy 70.428827 -351.881688) (xy 70.393111 -351.840472) (xy 70.363624 -351.794592)
			(xy 70.340967 -351.744982) (xy 70.325601 -351.692653) (xy 70.317839 -351.638669) (xy 68.835136 -351.638669)
			(xy 68.835136 -351.638675) (xy 68.827372 -351.692671) (xy 68.812003 -351.745012) (xy 68.78934 -351.794633)
			(xy 68.759846 -351.840523) (xy 68.724121 -351.881748) (xy 68.682892 -351.917469) (xy 68.636999 -351.946958)
			(xy 68.587376 -351.969616) (xy 68.535034 -351.98498) (xy 68.481037 -351.992739) (xy 68.453762 -351.9932)
			(xy 67.590162 -351.9932) (xy 67.562897 -351.992635) (xy 67.508923 -351.98487) (xy 67.456603 -351.969503)
			(xy 67.407003 -351.946847) (xy 67.361131 -351.917363) (xy 67.319922 -351.881651) (xy 67.284215 -351.840438)
			(xy 67.254735 -351.794564) (xy 67.232084 -351.744961) (xy 67.216722 -351.69264) (xy 67.208962 -351.638665)
			(xy 65.726113 -351.638665) (xy 65.726113 -351.638672) (xy 65.718351 -351.692661) (xy 65.702984 -351.744995)
			(xy 65.680326 -351.79461) (xy 65.650837 -351.840496) (xy 65.615119 -351.881717) (xy 65.573897 -351.917436)
			(xy 65.528012 -351.946925) (xy 65.478397 -351.969584) (xy 65.426063 -351.984951) (xy 65.372074 -351.992713)
			(xy 65.344802 -351.9932) (xy 64.481202 -351.9932) (xy 64.453934 -351.992661) (xy 64.399952 -351.9849)
			(xy 64.347624 -351.969535) (xy 64.298016 -351.94688) (xy 64.252136 -351.917395) (xy 64.21092 -351.881681)
			(xy 64.175206 -351.840465) (xy 64.145721 -351.794586) (xy 64.123066 -351.744978) (xy 64.107701 -351.69265)
			(xy 64.099939 -351.638668) (xy 62.617114 -351.638668) (xy 62.617114 -351.63867) (xy 62.609352 -351.692655)
			(xy 62.593988 -351.744987) (xy 62.571332 -351.794599) (xy 62.541847 -351.840483) (xy 62.506133 -351.881703)
			(xy 62.464916 -351.917422) (xy 62.419036 -351.946912) (xy 62.369426 -351.969573) (xy 62.317097 -351.984943)
			(xy 62.263112 -351.992711) (xy 62.235842 -351.9932) (xy 61.372242 -351.9932) (xy 61.344972 -351.992663)
			(xy 61.290986 -351.984907) (xy 61.238653 -351.969546) (xy 61.18904 -351.946893) (xy 61.143155 -351.917409)
			(xy 61.101934 -351.881695) (xy 61.066216 -351.840478) (xy 61.036727 -351.794597) (xy 61.014069 -351.744986)
			(xy 60.998702 -351.692655) (xy 60.99094 -351.63867) (xy 57.813415 -351.63867) (xy 57.273067 -353.042474)
			(xy 99.14839 -353.042474) (xy 99.152461 -352.986852) (xy 99.164587 -352.932415) (xy 99.18451 -352.880324)
			(xy 99.211806 -352.831689) (xy 99.245892 -352.787546) (xy 99.286041 -352.748837) (xy 99.331399 -352.716386)
			(xy 99.380999 -352.690885) (xy 99.433783 -352.672878) (xy 99.488626 -352.662748) (xy 99.54436 -352.660711)
			(xy 99.599797 -352.666811) (xy 99.653754 -352.680917) (xy 99.705083 -352.702729) (xy 99.752689 -352.731783)
			(xy 99.795557 -352.767458) (xy 99.832774 -352.808995) (xy 99.863547 -352.855508) (xy 99.887219 -352.906005)
			(xy 99.903287 -352.959412) (xy 99.91125 -353.013518) (xy 100.143562 -353.013518) (xy 100.147633 -352.957896)
			(xy 100.159759 -352.903459) (xy 100.179682 -352.851368) (xy 100.206978 -352.802733) (xy 100.241064 -352.75859)
			(xy 100.281213 -352.719881) (xy 100.326571 -352.68743) (xy 100.376171 -352.661929) (xy 100.428955 -352.643922)
			(xy 100.483798 -352.633792) (xy 100.539532 -352.631755) (xy 100.594969 -352.637855) (xy 100.648926 -352.651961)
			(xy 100.700255 -352.673773) (xy 100.747861 -352.702827) (xy 100.790729 -352.738502) (xy 100.827946 -352.780039)
			(xy 100.858719 -352.826552) (xy 100.882391 -352.877049) (xy 100.898459 -352.930456) (xy 100.906579 -352.985632)
			(xy 100.907088 -353.013518) (xy 100.906579 -353.041404) (xy 100.898459 -353.09658) (xy 100.884246 -353.14382)
			(xy 106.532932 -353.14382) (xy 106.537003 -353.088198) (xy 106.549129 -353.033761) (xy 106.569052 -352.98167)
			(xy 106.596348 -352.933035) (xy 106.630434 -352.888892) (xy 106.670583 -352.850183) (xy 106.715941 -352.817732)
			(xy 106.765541 -352.792231) (xy 106.818325 -352.774224) (xy 106.873168 -352.764094) (xy 106.928902 -352.762057)
			(xy 106.984339 -352.768157) (xy 107.038296 -352.782263) (xy 107.089625 -352.804075) (xy 107.137231 -352.833129)
			(xy 107.180099 -352.868804) (xy 107.217316 -352.910341) (xy 107.248089 -352.956854) (xy 107.271761 -353.007351)
			(xy 107.287829 -353.060758) (xy 107.295949 -353.115934) (xy 107.296458 -353.14382) (xy 107.295949 -353.171706)
			(xy 107.287829 -353.226882) (xy 107.271761 -353.280289) (xy 107.248089 -353.330786) (xy 107.217316 -353.377299)
			(xy 107.180099 -353.418836) (xy 107.137231 -353.454511) (xy 107.089625 -353.483565) (xy 107.038296 -353.505377)
			(xy 106.984339 -353.519483) (xy 106.928902 -353.525583) (xy 106.873168 -353.523546) (xy 106.818325 -353.513416)
			(xy 106.765541 -353.495409) (xy 106.715941 -353.469908) (xy 106.670583 -353.437457) (xy 106.630434 -353.398748)
			(xy 106.596348 -353.354605) (xy 106.569052 -353.30597) (xy 106.549129 -353.253879) (xy 106.537003 -353.199442)
			(xy 106.532932 -353.14382) (xy 100.884246 -353.14382) (xy 100.882391 -353.149987) (xy 100.858719 -353.200484)
			(xy 100.827946 -353.246997) (xy 100.790729 -353.288534) (xy 100.747861 -353.324209) (xy 100.700255 -353.353263)
			(xy 100.648926 -353.375075) (xy 100.594969 -353.389181) (xy 100.539532 -353.395281) (xy 100.483798 -353.393244)
			(xy 100.428955 -353.383114) (xy 100.376171 -353.365107) (xy 100.326571 -353.339606) (xy 100.281213 -353.307155)
			(xy 100.241064 -353.268446) (xy 100.206978 -353.224303) (xy 100.179682 -353.175668) (xy 100.159759 -353.123577)
			(xy 100.147633 -353.06914) (xy 100.143562 -353.013518) (xy 99.91125 -353.013518) (xy 99.911407 -353.014588)
			(xy 99.911916 -353.042474) (xy 99.911407 -353.07036) (xy 99.903287 -353.125536) (xy 99.887219 -353.178943)
			(xy 99.863547 -353.22944) (xy 99.832774 -353.275953) (xy 99.795557 -353.31749) (xy 99.752689 -353.353165)
			(xy 99.705083 -353.382219) (xy 99.653754 -353.404031) (xy 99.599797 -353.418137) (xy 99.54436 -353.424237)
			(xy 99.488626 -353.4222) (xy 99.433783 -353.41207) (xy 99.380999 -353.394063) (xy 99.331399 -353.368562)
			(xy 99.286041 -353.336111) (xy 99.245892 -353.297402) (xy 99.211806 -353.253259) (xy 99.18451 -353.204624)
			(xy 99.164587 -353.152533) (xy 99.152461 -353.098096) (xy 99.14839 -353.042474) (xy 57.273067 -353.042474)
			(xy 56.612204 -354.759372) (xy 64.099884 -354.759372) (xy 64.099884 -354.704828) (xy 64.107646 -354.650838)
			(xy 64.123013 -354.598503) (xy 64.145672 -354.548887) (xy 64.175161 -354.503001) (xy 64.210881 -354.461779)
			(xy 64.252103 -354.42606) (xy 64.297989 -354.396571) (xy 64.347605 -354.373912) (xy 64.39994 -354.358546)
			(xy 64.45393 -354.350783) (xy 64.481202 -354.35032) (xy 65.344802 -354.35032) (xy 65.37207 -354.350843)
			(xy 65.426051 -354.358604) (xy 65.478378 -354.373969) (xy 65.527985 -354.396624) (xy 65.573864 -354.426109)
			(xy 65.615079 -354.461822) (xy 65.650793 -354.503038) (xy 65.680277 -354.548917) (xy 65.702932 -354.598524)
			(xy 65.718296 -354.650851) (xy 65.726058 -354.704832) (xy 65.726058 -354.759368) (xy 65.726058 -354.759369)
			(xy 67.208906 -354.759369) (xy 67.208906 -354.704831) (xy 67.216667 -354.650848) (xy 67.232032 -354.598519)
			(xy 67.254686 -354.548909) (xy 67.28417 -354.503028) (xy 67.319883 -354.46181) (xy 67.361098 -354.426093)
			(xy 67.406976 -354.396604) (xy 67.456584 -354.373945) (xy 67.508911 -354.358575) (xy 67.562893 -354.350809)
			(xy 67.590162 -354.35032) (xy 68.453762 -354.35032) (xy 68.481033 -354.350817) (xy 68.535022 -354.358574)
			(xy 68.587357 -354.373936) (xy 68.636972 -354.396591) (xy 68.682859 -354.426076) (xy 68.724081 -354.461792)
			(xy 68.759801 -354.503011) (xy 68.789291 -354.548894) (xy 68.81195 -354.598508) (xy 68.827318 -354.650841)
			(xy 68.83508 -354.704829) (xy 68.83508 -354.759371) (xy 68.83508 -354.759373) (xy 70.317784 -354.759373)
			(xy 70.317784 -354.704827) (xy 70.325547 -354.650835) (xy 70.340915 -354.598498) (xy 70.363575 -354.548882)
			(xy 70.393066 -354.502995) (xy 70.428788 -354.461772) (xy 70.470012 -354.426053) (xy 70.515901 -354.396564)
			(xy 70.565519 -354.373907) (xy 70.617857 -354.358542) (xy 70.671849 -354.350782) (xy 70.699122 -354.35032)
			(xy 71.562722 -354.35032) (xy 71.589989 -354.350844) (xy 71.643968 -354.358608) (xy 71.696292 -354.373974)
			(xy 71.745897 -354.396631) (xy 71.791773 -354.426116) (xy 71.832986 -354.461829) (xy 71.868697 -354.503044)
			(xy 71.89818 -354.548922) (xy 71.920833 -354.598528) (xy 71.936197 -354.650854) (xy 71.943958 -354.704833)
			(xy 71.943958 -354.759367) (xy 71.943958 -354.75937) (xy 73.426806 -354.75937) (xy 73.426806 -354.70483)
			(xy 73.434568 -354.650846) (xy 73.449933 -354.598515) (xy 73.472589 -354.548904) (xy 73.502075 -354.503022)
			(xy 73.53779 -354.461802) (xy 73.579007 -354.426085) (xy 73.624888 -354.396598) (xy 73.674498 -354.373939)
			(xy 73.726828 -354.358572) (xy 73.780812 -354.350808) (xy 73.808082 -354.35032) (xy 74.671682 -354.35032)
			(xy 74.698953 -354.350818) (xy 74.752939 -354.358578) (xy 74.805271 -354.373942) (xy 74.854884 -354.396597)
			(xy 74.900768 -354.426083) (xy 74.941988 -354.461799) (xy 74.977706 -354.503018) (xy 75.007194 -354.5489)
			(xy 75.029852 -354.598512) (xy 75.045218 -354.650844) (xy 75.052981 -354.704829) (xy 75.052981 -354.759371)
			(xy 75.052981 -354.759374) (xy 76.535684 -354.759374) (xy 76.535684 -354.704826) (xy 76.543447 -354.650833)
			(xy 76.558816 -354.598494) (xy 76.581478 -354.548876) (xy 76.610971 -354.502988) (xy 76.646695 -354.461765)
			(xy 76.687922 -354.426046) (xy 76.733813 -354.396558) (xy 76.783434 -354.373902) (xy 76.835774 -354.358538)
			(xy 76.889768 -354.350781) (xy 76.917042 -354.35032) (xy 77.780642 -354.35032) (xy 77.807908 -354.350845)
			(xy 77.861885 -354.358611) (xy 77.914207 -354.37398) (xy 77.963809 -354.396637) (xy 78.009683 -354.426123)
			(xy 78.050893 -354.461836) (xy 78.086602 -354.503051) (xy 78.116083 -354.548928) (xy 78.138735 -354.598533)
			(xy 78.154098 -354.650856) (xy 78.161858 -354.704834) (xy 78.161858 -354.759366) (xy 78.161857 -354.759372)
			(xy 79.644684 -354.759372) (xy 79.644684 -354.704828) (xy 79.652446 -354.650838) (xy 79.667813 -354.598503)
			(xy 79.690472 -354.548887) (xy 79.719961 -354.503001) (xy 79.755681 -354.461779) (xy 79.796903 -354.42606)
			(xy 79.842789 -354.396571) (xy 79.892405 -354.373912) (xy 79.94474 -354.358546) (xy 79.99873 -354.350783)
			(xy 80.026002 -354.35032) (xy 80.889602 -354.35032) (xy 80.91687 -354.350843) (xy 80.970851 -354.358604)
			(xy 81.023178 -354.373969) (xy 81.072785 -354.396624) (xy 81.118664 -354.426109) (xy 81.159879 -354.461822)
			(xy 81.195593 -354.503038) (xy 81.225077 -354.548917) (xy 81.247732 -354.598524) (xy 81.263096 -354.650851)
			(xy 81.270858 -354.704832) (xy 81.270858 -354.759368) (xy 81.270858 -354.759369) (xy 82.753706 -354.759369)
			(xy 82.753706 -354.704831) (xy 82.761467 -354.650848) (xy 82.776832 -354.598519) (xy 82.799486 -354.548909)
			(xy 82.82897 -354.503028) (xy 82.864683 -354.46181) (xy 82.905898 -354.426093) (xy 82.951776 -354.396604)
			(xy 83.001384 -354.373945) (xy 83.053711 -354.358575) (xy 83.107693 -354.350809) (xy 83.134962 -354.35032)
			(xy 83.998562 -354.35032) (xy 84.025833 -354.350817) (xy 84.079822 -354.358574) (xy 84.132157 -354.373936)
			(xy 84.181772 -354.396591) (xy 84.227659 -354.426076) (xy 84.268881 -354.461792) (xy 84.304601 -354.503011)
			(xy 84.334091 -354.548894) (xy 84.35675 -354.598508) (xy 84.372118 -354.650841) (xy 84.37988 -354.704829)
			(xy 84.37988 -354.759371) (xy 84.37988 -354.759373) (xy 85.862584 -354.759373) (xy 85.862584 -354.704827)
			(xy 85.870347 -354.650835) (xy 85.885715 -354.598498) (xy 85.908375 -354.548882) (xy 85.937866 -354.502995)
			(xy 85.973588 -354.461772) (xy 86.014812 -354.426053) (xy 86.060701 -354.396564) (xy 86.110319 -354.373907)
			(xy 86.162657 -354.358542) (xy 86.216649 -354.350782) (xy 86.243922 -354.35032) (xy 87.107522 -354.35032)
			(xy 87.134789 -354.350844) (xy 87.188768 -354.358608) (xy 87.241092 -354.373974) (xy 87.290697 -354.396631)
			(xy 87.336573 -354.426116) (xy 87.377786 -354.461829) (xy 87.413497 -354.503044) (xy 87.44298 -354.548922)
			(xy 87.465633 -354.598528) (xy 87.480997 -354.650854) (xy 87.488758 -354.704833) (xy 87.488758 -354.759367)
			(xy 87.488758 -354.75937) (xy 88.971606 -354.75937) (xy 88.971606 -354.70483) (xy 88.979368 -354.650846)
			(xy 88.994733 -354.598515) (xy 89.017389 -354.548904) (xy 89.046875 -354.503022) (xy 89.08259 -354.461802)
			(xy 89.123807 -354.426085) (xy 89.169688 -354.396598) (xy 89.219298 -354.373939) (xy 89.271628 -354.358572)
			(xy 89.325612 -354.350808) (xy 89.352882 -354.35032) (xy 90.216482 -354.35032) (xy 90.243753 -354.350818)
			(xy 90.297739 -354.358578) (xy 90.350071 -354.373942) (xy 90.399684 -354.396597) (xy 90.445568 -354.426083)
			(xy 90.486788 -354.461799) (xy 90.522506 -354.503018) (xy 90.551994 -354.5489) (xy 90.574652 -354.598512)
			(xy 90.590018 -354.650844) (xy 90.597781 -354.704829) (xy 90.597781 -354.759371) (xy 90.597781 -354.759374)
			(xy 92.080484 -354.759374) (xy 92.080484 -354.704826) (xy 92.088247 -354.650833) (xy 92.103616 -354.598494)
			(xy 92.126278 -354.548876) (xy 92.155771 -354.502988) (xy 92.191495 -354.461765) (xy 92.232722 -354.426046)
			(xy 92.278613 -354.396558) (xy 92.328234 -354.373902) (xy 92.380574 -354.358538) (xy 92.434568 -354.350781)
			(xy 92.461842 -354.35032) (xy 93.325442 -354.35032) (xy 93.352708 -354.350845) (xy 93.406685 -354.358611)
			(xy 93.459007 -354.37398) (xy 93.508609 -354.396637) (xy 93.554483 -354.426123) (xy 93.595693 -354.461836)
			(xy 93.631402 -354.503051) (xy 93.632822 -354.50526) (xy 99.97643 -354.50526) (xy 99.980501 -354.449638)
			(xy 99.992627 -354.395201) (xy 100.01255 -354.34311) (xy 100.039846 -354.294475) (xy 100.073932 -354.250332)
			(xy 100.114081 -354.211623) (xy 100.159439 -354.179172) (xy 100.209039 -354.153671) (xy 100.261823 -354.135664)
			(xy 100.316666 -354.125534) (xy 100.3724 -354.123497) (xy 100.427837 -354.129597) (xy 100.453087 -354.136198)
			(xy 105.899202 -354.136198) (xy 105.903273 -354.080576) (xy 105.915399 -354.026139) (xy 105.935322 -353.974048)
			(xy 105.962618 -353.925413) (xy 105.996704 -353.88127) (xy 106.036853 -353.842561) (xy 106.082211 -353.81011)
			(xy 106.131811 -353.784609) (xy 106.184595 -353.766602) (xy 106.239438 -353.756472) (xy 106.295172 -353.754435)
			(xy 106.350609 -353.760535) (xy 106.404566 -353.774641) (xy 106.455895 -353.796453) (xy 106.503501 -353.825507)
			(xy 106.546369 -353.861182) (xy 106.583586 -353.902719) (xy 106.614359 -353.949232) (xy 106.638031 -353.999729)
			(xy 106.654099 -354.053136) (xy 106.662219 -354.108312) (xy 106.662728 -354.136198) (xy 106.662219 -354.164084)
			(xy 106.654099 -354.21926) (xy 106.638031 -354.272667) (xy 106.614359 -354.323164) (xy 106.583586 -354.369677)
			(xy 106.546369 -354.411214) (xy 106.503501 -354.446889) (xy 106.455895 -354.475943) (xy 106.404566 -354.497755)
			(xy 106.350609 -354.511861) (xy 106.295172 -354.517961) (xy 106.239438 -354.515924) (xy 106.184595 -354.505794)
			(xy 106.131811 -354.487787) (xy 106.082211 -354.462286) (xy 106.036853 -354.429835) (xy 105.996704 -354.391126)
			(xy 105.962618 -354.346983) (xy 105.935322 -354.298348) (xy 105.915399 -354.246257) (xy 105.903273 -354.19182)
			(xy 105.899202 -354.136198) (xy 100.453087 -354.136198) (xy 100.481794 -354.143703) (xy 100.533123 -354.165515)
			(xy 100.580729 -354.194569) (xy 100.623597 -354.230244) (xy 100.660814 -354.271781) (xy 100.691587 -354.318294)
			(xy 100.715259 -354.368791) (xy 100.731327 -354.422198) (xy 100.739447 -354.477374) (xy 100.739956 -354.50526)
			(xy 100.739447 -354.533146) (xy 100.731327 -354.588322) (xy 100.715259 -354.641729) (xy 100.691587 -354.692226)
			(xy 100.660814 -354.738739) (xy 100.623597 -354.780276) (xy 100.580729 -354.815951) (xy 100.533123 -354.845005)
			(xy 100.481794 -354.866817) (xy 100.427837 -354.880923) (xy 100.3724 -354.887023) (xy 100.316666 -354.884986)
			(xy 100.261823 -354.874856) (xy 100.209039 -354.856849) (xy 100.159439 -354.831348) (xy 100.114081 -354.798897)
			(xy 100.073932 -354.760188) (xy 100.039846 -354.716045) (xy 100.01255 -354.66741) (xy 99.992627 -354.615319)
			(xy 99.980501 -354.560882) (xy 99.97643 -354.50526) (xy 93.632822 -354.50526) (xy 93.660883 -354.548928)
			(xy 93.683535 -354.598533) (xy 93.698898 -354.650856) (xy 93.706658 -354.704834) (xy 93.706658 -354.759366)
			(xy 93.698898 -354.813344) (xy 93.683535 -354.865667) (xy 93.660883 -354.915272) (xy 93.631402 -354.961149)
			(xy 93.595693 -355.002364) (xy 93.554483 -355.038077) (xy 93.508609 -355.067563) (xy 93.459007 -355.09022)
			(xy 93.406685 -355.105589) (xy 93.352708 -355.113355) (xy 93.325442 -355.113844) (xy 92.461842 -355.113844)
			(xy 92.434568 -355.113419) (xy 92.380574 -355.105662) (xy 92.328234 -355.090298) (xy 92.278613 -355.067642)
			(xy 92.232722 -355.038154) (xy 92.191495 -355.002435) (xy 92.155771 -354.961212) (xy 92.126278 -354.915324)
			(xy 92.103616 -354.865706) (xy 92.088247 -354.813367) (xy 92.080484 -354.759374) (xy 90.597781 -354.759374)
			(xy 90.590018 -354.813356) (xy 90.574652 -354.865688) (xy 90.551994 -354.9153) (xy 90.522506 -354.961182)
			(xy 90.486788 -355.002401) (xy 90.445568 -355.038117) (xy 90.399684 -355.067603) (xy 90.350071 -355.090258)
			(xy 90.297739 -355.105622) (xy 90.243753 -355.113382) (xy 90.216482 -355.113844) (xy 89.352882 -355.113844)
			(xy 89.325612 -355.113392) (xy 89.271628 -355.105628) (xy 89.219298 -355.090261) (xy 89.169688 -355.067602)
			(xy 89.123807 -355.038115) (xy 89.08259 -355.002398) (xy 89.046875 -354.961178) (xy 89.017389 -354.915296)
			(xy 88.994733 -354.865685) (xy 88.979368 -354.813354) (xy 88.971606 -354.75937) (xy 87.488758 -354.75937)
			(xy 87.480997 -354.813346) (xy 87.465633 -354.865672) (xy 87.44298 -354.915278) (xy 87.413497 -354.961156)
			(xy 87.377786 -355.002371) (xy 87.336573 -355.038084) (xy 87.290697 -355.067569) (xy 87.241092 -355.090226)
			(xy 87.188768 -355.105592) (xy 87.134789 -355.113356) (xy 87.107522 -355.113844) (xy 86.243922 -355.113844)
			(xy 86.216649 -355.113418) (xy 86.162657 -355.105658) (xy 86.110319 -355.090293) (xy 86.060701 -355.067636)
			(xy 86.014812 -355.038147) (xy 85.973588 -355.002428) (xy 85.937866 -354.961205) (xy 85.908375 -354.915318)
			(xy 85.885715 -354.865702) (xy 85.870347 -354.813365) (xy 85.862584 -354.759373) (xy 84.37988 -354.759373)
			(xy 84.372118 -354.813359) (xy 84.35675 -354.865692) (xy 84.334091 -354.915306) (xy 84.304601 -354.961189)
			(xy 84.268881 -355.002408) (xy 84.227659 -355.038124) (xy 84.181772 -355.067609) (xy 84.132157 -355.090264)
			(xy 84.079822 -355.105626) (xy 84.025833 -355.113383) (xy 83.998562 -355.113844) (xy 83.134962 -355.113844)
			(xy 83.107693 -355.113391) (xy 83.053711 -355.105625) (xy 83.001384 -355.090255) (xy 82.951776 -355.067596)
			(xy 82.905898 -355.038107) (xy 82.864683 -355.00239) (xy 82.82897 -354.961172) (xy 82.799486 -354.915291)
			(xy 82.776832 -354.865681) (xy 82.761467 -354.813352) (xy 82.753706 -354.759369) (xy 81.270858 -354.759369)
			(xy 81.263096 -354.813349) (xy 81.247732 -354.865676) (xy 81.225077 -354.915283) (xy 81.195593 -354.961162)
			(xy 81.159879 -355.002378) (xy 81.118664 -355.038091) (xy 81.072785 -355.067576) (xy 81.023178 -355.090231)
			(xy 80.970851 -355.105596) (xy 80.91687 -355.113357) (xy 80.889602 -355.113844) (xy 80.026002 -355.113844)
			(xy 79.99873 -355.113417) (xy 79.94474 -355.105654) (xy 79.892405 -355.090288) (xy 79.842789 -355.067629)
			(xy 79.796903 -355.03814) (xy 79.755681 -355.002421) (xy 79.719961 -354.961199) (xy 79.690472 -354.915313)
			(xy 79.667813 -354.865697) (xy 79.652446 -354.813362) (xy 79.644684 -354.759372) (xy 78.161857 -354.759372)
			(xy 78.154098 -354.813344) (xy 78.138735 -354.865667) (xy 78.116083 -354.915272) (xy 78.086602 -354.961149)
			(xy 78.050893 -355.002364) (xy 78.009683 -355.038077) (xy 77.963809 -355.067563) (xy 77.914207 -355.09022)
			(xy 77.861885 -355.105589) (xy 77.807908 -355.113355) (xy 77.780642 -355.113844) (xy 76.917042 -355.113844)
			(xy 76.889768 -355.113419) (xy 76.835774 -355.105662) (xy 76.783434 -355.090298) (xy 76.733813 -355.067642)
			(xy 76.687922 -355.038154) (xy 76.646695 -355.002435) (xy 76.610971 -354.961212) (xy 76.581478 -354.915324)
			(xy 76.558816 -354.865706) (xy 76.543447 -354.813367) (xy 76.535684 -354.759374) (xy 75.052981 -354.759374)
			(xy 75.045218 -354.813356) (xy 75.029852 -354.865688) (xy 75.007194 -354.9153) (xy 74.977706 -354.961182)
			(xy 74.941988 -355.002401) (xy 74.900768 -355.038117) (xy 74.854884 -355.067603) (xy 74.805271 -355.090258)
			(xy 74.752939 -355.105622) (xy 74.698953 -355.113382) (xy 74.671682 -355.113844) (xy 73.808082 -355.113844)
			(xy 73.780812 -355.113392) (xy 73.726828 -355.105628) (xy 73.674498 -355.090261) (xy 73.624888 -355.067602)
			(xy 73.579007 -355.038115) (xy 73.53779 -355.002398) (xy 73.502075 -354.961178) (xy 73.472589 -354.915296)
			(xy 73.449933 -354.865685) (xy 73.434568 -354.813354) (xy 73.426806 -354.75937) (xy 71.943958 -354.75937)
			(xy 71.936197 -354.813346) (xy 71.920833 -354.865672) (xy 71.89818 -354.915278) (xy 71.868697 -354.961156)
			(xy 71.832986 -355.002371) (xy 71.791773 -355.038084) (xy 71.745897 -355.067569) (xy 71.696292 -355.090226)
			(xy 71.643968 -355.105592) (xy 71.589989 -355.113356) (xy 71.562722 -355.113844) (xy 70.699122 -355.113844)
			(xy 70.671849 -355.113418) (xy 70.617857 -355.105658) (xy 70.565519 -355.090293) (xy 70.515901 -355.067636)
			(xy 70.470012 -355.038147) (xy 70.428788 -355.002428) (xy 70.393066 -354.961205) (xy 70.363575 -354.915318)
			(xy 70.340915 -354.865702) (xy 70.325547 -354.813365) (xy 70.317784 -354.759373) (xy 68.83508 -354.759373)
			(xy 68.827318 -354.813359) (xy 68.81195 -354.865692) (xy 68.789291 -354.915306) (xy 68.759801 -354.961189)
			(xy 68.724081 -355.002408) (xy 68.682859 -355.038124) (xy 68.636972 -355.067609) (xy 68.587357 -355.090264)
			(xy 68.535022 -355.105626) (xy 68.481033 -355.113383) (xy 68.453762 -355.113844) (xy 67.590162 -355.113844)
			(xy 67.562893 -355.113391) (xy 67.508911 -355.105625) (xy 67.456584 -355.090255) (xy 67.406976 -355.067596)
			(xy 67.361098 -355.038107) (xy 67.319883 -355.00239) (xy 67.28417 -354.961172) (xy 67.254686 -354.915291)
			(xy 67.232032 -354.865681) (xy 67.216667 -354.813352) (xy 67.208906 -354.759369) (xy 65.726058 -354.759369)
			(xy 65.718296 -354.813349) (xy 65.702932 -354.865676) (xy 65.680277 -354.915283) (xy 65.650793 -354.961162)
			(xy 65.615079 -355.002378) (xy 65.573864 -355.038091) (xy 65.527985 -355.067576) (xy 65.478378 -355.090231)
			(xy 65.426051 -355.105596) (xy 65.37207 -355.113357) (xy 65.344802 -355.113844) (xy 64.481202 -355.113844)
			(xy 64.45393 -355.113417) (xy 64.39994 -355.105654) (xy 64.347605 -355.090288) (xy 64.297989 -355.067629)
			(xy 64.252103 -355.03814) (xy 64.210881 -355.002421) (xy 64.175161 -354.961199) (xy 64.145672 -354.915313)
			(xy 64.123013 -354.865697) (xy 64.107646 -354.813362) (xy 64.099884 -354.759372) (xy 56.612204 -354.759372)
			(xy 56.310239 -355.543866) (xy 100.796342 -355.543866) (xy 100.800413 -355.488244) (xy 100.812539 -355.433807)
			(xy 100.832462 -355.381716) (xy 100.859758 -355.333081) (xy 100.893844 -355.288938) (xy 100.933993 -355.250229)
			(xy 100.979351 -355.217778) (xy 101.028951 -355.192277) (xy 101.081735 -355.17427) (xy 101.136578 -355.16414)
			(xy 101.192312 -355.162103) (xy 101.247749 -355.168203) (xy 101.301706 -355.182309) (xy 101.353035 -355.204121)
			(xy 101.400641 -355.233175) (xy 101.443509 -355.26885) (xy 101.480726 -355.310387) (xy 101.483114 -355.313996)
			(xy 106.055922 -355.313996) (xy 106.056408 -355.286745) (xy 106.064164 -355.232797) (xy 106.079519 -355.180502)
			(xy 106.102161 -355.130925) (xy 106.131627 -355.085075) (xy 106.167318 -355.043884) (xy 106.208509 -355.008193)
			(xy 106.254359 -354.978727) (xy 106.303936 -354.956085) (xy 106.356231 -354.94073) (xy 106.410179 -354.932974)
			(xy 106.464681 -354.932974) (xy 106.518629 -354.94073) (xy 106.570924 -354.956085) (xy 106.620501 -354.978727)
			(xy 106.666351 -355.008193) (xy 106.707542 -355.043884) (xy 106.743233 -355.085075) (xy 106.772699 -355.130925)
			(xy 106.795341 -355.180502) (xy 106.810696 -355.232797) (xy 106.818452 -355.286745) (xy 106.818938 -355.313996)
			(xy 106.818455 -355.342566) (xy 106.809941 -355.399069) (xy 106.793088 -355.453667) (xy 106.768274 -355.505138)
			(xy 106.736054 -355.552329) (xy 106.697152 -355.594181) (xy 106.652438 -355.629757) (xy 106.62793 -355.64445)
			(xy 106.616417 -355.651599) (xy 106.59736 -355.670853) (xy 106.58403 -355.694437) (xy 106.577363 -355.720694)
			(xy 106.577428 -355.72446) (xy 106.991658 -355.72446) (xy 106.992258 -355.695119) (xy 107.001235 -355.637129)
			(xy 107.018987 -355.581197) (xy 107.045094 -355.528644) (xy 107.078941 -355.480708) (xy 107.11973 -355.438521)
			(xy 107.166498 -355.403077) (xy 107.192064 -355.388672) (xy 107.202732 -355.38283) (xy 107.216448 -355.363526)
			(xy 107.232704 -355.260148) (xy 107.225592 -355.237542) (xy 107.21721 -355.228906) (xy 107.197458 -355.207456)
			(xy 107.164022 -355.159689) (xy 107.13824 -355.107392) (xy 107.120711 -355.051782) (xy 107.111844 -354.994153)
			(xy 107.111292 -354.965) (xy 107.111733 -354.93833) (xy 107.119151 -354.885508) (xy 107.133856 -354.834235)
			(xy 107.155563 -354.785511) (xy 107.183846 -354.740286) (xy 107.218155 -354.699444) (xy 107.257819 -354.66378)
			(xy 107.279694 -354.648516) (xy 107.2896 -354.641912) (xy 107.301284 -354.621846) (xy 107.308142 -354.517706)
			(xy 107.299252 -354.49637) (xy 107.290362 -354.488242) (xy 107.270564 -354.470073) (xy 107.235771 -354.429123)
			(xy 107.207072 -354.383695) (xy 107.185034 -354.334687) (xy 107.170096 -354.28307) (xy 107.162552 -354.229867)
			(xy 107.162092 -354.203) (xy 107.162578 -354.175749) (xy 107.170334 -354.121801) (xy 107.185689 -354.069506)
			(xy 107.208331 -354.019929) (xy 107.237797 -353.974079) (xy 107.273488 -353.932888) (xy 107.314679 -353.897197)
			(xy 107.360529 -353.867731) (xy 107.410106 -353.845089) (xy 107.462401 -353.829734) (xy 107.516349 -353.821978)
			(xy 107.570851 -353.821978) (xy 107.624799 -353.829734) (xy 107.677094 -353.845089) (xy 107.726671 -353.867731)
			(xy 107.772521 -353.897197) (xy 107.813712 -353.932888) (xy 107.849403 -353.974079) (xy 107.878869 -354.019929)
			(xy 107.901511 -354.069506) (xy 107.916866 -354.121801) (xy 107.924622 -354.175749) (xy 107.925108 -354.203)
			(xy 107.924667 -354.22967) (xy 107.917249 -354.282492) (xy 107.902544 -354.333765) (xy 107.880837 -354.382489)
			(xy 107.852554 -354.427714) (xy 107.818245 -354.468556) (xy 107.778581 -354.50422) (xy 107.756706 -354.519484)
			(xy 107.7468 -354.526088) (xy 107.735116 -354.546154) (xy 107.728258 -354.650294) (xy 107.737148 -354.67163)
			(xy 107.746038 -354.679758) (xy 107.765836 -354.697927) (xy 107.800629 -354.738877) (xy 107.813575 -354.759369)
			(xy 114.589806 -354.759369) (xy 114.589806 -354.704831) (xy 114.597568 -354.650847) (xy 114.612932 -354.598518)
			(xy 114.635587 -354.548908) (xy 114.665071 -354.503026) (xy 114.700785 -354.461807) (xy 114.742 -354.42609)
			(xy 114.78788 -354.396602) (xy 114.837488 -354.373943) (xy 114.889816 -354.358574) (xy 114.943799 -354.350809)
			(xy 114.971068 -354.35032) (xy 115.834668 -354.35032) (xy 115.861939 -354.350817) (xy 115.915927 -354.358575)
			(xy 115.968261 -354.373938) (xy 116.017876 -354.396593) (xy 116.063761 -354.426078) (xy 116.104983 -354.461794)
			(xy 116.140703 -354.503013) (xy 116.170192 -354.548896) (xy 116.192851 -354.598509) (xy 116.208218 -354.650842)
			(xy 116.21598 -354.704829) (xy 116.21598 -354.759371) (xy 116.21598 -354.759374) (xy 117.698684 -354.759374)
			(xy 117.698684 -354.704826) (xy 117.706447 -354.650835) (xy 117.721815 -354.598497) (xy 117.744476 -354.54888)
			(xy 117.773968 -354.502993) (xy 117.80969 -354.46177) (xy 117.850915 -354.426051) (xy 117.896804 -354.396562)
			(xy 117.946423 -354.373905) (xy 117.998762 -354.358541) (xy 118.052754 -354.350782) (xy 118.080028 -354.35032)
			(xy 118.943628 -354.35032) (xy 118.970895 -354.350844) (xy 119.024873 -354.358609) (xy 119.077197 -354.373976)
			(xy 119.126801 -354.396633) (xy 119.172676 -354.426118) (xy 119.213888 -354.461831) (xy 119.249599 -354.503046)
			(xy 119.279081 -354.548924) (xy 119.301734 -354.59853) (xy 119.317097 -354.650855) (xy 119.324858 -354.704833)
			(xy 119.324858 -354.759367) (xy 119.324858 -354.75937) (xy 120.807706 -354.75937) (xy 120.807706 -354.70483)
			(xy 120.815468 -354.650845) (xy 120.830834 -354.598514) (xy 120.85349 -354.548902) (xy 120.882976 -354.50302)
			(xy 120.918692 -354.4618) (xy 120.95991 -354.426083) (xy 121.005791 -354.396596) (xy 121.055403 -354.373938)
			(xy 121.107733 -354.358571) (xy 121.161718 -354.350807) (xy 121.188988 -354.35032) (xy 122.052588 -354.35032)
			(xy 122.079858 -354.350819) (xy 122.133844 -354.358579) (xy 122.186176 -354.373944) (xy 122.235788 -354.396599)
			(xy 122.281671 -354.426085) (xy 122.322891 -354.461801) (xy 122.358608 -354.503019) (xy 122.388095 -354.548902)
			(xy 122.410752 -354.598513) (xy 122.426118 -354.650844) (xy 122.433881 -354.70483) (xy 122.433881 -354.75937)
			(xy 122.43388 -354.759374) (xy 123.916584 -354.759374) (xy 123.916584 -354.704826) (xy 123.924347 -354.650832)
			(xy 123.939717 -354.598493) (xy 123.962379 -354.548874) (xy 123.991872 -354.502986) (xy 124.027597 -354.461763)
			(xy 124.068825 -354.426044) (xy 124.114716 -354.396556) (xy 124.164338 -354.3739) (xy 124.216679 -354.358537)
			(xy 124.270673 -354.35078) (xy 124.297948 -354.35032) (xy 125.161548 -354.35032) (xy 125.188814 -354.350846)
			(xy 125.24279 -354.358613) (xy 125.295111 -354.373981) (xy 125.344713 -354.396639) (xy 125.390586 -354.426125)
			(xy 125.431795 -354.461839) (xy 125.467504 -354.503053) (xy 125.496984 -354.548929) (xy 125.519636 -354.598534)
			(xy 125.534998 -354.650857) (xy 125.542758 -354.704834) (xy 125.542758 -354.759366) (xy 125.542757 -354.759373)
			(xy 127.025584 -354.759373) (xy 127.025584 -354.704827) (xy 127.033346 -354.650837) (xy 127.048714 -354.598501)
			(xy 127.071373 -354.548885) (xy 127.100863 -354.502999) (xy 127.136583 -354.461777) (xy 127.177806 -354.426058)
			(xy 127.223692 -354.396569) (xy 127.273309 -354.373911) (xy 127.325645 -354.358545) (xy 127.379635 -354.350783)
			(xy 127.406908 -354.35032) (xy 128.270508 -354.35032) (xy 128.297776 -354.350843) (xy 128.351756 -354.358605)
			(xy 128.404082 -354.37397) (xy 128.453689 -354.396626) (xy 128.499567 -354.426111) (xy 128.540781 -354.461824)
			(xy 128.576494 -354.50304) (xy 128.605978 -354.548918) (xy 128.628632 -354.598525) (xy 128.643997 -354.650852)
			(xy 128.651758 -354.704832) (xy 128.651758 -354.759368) (xy 128.651758 -354.759369) (xy 130.134606 -354.759369)
			(xy 130.134606 -354.704831) (xy 130.142368 -354.650847) (xy 130.157732 -354.598518) (xy 130.180387 -354.548908)
			(xy 130.209871 -354.503026) (xy 130.245585 -354.461807) (xy 130.2868 -354.42609) (xy 130.33268 -354.396602)
			(xy 130.382288 -354.373943) (xy 130.434616 -354.358574) (xy 130.488599 -354.350809) (xy 130.515868 -354.35032)
			(xy 131.379468 -354.35032) (xy 131.406739 -354.350817) (xy 131.460727 -354.358575) (xy 131.513061 -354.373938)
			(xy 131.562676 -354.396593) (xy 131.608561 -354.426078) (xy 131.649783 -354.461794) (xy 131.685503 -354.503013)
			(xy 131.714992 -354.548896) (xy 131.737651 -354.598509) (xy 131.753018 -354.650842) (xy 131.76078 -354.704829)
			(xy 131.76078 -354.759371) (xy 131.76078 -354.759374) (xy 133.243484 -354.759374) (xy 133.243484 -354.704826)
			(xy 133.251247 -354.650835) (xy 133.266615 -354.598497) (xy 133.289276 -354.54888) (xy 133.318768 -354.502993)
			(xy 133.35449 -354.46177) (xy 133.395715 -354.426051) (xy 133.441604 -354.396562) (xy 133.491223 -354.373905)
			(xy 133.543562 -354.358541) (xy 133.597554 -354.350782) (xy 133.624828 -354.35032) (xy 134.488428 -354.35032)
			(xy 134.515695 -354.350844) (xy 134.569673 -354.358609) (xy 134.621997 -354.373976) (xy 134.671601 -354.396633)
			(xy 134.717476 -354.426118) (xy 134.758688 -354.461831) (xy 134.794399 -354.503046) (xy 134.823881 -354.548924)
			(xy 134.846534 -354.59853) (xy 134.861897 -354.650855) (xy 134.869658 -354.704833) (xy 134.869658 -354.759367)
			(xy 134.869658 -354.75937) (xy 136.352506 -354.75937) (xy 136.352506 -354.70483) (xy 136.360268 -354.650845)
			(xy 136.375634 -354.598514) (xy 136.39829 -354.548902) (xy 136.427776 -354.50302) (xy 136.463492 -354.4618)
			(xy 136.50471 -354.426083) (xy 136.550591 -354.396596) (xy 136.600203 -354.373938) (xy 136.652533 -354.358571)
			(xy 136.706518 -354.350807) (xy 136.733788 -354.35032) (xy 137.597388 -354.35032) (xy 137.624658 -354.350819)
			(xy 137.678644 -354.358579) (xy 137.730976 -354.373944) (xy 137.780588 -354.396599) (xy 137.826471 -354.426085)
			(xy 137.867691 -354.461801) (xy 137.903408 -354.503019) (xy 137.932895 -354.548902) (xy 137.955552 -354.598513)
			(xy 137.970918 -354.650844) (xy 137.978681 -354.70483) (xy 137.978681 -354.75937) (xy 137.97868 -354.759374)
			(xy 139.461384 -354.759374) (xy 139.461384 -354.704826) (xy 139.469147 -354.650832) (xy 139.484517 -354.598493)
			(xy 139.507179 -354.548874) (xy 139.536672 -354.502986) (xy 139.572397 -354.461763) (xy 139.613625 -354.426044)
			(xy 139.659516 -354.396556) (xy 139.709138 -354.3739) (xy 139.761479 -354.358537) (xy 139.815473 -354.35078)
			(xy 139.842748 -354.35032) (xy 140.706348 -354.35032) (xy 140.733614 -354.350846) (xy 140.78759 -354.358613)
			(xy 140.839911 -354.373981) (xy 140.889513 -354.396639) (xy 140.935386 -354.426125) (xy 140.976595 -354.461839)
			(xy 141.012304 -354.503053) (xy 141.041784 -354.548929) (xy 141.064436 -354.598534) (xy 141.079798 -354.650857)
			(xy 141.087558 -354.704834) (xy 141.087558 -354.759366) (xy 141.087557 -354.759373) (xy 142.570384 -354.759373)
			(xy 142.570384 -354.704827) (xy 142.578146 -354.650837) (xy 142.593514 -354.598501) (xy 142.616173 -354.548885)
			(xy 142.645663 -354.502999) (xy 142.681383 -354.461777) (xy 142.722606 -354.426058) (xy 142.768492 -354.396569)
			(xy 142.818109 -354.373911) (xy 142.870445 -354.358545) (xy 142.924435 -354.350783) (xy 142.951708 -354.35032)
			(xy 143.815308 -354.35032) (xy 143.842576 -354.350843) (xy 143.896556 -354.358605) (xy 143.948882 -354.37397)
			(xy 143.998489 -354.396626) (xy 144.044367 -354.426111) (xy 144.085581 -354.461824) (xy 144.121294 -354.50304)
			(xy 144.150778 -354.548918) (xy 144.173432 -354.598525) (xy 144.188797 -354.650852) (xy 144.196558 -354.704832)
			(xy 144.196558 -354.759368) (xy 144.188797 -354.813348) (xy 144.173432 -354.865675) (xy 144.150778 -354.915282)
			(xy 144.121294 -354.96116) (xy 144.085581 -355.002376) (xy 144.044367 -355.038089) (xy 143.998489 -355.067574)
			(xy 143.948882 -355.09023) (xy 143.896556 -355.105595) (xy 143.842576 -355.113357) (xy 143.815308 -355.113844)
			(xy 142.951708 -355.113844) (xy 142.924435 -355.113417) (xy 142.870445 -355.105655) (xy 142.818109 -355.090289)
			(xy 142.768492 -355.067631) (xy 142.722606 -355.038142) (xy 142.681383 -355.002423) (xy 142.645663 -354.961201)
			(xy 142.616173 -354.915315) (xy 142.593514 -354.865699) (xy 142.578146 -354.813363) (xy 142.570384 -354.759373)
			(xy 141.087557 -354.759373) (xy 141.079798 -354.813343) (xy 141.064436 -354.865666) (xy 141.041784 -354.915271)
			(xy 141.012304 -354.961147) (xy 140.976595 -355.002361) (xy 140.935386 -355.038075) (xy 140.889513 -355.067561)
			(xy 140.839911 -355.090219) (xy 140.78759 -355.105587) (xy 140.733614 -355.113354) (xy 140.706348 -355.113844)
			(xy 139.842748 -355.113844) (xy 139.815473 -355.11342) (xy 139.761479 -355.105663) (xy 139.709138 -355.0903)
			(xy 139.659516 -355.067644) (xy 139.613625 -355.038156) (xy 139.572397 -355.002437) (xy 139.536672 -354.961214)
			(xy 139.507179 -354.915326) (xy 139.484517 -354.865707) (xy 139.469147 -354.813368) (xy 139.461384 -354.759374)
			(xy 137.97868 -354.759374) (xy 137.970918 -354.813356) (xy 137.955552 -354.865687) (xy 137.932895 -354.915298)
			(xy 137.903408 -354.961181) (xy 137.867691 -355.002399) (xy 137.826471 -355.038115) (xy 137.780588 -355.067601)
			(xy 137.730976 -355.090256) (xy 137.678644 -355.105621) (xy 137.624658 -355.113381) (xy 137.597388 -355.113844)
			(xy 136.733788 -355.113844) (xy 136.706518 -355.113393) (xy 136.652533 -355.105629) (xy 136.600203 -355.090262)
			(xy 136.550591 -355.067604) (xy 136.50471 -355.038117) (xy 136.463492 -355.0024) (xy 136.427776 -354.96118)
			(xy 136.39829 -354.915298) (xy 136.375634 -354.865686) (xy 136.360268 -354.813355) (xy 136.352506 -354.75937)
			(xy 134.869658 -354.75937) (xy 134.861897 -354.813345) (xy 134.846534 -354.86567) (xy 134.823881 -354.915276)
			(xy 134.794399 -354.961154) (xy 134.758688 -355.002369) (xy 134.717476 -355.038082) (xy 134.671601 -355.067567)
			(xy 134.621997 -355.090224) (xy 134.569673 -355.105591) (xy 134.515695 -355.113356) (xy 134.488428 -355.113844)
			(xy 133.624828 -355.113844) (xy 133.597554 -355.113418) (xy 133.543562 -355.105659) (xy 133.491223 -355.090295)
			(xy 133.441604 -355.067638) (xy 133.395715 -355.038149) (xy 133.35449 -355.00243) (xy 133.318768 -354.961207)
			(xy 133.289276 -354.91532) (xy 133.266615 -354.865703) (xy 133.251247 -354.813365) (xy 133.243484 -354.759374)
			(xy 131.76078 -354.759374) (xy 131.753018 -354.813358) (xy 131.737651 -354.865691) (xy 131.714992 -354.915304)
			(xy 131.685503 -354.961187) (xy 131.649783 -355.002406) (xy 131.608561 -355.038122) (xy 131.562676 -355.067607)
			(xy 131.513061 -355.090262) (xy 131.460727 -355.105625) (xy 131.406739 -355.113383) (xy 131.379468 -355.113844)
			(xy 130.515868 -355.113844) (xy 130.488599 -355.113391) (xy 130.434616 -355.105626) (xy 130.382288 -355.090257)
			(xy 130.33268 -355.067598) (xy 130.2868 -355.03811) (xy 130.245585 -355.002393) (xy 130.209871 -354.961174)
			(xy 130.180387 -354.915292) (xy 130.157732 -354.865682) (xy 130.142368 -354.813353) (xy 130.134606 -354.759369)
			(xy 128.651758 -354.759369) (xy 128.643997 -354.813348) (xy 128.628632 -354.865675) (xy 128.605978 -354.915282)
			(xy 128.576494 -354.96116) (xy 128.540781 -355.002376) (xy 128.499567 -355.038089) (xy 128.453689 -355.067574)
			(xy 128.404082 -355.09023) (xy 128.351756 -355.105595) (xy 128.297776 -355.113357) (xy 128.270508 -355.113844)
			(xy 127.406908 -355.113844) (xy 127.379635 -355.113417) (xy 127.325645 -355.105655) (xy 127.273309 -355.090289)
			(xy 127.223692 -355.067631) (xy 127.177806 -355.038142) (xy 127.136583 -355.002423) (xy 127.100863 -354.961201)
			(xy 127.071373 -354.915315) (xy 127.048714 -354.865699) (xy 127.033346 -354.813363) (xy 127.025584 -354.759373)
			(xy 125.542757 -354.759373) (xy 125.534998 -354.813343) (xy 125.519636 -354.865666) (xy 125.496984 -354.915271)
			(xy 125.467504 -354.961147) (xy 125.431795 -355.002361) (xy 125.390586 -355.038075) (xy 125.344713 -355.067561)
			(xy 125.295111 -355.090219) (xy 125.24279 -355.105587) (xy 125.188814 -355.113354) (xy 125.161548 -355.113844)
			(xy 124.297948 -355.113844) (xy 124.270673 -355.11342) (xy 124.216679 -355.105663) (xy 124.164338 -355.0903)
			(xy 124.114716 -355.067644) (xy 124.068825 -355.038156) (xy 124.027597 -355.002437) (xy 123.991872 -354.961214)
			(xy 123.962379 -354.915326) (xy 123.939717 -354.865707) (xy 123.924347 -354.813368) (xy 123.916584 -354.759374)
			(xy 122.43388 -354.759374) (xy 122.426118 -354.813356) (xy 122.410752 -354.865687) (xy 122.388095 -354.915298)
			(xy 122.358608 -354.961181) (xy 122.322891 -355.002399) (xy 122.281671 -355.038115) (xy 122.235788 -355.067601)
			(xy 122.186176 -355.090256) (xy 122.133844 -355.105621) (xy 122.079858 -355.113381) (xy 122.052588 -355.113844)
			(xy 121.188988 -355.113844) (xy 121.161718 -355.113393) (xy 121.107733 -355.105629) (xy 121.055403 -355.090262)
			(xy 121.005791 -355.067604) (xy 120.95991 -355.038117) (xy 120.918692 -355.0024) (xy 120.882976 -354.96118)
			(xy 120.85349 -354.915298) (xy 120.830834 -354.865686) (xy 120.815468 -354.813355) (xy 120.807706 -354.75937)
			(xy 119.324858 -354.75937) (xy 119.317097 -354.813345) (xy 119.301734 -354.86567) (xy 119.279081 -354.915276)
			(xy 119.249599 -354.961154) (xy 119.213888 -355.002369) (xy 119.172676 -355.038082) (xy 119.126801 -355.067567)
			(xy 119.077197 -355.090224) (xy 119.024873 -355.105591) (xy 118.970895 -355.113356) (xy 118.943628 -355.113844)
			(xy 118.080028 -355.113844) (xy 118.052754 -355.113418) (xy 117.998762 -355.105659) (xy 117.946423 -355.090295)
			(xy 117.896804 -355.067638) (xy 117.850915 -355.038149) (xy 117.80969 -355.00243) (xy 117.773968 -354.961207)
			(xy 117.744476 -354.91532) (xy 117.721815 -354.865703) (xy 117.706447 -354.813365) (xy 117.698684 -354.759374)
			(xy 116.21598 -354.759374) (xy 116.208218 -354.813358) (xy 116.192851 -354.865691) (xy 116.170192 -354.915304)
			(xy 116.140703 -354.961187) (xy 116.104983 -355.002406) (xy 116.063761 -355.038122) (xy 116.017876 -355.067607)
			(xy 115.968261 -355.090262) (xy 115.915927 -355.105625) (xy 115.861939 -355.113383) (xy 115.834668 -355.113844)
			(xy 114.971068 -355.113844) (xy 114.943799 -355.113391) (xy 114.889816 -355.105626) (xy 114.837488 -355.090257)
			(xy 114.78788 -355.067598) (xy 114.742 -355.03811) (xy 114.700785 -355.002393) (xy 114.665071 -354.961174)
			(xy 114.635587 -354.915292) (xy 114.612932 -354.865682) (xy 114.597568 -354.813353) (xy 114.589806 -354.759369)
			(xy 107.813575 -354.759369) (xy 107.829328 -354.784305) (xy 107.851366 -354.833313) (xy 107.866304 -354.88493)
			(xy 107.873848 -354.938133) (xy 107.874308 -354.965) (xy 107.873774 -354.994343) (xy 107.864787 -355.052338)
			(xy 107.847025 -355.108272) (xy 107.820907 -355.160826) (xy 107.787049 -355.208761) (xy 107.746251 -355.250946)
			(xy 107.699473 -355.286385) (xy 107.673902 -355.300788) (xy 107.663234 -355.30663) (xy 107.649518 -355.325934)
			(xy 107.633262 -355.429312) (xy 107.640374 -355.451918) (xy 107.648756 -355.460554) (xy 107.668531 -355.481984)
			(xy 107.701965 -355.529756) (xy 107.727743 -355.582058) (xy 107.745266 -355.637672) (xy 107.754127 -355.695305)
			(xy 107.754674 -355.72446) (xy 107.754188 -355.751711) (xy 107.746432 -355.805659) (xy 107.731077 -355.857954)
			(xy 107.708435 -355.907531) (xy 107.678969 -355.953381) (xy 107.643278 -355.994572) (xy 107.602087 -356.030263)
			(xy 107.556237 -356.059729) (xy 107.50666 -356.082371) (xy 107.454365 -356.097726) (xy 107.400417 -356.105482)
			(xy 107.345915 -356.105482) (xy 107.291967 -356.097726) (xy 107.239672 -356.082371) (xy 107.190095 -356.059729)
			(xy 107.144245 -356.030263) (xy 107.103054 -355.994572) (xy 107.067363 -355.953381) (xy 107.037897 -355.907531)
			(xy 107.015255 -355.857954) (xy 106.9999 -355.805659) (xy 106.992144 -355.751711) (xy 106.991658 -355.72446)
			(xy 106.577428 -355.72446) (xy 106.577827 -355.747781) (xy 106.585391 -355.773795) (xy 106.599522 -355.796908)
			(xy 106.619228 -355.815497) (xy 106.630978 -355.82225) (xy 106.65669 -355.836645) (xy 106.703806 -355.872029)
			(xy 106.744919 -355.914239) (xy 106.779048 -355.962272) (xy 106.805383 -356.014982) (xy 106.823295 -356.071117)
			(xy 106.832359 -356.129338) (xy 106.832908 -356.1588) (xy 106.832422 -356.186051) (xy 106.824666 -356.239999)
			(xy 106.809311 -356.292294) (xy 106.786669 -356.341871) (xy 106.757203 -356.387721) (xy 106.721512 -356.428912)
			(xy 106.680321 -356.464603) (xy 106.634471 -356.494069) (xy 106.584894 -356.516711) (xy 106.532599 -356.532066)
			(xy 106.478651 -356.539822) (xy 106.424149 -356.539822) (xy 106.370201 -356.532066) (xy 106.317906 -356.516711)
			(xy 106.268329 -356.494069) (xy 106.222479 -356.464603) (xy 106.181288 -356.428912) (xy 106.145597 -356.387721)
			(xy 106.116131 -356.341871) (xy 106.093489 -356.292294) (xy 106.078134 -356.239999) (xy 106.070378 -356.186051)
			(xy 106.069892 -356.1588) (xy 106.070357 -356.130229) (xy 106.078872 -356.073725) (xy 106.095727 -356.019125)
			(xy 106.120544 -355.967654) (xy 106.152767 -355.920463) (xy 106.191673 -355.878612) (xy 106.236391 -355.843038)
			(xy 106.2609 -355.828346) (xy 106.272424 -355.821209) (xy 106.291495 -355.801958) (xy 106.304835 -355.778371)
			(xy 106.311507 -355.752107) (xy 106.311041 -355.725013) (xy 106.303471 -355.698994) (xy 106.289329 -355.67588)
			(xy 106.269608 -355.657295) (xy 106.257852 -355.650546) (xy 106.232122 -355.636182) (xy 106.185009 -355.60079)
			(xy 106.1439 -355.558573) (xy 106.109774 -355.510535) (xy 106.083443 -355.45782) (xy 106.065533 -355.401683)
			(xy 106.05647 -355.343459) (xy 106.055922 -355.313996) (xy 101.483114 -355.313996) (xy 101.511499 -355.3569)
			(xy 101.535171 -355.407397) (xy 101.551239 -355.460804) (xy 101.559359 -355.51598) (xy 101.559868 -355.543866)
			(xy 101.559359 -355.571752) (xy 101.551239 -355.626928) (xy 101.535171 -355.680335) (xy 101.511499 -355.730832)
			(xy 101.480726 -355.777345) (xy 101.443509 -355.818882) (xy 101.400641 -355.854557) (xy 101.353035 -355.883611)
			(xy 101.301706 -355.905423) (xy 101.247749 -355.919529) (xy 101.192312 -355.925629) (xy 101.136578 -355.923592)
			(xy 101.081735 -355.913462) (xy 101.028951 -355.895455) (xy 100.979351 -355.869954) (xy 100.933993 -355.837503)
			(xy 100.893844 -355.798794) (xy 100.859758 -355.754651) (xy 100.832462 -355.706016) (xy 100.812539 -355.653925)
			(xy 100.800413 -355.599488) (xy 100.796342 -355.543866) (xy 56.310239 -355.543866) (xy 56.18353 -355.87305)
			(xy 56.181507 -355.87798) (xy 56.175746 -355.886943) (xy 56.1721 -355.89083) (xy 55.841646 -356.221284)
			(xy 103.80167 -356.221284) (xy 103.805741 -356.165662) (xy 103.817867 -356.111225) (xy 103.83779 -356.059134)
			(xy 103.865086 -356.010499) (xy 103.899172 -355.966356) (xy 103.939321 -355.927647) (xy 103.984679 -355.895196)
			(xy 104.034279 -355.869695) (xy 104.087063 -355.851688) (xy 104.141906 -355.841558) (xy 104.19764 -355.839521)
			(xy 104.253077 -355.845621) (xy 104.307034 -355.859727) (xy 104.358363 -355.881539) (xy 104.405969 -355.910593)
			(xy 104.448837 -355.946268) (xy 104.486054 -355.987805) (xy 104.516827 -356.034318) (xy 104.540499 -356.084815)
			(xy 104.556567 -356.138222) (xy 104.564687 -356.193398) (xy 104.565196 -356.221284) (xy 104.564687 -356.24917)
			(xy 104.556567 -356.304346) (xy 104.540499 -356.357753) (xy 104.516827 -356.40825) (xy 104.486054 -356.454763)
			(xy 104.448837 -356.4963) (xy 104.405969 -356.531975) (xy 104.358363 -356.561029) (xy 104.307034 -356.582841)
			(xy 104.253077 -356.596947) (xy 104.19764 -356.603047) (xy 104.141906 -356.60101) (xy 104.087063 -356.59088)
			(xy 104.034279 -356.572873) (xy 103.984679 -356.547372) (xy 103.939321 -356.514921) (xy 103.899172 -356.476212)
			(xy 103.865086 -356.432069) (xy 103.83779 -356.383434) (xy 103.817867 -356.331343) (xy 103.805741 -356.276906)
			(xy 103.80167 -356.221284) (xy 55.841646 -356.221284) (xy 54.277961 -357.784969) (xy 64.099931 -357.784969)
			(xy 64.099931 -357.730431) (xy 64.107693 -357.676448) (xy 64.123058 -357.62412) (xy 64.145714 -357.57451)
			(xy 64.1752 -357.52863) (xy 64.210914 -357.487413) (xy 64.252132 -357.451698) (xy 64.298012 -357.422213)
			(xy 64.347621 -357.399557) (xy 64.39995 -357.384193) (xy 64.453933 -357.376431) (xy 64.481202 -357.375968)
			(xy 65.344802 -357.375968) (xy 65.372073 -357.376395) (xy 65.426061 -357.384157) (xy 65.478394 -357.399524)
			(xy 65.528008 -357.422182) (xy 65.573893 -357.45167) (xy 65.615113 -357.487388) (xy 65.650831 -357.528609)
			(xy 65.680319 -357.574493) (xy 65.702977 -357.624107) (xy 65.718343 -357.676441) (xy 65.726106 -357.730429)
			(xy 65.726106 -357.784966) (xy 67.208954 -357.784966) (xy 67.208954 -357.730435) (xy 67.216714 -357.676458)
			(xy 67.232077 -357.624136) (xy 67.254728 -357.574532) (xy 67.284208 -357.528657) (xy 67.319917 -357.487443)
			(xy 67.361126 -357.451731) (xy 67.406999 -357.422246) (xy 67.4566 -357.39959) (xy 67.508921 -357.384222)
			(xy 67.562897 -357.376457) (xy 67.590162 -357.375968) (xy 68.453762 -357.375968) (xy 68.481037 -357.376369)
			(xy 68.535032 -357.384127) (xy 68.587373 -357.399491) (xy 68.636995 -357.422149) (xy 68.682887 -357.451638)
			(xy 68.724115 -357.487358) (xy 68.75984 -357.528582) (xy 68.789333 -357.574471) (xy 68.811995 -357.624091)
			(xy 68.827365 -357.676431) (xy 68.835128 -357.730425) (xy 68.835128 -357.78497) (xy 70.317831 -357.78497)
			(xy 70.317831 -357.73043) (xy 70.325594 -357.676446) (xy 70.34096 -357.624115) (xy 70.363617 -357.574505)
			(xy 70.393105 -357.528623) (xy 70.428822 -357.487406) (xy 70.470041 -357.451691) (xy 70.515924 -357.422207)
			(xy 70.565536 -357.399552) (xy 70.617867 -357.384189) (xy 70.671852 -357.37643) (xy 70.699122 -357.375968)
			(xy 71.562722 -357.375968) (xy 71.589992 -357.376396) (xy 71.643978 -357.384161) (xy 71.696309 -357.399529)
			(xy 71.74592 -357.422189) (xy 71.791802 -357.451677) (xy 71.83302 -357.487395) (xy 71.868736 -357.528616)
			(xy 71.898222 -357.574499) (xy 71.920878 -357.624112) (xy 71.936244 -357.676444) (xy 71.944006 -357.730429)
			(xy 71.944006 -357.784966) (xy 73.426854 -357.784966) (xy 73.426854 -357.730434) (xy 73.434615 -357.676456)
			(xy 73.449978 -357.624132) (xy 73.472631 -357.574527) (xy 73.502113 -357.52865) (xy 73.537824 -357.487436)
			(xy 73.579036 -357.451724) (xy 73.624911 -357.42224) (xy 73.674515 -357.399584) (xy 73.726838 -357.384219)
			(xy 73.780816 -357.376456) (xy 73.808082 -357.375968) (xy 74.671682 -357.375968) (xy 74.698956 -357.37637)
			(xy 74.752949 -357.384131) (xy 74.805288 -357.399497) (xy 74.854907 -357.422155) (xy 74.900797 -357.451645)
			(xy 74.942022 -357.487365) (xy 74.977744 -357.528589) (xy 75.007236 -357.574477) (xy 75.029897 -357.624095)
			(xy 75.045265 -357.676433) (xy 75.053028 -357.730426) (xy 75.053028 -357.784971) (xy 76.535732 -357.784971)
			(xy 76.535732 -357.730429) (xy 76.543494 -357.676443) (xy 76.558861 -357.624111) (xy 76.58152 -357.574499)
			(xy 76.611009 -357.528617) (xy 76.646729 -357.487399) (xy 76.687951 -357.451684) (xy 76.733836 -357.4222)
			(xy 76.78345 -357.399547) (xy 76.835784 -357.384185) (xy 76.889771 -357.376429) (xy 76.917042 -357.375968)
			(xy 77.780642 -357.375968) (xy 77.807912 -357.376397) (xy 77.861895 -357.384165) (xy 77.914223 -357.399535)
			(xy 77.963832 -357.422195) (xy 78.009711 -357.451684) (xy 78.050927 -357.487402) (xy 78.086641 -357.528622)
			(xy 78.116125 -357.574505) (xy 78.13878 -357.624116) (xy 78.154144 -357.676446) (xy 78.161906 -357.73043)
			(xy 78.161906 -357.784969) (xy 79.644731 -357.784969) (xy 79.644731 -357.730431) (xy 79.652493 -357.676448)
			(xy 79.667858 -357.62412) (xy 79.690514 -357.57451) (xy 79.72 -357.52863) (xy 79.755714 -357.487413)
			(xy 79.796932 -357.451698) (xy 79.842812 -357.422213) (xy 79.892421 -357.399557) (xy 79.94475 -357.384193)
			(xy 79.998733 -357.376431) (xy 80.026002 -357.375968) (xy 80.889602 -357.375968) (xy 80.916873 -357.376395)
			(xy 80.970861 -357.384157) (xy 81.023194 -357.399524) (xy 81.072808 -357.422182) (xy 81.118693 -357.45167)
			(xy 81.159913 -357.487388) (xy 81.195631 -357.528609) (xy 81.225119 -357.574493) (xy 81.247777 -357.624107)
			(xy 81.263143 -357.676441) (xy 81.270906 -357.730429) (xy 81.270906 -357.784966) (xy 82.753754 -357.784966)
			(xy 82.753754 -357.730435) (xy 82.761514 -357.676458) (xy 82.776877 -357.624136) (xy 82.799528 -357.574532)
			(xy 82.829008 -357.528657) (xy 82.864717 -357.487443) (xy 82.905926 -357.451731) (xy 82.951799 -357.422246)
			(xy 83.0014 -357.39959) (xy 83.053721 -357.384222) (xy 83.107697 -357.376457) (xy 83.134962 -357.375968)
			(xy 83.998562 -357.375968) (xy 84.025837 -357.376369) (xy 84.079832 -357.384127) (xy 84.132173 -357.399491)
			(xy 84.181795 -357.422149) (xy 84.227687 -357.451638) (xy 84.268915 -357.487358) (xy 84.30464 -357.528582)
			(xy 84.334133 -357.574471) (xy 84.356795 -357.624091) (xy 84.372165 -357.676431) (xy 84.379928 -357.730425)
			(xy 84.379928 -357.78497) (xy 85.862631 -357.78497) (xy 85.862631 -357.73043) (xy 85.870394 -357.676446)
			(xy 85.88576 -357.624115) (xy 85.908417 -357.574505) (xy 85.937905 -357.528623) (xy 85.973622 -357.487406)
			(xy 86.014841 -357.451691) (xy 86.060724 -357.422207) (xy 86.110336 -357.399552) (xy 86.162667 -357.384189)
			(xy 86.216652 -357.37643) (xy 86.243922 -357.375968) (xy 87.107522 -357.375968) (xy 87.134792 -357.376396)
			(xy 87.188778 -357.384161) (xy 87.241109 -357.399529) (xy 87.29072 -357.422189) (xy 87.336602 -357.451677)
			(xy 87.37782 -357.487395) (xy 87.413536 -357.528616) (xy 87.443022 -357.574499) (xy 87.465678 -357.624112)
			(xy 87.481044 -357.676444) (xy 87.488806 -357.730429) (xy 87.488806 -357.784966) (xy 88.971654 -357.784966)
			(xy 88.971654 -357.730434) (xy 88.979415 -357.676456) (xy 88.994778 -357.624132) (xy 89.017431 -357.574527)
			(xy 89.046913 -357.52865) (xy 89.082624 -357.487436) (xy 89.123836 -357.451724) (xy 89.169711 -357.42224)
			(xy 89.219315 -357.399584) (xy 89.271638 -357.384219) (xy 89.325616 -357.376456) (xy 89.352882 -357.375968)
			(xy 90.216482 -357.375968) (xy 90.243756 -357.37637) (xy 90.297749 -357.384131) (xy 90.350088 -357.399497)
			(xy 90.399707 -357.422155) (xy 90.445597 -357.451645) (xy 90.486822 -357.487365) (xy 90.522544 -357.528589)
			(xy 90.552036 -357.574477) (xy 90.574697 -357.624095) (xy 90.590065 -357.676433) (xy 90.597828 -357.730426)
			(xy 90.597828 -357.784971) (xy 92.080532 -357.784971) (xy 92.080532 -357.730429) (xy 92.088294 -357.676443)
			(xy 92.103661 -357.624111) (xy 92.12632 -357.574499) (xy 92.155809 -357.528617) (xy 92.191529 -357.487399)
			(xy 92.232751 -357.451684) (xy 92.278636 -357.4222) (xy 92.32825 -357.399547) (xy 92.380584 -357.384185)
			(xy 92.434571 -357.376429) (xy 92.461842 -357.375968) (xy 93.325442 -357.375968) (xy 93.352712 -357.376397)
			(xy 93.406695 -357.384165) (xy 93.459023 -357.399535) (xy 93.508632 -357.422195) (xy 93.554511 -357.451684)
			(xy 93.595727 -357.487402) (xy 93.631441 -357.528622) (xy 93.660925 -357.574505) (xy 93.68358 -357.624116)
			(xy 93.698944 -357.676446) (xy 93.706706 -357.73043) (xy 93.706706 -357.784966) (xy 114.589854 -357.784966)
			(xy 114.589854 -357.730434) (xy 114.597614 -357.676458) (xy 114.612977 -357.624135) (xy 114.635629 -357.574531)
			(xy 114.66511 -357.528655) (xy 114.700819 -357.487441) (xy 114.742029 -357.451729) (xy 114.787903 -357.422244)
			(xy 114.837505 -357.399588) (xy 114.889826 -357.384221) (xy 114.943802 -357.376457) (xy 114.971068 -357.375968)
			(xy 115.834668 -357.375968) (xy 115.861943 -357.376369) (xy 115.915937 -357.384128) (xy 115.968278 -357.399493)
			(xy 116.017899 -357.422151) (xy 116.06379 -357.45164) (xy 116.105017 -357.48736) (xy 116.140741 -357.528584)
			(xy 116.170234 -357.574473) (xy 116.192896 -357.624092) (xy 116.208265 -357.676431) (xy 116.216028 -357.730425)
			(xy 116.216028 -357.78497) (xy 117.698731 -357.78497) (xy 117.698732 -357.73043) (xy 117.706494 -357.676445)
			(xy 117.72186 -357.624114) (xy 117.744518 -357.574503) (xy 117.774006 -357.528621) (xy 117.809724 -357.487404)
			(xy 117.850944 -357.451689) (xy 117.896827 -357.422205) (xy 117.94644 -357.39955) (xy 117.998772 -357.384188)
			(xy 118.052758 -357.37643) (xy 118.080028 -357.375968) (xy 118.943628 -357.375968) (xy 118.970898 -357.376396)
			(xy 119.024883 -357.384162) (xy 119.077213 -357.399531) (xy 119.126824 -357.42219) (xy 119.172705 -357.451679)
			(xy 119.213922 -357.487397) (xy 119.249637 -357.528618) (xy 119.279123 -357.574501) (xy 119.301779 -357.624113)
			(xy 119.317144 -357.676444) (xy 119.324906 -357.73043) (xy 119.324906 -357.784967) (xy 120.807754 -357.784967)
			(xy 120.807754 -357.730433) (xy 120.815515 -357.676455) (xy 120.830879 -357.624131) (xy 120.853532 -357.574525)
			(xy 120.883015 -357.528648) (xy 120.918726 -357.487434) (xy 120.959939 -357.451722) (xy 121.005815 -357.422238)
			(xy 121.055419 -357.399583) (xy 121.107743 -357.384218) (xy 121.161721 -357.376455) (xy 121.188988 -357.375968)
			(xy 122.052588 -357.375968) (xy 122.079862 -357.376371) (xy 122.133854 -357.384132) (xy 122.186192 -357.399499)
			(xy 122.235811 -357.422157) (xy 122.2817 -357.451647) (xy 122.322924 -357.487367) (xy 122.358646 -357.528591)
			(xy 122.388137 -357.574479) (xy 122.410797 -357.624096) (xy 122.426165 -357.676434) (xy 122.433928 -357.730426)
			(xy 122.433928 -357.784971) (xy 123.916632 -357.784971) (xy 123.916632 -357.730429) (xy 123.924394 -357.676442)
			(xy 123.939762 -357.62411) (xy 123.962421 -357.574497) (xy 123.991911 -357.528615) (xy 124.027631 -357.487397)
			(xy 124.068853 -357.451682) (xy 124.114739 -357.422198) (xy 124.164355 -357.399545) (xy 124.216689 -357.384184)
			(xy 124.270677 -357.376428) (xy 124.297948 -357.375968) (xy 125.161548 -357.375968) (xy 125.188817 -357.376398)
			(xy 125.2428 -357.384166) (xy 125.295128 -357.399536) (xy 125.344736 -357.422197) (xy 125.390614 -357.451687)
			(xy 125.431829 -357.487405) (xy 125.467542 -357.528624) (xy 125.497026 -357.574506) (xy 125.51968 -357.624117)
			(xy 125.535045 -357.676447) (xy 125.542806 -357.730431) (xy 125.542806 -357.784969) (xy 127.025631 -357.784969)
			(xy 127.025631 -357.730431) (xy 127.033393 -357.676447) (xy 127.048759 -357.624118) (xy 127.071415 -357.574508)
			(xy 127.100901 -357.528628) (xy 127.136617 -357.487411) (xy 127.177834 -357.451696) (xy 127.223715 -357.422211)
			(xy 127.273326 -357.399556) (xy 127.325655 -357.384191) (xy 127.379639 -357.376431) (xy 127.406908 -357.375968)
			(xy 128.270508 -357.375968) (xy 128.297779 -357.376395) (xy 128.351766 -357.384158) (xy 128.404099 -357.399525)
			(xy 128.453712 -357.422184) (xy 128.499595 -357.451672) (xy 128.540815 -357.48739) (xy 128.576532 -357.528611)
			(xy 128.60602 -357.574495) (xy 128.628677 -357.624109) (xy 128.644043 -357.676442) (xy 128.651806 -357.730429)
			(xy 128.651806 -357.784966) (xy 130.134654 -357.784966) (xy 130.134654 -357.730434) (xy 130.142414 -357.676458)
			(xy 130.157777 -357.624135) (xy 130.180429 -357.574531) (xy 130.20991 -357.528655) (xy 130.245619 -357.487441)
			(xy 130.286829 -357.451729) (xy 130.332703 -357.422244) (xy 130.382305 -357.399588) (xy 130.434626 -357.384221)
			(xy 130.488602 -357.376457) (xy 130.515868 -357.375968) (xy 131.379468 -357.375968) (xy 131.406743 -357.376369)
			(xy 131.460737 -357.384128) (xy 131.513078 -357.399493) (xy 131.562699 -357.422151) (xy 131.60859 -357.45164)
			(xy 131.649817 -357.48736) (xy 131.685541 -357.528584) (xy 131.715034 -357.574473) (xy 131.737696 -357.624092)
			(xy 131.753065 -357.676431) (xy 131.760828 -357.730425) (xy 131.760828 -357.78497) (xy 133.243531 -357.78497)
			(xy 133.243532 -357.73043) (xy 133.251294 -357.676445) (xy 133.26666 -357.624114) (xy 133.289318 -357.574503)
			(xy 133.318806 -357.528621) (xy 133.354524 -357.487404) (xy 133.395744 -357.451689) (xy 133.441627 -357.422205)
			(xy 133.49124 -357.39955) (xy 133.543572 -357.384188) (xy 133.597558 -357.37643) (xy 133.624828 -357.375968)
			(xy 134.488428 -357.375968) (xy 134.515698 -357.376396) (xy 134.569683 -357.384162) (xy 134.622013 -357.399531)
			(xy 134.671624 -357.42219) (xy 134.717505 -357.451679) (xy 134.758722 -357.487397) (xy 134.794437 -357.528618)
			(xy 134.823923 -357.574501) (xy 134.846579 -357.624113) (xy 134.861944 -357.676444) (xy 134.869706 -357.73043)
			(xy 134.869706 -357.784967) (xy 136.352554 -357.784967) (xy 136.352554 -357.730433) (xy 136.360315 -357.676455)
			(xy 136.375679 -357.624131) (xy 136.398332 -357.574525) (xy 136.427815 -357.528648) (xy 136.463526 -357.487434)
			(xy 136.504739 -357.451722) (xy 136.550615 -357.422238) (xy 136.600219 -357.399583) (xy 136.652543 -357.384218)
			(xy 136.706521 -357.376455) (xy 136.733788 -357.375968) (xy 137.597388 -357.375968) (xy 137.624662 -357.376371)
			(xy 137.678654 -357.384132) (xy 137.730992 -357.399499) (xy 137.780611 -357.422157) (xy 137.8265 -357.451647)
			(xy 137.867724 -357.487367) (xy 137.903446 -357.528591) (xy 137.932937 -357.574479) (xy 137.955597 -357.624096)
			(xy 137.970965 -357.676434) (xy 137.978728 -357.730426) (xy 137.978728 -357.784971) (xy 139.461432 -357.784971)
			(xy 139.461432 -357.730429) (xy 139.469194 -357.676442) (xy 139.484562 -357.62411) (xy 139.507221 -357.574497)
			(xy 139.536711 -357.528615) (xy 139.572431 -357.487397) (xy 139.613653 -357.451682) (xy 139.659539 -357.422198)
			(xy 139.709155 -357.399545) (xy 139.761489 -357.384184) (xy 139.815477 -357.376428) (xy 139.842748 -357.375968)
			(xy 140.706348 -357.375968) (xy 140.733617 -357.376398) (xy 140.7876 -357.384166) (xy 140.839928 -357.399536)
			(xy 140.889536 -357.422197) (xy 140.935414 -357.451687) (xy 140.976629 -357.487405) (xy 141.012342 -357.528624)
			(xy 141.041826 -357.574506) (xy 141.06448 -357.624117) (xy 141.079845 -357.676447) (xy 141.087606 -357.730431)
			(xy 141.087606 -357.784969) (xy 142.570431 -357.784969) (xy 142.570431 -357.730431) (xy 142.578193 -357.676447)
			(xy 142.593559 -357.624118) (xy 142.616215 -357.574508) (xy 142.645701 -357.528628) (xy 142.681417 -357.487411)
			(xy 142.722634 -357.451696) (xy 142.768515 -357.422211) (xy 142.818126 -357.399556) (xy 142.870455 -357.384191)
			(xy 142.924439 -357.376431) (xy 142.951708 -357.375968) (xy 143.815308 -357.375968) (xy 143.842579 -357.376395)
			(xy 143.896566 -357.384158) (xy 143.948899 -357.399525) (xy 143.998512 -357.422184) (xy 144.044395 -357.451672)
			(xy 144.085615 -357.48739) (xy 144.121332 -357.528611) (xy 144.15082 -357.574495) (xy 144.173477 -357.624109)
			(xy 144.188843 -357.676442) (xy 144.196606 -357.730429) (xy 144.196606 -357.784971) (xy 144.188843 -357.838958)
			(xy 144.173477 -357.891291) (xy 144.15082 -357.940905) (xy 144.121332 -357.986789) (xy 144.085615 -358.02801)
			(xy 144.044395 -358.063728) (xy 143.998512 -358.093216) (xy 143.948899 -358.115875) (xy 143.896566 -358.131242)
			(xy 143.842579 -358.139005) (xy 143.815308 -358.139492) (xy 142.951708 -358.139492) (xy 142.924439 -358.138969)
			(xy 142.870455 -358.131209) (xy 142.818126 -358.115844) (xy 142.768515 -358.093189) (xy 142.722634 -358.063704)
			(xy 142.681417 -358.027989) (xy 142.645701 -357.986772) (xy 142.616215 -357.940892) (xy 142.593559 -357.891282)
			(xy 142.578193 -357.838953) (xy 142.570431 -357.784969) (xy 141.087606 -357.784969) (xy 141.079845 -357.838953)
			(xy 141.06448 -357.891283) (xy 141.041826 -357.940894) (xy 141.012342 -357.986776) (xy 140.976629 -358.027995)
			(xy 140.935414 -358.063713) (xy 140.889536 -358.093203) (xy 140.839928 -358.115864) (xy 140.7876 -358.131234)
			(xy 140.733617 -358.139002) (xy 140.706348 -358.139492) (xy 139.842748 -358.139492) (xy 139.815477 -358.138972)
			(xy 139.761489 -358.131216) (xy 139.709155 -358.115855) (xy 139.659539 -358.093202) (xy 139.613653 -358.063718)
			(xy 139.572431 -358.028003) (xy 139.536711 -357.986785) (xy 139.507221 -357.940903) (xy 139.484562 -357.89129)
			(xy 139.469194 -357.838958) (xy 139.461432 -357.784971) (xy 137.978728 -357.784971) (xy 137.978728 -357.784974)
			(xy 137.970965 -357.838966) (xy 137.955597 -357.891304) (xy 137.932937 -357.940921) (xy 137.903446 -357.986809)
			(xy 137.867724 -358.028033) (xy 137.8265 -358.063753) (xy 137.780611 -358.093243) (xy 137.730992 -358.115901)
			(xy 137.678654 -358.131268) (xy 137.624662 -358.139029) (xy 137.597388 -358.139492) (xy 136.733788 -358.139492)
			(xy 136.706521 -358.138945) (xy 136.652543 -358.131182) (xy 136.600219 -358.115817) (xy 136.550615 -358.093162)
			(xy 136.504739 -358.063678) (xy 136.463526 -358.027966) (xy 136.427815 -357.986752) (xy 136.398332 -357.940875)
			(xy 136.375679 -357.891269) (xy 136.360315 -357.838945) (xy 136.352554 -357.784967) (xy 134.869706 -357.784967)
			(xy 134.869706 -357.78497) (xy 134.861944 -357.838956) (xy 134.846579 -357.891287) (xy 134.823923 -357.940899)
			(xy 134.794437 -357.986782) (xy 134.758722 -358.028003) (xy 134.717505 -358.063721) (xy 134.671624 -358.09321)
			(xy 134.622013 -358.115869) (xy 134.569683 -358.131238) (xy 134.515698 -358.139004) (xy 134.488428 -358.139492)
			(xy 133.624828 -358.139492) (xy 133.597558 -358.13897) (xy 133.543572 -358.131212) (xy 133.49124 -358.11585)
			(xy 133.441627 -358.093195) (xy 133.395744 -358.063711) (xy 133.354524 -358.027996) (xy 133.318806 -357.986779)
			(xy 133.289318 -357.940897) (xy 133.26666 -357.891286) (xy 133.251294 -357.838955) (xy 133.243531 -357.78497)
			(xy 131.760828 -357.78497) (xy 131.760828 -357.784975) (xy 131.753065 -357.838969) (xy 131.737696 -357.891308)
			(xy 131.715034 -357.940927) (xy 131.685541 -357.986816) (xy 131.649817 -358.02804) (xy 131.60859 -358.06376)
			(xy 131.562699 -358.093249) (xy 131.513078 -358.115907) (xy 131.460737 -358.131272) (xy 131.406743 -358.139031)
			(xy 131.379468 -358.139492) (xy 130.515868 -358.139492) (xy 130.488602 -358.138943) (xy 130.434626 -358.131179)
			(xy 130.382305 -358.115812) (xy 130.332703 -358.093156) (xy 130.286829 -358.063671) (xy 130.245619 -358.027959)
			(xy 130.20991 -357.986745) (xy 130.180429 -357.940869) (xy 130.157777 -357.891265) (xy 130.142414 -357.838942)
			(xy 130.134654 -357.784966) (xy 128.651806 -357.784966) (xy 128.651806 -357.784971) (xy 128.644043 -357.838958)
			(xy 128.628677 -357.891291) (xy 128.60602 -357.940905) (xy 128.576532 -357.986789) (xy 128.540815 -358.02801)
			(xy 128.499595 -358.063728) (xy 128.453712 -358.093216) (xy 128.404099 -358.115875) (xy 128.351766 -358.131242)
			(xy 128.297779 -358.139005) (xy 128.270508 -358.139492) (xy 127.406908 -358.139492) (xy 127.379639 -358.138969)
			(xy 127.325655 -358.131209) (xy 127.273326 -358.115844) (xy 127.223715 -358.093189) (xy 127.177834 -358.063704)
			(xy 127.136617 -358.027989) (xy 127.100901 -357.986772) (xy 127.071415 -357.940892) (xy 127.048759 -357.891282)
			(xy 127.033393 -357.838953) (xy 127.025631 -357.784969) (xy 125.542806 -357.784969) (xy 125.535045 -357.838953)
			(xy 125.51968 -357.891283) (xy 125.497026 -357.940894) (xy 125.467542 -357.986776) (xy 125.431829 -358.027995)
			(xy 125.390614 -358.063713) (xy 125.344736 -358.093203) (xy 125.295128 -358.115864) (xy 125.2428 -358.131234)
			(xy 125.188817 -358.139002) (xy 125.161548 -358.139492) (xy 124.297948 -358.139492) (xy 124.270677 -358.138972)
			(xy 124.216689 -358.131216) (xy 124.164355 -358.115855) (xy 124.114739 -358.093202) (xy 124.068853 -358.063718)
			(xy 124.027631 -358.028003) (xy 123.991911 -357.986785) (xy 123.962421 -357.940903) (xy 123.939762 -357.89129)
			(xy 123.924394 -357.838958) (xy 123.916632 -357.784971) (xy 122.433928 -357.784971) (xy 122.433928 -357.784974)
			(xy 122.426165 -357.838966) (xy 122.410797 -357.891304) (xy 122.388137 -357.940921) (xy 122.358646 -357.986809)
			(xy 122.322924 -358.028033) (xy 122.2817 -358.063753) (xy 122.235811 -358.093243) (xy 122.186192 -358.115901)
			(xy 122.133854 -358.131268) (xy 122.079862 -358.139029) (xy 122.052588 -358.139492) (xy 121.188988 -358.139492)
			(xy 121.161721 -358.138945) (xy 121.107743 -358.131182) (xy 121.055419 -358.115817) (xy 121.005815 -358.093162)
			(xy 120.959939 -358.063678) (xy 120.918726 -358.027966) (xy 120.883015 -357.986752) (xy 120.853532 -357.940875)
			(xy 120.830879 -357.891269) (xy 120.815515 -357.838945) (xy 120.807754 -357.784967) (xy 119.324906 -357.784967)
			(xy 119.324906 -357.78497) (xy 119.317144 -357.838956) (xy 119.301779 -357.891287) (xy 119.279123 -357.940899)
			(xy 119.249637 -357.986782) (xy 119.213922 -358.028003) (xy 119.172705 -358.063721) (xy 119.126824 -358.09321)
			(xy 119.077213 -358.115869) (xy 119.024883 -358.131238) (xy 118.970898 -358.139004) (xy 118.943628 -358.139492)
			(xy 118.080028 -358.139492) (xy 118.052758 -358.13897) (xy 117.998772 -358.131212) (xy 117.94644 -358.11585)
			(xy 117.896827 -358.093195) (xy 117.850944 -358.063711) (xy 117.809724 -358.027996) (xy 117.774006 -357.986779)
			(xy 117.744518 -357.940897) (xy 117.72186 -357.891286) (xy 117.706494 -357.838955) (xy 117.698731 -357.78497)
			(xy 116.216028 -357.78497) (xy 116.216028 -357.784975) (xy 116.208265 -357.838969) (xy 116.192896 -357.891308)
			(xy 116.170234 -357.940927) (xy 116.140741 -357.986816) (xy 116.105017 -358.02804) (xy 116.06379 -358.06376)
			(xy 116.017899 -358.093249) (xy 115.968278 -358.115907) (xy 115.915937 -358.131272) (xy 115.861943 -358.139031)
			(xy 115.834668 -358.139492) (xy 114.971068 -358.139492) (xy 114.943802 -358.138943) (xy 114.889826 -358.131179)
			(xy 114.837505 -358.115812) (xy 114.787903 -358.093156) (xy 114.742029 -358.063671) (xy 114.700819 -358.027959)
			(xy 114.66511 -357.986745) (xy 114.635629 -357.940869) (xy 114.612977 -357.891265) (xy 114.597614 -357.838942)
			(xy 114.589854 -357.784966) (xy 93.706706 -357.784966) (xy 93.706706 -357.78497) (xy 93.698944 -357.838954)
			(xy 93.68358 -357.891284) (xy 93.660925 -357.940895) (xy 93.631441 -357.986778) (xy 93.595727 -358.027998)
			(xy 93.554511 -358.063716) (xy 93.508632 -358.093205) (xy 93.459023 -358.115865) (xy 93.406695 -358.131235)
			(xy 93.352712 -358.139003) (xy 93.325442 -358.139492) (xy 92.461842 -358.139492) (xy 92.434571 -358.138971)
			(xy 92.380584 -358.131215) (xy 92.32825 -358.115853) (xy 92.278636 -358.0932) (xy 92.23275 -358.063716)
			(xy 92.191529 -358.028001) (xy 92.155809 -357.986783) (xy 92.12632 -357.940901) (xy 92.103661 -357.891289)
			(xy 92.088294 -357.838957) (xy 92.080532 -357.784971) (xy 90.597828 -357.784971) (xy 90.597828 -357.784974)
			(xy 90.590065 -357.838967) (xy 90.574697 -357.891305) (xy 90.552036 -357.940923) (xy 90.522544 -357.986811)
			(xy 90.486822 -358.028035) (xy 90.445597 -358.063755) (xy 90.399707 -358.093245) (xy 90.350088 -358.115903)
			(xy 90.297749 -358.131269) (xy 90.243756 -358.13903) (xy 90.216482 -358.139492) (xy 89.352882 -358.139492)
			(xy 89.325616 -358.138944) (xy 89.271638 -358.131181) (xy 89.219315 -358.115816) (xy 89.169711 -358.09316)
			(xy 89.123836 -358.063676) (xy 89.082624 -358.027964) (xy 89.046913 -357.98675) (xy 89.017431 -357.940873)
			(xy 88.994778 -357.891268) (xy 88.979415 -357.838944) (xy 88.971654 -357.784966) (xy 87.488806 -357.784966)
			(xy 87.488806 -357.784971) (xy 87.481044 -357.838956) (xy 87.465678 -357.891288) (xy 87.443022 -357.940901)
			(xy 87.413536 -357.986784) (xy 87.37782 -358.028005) (xy 87.336602 -358.063723) (xy 87.29072 -358.093211)
			(xy 87.241109 -358.115871) (xy 87.188778 -358.131239) (xy 87.134792 -358.139004) (xy 87.107522 -358.139492)
			(xy 86.243922 -358.139492) (xy 86.216652 -358.13897) (xy 86.162667 -358.131211) (xy 86.110336 -358.115848)
			(xy 86.060724 -358.093193) (xy 86.014841 -358.063709) (xy 85.973622 -358.027994) (xy 85.937905 -357.986777)
			(xy 85.908417 -357.940895) (xy 85.88576 -357.891285) (xy 85.870394 -357.838954) (xy 85.862631 -357.78497)
			(xy 84.379928 -357.78497) (xy 84.379928 -357.784975) (xy 84.372165 -357.838969) (xy 84.356795 -357.891309)
			(xy 84.334133 -357.940929) (xy 84.30464 -357.986818) (xy 84.268915 -358.028042) (xy 84.227687 -358.063762)
			(xy 84.181795 -358.093251) (xy 84.132173 -358.115908) (xy 84.079832 -358.131273) (xy 84.025837 -358.139031)
			(xy 83.998562 -358.139492) (xy 83.134962 -358.139492) (xy 83.107697 -358.138943) (xy 83.053721 -358.131178)
			(xy 83.0014 -358.11581) (xy 82.951799 -358.093154) (xy 82.905926 -358.063669) (xy 82.864717 -358.027957)
			(xy 82.829008 -357.986743) (xy 82.799528 -357.940868) (xy 82.776877 -357.891264) (xy 82.761514 -357.838942)
			(xy 82.753754 -357.784966) (xy 81.270906 -357.784966) (xy 81.270906 -357.784971) (xy 81.263143 -357.838959)
			(xy 81.247777 -357.891293) (xy 81.225119 -357.940907) (xy 81.195631 -357.986791) (xy 81.159913 -358.028012)
			(xy 81.118693 -358.06373) (xy 81.072808 -358.093218) (xy 81.023194 -358.115876) (xy 80.970861 -358.131243)
			(xy 80.916873 -358.139005) (xy 80.889602 -358.139492) (xy 80.026002 -358.139492) (xy 79.998733 -358.138969)
			(xy 79.94475 -358.131207) (xy 79.892421 -358.115843) (xy 79.842812 -358.093187) (xy 79.796932 -358.063702)
			(xy 79.755714 -358.027987) (xy 79.72 -357.98677) (xy 79.690514 -357.94089) (xy 79.667858 -357.89128)
			(xy 79.652493 -357.838952) (xy 79.644731 -357.784969) (xy 78.161906 -357.784969) (xy 78.161906 -357.78497)
			(xy 78.154144 -357.838954) (xy 78.13878 -357.891284) (xy 78.116125 -357.940895) (xy 78.086641 -357.986778)
			(xy 78.050927 -358.027998) (xy 78.009711 -358.063716) (xy 77.963832 -358.093205) (xy 77.914223 -358.115865)
			(xy 77.861895 -358.131235) (xy 77.807912 -358.139003) (xy 77.780642 -358.139492) (xy 76.917042 -358.139492)
			(xy 76.889771 -358.138971) (xy 76.835784 -358.131215) (xy 76.78345 -358.115853) (xy 76.733836 -358.0932)
			(xy 76.68795 -358.063716) (xy 76.646729 -358.028001) (xy 76.611009 -357.986783) (xy 76.58152 -357.940901)
			(xy 76.558861 -357.891289) (xy 76.543494 -357.838957) (xy 76.535732 -357.784971) (xy 75.053028 -357.784971)
			(xy 75.053028 -357.784974) (xy 75.045265 -357.838967) (xy 75.029897 -357.891305) (xy 75.007236 -357.940923)
			(xy 74.977744 -357.986811) (xy 74.942022 -358.028035) (xy 74.900797 -358.063755) (xy 74.854907 -358.093245)
			(xy 74.805288 -358.115903) (xy 74.752949 -358.131269) (xy 74.698956 -358.13903) (xy 74.671682 -358.139492)
			(xy 73.808082 -358.139492) (xy 73.780816 -358.138944) (xy 73.726838 -358.131181) (xy 73.674515 -358.115816)
			(xy 73.624911 -358.09316) (xy 73.579036 -358.063676) (xy 73.537824 -358.027964) (xy 73.502113 -357.98675)
			(xy 73.472631 -357.940873) (xy 73.449978 -357.891268) (xy 73.434615 -357.838944) (xy 73.426854 -357.784966)
			(xy 71.944006 -357.784966) (xy 71.944006 -357.784971) (xy 71.936244 -357.838956) (xy 71.920878 -357.891288)
			(xy 71.898222 -357.940901) (xy 71.868736 -357.986784) (xy 71.83302 -358.028005) (xy 71.791802 -358.063723)
			(xy 71.74592 -358.093211) (xy 71.696309 -358.115871) (xy 71.643978 -358.131239) (xy 71.589992 -358.139004)
			(xy 71.562722 -358.139492) (xy 70.699122 -358.139492) (xy 70.671852 -358.13897) (xy 70.617867 -358.131211)
			(xy 70.565536 -358.115848) (xy 70.515924 -358.093193) (xy 70.470041 -358.063709) (xy 70.428822 -358.027994)
			(xy 70.393105 -357.986777) (xy 70.363617 -357.940895) (xy 70.34096 -357.891285) (xy 70.325594 -357.838954)
			(xy 70.317831 -357.78497) (xy 68.835128 -357.78497) (xy 68.835128 -357.784975) (xy 68.827365 -357.838969)
			(xy 68.811995 -357.891309) (xy 68.789333 -357.940929) (xy 68.75984 -357.986818) (xy 68.724115 -358.028042)
			(xy 68.682887 -358.063762) (xy 68.636995 -358.093251) (xy 68.587373 -358.115908) (xy 68.535032 -358.131273)
			(xy 68.481037 -358.139031) (xy 68.453762 -358.139492) (xy 67.590162 -358.139492) (xy 67.562897 -358.138943)
			(xy 67.508921 -358.131178) (xy 67.4566 -358.11581) (xy 67.406999 -358.093154) (xy 67.361126 -358.063669)
			(xy 67.319917 -358.027957) (xy 67.284208 -357.986743) (xy 67.254728 -357.940868) (xy 67.232077 -357.891264)
			(xy 67.216714 -357.838942) (xy 67.208954 -357.784966) (xy 65.726106 -357.784966) (xy 65.726106 -357.784971)
			(xy 65.718343 -357.838959) (xy 65.702977 -357.891293) (xy 65.680319 -357.940907) (xy 65.650831 -357.986791)
			(xy 65.615113 -358.028012) (xy 65.573893 -358.06373) (xy 65.528008 -358.093218) (xy 65.478394 -358.115876)
			(xy 65.426061 -358.131243) (xy 65.372073 -358.139005) (xy 65.344802 -358.139492) (xy 64.481202 -358.139492)
			(xy 64.453933 -358.138969) (xy 64.39995 -358.131207) (xy 64.347621 -358.115843) (xy 64.298012 -358.093187)
			(xy 64.252132 -358.063702) (xy 64.210914 -358.027987) (xy 64.1752 -357.98677) (xy 64.145714 -357.94089)
			(xy 64.123058 -357.89128) (xy 64.107693 -357.838952) (xy 64.099931 -357.784969) (xy 54.277961 -357.784969)
			(xy 52.045147 -360.017783) (xy 101.774757 -360.017783) (xy 101.774757 -359.957817) (xy 101.782584 -359.898365)
			(xy 101.798104 -359.840443) (xy 101.821052 -359.785042) (xy 101.851035 -359.733111) (xy 101.88754 -359.685538)
			(xy 101.929942 -359.643136) (xy 101.977516 -359.606632) (xy 102.029448 -359.57665) (xy 102.084849 -359.553703)
			(xy 102.142771 -359.538183) (xy 102.202223 -359.530357) (xy 102.232206 -359.529888) (xy 103.095806 -359.529888)
			(xy 103.125793 -359.530279) (xy 103.185255 -359.538108) (xy 103.243186 -359.553631) (xy 103.298595 -359.576583)
			(xy 103.350534 -359.60657) (xy 103.398115 -359.643081) (xy 103.440523 -359.68549) (xy 103.477033 -359.733071)
			(xy 103.50702 -359.785011) (xy 103.529971 -359.84042) (xy 103.545494 -359.898351) (xy 103.553322 -359.957813)
			(xy 103.553322 -360.017787) (xy 103.545494 -360.077249) (xy 103.529971 -360.13518) (xy 103.525241 -360.1466)
			(xy 106.603292 -360.1466) (xy 106.603805 -360.117682) (xy 106.612541 -360.060509) (xy 106.629813 -360.005313)
			(xy 106.655224 -359.953358) (xy 106.688191 -359.905838) (xy 106.707686 -359.884472) (xy 106.714036 -359.877614)
			(xy 106.721148 -359.86085) (xy 106.724704 -359.775252) (xy 106.718862 -359.758234) (xy 106.71302 -359.750868)
			(xy 106.69712 -359.730454) (xy 106.670426 -359.686126) (xy 106.649966 -359.638599) (xy 106.636113 -359.588743)
			(xy 106.629123 -359.537472) (xy 106.628692 -359.5116) (xy 106.629178 -359.484349) (xy 106.636934 -359.430401)
			(xy 106.652289 -359.378106) (xy 106.674931 -359.328529) (xy 106.704397 -359.282679) (xy 106.740088 -359.241488)
			(xy 106.781279 -359.205797) (xy 106.827129 -359.176331) (xy 106.876706 -359.153689) (xy 106.929001 -359.138334)
			(xy 106.982949 -359.130578) (xy 107.037451 -359.130578) (xy 107.091399 -359.138334) (xy 107.143694 -359.153689)
			(xy 107.193271 -359.176331) (xy 107.239121 -359.205797) (xy 107.280312 -359.241488) (xy 107.316003 -359.282679)
			(xy 107.345469 -359.328529) (xy 107.368111 -359.378106) (xy 107.383466 -359.430401) (xy 107.391222 -359.484349)
			(xy 107.391708 -359.5116) (xy 107.391195 -359.540518) (xy 107.382459 -359.597691) (xy 107.365187 -359.652887)
			(xy 107.339776 -359.704842) (xy 107.306809 -359.752362) (xy 107.287314 -359.773728) (xy 107.280964 -359.780586)
			(xy 107.273852 -359.79735) (xy 107.270296 -359.882948) (xy 107.276138 -359.899966) (xy 107.28198 -359.907332)
			(xy 107.29788 -359.927746) (xy 107.324574 -359.972074) (xy 107.345034 -360.019601) (xy 107.358887 -360.069457)
			(xy 107.365877 -360.120728) (xy 107.366308 -360.1466) (xy 107.365822 -360.173851) (xy 107.358066 -360.227799)
			(xy 107.342711 -360.280094) (xy 107.320069 -360.329671) (xy 107.290603 -360.375521) (xy 107.254912 -360.416712)
			(xy 107.213721 -360.452403) (xy 107.167871 -360.481869) (xy 107.118294 -360.504511) (xy 107.065999 -360.519866)
			(xy 107.012051 -360.527622) (xy 106.957549 -360.527622) (xy 106.903601 -360.519866) (xy 106.851306 -360.504511)
			(xy 106.801729 -360.481869) (xy 106.755879 -360.452403) (xy 106.714688 -360.416712) (xy 106.678997 -360.375521)
			(xy 106.649531 -360.329671) (xy 106.626889 -360.280094) (xy 106.611534 -360.227799) (xy 106.603778 -360.173851)
			(xy 106.603292 -360.1466) (xy 103.525241 -360.1466) (xy 103.50702 -360.190589) (xy 103.477033 -360.242529)
			(xy 103.440523 -360.29011) (xy 103.398115 -360.332519) (xy 103.350534 -360.36903) (xy 103.298595 -360.399017)
			(xy 103.243186 -360.421969) (xy 103.185255 -360.437492) (xy 103.125793 -360.445321) (xy 103.095806 -360.445812)
			(xy 102.232206 -360.445812) (xy 102.202223 -360.445243) (xy 102.142771 -360.437417) (xy 102.084849 -360.421897)
			(xy 102.029448 -360.39895) (xy 101.977516 -360.368968) (xy 101.929942 -360.332464) (xy 101.88754 -360.290062)
			(xy 101.851035 -360.242489) (xy 101.821052 -360.190558) (xy 101.798104 -360.135157) (xy 101.782584 -360.077235)
			(xy 101.774757 -360.017783) (xy 52.045147 -360.017783) (xy 51.571144 -360.491786) (xy 51.563778 -360.498898)
			(xy 51.556158 -360.517694) (xy 51.556158 -361.5944) (xy 99.489292 -361.5944) (xy 99.493275 -361.541253)
			(xy 99.505134 -361.489292) (xy 99.524605 -361.43968) (xy 99.551252 -361.393523) (xy 99.58448 -361.351854)
			(xy 99.623548 -361.315602) (xy 99.667582 -361.285577) (xy 99.7156 -361.26245) (xy 99.766527 -361.246738)
			(xy 99.819228 -361.238791) (xy 99.845876 -361.238292) (xy 99.872284 -361.238789) (xy 99.924522 -361.246586)
			(xy 99.975035 -361.262015) (xy 100.022714 -361.284735) (xy 100.066515 -361.314249) (xy 100.105476 -361.349909)
			(xy 100.122482 -361.370118) (xy 100.130063 -361.378668) (xy 100.150689 -361.388452) (xy 100.162106 -361.388914)
			(xy 100.240846 -361.388914) (xy 100.252228 -361.388292) (xy 100.272798 -361.378547) (xy 100.28047 -361.370118)
			(xy 100.297489 -361.349919) (xy 100.336446 -361.314256) (xy 100.380244 -361.284738) (xy 100.427921 -361.262012)
			(xy 100.478432 -361.246578) (xy 100.530668 -361.238773) (xy 100.557076 -361.238292) (xy 100.583728 -361.238764)
			(xy 100.636438 -361.246705) (xy 100.687375 -361.262414) (xy 100.735402 -361.28554) (xy 100.779446 -361.315565)
			(xy 100.818522 -361.35182) (xy 100.851758 -361.393494) (xy 100.878411 -361.439657) (xy 100.897886 -361.489276)
			(xy 100.909748 -361.541244) (xy 100.913732 -361.5944) (xy 100.909748 -361.647556) (xy 100.897886 -361.699524)
			(xy 100.878411 -361.749143) (xy 100.851758 -361.795306) (xy 100.818522 -361.83698) (xy 100.779446 -361.873235)
			(xy 100.735402 -361.90326) (xy 100.687375 -361.926386) (xy 100.636438 -361.942095) (xy 100.583728 -361.950036)
			(xy 100.557076 -361.950508) (xy 100.530667 -361.950046) (xy 100.478427 -361.942241) (xy 100.427914 -361.926806)
			(xy 100.380234 -361.904079) (xy 100.336434 -361.874559) (xy 100.297475 -361.838894) (xy 100.28047 -361.818682)
			(xy 100.272909 -361.81011) (xy 100.252268 -361.800338) (xy 100.240846 -361.799886) (xy 100.162106 -361.799886)
			(xy 100.150721 -361.80048) (xy 100.130151 -361.810245) (xy 100.122482 -361.818682) (xy 100.105489 -361.838904)
			(xy 100.066527 -361.874566) (xy 100.022724 -361.904081) (xy 99.975041 -361.926803) (xy 99.924526 -361.942232)
			(xy 99.872286 -361.95003) (xy 99.845876 -361.950508) (xy 99.819228 -361.950009) (xy 99.766527 -361.942062)
			(xy 99.7156 -361.92635) (xy 99.667582 -361.903223) (xy 99.623548 -361.873198) (xy 99.58448 -361.836946)
			(xy 99.551252 -361.795277) (xy 99.524605 -361.74912) (xy 99.505134 -361.699508) (xy 99.493275 -361.647547)
			(xy 99.489292 -361.5944) (xy 51.556158 -361.5944) (xy 51.556158 -363.334808) (xy 54.890416 -363.334808)
			(xy 54.890416 -362.471208) (xy 54.890906 -362.441224) (xy 54.898734 -362.381768) (xy 54.914255 -362.323843)
			(xy 54.937204 -362.268439) (xy 54.967188 -362.216505) (xy 55.003694 -362.168929) (xy 55.046099 -362.126524)
			(xy 55.093675 -362.090018) (xy 55.145609 -362.060034) (xy 55.201013 -362.037085) (xy 55.258938 -362.021564)
			(xy 55.318394 -362.013736) (xy 55.378362 -362.013736) (xy 55.437818 -362.021564) (xy 55.495743 -362.037085)
			(xy 55.551147 -362.060034) (xy 55.603081 -362.090018) (xy 55.650657 -362.126524) (xy 55.693062 -362.168929)
			(xy 55.729568 -362.216505) (xy 55.759552 -362.268439) (xy 55.782501 -362.323843) (xy 55.798022 -362.381768)
			(xy 55.80585 -362.441224) (xy 55.80634 -362.471208) (xy 55.80634 -363.334808) (xy 55.80585 -363.364792)
			(xy 55.798022 -363.424248) (xy 55.782501 -363.482173) (xy 55.759552 -363.537577) (xy 55.729568 -363.589511)
			(xy 55.693062 -363.637087) (xy 55.650657 -363.679492) (xy 55.603081 -363.715998) (xy 55.551147 -363.745982)
			(xy 55.495743 -363.768931) (xy 55.437818 -363.784452) (xy 55.378362 -363.79228) (xy 55.318394 -363.79228)
			(xy 55.258938 -363.784452) (xy 55.201013 -363.768931) (xy 55.145609 -363.745982) (xy 55.093675 -363.715998)
			(xy 55.046099 -363.679492) (xy 55.003694 -363.637087) (xy 54.967188 -363.589511) (xy 54.937204 -363.537577)
			(xy 54.914255 -363.482173) (xy 54.898734 -363.424248) (xy 54.890906 -363.364792) (xy 54.890416 -363.334808)
			(xy 51.556158 -363.334808) (xy 51.556158 -365.797384) (xy 54.438294 -365.797384) (xy 54.438294 -365.737416)
			(xy 54.446121 -365.67796) (xy 54.461641 -365.620034) (xy 54.484589 -365.564629) (xy 54.514571 -365.512694)
			(xy 54.551076 -365.465115) (xy 54.593478 -365.422709) (xy 54.641052 -365.386199) (xy 54.692984 -365.356211)
			(xy 54.748387 -365.333257) (xy 54.806311 -365.317731) (xy 54.865766 -365.309897) (xy 54.89575 -365.309404)
			(xy 55.75935 -365.309404) (xy 55.789336 -365.309938) (xy 55.848794 -365.31776) (xy 55.906723 -365.333276)
			(xy 55.962131 -365.356222) (xy 56.01407 -365.386203) (xy 56.06165 -365.422708) (xy 56.104059 -365.465112)
			(xy 56.140569 -365.512689) (xy 56.170556 -365.564624) (xy 56.193508 -365.620029) (xy 56.20903 -365.677957)
			(xy 56.216859 -365.737414) (xy 56.216859 -365.797386) (xy 56.20903 -365.856843) (xy 56.193508 -365.914771)
			(xy 56.170556 -365.970176) (xy 56.140569 -366.022112) (xy 56.104059 -366.069688) (xy 56.06165 -366.112092)
			(xy 56.01407 -366.148597) (xy 55.962131 -366.178578) (xy 55.906723 -366.201524) (xy 55.848794 -366.21704)
			(xy 55.789336 -366.224862) (xy 55.75935 -366.225328) (xy 54.89575 -366.225328) (xy 54.865766 -366.224903)
			(xy 54.806311 -366.217069) (xy 54.748386 -366.201543) (xy 54.692984 -366.178589) (xy 54.641052 -366.148601)
			(xy 54.593478 -366.112091) (xy 54.551076 -366.069685) (xy 54.514571 -366.022106) (xy 54.484589 -365.970171)
			(xy 54.461641 -365.914766) (xy 54.446121 -365.85684) (xy 54.438294 -365.797384) (xy 51.556158 -365.797384)
			(xy 51.556158 -368.516662) (xy 53.966364 -368.516662) (xy 53.966364 -367.653062) (xy 53.96685 -367.625793)
			(xy 53.974612 -367.571809) (xy 53.989977 -367.519479) (xy 54.012634 -367.469869) (xy 54.04212 -367.423988)
			(xy 54.077835 -367.382771) (xy 54.119052 -367.347056) (xy 54.164933 -367.31757) (xy 54.214543 -367.294913)
			(xy 54.266873 -367.279548) (xy 54.320857 -367.271786) (xy 54.375395 -367.271786) (xy 54.429379 -367.279548)
			(xy 54.481709 -367.294913) (xy 54.531319 -367.31757) (xy 54.5772 -367.347056) (xy 54.618417 -367.382771)
			(xy 54.654132 -367.423988) (xy 54.683618 -367.469869) (xy 54.706275 -367.519479) (xy 54.72164 -367.571809)
			(xy 54.729402 -367.625793) (xy 54.729888 -367.653062) (xy 54.729888 -368.516662) (xy 57.339484 -368.516662)
			(xy 57.339484 -367.653062) (xy 57.33997 -367.625793) (xy 57.347732 -367.571809) (xy 57.363097 -367.519479)
			(xy 57.385754 -367.469869) (xy 57.41524 -367.423988) (xy 57.450955 -367.382771) (xy 57.492172 -367.347056)
			(xy 57.538053 -367.31757) (xy 57.587663 -367.294913) (xy 57.639993 -367.279548) (xy 57.693977 -367.271786)
			(xy 57.748515 -367.271786) (xy 57.802499 -367.279548) (xy 57.854829 -367.294913) (xy 57.904439 -367.31757)
			(xy 57.95032 -367.347056) (xy 57.991537 -367.382771) (xy 58.027252 -367.423988) (xy 58.056738 -367.469869)
			(xy 58.079395 -367.519479) (xy 58.09476 -367.571809) (xy 58.102522 -367.625793) (xy 58.103008 -367.653062)
			(xy 58.103008 -367.680826) (xy 99.682623 -367.680826) (xy 99.682626 -367.626333) (xy 99.690383 -367.572394)
			(xy 99.705738 -367.520109) (xy 99.728377 -367.47054) (xy 99.75784 -367.424698) (xy 99.793527 -367.383516)
			(xy 99.834711 -367.347831) (xy 99.880554 -367.31837) (xy 99.930124 -367.295733) (xy 99.98241 -367.28038)
			(xy 100.036349 -367.272624) (xy 100.090842 -367.272624) (xy 100.144781 -367.280378) (xy 100.197068 -367.295729)
			(xy 100.246637 -367.318365) (xy 100.292481 -367.347825) (xy 100.333666 -367.383509) (xy 100.369354 -367.424691)
			(xy 100.398818 -367.470532) (xy 100.421459 -367.5201) (xy 100.436815 -367.572385) (xy 100.444574 -367.626323)
			(xy 100.445062 -367.65357) (xy 100.444303 -367.687997) (xy 100.431907 -367.755726) (xy 100.420424 -367.78819)
			(xy 100.415625 -367.80207) (xy 100.413449 -367.83135) (xy 100.419694 -367.860038) (xy 100.433846 -367.885763)
			(xy 100.454732 -367.906397) (xy 100.480627 -367.920234) (xy 100.509389 -367.926131) (xy 100.524056 -367.92535)
			(xy 100.555552 -367.92408) (xy 100.582809 -367.924504) (xy 100.63677 -367.932255) (xy 100.689078 -367.947608)
			(xy 100.738668 -367.970248) (xy 100.784532 -367.999716) (xy 100.825735 -368.035411) (xy 100.861438 -368.076607)
			(xy 100.890915 -368.122465) (xy 100.913566 -368.172051) (xy 100.928929 -368.224356) (xy 100.93464 -368.264054)
			(xy 103.243332 -368.264054) (xy 103.243332 -368.209546) (xy 103.251089 -368.155594) (xy 103.266445 -368.103294)
			(xy 103.289087 -368.053713) (xy 103.318555 -368.007858) (xy 103.354249 -367.966663) (xy 103.395442 -367.930967)
			(xy 103.441295 -367.901497) (xy 103.490876 -367.878852) (xy 103.543174 -367.863493) (xy 103.597126 -367.855733)
			(xy 103.62438 -367.855246) (xy 103.651658 -367.855674) (xy 103.705657 -367.863443) (xy 103.757999 -367.878824)
			(xy 103.807616 -367.901505) (xy 103.853496 -367.931023) (xy 103.894704 -367.966775) (xy 103.930398 -368.008032)
			(xy 103.959852 -368.053954) (xy 103.982463 -368.103603) (xy 103.997771 -368.155966) (xy 104.002078 -368.182906)
			(xy 104.004785 -368.197766) (xy 104.017581 -368.225105) (xy 104.037808 -368.247511) (xy 104.063699 -368.263029)
			(xy 104.092995 -368.270304) (xy 104.123138 -368.268701) (xy 104.151497 -368.25836) (xy 104.163876 -368.249708)
			(xy 104.188882 -368.23155) (xy 104.243532 -368.202707) (xy 104.302116 -368.183048) (xy 104.363103 -368.173089)
			(xy 104.394 -368.172492) (xy 104.421251 -368.172978) (xy 104.475199 -368.180734) (xy 104.527494 -368.196089)
			(xy 104.577071 -368.218731) (xy 104.622921 -368.248197) (xy 104.664112 -368.283888) (xy 104.699803 -368.325079)
			(xy 104.729269 -368.370929) (xy 104.751911 -368.420506) (xy 104.767266 -368.472801) (xy 104.775022 -368.526749)
			(xy 104.775022 -368.581251) (xy 104.767266 -368.635199) (xy 104.751911 -368.687494) (xy 104.729269 -368.737071)
			(xy 104.699803 -368.782921) (xy 104.664112 -368.824112) (xy 104.622921 -368.859803) (xy 104.577071 -368.889269)
			(xy 104.527494 -368.911911) (xy 104.475199 -368.927266) (xy 104.421251 -368.935022) (xy 104.394 -368.935508)
			(xy 104.366724 -368.935053) (xy 104.312728 -368.927283) (xy 104.260389 -368.911901) (xy 104.210775 -368.889222)
			(xy 104.164896 -368.859707) (xy 104.12369 -368.823958) (xy 104.087995 -368.782705) (xy 104.05854 -368.736788)
			(xy 104.035925 -368.687144) (xy 104.020612 -368.634786) (xy 104.016302 -368.607848) (xy 104.013597 -368.592985)
			(xy 104.000809 -368.565637) (xy 103.980584 -368.543223) (xy 103.95469 -368.5277) (xy 103.925389 -368.520426)
			(xy 103.895241 -368.522035) (xy 103.866881 -368.532388) (xy 103.854504 -368.541046) (xy 103.829509 -368.55922)
			(xy 103.774855 -368.588058) (xy 103.716267 -368.607711) (xy 103.655278 -368.617667) (xy 103.62438 -368.618262)
			(xy 103.597126 -368.617867) (xy 103.543174 -368.610107) (xy 103.490876 -368.594748) (xy 103.441295 -368.572103)
			(xy 103.395442 -368.542633) (xy 103.354249 -368.506937) (xy 103.318555 -368.465742) (xy 103.289087 -368.419887)
			(xy 103.266445 -368.370306) (xy 103.251089 -368.318006) (xy 103.243332 -368.264054) (xy 100.93464 -368.264054)
			(xy 100.936691 -368.278315) (xy 100.936695 -368.332829) (xy 100.92894 -368.386789) (xy 100.913585 -368.439097)
			(xy 100.890942 -368.488686) (xy 100.861472 -368.534548) (xy 100.825775 -368.575749) (xy 100.784577 -368.61145)
			(xy 100.738718 -368.640925) (xy 100.68913 -368.663573) (xy 100.636825 -368.678933) (xy 100.582865 -368.686692)
			(xy 100.528351 -368.686694) (xy 100.474391 -368.678936) (xy 100.422085 -368.663578) (xy 100.372496 -368.640933)
			(xy 100.326636 -368.61146) (xy 100.285437 -368.57576) (xy 100.249738 -368.534561) (xy 100.220266 -368.4887)
			(xy 100.19762 -368.439112) (xy 100.182263 -368.386805) (xy 100.174506 -368.332845) (xy 100.174044 -368.305588)
			(xy 100.174792 -368.271161) (xy 100.187196 -368.203431) (xy 100.198682 -368.170968) (xy 100.203407 -368.157064)
			(xy 100.205595 -368.127796) (xy 100.199362 -368.099115) (xy 100.185224 -368.073394) (xy 100.164349 -368.052762)
			(xy 100.138465 -368.038925) (xy 100.109713 -368.033028) (xy 100.09505 -368.033808) (xy 100.063554 -368.035078)
			(xy 100.036307 -368.034573) (xy 99.982369 -368.026811) (xy 99.930085 -368.011453) (xy 99.880518 -367.98881)
			(xy 99.834678 -367.959345) (xy 99.793498 -367.923655) (xy 99.757815 -367.882469) (xy 99.728358 -367.836623)
			(xy 99.705724 -367.787053) (xy 99.690375 -367.734766) (xy 99.682623 -367.680826) (xy 58.103008 -367.680826)
			(xy 58.103008 -368.516662) (xy 58.102522 -368.543931) (xy 58.09476 -368.597915) (xy 58.079395 -368.650245)
			(xy 58.056738 -368.699855) (xy 58.027252 -368.745736) (xy 57.991537 -368.786953) (xy 57.95032 -368.822668)
			(xy 57.904439 -368.852154) (xy 57.854829 -368.874811) (xy 57.802499 -368.890176) (xy 57.748515 -368.897938)
			(xy 57.693977 -368.897938) (xy 57.639993 -368.890176) (xy 57.587663 -368.874811) (xy 57.538053 -368.852154)
			(xy 57.492172 -368.822668) (xy 57.450955 -368.786953) (xy 57.41524 -368.745736) (xy 57.385754 -368.699855)
			(xy 57.363097 -368.650245) (xy 57.347732 -368.597915) (xy 57.33997 -368.543931) (xy 57.339484 -368.516662)
			(xy 54.729888 -368.516662) (xy 54.729402 -368.543931) (xy 54.72164 -368.597915) (xy 54.706275 -368.650245)
			(xy 54.683618 -368.699855) (xy 54.654132 -368.745736) (xy 54.618417 -368.786953) (xy 54.5772 -368.822668)
			(xy 54.531319 -368.852154) (xy 54.481709 -368.874811) (xy 54.429379 -368.890176) (xy 54.375395 -368.897938)
			(xy 54.320857 -368.897938) (xy 54.266873 -368.890176) (xy 54.214543 -368.874811) (xy 54.164933 -368.852154)
			(xy 54.119052 -368.822668) (xy 54.077835 -368.786953) (xy 54.04212 -368.745736) (xy 54.012634 -368.699855)
			(xy 53.989977 -368.650245) (xy 53.974612 -368.597915) (xy 53.96685 -368.543931) (xy 53.966364 -368.516662)
			(xy 51.556158 -368.516662) (xy 51.556158 -368.990118) (xy 73.623686 -368.990118) (xy 73.627677 -368.927951)
			(xy 73.639586 -368.866804) (xy 73.659215 -368.807683) (xy 73.686244 -368.751557) (xy 73.720228 -368.699348)
			(xy 73.76061 -368.651913) (xy 73.806726 -368.610032) (xy 73.857818 -368.574392) (xy 73.913049 -368.545578)
			(xy 73.971511 -368.524064) (xy 74.032245 -368.510202) (xy 74.094252 -368.50422) (xy 74.156515 -368.506216)
			(xy 74.218012 -368.516159) (xy 74.277733 -368.533883) (xy 74.334696 -368.5591) (xy 74.387967 -368.591393)
			(xy 74.436672 -368.630233) (xy 74.480009 -368.674983) (xy 74.517269 -368.724907) (xy 74.547838 -368.779186)
			(xy 74.571216 -368.836929) (xy 74.587017 -368.897187) (xy 74.594983 -368.95897) (xy 74.595482 -368.990118)
			(xy 78.023728 -368.990118) (xy 78.027719 -368.927951) (xy 78.039628 -368.866804) (xy 78.059257 -368.807683)
			(xy 78.086286 -368.751557) (xy 78.12027 -368.699348) (xy 78.160652 -368.651913) (xy 78.206768 -368.610032)
			(xy 78.25786 -368.574392) (xy 78.313091 -368.545578) (xy 78.371553 -368.524064) (xy 78.432287 -368.510202)
			(xy 78.494294 -368.50422) (xy 78.556557 -368.506216) (xy 78.618054 -368.516159) (xy 78.677775 -368.533883)
			(xy 78.734738 -368.5591) (xy 78.788009 -368.591393) (xy 78.836714 -368.630233) (xy 78.880051 -368.674983)
			(xy 78.917311 -368.724907) (xy 78.94788 -368.779186) (xy 78.971258 -368.836929) (xy 78.987059 -368.897187)
			(xy 78.995025 -368.95897) (xy 78.995524 -368.990118) (xy 82.42377 -368.990118) (xy 82.427761 -368.927951)
			(xy 82.43967 -368.866804) (xy 82.459299 -368.807683) (xy 82.486328 -368.751557) (xy 82.520312 -368.699348)
			(xy 82.560694 -368.651913) (xy 82.60681 -368.610032) (xy 82.657902 -368.574392) (xy 82.713133 -368.545578)
			(xy 82.771595 -368.524064) (xy 82.832329 -368.510202) (xy 82.894336 -368.50422) (xy 82.956599 -368.506216)
			(xy 83.018096 -368.516159) (xy 83.077817 -368.533883) (xy 83.13478 -368.5591) (xy 83.188051 -368.591393)
			(xy 83.236756 -368.630233) (xy 83.280093 -368.674983) (xy 83.317353 -368.724907) (xy 83.347922 -368.779186)
			(xy 83.3713 -368.836929) (xy 83.387101 -368.897187) (xy 83.395067 -368.95897) (xy 83.395566 -368.990118)
			(xy 86.823812 -368.990118) (xy 86.827803 -368.927951) (xy 86.839712 -368.866804) (xy 86.859341 -368.807683)
			(xy 86.88637 -368.751557) (xy 86.920354 -368.699348) (xy 86.960736 -368.651913) (xy 87.006852 -368.610032)
			(xy 87.057944 -368.574392) (xy 87.113175 -368.545578) (xy 87.171637 -368.524064) (xy 87.232371 -368.510202)
			(xy 87.294378 -368.50422) (xy 87.356641 -368.506216) (xy 87.418138 -368.516159) (xy 87.477859 -368.533883)
			(xy 87.534822 -368.5591) (xy 87.588093 -368.591393) (xy 87.636798 -368.630233) (xy 87.680135 -368.674983)
			(xy 87.717395 -368.724907) (xy 87.747964 -368.779186) (xy 87.771342 -368.836929) (xy 87.787143 -368.897187)
			(xy 87.795109 -368.95897) (xy 87.795608 -368.990118) (xy 91.223854 -368.990118) (xy 91.227845 -368.927951)
			(xy 91.239754 -368.866804) (xy 91.259383 -368.807683) (xy 91.286412 -368.751557) (xy 91.320396 -368.699348)
			(xy 91.360778 -368.651913) (xy 91.406894 -368.610032) (xy 91.457986 -368.574392) (xy 91.513217 -368.545578)
			(xy 91.571679 -368.524064) (xy 91.632413 -368.510202) (xy 91.69442 -368.50422) (xy 91.756683 -368.506216)
			(xy 91.81818 -368.516159) (xy 91.877901 -368.533883) (xy 91.934864 -368.5591) (xy 91.988135 -368.591393)
			(xy 92.03684 -368.630233) (xy 92.080177 -368.674983) (xy 92.117437 -368.724907) (xy 92.148006 -368.779186)
			(xy 92.171384 -368.836929) (xy 92.187185 -368.897187) (xy 92.19206 -368.935) (xy 102.360982 -368.935)
			(xy 102.365053 -368.879378) (xy 102.377179 -368.824941) (xy 102.397102 -368.77285) (xy 102.424398 -368.724215)
			(xy 102.458484 -368.680072) (xy 102.498633 -368.641363) (xy 102.543991 -368.608912) (xy 102.593591 -368.583411)
			(xy 102.646375 -368.565404) (xy 102.701218 -368.555274) (xy 102.756952 -368.553237) (xy 102.812389 -368.559337)
			(xy 102.866346 -368.573443) (xy 102.917675 -368.595255) (xy 102.965281 -368.624309) (xy 103.008149 -368.659984)
			(xy 103.045366 -368.701521) (xy 103.076139 -368.748034) (xy 103.099811 -368.798531) (xy 103.115879 -368.851938)
			(xy 103.123999 -368.907114) (xy 103.124508 -368.935) (xy 103.123999 -368.962886) (xy 103.119991 -368.990118)
			(xy 117.623852 -368.990118) (xy 117.627843 -368.927951) (xy 117.639752 -368.866804) (xy 117.659381 -368.807683)
			(xy 117.68641 -368.751557) (xy 117.720394 -368.699348) (xy 117.760776 -368.651913) (xy 117.806892 -368.610032)
			(xy 117.857984 -368.574392) (xy 117.913215 -368.545578) (xy 117.971677 -368.524064) (xy 118.032411 -368.510202)
			(xy 118.094418 -368.50422) (xy 118.156681 -368.506216) (xy 118.218178 -368.516159) (xy 118.277899 -368.533883)
			(xy 118.334862 -368.5591) (xy 118.388133 -368.591393) (xy 118.436838 -368.630233) (xy 118.480175 -368.674983)
			(xy 118.517435 -368.724907) (xy 118.548004 -368.779186) (xy 118.571382 -368.836929) (xy 118.587183 -368.897187)
			(xy 118.595149 -368.95897) (xy 118.595648 -368.990118) (xy 122.023894 -368.990118) (xy 122.027885 -368.927951)
			(xy 122.039794 -368.866804) (xy 122.059423 -368.807683) (xy 122.086452 -368.751557) (xy 122.120436 -368.699348)
			(xy 122.160818 -368.651913) (xy 122.206934 -368.610032) (xy 122.258026 -368.574392) (xy 122.313257 -368.545578)
			(xy 122.371719 -368.524064) (xy 122.432453 -368.510202) (xy 122.49446 -368.50422) (xy 122.556723 -368.506216)
			(xy 122.61822 -368.516159) (xy 122.677941 -368.533883) (xy 122.734904 -368.5591) (xy 122.788175 -368.591393)
			(xy 122.83688 -368.630233) (xy 122.880217 -368.674983) (xy 122.917477 -368.724907) (xy 122.948046 -368.779186)
			(xy 122.971424 -368.836929) (xy 122.987225 -368.897187) (xy 122.995191 -368.95897) (xy 122.99569 -368.990118)
			(xy 126.423936 -368.990118) (xy 126.427927 -368.927951) (xy 126.439836 -368.866804) (xy 126.459465 -368.807683)
			(xy 126.486494 -368.751557) (xy 126.520478 -368.699348) (xy 126.56086 -368.651913) (xy 126.606976 -368.610032)
			(xy 126.658068 -368.574392) (xy 126.713299 -368.545578) (xy 126.771761 -368.524064) (xy 126.832495 -368.510202)
			(xy 126.894502 -368.50422) (xy 126.956765 -368.506216) (xy 127.018262 -368.516159) (xy 127.077983 -368.533883)
			(xy 127.134946 -368.5591) (xy 127.188217 -368.591393) (xy 127.236922 -368.630233) (xy 127.280259 -368.674983)
			(xy 127.317519 -368.724907) (xy 127.348088 -368.779186) (xy 127.371466 -368.836929) (xy 127.387267 -368.897187)
			(xy 127.395233 -368.95897) (xy 127.395732 -368.990118) (xy 130.823978 -368.990118) (xy 130.827969 -368.927951)
			(xy 130.839878 -368.866804) (xy 130.859507 -368.807683) (xy 130.886536 -368.751557) (xy 130.92052 -368.699348)
			(xy 130.960902 -368.651913) (xy 131.007018 -368.610032) (xy 131.05811 -368.574392) (xy 131.113341 -368.545578)
			(xy 131.171803 -368.524064) (xy 131.232537 -368.510202) (xy 131.294544 -368.50422) (xy 131.356807 -368.506216)
			(xy 131.418304 -368.516159) (xy 131.478025 -368.533883) (xy 131.534988 -368.5591) (xy 131.588259 -368.591393)
			(xy 131.636964 -368.630233) (xy 131.680301 -368.674983) (xy 131.717561 -368.724907) (xy 131.74813 -368.779186)
			(xy 131.771508 -368.836929) (xy 131.787309 -368.897187) (xy 131.795275 -368.95897) (xy 131.795774 -368.990118)
			(xy 135.22402 -368.990118) (xy 135.228011 -368.927951) (xy 135.23992 -368.866804) (xy 135.259549 -368.807683)
			(xy 135.286578 -368.751557) (xy 135.320562 -368.699348) (xy 135.360944 -368.651913) (xy 135.40706 -368.610032)
			(xy 135.458152 -368.574392) (xy 135.513383 -368.545578) (xy 135.571845 -368.524064) (xy 135.632579 -368.510202)
			(xy 135.694586 -368.50422) (xy 135.756849 -368.506216) (xy 135.818346 -368.516159) (xy 135.878067 -368.533883)
			(xy 135.93503 -368.5591) (xy 135.988301 -368.591393) (xy 136.037006 -368.630233) (xy 136.080343 -368.674983)
			(xy 136.117603 -368.724907) (xy 136.148172 -368.779186) (xy 136.17155 -368.836929) (xy 136.187351 -368.897187)
			(xy 136.195317 -368.95897) (xy 136.195816 -368.990118) (xy 136.195317 -369.021266) (xy 136.187351 -369.083049)
			(xy 136.17155 -369.143307) (xy 136.148172 -369.20105) (xy 136.117603 -369.255329) (xy 136.080343 -369.305253)
			(xy 136.037006 -369.350003) (xy 135.988301 -369.388843) (xy 135.93503 -369.421136) (xy 135.878067 -369.446353)
			(xy 135.818346 -369.464077) (xy 135.756849 -369.47402) (xy 135.694586 -369.476016) (xy 135.632579 -369.470034)
			(xy 135.571845 -369.456172) (xy 135.513383 -369.434658) (xy 135.458152 -369.405844) (xy 135.40706 -369.370204)
			(xy 135.360944 -369.328323) (xy 135.320562 -369.280888) (xy 135.286578 -369.228679) (xy 135.259549 -369.172553)
			(xy 135.23992 -369.113432) (xy 135.228011 -369.052285) (xy 135.22402 -368.990118) (xy 131.795774 -368.990118)
			(xy 131.795275 -369.021266) (xy 131.787309 -369.083049) (xy 131.771508 -369.143307) (xy 131.74813 -369.20105)
			(xy 131.717561 -369.255329) (xy 131.680301 -369.305253) (xy 131.636964 -369.350003) (xy 131.588259 -369.388843)
			(xy 131.534988 -369.421136) (xy 131.478025 -369.446353) (xy 131.418304 -369.464077) (xy 131.356807 -369.47402)
			(xy 131.294544 -369.476016) (xy 131.232537 -369.470034) (xy 131.171803 -369.456172) (xy 131.113341 -369.434658)
			(xy 131.05811 -369.405844) (xy 131.007018 -369.370204) (xy 130.960902 -369.328323) (xy 130.92052 -369.280888)
			(xy 130.886536 -369.228679) (xy 130.859507 -369.172553) (xy 130.839878 -369.113432) (xy 130.827969 -369.052285)
			(xy 130.823978 -368.990118) (xy 127.395732 -368.990118) (xy 127.395233 -369.021266) (xy 127.387267 -369.083049)
			(xy 127.371466 -369.143307) (xy 127.348088 -369.20105) (xy 127.317519 -369.255329) (xy 127.280259 -369.305253)
			(xy 127.236922 -369.350003) (xy 127.188217 -369.388843) (xy 127.134946 -369.421136) (xy 127.077983 -369.446353)
			(xy 127.018262 -369.464077) (xy 126.956765 -369.47402) (xy 126.894502 -369.476016) (xy 126.832495 -369.470034)
			(xy 126.771761 -369.456172) (xy 126.713299 -369.434658) (xy 126.658068 -369.405844) (xy 126.606976 -369.370204)
			(xy 126.56086 -369.328323) (xy 126.520478 -369.280888) (xy 126.486494 -369.228679) (xy 126.459465 -369.172553)
			(xy 126.439836 -369.113432) (xy 126.427927 -369.052285) (xy 126.423936 -368.990118) (xy 122.99569 -368.990118)
			(xy 122.995191 -369.021266) (xy 122.987225 -369.083049) (xy 122.971424 -369.143307) (xy 122.948046 -369.20105)
			(xy 122.917477 -369.255329) (xy 122.880217 -369.305253) (xy 122.83688 -369.350003) (xy 122.788175 -369.388843)
			(xy 122.734904 -369.421136) (xy 122.677941 -369.446353) (xy 122.61822 -369.464077) (xy 122.556723 -369.47402)
			(xy 122.49446 -369.476016) (xy 122.432453 -369.470034) (xy 122.371719 -369.456172) (xy 122.313257 -369.434658)
			(xy 122.258026 -369.405844) (xy 122.206934 -369.370204) (xy 122.160818 -369.328323) (xy 122.120436 -369.280888)
			(xy 122.086452 -369.228679) (xy 122.059423 -369.172553) (xy 122.039794 -369.113432) (xy 122.027885 -369.052285)
			(xy 122.023894 -368.990118) (xy 118.595648 -368.990118) (xy 118.595149 -369.021266) (xy 118.587183 -369.083049)
			(xy 118.571382 -369.143307) (xy 118.548004 -369.20105) (xy 118.517435 -369.255329) (xy 118.480175 -369.305253)
			(xy 118.436838 -369.350003) (xy 118.388133 -369.388843) (xy 118.334862 -369.421136) (xy 118.277899 -369.446353)
			(xy 118.218178 -369.464077) (xy 118.156681 -369.47402) (xy 118.094418 -369.476016) (xy 118.032411 -369.470034)
			(xy 117.971677 -369.456172) (xy 117.913215 -369.434658) (xy 117.857984 -369.405844) (xy 117.806892 -369.370204)
			(xy 117.760776 -369.328323) (xy 117.720394 -369.280888) (xy 117.68641 -369.228679) (xy 117.659381 -369.172553)
			(xy 117.639752 -369.113432) (xy 117.627843 -369.052285) (xy 117.623852 -368.990118) (xy 103.119991 -368.990118)
			(xy 103.115879 -369.018062) (xy 103.099811 -369.071469) (xy 103.076139 -369.121966) (xy 103.045366 -369.168479)
			(xy 103.008149 -369.210016) (xy 102.965281 -369.245691) (xy 102.917675 -369.274745) (xy 102.866346 -369.296557)
			(xy 102.812389 -369.310663) (xy 102.756952 -369.316763) (xy 102.701218 -369.314726) (xy 102.646375 -369.304596)
			(xy 102.593591 -369.286589) (xy 102.543991 -369.261088) (xy 102.498633 -369.228637) (xy 102.458484 -369.189928)
			(xy 102.424398 -369.145785) (xy 102.397102 -369.09715) (xy 102.377179 -369.045059) (xy 102.365053 -368.990622)
			(xy 102.360982 -368.935) (xy 92.19206 -368.935) (xy 92.195151 -368.95897) (xy 92.19565 -368.990118)
			(xy 92.195151 -369.021266) (xy 92.187185 -369.083049) (xy 92.171384 -369.143307) (xy 92.148006 -369.20105)
			(xy 92.117437 -369.255329) (xy 92.080177 -369.305253) (xy 92.03684 -369.350003) (xy 91.988135 -369.388843)
			(xy 91.934864 -369.421136) (xy 91.877901 -369.446353) (xy 91.81818 -369.464077) (xy 91.756683 -369.47402)
			(xy 91.69442 -369.476016) (xy 91.632413 -369.470034) (xy 91.571679 -369.456172) (xy 91.513217 -369.434658)
			(xy 91.457986 -369.405844) (xy 91.406894 -369.370204) (xy 91.360778 -369.328323) (xy 91.320396 -369.280888)
			(xy 91.286412 -369.228679) (xy 91.259383 -369.172553) (xy 91.239754 -369.113432) (xy 91.227845 -369.052285)
			(xy 91.223854 -368.990118) (xy 87.795608 -368.990118) (xy 87.795109 -369.021266) (xy 87.787143 -369.083049)
			(xy 87.771342 -369.143307) (xy 87.747964 -369.20105) (xy 87.717395 -369.255329) (xy 87.680135 -369.305253)
			(xy 87.636798 -369.350003) (xy 87.588093 -369.388843) (xy 87.534822 -369.421136) (xy 87.477859 -369.446353)
			(xy 87.418138 -369.464077) (xy 87.356641 -369.47402) (xy 87.294378 -369.476016) (xy 87.232371 -369.470034)
			(xy 87.171637 -369.456172) (xy 87.113175 -369.434658) (xy 87.057944 -369.405844) (xy 87.006852 -369.370204)
			(xy 86.960736 -369.328323) (xy 86.920354 -369.280888) (xy 86.88637 -369.228679) (xy 86.859341 -369.172553)
			(xy 86.839712 -369.113432) (xy 86.827803 -369.052285) (xy 86.823812 -368.990118) (xy 83.395566 -368.990118)
			(xy 83.395067 -369.021266) (xy 83.387101 -369.083049) (xy 83.3713 -369.143307) (xy 83.347922 -369.20105)
			(xy 83.317353 -369.255329) (xy 83.280093 -369.305253) (xy 83.236756 -369.350003) (xy 83.188051 -369.388843)
			(xy 83.13478 -369.421136) (xy 83.077817 -369.446353) (xy 83.018096 -369.464077) (xy 82.956599 -369.47402)
			(xy 82.894336 -369.476016) (xy 82.832329 -369.470034) (xy 82.771595 -369.456172) (xy 82.713133 -369.434658)
			(xy 82.657902 -369.405844) (xy 82.60681 -369.370204) (xy 82.560694 -369.328323) (xy 82.520312 -369.280888)
			(xy 82.486328 -369.228679) (xy 82.459299 -369.172553) (xy 82.43967 -369.113432) (xy 82.427761 -369.052285)
			(xy 82.42377 -368.990118) (xy 78.995524 -368.990118) (xy 78.995025 -369.021266) (xy 78.987059 -369.083049)
			(xy 78.971258 -369.143307) (xy 78.94788 -369.20105) (xy 78.917311 -369.255329) (xy 78.880051 -369.305253)
			(xy 78.836714 -369.350003) (xy 78.788009 -369.388843) (xy 78.734738 -369.421136) (xy 78.677775 -369.446353)
			(xy 78.618054 -369.464077) (xy 78.556557 -369.47402) (xy 78.494294 -369.476016) (xy 78.432287 -369.470034)
			(xy 78.371553 -369.456172) (xy 78.313091 -369.434658) (xy 78.25786 -369.405844) (xy 78.206768 -369.370204)
			(xy 78.160652 -369.328323) (xy 78.12027 -369.280888) (xy 78.086286 -369.228679) (xy 78.059257 -369.172553)
			(xy 78.039628 -369.113432) (xy 78.027719 -369.052285) (xy 78.023728 -368.990118) (xy 74.595482 -368.990118)
			(xy 74.594983 -369.021266) (xy 74.587017 -369.083049) (xy 74.571216 -369.143307) (xy 74.547838 -369.20105)
			(xy 74.517269 -369.255329) (xy 74.480009 -369.305253) (xy 74.436672 -369.350003) (xy 74.387967 -369.388843)
			(xy 74.334696 -369.421136) (xy 74.277733 -369.446353) (xy 74.218012 -369.464077) (xy 74.156515 -369.47402)
			(xy 74.094252 -369.476016) (xy 74.032245 -369.470034) (xy 73.971511 -369.456172) (xy 73.913049 -369.434658)
			(xy 73.857818 -369.405844) (xy 73.806726 -369.370204) (xy 73.76061 -369.328323) (xy 73.720228 -369.280888)
			(xy 73.686244 -369.228679) (xy 73.659215 -369.172553) (xy 73.639586 -369.113432) (xy 73.627677 -369.052285)
			(xy 73.623686 -368.990118) (xy 51.556158 -368.990118) (xy 51.556158 -371.310662) (xy 53.966364 -371.310662)
			(xy 53.966364 -370.447062) (xy 53.96685 -370.419793) (xy 53.974612 -370.365809) (xy 53.989977 -370.313479)
			(xy 54.012634 -370.263869) (xy 54.04212 -370.217988) (xy 54.077835 -370.176771) (xy 54.119052 -370.141056)
			(xy 54.164933 -370.11157) (xy 54.214543 -370.088913) (xy 54.266873 -370.073548) (xy 54.320857 -370.065786)
			(xy 54.375395 -370.065786) (xy 54.429379 -370.073548) (xy 54.481709 -370.088913) (xy 54.531319 -370.11157)
			(xy 54.5772 -370.141056) (xy 54.618417 -370.176771) (xy 54.654132 -370.217988) (xy 54.683618 -370.263869)
			(xy 54.706275 -370.313479) (xy 54.72164 -370.365809) (xy 54.729402 -370.419793) (xy 54.729888 -370.447062)
			(xy 54.729888 -371.310662) (xy 57.339484 -371.310662) (xy 57.339484 -370.447062) (xy 57.33997 -370.419793)
			(xy 57.347732 -370.365809) (xy 57.363097 -370.313479) (xy 57.385754 -370.263869) (xy 57.41524 -370.217988)
			(xy 57.450955 -370.176771) (xy 57.492172 -370.141056) (xy 57.538053 -370.11157) (xy 57.587663 -370.088913)
			(xy 57.639993 -370.073548) (xy 57.693977 -370.065786) (xy 57.748515 -370.065786) (xy 57.802499 -370.073548)
			(xy 57.854829 -370.088913) (xy 57.904439 -370.11157) (xy 57.95032 -370.141056) (xy 57.991537 -370.176771)
			(xy 58.027252 -370.217988) (xy 58.056738 -370.263869) (xy 58.079395 -370.313479) (xy 58.09476 -370.365809)
			(xy 58.102522 -370.419793) (xy 58.103008 -370.447062) (xy 58.103008 -370.522712) (xy 71.42482 -370.522712)
			(xy 71.424822 -370.457268) (xy 71.433616 -370.392418) (xy 71.451043 -370.329337) (xy 71.476788 -370.26917)
			(xy 71.493126 -370.240814) (xy 71.496483 -370.234795) (xy 71.500223 -370.221538) (xy 71.500492 -370.214652)
			(xy 71.500492 -369.928902) (xy 71.501027 -369.918781) (xy 71.508745 -369.900069) (xy 71.523016 -369.885715)
			(xy 71.541682 -369.877887) (xy 71.5518 -369.87734) (xy 72.26808 -369.87734) (xy 72.278238 -369.877739)
			(xy 72.296998 -369.885535) (xy 72.311323 -369.89994) (xy 72.319016 -369.918742) (xy 72.319388 -369.928902)
			(xy 72.319388 -370.214652) (xy 72.319606 -370.221546) (xy 72.323344 -370.234818) (xy 72.326754 -370.240814)
			(xy 72.343081 -370.269176) (xy 72.368827 -370.329341) (xy 72.386254 -370.39242) (xy 72.395049 -370.457269)
			(xy 72.39505 -370.522711) (xy 72.39505 -370.522712) (xy 75.824856 -370.522712) (xy 75.824858 -370.457268)
			(xy 75.833653 -370.392417) (xy 75.851082 -370.329337) (xy 75.876829 -370.26917) (xy 75.893168 -370.240814)
			(xy 75.896475 -370.234786) (xy 75.900086 -370.221525) (xy 75.90028 -370.214652) (xy 75.90028 -369.928902)
			(xy 75.900666 -369.918725) (xy 75.908459 -369.899923) (xy 75.922856 -369.885536) (xy 75.941665 -369.877759)
			(xy 75.951842 -369.87734) (xy 76.668122 -369.87734) (xy 76.678281 -369.877815) (xy 76.697052 -369.885597)
			(xy 76.711416 -369.899969) (xy 76.71919 -369.918742) (xy 76.719684 -369.928902) (xy 76.719684 -370.214652)
			(xy 76.719897 -370.221524) (xy 76.723491 -370.234786) (xy 76.726796 -370.240814) (xy 76.743122 -370.269176)
			(xy 76.768865 -370.329342) (xy 76.786291 -370.392421) (xy 76.795085 -370.457269) (xy 76.795086 -370.522711)
			(xy 80.224907 -370.522711) (xy 80.224908 -370.457268) (xy 80.233702 -370.392418) (xy 80.251129 -370.329338)
			(xy 80.276873 -370.26917) (xy 80.29321 -370.240814) (xy 80.296566 -370.234795) (xy 80.300307 -370.221538)
			(xy 80.300576 -370.214652) (xy 80.300576 -369.928902) (xy 80.301029 -369.918771) (xy 80.308763 -369.900043)
			(xy 80.32306 -369.885685) (xy 80.341755 -369.877873) (xy 80.351884 -369.87734) (xy 81.068164 -369.87734)
			(xy 81.078321 -369.877752) (xy 81.09708 -369.885543) (xy 81.111406 -369.899944) (xy 81.1191 -369.918743)
			(xy 81.119472 -369.928902) (xy 81.119472 -370.214652) (xy 81.119692 -370.221546) (xy 81.123429 -370.234818)
			(xy 81.126838 -370.240814) (xy 81.143166 -370.269176) (xy 81.168912 -370.329341) (xy 81.18634 -370.39242)
			(xy 81.195135 -370.457269) (xy 81.195136 -370.522711) (xy 84.624696 -370.522711) (xy 84.624698 -370.457268)
			(xy 84.633491 -370.392418) (xy 84.650918 -370.329338) (xy 84.676661 -370.269171) (xy 84.692998 -370.240814)
			(xy 84.696353 -370.234794) (xy 84.700095 -370.221538) (xy 84.700364 -370.214652) (xy 84.700364 -369.928902)
			(xy 84.700829 -369.918772) (xy 84.708561 -369.900047) (xy 84.722854 -369.88569) (xy 84.741545 -369.877875)
			(xy 84.751672 -369.87734) (xy 85.467952 -369.87734) (xy 85.478108 -369.877762) (xy 85.496867 -369.885549)
			(xy 85.511194 -369.899947) (xy 85.518888 -369.918744) (xy 85.51926 -369.928902) (xy 85.51926 -370.214652)
			(xy 85.519482 -370.221546) (xy 85.523218 -370.234818) (xy 85.526626 -370.240814) (xy 85.542954 -370.269175)
			(xy 85.568701 -370.32934) (xy 85.58613 -370.39242) (xy 85.594925 -370.457268) (xy 85.594925 -370.489988)
			(xy 89.023706 -370.489988) (xy 89.027697 -370.427821) (xy 89.039606 -370.366674) (xy 89.059235 -370.307553)
			(xy 89.086264 -370.251427) (xy 89.120248 -370.199218) (xy 89.16063 -370.151783) (xy 89.206746 -370.109902)
			(xy 89.257838 -370.074262) (xy 89.313069 -370.045448) (xy 89.371531 -370.023934) (xy 89.432265 -370.010072)
			(xy 89.494272 -370.00409) (xy 89.556535 -370.006086) (xy 89.618032 -370.016029) (xy 89.677753 -370.033753)
			(xy 89.734716 -370.05897) (xy 89.787987 -370.091263) (xy 89.836692 -370.130103) (xy 89.880029 -370.174853)
			(xy 89.917289 -370.224777) (xy 89.947858 -370.279056) (xy 89.971236 -370.336799) (xy 89.987037 -370.397057)
			(xy 89.995003 -370.45884) (xy 89.995502 -370.489988) (xy 89.995003 -370.521136) (xy 89.987037 -370.582919)
			(xy 89.971236 -370.643177) (xy 89.947858 -370.70092) (xy 89.917289 -370.755199) (xy 89.880029 -370.805123)
			(xy 89.836692 -370.849873) (xy 89.787987 -370.888713) (xy 89.734716 -370.921006) (xy 89.677753 -370.946223)
			(xy 89.618032 -370.963947) (xy 89.599149 -370.967) (xy 104.011992 -370.967) (xy 104.015722 -370.913749)
			(xy 104.026838 -370.861537) (xy 104.045124 -370.811385) (xy 104.070223 -370.764271) (xy 104.101645 -370.721117)
			(xy 104.138775 -370.682763) (xy 104.159558 -370.66601) (xy 104.168321 -370.658449) (xy 104.178501 -370.637689)
			(xy 104.179116 -370.626132) (xy 104.179116 -370.545868) (xy 104.178501 -370.534306) (xy 104.168337 -370.513535)
			(xy 104.159558 -370.50599) (xy 104.138775 -370.489237) (xy 104.101645 -370.450883) (xy 104.070223 -370.407729)
			(xy 104.045124 -370.360615) (xy 104.026838 -370.310463) (xy 104.015722 -370.258251) (xy 104.011992 -370.205)
			(xy 104.015722 -370.151749) (xy 104.026838 -370.099537) (xy 104.045124 -370.049385) (xy 104.070223 -370.002271)
			(xy 104.101645 -369.959117) (xy 104.138775 -369.920763) (xy 104.159558 -369.90401) (xy 104.168321 -369.896449)
			(xy 104.178501 -369.875689) (xy 104.179116 -369.864132) (xy 104.179116 -369.783868) (xy 104.178501 -369.772306)
			(xy 104.168337 -369.751535) (xy 104.159558 -369.74399) (xy 104.137061 -369.725815) (xy 104.097329 -369.683791)
			(xy 104.064392 -369.636252) (xy 104.039007 -369.584288) (xy 104.021753 -369.529088) (xy 104.013026 -369.471917)
			(xy 104.012492 -369.443) (xy 104.012978 -369.415749) (xy 104.020734 -369.361801) (xy 104.036089 -369.309506)
			(xy 104.058731 -369.259929) (xy 104.088197 -369.214079) (xy 104.123888 -369.172888) (xy 104.165079 -369.137197)
			(xy 104.210929 -369.107731) (xy 104.260506 -369.085089) (xy 104.312801 -369.069734) (xy 104.366749 -369.061978)
			(xy 104.421251 -369.061978) (xy 104.475199 -369.069734) (xy 104.527494 -369.085089) (xy 104.577071 -369.107731)
			(xy 104.622921 -369.137197) (xy 104.664112 -369.172888) (xy 104.699803 -369.214079) (xy 104.729269 -369.259929)
			(xy 104.751911 -369.309506) (xy 104.767266 -369.361801) (xy 104.775022 -369.415749) (xy 104.775508 -369.443)
			(xy 104.775025 -369.471919) (xy 104.766293 -369.529093) (xy 104.749031 -369.584294) (xy 104.723633 -369.636256)
			(xy 104.690681 -369.683789) (xy 104.650932 -369.725803) (xy 104.628442 -369.74399) (xy 104.619679 -369.751551)
			(xy 104.609499 -369.772311) (xy 104.608884 -369.783868) (xy 104.608884 -369.864132) (xy 104.609499 -369.875694)
			(xy 104.619663 -369.896465) (xy 104.628442 -369.90401) (xy 104.649225 -369.920763) (xy 104.686355 -369.959117)
			(xy 104.717777 -370.002271) (xy 104.742876 -370.049385) (xy 104.761162 -370.099537) (xy 104.772278 -370.151749)
			(xy 104.776008 -370.205) (xy 104.772278 -370.258251) (xy 104.761162 -370.310463) (xy 104.742876 -370.360615)
			(xy 104.717777 -370.407729) (xy 104.686355 -370.450883) (xy 104.649225 -370.489237) (xy 104.628442 -370.50599)
			(xy 104.619679 -370.513551) (xy 104.615187 -370.522712) (xy 115.424977 -370.522712) (xy 115.424979 -370.457267)
			(xy 115.433774 -370.392417) (xy 115.451204 -370.329336) (xy 115.476952 -370.26917) (xy 115.493292 -370.240814)
			(xy 115.496601 -370.234787) (xy 115.50021 -370.221525) (xy 115.500404 -370.214652) (xy 115.500404 -369.928902)
			(xy 115.500934 -369.918749) (xy 115.508702 -369.899986) (xy 115.523056 -369.885622) (xy 115.541813 -369.877841)
			(xy 115.551966 -369.87734) (xy 116.268246 -369.87734) (xy 116.278407 -369.877796) (xy 116.297177 -369.885586)
			(xy 116.311541 -369.899963) (xy 116.319314 -369.918741) (xy 116.319808 -369.928902) (xy 116.319808 -370.214652)
			(xy 116.320017 -370.221524) (xy 116.323614 -370.234787) (xy 116.32692 -370.240814) (xy 116.343248 -370.269175)
			(xy 116.368995 -370.32934) (xy 116.386425 -370.392419) (xy 116.39522 -370.457268) (xy 116.395221 -370.522711)
			(xy 116.395221 -370.522712) (xy 119.825027 -370.522712) (xy 119.825029 -370.457268) (xy 119.833823 -370.392418)
			(xy 119.851251 -370.329337) (xy 119.876996 -370.26917) (xy 119.893334 -370.240814) (xy 119.896692 -370.234796)
			(xy 119.900431 -370.221538) (xy 119.9007 -370.214652) (xy 119.9007 -369.928902) (xy 119.901227 -369.91878)
			(xy 119.908947 -369.900067) (xy 119.92322 -369.885712) (xy 119.941889 -369.877886) (xy 119.952008 -369.87734)
			(xy 120.668288 -369.87734) (xy 120.678446 -369.877732) (xy 120.697206 -369.885531) (xy 120.711531 -369.899938)
			(xy 120.719224 -369.918741) (xy 120.719596 -369.928902) (xy 120.719596 -370.214652) (xy 120.719848 -370.221542)
			(xy 120.723578 -370.234808) (xy 120.726962 -370.240814) (xy 120.743289 -370.269176) (xy 120.769034 -370.329341)
			(xy 120.786461 -370.39242) (xy 120.795256 -370.457269) (xy 120.795257 -370.522711) (xy 120.795257 -370.522712)
			(xy 124.225063 -370.522712) (xy 124.225065 -370.457268) (xy 124.23386 -370.392417) (xy 124.251289 -370.329336)
			(xy 124.277037 -370.26917) (xy 124.293376 -370.240814) (xy 124.296684 -370.234786) (xy 124.300294 -370.221525)
			(xy 124.300488 -370.214652) (xy 124.300488 -369.928902) (xy 124.300867 -369.918724) (xy 124.30866 -369.89992)
			(xy 124.32306 -369.885533) (xy 124.341872 -369.877757) (xy 124.35205 -369.87734) (xy 125.06833 -369.87734)
			(xy 125.07849 -369.877809) (xy 125.09726 -369.885593) (xy 125.111625 -369.899967) (xy 125.119398 -369.918742)
			(xy 125.119892 -369.928902) (xy 125.119892 -370.214652) (xy 125.120104 -370.221524) (xy 125.123699 -370.234786)
			(xy 125.127004 -370.240814) (xy 125.14333 -370.269176) (xy 125.169072 -370.329342) (xy 125.186498 -370.392421)
			(xy 125.195292 -370.457269) (xy 125.195293 -370.522711) (xy 125.195293 -370.522712) (xy 128.624853 -370.522712)
			(xy 128.624854 -370.457268) (xy 128.633649 -370.392417) (xy 128.651078 -370.329337) (xy 128.676825 -370.26917)
			(xy 128.693164 -370.240814) (xy 128.696471 -370.234785) (xy 128.700082 -370.221525) (xy 128.700276 -370.214652)
			(xy 128.700276 -369.928902) (xy 128.700666 -369.918726) (xy 128.708458 -369.899924) (xy 128.722854 -369.885538)
			(xy 128.741661 -369.877759) (xy 128.751838 -369.87734) (xy 129.468118 -369.87734) (xy 129.478277 -369.877818)
			(xy 129.497047 -369.885599) (xy 129.511412 -369.89997) (xy 129.519185 -369.918743) (xy 129.51968 -369.928902)
			(xy 129.51968 -370.214652) (xy 129.519893 -370.221524) (xy 129.523487 -370.234786) (xy 129.526792 -370.240814)
			(xy 129.543118 -370.269176) (xy 129.568861 -370.329342) (xy 129.586288 -370.392421) (xy 129.595081 -370.457269)
			(xy 129.595082 -370.489988) (xy 133.023872 -370.489988) (xy 133.027863 -370.427821) (xy 133.039772 -370.366674)
			(xy 133.059401 -370.307553) (xy 133.08643 -370.251427) (xy 133.120414 -370.199218) (xy 133.160796 -370.151783)
			(xy 133.206912 -370.109902) (xy 133.258004 -370.074262) (xy 133.313235 -370.045448) (xy 133.371697 -370.023934)
			(xy 133.432431 -370.010072) (xy 133.494438 -370.00409) (xy 133.556701 -370.006086) (xy 133.618198 -370.016029)
			(xy 133.677919 -370.033753) (xy 133.734882 -370.05897) (xy 133.788153 -370.091263) (xy 133.836858 -370.130103)
			(xy 133.880195 -370.174853) (xy 133.917455 -370.224777) (xy 133.948024 -370.279056) (xy 133.971402 -370.336799)
			(xy 133.987203 -370.397057) (xy 133.995169 -370.45884) (xy 133.995668 -370.489988) (xy 133.995169 -370.521136)
			(xy 133.987203 -370.582919) (xy 133.971402 -370.643177) (xy 133.948024 -370.70092) (xy 133.917455 -370.755199)
			(xy 133.880195 -370.805123) (xy 133.836858 -370.849873) (xy 133.788153 -370.888713) (xy 133.734882 -370.921006)
			(xy 133.677919 -370.946223) (xy 133.618198 -370.963947) (xy 133.556701 -370.97389) (xy 133.494438 -370.975886)
			(xy 133.432431 -370.969904) (xy 133.371697 -370.956042) (xy 133.313235 -370.934528) (xy 133.258004 -370.905714)
			(xy 133.206912 -370.870074) (xy 133.160796 -370.828193) (xy 133.120414 -370.780758) (xy 133.08643 -370.728549)
			(xy 133.059401 -370.672423) (xy 133.039772 -370.613302) (xy 133.027863 -370.552155) (xy 133.023872 -370.489988)
			(xy 129.595082 -370.489988) (xy 129.595083 -370.522711) (xy 129.586292 -370.587559) (xy 129.568868 -370.650639)
			(xy 129.543128 -370.710806) (xy 129.526792 -370.739162) (xy 129.52349 -370.745193) (xy 129.519877 -370.758452)
			(xy 129.51968 -370.765324) (xy 129.51968 -371.514878) (xy 129.519883 -371.52175) (xy 129.523484 -371.535013)
			(xy 129.526792 -371.54104) (xy 129.54314 -371.56939) (xy 129.565986 -371.62279) (xy 130.824993 -371.62279)
			(xy 130.824998 -371.557345) (xy 130.833795 -371.492494) (xy 130.851225 -371.429412) (xy 130.876973 -371.369245)
			(xy 130.893312 -371.340888) (xy 130.896632 -371.334866) (xy 130.900234 -371.3216) (xy 130.900424 -371.314726)
			(xy 130.900424 -371.028722) (xy 130.900882 -371.018554) (xy 130.908657 -370.999762) (xy 130.923032 -370.985377)
			(xy 130.941818 -370.977589) (xy 130.951986 -370.97716) (xy 131.668266 -370.97716) (xy 131.678438 -370.977592)
			(xy 131.697236 -370.98537) (xy 131.711623 -370.999754) (xy 131.719405 -371.01855) (xy 131.719828 -371.028722)
			(xy 131.719828 -371.314726) (xy 131.720007 -371.3216) (xy 131.723624 -371.334863) (xy 131.72694 -371.340888)
			(xy 131.743246 -371.369262) (xy 131.768994 -371.429424) (xy 131.786425 -371.492501) (xy 131.795222 -371.557347)
			(xy 131.795226 -371.622788) (xy 131.786438 -371.687635) (xy 131.769015 -371.750714) (xy 131.752116 -371.790214)
			(xy 133.023872 -371.790214) (xy 133.027863 -371.728047) (xy 133.039772 -371.6669) (xy 133.059401 -371.607779)
			(xy 133.08643 -371.551653) (xy 133.120414 -371.499444) (xy 133.160796 -371.452009) (xy 133.206912 -371.410128)
			(xy 133.258004 -371.374488) (xy 133.313235 -371.345674) (xy 133.371697 -371.32416) (xy 133.432431 -371.310298)
			(xy 133.494438 -371.304316) (xy 133.556701 -371.306312) (xy 133.618198 -371.316255) (xy 133.677919 -371.333979)
			(xy 133.734882 -371.359196) (xy 133.788153 -371.391489) (xy 133.836858 -371.430329) (xy 133.880195 -371.475079)
			(xy 133.917455 -371.525003) (xy 133.948024 -371.579282) (xy 133.952388 -371.590062) (xy 135.22402 -371.590062)
			(xy 135.228011 -371.527895) (xy 135.23992 -371.466748) (xy 135.259549 -371.407627) (xy 135.286578 -371.351501)
			(xy 135.320562 -371.299292) (xy 135.360944 -371.251857) (xy 135.40706 -371.209976) (xy 135.458152 -371.174336)
			(xy 135.513383 -371.145522) (xy 135.571845 -371.124008) (xy 135.632579 -371.110146) (xy 135.694586 -371.104164)
			(xy 135.756849 -371.10616) (xy 135.818346 -371.116103) (xy 135.878067 -371.133827) (xy 135.93503 -371.159044)
			(xy 135.988301 -371.191337) (xy 136.037006 -371.230177) (xy 136.080343 -371.274927) (xy 136.117603 -371.324851)
			(xy 136.148172 -371.37913) (xy 136.17155 -371.436873) (xy 136.187351 -371.497131) (xy 136.195317 -371.558914)
			(xy 136.195816 -371.590062) (xy 136.195317 -371.62121) (xy 136.187351 -371.682993) (xy 136.17155 -371.743251)
			(xy 136.148172 -371.800994) (xy 136.117603 -371.855273) (xy 136.080343 -371.905197) (xy 136.037006 -371.949947)
			(xy 135.988301 -371.988787) (xy 135.93503 -372.02108) (xy 135.878067 -372.046297) (xy 135.818346 -372.064021)
			(xy 135.756849 -372.073964) (xy 135.694586 -372.07596) (xy 135.632579 -372.069978) (xy 135.571845 -372.056116)
			(xy 135.513383 -372.034602) (xy 135.458152 -372.005788) (xy 135.40706 -371.970148) (xy 135.360944 -371.928267)
			(xy 135.320562 -371.880832) (xy 135.286578 -371.828623) (xy 135.259549 -371.772497) (xy 135.23992 -371.713376)
			(xy 135.228011 -371.652229) (xy 135.22402 -371.590062) (xy 133.952388 -371.590062) (xy 133.971402 -371.637025)
			(xy 133.987203 -371.697283) (xy 133.995169 -371.759066) (xy 133.995668 -371.790214) (xy 133.995169 -371.821362)
			(xy 133.987203 -371.883145) (xy 133.971402 -371.943403) (xy 133.948024 -372.001146) (xy 133.917455 -372.055425)
			(xy 133.880195 -372.105349) (xy 133.836858 -372.150099) (xy 133.788153 -372.188939) (xy 133.734882 -372.221232)
			(xy 133.677919 -372.246449) (xy 133.618198 -372.264173) (xy 133.556701 -372.274116) (xy 133.494438 -372.276112)
			(xy 133.432431 -372.27013) (xy 133.371697 -372.256268) (xy 133.313235 -372.234754) (xy 133.258004 -372.20594)
			(xy 133.206912 -372.1703) (xy 133.160796 -372.128419) (xy 133.120414 -372.080984) (xy 133.08643 -372.028775)
			(xy 133.059401 -371.972649) (xy 133.039772 -371.913528) (xy 133.027863 -371.852381) (xy 133.023872 -371.790214)
			(xy 131.752116 -371.790214) (xy 131.743275 -371.81088) (xy 131.72694 -371.839236) (xy 131.723616 -371.845256)
			(xy 131.720016 -371.858523) (xy 131.719828 -371.865398) (xy 131.719828 -372.614698) (xy 131.720017 -372.621571)
			(xy 131.723627 -372.634834) (xy 131.72694 -372.64086) (xy 131.743307 -372.6692) (xy 131.769049 -372.72937)
			(xy 131.786473 -372.792454) (xy 131.795263 -372.857306) (xy 131.795261 -372.890034) (xy 135.22402 -372.890034)
			(xy 135.228011 -372.827867) (xy 135.23992 -372.76672) (xy 135.259549 -372.707599) (xy 135.286578 -372.651473)
			(xy 135.320562 -372.599264) (xy 135.360944 -372.551829) (xy 135.40706 -372.509948) (xy 135.458152 -372.474308)
			(xy 135.513383 -372.445494) (xy 135.571845 -372.42398) (xy 135.632579 -372.410118) (xy 135.694586 -372.404136)
			(xy 135.756849 -372.406132) (xy 135.818346 -372.416075) (xy 135.878067 -372.433799) (xy 135.93503 -372.459016)
			(xy 135.988301 -372.491309) (xy 136.037006 -372.530149) (xy 136.080343 -372.574899) (xy 136.117603 -372.624823)
			(xy 136.148172 -372.679102) (xy 136.17155 -372.736845) (xy 136.187351 -372.797103) (xy 136.195317 -372.858886)
			(xy 136.195816 -372.890034) (xy 136.195317 -372.921182) (xy 136.187351 -372.982965) (xy 136.17155 -373.043223)
			(xy 136.148172 -373.100966) (xy 136.117603 -373.155245) (xy 136.080343 -373.205169) (xy 136.037006 -373.249919)
			(xy 135.988301 -373.288759) (xy 135.93503 -373.321052) (xy 135.878067 -373.346269) (xy 135.818346 -373.363993)
			(xy 135.756849 -373.373936) (xy 135.694586 -373.375932) (xy 135.632579 -373.36995) (xy 135.571845 -373.356088)
			(xy 135.513383 -373.334574) (xy 135.458152 -373.30576) (xy 135.40706 -373.27012) (xy 135.360944 -373.228239)
			(xy 135.320562 -373.180804) (xy 135.286578 -373.128595) (xy 135.259549 -373.072469) (xy 135.23992 -373.013348)
			(xy 135.228011 -372.952201) (xy 135.22402 -372.890034) (xy 131.795261 -372.890034) (xy 131.795259 -372.922752)
			(xy 131.786461 -372.987603) (xy 131.76903 -373.050685) (xy 131.74328 -373.110852) (xy 131.72694 -373.139208)
			(xy 131.723626 -373.145233) (xy 131.720019 -373.158496) (xy 131.719828 -373.16537) (xy 131.719828 -373.451374)
			(xy 131.719414 -373.461548) (xy 131.711631 -373.480349) (xy 131.697242 -373.494736) (xy 131.67844 -373.502515)
			(xy 131.668266 -373.502936) (xy 130.951986 -373.502936) (xy 130.94181 -373.502547) (xy 130.92301 -373.494752)
			(xy 130.908625 -373.480356) (xy 130.900845 -373.46155) (xy 130.900424 -373.451374) (xy 130.900424 -373.16537)
			(xy 130.90024 -373.158496) (xy 130.896626 -373.145234) (xy 130.893312 -373.139208) (xy 130.877004 -373.110836)
			(xy 130.851259 -373.050672) (xy 130.833831 -372.987596) (xy 130.825034 -372.922749) (xy 130.825031 -372.857309)
			(xy 130.833819 -372.792462) (xy 130.85124 -372.729383) (xy 130.876978 -372.669216) (xy 130.893312 -372.64086)
			(xy 130.896642 -372.634843) (xy 130.900238 -372.621573) (xy 130.900424 -372.614698) (xy 130.900424 -371.865398)
			(xy 130.90023 -371.858525) (xy 130.896623 -371.845262) (xy 130.893312 -371.839236) (xy 130.876943 -371.810897)
			(xy 130.851204 -371.750726) (xy 130.833782 -371.687643) (xy 130.824993 -371.62279) (xy 129.565986 -371.62279)
			(xy 129.568881 -371.629558) (xy 129.586305 -371.69264) (xy 129.595096 -371.75749) (xy 129.595095 -371.822934)
			(xy 129.586301 -371.887784) (xy 129.568873 -371.950864) (xy 129.543129 -372.011031) (xy 129.526792 -372.039388)
			(xy 129.523481 -372.045414) (xy 129.519873 -372.058677) (xy 129.51968 -372.06555) (xy 129.51968 -372.351554)
			(xy 129.519199 -372.36172) (xy 129.511432 -372.380511) (xy 129.497064 -372.394896) (xy 129.478284 -372.402686)
			(xy 129.468118 -372.403116) (xy 128.751838 -372.403116) (xy 128.741663 -372.402704) (xy 128.722861 -372.394923)
			(xy 128.708473 -372.380533) (xy 128.700695 -372.361729) (xy 128.700276 -372.351554) (xy 128.700276 -372.06555)
			(xy 128.700068 -372.058678) (xy 128.696471 -372.045415) (xy 128.693164 -372.039388) (xy 128.676838 -372.011026)
			(xy 128.651091 -371.950861) (xy 128.633663 -371.887782) (xy 128.624868 -371.822933) (xy 128.624866 -371.757491)
			(xy 128.633658 -371.692642) (xy 128.651083 -371.629562) (xy 128.676827 -371.569396) (xy 128.693164 -371.54104)
			(xy 128.696462 -371.535007) (xy 128.700078 -371.52175) (xy 128.700276 -371.514878) (xy 128.700276 -370.765324)
			(xy 128.700078 -370.758451) (xy 128.696474 -370.745188) (xy 128.693164 -370.739162) (xy 128.676816 -370.710812)
			(xy 128.651071 -370.650644) (xy 128.633645 -370.587563) (xy 128.624853 -370.522712) (xy 125.195293 -370.522712)
			(xy 125.186503 -370.587559) (xy 125.169079 -370.650639) (xy 125.143339 -370.710805) (xy 125.127004 -370.739162)
			(xy 125.123703 -370.745193) (xy 125.120089 -370.758452) (xy 125.119892 -370.765324) (xy 125.119892 -371.514878)
			(xy 125.120093 -371.521751) (xy 125.123695 -371.535013) (xy 125.127004 -371.54104) (xy 125.143352 -371.56939)
			(xy 125.166196 -371.62279) (xy 126.424943 -371.62279) (xy 126.424948 -371.557344) (xy 126.433746 -371.492493)
			(xy 126.451179 -371.429411) (xy 126.476929 -371.369244) (xy 126.49327 -371.340888) (xy 126.49664 -371.334876)
			(xy 126.500372 -371.321613) (xy 126.500636 -371.314726) (xy 126.500636 -371.028722) (xy 126.501144 -371.018597)
			(xy 126.508864 -370.999877) (xy 126.523144 -370.98552) (xy 126.541822 -370.9777) (xy 126.551944 -370.97716)
			(xy 127.268224 -370.97716) (xy 127.278375 -370.977601) (xy 127.29712 -370.985397) (xy 127.311441 -370.999787)
			(xy 127.319147 -371.018569) (xy 127.319532 -371.028722) (xy 127.319532 -371.314726) (xy 127.319768 -371.321619)
			(xy 127.323494 -371.334891) (xy 127.326898 -371.340888) (xy 127.343202 -371.369262) (xy 127.368947 -371.429425)
			(xy 127.386376 -371.492502) (xy 127.395172 -371.557347) (xy 127.395176 -371.622787) (xy 127.386389 -371.687635)
			(xy 127.368969 -371.750713) (xy 127.343232 -371.810879) (xy 127.326898 -371.839236) (xy 127.323525 -371.845247)
			(xy 127.319794 -371.85851) (xy 127.319532 -371.865398) (xy 127.319532 -372.614698) (xy 127.319762 -372.62159)
			(xy 127.323506 -372.634856) (xy 127.326898 -372.64086) (xy 127.343263 -372.669201) (xy 127.369002 -372.729371)
			(xy 127.386424 -372.792455) (xy 127.395213 -372.857307) (xy 127.395209 -372.922752) (xy 127.386412 -372.987603)
			(xy 127.368983 -373.050684) (xy 127.343236 -373.110851) (xy 127.326898 -373.139208) (xy 127.323535 -373.145224)
			(xy 127.319798 -373.158483) (xy 127.319532 -373.16537) (xy 127.319532 -373.451374) (xy 127.319051 -373.461503)
			(xy 127.311327 -373.480228) (xy 127.297038 -373.494587) (xy 127.27835 -373.502402) (xy 127.268224 -373.502936)
			(xy 126.551944 -373.502936) (xy 126.541797 -373.502443) (xy 126.523053 -373.494669) (xy 126.508729 -373.480294)
			(xy 126.501021 -373.461522) (xy 126.500636 -373.451374) (xy 126.500636 -373.16537) (xy 126.500406 -373.158477)
			(xy 126.496675 -373.145205) (xy 126.49327 -373.139208) (xy 126.47696 -373.110836) (xy 126.451212 -373.050674)
			(xy 126.433782 -372.987597) (xy 126.424984 -372.92275) (xy 126.42498 -372.857309) (xy 126.43377 -372.792461)
			(xy 126.451193 -372.729382) (xy 126.476934 -372.669216) (xy 126.49327 -372.64086) (xy 126.49665 -372.634853)
			(xy 126.500375 -372.621586) (xy 126.500636 -372.614698) (xy 126.500636 -371.865398) (xy 126.500434 -371.858503)
			(xy 126.496685 -371.845231) (xy 126.49327 -371.839236) (xy 126.476899 -371.810898) (xy 126.451157 -371.750727)
			(xy 126.433733 -371.687643) (xy 126.424943 -371.62279) (xy 125.166196 -371.62279) (xy 125.169092 -371.629559)
			(xy 125.186516 -371.69264) (xy 125.195307 -371.75749) (xy 125.195305 -371.822934) (xy 125.186511 -371.887784)
			(xy 125.169084 -371.950864) (xy 125.143341 -372.011031) (xy 125.127004 -372.039388) (xy 125.123694 -372.045415)
			(xy 125.120085 -372.058677) (xy 125.119892 -372.06555) (xy 125.119892 -372.351554) (xy 125.119399 -372.361719)
			(xy 125.111635 -372.380507) (xy 125.097271 -372.394892) (xy 125.078494 -372.402684) (xy 125.06833 -372.403116)
			(xy 124.35205 -372.403116) (xy 124.341876 -372.402694) (xy 124.323073 -372.394917) (xy 124.308685 -372.38053)
			(xy 124.300907 -372.361728) (xy 124.300488 -372.351554) (xy 124.300488 -372.06555) (xy 124.300278 -372.058678)
			(xy 124.296682 -372.045415) (xy 124.293376 -372.039388) (xy 124.277049 -372.011026) (xy 124.251302 -371.950861)
			(xy 124.233873 -371.887782) (xy 124.225078 -371.822933) (xy 124.225077 -371.757491) (xy 124.233868 -371.692642)
			(xy 124.251294 -371.629562) (xy 124.277038 -371.569396) (xy 124.293376 -371.54104) (xy 124.296675 -371.535008)
			(xy 124.300291 -371.52175) (xy 124.300488 -371.514878) (xy 124.300488 -370.765324) (xy 124.300288 -370.758451)
			(xy 124.296685 -370.745189) (xy 124.293376 -370.739162) (xy 124.277027 -370.710812) (xy 124.251282 -370.650644)
			(xy 124.233856 -370.587563) (xy 124.225063 -370.522712) (xy 120.795257 -370.522712) (xy 120.786466 -370.58756)
			(xy 120.769041 -370.650639) (xy 120.743299 -370.710806) (xy 120.726962 -370.739162) (xy 120.723577 -370.745167)
			(xy 120.719855 -370.758435) (xy 120.719596 -370.765324) (xy 120.719596 -371.514878) (xy 120.719838 -371.521769)
			(xy 120.723575 -371.535035) (xy 120.726962 -371.54104) (xy 120.743311 -371.56939) (xy 120.766158 -371.62279)
			(xy 122.024907 -371.62279) (xy 122.024912 -371.557345) (xy 122.033709 -371.492493) (xy 122.05114 -371.429412)
			(xy 122.076888 -371.369244) (xy 122.093228 -371.340888) (xy 122.096549 -371.334866) (xy 122.10015 -371.3216)
			(xy 122.10034 -371.314726) (xy 122.10034 -371.028722) (xy 122.100782 -371.018552) (xy 122.10856 -370.999757)
			(xy 122.12294 -370.985371) (xy 122.141732 -370.977586) (xy 122.151902 -370.97716) (xy 122.868182 -370.97716)
			(xy 122.878355 -370.977579) (xy 122.897154 -370.985362) (xy 122.91154 -370.99975) (xy 122.919322 -371.018549)
			(xy 122.919744 -371.028722) (xy 122.919744 -371.314726) (xy 122.919921 -371.3216) (xy 122.923539 -371.334863)
			(xy 122.926856 -371.340888) (xy 122.943161 -371.369262) (xy 122.968908 -371.429424) (xy 122.986339 -371.492501)
			(xy 122.995136 -371.557347) (xy 122.99514 -371.622788) (xy 122.986352 -371.687635) (xy 122.96893 -371.750714)
			(xy 122.943191 -371.81088) (xy 122.926856 -371.839236) (xy 122.923533 -371.845257) (xy 122.919932 -371.858523)
			(xy 122.919744 -371.865398) (xy 122.919744 -372.614698) (xy 122.919931 -372.621572) (xy 122.923542 -372.634835)
			(xy 122.926856 -372.64086) (xy 122.943222 -372.6692) (xy 122.968964 -372.729371) (xy 122.986387 -372.792454)
			(xy 122.995177 -372.857306) (xy 122.995173 -372.922752) (xy 122.986376 -372.987603) (xy 122.968944 -373.050685)
			(xy 122.943196 -373.110852) (xy 122.926856 -373.139208) (xy 122.923543 -373.145233) (xy 122.919935 -373.158496)
			(xy 122.919744 -373.16537) (xy 122.919744 -373.451374) (xy 122.919314 -373.461546) (xy 122.911534 -373.480344)
			(xy 122.89715 -373.49473) (xy 122.878354 -373.502513) (xy 122.868182 -373.502936) (xy 122.151902 -373.502936)
			(xy 122.141727 -373.502534) (xy 122.122928 -373.494745) (xy 122.108542 -373.480352) (xy 122.100761 -373.461549)
			(xy 122.10034 -373.451374) (xy 122.10034 -373.16537) (xy 122.100154 -373.158496) (xy 122.096541 -373.145234)
			(xy 122.093228 -373.139208) (xy 122.07692 -373.110836) (xy 122.051174 -373.050673) (xy 122.033745 -372.987596)
			(xy 122.024948 -372.922749) (xy 122.024944 -372.857309) (xy 122.033733 -372.792461) (xy 122.051154 -372.729382)
			(xy 122.076893 -372.669216) (xy 122.093228 -372.64086) (xy 122.096559 -372.634843) (xy 122.100154 -372.621573)
			(xy 122.10034 -372.614698) (xy 122.10034 -371.865398) (xy 122.100144 -371.858525) (xy 122.096538 -371.845263)
			(xy 122.093228 -371.839236) (xy 122.076859 -371.810897) (xy 122.051118 -371.750727) (xy 122.033696 -371.687643)
			(xy 122.024907 -371.62279) (xy 120.766158 -371.62279) (xy 120.769054 -371.629558) (xy 120.786479 -371.692639)
			(xy 120.79527 -371.75749) (xy 120.795269 -371.822934) (xy 120.786474 -371.887784) (xy 120.769046 -371.950865)
			(xy 120.7433 -372.011032) (xy 120.726962 -372.039388) (xy 120.723603 -372.045406) (xy 120.719864 -372.058664)
			(xy 120.719596 -372.06555) (xy 120.719596 -372.351554) (xy 120.719037 -372.361673) (xy 120.711331 -372.380387)
			(xy 120.697067 -372.394743) (xy 120.678404 -372.40257) (xy 120.668288 -372.403116) (xy 119.952008 -372.403116)
			(xy 119.941856 -372.402672) (xy 119.923107 -372.394882) (xy 119.908784 -372.380493) (xy 119.901081 -372.361707)
			(xy 119.9007 -372.351554) (xy 119.9007 -372.06555) (xy 119.900448 -372.05866) (xy 119.896718 -372.045394)
			(xy 119.893334 -372.039388) (xy 119.877009 -372.011025) (xy 119.851264 -371.95086) (xy 119.833836 -371.887781)
			(xy 119.825042 -371.822933) (xy 119.82504 -371.757491) (xy 119.833832 -371.692642) (xy 119.851256 -371.629563)
			(xy 119.876998 -371.569396) (xy 119.893334 -371.54104) (xy 119.896718 -371.535035) (xy 119.900441 -371.521767)
			(xy 119.9007 -371.514878) (xy 119.9007 -370.765324) (xy 119.900457 -370.758433) (xy 119.896721 -370.745167)
			(xy 119.893334 -370.739162) (xy 119.876987 -370.710811) (xy 119.851244 -370.650643) (xy 119.833819 -370.587562)
			(xy 119.825027 -370.522712) (xy 116.395221 -370.522712) (xy 116.386429 -370.58756) (xy 116.369002 -370.65064)
			(xy 116.343258 -370.710806) (xy 116.32692 -370.739162) (xy 116.32362 -370.745194) (xy 116.320005 -370.758452)
			(xy 116.319808 -370.765324) (xy 116.319808 -371.514878) (xy 116.320008 -371.521751) (xy 116.323611 -371.535013)
			(xy 116.32692 -371.54104) (xy 116.343271 -371.569389) (xy 116.36612 -371.622791) (xy 117.624857 -371.622791)
			(xy 117.624862 -371.557344) (xy 117.63366 -371.492492) (xy 117.651093 -371.429411) (xy 117.676845 -371.369244)
			(xy 117.693186 -371.340888) (xy 117.696549 -371.334872) (xy 117.700286 -371.321613) (xy 117.700552 -371.314726)
			(xy 117.700552 -371.028722) (xy 117.701045 -371.018595) (xy 117.708768 -370.999872) (xy 117.723052 -370.985515)
			(xy 117.741736 -370.977697) (xy 117.75186 -370.97716) (xy 118.46814 -370.97716) (xy 118.478292 -370.977588)
			(xy 118.497037 -370.985389) (xy 118.511358 -370.999783) (xy 118.519063 -371.018568) (xy 118.519448 -371.028722)
			(xy 118.519448 -371.314726) (xy 118.519681 -371.321619) (xy 118.523409 -371.334891) (xy 118.526814 -371.340888)
			(xy 118.543121 -371.369261) (xy 118.56887 -371.429424) (xy 118.586302 -371.4925) (xy 118.5951 -371.557347)
			(xy 118.595104 -371.622788) (xy 118.586315 -371.687636) (xy 118.568892 -371.750715) (xy 118.54315 -371.81088)
			(xy 118.526814 -371.839236) (xy 118.523442 -371.845247) (xy 118.51971 -371.85851) (xy 118.519448 -371.865398)
			(xy 118.519448 -372.614698) (xy 118.519654 -372.621593) (xy 118.523401 -372.634865) (xy 118.526814 -372.64086)
			(xy 118.543182 -372.6692) (xy 118.568925 -372.72937) (xy 118.58635 -372.792453) (xy 118.595141 -372.857306)
			(xy 118.595137 -372.922752) (xy 118.586339 -372.987604) (xy 118.568906 -373.050685) (xy 118.543155 -373.110852)
			(xy 118.526814 -373.139208) (xy 118.523452 -373.145224) (xy 118.519714 -373.158484) (xy 118.519448 -373.16537)
			(xy 118.519448 -373.451374) (xy 118.518952 -373.461501) (xy 118.51123 -373.480223) (xy 118.496947 -373.494581)
			(xy 118.478264 -373.502399) (xy 118.46814 -373.502936) (xy 117.75186 -373.502936) (xy 117.741708 -373.502512)
			(xy 117.722961 -373.49471) (xy 117.708641 -373.480315) (xy 117.700936 -373.461528) (xy 117.700552 -373.451374)
			(xy 117.700552 -373.16537) (xy 117.70032 -373.158477) (xy 117.696591 -373.145205) (xy 117.693186 -373.139208)
			(xy 117.676876 -373.110836) (xy 117.651127 -373.050674) (xy 117.633696 -372.987597) (xy 117.624898 -372.92275)
			(xy 117.624894 -372.857309) (xy 117.633684 -372.79246) (xy 117.651108 -372.729381) (xy 117.676849 -372.669216)
			(xy 117.693186 -372.64086) (xy 117.696559 -372.634849) (xy 117.70029 -372.621586) (xy 117.700552 -372.614698)
			(xy 117.700552 -371.865398) (xy 117.700348 -371.858503) (xy 117.6966 -371.845231) (xy 117.693186 -371.839236)
			(xy 117.676815 -371.810898) (xy 117.651072 -371.750728) (xy 117.633647 -371.687644) (xy 117.624857 -371.622791)
			(xy 116.36612 -371.622791) (xy 116.369015 -371.629557) (xy 116.386442 -371.692639) (xy 116.395234 -371.75749)
			(xy 116.395233 -371.822934) (xy 116.386437 -371.887785) (xy 116.369008 -371.950866) (xy 116.34326 -372.011032)
			(xy 116.32692 -372.039388) (xy 116.323611 -372.045415) (xy 116.320001 -372.058677) (xy 116.319808 -372.06555)
			(xy 116.319808 -372.351554) (xy 116.31923 -372.361703) (xy 116.311479 -372.380462) (xy 116.29714 -372.394828)
			(xy 116.278394 -372.402612) (xy 116.268246 -372.403116) (xy 115.551966 -372.403116) (xy 115.541786 -372.402763)
			(xy 115.522982 -372.394958) (xy 115.508597 -372.380551) (xy 115.500821 -372.361734) (xy 115.500404 -372.351554)
			(xy 115.500404 -372.06555) (xy 115.500192 -372.058678) (xy 115.496597 -372.045416) (xy 115.493292 -372.039388)
			(xy 115.476965 -372.011026) (xy 115.451217 -371.950861) (xy 115.433787 -371.887782) (xy 115.424992 -371.822933)
			(xy 115.42499 -371.757491) (xy 115.433783 -371.692641) (xy 115.451209 -371.629562) (xy 115.476954 -371.569396)
			(xy 115.493292 -371.54104) (xy 115.496592 -371.535008) (xy 115.500207 -371.52175) (xy 115.500404 -371.514878)
			(xy 115.500404 -370.765324) (xy 115.500203 -370.758451) (xy 115.496601 -370.745189) (xy 115.493292 -370.739162)
			(xy 115.476943 -370.710812) (xy 115.451197 -370.650644) (xy 115.43377 -370.587563) (xy 115.424977 -370.522712)
			(xy 104.615187 -370.522712) (xy 104.609499 -370.534311) (xy 104.608884 -370.545868) (xy 104.608884 -370.626132)
			(xy 104.609499 -370.637694) (xy 104.619663 -370.658465) (xy 104.628442 -370.66601) (xy 104.649225 -370.682763)
			(xy 104.686355 -370.721117) (xy 104.717777 -370.764271) (xy 104.742876 -370.811385) (xy 104.761162 -370.861537)
			(xy 104.772278 -370.913749) (xy 104.776008 -370.967) (xy 104.772278 -371.020251) (xy 104.761162 -371.072463)
			(xy 104.742876 -371.122615) (xy 104.717777 -371.169729) (xy 104.686355 -371.212883) (xy 104.649225 -371.251237)
			(xy 104.628442 -371.26799) (xy 104.619679 -371.275551) (xy 104.609499 -371.296311) (xy 104.608884 -371.307868)
			(xy 104.608884 -371.388132) (xy 104.609499 -371.399694) (xy 104.619663 -371.420465) (xy 104.628442 -371.42801)
			(xy 104.650939 -371.446185) (xy 104.690671 -371.488209) (xy 104.723608 -371.535748) (xy 104.748993 -371.587712)
			(xy 104.766247 -371.642912) (xy 104.774974 -371.700083) (xy 104.775508 -371.729) (xy 104.775022 -371.756251)
			(xy 104.767266 -371.810199) (xy 104.751911 -371.862494) (xy 104.729269 -371.912071) (xy 104.699803 -371.957921)
			(xy 104.664112 -371.999112) (xy 104.622921 -372.034803) (xy 104.577071 -372.064269) (xy 104.527494 -372.086911)
			(xy 104.475199 -372.102266) (xy 104.421251 -372.110022) (xy 104.366749 -372.110022) (xy 104.312801 -372.102266)
			(xy 104.260506 -372.086911) (xy 104.210929 -372.064269) (xy 104.165079 -372.034803) (xy 104.123888 -371.999112)
			(xy 104.088197 -371.957921) (xy 104.058731 -371.912071) (xy 104.036089 -371.862494) (xy 104.020734 -371.810199)
			(xy 104.012978 -371.756251) (xy 104.012492 -371.729) (xy 104.012975 -371.700081) (xy 104.021707 -371.642907)
			(xy 104.038969 -371.587706) (xy 104.064367 -371.535744) (xy 104.097319 -371.488211) (xy 104.137068 -371.446197)
			(xy 104.159558 -371.42801) (xy 104.168321 -371.420449) (xy 104.178501 -371.399689) (xy 104.179116 -371.388132)
			(xy 104.179116 -371.307868) (xy 104.178501 -371.296306) (xy 104.168337 -371.275535) (xy 104.159558 -371.26799)
			(xy 104.138775 -371.251237) (xy 104.101645 -371.212883) (xy 104.070223 -371.169729) (xy 104.045124 -371.122615)
			(xy 104.026838 -371.072463) (xy 104.015722 -371.020251) (xy 104.011992 -370.967) (xy 89.599149 -370.967)
			(xy 89.556535 -370.97389) (xy 89.494272 -370.975886) (xy 89.432265 -370.969904) (xy 89.371531 -370.956042)
			(xy 89.313069 -370.934528) (xy 89.257838 -370.905714) (xy 89.206746 -370.870074) (xy 89.16063 -370.828193)
			(xy 89.120248 -370.780758) (xy 89.086264 -370.728549) (xy 89.059235 -370.672423) (xy 89.039606 -370.613302)
			(xy 89.027697 -370.552155) (xy 89.023706 -370.489988) (xy 85.594925 -370.489988) (xy 85.594926 -370.522711)
			(xy 85.586134 -370.58756) (xy 85.568708 -370.65064) (xy 85.542964 -370.710806) (xy 85.526626 -370.739162)
			(xy 85.523238 -370.745165) (xy 85.519518 -370.758435) (xy 85.51926 -370.765324) (xy 85.51926 -371.514878)
			(xy 85.519472 -371.521773) (xy 85.523215 -371.535045) (xy 85.526626 -371.54104) (xy 85.542976 -371.569389)
			(xy 85.565826 -371.62279) (xy 86.824823 -371.62279) (xy 86.824827 -371.557345) (xy 86.833625 -371.492493)
			(xy 86.851057 -371.429411) (xy 86.876806 -371.369244) (xy 86.893146 -371.340888) (xy 86.896514 -371.334875)
			(xy 86.900247 -371.321613) (xy 86.900512 -371.314726) (xy 86.900512 -371.028722) (xy 86.901044 -371.0186)
			(xy 86.908759 -370.999885) (xy 86.923031 -370.985529) (xy 86.941701 -370.977704) (xy 86.95182 -370.97716)
			(xy 87.6681 -370.97716) (xy 87.678249 -370.977621) (xy 87.696994 -370.985409) (xy 87.711316 -370.999793)
			(xy 87.719023 -371.018571) (xy 87.719408 -371.028722) (xy 87.719408 -371.314726) (xy 87.719669 -371.321615)
			(xy 87.723392 -371.334881) (xy 87.726774 -371.340888) (xy 87.743079 -371.369262) (xy 87.768825 -371.429425)
			(xy 87.786254 -371.492501) (xy 87.795051 -371.557347) (xy 87.795056 -371.622788) (xy 87.786268 -371.687635)
			(xy 87.768847 -371.750714) (xy 87.751949 -371.790214) (xy 89.023706 -371.790214) (xy 89.027697 -371.728047)
			(xy 89.039606 -371.6669) (xy 89.059235 -371.607779) (xy 89.086264 -371.551653) (xy 89.120248 -371.499444)
			(xy 89.16063 -371.452009) (xy 89.206746 -371.410128) (xy 89.257838 -371.374488) (xy 89.313069 -371.345674)
			(xy 89.371531 -371.32416) (xy 89.432265 -371.310298) (xy 89.494272 -371.304316) (xy 89.556535 -371.306312)
			(xy 89.618032 -371.316255) (xy 89.677753 -371.333979) (xy 89.734716 -371.359196) (xy 89.787987 -371.391489)
			(xy 89.836692 -371.430329) (xy 89.880029 -371.475079) (xy 89.917289 -371.525003) (xy 89.947858 -371.579282)
			(xy 89.952222 -371.590062) (xy 91.223854 -371.590062) (xy 91.227845 -371.527895) (xy 91.239754 -371.466748)
			(xy 91.259383 -371.407627) (xy 91.286412 -371.351501) (xy 91.320396 -371.299292) (xy 91.360778 -371.251857)
			(xy 91.406894 -371.209976) (xy 91.457986 -371.174336) (xy 91.513217 -371.145522) (xy 91.571679 -371.124008)
			(xy 91.632413 -371.110146) (xy 91.69442 -371.104164) (xy 91.756683 -371.10616) (xy 91.81818 -371.116103)
			(xy 91.877901 -371.133827) (xy 91.934864 -371.159044) (xy 91.988135 -371.191337) (xy 92.03684 -371.230177)
			(xy 92.080177 -371.274927) (xy 92.117437 -371.324851) (xy 92.148006 -371.37913) (xy 92.171384 -371.436873)
			(xy 92.187185 -371.497131) (xy 92.195151 -371.558914) (xy 92.19565 -371.590062) (xy 92.195151 -371.62121)
			(xy 92.187185 -371.682993) (xy 92.171384 -371.743251) (xy 92.148006 -371.800994) (xy 92.117437 -371.855273)
			(xy 92.080177 -371.905197) (xy 92.03684 -371.949947) (xy 91.988135 -371.988787) (xy 91.934864 -372.02108)
			(xy 91.877901 -372.046297) (xy 91.81818 -372.064021) (xy 91.756683 -372.073964) (xy 91.69442 -372.07596)
			(xy 91.632413 -372.069978) (xy 91.571679 -372.056116) (xy 91.513217 -372.034602) (xy 91.457986 -372.005788)
			(xy 91.406894 -371.970148) (xy 91.360778 -371.928267) (xy 91.320396 -371.880832) (xy 91.286412 -371.828623)
			(xy 91.259383 -371.772497) (xy 91.239754 -371.713376) (xy 91.227845 -371.652229) (xy 91.223854 -371.590062)
			(xy 89.952222 -371.590062) (xy 89.971236 -371.637025) (xy 89.987037 -371.697283) (xy 89.995003 -371.759066)
			(xy 89.995502 -371.790214) (xy 89.995003 -371.821362) (xy 89.987037 -371.883145) (xy 89.971236 -371.943403)
			(xy 89.947858 -372.001146) (xy 89.917289 -372.055425) (xy 89.880029 -372.105349) (xy 89.836692 -372.150099)
			(xy 89.787987 -372.188939) (xy 89.734716 -372.221232) (xy 89.677753 -372.246449) (xy 89.618032 -372.264173)
			(xy 89.556535 -372.274116) (xy 89.494272 -372.276112) (xy 89.432265 -372.27013) (xy 89.371531 -372.256268)
			(xy 89.313069 -372.234754) (xy 89.257838 -372.20594) (xy 89.206746 -372.1703) (xy 89.16063 -372.128419)
			(xy 89.120248 -372.080984) (xy 89.086264 -372.028775) (xy 89.059235 -371.972649) (xy 89.039606 -371.913528)
			(xy 89.027697 -371.852381) (xy 89.023706 -371.790214) (xy 87.751949 -371.790214) (xy 87.743108 -371.81088)
			(xy 87.726774 -371.839236) (xy 87.723399 -371.845246) (xy 87.71967 -371.85851) (xy 87.719408 -371.865398)
			(xy 87.719408 -372.614698) (xy 87.719641 -372.621589) (xy 87.723383 -372.634855) (xy 87.726774 -372.64086)
			(xy 87.74314 -372.6692) (xy 87.76888 -372.729371) (xy 87.786303 -372.792454) (xy 87.795092 -372.857307)
			(xy 87.79509 -372.890034) (xy 91.223854 -372.890034) (xy 91.227845 -372.827867) (xy 91.239754 -372.76672)
			(xy 91.259383 -372.707599) (xy 91.286412 -372.651473) (xy 91.320396 -372.599264) (xy 91.360778 -372.551829)
			(xy 91.406894 -372.509948) (xy 91.457986 -372.474308) (xy 91.513217 -372.445494) (xy 91.571679 -372.42398)
			(xy 91.632413 -372.410118) (xy 91.69442 -372.404136) (xy 91.756683 -372.406132) (xy 91.81818 -372.416075)
			(xy 91.877901 -372.433799) (xy 91.934864 -372.459016) (xy 91.988135 -372.491309) (xy 92.03684 -372.530149)
			(xy 92.080177 -372.574899) (xy 92.117437 -372.624823) (xy 92.148006 -372.679102) (xy 92.171384 -372.736845)
			(xy 92.187185 -372.797103) (xy 92.195151 -372.858886) (xy 92.19565 -372.890034) (xy 92.195151 -372.921182)
			(xy 92.187185 -372.982965) (xy 92.171384 -373.043223) (xy 92.148006 -373.100966) (xy 92.117437 -373.155245)
			(xy 92.080177 -373.205169) (xy 92.03684 -373.249919) (xy 91.988135 -373.288759) (xy 91.934864 -373.321052)
			(xy 91.877901 -373.346269) (xy 91.81818 -373.363993) (xy 91.756683 -373.373936) (xy 91.69442 -373.375932)
			(xy 91.632413 -373.36995) (xy 91.571679 -373.356088) (xy 91.513217 -373.334574) (xy 91.457986 -373.30576)
			(xy 91.406894 -373.27012) (xy 91.360778 -373.228239) (xy 91.320396 -373.180804) (xy 91.286412 -373.128595)
			(xy 91.259383 -373.072469) (xy 91.239754 -373.013348) (xy 91.227845 -372.952201) (xy 91.223854 -372.890034)
			(xy 87.79509 -372.890034) (xy 87.795088 -372.922752) (xy 87.786291 -372.987603) (xy 87.768861 -373.050684)
			(xy 87.743113 -373.110852) (xy 87.726774 -373.139208) (xy 87.723409 -373.145223) (xy 87.719674 -373.158483)
			(xy 87.719408 -373.16537) (xy 87.719408 -373.451374) (xy 87.718854 -373.461493) (xy 87.711143 -373.480205)
			(xy 87.696878 -373.49456) (xy 87.678216 -373.502389) (xy 87.6681 -373.502936) (xy 86.95182 -373.502936)
			(xy 86.941672 -373.502463) (xy 86.922927 -373.494681) (xy 86.908604 -373.4803) (xy 86.900897 -373.461524)
			(xy 86.900512 -373.451374) (xy 86.900512 -373.16537) (xy 86.900285 -373.158477) (xy 86.896553 -373.145205)
			(xy 86.893146 -373.139208) (xy 86.876837 -373.110836) (xy 86.85109 -373.050673) (xy 86.83366 -372.987596)
			(xy 86.824864 -372.922749) (xy 86.82486 -372.857309) (xy 86.833649 -372.792461) (xy 86.851071 -372.729382)
			(xy 86.876811 -372.669216) (xy 86.893146 -372.64086) (xy 86.896524 -372.634852) (xy 86.900251 -372.621586)
			(xy 86.900512 -372.614698) (xy 86.900512 -371.865398) (xy 86.900313 -371.858502) (xy 86.896562 -371.84523)
			(xy 86.893146 -371.839236) (xy 86.876776 -371.810898) (xy 86.851035 -371.750727) (xy 86.833612 -371.687643)
			(xy 86.824823 -371.62279) (xy 85.565826 -371.62279) (xy 85.568721 -371.629557) (xy 85.586147 -371.692639)
			(xy 85.59494 -371.75749) (xy 85.594938 -371.822934) (xy 85.586143 -371.887785) (xy 85.568713 -371.950866)
			(xy 85.542965 -372.011032) (xy 85.526626 -372.039388) (xy 85.523264 -372.045404) (xy 85.519527 -372.058664)
			(xy 85.51926 -372.06555) (xy 85.51926 -372.351554) (xy 85.518736 -372.361678) (xy 85.511023 -372.380398)
			(xy 85.496748 -372.394756) (xy 85.478073 -372.402576) (xy 85.467952 -372.403116) (xy 84.751672 -372.403116)
			(xy 84.741518 -372.402702) (xy 84.722768 -372.3949) (xy 84.708446 -372.380501) (xy 84.700745 -372.36171)
			(xy 84.700364 -372.351554) (xy 84.700364 -372.06555) (xy 84.700138 -372.058657) (xy 84.696405 -372.045385)
			(xy 84.692998 -372.039388) (xy 84.676674 -372.011025) (xy 84.650931 -371.950859) (xy 84.633505 -371.887781)
			(xy 84.624711 -371.822933) (xy 84.624709 -371.757491) (xy 84.6335 -371.692643) (xy 84.650923 -371.629563)
			(xy 84.676663 -371.569397) (xy 84.692998 -371.54104) (xy 84.696379 -371.535033) (xy 84.700105 -371.521767)
			(xy 84.700364 -371.514878) (xy 84.700364 -370.765324) (xy 84.700148 -370.75843) (xy 84.696408 -370.745158)
			(xy 84.692998 -370.739162) (xy 84.676652 -370.710811) (xy 84.650911 -370.650643) (xy 84.633487 -370.587561)
			(xy 84.624696 -370.522711) (xy 81.195136 -370.522711) (xy 81.186345 -370.58756) (xy 81.168919 -370.65064)
			(xy 81.143175 -370.710806) (xy 81.126838 -370.739162) (xy 81.123451 -370.745166) (xy 81.11973 -370.758435)
			(xy 81.119472 -370.765324) (xy 81.119472 -371.514878) (xy 81.119682 -371.521773) (xy 81.123426 -371.535045)
			(xy 81.126838 -371.54104) (xy 81.143188 -371.569389) (xy 81.166037 -371.62279) (xy 82.424787 -371.62279)
			(xy 82.424791 -371.557345) (xy 82.433588 -371.492494) (xy 82.451018 -371.429412) (xy 82.476765 -371.369245)
			(xy 82.493104 -371.340888) (xy 82.496423 -371.334866) (xy 82.500026 -371.3216) (xy 82.500216 -371.314726)
			(xy 82.500216 -371.028722) (xy 82.500751 -371.018568) (xy 82.508514 -370.999804) (xy 82.522867 -370.985439)
			(xy 82.541625 -370.977659) (xy 82.551778 -370.97716) (xy 83.268058 -370.97716) (xy 83.27823 -370.977599)
			(xy 83.297028 -370.985374) (xy 83.311415 -370.999756) (xy 83.319197 -371.018551) (xy 83.31962 -371.028722)
			(xy 83.31962 -371.314726) (xy 83.319799 -371.3216) (xy 83.323416 -371.334863) (xy 83.326732 -371.340888)
			(xy 83.343038 -371.369262) (xy 83.368786 -371.429424) (xy 83.386218 -371.4925) (xy 83.395015 -371.557347)
			(xy 83.395019 -371.622788) (xy 83.386231 -371.687636) (xy 83.368808 -371.750714) (xy 83.343068 -371.81088)
			(xy 83.326732 -371.839236) (xy 83.323407 -371.845256) (xy 83.319808 -371.858523) (xy 83.31962 -371.865398)
			(xy 83.31962 -372.614698) (xy 83.31981 -372.621571) (xy 83.32342 -372.634834) (xy 83.326732 -372.64086)
			(xy 83.343099 -372.6692) (xy 83.368842 -372.72937) (xy 83.386266 -372.792454) (xy 83.395056 -372.857306)
			(xy 83.395052 -372.922752) (xy 83.386254 -372.987604) (xy 83.368823 -373.050685) (xy 83.343073 -373.110852)
			(xy 83.326732 -373.139208) (xy 83.323417 -373.145233) (xy 83.319811 -373.158496) (xy 83.31962 -373.16537)
			(xy 83.31962 -373.451374) (xy 83.319214 -373.461549) (xy 83.311429 -373.480351) (xy 83.297038 -373.494738)
			(xy 83.278233 -373.502517) (xy 83.268058 -373.502936) (xy 82.551778 -373.502936) (xy 82.541602 -373.502553)
			(xy 82.522802 -373.494756) (xy 82.508417 -373.480358) (xy 82.500637 -373.461551) (xy 82.500216 -373.451374)
			(xy 82.500216 -373.16537) (xy 82.500033 -373.158496) (xy 82.496419 -373.145233) (xy 82.493104 -373.139208)
			(xy 82.476797 -373.110836) (xy 82.451052 -373.050672) (xy 82.433623 -372.987596) (xy 82.424828 -372.922749)
			(xy 82.424824 -372.857309) (xy 82.433612 -372.792462) (xy 82.451032 -372.729383) (xy 82.47677 -372.669216)
			(xy 82.493104 -372.64086) (xy 82.496433 -372.634842) (xy 82.50003 -372.621573) (xy 82.500216 -372.614698)
			(xy 82.500216 -371.865398) (xy 82.500023 -371.858525) (xy 82.496415 -371.845262) (xy 82.493104 -371.839236)
			(xy 82.476736 -371.810897) (xy 82.450996 -371.750726) (xy 82.433575 -371.687642) (xy 82.424787 -371.62279)
			(xy 81.166037 -371.62279) (xy 81.168932 -371.629557) (xy 81.186358 -371.692639) (xy 81.19515 -371.75749)
			(xy 81.195148 -371.822934) (xy 81.186353 -371.887785) (xy 81.168924 -371.950865) (xy 81.143177 -372.011032)
			(xy 81.126838 -372.039388) (xy 81.123477 -372.045405) (xy 81.11974 -372.058664) (xy 81.119472 -372.06555)
			(xy 81.119472 -372.351554) (xy 81.118936 -372.361676) (xy 81.111226 -372.380394) (xy 81.096954 -372.394752)
			(xy 81.078283 -372.402574) (xy 81.068164 -372.403116) (xy 80.351884 -372.403116) (xy 80.341731 -372.402692)
			(xy 80.322981 -372.394894) (xy 80.308659 -372.380499) (xy 80.300957 -372.361709) (xy 80.300576 -372.351554)
			(xy 80.300576 -372.06555) (xy 80.300327 -372.05866) (xy 80.296596 -372.045394) (xy 80.29321 -372.039388)
			(xy 80.276885 -372.011025) (xy 80.251142 -371.95086) (xy 80.233715 -371.887781) (xy 80.224921 -371.822933)
			(xy 80.22492 -371.757491) (xy 80.23371 -371.692643) (xy 80.251134 -371.629563) (xy 80.276874 -371.569396)
			(xy 80.29321 -371.54104) (xy 80.296592 -371.535034) (xy 80.300317 -371.521767) (xy 80.300576 -371.514878)
			(xy 80.300576 -370.765324) (xy 80.300337 -370.758433) (xy 80.296599 -370.745167) (xy 80.29321 -370.739162)
			(xy 80.276863 -370.710811) (xy 80.251122 -370.650643) (xy 80.233698 -370.587562) (xy 80.224907 -370.522711)
			(xy 76.795086 -370.522711) (xy 76.786296 -370.587559) (xy 76.768872 -370.650639) (xy 76.743131 -370.710805)
			(xy 76.726796 -370.739162) (xy 76.723494 -370.745193) (xy 76.719881 -370.758452) (xy 76.719684 -370.765324)
			(xy 76.719684 -371.514878) (xy 76.719886 -371.52175) (xy 76.723488 -371.535013) (xy 76.726796 -371.54104)
			(xy 76.743144 -371.56939) (xy 76.765989 -371.62279) (xy 78.024736 -371.62279) (xy 78.024741 -371.557344)
			(xy 78.033539 -371.492493) (xy 78.050971 -371.429411) (xy 78.076721 -371.369244) (xy 78.093062 -371.340888)
			(xy 78.096431 -371.334876) (xy 78.100164 -371.321613) (xy 78.100428 -371.314726) (xy 78.100428 -371.028722)
			(xy 78.100944 -371.018598) (xy 78.108662 -370.99988) (xy 78.12294 -370.985523) (xy 78.141615 -370.977701)
			(xy 78.151736 -370.97716) (xy 78.868016 -370.97716) (xy 78.878166 -370.977607) (xy 78.896911 -370.985401)
			(xy 78.911233 -370.999789) (xy 78.918939 -371.01857) (xy 78.919324 -371.028722) (xy 78.919324 -371.314726)
			(xy 78.919561 -371.321618) (xy 78.923287 -371.33489) (xy 78.92669 -371.340888) (xy 78.942994 -371.369262)
			(xy 78.96874 -371.429425) (xy 78.986169 -371.492501) (xy 78.994965 -371.557347) (xy 78.994969 -371.622787)
			(xy 78.986182 -371.687635) (xy 78.968761 -371.750713) (xy 78.943024 -371.81088) (xy 78.92669 -371.839236)
			(xy 78.923316 -371.845246) (xy 78.919586 -371.85851) (xy 78.919324 -371.865398) (xy 78.919324 -372.614698)
			(xy 78.919555 -372.62159) (xy 78.923298 -372.634856) (xy 78.92669 -372.64086) (xy 78.943055 -372.669201)
			(xy 78.968795 -372.729371) (xy 78.986217 -372.792455) (xy 78.995006 -372.857307) (xy 78.995002 -372.922752)
			(xy 78.986205 -372.987603) (xy 78.968776 -373.050684) (xy 78.943029 -373.110851) (xy 78.92669 -373.139208)
			(xy 78.923326 -373.145223) (xy 78.91959 -373.158483) (xy 78.919324 -373.16537) (xy 78.919324 -373.451374)
			(xy 78.918851 -373.461504) (xy 78.911125 -373.480231) (xy 78.896834 -373.49459) (xy 78.878143 -373.502403)
			(xy 78.868016 -373.502936) (xy 78.151736 -373.502936) (xy 78.141589 -373.502449) (xy 78.122844 -373.494673)
			(xy 78.108521 -373.480296) (xy 78.100813 -373.461523) (xy 78.100428 -373.451374) (xy 78.100428 -373.16537)
			(xy 78.100199 -373.158477) (xy 78.096468 -373.145205) (xy 78.093062 -373.139208) (xy 78.076753 -373.110836)
			(xy 78.051005 -373.050673) (xy 78.033574 -372.987597) (xy 78.024778 -372.92275) (xy 78.024774 -372.857309)
			(xy 78.033563 -372.792461) (xy 78.050986 -372.729382) (xy 78.076726 -372.669216) (xy 78.093062 -372.64086)
			(xy 78.096441 -372.634853) (xy 78.100167 -372.621586) (xy 78.100428 -372.614698) (xy 78.100428 -371.865398)
			(xy 78.100227 -371.858503) (xy 78.096477 -371.845231) (xy 78.093062 -371.839236) (xy 78.076692 -371.810898)
			(xy 78.05095 -371.750727) (xy 78.033526 -371.687643) (xy 78.024736 -371.62279) (xy 76.765989 -371.62279)
			(xy 76.768885 -371.629559) (xy 76.786309 -371.69264) (xy 76.7951 -371.75749) (xy 76.795098 -371.822934)
			(xy 76.786304 -371.887784) (xy 76.768877 -371.950864) (xy 76.743133 -372.011031) (xy 76.726796 -372.039388)
			(xy 76.723485 -372.045415) (xy 76.719877 -372.058677) (xy 76.719684 -372.06555) (xy 76.719684 -372.351554)
			(xy 76.719199 -372.36172) (xy 76.711433 -372.380509) (xy 76.697067 -372.394895) (xy 76.678287 -372.402686)
			(xy 76.668122 -372.403116) (xy 75.951842 -372.403116) (xy 75.941667 -372.402701) (xy 75.922865 -372.394921)
			(xy 75.908477 -372.380532) (xy 75.900699 -372.361729) (xy 75.90028 -372.351554) (xy 75.90028 -372.06555)
			(xy 75.900071 -372.058678) (xy 75.896475 -372.045415) (xy 75.893168 -372.039388) (xy 75.876842 -372.011026)
			(xy 75.851095 -371.950861) (xy 75.833666 -371.887782) (xy 75.824871 -371.822933) (xy 75.82487 -371.757491)
			(xy 75.833661 -371.692642) (xy 75.851087 -371.629562) (xy 75.876831 -371.569396) (xy 75.893168 -371.54104)
			(xy 75.896466 -371.535007) (xy 75.900082 -371.52175) (xy 75.90028 -371.514878) (xy 75.90028 -370.765324)
			(xy 75.900081 -370.758451) (xy 75.896478 -370.745188) (xy 75.893168 -370.739162) (xy 75.87682 -370.710812)
			(xy 75.851075 -370.650644) (xy 75.833649 -370.587563) (xy 75.824856 -370.522712) (xy 72.39505 -370.522712)
			(xy 72.386259 -370.58756) (xy 72.368833 -370.650639) (xy 72.343091 -370.710806) (xy 72.326754 -370.739162)
			(xy 72.323369 -370.745166) (xy 72.319647 -370.758435) (xy 72.319388 -370.765324) (xy 72.319388 -371.514878)
			(xy 72.319596 -371.521773) (xy 72.323341 -371.535045) (xy 72.326754 -371.54104) (xy 72.343103 -371.56939)
			(xy 72.365951 -371.62279) (xy 73.6247 -371.62279) (xy 73.624705 -371.557345) (xy 73.633502 -371.492493)
			(xy 73.650933 -371.429412) (xy 73.676681 -371.369244) (xy 73.69302 -371.340888) (xy 73.69634 -371.334866)
			(xy 73.699942 -371.3216) (xy 73.700132 -371.314726) (xy 73.700132 -371.028722) (xy 73.700582 -371.018553)
			(xy 73.708359 -370.99976) (xy 73.722736 -370.985374) (xy 73.741525 -370.977587) (xy 73.751694 -370.97716)
			(xy 74.467974 -370.97716) (xy 74.478147 -370.977586) (xy 74.496945 -370.985366) (xy 74.511331 -370.999752)
			(xy 74.519113 -371.018549) (xy 74.519536 -371.028722) (xy 74.519536 -371.314726) (xy 74.519714 -371.3216)
			(xy 74.523331 -371.334863) (xy 74.526648 -371.340888) (xy 74.542954 -371.369262) (xy 74.568701 -371.429424)
			(xy 74.586132 -371.492501) (xy 74.594929 -371.557347) (xy 74.594933 -371.622788) (xy 74.586145 -371.687635)
			(xy 74.568723 -371.750714) (xy 74.542983 -371.81088) (xy 74.526648 -371.839236) (xy 74.523324 -371.845256)
			(xy 74.519724 -371.858523) (xy 74.519536 -371.865398) (xy 74.519536 -372.614698) (xy 74.519724 -372.621572)
			(xy 74.523335 -372.634834) (xy 74.526648 -372.64086) (xy 74.543015 -372.6692) (xy 74.568756 -372.72937)
			(xy 74.58618 -372.792454) (xy 74.59497 -372.857306) (xy 74.594966 -372.922752) (xy 74.586169 -372.987603)
			(xy 74.568737 -373.050685) (xy 74.542988 -373.110852) (xy 74.526648 -373.139208) (xy 74.523334 -373.145233)
			(xy 74.519727 -373.158496) (xy 74.519536 -373.16537) (xy 74.519536 -373.451374) (xy 74.519114 -373.461547)
			(xy 74.511333 -373.480346) (xy 74.496946 -373.494733) (xy 74.478147 -373.502514) (xy 74.467974 -373.502936)
			(xy 73.751694 -373.502936) (xy 73.741519 -373.50254) (xy 73.722719 -373.494749) (xy 73.708333 -373.480354)
			(xy 73.700553 -373.461549) (xy 73.700132 -373.451374) (xy 73.700132 -373.16537) (xy 73.699947 -373.158496)
			(xy 73.696334 -373.145234) (xy 73.69302 -373.139208) (xy 73.676712 -373.110836) (xy 73.650966 -373.050673)
			(xy 73.633538 -372.987596) (xy 73.624741 -372.922749) (xy 73.624737 -372.857309) (xy 73.633526 -372.792461)
			(xy 73.650947 -372.729383) (xy 73.676685 -372.669216) (xy 73.69302 -372.64086) (xy 73.69635 -372.634843)
			(xy 73.699946 -372.621573) (xy 73.700132 -372.614698) (xy 73.700132 -371.865398) (xy 73.699937 -371.858525)
			(xy 73.69633 -371.845262) (xy 73.69302 -371.839236) (xy 73.676651 -371.810897) (xy 73.650911 -371.750726)
			(xy 73.633489 -371.687643) (xy 73.6247 -371.62279) (xy 72.365951 -371.62279) (xy 72.368847 -371.629558)
			(xy 72.386272 -371.692639) (xy 72.395064 -371.75749) (xy 72.395062 -371.822934) (xy 72.386267 -371.887784)
			(xy 72.368839 -371.950865) (xy 72.343093 -372.011032) (xy 72.326754 -372.039388) (xy 72.323395 -372.045405)
			(xy 72.319656 -372.058664) (xy 72.319388 -372.06555) (xy 72.319388 -372.351554) (xy 72.318836 -372.361674)
			(xy 72.311129 -372.380389) (xy 72.296863 -372.394746) (xy 72.278197 -372.402572) (xy 72.26808 -372.403116)
			(xy 71.5518 -372.403116) (xy 71.541648 -372.402679) (xy 71.522899 -372.394886) (xy 71.508576 -372.380494)
			(xy 71.500873 -372.361708) (xy 71.500492 -372.351554) (xy 71.500492 -372.06555) (xy 71.500241 -372.05866)
			(xy 71.496511 -372.045394) (xy 71.493126 -372.039388) (xy 71.476801 -372.011025) (xy 71.451057 -371.95086)
			(xy 71.433629 -371.887781) (xy 71.424835 -371.822933) (xy 71.424834 -371.757491) (xy 71.433624 -371.692642)
			(xy 71.451049 -371.629563) (xy 71.47679 -371.569396) (xy 71.493126 -371.54104) (xy 71.496509 -371.535034)
			(xy 71.500233 -371.521767) (xy 71.500492 -371.514878) (xy 71.500492 -370.765324) (xy 71.500251 -370.758433)
			(xy 71.496514 -370.745167) (xy 71.493126 -370.739162) (xy 71.476779 -370.710811) (xy 71.451037 -370.650643)
			(xy 71.433612 -370.587562) (xy 71.42482 -370.522712) (xy 58.103008 -370.522712) (xy 58.103008 -371.310662)
			(xy 58.102522 -371.337931) (xy 58.09476 -371.391915) (xy 58.079395 -371.444245) (xy 58.056738 -371.493855)
			(xy 58.027252 -371.539736) (xy 57.991537 -371.580953) (xy 57.95032 -371.616668) (xy 57.904439 -371.646154)
			(xy 57.854829 -371.668811) (xy 57.802499 -371.684176) (xy 57.748515 -371.691938) (xy 57.693977 -371.691938)
			(xy 57.639993 -371.684176) (xy 57.587663 -371.668811) (xy 57.538053 -371.646154) (xy 57.492172 -371.616668)
			(xy 57.450955 -371.580953) (xy 57.41524 -371.539736) (xy 57.385754 -371.493855) (xy 57.363097 -371.444245)
			(xy 57.347732 -371.391915) (xy 57.33997 -371.337931) (xy 57.339484 -371.310662) (xy 54.729888 -371.310662)
			(xy 54.729402 -371.337931) (xy 54.72164 -371.391915) (xy 54.706275 -371.444245) (xy 54.683618 -371.493855)
			(xy 54.654132 -371.539736) (xy 54.618417 -371.580953) (xy 54.5772 -371.616668) (xy 54.531319 -371.646154)
			(xy 54.481709 -371.668811) (xy 54.429379 -371.684176) (xy 54.375395 -371.691938) (xy 54.320857 -371.691938)
			(xy 54.266873 -371.684176) (xy 54.214543 -371.668811) (xy 54.164933 -371.646154) (xy 54.119052 -371.616668)
			(xy 54.077835 -371.580953) (xy 54.04212 -371.539736) (xy 54.012634 -371.493855) (xy 53.989977 -371.444245)
			(xy 53.974612 -371.391915) (xy 53.96685 -371.337931) (xy 53.966364 -371.310662) (xy 51.556158 -371.310662)
			(xy 51.556158 -373.88419) (xy 56.962292 -373.88419) (xy 56.966363 -373.828568) (xy 56.978489 -373.774131)
			(xy 56.998412 -373.72204) (xy 57.025708 -373.673405) (xy 57.059794 -373.629262) (xy 57.099943 -373.590553)
			(xy 57.145301 -373.558102) (xy 57.194901 -373.532601) (xy 57.247685 -373.514594) (xy 57.302528 -373.504464)
			(xy 57.358262 -373.502427) (xy 57.413699 -373.508527) (xy 57.467656 -373.522633) (xy 57.518985 -373.544445)
			(xy 57.566591 -373.573499) (xy 57.609459 -373.609174) (xy 57.646676 -373.650711) (xy 57.677449 -373.697224)
			(xy 57.701121 -373.747721) (xy 57.717189 -373.801128) (xy 57.725309 -373.856304) (xy 57.725818 -373.88419)
			(xy 57.725309 -373.912076) (xy 57.717189 -373.967252) (xy 57.701121 -374.020659) (xy 57.677449 -374.071156)
			(xy 57.646676 -374.117669) (xy 57.609459 -374.159206) (xy 57.566591 -374.194881) (xy 57.518985 -374.223935)
			(xy 57.467656 -374.245747) (xy 57.413699 -374.259853) (xy 57.358262 -374.265953) (xy 57.302528 -374.263916)
			(xy 57.247685 -374.253786) (xy 57.194901 -374.235779) (xy 57.145301 -374.210278) (xy 57.099943 -374.177827)
			(xy 57.059794 -374.139118) (xy 57.025708 -374.094975) (xy 56.998412 -374.04634) (xy 56.978489 -373.994249)
			(xy 56.966363 -373.939812) (xy 56.962292 -373.88419) (xy 51.556158 -373.88419) (xy 51.556158 -374.422887)
			(xy 71.424803 -374.422887) (xy 71.424808 -374.357441) (xy 71.433606 -374.29259) (xy 71.451037 -374.229508)
			(xy 71.476786 -374.16934) (xy 71.493126 -374.140984) (xy 71.496494 -374.134971) (xy 71.500227 -374.121709)
			(xy 71.500492 -374.114822) (xy 71.500492 -373.828818) (xy 71.50104 -373.818698) (xy 71.508753 -373.799987)
			(xy 71.52302 -373.785631) (xy 71.541684 -373.777803) (xy 71.5518 -373.777256) (xy 72.26808 -373.777256)
			(xy 72.278227 -373.777737) (xy 72.296971 -373.785518) (xy 72.311293 -373.799896) (xy 72.319002 -373.818669)
			(xy 72.319388 -373.828818) (xy 72.319388 -374.114822) (xy 72.319618 -374.121715) (xy 72.323348 -374.134987)
			(xy 72.326754 -374.140984) (xy 72.343056 -374.16936) (xy 72.368804 -374.229522) (xy 72.386234 -374.292598)
			(xy 72.395032 -374.357444) (xy 72.395037 -374.422884) (xy 72.395037 -374.422887) (xy 75.824839 -374.422887)
			(xy 75.824844 -374.357441) (xy 75.833643 -374.292589) (xy 75.851076 -374.229507) (xy 75.876827 -374.16934)
			(xy 75.893168 -374.140984) (xy 75.896486 -374.134961) (xy 75.90009 -374.121696) (xy 75.90028 -374.114822)
			(xy 75.90028 -373.828818) (xy 75.900679 -373.818642) (xy 75.908466 -373.79984) (xy 75.92286 -373.785453)
			(xy 75.941666 -373.777675) (xy 75.951842 -373.777256) (xy 76.668122 -373.777256) (xy 76.678283 -373.777716)
			(xy 76.697057 -373.785501) (xy 76.711422 -373.799877) (xy 76.719192 -373.818656) (xy 76.719684 -373.828818)
			(xy 76.719684 -374.114822) (xy 76.71987 -374.121696) (xy 76.723482 -374.134958) (xy 76.726796 -374.140984)
			(xy 76.743097 -374.16936) (xy 76.768842 -374.229523) (xy 76.786271 -374.292599) (xy 76.795068 -374.357444)
			(xy 76.795073 -374.422884) (xy 76.795073 -374.422887) (xy 80.224889 -374.422887) (xy 80.224894 -374.357441)
			(xy 80.233692 -374.29259) (xy 80.251123 -374.229508) (xy 80.276871 -374.169341) (xy 80.29321 -374.140984)
			(xy 80.296577 -374.13497) (xy 80.300311 -374.121709) (xy 80.300576 -374.114822) (xy 80.300576 -373.828818)
			(xy 80.301042 -373.818688) (xy 80.308771 -373.79996) (xy 80.323064 -373.785602) (xy 80.341756 -373.777789)
			(xy 80.351884 -373.777256) (xy 81.068164 -373.777256) (xy 81.07831 -373.77775) (xy 81.097053 -373.785526)
			(xy 81.111376 -373.7999) (xy 81.119085 -373.81867) (xy 81.119472 -373.828818) (xy 81.119472 -374.114822)
			(xy 81.119704 -374.121715) (xy 81.123433 -374.134987) (xy 81.126838 -374.140984) (xy 81.14314 -374.16936)
			(xy 81.168889 -374.229521) (xy 81.18632 -374.292598) (xy 81.195118 -374.357444) (xy 81.195123 -374.422884)
			(xy 81.195123 -374.422887) (xy 84.624679 -374.422887) (xy 84.624684 -374.357441) (xy 84.633481 -374.29259)
			(xy 84.650912 -374.229508) (xy 84.676659 -374.169341) (xy 84.692998 -374.140984) (xy 84.696364 -374.13497)
			(xy 84.700099 -374.121709) (xy 84.700364 -374.114822) (xy 84.700364 -373.828818) (xy 84.700842 -373.818689)
			(xy 84.708568 -373.799964) (xy 84.722858 -373.785606) (xy 84.741546 -373.777791) (xy 84.751672 -373.777256)
			(xy 85.467952 -373.777256) (xy 85.478098 -373.77776) (xy 85.49684 -373.785532) (xy 85.511164 -373.799903)
			(xy 85.518873 -373.818671) (xy 85.51926 -373.828818) (xy 85.51926 -374.114822) (xy 85.519494 -374.121715)
			(xy 85.523222 -374.134987) (xy 85.526626 -374.140984) (xy 85.542929 -374.169359) (xy 85.568678 -374.229521)
			(xy 85.58611 -374.292597) (xy 85.594908 -374.357444) (xy 85.59491 -374.390158) (xy 89.023706 -374.390158)
			(xy 89.027697 -374.327991) (xy 89.039606 -374.266844) (xy 89.059235 -374.207723) (xy 89.086264 -374.151597)
			(xy 89.120248 -374.099388) (xy 89.16063 -374.051953) (xy 89.206746 -374.010072) (xy 89.257838 -373.974432)
			(xy 89.313069 -373.945618) (xy 89.371531 -373.924104) (xy 89.432265 -373.910242) (xy 89.494272 -373.90426)
			(xy 89.556535 -373.906256) (xy 89.618032 -373.916199) (xy 89.677753 -373.933923) (xy 89.734716 -373.95914)
			(xy 89.787987 -373.991433) (xy 89.836692 -374.030273) (xy 89.880029 -374.075023) (xy 89.917289 -374.124947)
			(xy 89.947858 -374.179226) (xy 89.971236 -374.236969) (xy 89.987037 -374.297227) (xy 89.995003 -374.35901)
			(xy 89.995502 -374.390158) (xy 89.995003 -374.421306) (xy 89.994799 -374.422887) (xy 115.42496 -374.422887)
			(xy 115.424965 -374.357441) (xy 115.433764 -374.292588) (xy 115.451198 -374.229507) (xy 115.47695 -374.16934)
			(xy 115.493292 -374.140984) (xy 115.496612 -374.134962) (xy 115.500214 -374.121696) (xy 115.500404 -374.114822)
			(xy 115.500404 -373.828818) (xy 115.500947 -373.818666) (xy 115.508709 -373.799903) (xy 115.52306 -373.785539)
			(xy 115.541814 -373.777757) (xy 115.551966 -373.777256) (xy 116.268246 -373.777256) (xy 116.278409 -373.777696)
			(xy 116.297183 -373.785489) (xy 116.311547 -373.799871) (xy 116.319316 -373.818654) (xy 116.319808 -373.828818)
			(xy 116.319808 -374.114822) (xy 116.31999 -374.121696) (xy 116.323605 -374.134959) (xy 116.32692 -374.140984)
			(xy 116.343223 -374.169359) (xy 116.368972 -374.229521) (xy 116.386404 -374.292597) (xy 116.395202 -374.357444)
			(xy 116.395207 -374.422884) (xy 116.395207 -374.422887) (xy 119.82501 -374.422887) (xy 119.825015 -374.357441)
			(xy 119.833813 -374.292589) (xy 119.851245 -374.229508) (xy 119.876994 -374.16934) (xy 119.893334 -374.140984)
			(xy 119.896702 -374.134971) (xy 119.900435 -374.121709) (xy 119.9007 -374.114822) (xy 119.9007 -373.828818)
			(xy 119.90124 -373.818697) (xy 119.908955 -373.799984) (xy 119.923224 -373.785629) (xy 119.94189 -373.777802)
			(xy 119.952008 -373.777256) (xy 120.668288 -373.777256) (xy 120.678436 -373.777731) (xy 120.69718 -373.785514)
			(xy 120.711502 -373.799894) (xy 120.71921 -373.818669) (xy 120.719596 -373.828818) (xy 120.719596 -374.114822)
			(xy 120.71986 -374.121711) (xy 120.723581 -374.134977) (xy 120.726962 -374.140984) (xy 120.743264 -374.16936)
			(xy 120.769011 -374.229522) (xy 120.786441 -374.292598) (xy 120.795239 -374.357444) (xy 120.795243 -374.422884)
			(xy 120.795243 -374.422887) (xy 124.225046 -374.422887) (xy 124.225051 -374.357441) (xy 124.23385 -374.292589)
			(xy 124.251283 -374.229507) (xy 124.277035 -374.16934) (xy 124.293376 -374.140984) (xy 124.296695 -374.134961)
			(xy 124.300298 -374.121696) (xy 124.300488 -374.114822) (xy 124.300488 -373.828818) (xy 124.30088 -373.818641)
			(xy 124.308668 -373.799837) (xy 124.323064 -373.78545) (xy 124.341873 -373.777673) (xy 124.35205 -373.777256)
			(xy 125.06833 -373.777256) (xy 125.078492 -373.777709) (xy 125.097265 -373.785497) (xy 125.11163 -373.799875)
			(xy 125.1194 -373.818656) (xy 125.119892 -373.828818) (xy 125.119892 -374.114822) (xy 125.120076 -374.121696)
			(xy 125.12369 -374.134959) (xy 125.127004 -374.140984) (xy 125.143304 -374.16936) (xy 125.169049 -374.229523)
			(xy 125.186478 -374.292599) (xy 125.195275 -374.357444) (xy 125.19528 -374.422884) (xy 125.19528 -374.422887)
			(xy 128.624836 -374.422887) (xy 128.624841 -374.357441) (xy 128.633639 -374.292589) (xy 128.651072 -374.229507)
			(xy 128.676823 -374.16934) (xy 128.693164 -374.140984) (xy 128.696481 -374.134961) (xy 128.700086 -374.121696)
			(xy 128.700276 -374.114822) (xy 128.700276 -373.828818) (xy 128.700679 -373.818643) (xy 128.708465 -373.799841)
			(xy 128.722858 -373.785454) (xy 128.741663 -373.777675) (xy 128.751838 -373.777256) (xy 129.468118 -373.777256)
			(xy 129.478279 -373.777719) (xy 129.497052 -373.785503) (xy 129.511418 -373.799878) (xy 129.519188 -373.818656)
			(xy 129.51968 -373.828818) (xy 129.51968 -374.114822) (xy 129.519866 -374.121696) (xy 129.523479 -374.134958)
			(xy 129.526792 -374.140984) (xy 129.543093 -374.16936) (xy 129.568838 -374.229523) (xy 129.586268 -374.292598)
			(xy 129.595064 -374.357444) (xy 129.595066 -374.390158) (xy 133.023872 -374.390158) (xy 133.027863 -374.327991)
			(xy 133.039772 -374.266844) (xy 133.059401 -374.207723) (xy 133.08643 -374.151597) (xy 133.120414 -374.099388)
			(xy 133.160796 -374.051953) (xy 133.206912 -374.010072) (xy 133.258004 -373.974432) (xy 133.313235 -373.945618)
			(xy 133.371697 -373.924104) (xy 133.432431 -373.910242) (xy 133.494438 -373.90426) (xy 133.556701 -373.906256)
			(xy 133.618198 -373.916199) (xy 133.677919 -373.933923) (xy 133.734882 -373.95914) (xy 133.788153 -373.991433)
			(xy 133.836858 -374.030273) (xy 133.880195 -374.075023) (xy 133.917455 -374.124947) (xy 133.948024 -374.179226)
			(xy 133.971402 -374.236969) (xy 133.987203 -374.297227) (xy 133.995169 -374.35901) (xy 133.995668 -374.390158)
			(xy 133.995169 -374.421306) (xy 133.987203 -374.483089) (xy 133.971402 -374.543347) (xy 133.948024 -374.60109)
			(xy 133.917455 -374.655369) (xy 133.880195 -374.705293) (xy 133.836858 -374.750043) (xy 133.788153 -374.788883)
			(xy 133.734882 -374.821176) (xy 133.677919 -374.846393) (xy 133.618198 -374.864117) (xy 133.556701 -374.87406)
			(xy 133.494438 -374.876056) (xy 133.432431 -374.870074) (xy 133.371697 -374.856212) (xy 133.313235 -374.834698)
			(xy 133.258004 -374.805884) (xy 133.206912 -374.770244) (xy 133.160796 -374.728363) (xy 133.120414 -374.680928)
			(xy 133.08643 -374.628719) (xy 133.059401 -374.572593) (xy 133.039772 -374.513472) (xy 133.027863 -374.452325)
			(xy 133.023872 -374.390158) (xy 129.595066 -374.390158) (xy 129.595069 -374.422884) (xy 129.586282 -374.487731)
			(xy 129.568862 -374.550809) (xy 129.543126 -374.610976) (xy 129.526792 -374.639332) (xy 129.523465 -374.645351)
			(xy 129.519867 -374.658619) (xy 129.51968 -374.665494) (xy 129.51968 -375.414794) (xy 129.519877 -375.421667)
			(xy 129.523482 -375.43493) (xy 129.526792 -375.440956) (xy 129.543154 -375.469298) (xy 129.568894 -375.529469)
			(xy 129.586316 -375.592552) (xy 129.595105 -375.657403) (xy 129.595102 -375.722848) (xy 129.586306 -375.787699)
			(xy 129.568877 -375.85078) (xy 129.54313 -375.910947) (xy 129.526792 -375.939304) (xy 129.523475 -375.945328)
			(xy 129.519871 -375.958592) (xy 129.51968 -375.965466) (xy 129.51968 -376.25147) (xy 129.519212 -376.261637)
			(xy 129.51144 -376.280428) (xy 129.497068 -376.294813) (xy 129.478285 -376.302602) (xy 129.468118 -376.303032)
			(xy 128.751838 -376.303032) (xy 128.741665 -376.302604) (xy 128.722866 -376.294826) (xy 128.708478 -376.280441)
			(xy 128.700697 -376.261643) (xy 128.700276 -376.25147) (xy 128.700276 -375.965466) (xy 128.7001 -375.958592)
			(xy 128.696481 -375.945329) (xy 128.693164 -375.939304) (xy 128.676851 -375.910934) (xy 128.651104 -375.850771)
			(xy 128.633674 -375.787694) (xy 128.624877 -375.722846) (xy 128.624873 -375.657405) (xy 128.633663 -375.592557)
			(xy 128.651087 -375.529478) (xy 128.676828 -375.469312) (xy 128.693164 -375.440956) (xy 128.696491 -375.434938)
			(xy 128.700089 -375.421669) (xy 128.700276 -375.414794) (xy 128.700276 -374.665494) (xy 128.700089 -374.65862)
			(xy 128.696478 -374.645358) (xy 128.693164 -374.639332) (xy 128.67679 -374.610996) (xy 128.651048 -374.550825)
			(xy 128.633625 -374.48774) (xy 128.624836 -374.422887) (xy 125.19528 -374.422887) (xy 125.186493 -374.487731)
			(xy 125.169073 -374.550809) (xy 125.143337 -374.610975) (xy 125.127004 -374.639332) (xy 125.123678 -374.645351)
			(xy 125.120079 -374.658619) (xy 125.119892 -374.665494) (xy 125.119892 -375.414794) (xy 125.120087 -375.421667)
			(xy 125.123693 -375.43493) (xy 125.127004 -375.440956) (xy 125.143365 -375.469299) (xy 125.169105 -375.529469)
			(xy 125.186527 -375.592552) (xy 125.195316 -375.657403) (xy 125.195312 -375.722848) (xy 125.186516 -375.787699)
			(xy 125.169088 -375.85078) (xy 125.143342 -375.910947) (xy 125.127004 -375.939304) (xy 125.123688 -375.945328)
			(xy 125.120083 -375.958592) (xy 125.119892 -375.965466) (xy 125.119892 -376.25147) (xy 125.119343 -376.261622)
			(xy 125.111584 -376.280385) (xy 125.097235 -376.29475) (xy 125.078482 -376.302531) (xy 125.06833 -376.303032)
			(xy 124.35205 -376.303032) (xy 124.341878 -376.302595) (xy 124.323079 -376.29482) (xy 124.308691 -376.280438)
			(xy 124.300909 -376.261642) (xy 124.300488 -376.25147) (xy 124.300488 -375.965466) (xy 124.300311 -375.958592)
			(xy 124.296693 -375.945329) (xy 124.293376 -375.939304) (xy 124.277063 -375.910934) (xy 124.251315 -375.850771)
			(xy 124.233884 -375.787694) (xy 124.225087 -375.722846) (xy 124.225084 -375.657405) (xy 124.233874 -375.592557)
			(xy 124.251298 -375.529478) (xy 124.277039 -375.469312) (xy 124.293376 -375.440956) (xy 124.296705 -375.434938)
			(xy 124.300302 -375.421669) (xy 124.300488 -375.414794) (xy 124.300488 -374.665494) (xy 124.3003 -374.65862)
			(xy 124.296689 -374.645358) (xy 124.293376 -374.639332) (xy 124.277002 -374.610996) (xy 124.251259 -374.550825)
			(xy 124.233835 -374.487741) (xy 124.225046 -374.422887) (xy 120.795243 -374.422887) (xy 120.786456 -374.487731)
			(xy 120.769035 -374.55081) (xy 120.743297 -374.610976) (xy 120.726962 -374.639332) (xy 120.723588 -374.645342)
			(xy 120.719859 -374.658606) (xy 120.719596 -374.665494) (xy 120.719596 -375.414794) (xy 120.719832 -375.421685)
			(xy 120.723573 -375.434951) (xy 120.726962 -375.440956) (xy 120.743325 -375.469298) (xy 120.769066 -375.529468)
			(xy 120.78649 -375.592551) (xy 120.79528 -375.657403) (xy 120.795276 -375.722848) (xy 120.786479 -375.787699)
			(xy 120.769049 -375.850781) (xy 120.743301 -375.910948) (xy 120.726962 -375.939304) (xy 120.723598 -375.945319)
			(xy 120.719862 -375.958579) (xy 120.719596 -375.965466) (xy 120.719596 -376.25147) (xy 120.71905 -376.26159)
			(xy 120.711339 -376.280304) (xy 120.697071 -376.29466) (xy 120.678405 -376.302487) (xy 120.668288 -376.303032)
			(xy 119.952008 -376.303032) (xy 119.941858 -376.302572) (xy 119.923112 -376.294786) (xy 119.90879 -376.280401)
			(xy 119.901084 -376.261621) (xy 119.9007 -376.25147) (xy 119.9007 -375.965466) (xy 119.900441 -375.958577)
			(xy 119.896716 -375.945311) (xy 119.893334 -375.939304) (xy 119.877022 -375.910934) (xy 119.851276 -375.85077)
			(xy 119.833847 -375.787693) (xy 119.825051 -375.722846) (xy 119.825048 -375.657405) (xy 119.833837 -375.592557)
			(xy 119.851259 -375.529478) (xy 119.876999 -375.469312) (xy 119.893334 -375.440956) (xy 119.896712 -375.434948)
			(xy 119.900439 -375.421682) (xy 119.9007 -375.414794) (xy 119.9007 -374.665494) (xy 119.900469 -374.658602)
			(xy 119.896725 -374.645337) (xy 119.893334 -374.639332) (xy 119.876961 -374.610995) (xy 119.851221 -374.550824)
			(xy 119.833799 -374.48774) (xy 119.82501 -374.422887) (xy 116.395207 -374.422887) (xy 116.386419 -374.487732)
			(xy 116.368996 -374.550811) (xy 116.343256 -374.610976) (xy 116.32692 -374.639332) (xy 116.323595 -374.645352)
			(xy 116.319996 -374.658619) (xy 116.319808 -374.665494) (xy 116.319808 -375.414794) (xy 116.320002 -375.421667)
			(xy 116.323609 -375.43493) (xy 116.32692 -375.440956) (xy 116.343284 -375.469298) (xy 116.369028 -375.529467)
			(xy 116.386453 -375.59255) (xy 116.395243 -375.657403) (xy 116.39524 -375.722848) (xy 116.386443 -375.7877)
			(xy 116.369011 -375.850781) (xy 116.343261 -375.910948) (xy 116.32692 -375.939304) (xy 116.323605 -375.945329)
			(xy 116.319999 -375.958592) (xy 116.319808 -375.965466) (xy 116.319808 -376.25147) (xy 116.319243 -376.26162)
			(xy 116.311487 -376.28038) (xy 116.297144 -376.294745) (xy 116.278395 -376.302528) (xy 116.268246 -376.303032)
			(xy 115.551966 -376.303032) (xy 115.541802 -376.302594) (xy 115.523027 -376.294803) (xy 115.508662 -376.28042)
			(xy 115.500894 -376.261634) (xy 115.500404 -376.25147) (xy 115.500404 -375.965466) (xy 115.500225 -375.958592)
			(xy 115.496608 -375.945329) (xy 115.493292 -375.939304) (xy 115.476978 -375.910934) (xy 115.451229 -375.850771)
			(xy 115.433798 -375.787694) (xy 115.425001 -375.722846) (xy 115.424998 -375.657405) (xy 115.433788 -375.592556)
			(xy 115.451212 -375.529477) (xy 115.476955 -375.469312) (xy 115.493292 -375.440956) (xy 115.496622 -375.434939)
			(xy 115.500218 -375.421669) (xy 115.500404 -375.414794) (xy 115.500404 -374.665494) (xy 115.500214 -374.658621)
			(xy 115.496604 -374.645358) (xy 115.493292 -374.639332) (xy 115.476917 -374.610996) (xy 115.451174 -374.550825)
			(xy 115.43375 -374.487741) (xy 115.42496 -374.422887) (xy 89.994799 -374.422887) (xy 89.987037 -374.483089)
			(xy 89.971236 -374.543347) (xy 89.947858 -374.60109) (xy 89.917289 -374.655369) (xy 89.880029 -374.705293)
			(xy 89.836692 -374.750043) (xy 89.787987 -374.788883) (xy 89.734716 -374.821176) (xy 89.677753 -374.846393)
			(xy 89.618032 -374.864117) (xy 89.556535 -374.87406) (xy 89.494272 -374.876056) (xy 89.432265 -374.870074)
			(xy 89.371531 -374.856212) (xy 89.313069 -374.834698) (xy 89.257838 -374.805884) (xy 89.206746 -374.770244)
			(xy 89.16063 -374.728363) (xy 89.120248 -374.680928) (xy 89.086264 -374.628719) (xy 89.059235 -374.572593)
			(xy 89.039606 -374.513472) (xy 89.027697 -374.452325) (xy 89.023706 -374.390158) (xy 85.59491 -374.390158)
			(xy 85.594912 -374.422884) (xy 85.586124 -374.487732) (xy 85.568702 -374.550811) (xy 85.542962 -374.610976)
			(xy 85.526626 -374.639332) (xy 85.523249 -374.64534) (xy 85.519522 -374.658606) (xy 85.51926 -374.665494)
			(xy 85.51926 -375.414794) (xy 85.519466 -375.421689) (xy 85.523213 -375.434961) (xy 85.526626 -375.440956)
			(xy 85.54299 -375.469298) (xy 85.568733 -375.529467) (xy 85.586158 -375.592551) (xy 85.594949 -375.657403)
			(xy 85.594945 -375.722848) (xy 85.586148 -375.7877) (xy 85.568716 -375.850781) (xy 85.542966 -375.910948)
			(xy 85.526626 -375.939304) (xy 85.523258 -375.945317) (xy 85.519525 -375.958579) (xy 85.51926 -375.965466)
			(xy 85.51926 -376.25147) (xy 85.518749 -376.261595) (xy 85.511031 -376.280315) (xy 85.496752 -376.294673)
			(xy 85.478074 -376.302493) (xy 85.467952 -376.303032) (xy 84.751672 -376.303032) (xy 84.74152 -376.302602)
			(xy 84.722773 -376.294803) (xy 84.708452 -376.28041) (xy 84.700747 -376.261624) (xy 84.700364 -376.25147)
			(xy 84.700364 -375.965466) (xy 84.700132 -375.958573) (xy 84.696403 -375.945301) (xy 84.692998 -375.939304)
			(xy 84.676687 -375.910933) (xy 84.650943 -375.85077) (xy 84.633516 -375.787693) (xy 84.62472 -375.722846)
			(xy 84.624717 -375.657406) (xy 84.633505 -375.592558) (xy 84.650926 -375.529479) (xy 84.676664 -375.469313)
			(xy 84.692998 -375.440956) (xy 84.696374 -375.434947) (xy 84.700103 -375.421682) (xy 84.700364 -375.414794)
			(xy 84.700364 -374.665494) (xy 84.700138 -374.658602) (xy 84.696391 -374.645336) (xy 84.692998 -374.639332)
			(xy 84.676626 -374.610995) (xy 84.650888 -374.550823) (xy 84.633467 -374.487739) (xy 84.624679 -374.422887)
			(xy 81.195123 -374.422887) (xy 81.186335 -374.487732) (xy 81.168913 -374.55081) (xy 81.143173 -374.610976)
			(xy 81.126838 -374.639332) (xy 81.123462 -374.645341) (xy 81.119734 -374.658606) (xy 81.119472 -374.665494)
			(xy 81.119472 -375.414794) (xy 81.119676 -375.421689) (xy 81.123424 -375.434961) (xy 81.126838 -375.440956)
			(xy 81.143202 -375.469298) (xy 81.168944 -375.529468) (xy 81.186369 -375.592551) (xy 81.195159 -375.657403)
			(xy 81.195155 -375.722848) (xy 81.186358 -375.7877) (xy 81.168927 -375.850781) (xy 81.143178 -375.910948)
			(xy 81.126838 -375.939304) (xy 81.123471 -375.945318) (xy 81.119737 -375.958579) (xy 81.119472 -375.965466)
			(xy 81.119472 -376.25147) (xy 81.118949 -376.261593) (xy 81.111234 -376.280312) (xy 81.096958 -376.294669)
			(xy 81.078284 -376.302491) (xy 81.068164 -376.303032) (xy 80.351884 -376.303032) (xy 80.341733 -376.302592)
			(xy 80.322986 -376.294797) (xy 80.308664 -376.280407) (xy 80.300959 -376.261623) (xy 80.300576 -376.25147)
			(xy 80.300576 -375.965466) (xy 80.300342 -375.958573) (xy 80.296614 -375.945301) (xy 80.29321 -375.939304)
			(xy 80.276899 -375.910933) (xy 80.251154 -375.85077) (xy 80.233726 -375.787693) (xy 80.22493 -375.722846)
			(xy 80.224927 -375.657405) (xy 80.233716 -375.592558) (xy 80.251137 -375.529479) (xy 80.276876 -375.469312)
			(xy 80.29321 -375.440956) (xy 80.296586 -375.434947) (xy 80.300315 -375.421682) (xy 80.300576 -375.414794)
			(xy 80.300576 -374.665494) (xy 80.300348 -374.658602) (xy 80.296602 -374.645336) (xy 80.29321 -374.639332)
			(xy 80.276838 -374.610995) (xy 80.251099 -374.550824) (xy 80.233677 -374.48774) (xy 80.224889 -374.422887)
			(xy 76.795073 -374.422887) (xy 76.786286 -374.487731) (xy 76.768866 -374.550809) (xy 76.743129 -374.610976)
			(xy 76.726796 -374.639332) (xy 76.72347 -374.645351) (xy 76.719871 -374.658619) (xy 76.719684 -374.665494)
			(xy 76.719684 -375.414794) (xy 76.71988 -375.421667) (xy 76.723486 -375.43493) (xy 76.726796 -375.440956)
			(xy 76.743158 -375.469299) (xy 76.768897 -375.529469) (xy 76.78632 -375.592552) (xy 76.795109 -375.657403)
			(xy 76.795105 -375.722848) (xy 76.786309 -375.787699) (xy 76.76888 -375.85078) (xy 76.743134 -375.910947)
			(xy 76.726796 -375.939304) (xy 76.72348 -375.945328) (xy 76.719875 -375.958592) (xy 76.719684 -375.965466)
			(xy 76.719684 -376.25147) (xy 76.719212 -376.261637) (xy 76.711441 -376.280427) (xy 76.69707 -376.294812)
			(xy 76.678288 -376.302602) (xy 76.668122 -376.303032) (xy 75.951842 -376.303032) (xy 75.941669 -376.302601)
			(xy 75.92287 -376.294824) (xy 75.908482 -376.28044) (xy 75.900701 -376.261643) (xy 75.90028 -376.25147)
			(xy 75.90028 -375.965466) (xy 75.900104 -375.958592) (xy 75.896485 -375.945329) (xy 75.893168 -375.939304)
			(xy 75.876855 -375.910934) (xy 75.851107 -375.850771) (xy 75.833677 -375.787694) (xy 75.82488 -375.722846)
			(xy 75.824877 -375.657405) (xy 75.833667 -375.592557) (xy 75.85109 -375.529478) (xy 75.876832 -375.469312)
			(xy 75.893168 -375.440956) (xy 75.896496 -375.434938) (xy 75.900093 -375.421669) (xy 75.90028 -375.414794)
			(xy 75.90028 -374.665494) (xy 75.900093 -374.65862) (xy 75.896481 -374.645358) (xy 75.893168 -374.639332)
			(xy 75.876794 -374.610996) (xy 75.851052 -374.550825) (xy 75.833628 -374.48774) (xy 75.824839 -374.422887)
			(xy 72.395037 -374.422887) (xy 72.386249 -374.487731) (xy 72.368827 -374.55081) (xy 72.343089 -374.610976)
			(xy 72.326754 -374.639332) (xy 72.323379 -374.645342) (xy 72.31965 -374.658606) (xy 72.319388 -374.665494)
			(xy 72.319388 -375.414794) (xy 72.31959 -375.421689) (xy 72.323339 -375.434962) (xy 72.326754 -375.440956)
			(xy 72.343117 -375.469298) (xy 72.368859 -375.529468) (xy 72.386283 -375.592551) (xy 72.395073 -375.657403)
			(xy 72.395069 -375.722848) (xy 72.386272 -375.787699) (xy 72.368842 -375.850781) (xy 72.343094 -375.910948)
			(xy 72.326754 -375.939304) (xy 72.323389 -375.945319) (xy 72.319654 -375.958579) (xy 72.319388 -375.965466)
			(xy 72.319388 -376.25147) (xy 72.31885 -376.261591) (xy 72.311137 -376.280307) (xy 72.296867 -376.294663)
			(xy 72.278198 -376.302488) (xy 72.26808 -376.303032) (xy 71.5518 -376.303032) (xy 71.54165 -376.302579)
			(xy 71.522904 -376.294789) (xy 71.508582 -376.280403) (xy 71.500876 -376.261622) (xy 71.500492 -376.25147)
			(xy 71.500492 -375.965466) (xy 71.500234 -375.958577) (xy 71.496509 -375.94531) (xy 71.493126 -375.939304)
			(xy 71.476814 -375.910934) (xy 71.451069 -375.85077) (xy 71.43364 -375.787693) (xy 71.424844 -375.722846)
			(xy 71.424841 -375.657405) (xy 71.43363 -375.592558) (xy 71.451052 -375.529479) (xy 71.476791 -375.469312)
			(xy 71.493126 -375.440956) (xy 71.496504 -375.434948) (xy 71.500231 -375.421682) (xy 71.500492 -375.414794)
			(xy 71.500492 -374.665494) (xy 71.500262 -374.658602) (xy 71.496518 -374.645336) (xy 71.493126 -374.639332)
			(xy 71.476753 -374.610995) (xy 71.451014 -374.550824) (xy 71.433592 -374.48774) (xy 71.424803 -374.422887)
			(xy 51.556158 -374.422887) (xy 51.556158 -375.449846) (xy 56.712102 -375.449846) (xy 56.716173 -375.394224)
			(xy 56.728299 -375.339787) (xy 56.748222 -375.287696) (xy 56.775518 -375.239061) (xy 56.809604 -375.194918)
			(xy 56.849753 -375.156209) (xy 56.895111 -375.123758) (xy 56.944711 -375.098257) (xy 56.997495 -375.08025)
			(xy 57.052338 -375.07012) (xy 57.108072 -375.068083) (xy 57.163509 -375.074183) (xy 57.191673 -375.081546)
			(xy 58.879484 -375.081546) (xy 58.883555 -375.025924) (xy 58.895681 -374.971487) (xy 58.915604 -374.919396)
			(xy 58.9429 -374.870761) (xy 58.976986 -374.826618) (xy 59.017135 -374.787909) (xy 59.062493 -374.755458)
			(xy 59.112093 -374.729957) (xy 59.164877 -374.71195) (xy 59.21972 -374.70182) (xy 59.275454 -374.699783)
			(xy 59.330891 -374.705883) (xy 59.384848 -374.719989) (xy 59.436177 -374.741801) (xy 59.483783 -374.770855)
			(xy 59.526651 -374.80653) (xy 59.563868 -374.848067) (xy 59.594641 -374.89458) (xy 59.618313 -374.945077)
			(xy 59.634381 -374.998484) (xy 59.642501 -375.05366) (xy 59.64301 -375.081546) (xy 59.642501 -375.109432)
			(xy 59.634381 -375.164608) (xy 59.618313 -375.218015) (xy 59.594641 -375.268512) (xy 59.563868 -375.315025)
			(xy 59.526651 -375.356562) (xy 59.483783 -375.392237) (xy 59.436177 -375.421291) (xy 59.384848 -375.443103)
			(xy 59.330891 -375.457209) (xy 59.275454 -375.463309) (xy 59.21972 -375.461272) (xy 59.164877 -375.451142)
			(xy 59.112093 -375.433135) (xy 59.062493 -375.407634) (xy 59.017135 -375.375183) (xy 58.976986 -375.336474)
			(xy 58.9429 -375.292331) (xy 58.915604 -375.243696) (xy 58.895681 -375.191605) (xy 58.883555 -375.137168)
			(xy 58.879484 -375.081546) (xy 57.191673 -375.081546) (xy 57.217466 -375.088289) (xy 57.268795 -375.110101)
			(xy 57.316401 -375.139155) (xy 57.359269 -375.17483) (xy 57.396486 -375.216367) (xy 57.427259 -375.26288)
			(xy 57.450931 -375.313377) (xy 57.466999 -375.366784) (xy 57.475119 -375.42196) (xy 57.475628 -375.449846)
			(xy 57.475119 -375.477732) (xy 57.466999 -375.532908) (xy 57.450931 -375.586315) (xy 57.427259 -375.636812)
			(xy 57.396486 -375.683325) (xy 57.359269 -375.724862) (xy 57.316401 -375.760537) (xy 57.268795 -375.789591)
			(xy 57.217466 -375.811403) (xy 57.163509 -375.825509) (xy 57.108072 -375.831609) (xy 57.052338 -375.829572)
			(xy 56.997495 -375.819442) (xy 56.944711 -375.801435) (xy 56.895111 -375.775934) (xy 56.849753 -375.743483)
			(xy 56.809604 -375.704774) (xy 56.775518 -375.660631) (xy 56.748222 -375.611996) (xy 56.728299 -375.559905)
			(xy 56.716173 -375.505468) (xy 56.712102 -375.449846) (xy 51.556158 -375.449846) (xy 51.556158 -376.69597)
			(xy 54.986172 -376.69597) (xy 54.990243 -376.640348) (xy 55.002369 -376.585911) (xy 55.022292 -376.53382)
			(xy 55.049588 -376.485185) (xy 55.083674 -376.441042) (xy 55.123823 -376.402333) (xy 55.169181 -376.369882)
			(xy 55.218781 -376.344381) (xy 55.271565 -376.326374) (xy 55.326408 -376.316244) (xy 55.382142 -376.314207)
			(xy 55.437579 -376.320307) (xy 55.491536 -376.334413) (xy 55.518106 -376.345704) (xy 59.301886 -376.345704)
			(xy 59.305957 -376.290082) (xy 59.318083 -376.235645) (xy 59.338006 -376.183554) (xy 59.365302 -376.134919)
			(xy 59.399388 -376.090776) (xy 59.439537 -376.052067) (xy 59.484895 -376.019616) (xy 59.534495 -375.994115)
			(xy 59.587279 -375.976108) (xy 59.642122 -375.965978) (xy 59.697856 -375.963941) (xy 59.753293 -375.970041)
			(xy 59.80725 -375.984147) (xy 59.858579 -376.005959) (xy 59.906185 -376.035013) (xy 59.949053 -376.070688)
			(xy 59.98627 -376.112225) (xy 60.017043 -376.158738) (xy 60.040715 -376.209235) (xy 60.056783 -376.262642)
			(xy 60.064903 -376.317818) (xy 60.065412 -376.345704) (xy 60.064903 -376.37359) (xy 60.056783 -376.428766)
			(xy 60.040715 -376.482173) (xy 60.017043 -376.53267) (xy 59.98627 -376.579183) (xy 59.949053 -376.62072)
			(xy 59.906185 -376.656395) (xy 59.858579 -376.685449) (xy 59.80725 -376.707261) (xy 59.753293 -376.721367)
			(xy 59.697856 -376.727467) (xy 59.642122 -376.72543) (xy 59.587279 -376.7153) (xy 59.534495 -376.697293)
			(xy 59.484895 -376.671792) (xy 59.439537 -376.639341) (xy 59.399388 -376.600632) (xy 59.365302 -376.556489)
			(xy 59.338006 -376.507854) (xy 59.318083 -376.455763) (xy 59.305957 -376.401326) (xy 59.301886 -376.345704)
			(xy 55.518106 -376.345704) (xy 55.542865 -376.356225) (xy 55.590471 -376.385279) (xy 55.633339 -376.420954)
			(xy 55.670556 -376.462491) (xy 55.701329 -376.509004) (xy 55.725001 -376.559501) (xy 55.741069 -376.612908)
			(xy 55.749189 -376.668084) (xy 55.749698 -376.69597) (xy 55.749189 -376.723856) (xy 55.741069 -376.779032)
			(xy 55.727863 -376.822925) (xy 73.624724 -376.822925) (xy 73.624724 -376.757482) (xy 73.633516 -376.692633)
			(xy 73.650941 -376.629553) (xy 73.676683 -376.569386) (xy 73.69302 -376.54103) (xy 73.696325 -376.535001)
			(xy 73.699937 -376.521741) (xy 73.700132 -376.514868) (xy 73.700132 -375.765568) (xy 73.699948 -375.758694)
			(xy 73.696334 -375.745432) (xy 73.69302 -375.739406) (xy 73.67671 -375.711035) (xy 73.650965 -375.650871)
			(xy 73.633536 -375.587794) (xy 73.62474 -375.522948) (xy 73.624737 -375.457507) (xy 73.633525 -375.39266)
			(xy 73.650947 -375.329581) (xy 73.676685 -375.269414) (xy 73.69302 -375.241058) (xy 73.696351 -375.235041)
			(xy 73.699946 -375.221771) (xy 73.700132 -375.214896) (xy 73.700132 -374.928638) (xy 73.700595 -374.91847)
			(xy 73.708366 -374.899677) (xy 73.72274 -374.885291) (xy 73.741526 -374.877504) (xy 73.751694 -374.877076)
			(xy 74.467974 -374.877076) (xy 74.478149 -374.877486) (xy 74.49695 -374.88527) (xy 74.511337 -374.89966)
			(xy 74.519116 -374.918463) (xy 74.519536 -374.928638) (xy 74.519536 -375.214896) (xy 74.519725 -375.22177)
			(xy 74.523335 -375.235032) (xy 74.526648 -375.241058) (xy 74.543013 -375.269399) (xy 74.568755 -375.329569)
			(xy 74.586179 -375.392652) (xy 74.594969 -375.457505) (xy 74.594965 -375.52295) (xy 74.586168 -375.587801)
			(xy 74.568737 -375.650883) (xy 74.542988 -375.71105) (xy 74.526648 -375.739406) (xy 74.523335 -375.745432)
			(xy 74.519728 -375.758695) (xy 74.519536 -375.765568) (xy 74.519536 -376.514868) (xy 74.519736 -376.521741)
			(xy 74.523338 -376.535004) (xy 74.526648 -376.54103) (xy 74.542989 -376.569384) (xy 74.568733 -376.629551)
			(xy 74.58616 -376.692632) (xy 74.594953 -376.757482) (xy 74.594952 -376.822925) (xy 78.02476 -376.822925)
			(xy 78.02476 -376.757482) (xy 78.033553 -376.692632) (xy 78.05098 -376.629552) (xy 78.076724 -376.569386)
			(xy 78.093062 -376.54103) (xy 78.096417 -376.53501) (xy 78.100158 -376.521754) (xy 78.100428 -376.514868)
			(xy 78.100428 -375.765568) (xy 78.1002 -375.758675) (xy 78.096468 -375.745403) (xy 78.093062 -375.739406)
			(xy 78.076751 -375.711035) (xy 78.051003 -375.650872) (xy 78.033573 -375.587795) (xy 78.024776 -375.522948)
			(xy 78.024773 -375.457507) (xy 78.033562 -375.392659) (xy 78.050985 -375.32958) (xy 78.076726 -375.269414)
			(xy 78.093062 -375.241058) (xy 78.096442 -375.235051) (xy 78.100167 -375.221784) (xy 78.100428 -375.214896)
			(xy 78.100428 -374.928638) (xy 78.100958 -374.918515) (xy 78.108671 -374.899797) (xy 78.122944 -374.88544)
			(xy 78.141616 -374.877618) (xy 78.151736 -374.877076) (xy 78.868016 -374.877076) (xy 78.878168 -374.877508)
			(xy 78.896916 -374.885304) (xy 78.911238 -374.899697) (xy 78.918942 -374.918484) (xy 78.919324 -374.928638)
			(xy 78.919324 -375.214896) (xy 78.919556 -375.221788) (xy 78.923299 -375.235054) (xy 78.92669 -375.241058)
			(xy 78.943054 -375.2694) (xy 78.968793 -375.32957) (xy 78.986216 -375.392653) (xy 78.995005 -375.457505)
			(xy 78.995001 -375.52295) (xy 78.986205 -375.587801) (xy 78.968775 -375.650882) (xy 78.943029 -375.711049)
			(xy 78.92669 -375.739406) (xy 78.923327 -375.745422) (xy 78.91959 -375.758681) (xy 78.919324 -375.765568)
			(xy 78.919324 -376.514868) (xy 78.919566 -376.521759) (xy 78.923302 -376.535025) (xy 78.92669 -376.54103)
			(xy 78.94303 -376.569385) (xy 78.968772 -376.629552) (xy 78.986197 -376.692632) (xy 78.994989 -376.757482)
			(xy 82.42481 -376.757482) (xy 82.433602 -376.692633) (xy 82.451026 -376.629553) (xy 82.476768 -376.569387)
			(xy 82.493104 -376.54103) (xy 82.496408 -376.535) (xy 82.50002 -376.52174) (xy 82.500216 -376.514868)
			(xy 82.500216 -375.765568) (xy 82.500034 -375.758694) (xy 82.496419 -375.745431) (xy 82.493104 -375.739406)
			(xy 82.476795 -375.711034) (xy 82.45105 -375.650871) (xy 82.433622 -375.587794) (xy 82.424826 -375.522948)
			(xy 82.424823 -375.457507) (xy 82.433611 -375.39266) (xy 82.451032 -375.329581) (xy 82.47677 -375.269415)
			(xy 82.493104 -375.241058) (xy 82.496434 -375.235041) (xy 82.50003 -375.221771) (xy 82.500216 -375.214896)
			(xy 82.500216 -374.928638) (xy 82.500694 -374.918472) (xy 82.508463 -374.899682) (xy 82.522832 -374.885297)
			(xy 82.541612 -374.877506) (xy 82.551778 -374.877076) (xy 83.268058 -374.877076) (xy 83.278232 -374.877499)
			(xy 83.297033 -374.885277) (xy 83.31142 -374.899664) (xy 83.3192 -374.918464) (xy 83.31962 -374.928638)
			(xy 83.31962 -375.214896) (xy 83.319811 -375.221769) (xy 83.32342 -375.235032) (xy 83.326732 -375.241058)
			(xy 83.343097 -375.269399) (xy 83.36884 -375.329569) (xy 83.386265 -375.392652) (xy 83.395055 -375.457505)
			(xy 83.395051 -375.52295) (xy 83.386254 -375.587802) (xy 83.368822 -375.650883) (xy 83.343072 -375.71105)
			(xy 83.326732 -375.739406) (xy 83.323418 -375.745431) (xy 83.319812 -375.758694) (xy 83.31962 -375.765568)
			(xy 83.31962 -376.514868) (xy 83.319822 -376.521741) (xy 83.323423 -376.535003) (xy 83.326732 -376.54103)
			(xy 83.343074 -376.569384) (xy 83.368819 -376.629551) (xy 83.386246 -376.692631) (xy 83.395039 -376.757482)
			(xy 86.824846 -376.757482) (xy 86.833639 -376.692633) (xy 86.851065 -376.629553) (xy 86.876809 -376.569386)
			(xy 86.893146 -376.54103) (xy 86.896499 -376.535009) (xy 86.900242 -376.521753) (xy 86.900512 -376.514868)
			(xy 86.900512 -375.765568) (xy 86.900286 -375.758675) (xy 86.896553 -375.745402) (xy 86.893146 -375.739406)
			(xy 86.876836 -375.711035) (xy 86.851089 -375.650872) (xy 86.833659 -375.587795) (xy 86.824863 -375.522948)
			(xy 86.824859 -375.457507) (xy 86.833648 -375.392659) (xy 86.851071 -375.32958) (xy 86.876811 -375.269414)
			(xy 86.893146 -375.241058) (xy 86.896524 -375.23505) (xy 86.900251 -375.221784) (xy 86.900512 -375.214896)
			(xy 86.900512 -374.928638) (xy 86.901057 -374.918517) (xy 86.908767 -374.899802) (xy 86.923035 -374.885446)
			(xy 86.941702 -374.87762) (xy 86.95182 -374.877076) (xy 87.6681 -374.877076) (xy 87.678251 -374.877521)
			(xy 87.696999 -374.885312) (xy 87.711321 -374.899701) (xy 87.719025 -374.918485) (xy 87.719408 -374.928638)
			(xy 87.719408 -375.214896) (xy 87.719642 -375.221787) (xy 87.723384 -375.235053) (xy 87.726774 -375.241058)
			(xy 87.743138 -375.269399) (xy 87.768879 -375.32957) (xy 87.786302 -375.392653) (xy 87.795091 -375.457505)
			(xy 87.795087 -375.52295) (xy 87.786291 -375.587801) (xy 87.768861 -375.650882) (xy 87.752065 -375.69013)
			(xy 89.023706 -375.69013) (xy 89.027697 -375.627963) (xy 89.039606 -375.566816) (xy 89.059235 -375.507695)
			(xy 89.086264 -375.451569) (xy 89.120248 -375.39936) (xy 89.16063 -375.351925) (xy 89.206746 -375.310044)
			(xy 89.257838 -375.274404) (xy 89.313069 -375.24559) (xy 89.371531 -375.224076) (xy 89.432265 -375.210214)
			(xy 89.494272 -375.204232) (xy 89.556535 -375.206228) (xy 89.618032 -375.216171) (xy 89.677753 -375.233895)
			(xy 89.734716 -375.259112) (xy 89.787987 -375.291405) (xy 89.836692 -375.330245) (xy 89.880029 -375.374995)
			(xy 89.917289 -375.424919) (xy 89.947858 -375.479198) (xy 89.952325 -375.490232) (xy 91.223854 -375.490232)
			(xy 91.227845 -375.428065) (xy 91.239754 -375.366918) (xy 91.259383 -375.307797) (xy 91.286412 -375.251671)
			(xy 91.320396 -375.199462) (xy 91.360778 -375.152027) (xy 91.406894 -375.110146) (xy 91.457986 -375.074506)
			(xy 91.513217 -375.045692) (xy 91.571679 -375.024178) (xy 91.632413 -375.010316) (xy 91.69442 -375.004334)
			(xy 91.756683 -375.00633) (xy 91.81818 -375.016273) (xy 91.877901 -375.033997) (xy 91.934864 -375.059214)
			(xy 91.988135 -375.091507) (xy 92.03684 -375.130347) (xy 92.080177 -375.175097) (xy 92.108742 -375.213371)
			(xy 104.681961 -375.213371) (xy 104.681961 -375.153429) (xy 104.689785 -375.094001) (xy 104.7053 -375.036103)
			(xy 104.72824 -374.980725) (xy 104.758212 -374.928815) (xy 104.794703 -374.881262) (xy 104.837089 -374.838879)
			(xy 104.884645 -374.802391) (xy 104.936557 -374.772424) (xy 104.991937 -374.749489) (xy 105.049837 -374.733978)
			(xy 105.109265 -374.726159) (xy 105.139236 -374.725692) (xy 106.002836 -374.725692) (xy 106.032802 -374.726184)
			(xy 106.092221 -374.734011) (xy 106.15011 -374.749527) (xy 106.205479 -374.772465) (xy 106.25738 -374.802434)
			(xy 106.304926 -374.838921) (xy 106.347303 -374.881301) (xy 106.383786 -374.92885) (xy 106.413751 -374.980753)
			(xy 106.436685 -375.036124) (xy 106.452196 -375.094014) (xy 106.460018 -375.153434) (xy 106.460018 -375.213366)
			(xy 106.452196 -375.272786) (xy 106.436685 -375.330676) (xy 106.413751 -375.386047) (xy 106.383786 -375.43795)
			(xy 106.347303 -375.485499) (xy 106.304926 -375.527879) (xy 106.25738 -375.564366) (xy 106.205479 -375.594335)
			(xy 106.15011 -375.617273) (xy 106.092221 -375.632789) (xy 106.032802 -375.640616) (xy 106.002836 -375.641108)
			(xy 105.139236 -375.641108) (xy 105.109265 -375.640641) (xy 105.049837 -375.632822) (xy 104.991937 -375.617311)
			(xy 104.936557 -375.594376) (xy 104.884645 -375.564409) (xy 104.837089 -375.527921) (xy 104.794703 -375.485538)
			(xy 104.758212 -375.437985) (xy 104.72824 -375.386075) (xy 104.7053 -375.330697) (xy 104.689785 -375.272799)
			(xy 104.681961 -375.213371) (xy 92.108742 -375.213371) (xy 92.117437 -375.225021) (xy 92.148006 -375.2793)
			(xy 92.171384 -375.337043) (xy 92.187185 -375.397301) (xy 92.195151 -375.459084) (xy 92.19565 -375.490232)
			(xy 92.195151 -375.52138) (xy 92.187185 -375.583163) (xy 92.171384 -375.643421) (xy 92.148006 -375.701164)
			(xy 92.117437 -375.755443) (xy 92.080177 -375.805367) (xy 92.03684 -375.850117) (xy 91.988135 -375.888957)
			(xy 91.934864 -375.92125) (xy 91.877901 -375.946467) (xy 91.81818 -375.964191) (xy 91.756683 -375.974134)
			(xy 91.69442 -375.97613) (xy 91.632413 -375.970148) (xy 91.571679 -375.956286) (xy 91.513217 -375.934772)
			(xy 91.457986 -375.905958) (xy 91.406894 -375.870318) (xy 91.360778 -375.828437) (xy 91.320396 -375.781002)
			(xy 91.286412 -375.728793) (xy 91.259383 -375.672667) (xy 91.239754 -375.613546) (xy 91.227845 -375.552399)
			(xy 91.223854 -375.490232) (xy 89.952325 -375.490232) (xy 89.971236 -375.536941) (xy 89.987037 -375.597199)
			(xy 89.995003 -375.658982) (xy 89.995502 -375.69013) (xy 89.995003 -375.721278) (xy 89.987037 -375.783061)
			(xy 89.971236 -375.843319) (xy 89.947858 -375.901062) (xy 89.917289 -375.955341) (xy 89.880029 -376.005265)
			(xy 89.836692 -376.050015) (xy 89.787987 -376.088855) (xy 89.734716 -376.121148) (xy 89.677753 -376.146365)
			(xy 89.618032 -376.164089) (xy 89.556535 -376.174032) (xy 89.494272 -376.176028) (xy 89.432265 -376.170046)
			(xy 89.371531 -376.156184) (xy 89.313069 -376.13467) (xy 89.257838 -376.105856) (xy 89.206746 -376.070216)
			(xy 89.16063 -376.028335) (xy 89.120248 -375.9809) (xy 89.086264 -375.928691) (xy 89.059235 -375.872565)
			(xy 89.039606 -375.813444) (xy 89.027697 -375.752297) (xy 89.023706 -375.69013) (xy 87.752065 -375.69013)
			(xy 87.743113 -375.71105) (xy 87.726774 -375.739406) (xy 87.72341 -375.745421) (xy 87.719674 -375.758681)
			(xy 87.719408 -375.765568) (xy 87.719408 -376.514868) (xy 87.719653 -376.521758) (xy 87.723387 -376.535024)
			(xy 87.726774 -376.54103) (xy 87.743114 -376.569384) (xy 87.768857 -376.629552) (xy 87.786283 -376.692632)
			(xy 87.795075 -376.757482) (xy 87.795075 -376.790204) (xy 91.223854 -376.790204) (xy 91.227845 -376.728037)
			(xy 91.239754 -376.66689) (xy 91.259383 -376.607769) (xy 91.286412 -376.551643) (xy 91.320396 -376.499434)
			(xy 91.360778 -376.451999) (xy 91.406894 -376.410118) (xy 91.457986 -376.374478) (xy 91.513217 -376.345664)
			(xy 91.571679 -376.32415) (xy 91.632413 -376.310288) (xy 91.69442 -376.304306) (xy 91.756683 -376.306302)
			(xy 91.81818 -376.316245) (xy 91.877901 -376.333969) (xy 91.934864 -376.359186) (xy 91.988135 -376.391479)
			(xy 92.03684 -376.430319) (xy 92.080177 -376.475069) (xy 92.087322 -376.484642) (xy 99.998528 -376.484642)
			(xy 100.002599 -376.42902) (xy 100.014725 -376.374583) (xy 100.034648 -376.322492) (xy 100.061944 -376.273857)
			(xy 100.09603 -376.229714) (xy 100.136179 -376.191005) (xy 100.181537 -376.158554) (xy 100.231137 -376.133053)
			(xy 100.283921 -376.115046) (xy 100.338764 -376.104916) (xy 100.394498 -376.102879) (xy 100.449935 -376.108979)
			(xy 100.503892 -376.123085) (xy 100.555221 -376.144897) (xy 100.602827 -376.173951) (xy 100.645695 -376.209626)
			(xy 100.682912 -376.251163) (xy 100.713685 -376.297676) (xy 100.737357 -376.348173) (xy 100.753425 -376.40158)
			(xy 100.761545 -376.456756) (xy 100.762054 -376.484642) (xy 100.761545 -376.512528) (xy 100.753425 -376.567704)
			(xy 100.737357 -376.621111) (xy 100.713685 -376.671608) (xy 100.682912 -376.718121) (xy 100.645695 -376.759658)
			(xy 100.602827 -376.795333) (xy 100.557617 -376.822925) (xy 117.624881 -376.822925) (xy 117.624881 -376.757482)
			(xy 117.633674 -376.692632) (xy 117.651102 -376.629552) (xy 117.676847 -376.569386) (xy 117.693186 -376.54103)
			(xy 117.696535 -376.535007) (xy 117.700281 -376.521753) (xy 117.700552 -376.514868) (xy 117.700552 -375.765568)
			(xy 117.700321 -375.758675) (xy 117.696591 -375.745403) (xy 117.693186 -375.739406) (xy 117.676874 -375.711035)
			(xy 117.651125 -375.650873) (xy 117.633694 -375.587795) (xy 117.624897 -375.522948) (xy 117.624893 -375.457507)
			(xy 117.633683 -375.392658) (xy 117.651107 -375.329579) (xy 117.676849 -375.269414) (xy 117.693186 -375.241058)
			(xy 117.69656 -375.235048) (xy 117.70029 -375.221784) (xy 117.700552 -375.214896) (xy 117.700552 -374.928638)
			(xy 117.701058 -374.918512) (xy 117.708776 -374.89979) (xy 117.723056 -374.885432) (xy 117.741737 -374.877613)
			(xy 117.75186 -374.877076) (xy 118.46814 -374.877076) (xy 118.478294 -374.877488) (xy 118.497042 -374.885293)
			(xy 118.511363 -374.899691) (xy 118.519066 -374.918482) (xy 118.519448 -374.928638) (xy 118.519448 -375.214896)
			(xy 118.519655 -375.221791) (xy 118.523401 -375.235063) (xy 118.526814 -375.241058) (xy 118.54318 -375.269399)
			(xy 118.568924 -375.329568) (xy 118.586349 -375.392652) (xy 118.595139 -375.457505) (xy 118.595136 -375.52295)
			(xy 118.586338 -375.587802) (xy 118.568906 -375.650883) (xy 118.543155 -375.71105) (xy 118.526814 -375.739406)
			(xy 118.523453 -375.745423) (xy 118.519714 -375.758682) (xy 118.519448 -375.765568) (xy 118.519448 -376.514868)
			(xy 118.519665 -376.521762) (xy 118.523404 -376.535034) (xy 118.526814 -376.54103) (xy 118.543156 -376.569384)
			(xy 118.568902 -376.629551) (xy 118.58633 -376.692631) (xy 118.595123 -376.757482) (xy 118.595123 -376.822925)
			(xy 122.024931 -376.822925) (xy 122.024931 -376.757482) (xy 122.033723 -376.692633) (xy 122.051148 -376.629553)
			(xy 122.076891 -376.569386) (xy 122.093228 -376.54103) (xy 122.096534 -376.535001) (xy 122.100145 -376.521741)
			(xy 122.10034 -376.514868) (xy 122.10034 -375.765568) (xy 122.100155 -375.758694) (xy 122.096541 -375.745432)
			(xy 122.093228 -375.739406) (xy 122.076918 -375.711035) (xy 122.051172 -375.650871) (xy 122.033743 -375.587794)
			(xy 122.024947 -375.522948) (xy 122.024943 -375.457507) (xy 122.033732 -375.392659) (xy 122.051154 -375.32958)
			(xy 122.076893 -375.269414) (xy 122.093228 -375.241058) (xy 122.09656 -375.235042) (xy 122.100154 -375.221771)
			(xy 122.10034 -375.214896) (xy 122.10034 -374.928638) (xy 122.100795 -374.918469) (xy 122.108568 -374.899674)
			(xy 122.122944 -374.885288) (xy 122.141733 -374.877502) (xy 122.151902 -374.877076) (xy 122.868182 -374.877076)
			(xy 122.878357 -374.877479) (xy 122.897159 -374.885265) (xy 122.911546 -374.899658) (xy 122.919325 -374.918463)
			(xy 122.919744 -374.928638) (xy 122.919744 -375.214896) (xy 122.919932 -375.22177) (xy 122.923542 -375.235033)
			(xy 122.926856 -375.241058) (xy 122.943221 -375.269399) (xy 122.968962 -375.329569) (xy 122.986386 -375.392653)
			(xy 122.995176 -375.457505) (xy 122.995172 -375.52295) (xy 122.986375 -375.587801) (xy 122.968944 -375.650883)
			(xy 122.943196 -375.71105) (xy 122.926856 -375.739406) (xy 122.923544 -375.745432) (xy 122.919936 -375.758695)
			(xy 122.919744 -375.765568) (xy 122.919744 -376.514868) (xy 122.919943 -376.521741) (xy 122.923546 -376.535004)
			(xy 122.926856 -376.54103) (xy 122.943197 -376.569384) (xy 122.968941 -376.629551) (xy 122.986367 -376.692632)
			(xy 122.99516 -376.757482) (xy 122.995159 -376.822925) (xy 126.424967 -376.822925) (xy 126.424967 -376.757482)
			(xy 126.43376 -376.692632) (xy 126.451187 -376.629552) (xy 126.476932 -376.569386) (xy 126.49327 -376.54103)
			(xy 126.496625 -376.535011) (xy 126.500366 -376.521754) (xy 126.500636 -376.514868) (xy 126.500636 -375.765568)
			(xy 126.500407 -375.758675) (xy 126.496676 -375.745403) (xy 126.49327 -375.739406) (xy 126.476959 -375.711035)
			(xy 126.451211 -375.650872) (xy 126.43378 -375.587795) (xy 126.424983 -375.522948) (xy 126.42498 -375.457507)
			(xy 126.433769 -375.392659) (xy 126.451193 -375.32958) (xy 126.476934 -375.269414) (xy 126.49327 -375.241058)
			(xy 126.496651 -375.235051) (xy 126.500376 -375.221784) (xy 126.500636 -375.214896) (xy 126.500636 -374.928638)
			(xy 126.501158 -374.918514) (xy 126.508872 -374.899795) (xy 126.523148 -374.885437) (xy 126.541823 -374.877616)
			(xy 126.551944 -374.877076) (xy 127.268224 -374.877076) (xy 127.278377 -374.877501) (xy 127.297125 -374.8853)
			(xy 127.311447 -374.899695) (xy 127.31915 -374.918483) (xy 127.319532 -374.928638) (xy 127.319532 -375.214896)
			(xy 127.319763 -375.221788) (xy 127.323506 -375.235054) (xy 127.326898 -375.241058) (xy 127.343261 -375.2694)
			(xy 127.369001 -375.32957) (xy 127.386423 -375.392653) (xy 127.395212 -375.457505) (xy 127.395208 -375.52295)
			(xy 127.386412 -375.587801) (xy 127.368983 -375.650882) (xy 127.343236 -375.711049) (xy 127.326898 -375.739406)
			(xy 127.323535 -375.745422) (xy 127.319798 -375.758681) (xy 127.319532 -375.765568) (xy 127.319532 -376.514868)
			(xy 127.319751 -376.521762) (xy 127.323489 -376.535034) (xy 127.326898 -376.54103) (xy 127.343238 -376.569385)
			(xy 127.368979 -376.629552) (xy 127.386404 -376.692633) (xy 127.395196 -376.757482) (xy 127.395195 -376.822925)
			(xy 130.825017 -376.822925) (xy 130.825017 -376.757482) (xy 130.833809 -376.692633) (xy 130.851234 -376.629553)
			(xy 130.876976 -376.569386) (xy 130.893312 -376.54103) (xy 130.896617 -376.535001) (xy 130.900229 -376.521741)
			(xy 130.900424 -376.514868) (xy 130.900424 -375.765568) (xy 130.900241 -375.758694) (xy 130.896626 -375.745431)
			(xy 130.893312 -375.739406) (xy 130.877003 -375.711035) (xy 130.851258 -375.650871) (xy 130.833829 -375.587794)
			(xy 130.825033 -375.522948) (xy 130.82503 -375.457507) (xy 130.833818 -375.39266) (xy 130.851239 -375.329581)
			(xy 130.876978 -375.269414) (xy 130.893312 -375.241058) (xy 130.896643 -375.235041) (xy 130.900238 -375.221771)
			(xy 130.900424 -375.214896) (xy 130.900424 -374.928638) (xy 130.900895 -374.918471) (xy 130.908665 -374.899679)
			(xy 130.923036 -374.885294) (xy 130.941819 -374.877505) (xy 130.951986 -374.877076) (xy 131.668266 -374.877076)
			(xy 131.67844 -374.877493) (xy 131.697241 -374.885274) (xy 131.711629 -374.899662) (xy 131.719408 -374.918464)
			(xy 131.719828 -374.928638) (xy 131.719828 -375.214896) (xy 131.720018 -375.221769) (xy 131.723627 -375.235032)
			(xy 131.72694 -375.241058) (xy 131.743305 -375.269399) (xy 131.769048 -375.329569) (xy 131.786472 -375.392652)
			(xy 131.795262 -375.457505) (xy 131.795258 -375.52295) (xy 131.786461 -375.587802) (xy 131.769029 -375.650883)
			(xy 131.752233 -375.69013) (xy 133.023872 -375.69013) (xy 133.027863 -375.627963) (xy 133.039772 -375.566816)
			(xy 133.059401 -375.507695) (xy 133.08643 -375.451569) (xy 133.120414 -375.39936) (xy 133.160796 -375.351925)
			(xy 133.206912 -375.310044) (xy 133.258004 -375.274404) (xy 133.313235 -375.24559) (xy 133.371697 -375.224076)
			(xy 133.432431 -375.210214) (xy 133.494438 -375.204232) (xy 133.556701 -375.206228) (xy 133.618198 -375.216171)
			(xy 133.677919 -375.233895) (xy 133.734882 -375.259112) (xy 133.788153 -375.291405) (xy 133.836858 -375.330245)
			(xy 133.880195 -375.374995) (xy 133.917455 -375.424919) (xy 133.948024 -375.479198) (xy 133.952491 -375.490232)
			(xy 135.22402 -375.490232) (xy 135.228011 -375.428065) (xy 135.23992 -375.366918) (xy 135.259549 -375.307797)
			(xy 135.286578 -375.251671) (xy 135.320562 -375.199462) (xy 135.360944 -375.152027) (xy 135.40706 -375.110146)
			(xy 135.458152 -375.074506) (xy 135.513383 -375.045692) (xy 135.571845 -375.024178) (xy 135.632579 -375.010316)
			(xy 135.694586 -375.004334) (xy 135.756849 -375.00633) (xy 135.818346 -375.016273) (xy 135.878067 -375.033997)
			(xy 135.93503 -375.059214) (xy 135.988301 -375.091507) (xy 136.037006 -375.130347) (xy 136.080343 -375.175097)
			(xy 136.117603 -375.225021) (xy 136.148172 -375.2793) (xy 136.17155 -375.337043) (xy 136.187351 -375.397301)
			(xy 136.195317 -375.459084) (xy 136.195816 -375.490232) (xy 136.195317 -375.52138) (xy 136.187351 -375.583163)
			(xy 136.17155 -375.643421) (xy 136.148172 -375.701164) (xy 136.117603 -375.755443) (xy 136.080343 -375.805367)
			(xy 136.037006 -375.850117) (xy 135.988301 -375.888957) (xy 135.93503 -375.92125) (xy 135.878067 -375.946467)
			(xy 135.818346 -375.964191) (xy 135.756849 -375.974134) (xy 135.694586 -375.97613) (xy 135.632579 -375.970148)
			(xy 135.571845 -375.956286) (xy 135.513383 -375.934772) (xy 135.458152 -375.905958) (xy 135.40706 -375.870318)
			(xy 135.360944 -375.828437) (xy 135.320562 -375.781002) (xy 135.286578 -375.728793) (xy 135.259549 -375.672667)
			(xy 135.23992 -375.613546) (xy 135.228011 -375.552399) (xy 135.22402 -375.490232) (xy 133.952491 -375.490232)
			(xy 133.971402 -375.536941) (xy 133.987203 -375.597199) (xy 133.995169 -375.658982) (xy 133.995668 -375.69013)
			(xy 133.995169 -375.721278) (xy 133.987203 -375.783061) (xy 133.971402 -375.843319) (xy 133.948024 -375.901062)
			(xy 133.917455 -375.955341) (xy 133.880195 -376.005265) (xy 133.836858 -376.050015) (xy 133.788153 -376.088855)
			(xy 133.734882 -376.121148) (xy 133.677919 -376.146365) (xy 133.618198 -376.164089) (xy 133.556701 -376.174032)
			(xy 133.494438 -376.176028) (xy 133.432431 -376.170046) (xy 133.371697 -376.156184) (xy 133.313235 -376.13467)
			(xy 133.258004 -376.105856) (xy 133.206912 -376.070216) (xy 133.160796 -376.028335) (xy 133.120414 -375.9809)
			(xy 133.08643 -375.928691) (xy 133.059401 -375.872565) (xy 133.039772 -375.813444) (xy 133.027863 -375.752297)
			(xy 133.023872 -375.69013) (xy 131.752233 -375.69013) (xy 131.74328 -375.71105) (xy 131.72694 -375.739406)
			(xy 131.723626 -375.745431) (xy 131.72002 -375.758694) (xy 131.719828 -375.765568) (xy 131.719828 -376.514868)
			(xy 131.720029 -376.521741) (xy 131.723631 -376.535004) (xy 131.72694 -376.54103) (xy 131.743281 -376.569384)
			(xy 131.769026 -376.629551) (xy 131.786453 -376.692632) (xy 131.795246 -376.757482) (xy 131.795245 -376.790204)
			(xy 135.22402 -376.790204) (xy 135.228011 -376.728037) (xy 135.23992 -376.66689) (xy 135.259549 -376.607769)
			(xy 135.286578 -376.551643) (xy 135.320562 -376.499434) (xy 135.360944 -376.451999) (xy 135.40706 -376.410118)
			(xy 135.458152 -376.374478) (xy 135.513383 -376.345664) (xy 135.571845 -376.32415) (xy 135.632579 -376.310288)
			(xy 135.694586 -376.304306) (xy 135.756849 -376.306302) (xy 135.818346 -376.316245) (xy 135.878067 -376.333969)
			(xy 135.93503 -376.359186) (xy 135.988301 -376.391479) (xy 136.037006 -376.430319) (xy 136.080343 -376.475069)
			(xy 136.117603 -376.524993) (xy 136.148172 -376.579272) (xy 136.17155 -376.637015) (xy 136.187351 -376.697273)
			(xy 136.195317 -376.759056) (xy 136.195816 -376.790204) (xy 136.195317 -376.821352) (xy 136.187351 -376.883135)
			(xy 136.17155 -376.943393) (xy 136.148172 -377.001136) (xy 136.117603 -377.055415) (xy 136.080343 -377.105339)
			(xy 136.037006 -377.150089) (xy 135.988301 -377.188929) (xy 135.93503 -377.221222) (xy 135.878067 -377.246439)
			(xy 135.818346 -377.264163) (xy 135.756849 -377.274106) (xy 135.694586 -377.276102) (xy 135.632579 -377.27012)
			(xy 135.571845 -377.256258) (xy 135.513383 -377.234744) (xy 135.458152 -377.20593) (xy 135.40706 -377.17029)
			(xy 135.360944 -377.128409) (xy 135.320562 -377.080974) (xy 135.286578 -377.028765) (xy 135.259549 -376.972639)
			(xy 135.23992 -376.913518) (xy 135.228011 -376.852371) (xy 135.22402 -376.790204) (xy 131.795245 -376.790204)
			(xy 131.795245 -376.822925) (xy 131.786452 -376.887775) (xy 131.769024 -376.950855) (xy 131.743278 -377.011022)
			(xy 131.72694 -377.039378) (xy 131.723636 -377.045408) (xy 131.720023 -377.058668) (xy 131.719828 -377.06554)
			(xy 131.719828 -377.35129) (xy 131.719427 -377.361465) (xy 131.711639 -377.380266) (xy 131.697246 -377.394653)
			(xy 131.678441 -377.402432) (xy 131.668266 -377.402852) (xy 130.951986 -377.402852) (xy 130.941826 -377.402378)
			(xy 130.923055 -377.394597) (xy 130.90869 -377.380225) (xy 130.900918 -377.36145) (xy 130.900424 -377.35129)
			(xy 130.900424 -377.06554) (xy 130.900214 -377.058668) (xy 130.896618 -377.045405) (xy 130.893312 -377.039378)
			(xy 130.876979 -377.01102) (xy 130.851236 -376.950853) (xy 130.83381 -376.887774) (xy 130.825017 -376.822925)
			(xy 127.395195 -376.822925) (xy 127.386403 -376.887774) (xy 127.368977 -376.950854) (xy 127.343234 -377.011021)
			(xy 127.326898 -377.039378) (xy 127.323545 -377.045399) (xy 127.319802 -377.058655) (xy 127.319532 -377.06554)
			(xy 127.319532 -377.35129) (xy 127.319064 -377.36142) (xy 127.311335 -377.380146) (xy 127.297042 -377.394503)
			(xy 127.278351 -377.402318) (xy 127.268224 -377.402852) (xy 126.551944 -377.402852) (xy 126.541799 -377.402343)
			(xy 126.523058 -377.394572) (xy 126.508735 -377.380202) (xy 126.501024 -377.361436) (xy 126.500636 -377.35129)
			(xy 126.500636 -377.06554) (xy 126.500418 -377.058646) (xy 126.49668 -377.045374) (xy 126.49327 -377.039378)
			(xy 126.476935 -377.01102) (xy 126.451189 -376.950854) (xy 126.433761 -376.887774) (xy 126.424967 -376.822925)
			(xy 122.995159 -376.822925) (xy 122.986366 -376.887775) (xy 122.968938 -376.950855) (xy 122.943194 -377.011022)
			(xy 122.926856 -377.039378) (xy 122.923553 -377.045409) (xy 122.919939 -377.058668) (xy 122.919744 -377.06554)
			(xy 122.919744 -377.35129) (xy 122.919328 -377.361463) (xy 122.911543 -377.380261) (xy 122.897154 -377.394647)
			(xy 122.878355 -377.402429) (xy 122.868182 -377.402852) (xy 122.151902 -377.402852) (xy 122.141729 -377.402434)
			(xy 122.122933 -377.394648) (xy 122.108547 -377.380261) (xy 122.100764 -377.361463) (xy 122.10034 -377.35129)
			(xy 122.10034 -377.06554) (xy 122.100128 -377.058668) (xy 122.096533 -377.045406) (xy 122.093228 -377.039378)
			(xy 122.076894 -377.01102) (xy 122.051151 -376.950853) (xy 122.033724 -376.887774) (xy 122.024931 -376.822925)
			(xy 118.595123 -376.822925) (xy 118.586329 -376.887776) (xy 118.5689 -376.950856) (xy 118.543153 -377.011022)
			(xy 118.526814 -377.039378) (xy 118.523462 -377.045399) (xy 118.519718 -377.058655) (xy 118.519448 -377.06554)
			(xy 118.519448 -377.35129) (xy 118.518965 -377.361418) (xy 118.511238 -377.380141) (xy 118.496951 -377.394498)
			(xy 118.478265 -377.402315) (xy 118.46814 -377.402852) (xy 117.75186 -377.402852) (xy 117.74171 -377.402412)
			(xy 117.722967 -377.394613) (xy 117.708647 -377.380223) (xy 117.700939 -377.361442) (xy 117.700552 -377.35129)
			(xy 117.700552 -377.06554) (xy 117.700332 -377.058646) (xy 117.696595 -377.045374) (xy 117.693186 -377.039378)
			(xy 117.676851 -377.01102) (xy 117.651104 -376.950855) (xy 117.633675 -376.887775) (xy 117.624881 -376.822925)
			(xy 100.557617 -376.822925) (xy 100.555221 -376.824387) (xy 100.503892 -376.846199) (xy 100.449935 -376.860305)
			(xy 100.394498 -376.866405) (xy 100.338764 -376.864368) (xy 100.283921 -376.854238) (xy 100.231137 -376.836231)
			(xy 100.181537 -376.81073) (xy 100.136179 -376.778279) (xy 100.09603 -376.73957) (xy 100.061944 -376.695427)
			(xy 100.034648 -376.646792) (xy 100.014725 -376.594701) (xy 100.002599 -376.540264) (xy 99.998528 -376.484642)
			(xy 92.087322 -376.484642) (xy 92.117437 -376.524993) (xy 92.148006 -376.579272) (xy 92.171384 -376.637015)
			(xy 92.187185 -376.697273) (xy 92.195151 -376.759056) (xy 92.19565 -376.790204) (xy 92.195151 -376.821352)
			(xy 92.187185 -376.883135) (xy 92.171384 -376.943393) (xy 92.148006 -377.001136) (xy 92.117437 -377.055415)
			(xy 92.080177 -377.105339) (xy 92.03684 -377.150089) (xy 91.988135 -377.188929) (xy 91.934864 -377.221222)
			(xy 91.877901 -377.246439) (xy 91.81818 -377.264163) (xy 91.756683 -377.274106) (xy 91.69442 -377.276102)
			(xy 91.632413 -377.27012) (xy 91.571679 -377.256258) (xy 91.513217 -377.234744) (xy 91.457986 -377.20593)
			(xy 91.406894 -377.17029) (xy 91.360778 -377.128409) (xy 91.320396 -377.080974) (xy 91.286412 -377.028765)
			(xy 91.259383 -376.972639) (xy 91.239754 -376.913518) (xy 91.227845 -376.852371) (xy 91.223854 -376.790204)
			(xy 87.795075 -376.790204) (xy 87.795075 -376.822925) (xy 87.786281 -376.887775) (xy 87.768855 -376.950855)
			(xy 87.743111 -377.011022) (xy 87.726774 -377.039378) (xy 87.72342 -377.045398) (xy 87.719678 -377.058654)
			(xy 87.719408 -377.06554) (xy 87.719408 -377.35129) (xy 87.718867 -377.36141) (xy 87.711151 -377.380122)
			(xy 87.703706 -377.387612) (xy 100.044502 -377.387612) (xy 100.048573 -377.33199) (xy 100.060699 -377.277553)
			(xy 100.080622 -377.225462) (xy 100.107918 -377.176827) (xy 100.142004 -377.132684) (xy 100.182153 -377.093975)
			(xy 100.227511 -377.061524) (xy 100.277111 -377.036023) (xy 100.329895 -377.018016) (xy 100.384738 -377.007886)
			(xy 100.440472 -377.005849) (xy 100.495909 -377.011949) (xy 100.549866 -377.026055) (xy 100.601195 -377.047867)
			(xy 100.648801 -377.076921) (xy 100.691669 -377.112596) (xy 100.728886 -377.154133) (xy 100.759659 -377.200646)
			(xy 100.783331 -377.251143) (xy 100.799399 -377.30455) (xy 100.807519 -377.359726) (xy 100.808028 -377.387612)
			(xy 100.807519 -377.415498) (xy 100.799399 -377.470674) (xy 100.783331 -377.524081) (xy 100.759659 -377.574578)
			(xy 100.728886 -377.621091) (xy 100.691669 -377.662628) (xy 100.648801 -377.698303) (xy 100.601195 -377.727357)
			(xy 100.549866 -377.749169) (xy 100.495909 -377.763275) (xy 100.440472 -377.769375) (xy 100.384738 -377.767338)
			(xy 100.329895 -377.757208) (xy 100.277111 -377.739201) (xy 100.227511 -377.7137) (xy 100.182153 -377.681249)
			(xy 100.142004 -377.64254) (xy 100.107918 -377.598397) (xy 100.080622 -377.549762) (xy 100.060699 -377.497671)
			(xy 100.048573 -377.443234) (xy 100.044502 -377.387612) (xy 87.703706 -377.387612) (xy 87.696882 -377.394477)
			(xy 87.678217 -377.402305) (xy 87.6681 -377.402852) (xy 86.95182 -377.402852) (xy 86.941674 -377.402363)
			(xy 86.922932 -377.394584) (xy 86.908609 -377.380209) (xy 86.9009 -377.361438) (xy 86.900512 -377.35129)
			(xy 86.900512 -377.06554) (xy 86.900297 -377.058646) (xy 86.896557 -377.045374) (xy 86.893146 -377.039378)
			(xy 86.876812 -377.01102) (xy 86.851067 -376.950854) (xy 86.83364 -376.887774) (xy 86.824847 -376.822925)
			(xy 86.824846 -376.757482) (xy 83.395039 -376.757482) (xy 83.395039 -376.822925) (xy 83.386245 -376.887775)
			(xy 83.368816 -376.950856) (xy 83.343071 -377.011022) (xy 83.326732 -377.039378) (xy 83.323428 -377.045408)
			(xy 83.319815 -377.058668) (xy 83.31962 -377.06554) (xy 83.31962 -377.35129) (xy 83.319227 -377.361466)
			(xy 83.311438 -377.380269) (xy 83.297042 -377.394655) (xy 83.278234 -377.402433) (xy 83.268058 -377.402852)
			(xy 82.551778 -377.402852) (xy 82.541618 -377.402385) (xy 82.522846 -377.394601) (xy 82.508481 -377.380227)
			(xy 82.500709 -377.361451) (xy 82.500216 -377.35129) (xy 82.500216 -377.06554) (xy 82.500007 -377.058668)
			(xy 82.49641 -377.045405) (xy 82.493104 -377.039378) (xy 82.476771 -377.01102) (xy 82.451029 -376.950853)
			(xy 82.433603 -376.887773) (xy 82.424811 -376.822925) (xy 82.42481 -376.757482) (xy 78.994989 -376.757482)
			(xy 78.994988 -376.822925) (xy 78.986196 -376.887774) (xy 78.96877 -376.950854) (xy 78.943027 -377.011022)
			(xy 78.92669 -377.039378) (xy 78.923337 -377.045399) (xy 78.919594 -377.058655) (xy 78.919324 -377.06554)
			(xy 78.919324 -377.35129) (xy 78.918864 -377.36142) (xy 78.911133 -377.380148) (xy 78.896838 -377.394506)
			(xy 78.878144 -377.402319) (xy 78.868016 -377.402852) (xy 78.151736 -377.402852) (xy 78.141591 -377.40235)
			(xy 78.122849 -377.394576) (xy 78.108526 -377.380204) (xy 78.100816 -377.361437) (xy 78.100428 -377.35129)
			(xy 78.100428 -377.06554) (xy 78.100211 -377.058646) (xy 78.096472 -377.045374) (xy 78.093062 -377.039378)
			(xy 78.076727 -377.01102) (xy 78.050982 -376.950854) (xy 78.033554 -376.887774) (xy 78.02476 -376.822925)
			(xy 74.594952 -376.822925) (xy 74.586159 -376.887775) (xy 74.568731 -376.950855) (xy 74.542986 -377.011022)
			(xy 74.526648 -377.039378) (xy 74.523345 -377.045408) (xy 74.519731 -377.058668) (xy 74.519536 -377.06554)
			(xy 74.519536 -377.35129) (xy 74.519127 -377.361464) (xy 74.511341 -377.380264) (xy 74.49695 -377.39465)
			(xy 74.478148 -377.402431) (xy 74.467974 -377.402852) (xy 73.751694 -377.402852) (xy 73.741521 -377.402441)
			(xy 73.722724 -377.394652) (xy 73.708339 -377.380263) (xy 73.700556 -377.361463) (xy 73.700132 -377.35129)
			(xy 73.700132 -377.06554) (xy 73.699921 -377.058668) (xy 73.696325 -377.045406) (xy 73.69302 -377.039378)
			(xy 73.676687 -377.01102) (xy 73.650943 -376.950853) (xy 73.633517 -376.887774) (xy 73.624724 -376.822925)
			(xy 55.727863 -376.822925) (xy 55.725001 -376.832439) (xy 55.701329 -376.882936) (xy 55.670556 -376.929449)
			(xy 55.633339 -376.970986) (xy 55.590471 -377.006661) (xy 55.542865 -377.035715) (xy 55.491536 -377.057527)
			(xy 55.437579 -377.071633) (xy 55.382142 -377.077733) (xy 55.326408 -377.075696) (xy 55.271565 -377.065566)
			(xy 55.218781 -377.047559) (xy 55.169181 -377.022058) (xy 55.123823 -376.989607) (xy 55.083674 -376.950898)
			(xy 55.049588 -376.906755) (xy 55.022292 -376.85812) (xy 55.002369 -376.806029) (xy 54.990243 -376.751592)
			(xy 54.986172 -376.69597) (xy 51.556158 -376.69597) (xy 51.556158 -377.556268) (xy 58.845702 -377.556268)
			(xy 58.849773 -377.500646) (xy 58.861899 -377.446209) (xy 58.881822 -377.394118) (xy 58.909118 -377.345483)
			(xy 58.943204 -377.30134) (xy 58.983353 -377.262631) (xy 59.028711 -377.23018) (xy 59.078311 -377.204679)
			(xy 59.131095 -377.186672) (xy 59.185938 -377.176542) (xy 59.241672 -377.174505) (xy 59.297109 -377.180605)
			(xy 59.351066 -377.194711) (xy 59.402395 -377.216523) (xy 59.450001 -377.245577) (xy 59.492869 -377.281252)
			(xy 59.530086 -377.322789) (xy 59.560859 -377.369302) (xy 59.584531 -377.419799) (xy 59.600599 -377.473206)
			(xy 59.608719 -377.528382) (xy 59.609228 -377.556268) (xy 59.608719 -377.584154) (xy 59.600599 -377.63933)
			(xy 59.584531 -377.692737) (xy 59.560859 -377.743234) (xy 59.530086 -377.789747) (xy 59.492869 -377.831284)
			(xy 59.450001 -377.866959) (xy 59.402395 -377.896013) (xy 59.351066 -377.917825) (xy 59.297109 -377.931931)
			(xy 59.241672 -377.938031) (xy 59.185938 -377.935994) (xy 59.131095 -377.925864) (xy 59.078311 -377.907857)
			(xy 59.028711 -377.882356) (xy 58.983353 -377.849905) (xy 58.943204 -377.811196) (xy 58.909118 -377.767053)
			(xy 58.881822 -377.718418) (xy 58.861899 -377.666327) (xy 58.849773 -377.61189) (xy 58.845702 -377.556268)
			(xy 51.556158 -377.556268) (xy 51.556158 -378.376434) (xy 54.891938 -378.376434) (xy 54.896009 -378.320812)
			(xy 54.908135 -378.266375) (xy 54.928058 -378.214284) (xy 54.955354 -378.165649) (xy 54.98944 -378.121506)
			(xy 55.029589 -378.082797) (xy 55.074947 -378.050346) (xy 55.124547 -378.024845) (xy 55.177331 -378.006838)
			(xy 55.232174 -377.996708) (xy 55.287908 -377.994671) (xy 55.343345 -378.000771) (xy 55.397302 -378.014877)
			(xy 55.448631 -378.036689) (xy 55.496237 -378.065743) (xy 55.539105 -378.101418) (xy 55.576322 -378.142955)
			(xy 55.584423 -378.1552) (xy 55.980328 -378.1552) (xy 55.984399 -378.099578) (xy 55.996525 -378.045141)
			(xy 56.016448 -377.99305) (xy 56.043744 -377.944415) (xy 56.07783 -377.900272) (xy 56.117979 -377.861563)
			(xy 56.163337 -377.829112) (xy 56.212937 -377.803611) (xy 56.265721 -377.785604) (xy 56.320564 -377.775474)
			(xy 56.376298 -377.773437) (xy 56.431735 -377.779537) (xy 56.485692 -377.793643) (xy 56.537021 -377.815455)
			(xy 56.584627 -377.844509) (xy 56.627495 -377.880184) (xy 56.664712 -377.921721) (xy 56.695485 -377.968234)
			(xy 56.719157 -378.018731) (xy 56.735225 -378.072138) (xy 56.743345 -378.127314) (xy 56.743854 -378.1552)
			(xy 56.743345 -378.183086) (xy 56.735225 -378.238262) (xy 56.719157 -378.291669) (xy 56.704563 -378.3228)
			(xy 71.424812 -378.3228) (xy 71.424815 -378.257355) (xy 71.433611 -378.192505) (xy 71.451041 -378.129424)
			(xy 71.476787 -378.069256) (xy 71.493126 -378.0409) (xy 71.496488 -378.034884) (xy 71.500225 -378.021624)
			(xy 71.500492 -378.014738) (xy 71.500492 -377.728734) (xy 71.501053 -377.718615) (xy 71.508761 -377.699904)
			(xy 71.523024 -377.685548) (xy 71.541685 -377.67772) (xy 71.5518 -377.677172) (xy 72.26808 -377.677172)
			(xy 72.278229 -377.677637) (xy 72.296976 -377.685421) (xy 72.311299 -377.699804) (xy 72.319005 -377.718583)
			(xy 72.319388 -377.728734) (xy 72.319388 -378.014738) (xy 72.319612 -378.021632) (xy 72.323346 -378.034904)
			(xy 72.326754 -378.0409) (xy 72.34307 -378.069268) (xy 72.368816 -378.129432) (xy 72.386245 -378.19251)
			(xy 72.395041 -378.257357) (xy 72.395044 -378.322798) (xy 72.395044 -378.3228) (xy 75.824848 -378.3228)
			(xy 75.824851 -378.257355) (xy 75.833648 -378.192504) (xy 75.851079 -378.129423) (xy 75.876828 -378.069256)
			(xy 75.893168 -378.0409) (xy 75.89648 -378.034874) (xy 75.900088 -378.021611) (xy 75.90028 -378.014738)
			(xy 75.90028 -377.728734) (xy 75.900693 -377.718559) (xy 75.908474 -377.699757) (xy 75.922864 -377.68537)
			(xy 75.941667 -377.677591) (xy 75.951842 -377.677172) (xy 76.668122 -377.677172) (xy 76.678299 -377.677547)
			(xy 76.697101 -377.685345) (xy 76.711486 -377.699746) (xy 76.719264 -377.718556) (xy 76.719684 -377.728734)
			(xy 76.719684 -378.014738) (xy 76.719902 -378.021609) (xy 76.723493 -378.034872) (xy 76.726796 -378.0409)
			(xy 76.74311 -378.069269) (xy 76.768854 -378.129433) (xy 76.786282 -378.19251) (xy 76.795077 -378.257357)
			(xy 76.79508 -378.322798) (xy 76.79508 -378.3228) (xy 80.224899 -378.3228) (xy 80.224902 -378.257356)
			(xy 80.233697 -378.192505) (xy 80.251126 -378.129424) (xy 80.276872 -378.069257) (xy 80.29321 -378.0409)
			(xy 80.296571 -378.034883) (xy 80.300309 -378.021624) (xy 80.300576 -378.014738) (xy 80.300576 -377.728734)
			(xy 80.301056 -377.718605) (xy 80.308779 -377.699878) (xy 80.323068 -377.685519) (xy 80.341758 -377.677705)
			(xy 80.351884 -377.677172) (xy 81.068164 -377.677172) (xy 81.078312 -377.677651) (xy 81.097058 -377.685429)
			(xy 81.111382 -377.699808) (xy 81.119088 -377.718584) (xy 81.119472 -377.728734) (xy 81.119472 -378.014738)
			(xy 81.119698 -378.021631) (xy 81.123431 -378.034903) (xy 81.126838 -378.0409) (xy 81.143154 -378.069268)
			(xy 81.168901 -378.129432) (xy 81.186331 -378.192509) (xy 81.195127 -378.257357) (xy 81.19513 -378.322798)
			(xy 81.19513 -378.3228) (xy 84.624688 -378.3228) (xy 84.624691 -378.257356) (xy 84.633487 -378.192505)
			(xy 84.650915 -378.129424) (xy 84.67666 -378.069257) (xy 84.692998 -378.0409) (xy 84.696358 -378.034883)
			(xy 84.700097 -378.021624) (xy 84.700364 -378.014738) (xy 84.700364 -377.728734) (xy 84.700855 -377.718607)
			(xy 84.708576 -377.699882) (xy 84.722862 -377.685523) (xy 84.741547 -377.677707) (xy 84.751672 -377.677172)
			(xy 85.467952 -377.677172) (xy 85.4781 -377.67766) (xy 85.496845 -377.685435) (xy 85.51117 -377.699811)
			(xy 85.518876 -377.718585) (xy 85.51926 -377.728734) (xy 85.51926 -378.014738) (xy 85.519487 -378.021631)
			(xy 85.523219 -378.034903) (xy 85.526626 -378.0409) (xy 85.542942 -378.069268) (xy 85.56869 -378.129432)
			(xy 85.58612 -378.192509) (xy 85.594917 -378.257357) (xy 85.594918 -378.290074) (xy 89.023706 -378.290074)
			(xy 89.027697 -378.227907) (xy 89.039606 -378.16676) (xy 89.059235 -378.107639) (xy 89.086264 -378.051513)
			(xy 89.120248 -377.999304) (xy 89.16063 -377.951869) (xy 89.206746 -377.909988) (xy 89.257838 -377.874348)
			(xy 89.313069 -377.845534) (xy 89.371531 -377.82402) (xy 89.432265 -377.810158) (xy 89.494272 -377.804176)
			(xy 89.556535 -377.806172) (xy 89.618032 -377.816115) (xy 89.677753 -377.833839) (xy 89.734716 -377.859056)
			(xy 89.787987 -377.891349) (xy 89.836692 -377.930189) (xy 89.880029 -377.974939) (xy 89.917289 -378.024863)
			(xy 89.947858 -378.079142) (xy 89.971236 -378.136885) (xy 89.987037 -378.197143) (xy 89.995003 -378.258926)
			(xy 89.995502 -378.290074) (xy 89.995003 -378.321222) (xy 89.9948 -378.3228) (xy 115.424969 -378.3228)
			(xy 115.424972 -378.257355) (xy 115.433769 -378.192504) (xy 115.451201 -378.129422) (xy 115.476951 -378.069256)
			(xy 115.493292 -378.0409) (xy 115.496606 -378.034875) (xy 115.500212 -378.021612) (xy 115.500404 -378.014738)
			(xy 115.500404 -377.728734) (xy 115.500961 -377.718583) (xy 115.508717 -377.699821) (xy 115.523064 -377.685456)
			(xy 115.541815 -377.677674) (xy 115.551966 -377.677172) (xy 116.268246 -377.677172) (xy 116.278411 -377.677597)
			(xy 116.297188 -377.685393) (xy 116.311552 -377.69978) (xy 116.319319 -377.718568) (xy 116.319808 -377.728734)
			(xy 116.319808 -378.014738) (xy 116.320023 -378.02161) (xy 116.323615 -378.034872) (xy 116.32692 -378.0409)
			(xy 116.343237 -378.069268) (xy 116.368985 -378.129431) (xy 116.386415 -378.192509) (xy 116.395212 -378.257357)
			(xy 116.395215 -378.322799) (xy 116.395215 -378.3228) (xy 119.825019 -378.3228) (xy 119.825022 -378.257355)
			(xy 119.833818 -378.192504) (xy 119.851248 -378.129423) (xy 119.876995 -378.069256) (xy 119.893334 -378.0409)
			(xy 119.896697 -378.034884) (xy 119.900433 -378.021624) (xy 119.9007 -378.014738) (xy 119.9007 -377.728734)
			(xy 119.901253 -377.718614) (xy 119.908963 -377.699902) (xy 119.923228 -377.685546) (xy 119.941892 -377.677718)
			(xy 119.952008 -377.677172) (xy 120.668288 -377.677172) (xy 120.678438 -377.677631) (xy 120.697185 -377.685417)
			(xy 120.711507 -377.699802) (xy 120.719213 -377.718582) (xy 120.719596 -377.728734) (xy 120.719596 -378.014738)
			(xy 120.719854 -378.021627) (xy 120.723579 -378.034893) (xy 120.726962 -378.0409) (xy 120.743277 -378.069268)
			(xy 120.769023 -378.129432) (xy 120.786452 -378.19251) (xy 120.795248 -378.257357) (xy 120.795251 -378.322798)
			(xy 120.795251 -378.3228) (xy 124.225055 -378.3228) (xy 124.225058 -378.257355) (xy 124.233855 -378.192504)
			(xy 124.251286 -378.129423) (xy 124.277036 -378.069256) (xy 124.293376 -378.0409) (xy 124.296689 -378.034874)
			(xy 124.300296 -378.021611) (xy 124.300488 -378.014738) (xy 124.300488 -377.728734) (xy 124.300893 -377.718558)
			(xy 124.308676 -377.699755) (xy 124.323068 -377.685367) (xy 124.341874 -377.67759) (xy 124.35205 -377.677172)
			(xy 125.06833 -377.677172) (xy 125.078508 -377.67754) (xy 125.09731 -377.685341) (xy 125.111695 -377.699744)
			(xy 125.119473 -377.718556) (xy 125.119892 -377.728734) (xy 125.119892 -378.014738) (xy 125.120109 -378.021609)
			(xy 125.1237 -378.034872) (xy 125.127004 -378.0409) (xy 125.143318 -378.069269) (xy 125.169062 -378.129433)
			(xy 125.186489 -378.19251) (xy 125.195284 -378.257357) (xy 125.195287 -378.322798) (xy 125.195287 -378.3228)
			(xy 128.624845 -378.3228) (xy 128.624848 -378.257355) (xy 128.633645 -378.192504) (xy 128.651075 -378.129423)
			(xy 128.676824 -378.069256) (xy 128.693164 -378.0409) (xy 128.696476 -378.034874) (xy 128.700084 -378.021611)
			(xy 128.700276 -378.014738) (xy 128.700276 -377.728734) (xy 128.700693 -377.71856) (xy 128.708474 -377.699759)
			(xy 128.722862 -377.685371) (xy 128.741664 -377.677592) (xy 128.751838 -377.677172) (xy 129.468118 -377.677172)
			(xy 129.478295 -377.67755) (xy 129.497097 -377.685347) (xy 129.511482 -377.699747) (xy 129.51926 -377.718557)
			(xy 129.51968 -377.728734) (xy 129.51968 -378.014738) (xy 129.519898 -378.021609) (xy 129.523489 -378.034872)
			(xy 129.526792 -378.0409) (xy 129.543106 -378.069269) (xy 129.568851 -378.129433) (xy 129.586278 -378.19251)
			(xy 129.595074 -378.257357) (xy 129.595075 -378.290074) (xy 133.023872 -378.290074) (xy 133.027863 -378.227907)
			(xy 133.039772 -378.16676) (xy 133.059401 -378.107639) (xy 133.08643 -378.051513) (xy 133.120414 -377.999304)
			(xy 133.160796 -377.951869) (xy 133.206912 -377.909988) (xy 133.258004 -377.874348) (xy 133.313235 -377.845534)
			(xy 133.371697 -377.82402) (xy 133.432431 -377.810158) (xy 133.494438 -377.804176) (xy 133.556701 -377.806172)
			(xy 133.618198 -377.816115) (xy 133.677919 -377.833839) (xy 133.734882 -377.859056) (xy 133.788153 -377.891349)
			(xy 133.836858 -377.930189) (xy 133.880195 -377.974939) (xy 133.917455 -378.024863) (xy 133.948024 -378.079142)
			(xy 133.971402 -378.136885) (xy 133.987203 -378.197143) (xy 133.995169 -378.258926) (xy 133.995668 -378.290074)
			(xy 133.995169 -378.321222) (xy 133.987203 -378.383005) (xy 133.971402 -378.443263) (xy 133.948024 -378.501006)
			(xy 133.917455 -378.555285) (xy 133.880195 -378.605209) (xy 133.836858 -378.649959) (xy 133.789995 -378.68733)
			(xy 149.188168 -378.68733) (xy 149.192239 -378.631708) (xy 149.204365 -378.577271) (xy 149.224288 -378.52518)
			(xy 149.251584 -378.476545) (xy 149.28567 -378.432402) (xy 149.325819 -378.393693) (xy 149.371177 -378.361242)
			(xy 149.420777 -378.335741) (xy 149.473561 -378.317734) (xy 149.528404 -378.307604) (xy 149.584138 -378.305567)
			(xy 149.639575 -378.311667) (xy 149.693532 -378.325773) (xy 149.744861 -378.347585) (xy 149.792467 -378.376639)
			(xy 149.835335 -378.412314) (xy 149.872552 -378.453851) (xy 149.903325 -378.500364) (xy 149.926997 -378.550861)
			(xy 149.943065 -378.604268) (xy 149.951185 -378.659444) (xy 149.951694 -378.68733) (xy 149.951185 -378.715216)
			(xy 149.943065 -378.770392) (xy 149.926997 -378.823799) (xy 149.903325 -378.874296) (xy 149.872552 -378.920809)
			(xy 149.835335 -378.962346) (xy 149.792467 -378.998021) (xy 149.744861 -379.027075) (xy 149.693532 -379.048887)
			(xy 149.639575 -379.062993) (xy 149.584138 -379.069093) (xy 149.528404 -379.067056) (xy 149.473561 -379.056926)
			(xy 149.420777 -379.038919) (xy 149.371177 -379.013418) (xy 149.325819 -378.980967) (xy 149.28567 -378.942258)
			(xy 149.251584 -378.898115) (xy 149.224288 -378.84948) (xy 149.204365 -378.797389) (xy 149.192239 -378.742952)
			(xy 149.188168 -378.68733) (xy 133.789995 -378.68733) (xy 133.788153 -378.688799) (xy 133.734882 -378.721092)
			(xy 133.677919 -378.746309) (xy 133.618198 -378.764033) (xy 133.556701 -378.773976) (xy 133.494438 -378.775972)
			(xy 133.432431 -378.76999) (xy 133.371697 -378.756128) (xy 133.313235 -378.734614) (xy 133.258004 -378.7058)
			(xy 133.206912 -378.67016) (xy 133.160796 -378.628279) (xy 133.120414 -378.580844) (xy 133.08643 -378.528635)
			(xy 133.059401 -378.472509) (xy 133.039772 -378.413388) (xy 133.027863 -378.352241) (xy 133.023872 -378.290074)
			(xy 129.595075 -378.290074) (xy 129.595077 -378.322798) (xy 129.586287 -378.387646) (xy 129.568865 -378.450725)
			(xy 129.543127 -378.510892) (xy 129.526792 -378.539248) (xy 129.52346 -378.545264) (xy 129.519865 -378.558534)
			(xy 129.51968 -378.56541) (xy 129.51968 -379.31471) (xy 129.519871 -379.321583) (xy 129.52348 -379.334846)
			(xy 129.526792 -379.340872) (xy 129.543167 -379.369207) (xy 129.568906 -379.429379) (xy 129.586327 -379.492463)
			(xy 129.595115 -379.557317) (xy 129.595109 -379.622762) (xy 129.586311 -379.687614) (xy 129.56888 -379.750696)
			(xy 129.543131 -379.810863) (xy 129.526792 -379.83922) (xy 129.52347 -379.845241) (xy 129.519869 -379.858508)
			(xy 129.51968 -379.865382) (xy 129.51968 -380.151386) (xy 129.519156 -380.161541) (xy 129.511389 -380.180306)
			(xy 129.497033 -380.194671) (xy 129.478272 -380.202449) (xy 129.468118 -380.202948) (xy 128.751838 -380.202948)
			(xy 128.741667 -380.202505) (xy 128.722871 -380.19473) (xy 128.708484 -380.18035) (xy 128.7007 -380.161557)
			(xy 128.700276 -380.151386) (xy 128.700276 -379.865382) (xy 128.700094 -379.858508) (xy 128.696479 -379.845245)
			(xy 128.693164 -379.83922) (xy 128.676865 -379.810843) (xy 128.651116 -379.750681) (xy 128.633684 -379.687605)
			(xy 128.624886 -379.622759) (xy 128.624881 -379.557319) (xy 128.633668 -379.492472) (xy 128.65109 -379.429393)
			(xy 128.676829 -379.369228) (xy 128.693164 -379.340872) (xy 128.696486 -379.334851) (xy 128.700087 -379.321584)
			(xy 128.700276 -379.31471) (xy 128.700276 -378.56541) (xy 128.700083 -378.558537) (xy 128.696476 -378.545274)
			(xy 128.693164 -378.539248) (xy 128.676804 -378.510904) (xy 128.651061 -378.450735) (xy 128.633636 -378.387652)
			(xy 128.624845 -378.3228) (xy 125.195287 -378.3228) (xy 125.186498 -378.387646) (xy 125.169076 -378.450725)
			(xy 125.143338 -378.510891) (xy 125.127004 -378.539248) (xy 125.123672 -378.545264) (xy 125.120077 -378.558535)
			(xy 125.119892 -378.56541) (xy 125.119892 -379.31471) (xy 125.120081 -379.321583) (xy 125.123691 -379.334846)
			(xy 125.127004 -379.340872) (xy 125.143379 -379.369207) (xy 125.169117 -379.429379) (xy 125.186538 -379.492464)
			(xy 125.195325 -379.557317) (xy 125.19532 -379.622762) (xy 125.186522 -379.687614) (xy 125.169091 -379.750695)
			(xy 125.143343 -379.810863) (xy 125.127004 -379.83922) (xy 125.123682 -379.845241) (xy 125.120081 -379.858508)
			(xy 125.119892 -379.865382) (xy 125.119892 -380.151386) (xy 125.119356 -380.161539) (xy 125.111592 -380.180302)
			(xy 125.097239 -380.194667) (xy 125.078483 -380.202447) (xy 125.06833 -380.202948) (xy 124.35205 -380.202948)
			(xy 124.34188 -380.202495) (xy 124.323084 -380.194724) (xy 124.308696 -380.180347) (xy 124.300912 -380.161556)
			(xy 124.300488 -380.151386) (xy 124.300488 -379.865382) (xy 124.300305 -379.858508) (xy 124.296691 -379.845245)
			(xy 124.293376 -379.83922) (xy 124.277076 -379.810843) (xy 124.251327 -379.750681) (xy 124.233895 -379.687606)
			(xy 124.225096 -379.62276) (xy 124.225091 -379.557319) (xy 124.233879 -379.492472) (xy 124.251301 -379.429393)
			(xy 124.277041 -379.369228) (xy 124.293376 -379.340872) (xy 124.296699 -379.334851) (xy 124.3003 -379.321585)
			(xy 124.300488 -379.31471) (xy 124.300488 -378.56541) (xy 124.300294 -378.558537) (xy 124.296687 -378.545274)
			(xy 124.293376 -378.539248) (xy 124.277015 -378.510904) (xy 124.251272 -378.450735) (xy 124.233846 -378.387652)
			(xy 124.225055 -378.3228) (xy 120.795251 -378.3228) (xy 120.786461 -378.387646) (xy 120.769038 -378.450726)
			(xy 120.743298 -378.510892) (xy 120.726962 -378.539248) (xy 120.723582 -378.545255) (xy 120.719856 -378.558522)
			(xy 120.719596 -378.56541) (xy 120.719596 -379.31471) (xy 120.719826 -379.321602) (xy 120.723571 -379.334867)
			(xy 120.726962 -379.340872) (xy 120.743338 -379.369207) (xy 120.769079 -379.429378) (xy 120.786501 -379.492463)
			(xy 120.795289 -379.557316) (xy 120.795283 -379.622762) (xy 120.786485 -379.687614) (xy 120.769052 -379.750696)
			(xy 120.743302 -379.810864) (xy 120.726962 -379.83922) (xy 120.723592 -379.845232) (xy 120.71986 -379.858495)
			(xy 120.719596 -379.865382) (xy 120.719596 -380.151386) (xy 120.719063 -380.161507) (xy 120.711347 -380.180221)
			(xy 120.697075 -380.194577) (xy 120.678406 -380.202403) (xy 120.668288 -380.202948) (xy 119.952008 -380.202948)
			(xy 119.94186 -380.202473) (xy 119.923117 -380.194689) (xy 119.908795 -380.180309) (xy 119.901087 -380.161535)
			(xy 119.9007 -380.151386) (xy 119.9007 -379.865382) (xy 119.900435 -379.858493) (xy 119.896714 -379.845227)
			(xy 119.893334 -379.83922) (xy 119.877036 -379.810842) (xy 119.851289 -379.750681) (xy 119.833858 -379.687605)
			(xy 119.82506 -379.622759) (xy 119.825055 -379.55732) (xy 119.833842 -379.492473) (xy 119.851262 -379.429394)
			(xy 119.877 -379.369228) (xy 119.893334 -379.340872) (xy 119.896707 -379.334861) (xy 119.900437 -379.321598)
			(xy 119.9007 -379.31471) (xy 119.9007 -378.56541) (xy 119.900463 -378.558519) (xy 119.896723 -378.545253)
			(xy 119.893334 -378.539248) (xy 119.876975 -378.510904) (xy 119.851233 -378.450734) (xy 119.833809 -378.387652)
			(xy 119.825019 -378.3228) (xy 116.395215 -378.3228) (xy 116.386424 -378.387647) (xy 116.368999 -378.450726)
			(xy 116.343257 -378.510892) (xy 116.32692 -378.539248) (xy 116.32359 -378.545265) (xy 116.319993 -378.558535)
			(xy 116.319808 -378.56541) (xy 116.319808 -379.31471) (xy 116.319995 -379.321584) (xy 116.323606 -379.334846)
			(xy 116.32692 -379.340872) (xy 116.343298 -379.369206) (xy 116.36904 -379.429378) (xy 116.386464 -379.492462)
			(xy 116.395253 -379.557316) (xy 116.395247 -379.622763) (xy 116.386448 -379.687615) (xy 116.369014 -379.750697)
			(xy 116.343262 -379.810864) (xy 116.32692 -379.83922) (xy 116.3236 -379.845242) (xy 116.319997 -379.858508)
			(xy 116.319808 -379.865382) (xy 116.319808 -380.151386) (xy 116.319256 -380.161537) (xy 116.311495 -380.180297)
			(xy 116.297148 -380.194661) (xy 116.278397 -380.202445) (xy 116.268246 -380.202948) (xy 115.551966 -380.202948)
			(xy 115.541804 -380.202494) (xy 115.523032 -380.194706) (xy 115.508667 -380.180328) (xy 115.500896 -380.161548)
			(xy 115.500404 -380.151386) (xy 115.500404 -379.865382) (xy 115.500219 -379.858508) (xy 115.496606 -379.845245)
			(xy 115.493292 -379.83922) (xy 115.476992 -379.810843) (xy 115.451242 -379.750682) (xy 115.433809 -379.687606)
			(xy 115.42501 -379.62276) (xy 115.425005 -379.557319) (xy 115.433793 -379.492472) (xy 115.451216 -379.429393)
			(xy 115.476956 -379.369228) (xy 115.493292 -379.340872) (xy 115.496616 -379.334852) (xy 115.500216 -379.321585)
			(xy 115.500404 -379.31471) (xy 115.500404 -378.56541) (xy 115.500208 -378.558537) (xy 115.496603 -378.545274)
			(xy 115.493292 -378.539248) (xy 115.476931 -378.510905) (xy 115.451186 -378.450735) (xy 115.43376 -378.387653)
			(xy 115.424969 -378.3228) (xy 89.9948 -378.3228) (xy 89.987037 -378.383005) (xy 89.971236 -378.443263)
			(xy 89.947858 -378.501006) (xy 89.917289 -378.555285) (xy 89.880029 -378.605209) (xy 89.836692 -378.649959)
			(xy 89.787987 -378.688799) (xy 89.734716 -378.721092) (xy 89.677753 -378.746309) (xy 89.618032 -378.764033)
			(xy 89.556535 -378.773976) (xy 89.494272 -378.775972) (xy 89.432265 -378.76999) (xy 89.371531 -378.756128)
			(xy 89.313069 -378.734614) (xy 89.257838 -378.7058) (xy 89.206746 -378.67016) (xy 89.16063 -378.628279)
			(xy 89.120248 -378.580844) (xy 89.086264 -378.528635) (xy 89.059235 -378.472509) (xy 89.039606 -378.413388)
			(xy 89.027697 -378.352241) (xy 89.023706 -378.290074) (xy 85.594918 -378.290074) (xy 85.59492 -378.322799)
			(xy 85.586129 -378.387647) (xy 85.568705 -378.450726) (xy 85.542963 -378.510892) (xy 85.526626 -378.539248)
			(xy 85.523243 -378.545254) (xy 85.51952 -378.558521) (xy 85.51926 -378.56541) (xy 85.51926 -379.31471)
			(xy 85.51946 -379.321606) (xy 85.523211 -379.334877) (xy 85.526626 -379.340872) (xy 85.543003 -379.369206)
			(xy 85.568746 -379.429378) (xy 85.586169 -379.492462) (xy 85.594958 -379.557316) (xy 85.594952 -379.622763)
			(xy 85.586153 -379.687615) (xy 85.568719 -379.750697) (xy 85.542968 -379.810864) (xy 85.526626 -379.83922)
			(xy 85.523253 -379.845231) (xy 85.519523 -379.858494) (xy 85.51926 -379.865382) (xy 85.51926 -380.151386)
			(xy 85.518762 -380.161512) (xy 85.511039 -380.180233) (xy 85.496756 -380.194589) (xy 85.478075 -380.202409)
			(xy 85.467952 -380.202948) (xy 84.751672 -380.202948) (xy 84.741522 -380.202502) (xy 84.722778 -380.194707)
			(xy 84.708458 -380.180318) (xy 84.70075 -380.161538) (xy 84.700364 -380.151386) (xy 84.700364 -379.865382)
			(xy 84.700126 -379.85849) (xy 84.696401 -379.845218) (xy 84.692998 -379.83922) (xy 84.676701 -379.810842)
			(xy 84.650956 -379.75068) (xy 84.633526 -379.687604) (xy 84.624729 -379.622759) (xy 84.624724 -379.55732)
			(xy 84.63351 -379.492473) (xy 84.650929 -379.429395) (xy 84.676665 -379.369229) (xy 84.692998 -379.340872)
			(xy 84.696368 -379.33486) (xy 84.700101 -379.321597) (xy 84.700364 -379.31471) (xy 84.700364 -378.56541)
			(xy 84.700132 -378.558518) (xy 84.696389 -378.545252) (xy 84.692998 -378.539248) (xy 84.67664 -378.510904)
			(xy 84.6509 -378.450734) (xy 84.633478 -378.387651) (xy 84.624688 -378.3228) (xy 81.19513 -378.3228)
			(xy 81.18634 -378.387647) (xy 81.168916 -378.450726) (xy 81.143174 -378.510892) (xy 81.126838 -378.539248)
			(xy 81.123456 -378.545254) (xy 81.119732 -378.558521) (xy 81.119472 -378.56541) (xy 81.119472 -379.31471)
			(xy 81.11967 -379.321606) (xy 81.123422 -379.334878) (xy 81.126838 -379.340872) (xy 81.143215 -379.369206)
			(xy 81.168957 -379.429378) (xy 81.18638 -379.492463) (xy 81.195168 -379.557316) (xy 81.195163 -379.622763)
			(xy 81.186364 -379.687615) (xy 81.16893 -379.750697) (xy 81.143179 -379.810864) (xy 81.126838 -379.83922)
			(xy 81.123466 -379.845231) (xy 81.119735 -379.858494) (xy 81.119472 -379.865382) (xy 81.119472 -380.151386)
			(xy 81.118962 -380.16151) (xy 81.111241 -380.180229) (xy 81.096962 -380.194585) (xy 81.078286 -380.202407)
			(xy 81.068164 -380.202948) (xy 80.351884 -380.202948) (xy 80.341735 -380.202493) (xy 80.322991 -380.194701)
			(xy 80.30867 -380.180315) (xy 80.300962 -380.161537) (xy 80.300576 -380.151386) (xy 80.300576 -379.865382)
			(xy 80.300336 -379.85849) (xy 80.296612 -379.845218) (xy 80.29321 -379.83922) (xy 80.276913 -379.810842)
			(xy 80.251167 -379.75068) (xy 80.233737 -379.687605) (xy 80.22494 -379.622759) (xy 80.224934 -379.55732)
			(xy 80.233721 -379.492473) (xy 80.25114 -379.429395) (xy 80.276877 -379.369228) (xy 80.29321 -379.340872)
			(xy 80.296581 -379.33486) (xy 80.300313 -379.321597) (xy 80.300576 -379.31471) (xy 80.300576 -378.56541)
			(xy 80.300342 -378.558519) (xy 80.296601 -378.545253) (xy 80.29321 -378.539248) (xy 80.276851 -378.510904)
			(xy 80.251111 -378.450734) (xy 80.233688 -378.387651) (xy 80.224899 -378.3228) (xy 76.79508 -378.3228)
			(xy 76.786291 -378.387646) (xy 76.768869 -378.450725) (xy 76.743131 -378.510891) (xy 76.726796 -378.539248)
			(xy 76.723464 -378.545264) (xy 76.719869 -378.558534) (xy 76.719684 -378.56541) (xy 76.719684 -379.31471)
			(xy 76.719874 -379.321583) (xy 76.723484 -379.334846) (xy 76.726796 -379.340872) (xy 76.743171 -379.369207)
			(xy 76.76891 -379.429379) (xy 76.786331 -379.492464) (xy 76.795118 -379.557317) (xy 76.795113 -379.622762)
			(xy 76.786315 -379.687614) (xy 76.768884 -379.750696) (xy 76.743135 -379.810863) (xy 76.726796 -379.83922)
			(xy 76.723474 -379.845241) (xy 76.719873 -379.858508) (xy 76.719684 -379.865382) (xy 76.719684 -380.151386)
			(xy 76.719156 -380.16154) (xy 76.71139 -380.180305) (xy 76.697035 -380.19467) (xy 76.678276 -380.202449)
			(xy 76.668122 -380.202948) (xy 75.951842 -380.202948) (xy 75.941671 -380.202501) (xy 75.922875 -380.194728)
			(xy 75.908488 -380.180349) (xy 75.900704 -380.161556) (xy 75.90028 -380.151386) (xy 75.90028 -379.865382)
			(xy 75.900098 -379.858508) (xy 75.896483 -379.845245) (xy 75.893168 -379.83922) (xy 75.876869 -379.810843)
			(xy 75.85112 -379.750681) (xy 75.833688 -379.687605) (xy 75.82489 -379.622759) (xy 75.824884 -379.557319)
			(xy 75.833672 -379.492472) (xy 75.851094 -379.429393) (xy 75.876833 -379.369228) (xy 75.893168 -379.340872)
			(xy 75.89649 -379.334851) (xy 75.900091 -379.321584) (xy 75.90028 -379.31471) (xy 75.90028 -378.56541)
			(xy 75.900087 -378.558537) (xy 75.896479 -378.545274) (xy 75.893168 -378.539248) (xy 75.876808 -378.510904)
			(xy 75.851064 -378.450735) (xy 75.833639 -378.387652) (xy 75.824848 -378.3228) (xy 72.395044 -378.3228)
			(xy 72.386254 -378.387647) (xy 72.368831 -378.450726) (xy 72.34309 -378.510892) (xy 72.326754 -378.539248)
			(xy 72.323374 -378.545255) (xy 72.319648 -378.558522) (xy 72.319388 -378.56541) (xy 72.319388 -379.31471)
			(xy 72.319584 -379.321606) (xy 72.323337 -379.334878) (xy 72.326754 -379.340872) (xy 72.343131 -379.369207)
			(xy 72.368871 -379.429378) (xy 72.386294 -379.492463) (xy 72.395082 -379.557316) (xy 72.395077 -379.622763)
			(xy 72.386278 -379.687615) (xy 72.368845 -379.750696) (xy 72.343095 -379.810864) (xy 72.326754 -379.83922)
			(xy 72.323383 -379.845232) (xy 72.319652 -379.858495) (xy 72.319388 -379.865382) (xy 72.319388 -380.151386)
			(xy 72.318863 -380.161508) (xy 72.311145 -380.180224) (xy 72.296871 -380.19458) (xy 72.278199 -380.202404)
			(xy 72.26808 -380.202948) (xy 71.5518 -380.202948) (xy 71.541652 -380.202479) (xy 71.522909 -380.194693)
			(xy 71.508587 -380.180311) (xy 71.500879 -380.161536) (xy 71.500492 -380.151386) (xy 71.500492 -379.865382)
			(xy 71.500228 -379.858493) (xy 71.496507 -379.845227) (xy 71.493126 -379.83922) (xy 71.476828 -379.810842)
			(xy 71.451081 -379.75068) (xy 71.433651 -379.687605) (xy 71.424853 -379.622759) (xy 71.424848 -379.55732)
			(xy 71.433635 -379.492473) (xy 71.451055 -379.429394) (xy 71.476792 -379.369228) (xy 71.493126 -379.340872)
			(xy 71.496498 -379.334861) (xy 71.500229 -379.321598) (xy 71.500492 -379.31471) (xy 71.500492 -378.56541)
			(xy 71.500256 -378.558519) (xy 71.496516 -378.545253) (xy 71.493126 -378.539248) (xy 71.476767 -378.510904)
			(xy 71.451026 -378.450734) (xy 71.433602 -378.387652) (xy 71.424812 -378.3228) (xy 56.704563 -378.3228)
			(xy 56.695485 -378.342166) (xy 56.664712 -378.388679) (xy 56.627495 -378.430216) (xy 56.584627 -378.465891)
			(xy 56.537021 -378.494945) (xy 56.485692 -378.516757) (xy 56.431735 -378.530863) (xy 56.376298 -378.536963)
			(xy 56.320564 -378.534926) (xy 56.265721 -378.524796) (xy 56.212937 -378.506789) (xy 56.163337 -378.481288)
			(xy 56.117979 -378.448837) (xy 56.07783 -378.410128) (xy 56.043744 -378.365985) (xy 56.016448 -378.31735)
			(xy 55.996525 -378.265259) (xy 55.984399 -378.210822) (xy 55.980328 -378.1552) (xy 55.584423 -378.1552)
			(xy 55.607095 -378.189468) (xy 55.630767 -378.239965) (xy 55.646835 -378.293372) (xy 55.654955 -378.348548)
			(xy 55.655464 -378.376434) (xy 55.654955 -378.40432) (xy 55.646835 -378.459496) (xy 55.630767 -378.512903)
			(xy 55.607095 -378.5634) (xy 55.576322 -378.609913) (xy 55.539105 -378.65145) (xy 55.496237 -378.687125)
			(xy 55.448631 -378.716179) (xy 55.397302 -378.737991) (xy 55.343345 -378.752097) (xy 55.287908 -378.758197)
			(xy 55.232174 -378.75616) (xy 55.177331 -378.74603) (xy 55.124547 -378.728023) (xy 55.074947 -378.702522)
			(xy 55.029589 -378.670071) (xy 54.98944 -378.631362) (xy 54.955354 -378.587219) (xy 54.928058 -378.538584)
			(xy 54.908135 -378.486493) (xy 54.896009 -378.432056) (xy 54.891938 -378.376434) (xy 51.556158 -378.376434)
			(xy 51.556158 -378.829316) (xy 58.842146 -378.829316) (xy 58.846217 -378.773694) (xy 58.858343 -378.719257)
			(xy 58.878266 -378.667166) (xy 58.905562 -378.618531) (xy 58.939648 -378.574388) (xy 58.979797 -378.535679)
			(xy 59.025155 -378.503228) (xy 59.074755 -378.477727) (xy 59.127539 -378.45972) (xy 59.182382 -378.44959)
			(xy 59.238116 -378.447553) (xy 59.293553 -378.453653) (xy 59.34751 -378.467759) (xy 59.398839 -378.489571)
			(xy 59.446445 -378.518625) (xy 59.489313 -378.5543) (xy 59.52653 -378.595837) (xy 59.557303 -378.64235)
			(xy 59.580975 -378.692847) (xy 59.597043 -378.746254) (xy 59.605163 -378.80143) (xy 59.605672 -378.829316)
			(xy 59.605163 -378.857202) (xy 59.597043 -378.912378) (xy 59.580975 -378.965785) (xy 59.557303 -379.016282)
			(xy 59.52653 -379.062795) (xy 59.489313 -379.104332) (xy 59.446445 -379.140007) (xy 59.398839 -379.169061)
			(xy 59.34751 -379.190873) (xy 59.293553 -379.204979) (xy 59.238116 -379.211079) (xy 59.182382 -379.209042)
			(xy 59.127539 -379.198912) (xy 59.074755 -379.180905) (xy 59.025155 -379.155404) (xy 58.979797 -379.122953)
			(xy 58.939648 -379.084244) (xy 58.905562 -379.040101) (xy 58.878266 -378.991466) (xy 58.858343 -378.939375)
			(xy 58.846217 -378.884938) (xy 58.842146 -378.829316) (xy 51.556158 -378.829316) (xy 51.556158 -379.659896)
			(xy 54.995316 -379.659896) (xy 54.999387 -379.604274) (xy 55.011513 -379.549837) (xy 55.031436 -379.497746)
			(xy 55.058732 -379.449111) (xy 55.092818 -379.404968) (xy 55.132967 -379.366259) (xy 55.178325 -379.333808)
			(xy 55.227925 -379.308307) (xy 55.280709 -379.2903) (xy 55.335552 -379.28017) (xy 55.391286 -379.278133)
			(xy 55.446723 -379.284233) (xy 55.50068 -379.298339) (xy 55.552009 -379.320151) (xy 55.599615 -379.349205)
			(xy 55.642483 -379.38488) (xy 55.6797 -379.426417) (xy 55.710473 -379.47293) (xy 55.734145 -379.523427)
			(xy 55.750213 -379.576834) (xy 55.758333 -379.63201) (xy 55.758842 -379.659896) (xy 55.758333 -379.687782)
			(xy 55.750213 -379.742958) (xy 55.734145 -379.796365) (xy 55.710473 -379.846862) (xy 55.6797 -379.893375)
			(xy 55.642483 -379.934912) (xy 55.599615 -379.970587) (xy 55.552009 -379.999641) (xy 55.50068 -380.021453)
			(xy 55.446723 -380.035559) (xy 55.391286 -380.041659) (xy 55.335552 -380.039622) (xy 55.280709 -380.029492)
			(xy 55.227925 -380.011485) (xy 55.178325 -379.985984) (xy 55.132967 -379.953533) (xy 55.092818 -379.914824)
			(xy 55.058732 -379.870681) (xy 55.031436 -379.822046) (xy 55.011513 -379.769955) (xy 54.999387 -379.715518)
			(xy 54.995316 -379.659896) (xy 51.556158 -379.659896) (xy 51.556158 -380.604268) (xy 56.220104 -380.604268)
			(xy 56.224175 -380.548646) (xy 56.236301 -380.494209) (xy 56.256224 -380.442118) (xy 56.28352 -380.393483)
			(xy 56.317606 -380.34934) (xy 56.357755 -380.310631) (xy 56.403113 -380.27818) (xy 56.452713 -380.252679)
			(xy 56.505497 -380.234672) (xy 56.56034 -380.224542) (xy 56.616074 -380.222505) (xy 56.671511 -380.228605)
			(xy 56.725468 -380.242711) (xy 56.776797 -380.264523) (xy 56.824403 -380.293577) (xy 56.867271 -380.329252)
			(xy 56.904488 -380.370789) (xy 56.935261 -380.417302) (xy 56.958933 -380.467799) (xy 56.975001 -380.521206)
			(xy 56.983121 -380.576382) (xy 56.98363 -380.604268) (xy 56.983121 -380.632154) (xy 56.979406 -380.657396)
			(xy 73.624731 -380.657396) (xy 73.633521 -380.592548) (xy 73.650944 -380.529469) (xy 73.676685 -380.469302)
			(xy 73.69302 -380.440946) (xy 73.69632 -380.434914) (xy 73.699935 -380.421656) (xy 73.700132 -380.414784)
			(xy 73.700132 -379.665484) (xy 73.699942 -379.658611) (xy 73.696332 -379.645348) (xy 73.69302 -379.639322)
			(xy 73.676724 -379.610943) (xy 73.650977 -379.550782) (xy 73.633547 -379.487706) (xy 73.624749 -379.422861)
			(xy 73.624744 -379.357421) (xy 73.63353 -379.292575) (xy 73.65095 -379.229496) (xy 73.676686 -379.16933)
			(xy 73.69302 -379.140974) (xy 73.696345 -379.134955) (xy 73.699944 -379.121687) (xy 73.700132 -379.114812)
			(xy 73.700132 -378.828554) (xy 73.700596 -378.818394) (xy 73.708384 -378.799625) (xy 73.722759 -378.785262)
			(xy 73.741534 -378.777488) (xy 73.751694 -378.776992) (xy 74.467974 -378.776992) (xy 74.478125 -378.777553)
			(xy 74.496884 -378.785311) (xy 74.511249 -378.799655) (xy 74.519032 -378.818404) (xy 74.519536 -378.828554)
			(xy 74.519536 -379.114812) (xy 74.519719 -379.121686) (xy 74.523333 -379.134949) (xy 74.526648 -379.140974)
			(xy 74.543026 -379.169308) (xy 74.568767 -379.229479) (xy 74.58619 -379.292564) (xy 74.594978 -379.357418)
			(xy 74.594972 -379.422864) (xy 74.586173 -379.487717) (xy 74.56874 -379.550798) (xy 74.542989 -379.610966)
			(xy 74.526648 -379.639322) (xy 74.523329 -379.645345) (xy 74.519726 -379.65861) (xy 74.519536 -379.665484)
			(xy 74.519536 -380.414784) (xy 74.51973 -380.421657) (xy 74.523336 -380.43492) (xy 74.526648 -380.440946)
			(xy 74.543003 -380.469293) (xy 74.568746 -380.529461) (xy 74.586171 -380.592544) (xy 74.594962 -380.657395)
			(xy 74.594962 -380.657396) (xy 78.024767 -380.657396) (xy 78.033558 -380.592547) (xy 78.050983 -380.529468)
			(xy 78.076725 -380.469302) (xy 78.093062 -380.440946) (xy 78.096446 -380.434941) (xy 78.100169 -380.421673)
			(xy 78.100428 -380.414784) (xy 78.100428 -379.665484) (xy 78.100194 -379.658591) (xy 78.096466 -379.645319)
			(xy 78.093062 -379.639322) (xy 78.076765 -379.610944) (xy 78.051016 -379.550782) (xy 78.033584 -379.487707)
			(xy 78.024786 -379.422861) (xy 78.02478 -379.357421) (xy 78.033567 -379.292574) (xy 78.050988 -379.229495)
			(xy 78.076727 -379.16933) (xy 78.093062 -379.140974) (xy 78.096436 -379.134964) (xy 78.100165 -379.1217)
			(xy 78.100428 -379.114812) (xy 78.100428 -378.828554) (xy 78.100889 -378.818426) (xy 78.108629 -378.799706)
			(xy 78.122923 -378.785352) (xy 78.14161 -378.777532) (xy 78.151736 -378.776992) (xy 78.868016 -378.776992)
			(xy 78.87817 -378.777408) (xy 78.896921 -378.785208) (xy 78.911244 -378.799606) (xy 78.918945 -378.818398)
			(xy 78.919324 -378.828554) (xy 78.919324 -379.114812) (xy 78.919566 -379.121704) (xy 78.923289 -379.134976)
			(xy 78.92669 -379.140974) (xy 78.943067 -379.169308) (xy 78.968806 -379.22948) (xy 78.986227 -379.292565)
			(xy 78.995014 -379.357418) (xy 78.995008 -379.422864) (xy 78.98621 -379.487716) (xy 78.968778 -379.550798)
			(xy 78.94303 -379.610965) (xy 78.92669 -379.639322) (xy 78.923321 -379.645335) (xy 78.919588 -379.658597)
			(xy 78.919324 -379.665484) (xy 78.919324 -380.414784) (xy 78.91956 -380.421675) (xy 78.9233 -380.434941)
			(xy 78.92669 -380.440946) (xy 78.943043 -380.469293) (xy 78.968784 -380.529462) (xy 78.986208 -380.592544)
			(xy 78.994998 -380.657395) (xy 78.994998 -380.657397) (xy 82.424817 -380.657397) (xy 82.433607 -380.592548)
			(xy 82.45103 -380.529469) (xy 82.476769 -380.469303) (xy 82.493104 -380.440946) (xy 82.496403 -380.434914)
			(xy 82.500018 -380.421656) (xy 82.500216 -380.414784) (xy 82.500216 -379.665484) (xy 82.500028 -379.65861)
			(xy 82.496417 -379.645348) (xy 82.493104 -379.639322) (xy 82.476808 -379.610943) (xy 82.451063 -379.550781)
			(xy 82.433633 -379.487706) (xy 82.424836 -379.422861) (xy 82.42483 -379.357422) (xy 82.433616 -379.292575)
			(xy 82.451035 -379.229497) (xy 82.476771 -379.16933) (xy 82.493104 -379.140974) (xy 82.496428 -379.134954)
			(xy 82.500028 -379.121687) (xy 82.500216 -379.114812) (xy 82.500216 -378.828554) (xy 82.500695 -378.818396)
			(xy 82.508481 -378.79963) (xy 82.52285 -378.785267) (xy 82.54162 -378.777491) (xy 82.551778 -378.776992)
			(xy 83.268058 -378.776992) (xy 83.278207 -378.777567) (xy 83.296967 -378.785319) (xy 83.311332 -378.799659)
			(xy 83.319116 -378.818405) (xy 83.31962 -378.828554) (xy 83.31962 -379.114812) (xy 83.319805 -379.121686)
			(xy 83.323418 -379.134949) (xy 83.326732 -379.140974) (xy 83.343111 -379.169307) (xy 83.368853 -379.229479)
			(xy 83.386276 -379.292564) (xy 83.395064 -379.357418) (xy 83.395058 -379.422864) (xy 83.386259 -379.487717)
			(xy 83.368825 -379.550799) (xy 83.343073 -379.610966) (xy 83.326732 -379.639322) (xy 83.323412 -379.645344)
			(xy 83.319809 -379.65861) (xy 83.31962 -379.665484) (xy 83.31962 -380.414784) (xy 83.319816 -380.421657)
			(xy 83.323421 -380.43492) (xy 83.326732 -380.440946) (xy 83.343087 -380.469293) (xy 83.368831 -380.529461)
			(xy 83.386257 -380.592543) (xy 83.395048 -380.657395) (xy 83.395048 -380.657396) (xy 86.824853 -380.657396)
			(xy 86.833644 -380.592548) (xy 86.851068 -380.529468) (xy 86.87681 -380.469302) (xy 86.893146 -380.440946)
			(xy 86.896529 -380.43494) (xy 86.900252 -380.421673) (xy 86.900512 -380.414784) (xy 86.900512 -379.665484)
			(xy 86.90028 -379.658591) (xy 86.896551 -379.645319) (xy 86.893146 -379.639322) (xy 86.876849 -379.610943)
			(xy 86.851101 -379.550782) (xy 86.83367 -379.487707) (xy 86.824872 -379.422861) (xy 86.824866 -379.357421)
			(xy 86.833653 -379.292574) (xy 86.851074 -379.229496) (xy 86.876812 -379.16933) (xy 86.893146 -379.140974)
			(xy 86.896519 -379.134963) (xy 86.900249 -379.1217) (xy 86.900512 -379.114812) (xy 86.900512 -378.828554)
			(xy 86.900988 -378.818428) (xy 86.908726 -378.799711) (xy 86.923015 -378.785357) (xy 86.941696 -378.777535)
			(xy 86.95182 -378.776992) (xy 87.6681 -378.776992) (xy 87.678253 -378.777422) (xy 87.697004 -378.785216)
			(xy 87.711327 -378.79961) (xy 87.719028 -378.818399) (xy 87.719408 -378.828554) (xy 87.719408 -379.114812)
			(xy 87.719674 -379.121701) (xy 87.723394 -379.134967) (xy 87.726774 -379.140974) (xy 87.743152 -379.169308)
			(xy 87.768891 -379.22948) (xy 87.786313 -379.292565) (xy 87.7951 -379.357418) (xy 87.795095 -379.422864)
			(xy 87.786296 -379.487716) (xy 87.768864 -379.550798) (xy 87.752067 -379.590046) (xy 89.023706 -379.590046)
			(xy 89.027697 -379.527879) (xy 89.039606 -379.466732) (xy 89.059235 -379.407611) (xy 89.086264 -379.351485)
			(xy 89.120248 -379.299276) (xy 89.16063 -379.251841) (xy 89.206746 -379.20996) (xy 89.257838 -379.17432)
			(xy 89.313069 -379.145506) (xy 89.371531 -379.123992) (xy 89.432265 -379.11013) (xy 89.494272 -379.104148)
			(xy 89.556535 -379.106144) (xy 89.618032 -379.116087) (xy 89.677753 -379.133811) (xy 89.734716 -379.159028)
			(xy 89.787987 -379.191321) (xy 89.836692 -379.230161) (xy 89.880029 -379.274911) (xy 89.917289 -379.324835)
			(xy 89.947858 -379.379114) (xy 89.952325 -379.390148) (xy 91.223854 -379.390148) (xy 91.227845 -379.327981)
			(xy 91.239754 -379.266834) (xy 91.259383 -379.207713) (xy 91.286412 -379.151587) (xy 91.320396 -379.099378)
			(xy 91.360778 -379.051943) (xy 91.406894 -379.010062) (xy 91.457986 -378.974422) (xy 91.513217 -378.945608)
			(xy 91.571679 -378.924094) (xy 91.632413 -378.910232) (xy 91.69442 -378.90425) (xy 91.756683 -378.906246)
			(xy 91.81818 -378.916189) (xy 91.877901 -378.933913) (xy 91.934864 -378.95913) (xy 91.988135 -378.991423)
			(xy 92.03684 -379.030263) (xy 92.080177 -379.075013) (xy 92.117437 -379.124937) (xy 92.148006 -379.179216)
			(xy 92.171384 -379.236959) (xy 92.187185 -379.297217) (xy 92.195151 -379.359) (xy 92.19565 -379.390148)
			(xy 92.195151 -379.421296) (xy 92.187185 -379.483079) (xy 92.171384 -379.543337) (xy 92.148006 -379.60108)
			(xy 92.117437 -379.655359) (xy 92.080177 -379.705283) (xy 92.03684 -379.750033) (xy 91.988135 -379.788873)
			(xy 91.934864 -379.821166) (xy 91.877901 -379.846383) (xy 91.81818 -379.864107) (xy 91.756683 -379.87405)
			(xy 91.69442 -379.876046) (xy 91.632413 -379.870064) (xy 91.571679 -379.856202) (xy 91.513217 -379.834688)
			(xy 91.457986 -379.805874) (xy 91.406894 -379.770234) (xy 91.360778 -379.728353) (xy 91.320396 -379.680918)
			(xy 91.286412 -379.628709) (xy 91.259383 -379.572583) (xy 91.239754 -379.513462) (xy 91.227845 -379.452315)
			(xy 91.223854 -379.390148) (xy 89.952325 -379.390148) (xy 89.971236 -379.436857) (xy 89.987037 -379.497115)
			(xy 89.995003 -379.558898) (xy 89.995502 -379.590046) (xy 89.995003 -379.621194) (xy 89.987037 -379.682977)
			(xy 89.971236 -379.743235) (xy 89.947858 -379.800978) (xy 89.917289 -379.855257) (xy 89.880029 -379.905181)
			(xy 89.836692 -379.949931) (xy 89.787987 -379.988771) (xy 89.734716 -380.021064) (xy 89.677753 -380.046281)
			(xy 89.618032 -380.064005) (xy 89.556535 -380.073948) (xy 89.494272 -380.075944) (xy 89.432265 -380.069962)
			(xy 89.371531 -380.0561) (xy 89.313069 -380.034586) (xy 89.257838 -380.005772) (xy 89.206746 -379.970132)
			(xy 89.16063 -379.928251) (xy 89.120248 -379.880816) (xy 89.086264 -379.828607) (xy 89.059235 -379.772481)
			(xy 89.039606 -379.71336) (xy 89.027697 -379.652213) (xy 89.023706 -379.590046) (xy 87.752067 -379.590046)
			(xy 87.743114 -379.610966) (xy 87.726774 -379.639322) (xy 87.723404 -379.645334) (xy 87.719672 -379.658597)
			(xy 87.719408 -379.665484) (xy 87.719408 -380.414784) (xy 87.719646 -380.421675) (xy 87.723385 -380.434941)
			(xy 87.726774 -380.440946) (xy 87.743128 -380.469293) (xy 87.76887 -380.529462) (xy 87.786294 -380.592544)
			(xy 87.795084 -380.657395) (xy 87.795083 -380.69012) (xy 91.223854 -380.69012) (xy 91.227845 -380.627953)
			(xy 91.239754 -380.566806) (xy 91.259383 -380.507685) (xy 91.286412 -380.451559) (xy 91.320396 -380.39935)
			(xy 91.360778 -380.351915) (xy 91.406894 -380.310034) (xy 91.457986 -380.274394) (xy 91.513217 -380.24558)
			(xy 91.571679 -380.224066) (xy 91.632413 -380.210204) (xy 91.69442 -380.204222) (xy 91.756683 -380.206218)
			(xy 91.81818 -380.216161) (xy 91.877901 -380.233885) (xy 91.934864 -380.259102) (xy 91.988135 -380.291395)
			(xy 92.03684 -380.330235) (xy 92.080177 -380.374985) (xy 92.117437 -380.424909) (xy 92.148006 -380.479188)
			(xy 92.171384 -380.536931) (xy 92.187185 -380.597189) (xy 92.195151 -380.658972) (xy 92.19565 -380.69012)
			(xy 92.195151 -380.721268) (xy 92.187185 -380.783051) (xy 92.171384 -380.843309) (xy 92.148006 -380.901052)
			(xy 92.117437 -380.955331) (xy 92.080177 -381.005255) (xy 92.03684 -381.050005) (xy 91.988135 -381.088845)
			(xy 91.934864 -381.121138) (xy 91.877901 -381.146355) (xy 91.81818 -381.164079) (xy 91.756683 -381.174022)
			(xy 91.69442 -381.176018) (xy 91.632413 -381.170036) (xy 91.571679 -381.156174) (xy 91.513217 -381.13466)
			(xy 91.457986 -381.105846) (xy 91.406894 -381.070206) (xy 91.360778 -381.028325) (xy 91.320396 -380.98089)
			(xy 91.286412 -380.928681) (xy 91.259383 -380.872555) (xy 91.239754 -380.813434) (xy 91.227845 -380.752287)
			(xy 91.223854 -380.69012) (xy 87.795083 -380.69012) (xy 87.795082 -380.722839) (xy 87.786287 -380.78769)
			(xy 87.768858 -380.85077) (xy 87.743112 -380.910938) (xy 87.726774 -380.939294) (xy 87.723414 -380.945311)
			(xy 87.719676 -380.95857) (xy 87.719408 -380.965456) (xy 87.719408 -381.251206) (xy 87.71888 -381.261327)
			(xy 87.711159 -381.280039) (xy 87.704386 -381.286851) (xy 100.042966 -381.286851) (xy 100.042966 -381.232349)
			(xy 100.050722 -381.178401) (xy 100.066077 -381.126106) (xy 100.088717 -381.076529) (xy 100.118182 -381.030678)
			(xy 100.153873 -380.989487) (xy 100.195062 -380.953794) (xy 100.240911 -380.924327) (xy 100.290488 -380.901684)
			(xy 100.342782 -380.886326) (xy 100.396729 -380.878567) (xy 100.42398 -380.87808) (xy 100.453271 -380.878598)
			(xy 100.511167 -380.887545) (xy 100.567016 -380.905232) (xy 100.619507 -380.931244) (xy 100.667407 -380.96497)
			(xy 100.709593 -381.005618) (xy 100.745074 -381.052234) (xy 100.759514 -381.077724) (xy 100.766512 -381.089738)
			(xy 100.78586 -381.109691) (xy 100.809873 -381.123686) (xy 100.83677 -381.130687) (xy 100.864559 -381.130175)
			(xy 100.89118 -381.122187) (xy 100.91466 -381.107316) (xy 100.93326 -381.086664) (xy 100.939854 -381.074422)
			(xy 100.952016 -381.050864) (xy 100.981867 -381.007049) (xy 101.017499 -380.967792) (xy 101.058226 -380.93385)
			(xy 101.103263 -380.905877) (xy 101.15174 -380.884412) (xy 101.202723 -380.86987) (xy 101.25523 -380.862531)
			(xy 101.281738 -380.862078) (xy 101.308986 -380.862595) (xy 101.362928 -380.870355) (xy 101.387499 -380.877572)
			(xy 105.0036 -380.877572) (xy 105.0036 -380.013972) (xy 105.00409 -379.983988) (xy 105.011918 -379.924532)
			(xy 105.027439 -379.866607) (xy 105.050388 -379.811203) (xy 105.080372 -379.759269) (xy 105.116878 -379.711693)
			(xy 105.159283 -379.669288) (xy 105.206859 -379.632782) (xy 105.258793 -379.602798) (xy 105.314197 -379.579849)
			(xy 105.372122 -379.564328) (xy 105.431578 -379.5565) (xy 105.491546 -379.5565) (xy 105.551002 -379.564328)
			(xy 105.608927 -379.579849) (xy 105.664331 -379.602798) (xy 105.716265 -379.632782) (xy 105.763841 -379.669288)
			(xy 105.806246 -379.711693) (xy 105.842752 -379.759269) (xy 105.872736 -379.811203) (xy 105.895685 -379.866607)
			(xy 105.911206 -379.924532) (xy 105.919034 -379.983988) (xy 105.919524 -380.013972) (xy 105.919524 -380.657396)
			(xy 117.624888 -380.657396) (xy 117.633679 -380.592547) (xy 117.651105 -380.529468) (xy 117.676849 -380.469302)
			(xy 117.693186 -380.440946) (xy 117.696564 -380.434938) (xy 117.700292 -380.421672) (xy 117.700552 -380.414784)
			(xy 117.700552 -379.665484) (xy 117.700315 -379.658592) (xy 117.696589 -379.645319) (xy 117.693186 -379.639322)
			(xy 117.676888 -379.610944) (xy 117.651138 -379.550783) (xy 117.633705 -379.487707) (xy 117.624906 -379.422861)
			(xy 117.624901 -379.357421) (xy 117.633688 -379.292574) (xy 117.65111 -379.229495) (xy 117.67685 -379.16933)
			(xy 117.693186 -379.140974) (xy 117.696554 -379.134961) (xy 117.700288 -379.121699) (xy 117.700552 -379.114812)
			(xy 117.700552 -378.828554) (xy 117.700989 -378.818423) (xy 117.708734 -378.799698) (xy 117.723036 -378.785343)
			(xy 117.741731 -378.777528) (xy 117.75186 -378.776992) (xy 118.46814 -378.776992) (xy 118.478296 -378.777389)
			(xy 118.497047 -378.785196) (xy 118.511369 -378.7996) (xy 118.519069 -378.818396) (xy 118.519448 -378.828554)
			(xy 118.519448 -379.114812) (xy 118.519687 -379.121704) (xy 118.523411 -379.134976) (xy 118.526814 -379.140974)
			(xy 118.543194 -379.169307) (xy 118.568936 -379.229479) (xy 118.58636 -379.292564) (xy 118.595149 -379.357418)
			(xy 118.595143 -379.422865) (xy 118.586343 -379.487717) (xy 118.568909 -379.550799) (xy 118.543156 -379.610966)
			(xy 118.526814 -379.639322) (xy 118.523447 -379.645336) (xy 118.519712 -379.658597) (xy 118.519448 -379.665484)
			(xy 118.519448 -380.414784) (xy 118.519659 -380.421679) (xy 118.523403 -380.43495) (xy 118.526814 -380.440946)
			(xy 118.54317 -380.469292) (xy 118.568915 -380.529461) (xy 118.586341 -380.592543) (xy 118.595133 -380.657395)
			(xy 118.595133 -380.657396) (xy 122.024938 -380.657396) (xy 122.033728 -380.592548) (xy 122.051152 -380.529469)
			(xy 122.076892 -380.469302) (xy 122.093228 -380.440946) (xy 122.096528 -380.434914) (xy 122.100143 -380.421656)
			(xy 122.10034 -380.414784) (xy 122.10034 -379.665484) (xy 122.100149 -379.658611) (xy 122.09654 -379.645348)
			(xy 122.093228 -379.639322) (xy 122.076932 -379.610943) (xy 122.051185 -379.550782) (xy 122.033754 -379.487706)
			(xy 122.024956 -379.422861) (xy 122.024951 -379.357421) (xy 122.033737 -379.292575) (xy 122.051157 -379.229496)
			(xy 122.076894 -379.16933) (xy 122.093228 -379.140974) (xy 122.096554 -379.134955) (xy 122.100152 -379.121687)
			(xy 122.10034 -379.114812) (xy 122.10034 -378.828554) (xy 122.100796 -378.818393) (xy 122.108586 -378.799623)
			(xy 122.122963 -378.785259) (xy 122.141741 -378.777486) (xy 122.151902 -378.776992) (xy 122.868182 -378.776992)
			(xy 122.878333 -378.777547) (xy 122.897093 -378.785307) (xy 122.911457 -378.799653) (xy 122.919241 -378.818404)
			(xy 122.919744 -378.828554) (xy 122.919744 -379.114812) (xy 122.919926 -379.121686) (xy 122.92354 -379.134949)
			(xy 122.926856 -379.140974) (xy 122.943234 -379.169308) (xy 122.968975 -379.22948) (xy 122.986397 -379.292564)
			(xy 122.995185 -379.357418) (xy 122.995179 -379.422864) (xy 122.98638 -379.487716) (xy 122.968947 -379.550798)
			(xy 122.943197 -379.610966) (xy 122.926856 -379.639322) (xy 122.923538 -379.645345) (xy 122.919934 -379.65861)
			(xy 122.919744 -379.665484) (xy 122.919744 -380.414784) (xy 122.919937 -380.421657) (xy 122.923544 -380.43492)
			(xy 122.926856 -380.440946) (xy 122.94321 -380.469293) (xy 122.968953 -380.529462) (xy 122.986378 -380.592544)
			(xy 122.995169 -380.657395) (xy 122.995169 -380.657396) (xy 126.424974 -380.657396) (xy 126.433765 -380.592547)
			(xy 126.45119 -380.529468) (xy 126.476933 -380.469302) (xy 126.49327 -380.440946) (xy 126.496655 -380.434941)
			(xy 126.500377 -380.421673) (xy 126.500636 -380.414784) (xy 126.500636 -379.665484) (xy 126.500401 -379.658591)
			(xy 126.496674 -379.645319) (xy 126.49327 -379.639322) (xy 126.476972 -379.610944) (xy 126.451223 -379.550783)
			(xy 126.433791 -379.487707) (xy 126.424992 -379.422861) (xy 126.424987 -379.357421) (xy 126.433774 -379.292574)
			(xy 126.451196 -379.229495) (xy 126.476935 -379.16933) (xy 126.49327 -379.140974) (xy 126.496645 -379.134964)
			(xy 126.500373 -379.1217) (xy 126.500636 -379.114812) (xy 126.500636 -378.828554) (xy 126.501089 -378.818425)
			(xy 126.508831 -378.799703) (xy 126.523127 -378.785349) (xy 126.541817 -378.777531) (xy 126.551944 -378.776992)
			(xy 127.268224 -378.776992) (xy 127.278379 -378.777402) (xy 127.29713 -378.785204) (xy 127.311452 -378.799604)
			(xy 127.319153 -378.818397) (xy 127.319532 -378.828554) (xy 127.319532 -379.114812) (xy 127.319773 -379.121704)
			(xy 127.323496 -379.134976) (xy 127.326898 -379.140974) (xy 127.343275 -379.169308) (xy 127.369013 -379.22948)
			(xy 127.386434 -379.292565) (xy 127.395221 -379.357418) (xy 127.395215 -379.422864) (xy 127.386417 -379.487716)
			(xy 127.368986 -379.550797) (xy 127.343237 -379.610965) (xy 127.326898 -379.639322) (xy 127.32353 -379.645335)
			(xy 127.319796 -379.658597) (xy 127.319532 -379.665484) (xy 127.319532 -380.414784) (xy 127.319767 -380.421675)
			(xy 127.323508 -380.434941) (xy 127.326898 -380.440946) (xy 127.343251 -380.469293) (xy 127.368992 -380.529462)
			(xy 127.386415 -380.592544) (xy 127.395205 -380.657395) (xy 127.395205 -380.657397) (xy 130.825024 -380.657397)
			(xy 130.833814 -380.592548) (xy 130.851237 -380.529469) (xy 130.876977 -380.469302) (xy 130.893312 -380.440946)
			(xy 130.896611 -380.434914) (xy 130.900226 -380.421656) (xy 130.900424 -380.414784) (xy 130.900424 -379.665484)
			(xy 130.900235 -379.658611) (xy 130.896624 -379.645348) (xy 130.893312 -379.639322) (xy 130.877016 -379.610943)
			(xy 130.85127 -379.550781) (xy 130.83384 -379.487706) (xy 130.825042 -379.422861) (xy 130.825037 -379.357421)
			(xy 130.833823 -379.292575) (xy 130.851243 -379.229496) (xy 130.876979 -379.16933) (xy 130.893312 -379.140974)
			(xy 130.896637 -379.134954) (xy 130.900236 -379.121687) (xy 130.900424 -379.114812) (xy 130.900424 -378.828554)
			(xy 130.900895 -378.818395) (xy 130.908682 -378.799628) (xy 130.923054 -378.785264) (xy 130.941827 -378.777489)
			(xy 130.951986 -378.776992) (xy 131.668266 -378.776992) (xy 131.678416 -378.77756) (xy 131.697175 -378.785315)
			(xy 131.71154 -378.799657) (xy 131.719324 -378.818405) (xy 131.719828 -378.828554) (xy 131.719828 -379.114812)
			(xy 131.720012 -379.121686) (xy 131.723625 -379.134949) (xy 131.72694 -379.140974) (xy 131.743319 -379.169307)
			(xy 131.76906 -379.229479) (xy 131.786483 -379.292564) (xy 131.795271 -379.357418) (xy 131.795265 -379.422864)
			(xy 131.786466 -379.487717) (xy 131.769033 -379.550799) (xy 131.752235 -379.590046) (xy 133.023872 -379.590046)
			(xy 133.027863 -379.527879) (xy 133.039772 -379.466732) (xy 133.059401 -379.407611) (xy 133.08643 -379.351485)
			(xy 133.120414 -379.299276) (xy 133.160796 -379.251841) (xy 133.206912 -379.20996) (xy 133.258004 -379.17432)
			(xy 133.313235 -379.145506) (xy 133.371697 -379.123992) (xy 133.432431 -379.11013) (xy 133.494438 -379.104148)
			(xy 133.556701 -379.106144) (xy 133.618198 -379.116087) (xy 133.677919 -379.133811) (xy 133.734882 -379.159028)
			(xy 133.788153 -379.191321) (xy 133.836858 -379.230161) (xy 133.880195 -379.274911) (xy 133.917455 -379.324835)
			(xy 133.948024 -379.379114) (xy 133.952491 -379.390148) (xy 135.22402 -379.390148) (xy 135.228011 -379.327981)
			(xy 135.23992 -379.266834) (xy 135.259549 -379.207713) (xy 135.286578 -379.151587) (xy 135.320562 -379.099378)
			(xy 135.360944 -379.051943) (xy 135.40706 -379.010062) (xy 135.458152 -378.974422) (xy 135.513383 -378.945608)
			(xy 135.571845 -378.924094) (xy 135.632579 -378.910232) (xy 135.694586 -378.90425) (xy 135.756849 -378.906246)
			(xy 135.818346 -378.916189) (xy 135.878067 -378.933913) (xy 135.93503 -378.95913) (xy 135.988301 -378.991423)
			(xy 136.037006 -379.030263) (xy 136.080343 -379.075013) (xy 136.117603 -379.124937) (xy 136.148172 -379.179216)
			(xy 136.17155 -379.236959) (xy 136.187351 -379.297217) (xy 136.195317 -379.359) (xy 136.195816 -379.390148)
			(xy 136.195714 -379.396498) (xy 147.395944 -379.396498) (xy 147.400015 -379.340876) (xy 147.412141 -379.286439)
			(xy 147.432064 -379.234348) (xy 147.45936 -379.185713) (xy 147.493446 -379.14157) (xy 147.533595 -379.102861)
			(xy 147.578953 -379.07041) (xy 147.628553 -379.044909) (xy 147.681337 -379.026902) (xy 147.73618 -379.016772)
			(xy 147.791914 -379.014735) (xy 147.847351 -379.020835) (xy 147.901308 -379.034941) (xy 147.952637 -379.056753)
			(xy 148.000243 -379.085807) (xy 148.043111 -379.121482) (xy 148.080328 -379.163019) (xy 148.111101 -379.209532)
			(xy 148.134773 -379.260029) (xy 148.150841 -379.313436) (xy 148.158961 -379.368612) (xy 148.15947 -379.396498)
			(xy 148.158961 -379.424384) (xy 148.150841 -379.47956) (xy 148.134773 -379.532967) (xy 148.111101 -379.583464)
			(xy 148.080328 -379.629977) (xy 148.043111 -379.671514) (xy 148.000243 -379.707189) (xy 147.952637 -379.736243)
			(xy 147.901308 -379.758055) (xy 147.847351 -379.772161) (xy 147.791914 -379.778261) (xy 147.73618 -379.776224)
			(xy 147.681337 -379.766094) (xy 147.628553 -379.748087) (xy 147.578953 -379.722586) (xy 147.533595 -379.690135)
			(xy 147.493446 -379.651426) (xy 147.45936 -379.607283) (xy 147.432064 -379.558648) (xy 147.412141 -379.506557)
			(xy 147.400015 -379.45212) (xy 147.395944 -379.396498) (xy 136.195714 -379.396498) (xy 136.195317 -379.421296)
			(xy 136.187351 -379.483079) (xy 136.17155 -379.543337) (xy 136.148172 -379.60108) (xy 136.117603 -379.655359)
			(xy 136.080343 -379.705283) (xy 136.037006 -379.750033) (xy 135.988301 -379.788873) (xy 135.93503 -379.821166)
			(xy 135.878067 -379.846383) (xy 135.818346 -379.864107) (xy 135.756849 -379.87405) (xy 135.694586 -379.876046)
			(xy 135.632579 -379.870064) (xy 135.571845 -379.856202) (xy 135.513383 -379.834688) (xy 135.458152 -379.805874)
			(xy 135.40706 -379.770234) (xy 135.360944 -379.728353) (xy 135.320562 -379.680918) (xy 135.286578 -379.628709)
			(xy 135.259549 -379.572583) (xy 135.23992 -379.513462) (xy 135.228011 -379.452315) (xy 135.22402 -379.390148)
			(xy 133.952491 -379.390148) (xy 133.971402 -379.436857) (xy 133.987203 -379.497115) (xy 133.995169 -379.558898)
			(xy 133.995668 -379.590046) (xy 133.995169 -379.621194) (xy 133.987203 -379.682977) (xy 133.971402 -379.743235)
			(xy 133.948024 -379.800978) (xy 133.917455 -379.855257) (xy 133.880515 -379.904752) (xy 149.687786 -379.904752)
			(xy 149.691857 -379.84913) (xy 149.703983 -379.794693) (xy 149.723906 -379.742602) (xy 149.751202 -379.693967)
			(xy 149.785288 -379.649824) (xy 149.825437 -379.611115) (xy 149.870795 -379.578664) (xy 149.920395 -379.553163)
			(xy 149.973179 -379.535156) (xy 150.028022 -379.525026) (xy 150.083756 -379.522989) (xy 150.139193 -379.529089)
			(xy 150.19315 -379.543195) (xy 150.244479 -379.565007) (xy 150.292085 -379.594061) (xy 150.334953 -379.629736)
			(xy 150.37217 -379.671273) (xy 150.402943 -379.717786) (xy 150.426615 -379.768283) (xy 150.442683 -379.82169)
			(xy 150.450803 -379.876866) (xy 150.451312 -379.904752) (xy 150.450803 -379.932638) (xy 150.442683 -379.987814)
			(xy 150.426615 -380.041221) (xy 150.402943 -380.091718) (xy 150.37217 -380.138231) (xy 150.334953 -380.179768)
			(xy 150.292085 -380.215443) (xy 150.244479 -380.244497) (xy 150.19315 -380.266309) (xy 150.139193 -380.280415)
			(xy 150.083756 -380.286515) (xy 150.028022 -380.284478) (xy 149.973179 -380.274348) (xy 149.920395 -380.256341)
			(xy 149.870795 -380.23084) (xy 149.825437 -380.198389) (xy 149.785288 -380.15968) (xy 149.751202 -380.115537)
			(xy 149.723906 -380.066902) (xy 149.703983 -380.014811) (xy 149.691857 -379.960374) (xy 149.687786 -379.904752)
			(xy 133.880515 -379.904752) (xy 133.880195 -379.905181) (xy 133.836858 -379.949931) (xy 133.788153 -379.988771)
			(xy 133.734882 -380.021064) (xy 133.677919 -380.046281) (xy 133.618198 -380.064005) (xy 133.556701 -380.073948)
			(xy 133.494438 -380.075944) (xy 133.432431 -380.069962) (xy 133.371697 -380.0561) (xy 133.313235 -380.034586)
			(xy 133.258004 -380.005772) (xy 133.206912 -379.970132) (xy 133.160796 -379.928251) (xy 133.120414 -379.880816)
			(xy 133.08643 -379.828607) (xy 133.059401 -379.772481) (xy 133.039772 -379.71336) (xy 133.027863 -379.652213)
			(xy 133.023872 -379.590046) (xy 131.752235 -379.590046) (xy 131.743281 -379.610966) (xy 131.72694 -379.639322)
			(xy 131.723621 -379.645344) (xy 131.720018 -379.65861) (xy 131.719828 -379.665484) (xy 131.719828 -380.414784)
			(xy 131.720023 -380.421657) (xy 131.723629 -380.43492) (xy 131.72694 -380.440946) (xy 131.743295 -380.469293)
			(xy 131.769038 -380.529461) (xy 131.786464 -380.592543) (xy 131.795255 -380.657395) (xy 131.795254 -380.69012)
			(xy 135.22402 -380.69012) (xy 135.228011 -380.627953) (xy 135.23992 -380.566806) (xy 135.259549 -380.507685)
			(xy 135.286578 -380.451559) (xy 135.320562 -380.39935) (xy 135.360944 -380.351915) (xy 135.40706 -380.310034)
			(xy 135.458152 -380.274394) (xy 135.513383 -380.24558) (xy 135.571845 -380.224066) (xy 135.632579 -380.210204)
			(xy 135.694586 -380.204222) (xy 135.756849 -380.206218) (xy 135.818346 -380.216161) (xy 135.878067 -380.233885)
			(xy 135.93503 -380.259102) (xy 135.988301 -380.291395) (xy 136.037006 -380.330235) (xy 136.080343 -380.374985)
			(xy 136.117603 -380.424909) (xy 136.12077 -380.430532) (xy 146.648168 -380.430532) (xy 146.652239 -380.37491)
			(xy 146.664365 -380.320473) (xy 146.684288 -380.268382) (xy 146.711584 -380.219747) (xy 146.74567 -380.175604)
			(xy 146.785819 -380.136895) (xy 146.831177 -380.104444) (xy 146.880777 -380.078943) (xy 146.933561 -380.060936)
			(xy 146.988404 -380.050806) (xy 147.044138 -380.048769) (xy 147.099575 -380.054869) (xy 147.153532 -380.068975)
			(xy 147.204861 -380.090787) (xy 147.252467 -380.119841) (xy 147.295335 -380.155516) (xy 147.332552 -380.197053)
			(xy 147.363325 -380.243566) (xy 147.386997 -380.294063) (xy 147.403065 -380.34747) (xy 147.411185 -380.402646)
			(xy 147.411694 -380.430532) (xy 147.411185 -380.458418) (xy 147.403065 -380.513594) (xy 147.386997 -380.567001)
			(xy 147.363325 -380.617498) (xy 147.332552 -380.664011) (xy 147.295335 -380.705548) (xy 147.252467 -380.741223)
			(xy 147.204861 -380.770277) (xy 147.153532 -380.792089) (xy 147.099575 -380.806195) (xy 147.044138 -380.812295)
			(xy 146.988404 -380.810258) (xy 146.933561 -380.800128) (xy 146.880777 -380.782121) (xy 146.831177 -380.75662)
			(xy 146.785819 -380.724169) (xy 146.74567 -380.68546) (xy 146.711584 -380.641317) (xy 146.684288 -380.592682)
			(xy 146.664365 -380.540591) (xy 146.652239 -380.486154) (xy 146.648168 -380.430532) (xy 136.12077 -380.430532)
			(xy 136.148172 -380.479188) (xy 136.17155 -380.536931) (xy 136.187351 -380.597189) (xy 136.195317 -380.658972)
			(xy 136.195816 -380.69012) (xy 136.195317 -380.721268) (xy 136.187351 -380.783051) (xy 136.17155 -380.843309)
			(xy 136.148172 -380.901052) (xy 136.117603 -380.955331) (xy 136.080343 -381.005255) (xy 136.037006 -381.050005)
			(xy 135.988301 -381.088845) (xy 135.93503 -381.121138) (xy 135.878067 -381.146355) (xy 135.818346 -381.164079)
			(xy 135.756849 -381.174022) (xy 135.694586 -381.176018) (xy 135.632579 -381.170036) (xy 135.571845 -381.156174)
			(xy 135.513383 -381.13466) (xy 135.458152 -381.105846) (xy 135.40706 -381.070206) (xy 135.360944 -381.028325)
			(xy 135.320562 -380.98089) (xy 135.286578 -380.928681) (xy 135.259549 -380.872555) (xy 135.23992 -380.813434)
			(xy 135.228011 -380.752287) (xy 135.22402 -380.69012) (xy 131.795254 -380.69012) (xy 131.795253 -380.722839)
			(xy 131.786457 -380.78769) (xy 131.769027 -380.850771) (xy 131.743279 -380.910938) (xy 131.72694 -380.939294)
			(xy 131.723631 -380.945321) (xy 131.720021 -380.958583) (xy 131.719828 -380.965456) (xy 131.719828 -381.251206)
			(xy 131.71944 -381.261382) (xy 131.711647 -381.280184) (xy 131.69725 -381.294569) (xy 131.678443 -381.302348)
			(xy 131.668266 -381.302768) (xy 130.951986 -381.302768) (xy 130.941828 -381.302278) (xy 130.92306 -381.2945)
			(xy 130.908695 -381.280133) (xy 130.90092 -381.261364) (xy 130.900424 -381.251206) (xy 130.900424 -380.965456)
			(xy 130.900208 -380.958585) (xy 130.896616 -380.945322) (xy 130.893312 -380.939294) (xy 130.876992 -380.910928)
			(xy 130.851248 -380.850763) (xy 130.833821 -380.787685) (xy 130.825027 -380.722838) (xy 130.825024 -380.657397)
			(xy 127.395205 -380.657397) (xy 127.395203 -380.722839) (xy 127.386408 -380.787689) (xy 127.36898 -380.85077)
			(xy 127.343236 -380.910937) (xy 127.326898 -380.939294) (xy 127.32354 -380.945312) (xy 127.3198 -380.95857)
			(xy 127.319532 -380.965456) (xy 127.319532 -381.251206) (xy 127.319077 -381.261337) (xy 127.311342 -381.280063)
			(xy 127.297046 -381.29442) (xy 127.278352 -381.302234) (xy 127.268224 -381.302768) (xy 126.551944 -381.302768)
			(xy 126.541789 -381.302342) (xy 126.523031 -381.294555) (xy 126.508705 -381.280159) (xy 126.50101 -381.261363)
			(xy 126.500636 -381.251206) (xy 126.500636 -380.965456) (xy 126.500412 -380.958562) (xy 126.496678 -380.94529)
			(xy 126.49327 -380.939294) (xy 126.476949 -380.910929) (xy 126.451202 -380.850765) (xy 126.433772 -380.787686)
			(xy 126.424976 -380.722838) (xy 126.424974 -380.657396) (xy 122.995169 -380.657396) (xy 122.995166 -380.722839)
			(xy 122.986371 -380.78769) (xy 122.968942 -380.850771) (xy 122.943195 -380.910938) (xy 122.926856 -380.939294)
			(xy 122.923548 -380.945322) (xy 122.919937 -380.958583) (xy 122.919744 -380.965456) (xy 122.919744 -381.251206)
			(xy 122.919341 -381.26138) (xy 122.91155 -381.280178) (xy 122.897158 -381.294564) (xy 122.878356 -381.302345)
			(xy 122.868182 -381.302768) (xy 122.151902 -381.302768) (xy 122.141745 -381.302265) (xy 122.122977 -381.294492)
			(xy 122.108612 -381.28013) (xy 122.100836 -381.261363) (xy 122.10034 -381.251206) (xy 122.10034 -380.965456)
			(xy 122.100122 -380.958585) (xy 122.096531 -380.945322) (xy 122.093228 -380.939294) (xy 122.076908 -380.910928)
			(xy 122.051163 -380.850764) (xy 122.033735 -380.787686) (xy 122.02494 -380.722838) (xy 122.024938 -380.657396)
			(xy 118.595133 -380.657396) (xy 118.59513 -380.72284) (xy 118.586334 -380.787691) (xy 118.568903 -380.850772)
			(xy 118.543154 -380.910938) (xy 118.526814 -380.939294) (xy 118.523457 -380.945313) (xy 118.519716 -380.95857)
			(xy 118.519448 -380.965456) (xy 118.519448 -381.251206) (xy 118.518978 -381.261335) (xy 118.511246 -381.280058)
			(xy 118.496954 -381.294415) (xy 118.478266 -381.302231) (xy 118.46814 -381.302768) (xy 117.75186 -381.302768)
			(xy 117.741699 -381.30241) (xy 117.72294 -381.294596) (xy 117.708617 -381.280179) (xy 117.700924 -381.261369)
			(xy 117.700552 -381.251206) (xy 117.700552 -380.965456) (xy 117.700326 -380.958563) (xy 117.696593 -380.945291)
			(xy 117.693186 -380.939294) (xy 117.676864 -380.910929) (xy 117.651116 -380.850765) (xy 117.633686 -380.787687)
			(xy 117.62489 -380.722838) (xy 117.624888 -380.657396) (xy 105.919524 -380.657396) (xy 105.919524 -380.877572)
			(xy 105.919034 -380.907556) (xy 105.911206 -380.967012) (xy 105.895685 -381.024937) (xy 105.872736 -381.080341)
			(xy 105.842752 -381.132275) (xy 105.806246 -381.179851) (xy 105.763841 -381.222256) (xy 105.716265 -381.258762)
			(xy 105.664331 -381.288746) (xy 105.608927 -381.311695) (xy 105.551002 -381.327216) (xy 105.491546 -381.335044)
			(xy 105.431578 -381.335044) (xy 105.372122 -381.327216) (xy 105.314197 -381.311695) (xy 105.258793 -381.288746)
			(xy 105.206859 -381.258762) (xy 105.159283 -381.222256) (xy 105.116878 -381.179851) (xy 105.080372 -381.132275)
			(xy 105.050388 -381.080341) (xy 105.027439 -381.024937) (xy 105.011918 -380.967012) (xy 105.00409 -380.907556)
			(xy 105.0036 -380.877572) (xy 101.387499 -380.877572) (xy 101.415216 -380.885713) (xy 101.464787 -380.908356)
			(xy 101.510631 -380.937822) (xy 101.551815 -380.973512) (xy 101.587501 -381.0147) (xy 101.616963 -381.060547)
			(xy 101.6396 -381.110119) (xy 101.654953 -381.162409) (xy 101.662708 -381.216352) (xy 101.662708 -381.270848)
			(xy 101.654953 -381.324791) (xy 101.6396 -381.377081) (xy 101.616963 -381.426653) (xy 101.587501 -381.4725)
			(xy 101.551815 -381.513688) (xy 101.510631 -381.549378) (xy 101.464787 -381.578844) (xy 101.415216 -381.601487)
			(xy 101.362928 -381.616845) (xy 101.308986 -381.624605) (xy 101.281738 -381.625094) (xy 101.252446 -381.624576)
			(xy 101.194551 -381.61563) (xy 101.138701 -381.597945) (xy 101.086209 -381.571933) (xy 101.038308 -381.538207)
			(xy 100.996123 -381.497558) (xy 100.960643 -381.450941) (xy 100.946204 -381.42545) (xy 100.939178 -381.413456)
			(xy 100.919833 -381.393509) (xy 100.895826 -381.379518) (xy 100.868935 -381.372518) (xy 100.841153 -381.373028)
			(xy 100.814538 -381.38101) (xy 100.79106 -381.395872) (xy 100.77246 -381.416515) (xy 100.765864 -381.428752)
			(xy 100.753677 -381.452297) (xy 100.723831 -381.496112) (xy 100.688202 -381.53537) (xy 100.647479 -381.569314)
			(xy 100.602446 -381.597289) (xy 100.553972 -381.618756) (xy 100.502991 -381.6333) (xy 100.450487 -381.640642)
			(xy 100.42398 -381.641096) (xy 100.396729 -381.640633) (xy 100.342782 -381.632874) (xy 100.290488 -381.617516)
			(xy 100.240911 -381.594873) (xy 100.195062 -381.565406) (xy 100.153873 -381.529713) (xy 100.118182 -381.488522)
			(xy 100.088717 -381.442671) (xy 100.066077 -381.393094) (xy 100.050722 -381.340799) (xy 100.042966 -381.286851)
			(xy 87.704386 -381.286851) (xy 87.696886 -381.294394) (xy 87.678218 -381.302221) (xy 87.6681 -381.302768)
			(xy 86.95182 -381.302768) (xy 86.941663 -381.302362) (xy 86.922905 -381.294567) (xy 86.90858 -381.280165)
			(xy 86.900885 -381.261365) (xy 86.900512 -381.251206) (xy 86.900512 -380.965456) (xy 86.90029 -380.958562)
			(xy 86.896555 -380.94529) (xy 86.893146 -380.939294) (xy 86.876825 -380.910929) (xy 86.85108 -380.850764)
			(xy 86.833651 -380.787686) (xy 86.824856 -380.722838) (xy 86.824853 -380.657396) (xy 83.395048 -380.657396)
			(xy 83.395046 -380.722839) (xy 83.38625 -380.78769) (xy 83.36882 -380.850771) (xy 83.343072 -380.910938)
			(xy 83.326732 -380.939294) (xy 83.323422 -380.945321) (xy 83.319813 -380.958583) (xy 83.31962 -380.965456)
			(xy 83.31962 -381.251206) (xy 83.31924 -381.261383) (xy 83.311445 -381.280186) (xy 83.297046 -381.294572)
			(xy 83.278236 -381.302349) (xy 83.268058 -381.302768) (xy 82.551778 -381.302768) (xy 82.54162 -381.302285)
			(xy 82.522851 -381.294504) (xy 82.508487 -381.280136) (xy 82.500712 -381.261365) (xy 82.500216 -381.251206)
			(xy 82.500216 -380.965456) (xy 82.5 -380.958585) (xy 82.496408 -380.945322) (xy 82.493104 -380.939294)
			(xy 82.476785 -380.910928) (xy 82.451041 -380.850763) (xy 82.433614 -380.787685) (xy 82.42482 -380.722838)
			(xy 82.424817 -380.657397) (xy 78.994998 -380.657397) (xy 78.994996 -380.722839) (xy 78.986201 -380.787689)
			(xy 78.968773 -380.85077) (xy 78.943028 -380.910937) (xy 78.92669 -380.939294) (xy 78.923331 -380.945312)
			(xy 78.919592 -380.95857) (xy 78.919324 -380.965456) (xy 78.919324 -381.251206) (xy 78.918877 -381.261337)
			(xy 78.911141 -381.280066) (xy 78.896842 -381.294423) (xy 78.878145 -381.302235) (xy 78.868016 -381.302768)
			(xy 78.151736 -381.302768) (xy 78.14158 -381.302348) (xy 78.122823 -381.294558) (xy 78.108497 -381.28016)
			(xy 78.100802 -381.261364) (xy 78.100428 -381.251206) (xy 78.100428 -380.965456) (xy 78.100204 -380.958562)
			(xy 78.09647 -380.94529) (xy 78.093062 -380.939294) (xy 78.076741 -380.910929) (xy 78.050994 -380.850764)
			(xy 78.033565 -380.787686) (xy 78.02477 -380.722838) (xy 78.024767 -380.657396) (xy 74.594962 -380.657396)
			(xy 74.59496 -380.722839) (xy 74.586164 -380.78769) (xy 74.568734 -380.850771) (xy 74.542987 -380.910938)
			(xy 74.526648 -380.939294) (xy 74.523339 -380.945322) (xy 74.519729 -380.958583) (xy 74.519536 -380.965456)
			(xy 74.519536 -381.251206) (xy 74.51914 -381.261381) (xy 74.511349 -381.280181) (xy 74.496954 -381.294567)
			(xy 74.478149 -381.302347) (xy 74.467974 -381.302768) (xy 73.751694 -381.302768) (xy 73.741537 -381.302272)
			(xy 73.722769 -381.294496) (xy 73.708404 -381.280131) (xy 73.700628 -381.261363) (xy 73.700132 -381.251206)
			(xy 73.700132 -380.965456) (xy 73.699915 -380.958585) (xy 73.696323 -380.945322) (xy 73.69302 -380.939294)
			(xy 73.6767 -380.910928) (xy 73.650956 -380.850764) (xy 73.633528 -380.787685) (xy 73.624733 -380.722838)
			(xy 73.624731 -380.657396) (xy 56.979406 -380.657396) (xy 56.975001 -380.68733) (xy 56.958933 -380.740737)
			(xy 56.935261 -380.791234) (xy 56.904488 -380.837747) (xy 56.867271 -380.879284) (xy 56.824403 -380.914959)
			(xy 56.776797 -380.944013) (xy 56.725468 -380.965825) (xy 56.671511 -380.979931) (xy 56.616074 -380.986031)
			(xy 56.56034 -380.983994) (xy 56.505497 -380.973864) (xy 56.452713 -380.955857) (xy 56.403113 -380.930356)
			(xy 56.357755 -380.897905) (xy 56.317606 -380.859196) (xy 56.28352 -380.815053) (xy 56.256224 -380.766418)
			(xy 56.236301 -380.714327) (xy 56.224175 -380.65989) (xy 56.220104 -380.604268) (xy 51.556158 -380.604268)
			(xy 51.556158 -381.620268) (xy 57.056272 -381.620268) (xy 57.060343 -381.564646) (xy 57.072469 -381.510209)
			(xy 57.092392 -381.458118) (xy 57.119688 -381.409483) (xy 57.153774 -381.36534) (xy 57.193923 -381.326631)
			(xy 57.239281 -381.29418) (xy 57.288881 -381.268679) (xy 57.341665 -381.250672) (xy 57.396508 -381.240542)
			(xy 57.452242 -381.238505) (xy 57.507679 -381.244605) (xy 57.561636 -381.258711) (xy 57.612965 -381.280523)
			(xy 57.660571 -381.309577) (xy 57.703439 -381.345252) (xy 57.740656 -381.386789) (xy 57.771429 -381.433302)
			(xy 57.795101 -381.483799) (xy 57.811169 -381.537206) (xy 57.819289 -381.592382) (xy 57.819798 -381.620268)
			(xy 57.819289 -381.648154) (xy 57.811169 -381.70333) (xy 57.795101 -381.756737) (xy 57.771429 -381.807234)
			(xy 57.740656 -381.853747) (xy 57.703439 -381.895284) (xy 57.660571 -381.930959) (xy 57.612965 -381.960013)
			(xy 57.561636 -381.981825) (xy 57.507679 -381.995931) (xy 57.452242 -382.002031) (xy 57.396508 -381.999994)
			(xy 57.341665 -381.989864) (xy 57.288881 -381.971857) (xy 57.239281 -381.946356) (xy 57.193923 -381.913905)
			(xy 57.153774 -381.875196) (xy 57.119688 -381.831053) (xy 57.092392 -381.782418) (xy 57.072469 -381.730327)
			(xy 57.060343 -381.67589) (xy 57.056272 -381.620268) (xy 51.556158 -381.620268) (xy 51.556158 -382.281684)
			(xy 58.230514 -382.281684) (xy 58.234585 -382.226062) (xy 58.246711 -382.171625) (xy 58.266634 -382.119534)
			(xy 58.29393 -382.070899) (xy 58.328016 -382.026756) (xy 58.368165 -381.988047) (xy 58.413523 -381.955596)
			(xy 58.463123 -381.930095) (xy 58.515907 -381.912088) (xy 58.57075 -381.901958) (xy 58.626484 -381.899921)
			(xy 58.681921 -381.906021) (xy 58.735878 -381.920127) (xy 58.787207 -381.941939) (xy 58.834813 -381.970993)
			(xy 58.877681 -382.006668) (xy 58.914898 -382.048205) (xy 58.945671 -382.094718) (xy 58.969343 -382.145215)
			(xy 58.985411 -382.198622) (xy 58.988956 -382.222713) (xy 71.424821 -382.222713) (xy 71.424823 -382.15727)
			(xy 71.433617 -382.09242) (xy 71.451044 -382.029339) (xy 71.476788 -381.969172) (xy 71.493126 -381.940816)
			(xy 71.496483 -381.934797) (xy 71.500223 -381.92154) (xy 71.500492 -381.914654) (xy 71.500492 -381.628904)
			(xy 71.500919 -381.618783) (xy 71.508664 -381.600081) (xy 71.522977 -381.585767) (xy 71.541679 -381.57802)
			(xy 71.5518 -381.577596) (xy 72.26808 -381.577596) (xy 72.278201 -381.578032) (xy 72.296903 -381.585773)
			(xy 72.311218 -381.600083) (xy 72.318965 -381.618783) (xy 72.319388 -381.628904) (xy 72.319388 -381.914654)
			(xy 72.319606 -381.921548) (xy 72.323344 -381.93482) (xy 72.326754 -381.940816) (xy 72.343083 -381.969177)
			(xy 72.368828 -382.029342) (xy 72.386256 -382.092421) (xy 72.39505 -382.15727) (xy 72.395051 -382.222713)
			(xy 75.824858 -382.222713) (xy 75.824859 -382.157269) (xy 75.833653 -382.092419) (xy 75.851082 -382.029339)
			(xy 75.876829 -381.969172) (xy 75.893168 -381.940816) (xy 75.896474 -381.934787) (xy 75.900086 -381.921527)
			(xy 75.90028 -381.914654) (xy 75.90028 -381.628904) (xy 75.900725 -381.618753) (xy 75.908515 -381.600004)
			(xy 75.922904 -381.585681) (xy 75.941689 -381.577978) (xy 75.951842 -381.577596) (xy 76.668122 -381.577596)
			(xy 76.678245 -381.578107) (xy 76.696958 -381.585834) (xy 76.711312 -381.600112) (xy 76.719138 -381.618784)
			(xy 76.719684 -381.628904) (xy 76.719684 -381.914654) (xy 76.719895 -381.921526) (xy 76.72349 -381.934789)
			(xy 76.726796 -381.940816) (xy 76.743124 -381.969177) (xy 76.768867 -382.029343) (xy 76.786293 -382.092422)
			(xy 76.795086 -382.157271) (xy 76.795087 -382.222712) (xy 76.795087 -382.222713) (xy 80.224908 -382.222713)
			(xy 80.224909 -382.15727) (xy 80.233702 -382.09242) (xy 80.251129 -382.02934) (xy 80.276873 -381.969172)
			(xy 80.29321 -381.940816) (xy 80.296565 -381.934797) (xy 80.300307 -381.92154) (xy 80.300576 -381.914654)
			(xy 80.300576 -381.628904) (xy 80.301088 -381.618798) (xy 80.30882 -381.600125) (xy 80.323108 -381.585831)
			(xy 80.341779 -381.578092) (xy 80.351884 -381.577596) (xy 81.068164 -381.577596) (xy 81.078284 -381.578046)
			(xy 81.096986 -381.585781) (xy 81.111301 -381.600087) (xy 81.119048 -381.618785) (xy 81.119472 -381.628904)
			(xy 81.119472 -381.914654) (xy 81.119691 -381.921548) (xy 81.123429 -381.93482) (xy 81.126838 -381.940816)
			(xy 81.143168 -381.969177) (xy 81.168914 -382.029342) (xy 81.186342 -382.092421) (xy 81.195136 -382.15727)
			(xy 81.195137 -382.222713) (xy 84.624697 -382.222713) (xy 84.624699 -382.15727) (xy 84.633492 -382.09242)
			(xy 84.650918 -382.02934) (xy 84.676661 -381.969173) (xy 84.692998 -381.940816) (xy 84.696353 -381.934796)
			(xy 84.700095 -381.92154) (xy 84.700364 -381.914654) (xy 84.700364 -381.628904) (xy 84.700888 -381.6188)
			(xy 84.708617 -381.600129) (xy 84.722902 -381.585835) (xy 84.741568 -381.578094) (xy 84.751672 -381.577596)
			(xy 85.467952 -381.577596) (xy 85.478071 -381.578055) (xy 85.496773 -381.585787) (xy 85.511088 -381.60009)
			(xy 85.518836 -381.618786) (xy 85.51926 -381.628904) (xy 85.51926 -381.914654) (xy 85.519481 -381.921548)
			(xy 85.523217 -381.93482) (xy 85.526626 -381.940816) (xy 85.542956 -381.969176) (xy 85.568703 -382.029342)
			(xy 85.586131 -382.092421) (xy 85.594926 -382.15727) (xy 85.594927 -382.222713) (xy 89.024734 -382.222713)
			(xy 89.024735 -382.15727) (xy 89.033529 -382.09242) (xy 89.050957 -382.029339) (xy 89.076702 -381.969172)
			(xy 89.09304 -381.940816) (xy 89.096344 -381.934786) (xy 89.099957 -381.921527) (xy 89.100152 -381.914654)
			(xy 89.100152 -381.628904) (xy 89.100624 -381.618756) (xy 89.108409 -381.600013) (xy 89.12279 -381.585691)
			(xy 89.141564 -381.577983) (xy 89.151714 -381.577596) (xy 89.867994 -381.577596) (xy 89.878115 -381.57813)
			(xy 89.896828 -381.585848) (xy 89.911183 -381.600119) (xy 89.91901 -381.618786) (xy 89.919556 -381.628904)
			(xy 89.919556 -381.914654) (xy 89.919758 -381.921527) (xy 89.923359 -381.93479) (xy 89.926668 -381.940816)
			(xy 89.942997 -381.969177) (xy 89.968741 -382.029343) (xy 89.986168 -382.092422) (xy 89.994962 -382.15727)
			(xy 89.994963 -382.222713) (xy 89.994963 -382.222714) (xy 115.424978 -382.222714) (xy 115.424979 -382.157269)
			(xy 115.433775 -382.092419) (xy 115.451204 -382.029338) (xy 115.476952 -381.969172) (xy 115.493292 -381.940816)
			(xy 115.4966 -381.934788) (xy 115.50021 -381.921527) (xy 115.500404 -381.914654) (xy 115.500404 -381.628904)
			(xy 115.500825 -381.61875) (xy 115.50862 -381.599997) (xy 115.523017 -381.585673) (xy 115.54181 -381.577974)
			(xy 115.551966 -381.577596) (xy 116.268246 -381.577596) (xy 116.27837 -381.578088) (xy 116.297084 -381.585822)
			(xy 116.311437 -381.600106) (xy 116.319262 -381.618782) (xy 116.319808 -381.628904) (xy 116.319808 -381.914654)
			(xy 116.320017 -381.921526) (xy 116.323613 -381.934789) (xy 116.32692 -381.940816) (xy 116.34325 -381.969176)
			(xy 116.368997 -382.029342) (xy 116.386426 -382.092421) (xy 116.395221 -382.15727) (xy 116.395222 -382.222713)
			(xy 119.825028 -382.222713) (xy 119.82503 -382.15727) (xy 119.833824 -382.09242) (xy 119.851251 -382.029339)
			(xy 119.876996 -381.969172) (xy 119.893334 -381.940816) (xy 119.896691 -381.934797) (xy 119.900431 -381.92154)
			(xy 119.9007 -381.914654) (xy 119.9007 -381.628904) (xy 119.901119 -381.618782) (xy 119.908866 -381.600078)
			(xy 119.923182 -381.585764) (xy 119.941886 -381.578019) (xy 119.952008 -381.577596) (xy 120.668288 -381.577596)
			(xy 120.678409 -381.578026) (xy 120.697112 -381.585769) (xy 120.711426 -381.600081) (xy 120.719173 -381.618783)
			(xy 120.719596 -381.628904) (xy 120.719596 -381.914654) (xy 120.719848 -381.921544) (xy 120.723577 -381.93481)
			(xy 120.726962 -381.940816) (xy 120.743291 -381.969177) (xy 120.769035 -382.029342) (xy 120.786463 -382.092422)
			(xy 120.795257 -382.15727) (xy 120.795258 -382.222713) (xy 124.225064 -382.222713) (xy 124.225066 -382.157269)
			(xy 124.233861 -382.092419) (xy 124.25129 -382.029338) (xy 124.277037 -381.969172) (xy 124.293376 -381.940816)
			(xy 124.296683 -381.934788) (xy 124.300294 -381.921527) (xy 124.300488 -381.914654) (xy 124.300488 -381.628904)
			(xy 124.300925 -381.618752) (xy 124.308717 -381.600002) (xy 124.323109 -381.585679) (xy 124.341896 -381.577977)
			(xy 124.35205 -381.577596) (xy 125.06833 -381.577596) (xy 125.078453 -381.578101) (xy 125.097167 -381.58583)
			(xy 125.11152 -381.60011) (xy 125.119346 -381.618783) (xy 125.119892 -381.628904) (xy 125.119892 -381.914654)
			(xy 125.120103 -381.921526) (xy 125.123698 -381.934789) (xy 125.127004 -381.940816) (xy 125.143332 -381.969177)
			(xy 125.169074 -382.029343) (xy 125.1865 -382.092422) (xy 125.195293 -382.157271) (xy 125.195294 -382.222712)
			(xy 125.195294 -382.222713) (xy 128.624854 -382.222713) (xy 128.624855 -382.157269) (xy 128.63365 -382.092419)
			(xy 128.651079 -382.029339) (xy 128.676825 -381.969172) (xy 128.693164 -381.940816) (xy 128.69647 -381.934787)
			(xy 128.700082 -381.921527) (xy 128.700276 -381.914654) (xy 128.700276 -381.628904) (xy 128.700724 -381.618753)
			(xy 128.708514 -381.600005) (xy 128.722902 -381.585683) (xy 128.741685 -381.577979) (xy 128.751838 -381.577596)
			(xy 129.468118 -381.577596) (xy 129.47824 -381.57811) (xy 129.496954 -381.585836) (xy 129.511308 -381.600113)
			(xy 129.519134 -381.618784) (xy 129.51968 -381.628904) (xy 129.51968 -381.914654) (xy 129.519892 -381.921526)
			(xy 129.523487 -381.934788) (xy 129.526792 -381.940816) (xy 129.54312 -381.969177) (xy 129.568863 -382.029343)
			(xy 129.586289 -382.092422) (xy 129.595083 -382.15727) (xy 129.595083 -382.18999) (xy 133.023872 -382.18999)
			(xy 133.027863 -382.127823) (xy 133.039772 -382.066676) (xy 133.059401 -382.007555) (xy 133.08643 -381.951429)
			(xy 133.120414 -381.89922) (xy 133.160796 -381.851785) (xy 133.206912 -381.809904) (xy 133.258004 -381.774264)
			(xy 133.313235 -381.74545) (xy 133.371697 -381.723936) (xy 133.432431 -381.710074) (xy 133.494438 -381.704092)
			(xy 133.556701 -381.706088) (xy 133.588318 -381.7112) (xy 147.45284 -381.7112) (xy 147.456911 -381.655578)
			(xy 147.469037 -381.601141) (xy 147.48896 -381.54905) (xy 147.516256 -381.500415) (xy 147.550342 -381.456272)
			(xy 147.590491 -381.417563) (xy 147.635849 -381.385112) (xy 147.685449 -381.359611) (xy 147.738233 -381.341604)
			(xy 147.793076 -381.331474) (xy 147.84881 -381.329437) (xy 147.904247 -381.335537) (xy 147.958204 -381.349643)
			(xy 148.009533 -381.371455) (xy 148.057139 -381.400509) (xy 148.100007 -381.436184) (xy 148.137224 -381.477721)
			(xy 148.167997 -381.524234) (xy 148.191669 -381.574731) (xy 148.207737 -381.628138) (xy 148.215857 -381.683314)
			(xy 148.216366 -381.7112) (xy 148.215857 -381.739086) (xy 148.207737 -381.794262) (xy 148.191669 -381.847669)
			(xy 148.167997 -381.898166) (xy 148.137224 -381.944679) (xy 148.100007 -381.986216) (xy 148.057139 -382.021891)
			(xy 148.009533 -382.050945) (xy 147.958204 -382.072757) (xy 147.904247 -382.086863) (xy 147.84881 -382.092963)
			(xy 147.793076 -382.090926) (xy 147.738233 -382.080796) (xy 147.685449 -382.062789) (xy 147.635849 -382.037288)
			(xy 147.590491 -382.004837) (xy 147.550342 -381.966128) (xy 147.516256 -381.921985) (xy 147.48896 -381.87335)
			(xy 147.469037 -381.821259) (xy 147.456911 -381.766822) (xy 147.45284 -381.7112) (xy 133.588318 -381.7112)
			(xy 133.618198 -381.716031) (xy 133.677919 -381.733755) (xy 133.734882 -381.758972) (xy 133.788153 -381.791265)
			(xy 133.836858 -381.830105) (xy 133.880195 -381.874855) (xy 133.917455 -381.924779) (xy 133.948024 -381.979058)
			(xy 133.971402 -382.036801) (xy 133.987203 -382.097059) (xy 133.995169 -382.158842) (xy 133.995668 -382.18999)
			(xy 133.995169 -382.221138) (xy 133.987203 -382.282921) (xy 133.971402 -382.343179) (xy 133.948024 -382.400922)
			(xy 133.923483 -382.444498) (xy 146.412456 -382.444498) (xy 146.416527 -382.388876) (xy 146.428653 -382.334439)
			(xy 146.448576 -382.282348) (xy 146.475872 -382.233713) (xy 146.509958 -382.18957) (xy 146.550107 -382.150861)
			(xy 146.595465 -382.11841) (xy 146.645065 -382.092909) (xy 146.697849 -382.074902) (xy 146.752692 -382.064772)
			(xy 146.808426 -382.062735) (xy 146.863863 -382.068835) (xy 146.91782 -382.082941) (xy 146.969149 -382.104753)
			(xy 147.016755 -382.133807) (xy 147.059623 -382.169482) (xy 147.09684 -382.211019) (xy 147.127613 -382.257532)
			(xy 147.151285 -382.308029) (xy 147.167353 -382.361436) (xy 147.175473 -382.416612) (xy 147.175982 -382.444498)
			(xy 147.175473 -382.472384) (xy 147.167353 -382.52756) (xy 147.151285 -382.580967) (xy 147.127613 -382.631464)
			(xy 147.09684 -382.677977) (xy 147.059623 -382.719514) (xy 147.016755 -382.755189) (xy 146.969149 -382.784243)
			(xy 146.91782 -382.806055) (xy 146.863863 -382.820161) (xy 146.808426 -382.826261) (xy 146.752692 -382.824224)
			(xy 146.697849 -382.814094) (xy 146.645065 -382.796087) (xy 146.595465 -382.770586) (xy 146.550107 -382.738135)
			(xy 146.509958 -382.699426) (xy 146.475872 -382.655283) (xy 146.448576 -382.606648) (xy 146.428653 -382.554557)
			(xy 146.416527 -382.50012) (xy 146.412456 -382.444498) (xy 133.923483 -382.444498) (xy 133.917455 -382.455201)
			(xy 133.880195 -382.505125) (xy 133.836858 -382.549875) (xy 133.788153 -382.588715) (xy 133.734882 -382.621008)
			(xy 133.677919 -382.646225) (xy 133.618198 -382.663949) (xy 133.556701 -382.673892) (xy 133.494438 -382.675888)
			(xy 133.432431 -382.669906) (xy 133.371697 -382.656044) (xy 133.313235 -382.63453) (xy 133.258004 -382.605716)
			(xy 133.206912 -382.570076) (xy 133.160796 -382.528195) (xy 133.120414 -382.48076) (xy 133.08643 -382.428551)
			(xy 133.059401 -382.372425) (xy 133.039772 -382.313304) (xy 133.027863 -382.252157) (xy 133.023872 -382.18999)
			(xy 129.595083 -382.18999) (xy 129.595084 -382.222712) (xy 129.586293 -382.287561) (xy 129.568869 -382.350641)
			(xy 129.543128 -382.410808) (xy 129.526792 -382.439164) (xy 129.523489 -382.445195) (xy 129.519876 -382.458454)
			(xy 129.51968 -382.465326) (xy 129.51968 -383.21488) (xy 129.519882 -383.221752) (xy 129.523484 -383.235015)
			(xy 129.526792 -383.241042) (xy 129.543142 -383.269391) (xy 129.565988 -383.322792) (xy 130.824995 -383.322792)
			(xy 130.824999 -383.257347) (xy 130.833796 -383.192495) (xy 130.851226 -383.129414) (xy 130.876973 -383.069247)
			(xy 130.893312 -383.04089) (xy 130.896631 -383.034868) (xy 130.900234 -383.021602) (xy 130.900424 -383.014728)
			(xy 130.900424 -382.728724) (xy 130.900842 -382.718568) (xy 130.908634 -382.699812) (xy 130.923032 -382.685487)
			(xy 130.941828 -382.67779) (xy 130.951986 -382.677416) (xy 131.668266 -382.677416) (xy 131.678388 -382.677954)
			(xy 131.697103 -382.685666) (xy 131.71146 -382.699937) (xy 131.719284 -382.718606) (xy 131.719828 -382.728724)
			(xy 131.719828 -383.014728) (xy 131.720005 -383.021602) (xy 131.723623 -383.034865) (xy 131.72694 -383.04089)
			(xy 131.743248 -383.069263) (xy 131.768995 -383.129425) (xy 131.786426 -383.192502) (xy 131.795223 -383.257349)
			(xy 131.795227 -383.32279) (xy 131.786438 -383.387637) (xy 131.769016 -383.450716) (xy 131.752117 -383.490216)
			(xy 133.023872 -383.490216) (xy 133.027863 -383.428049) (xy 133.039772 -383.366902) (xy 133.059401 -383.307781)
			(xy 133.08643 -383.251655) (xy 133.120414 -383.199446) (xy 133.160796 -383.152011) (xy 133.206912 -383.11013)
			(xy 133.258004 -383.07449) (xy 133.313235 -383.045676) (xy 133.371697 -383.024162) (xy 133.432431 -383.0103)
			(xy 133.494438 -383.004318) (xy 133.556701 -383.006314) (xy 133.618198 -383.016257) (xy 133.677919 -383.033981)
			(xy 133.734882 -383.059198) (xy 133.788153 -383.091491) (xy 133.836858 -383.130331) (xy 133.880195 -383.175081)
			(xy 133.917455 -383.225005) (xy 133.948024 -383.279284) (xy 133.952388 -383.290064) (xy 135.22402 -383.290064)
			(xy 135.228011 -383.227897) (xy 135.23992 -383.16675) (xy 135.259549 -383.107629) (xy 135.286578 -383.051503)
			(xy 135.320562 -382.999294) (xy 135.360944 -382.951859) (xy 135.40706 -382.909978) (xy 135.458152 -382.874338)
			(xy 135.513383 -382.845524) (xy 135.571845 -382.82401) (xy 135.632579 -382.810148) (xy 135.694586 -382.804166)
			(xy 135.756849 -382.806162) (xy 135.818346 -382.816105) (xy 135.878067 -382.833829) (xy 135.93503 -382.859046)
			(xy 135.988301 -382.891339) (xy 136.037006 -382.930179) (xy 136.080343 -382.974929) (xy 136.117603 -383.024853)
			(xy 136.148172 -383.079132) (xy 136.17155 -383.136875) (xy 136.187351 -383.197133) (xy 136.195317 -383.258916)
			(xy 136.195816 -383.290064) (xy 136.195317 -383.321212) (xy 136.187351 -383.382995) (xy 136.17155 -383.443253)
			(xy 136.164568 -383.460498) (xy 147.395944 -383.460498) (xy 147.400015 -383.404876) (xy 147.412141 -383.350439)
			(xy 147.432064 -383.298348) (xy 147.45936 -383.249713) (xy 147.493446 -383.20557) (xy 147.533595 -383.166861)
			(xy 147.578953 -383.13441) (xy 147.628553 -383.108909) (xy 147.681337 -383.090902) (xy 147.73618 -383.080772)
			(xy 147.791914 -383.078735) (xy 147.847351 -383.084835) (xy 147.901308 -383.098941) (xy 147.952637 -383.120753)
			(xy 148.000243 -383.149807) (xy 148.043111 -383.185482) (xy 148.080328 -383.227019) (xy 148.111101 -383.273532)
			(xy 148.134773 -383.324029) (xy 148.147251 -383.365502) (xy 149.854156 -383.365502) (xy 149.858227 -383.30988)
			(xy 149.870353 -383.255443) (xy 149.890276 -383.203352) (xy 149.917572 -383.154717) (xy 149.951658 -383.110574)
			(xy 149.991807 -383.071865) (xy 150.037165 -383.039414) (xy 150.086765 -383.013913) (xy 150.139549 -382.995906)
			(xy 150.194392 -382.985776) (xy 150.250126 -382.983739) (xy 150.305563 -382.989839) (xy 150.35952 -383.003945)
			(xy 150.410849 -383.025757) (xy 150.458455 -383.054811) (xy 150.501323 -383.090486) (xy 150.53854 -383.132023)
			(xy 150.569313 -383.178536) (xy 150.592985 -383.229033) (xy 150.609053 -383.28244) (xy 150.617173 -383.337616)
			(xy 150.617682 -383.365502) (xy 150.617173 -383.393388) (xy 150.609053 -383.448564) (xy 150.592985 -383.501971)
			(xy 150.569313 -383.552468) (xy 150.53854 -383.598981) (xy 150.501323 -383.640518) (xy 150.458455 -383.676193)
			(xy 150.410849 -383.705247) (xy 150.35952 -383.727059) (xy 150.305563 -383.741165) (xy 150.250126 -383.747265)
			(xy 150.194392 -383.745228) (xy 150.139549 -383.735098) (xy 150.086765 -383.717091) (xy 150.037165 -383.69159)
			(xy 149.991807 -383.659139) (xy 149.951658 -383.62043) (xy 149.917572 -383.576287) (xy 149.890276 -383.527652)
			(xy 149.870353 -383.475561) (xy 149.858227 -383.421124) (xy 149.854156 -383.365502) (xy 148.147251 -383.365502)
			(xy 148.150841 -383.377436) (xy 148.158961 -383.432612) (xy 148.15947 -383.460498) (xy 148.158961 -383.488384)
			(xy 148.150841 -383.54356) (xy 148.134773 -383.596967) (xy 148.111101 -383.647464) (xy 148.080328 -383.693977)
			(xy 148.043111 -383.735514) (xy 148.000243 -383.771189) (xy 147.952637 -383.800243) (xy 147.901308 -383.822055)
			(xy 147.847351 -383.836161) (xy 147.791914 -383.842261) (xy 147.73618 -383.840224) (xy 147.681337 -383.830094)
			(xy 147.628553 -383.812087) (xy 147.578953 -383.786586) (xy 147.533595 -383.754135) (xy 147.493446 -383.715426)
			(xy 147.45936 -383.671283) (xy 147.432064 -383.622648) (xy 147.412141 -383.570557) (xy 147.400015 -383.51612)
			(xy 147.395944 -383.460498) (xy 136.164568 -383.460498) (xy 136.148172 -383.500996) (xy 136.117603 -383.555275)
			(xy 136.080343 -383.605199) (xy 136.037006 -383.649949) (xy 135.988301 -383.688789) (xy 135.93503 -383.721082)
			(xy 135.878067 -383.746299) (xy 135.818346 -383.764023) (xy 135.756849 -383.773966) (xy 135.694586 -383.775962)
			(xy 135.632579 -383.76998) (xy 135.571845 -383.756118) (xy 135.513383 -383.734604) (xy 135.458152 -383.70579)
			(xy 135.40706 -383.67015) (xy 135.360944 -383.628269) (xy 135.320562 -383.580834) (xy 135.286578 -383.528625)
			(xy 135.259549 -383.472499) (xy 135.23992 -383.413378) (xy 135.228011 -383.352231) (xy 135.22402 -383.290064)
			(xy 133.952388 -383.290064) (xy 133.971402 -383.337027) (xy 133.987203 -383.397285) (xy 133.995169 -383.459068)
			(xy 133.995668 -383.490216) (xy 133.995169 -383.521364) (xy 133.987203 -383.583147) (xy 133.971402 -383.643405)
			(xy 133.948024 -383.701148) (xy 133.917455 -383.755427) (xy 133.880195 -383.805351) (xy 133.836858 -383.850101)
			(xy 133.788153 -383.888941) (xy 133.734882 -383.921234) (xy 133.677919 -383.946451) (xy 133.618198 -383.964175)
			(xy 133.556701 -383.974118) (xy 133.494438 -383.976114) (xy 133.432431 -383.970132) (xy 133.371697 -383.95627)
			(xy 133.313235 -383.934756) (xy 133.258004 -383.905942) (xy 133.206912 -383.870302) (xy 133.160796 -383.828421)
			(xy 133.120414 -383.780986) (xy 133.08643 -383.728777) (xy 133.059401 -383.672651) (xy 133.039772 -383.61353)
			(xy 133.027863 -383.552383) (xy 133.023872 -383.490216) (xy 131.752117 -383.490216) (xy 131.743276 -383.510882)
			(xy 131.72694 -383.539238) (xy 131.723615 -383.545258) (xy 131.720015 -383.558525) (xy 131.719828 -383.5654)
			(xy 131.719828 -384.3147) (xy 131.720017 -384.321574) (xy 131.723627 -384.334836) (xy 131.72694 -384.340862)
			(xy 131.743309 -384.369201) (xy 131.769051 -384.429372) (xy 131.786475 -384.492455) (xy 131.795264 -384.557308)
			(xy 131.795262 -384.590036) (xy 135.22402 -384.590036) (xy 135.228011 -384.527869) (xy 135.23992 -384.466722)
			(xy 135.259549 -384.407601) (xy 135.286578 -384.351475) (xy 135.320562 -384.299266) (xy 135.360944 -384.251831)
			(xy 135.40706 -384.20995) (xy 135.458152 -384.17431) (xy 135.513383 -384.145496) (xy 135.571845 -384.123982)
			(xy 135.632579 -384.11012) (xy 135.694586 -384.104138) (xy 135.756849 -384.106134) (xy 135.818346 -384.116077)
			(xy 135.878067 -384.133801) (xy 135.93503 -384.159018) (xy 135.988301 -384.191311) (xy 136.037006 -384.230151)
			(xy 136.080343 -384.274901) (xy 136.117603 -384.324825) (xy 136.148172 -384.379104) (xy 136.17155 -384.436847)
			(xy 136.187351 -384.497105) (xy 136.195317 -384.558888) (xy 136.195816 -384.590036) (xy 136.195788 -384.591814)
			(xy 149.09876 -384.591814) (xy 149.102831 -384.536192) (xy 149.114957 -384.481755) (xy 149.13488 -384.429664)
			(xy 149.162176 -384.381029) (xy 149.196262 -384.336886) (xy 149.236411 -384.298177) (xy 149.281769 -384.265726)
			(xy 149.331369 -384.240225) (xy 149.384153 -384.222218) (xy 149.438996 -384.212088) (xy 149.49473 -384.210051)
			(xy 149.550167 -384.216151) (xy 149.604124 -384.230257) (xy 149.655453 -384.252069) (xy 149.703059 -384.281123)
			(xy 149.745927 -384.316798) (xy 149.783144 -384.358335) (xy 149.813917 -384.404848) (xy 149.837589 -384.455345)
			(xy 149.853657 -384.508752) (xy 149.861777 -384.563928) (xy 149.862286 -384.591814) (xy 149.861777 -384.6197)
			(xy 149.853657 -384.674876) (xy 149.837589 -384.728283) (xy 149.813917 -384.77878) (xy 149.783144 -384.825293)
			(xy 149.745927 -384.86683) (xy 149.703059 -384.902505) (xy 149.655453 -384.931559) (xy 149.604124 -384.953371)
			(xy 149.550167 -384.967477) (xy 149.49473 -384.973577) (xy 149.438996 -384.97154) (xy 149.384153 -384.96141)
			(xy 149.331369 -384.943403) (xy 149.281769 -384.917902) (xy 149.236411 -384.885451) (xy 149.196262 -384.846742)
			(xy 149.162176 -384.802599) (xy 149.13488 -384.753964) (xy 149.114957 -384.701873) (xy 149.102831 -384.647436)
			(xy 149.09876 -384.591814) (xy 136.195788 -384.591814) (xy 136.195317 -384.621184) (xy 136.187351 -384.682967)
			(xy 136.17155 -384.743225) (xy 136.148172 -384.800968) (xy 136.117603 -384.855247) (xy 136.080343 -384.905171)
			(xy 136.037006 -384.949921) (xy 135.988301 -384.988761) (xy 135.93503 -385.021054) (xy 135.878067 -385.046271)
			(xy 135.818346 -385.063995) (xy 135.756849 -385.073938) (xy 135.694586 -385.075934) (xy 135.632579 -385.069952)
			(xy 135.571845 -385.05609) (xy 135.513383 -385.034576) (xy 135.458152 -385.005762) (xy 135.40706 -384.970122)
			(xy 135.360944 -384.928241) (xy 135.320562 -384.880806) (xy 135.286578 -384.828597) (xy 135.259549 -384.772471)
			(xy 135.23992 -384.71335) (xy 135.228011 -384.652203) (xy 135.22402 -384.590036) (xy 131.795262 -384.590036)
			(xy 131.79526 -384.622754) (xy 131.786462 -384.687605) (xy 131.76903 -384.750687) (xy 131.74328 -384.810854)
			(xy 131.72694 -384.83921) (xy 131.723625 -384.845235) (xy 131.720019 -384.858498) (xy 131.719828 -384.865372)
			(xy 131.719828 -385.151376) (xy 131.719359 -385.161525) (xy 131.711577 -385.180272) (xy 131.697195 -385.194595)
			(xy 131.678417 -385.202301) (xy 131.668266 -385.202684) (xy 130.951986 -385.202684) (xy 130.941861 -385.202185)
			(xy 130.923145 -385.194457) (xy 130.90879 -385.180175) (xy 130.900967 -385.161498) (xy 130.900424 -385.151376)
			(xy 130.900424 -384.865372) (xy 130.90024 -384.858498) (xy 130.896626 -384.845236) (xy 130.893312 -384.83921)
			(xy 130.877006 -384.810837) (xy 130.851261 -384.750674) (xy 130.833832 -384.687597) (xy 130.825036 -384.622751)
			(xy 130.825031 -384.557311) (xy 130.833819 -384.492463) (xy 130.85124 -384.429385) (xy 130.876978 -384.369218)
			(xy 130.893312 -384.340862) (xy 130.896641 -384.334844) (xy 130.900237 -384.321575) (xy 130.900424 -384.3147)
			(xy 130.900424 -383.5654) (xy 130.900229 -383.558527) (xy 130.896623 -383.545264) (xy 130.893312 -383.539238)
			(xy 130.876945 -383.510898) (xy 130.851205 -383.450728) (xy 130.833783 -383.387644) (xy 130.824995 -383.322792)
			(xy 129.565988 -383.322792) (xy 129.568883 -383.32956) (xy 129.586307 -383.392641) (xy 129.595097 -383.457492)
			(xy 129.595096 -383.522936) (xy 129.586301 -383.587786) (xy 129.568874 -383.650866) (xy 129.543129 -383.711033)
			(xy 129.526792 -383.73939) (xy 129.52348 -383.745416) (xy 129.519873 -383.758679) (xy 129.51968 -383.765552)
			(xy 129.51968 -384.051556) (xy 129.519242 -384.06171) (xy 129.511457 -384.080465) (xy 129.497065 -384.094791)
			(xy 129.478274 -384.102488) (xy 129.468118 -384.102864) (xy 128.751838 -384.102864) (xy 128.741714 -384.102342)
			(xy 128.722995 -384.094628) (xy 128.708637 -384.080352) (xy 128.700816 -384.061677) (xy 128.700276 -384.051556)
			(xy 128.700276 -383.765552) (xy 128.700067 -383.75868) (xy 128.696471 -383.745417) (xy 128.693164 -383.73939)
			(xy 128.676839 -383.711027) (xy 128.651093 -383.650862) (xy 128.633664 -383.587783) (xy 128.624869 -383.522935)
			(xy 128.624867 -383.457493) (xy 128.633659 -383.392644) (xy 128.651084 -383.329564) (xy 128.676827 -383.269398)
			(xy 128.693164 -383.241042) (xy 128.696461 -383.235009) (xy 128.700078 -383.221752) (xy 128.700276 -383.21488)
			(xy 128.700276 -382.465326) (xy 128.700077 -382.458453) (xy 128.696474 -382.44519) (xy 128.693164 -382.439164)
			(xy 128.676817 -382.410813) (xy 128.651073 -382.350645) (xy 128.633647 -382.287564) (xy 128.624854 -382.222713)
			(xy 125.195294 -382.222713) (xy 125.186503 -382.287561) (xy 125.16908 -382.35064) (xy 125.143339 -382.410807)
			(xy 125.127004 -382.439164) (xy 125.123702 -382.445195) (xy 125.120088 -382.458454) (xy 125.119892 -382.465326)
			(xy 125.119892 -383.21488) (xy 125.120092 -383.221753) (xy 125.123695 -383.235015) (xy 125.127004 -383.241042)
			(xy 125.143354 -383.269391) (xy 125.166199 -383.322792) (xy 126.424945 -383.322792) (xy 126.424949 -383.257346)
			(xy 126.433747 -383.192494) (xy 126.451179 -383.129413) (xy 126.476929 -383.069246) (xy 126.49327 -383.04089)
			(xy 126.496639 -383.034878) (xy 126.500371 -383.021615) (xy 126.500636 -383.014728) (xy 126.500636 -382.728724)
			(xy 126.501036 -382.718599) (xy 126.508783 -382.699889) (xy 126.523105 -382.685572) (xy 126.541818 -382.677832)
			(xy 126.551944 -382.677416) (xy 127.268224 -382.677416) (xy 127.278336 -382.677866) (xy 127.297018 -382.685614)
			(xy 127.311313 -382.699922) (xy 127.319044 -382.718611) (xy 127.319532 -382.728724) (xy 127.319532 -383.014728)
			(xy 127.319767 -383.021621) (xy 127.323494 -383.034893) (xy 127.326898 -383.04089) (xy 127.343204 -383.069263)
			(xy 127.368948 -383.129427) (xy 127.386377 -383.192503) (xy 127.395173 -383.257349) (xy 127.395177 -383.322789)
			(xy 127.386389 -383.387636) (xy 127.368969 -383.450715) (xy 127.343232 -383.510881) (xy 127.326898 -383.539238)
			(xy 127.323524 -383.545248) (xy 127.319794 -383.558512) (xy 127.319532 -383.5654) (xy 127.319532 -384.3147)
			(xy 127.319761 -384.321592) (xy 127.323506 -384.334858) (xy 127.326898 -384.340862) (xy 127.343265 -384.369202)
			(xy 127.369004 -384.429373) (xy 127.386426 -384.492456) (xy 127.395214 -384.557308) (xy 127.39521 -384.622753)
			(xy 127.386413 -384.687604) (xy 127.368983 -384.750686) (xy 127.343237 -384.810853) (xy 127.326898 -384.83921)
			(xy 127.323534 -384.845225) (xy 127.319798 -384.858485) (xy 127.319532 -384.865372) (xy 127.319532 -385.151376)
			(xy 127.318996 -385.161479) (xy 127.311272 -385.180151) (xy 127.296991 -385.194445) (xy 127.278327 -385.202187)
			(xy 127.268224 -385.202684) (xy 126.551944 -385.202684) (xy 126.541822 -385.202247) (xy 126.523117 -385.194511)
			(xy 126.5088 -385.1802) (xy 126.501056 -385.161497) (xy 126.500636 -385.151376) (xy 126.500636 -384.865372)
			(xy 126.500405 -384.858479) (xy 126.496675 -384.845207) (xy 126.49327 -384.83921) (xy 126.476962 -384.810837)
			(xy 126.451214 -384.750675) (xy 126.433783 -384.687598) (xy 126.424986 -384.622751) (xy 126.424981 -384.55731)
			(xy 126.43377 -384.492462) (xy 126.451193 -384.429384) (xy 126.476934 -384.369218) (xy 126.49327 -384.340862)
			(xy 126.496649 -384.334854) (xy 126.500375 -384.321588) (xy 126.500636 -384.3147) (xy 126.500636 -383.5654)
			(xy 126.500433 -383.558505) (xy 126.496684 -383.545233) (xy 126.49327 -383.539238) (xy 126.476901 -383.510899)
			(xy 126.451158 -383.450729) (xy 126.433734 -383.387645) (xy 126.424945 -383.322792) (xy 125.166199 -383.322792)
			(xy 125.169094 -383.32956) (xy 125.186517 -383.392642) (xy 125.195308 -383.457492) (xy 125.195306 -383.522935)
			(xy 125.186512 -383.587785) (xy 125.169085 -383.650866) (xy 125.143341 -383.711033) (xy 125.127004 -383.73939)
			(xy 125.123693 -383.745417) (xy 125.120085 -383.758679) (xy 125.119892 -383.765552) (xy 125.119892 -384.051556)
			(xy 125.119442 -384.061708) (xy 125.11166 -384.080461) (xy 125.097271 -384.094786) (xy 125.078484 -384.102486)
			(xy 125.06833 -384.102864) (xy 124.35205 -384.102864) (xy 124.341927 -384.102333) (xy 124.323208 -384.094622)
			(xy 124.30885 -384.080349) (xy 124.301028 -384.061676) (xy 124.300488 -384.051556) (xy 124.300488 -383.765552)
			(xy 124.300278 -383.75868) (xy 124.296682 -383.745417) (xy 124.293376 -383.73939) (xy 124.277051 -383.711027)
			(xy 124.251304 -383.650862) (xy 124.233875 -383.587783) (xy 124.225079 -383.522935) (xy 124.225077 -383.457493)
			(xy 124.233869 -383.392643) (xy 124.251295 -383.329564) (xy 124.277039 -383.269398) (xy 124.293376 -383.241042)
			(xy 124.296674 -383.235009) (xy 124.300291 -383.221752) (xy 124.300488 -383.21488) (xy 124.300488 -382.465326)
			(xy 124.300287 -382.458453) (xy 124.296685 -382.445191) (xy 124.293376 -382.439164) (xy 124.277029 -382.410813)
			(xy 124.251284 -382.350645) (xy 124.233857 -382.287564) (xy 124.225064 -382.222713) (xy 120.795258 -382.222713)
			(xy 120.786466 -382.287562) (xy 120.769041 -382.350641) (xy 120.743299 -382.410808) (xy 120.726962 -382.439164)
			(xy 120.723612 -382.445186) (xy 120.719867 -382.458441) (xy 120.719596 -382.465326) (xy 120.719596 -383.21488)
			(xy 120.719838 -383.221771) (xy 120.723574 -383.235037) (xy 120.726962 -383.241042) (xy 120.743313 -383.269391)
			(xy 120.76616 -383.322792) (xy 122.024908 -383.322792) (xy 122.024913 -383.257346) (xy 122.03371 -383.192495)
			(xy 122.05114 -383.129414) (xy 122.076889 -383.069246) (xy 122.093228 -383.04089) (xy 122.096548 -383.034868)
			(xy 122.10015 -383.021602) (xy 122.10034 -383.014728) (xy 122.10034 -382.728724) (xy 122.100742 -382.718566)
			(xy 122.108537 -382.699807) (xy 122.122941 -382.685481) (xy 122.141742 -382.677788) (xy 122.151902 -382.677416)
			(xy 122.868182 -382.677416) (xy 122.878305 -382.677941) (xy 122.897021 -382.685658) (xy 122.911377 -382.699932)
			(xy 122.919201 -382.718604) (xy 122.919744 -382.728724) (xy 122.919744 -383.014728) (xy 122.91992 -383.021603)
			(xy 122.923539 -383.034865) (xy 122.926856 -383.04089) (xy 122.943163 -383.069263) (xy 122.96891 -383.129426)
			(xy 122.98634 -383.192502) (xy 122.995137 -383.257349) (xy 122.995141 -383.322789) (xy 122.986352 -383.387637)
			(xy 122.96893 -383.450716) (xy 122.943191 -383.510882) (xy 122.926856 -383.539238) (xy 122.923532 -383.545258)
			(xy 122.919932 -383.558525) (xy 122.919744 -383.5654) (xy 122.919744 -384.3147) (xy 122.919931 -384.321574)
			(xy 122.923542 -384.334837) (xy 122.926856 -384.340862) (xy 122.943224 -384.369201) (xy 122.968965 -384.429372)
			(xy 122.986389 -384.492455) (xy 122.995178 -384.557308) (xy 122.995174 -384.622754) (xy 122.986376 -384.687605)
			(xy 122.968945 -384.750687) (xy 122.943196 -384.810854) (xy 122.926856 -384.83921) (xy 122.923542 -384.845235)
			(xy 122.919935 -384.858498) (xy 122.919744 -384.865372) (xy 122.919744 -385.151376) (xy 122.91926 -385.161523)
			(xy 122.91148 -385.180267) (xy 122.897103 -385.194589) (xy 122.878331 -385.202298) (xy 122.868182 -385.202684)
			(xy 122.151902 -385.202684) (xy 122.141778 -385.202172) (xy 122.123062 -385.19445) (xy 122.108706 -385.180171)
			(xy 122.100883 -385.161497) (xy 122.10034 -385.151376) (xy 122.10034 -384.865372) (xy 122.100154 -384.858498)
			(xy 122.096541 -384.845236) (xy 122.093228 -384.83921) (xy 122.076921 -384.810837) (xy 122.051175 -384.750674)
			(xy 122.033746 -384.687597) (xy 122.024949 -384.622751) (xy 122.024945 -384.557311) (xy 122.033734 -384.492463)
			(xy 122.051155 -384.429384) (xy 122.076893 -384.369218) (xy 122.093228 -384.340862) (xy 122.096558 -384.334845)
			(xy 122.100154 -384.321575) (xy 122.10034 -384.3147) (xy 122.10034 -383.5654) (xy 122.100143 -383.558527)
			(xy 122.096538 -383.545265) (xy 122.093228 -383.539238) (xy 122.07686 -383.510899) (xy 122.05112 -383.450728)
			(xy 122.033697 -383.387644) (xy 122.024908 -383.322792) (xy 120.76616 -383.322792) (xy 120.769055 -383.329559)
			(xy 120.78648 -383.392641) (xy 120.795272 -383.457492) (xy 120.79527 -383.522936) (xy 120.786475 -383.587786)
			(xy 120.769046 -383.650867) (xy 120.7433 -383.711034) (xy 120.726962 -383.73939) (xy 120.723602 -383.745407)
			(xy 120.719864 -383.758666) (xy 120.719596 -383.765552) (xy 120.719596 -384.051556) (xy 120.719148 -384.061676)
			(xy 120.711413 -384.080379) (xy 120.697106 -384.094695) (xy 120.678408 -384.102441) (xy 120.668288 -384.102864)
			(xy 119.952008 -384.102864) (xy 119.941882 -384.102477) (xy 119.923171 -384.094724) (xy 119.908855 -384.080399)
			(xy 119.901116 -384.061683) (xy 119.9007 -384.051556) (xy 119.9007 -383.765552) (xy 119.900447 -383.758662)
			(xy 119.896718 -383.745396) (xy 119.893334 -383.73939) (xy 119.87701 -383.711026) (xy 119.851265 -383.650861)
			(xy 119.833838 -383.587783) (xy 119.825043 -383.522935) (xy 119.825041 -383.457493) (xy 119.833832 -383.392644)
			(xy 119.851256 -383.329565) (xy 119.876998 -383.269398) (xy 119.893334 -383.241042) (xy 119.896717 -383.235036)
			(xy 119.900441 -383.221769) (xy 119.9007 -383.21488) (xy 119.9007 -382.465326) (xy 119.900457 -382.458435)
			(xy 119.896721 -382.44517) (xy 119.893334 -382.439164) (xy 119.876988 -382.410812) (xy 119.851245 -382.350645)
			(xy 119.83382 -382.287564) (xy 119.825028 -382.222713) (xy 116.395222 -382.222713) (xy 116.386429 -382.287562)
			(xy 116.369003 -382.350642) (xy 116.343258 -382.410808) (xy 116.32692 -382.439164) (xy 116.323619 -382.445196)
			(xy 116.320004 -382.458454) (xy 116.319808 -382.465326) (xy 116.319808 -383.21488) (xy 116.320007 -383.221753)
			(xy 116.32361 -383.235015) (xy 116.32692 -383.241042) (xy 116.343272 -383.26939) (xy 116.366122 -383.322792)
			(xy 117.624858 -383.322792) (xy 117.624862 -383.257346) (xy 117.633661 -383.192494) (xy 117.651094 -383.129413)
			(xy 117.676845 -383.069246) (xy 117.693186 -383.04089) (xy 117.696549 -383.034874) (xy 117.700286 -383.021615)
			(xy 117.700552 -383.014728) (xy 117.700552 -382.728724) (xy 117.701103 -382.718623) (xy 117.708824 -382.699954)
			(xy 117.7231 -382.68566) (xy 117.741759 -382.677916) (xy 117.75186 -382.677416) (xy 118.46814 -382.677416)
			(xy 118.478253 -382.677853) (xy 118.496935 -382.685607) (xy 118.511229 -382.699918) (xy 118.51896 -382.71861)
			(xy 118.519448 -382.728724) (xy 118.519448 -383.014728) (xy 118.519681 -383.021621) (xy 118.523409 -383.034893)
			(xy 118.526814 -383.04089) (xy 118.543122 -383.069263) (xy 118.568872 -383.129425) (xy 118.586303 -383.192502)
			(xy 118.595101 -383.257349) (xy 118.595105 -383.32279) (xy 118.586315 -383.387638) (xy 118.568892 -383.450717)
			(xy 118.54315 -383.510882) (xy 118.526814 -383.539238) (xy 118.523441 -383.545249) (xy 118.51971 -383.558512)
			(xy 118.519448 -383.5654) (xy 118.519448 -384.3147) (xy 118.519653 -384.321595) (xy 118.523401 -384.334867)
			(xy 118.526814 -384.340862) (xy 118.543183 -384.369201) (xy 118.568927 -384.429371) (xy 118.586352 -384.492455)
			(xy 118.595142 -384.557308) (xy 118.595138 -384.622754) (xy 118.586339 -384.687606) (xy 118.568906 -384.750687)
			(xy 118.543155 -384.810854) (xy 118.526814 -384.83921) (xy 118.523451 -384.845226) (xy 118.519714 -384.858485)
			(xy 118.519448 -384.865372) (xy 118.519448 -385.151376) (xy 118.518897 -385.161477) (xy 118.511176 -385.180146)
			(xy 118.4969 -385.19444) (xy 118.478241 -385.202184) (xy 118.46814 -385.202684) (xy 117.75186 -385.202684)
			(xy 117.741747 -385.202247) (xy 117.723065 -385.194493) (xy 117.708771 -385.180182) (xy 117.70104 -385.16149)
			(xy 117.700552 -385.151376) (xy 117.700552 -384.865372) (xy 117.700319 -384.858479) (xy 117.696591 -384.845207)
			(xy 117.693186 -384.83921) (xy 117.676878 -384.810837) (xy 117.651128 -384.750675) (xy 117.633697 -384.687598)
			(xy 117.624899 -384.622751) (xy 117.624895 -384.55731) (xy 117.633685 -384.492462) (xy 117.651108 -384.429383)
			(xy 117.67685 -384.369218) (xy 117.693186 -384.340862) (xy 117.696559 -384.334851) (xy 117.70029 -384.321588)
			(xy 117.700552 -384.3147) (xy 117.700552 -383.5654) (xy 117.700347 -383.558505) (xy 117.696599 -383.545233)
			(xy 117.693186 -383.539238) (xy 117.676817 -383.510899) (xy 117.651073 -383.450729) (xy 117.633648 -383.387645)
			(xy 117.624858 -383.322792) (xy 116.366122 -383.322792) (xy 116.369017 -383.329558) (xy 116.386443 -383.39264)
			(xy 116.395235 -383.457491) (xy 116.395234 -383.522936) (xy 116.386438 -383.587787) (xy 116.369008 -383.650868)
			(xy 116.34326 -383.711034) (xy 116.32692 -383.73939) (xy 116.32361 -383.745417) (xy 116.320001 -383.758679)
			(xy 116.319808 -383.765552) (xy 116.319808 -384.051556) (xy 116.319342 -384.061706) (xy 116.311563 -384.080456)
			(xy 116.297179 -384.094781) (xy 116.278398 -384.102483) (xy 116.268246 -384.102864) (xy 115.551966 -384.102864)
			(xy 115.541838 -384.102401) (xy 115.523116 -384.094663) (xy 115.508761 -384.08037) (xy 115.500943 -384.061682)
			(xy 115.500404 -384.051556) (xy 115.500404 -383.765552) (xy 115.500191 -383.75868) (xy 115.496597 -383.745418)
			(xy 115.493292 -383.73939) (xy 115.476967 -383.711027) (xy 115.451219 -383.650862) (xy 115.433789 -383.587784)
			(xy 115.424993 -383.522935) (xy 115.424991 -383.457492) (xy 115.433783 -383.392643) (xy 115.451209 -383.329564)
			(xy 115.476954 -383.269398) (xy 115.493292 -383.241042) (xy 115.496591 -383.23501) (xy 115.500207 -383.221752)
			(xy 115.500404 -383.21488) (xy 115.500404 -382.465326) (xy 115.500202 -382.458454) (xy 115.496601 -382.445191)
			(xy 115.493292 -382.439164) (xy 115.476944 -382.410813) (xy 115.451199 -382.350646) (xy 115.433771 -382.287565)
			(xy 115.424978 -382.222714) (xy 89.994963 -382.222714) (xy 89.986172 -382.287561) (xy 89.968747 -382.350641)
			(xy 89.943004 -382.410808) (xy 89.926668 -382.439164) (xy 89.923364 -382.445194) (xy 89.919752 -382.458454)
			(xy 89.919556 -382.465326) (xy 89.919556 -383.21488) (xy 89.919749 -383.221753) (xy 89.923356 -383.235016)
			(xy 89.926668 -383.241042) (xy 89.943019 -383.269391) (xy 89.965866 -383.322792) (xy 91.22486 -383.322792)
			(xy 91.224864 -383.257346) (xy 91.233662 -383.192494) (xy 91.251095 -383.129413) (xy 91.276847 -383.069246)
			(xy 91.293188 -383.04089) (xy 91.296505 -383.034867) (xy 91.30011 -383.021602) (xy 91.3003 -383.014728)
			(xy 91.3003 -382.728724) (xy 91.300741 -382.718571) (xy 91.308529 -382.699819) (xy 91.32292 -382.685495)
			(xy 91.341708 -382.677795) (xy 91.351862 -382.677416) (xy 92.068142 -382.677416) (xy 92.078268 -382.677891)
			(xy 92.096986 -382.685629) (xy 92.11134 -382.699918) (xy 92.119162 -382.7186) (xy 92.119704 -382.728724)
			(xy 92.119704 -383.014728) (xy 92.119885 -383.021602) (xy 92.1235 -383.034865) (xy 92.126816 -383.04089)
			(xy 92.143124 -383.069263) (xy 92.168873 -383.129425) (xy 92.186305 -383.192502) (xy 92.195102 -383.257349)
			(xy 92.195107 -383.32279) (xy 92.186317 -383.387638) (xy 92.168894 -383.450717) (xy 92.143152 -383.510882)
			(xy 92.126816 -383.539238) (xy 92.123489 -383.545257) (xy 92.119891 -383.558525) (xy 92.119704 -383.5654)
			(xy 92.119704 -384.3147) (xy 92.119895 -384.321573) (xy 92.123504 -384.334836) (xy 92.126816 -384.340862)
			(xy 92.143185 -384.369201) (xy 92.168929 -384.429371) (xy 92.186353 -384.492455) (xy 92.195143 -384.557308)
			(xy 92.195139 -384.622754) (xy 92.186341 -384.687606) (xy 92.168908 -384.750687) (xy 92.143157 -384.810854)
			(xy 92.126816 -384.83921) (xy 92.123499 -384.845233) (xy 92.119894 -384.858498) (xy 92.119704 -384.865372)
			(xy 92.119704 -385.151376) (xy 92.119259 -385.161528) (xy 92.111472 -385.180279) (xy 92.097082 -385.194603)
			(xy 92.078296 -385.202305) (xy 92.068142 -385.202684) (xy 91.351862 -385.202684) (xy 91.341736 -385.202205)
			(xy 91.323018 -385.194469) (xy 91.308664 -385.180181) (xy 91.300842 -385.1615) (xy 91.3003 -385.151376)
			(xy 91.3003 -384.865372) (xy 91.300119 -384.858498) (xy 91.296503 -384.845235) (xy 91.293188 -384.83921)
			(xy 91.27688 -384.810838) (xy 91.25113 -384.750675) (xy 91.233699 -384.687598) (xy 91.224901 -384.622751)
			(xy 91.224897 -384.55731) (xy 91.233686 -384.492462) (xy 91.25111 -384.429383) (xy 91.276852 -384.369218)
			(xy 91.293188 -384.340862) (xy 91.296515 -384.334844) (xy 91.300113 -384.321575) (xy 91.3003 -384.3147)
			(xy 91.3003 -383.5654) (xy 91.300108 -383.558527) (xy 91.2965 -383.545264) (xy 91.293188 -383.539238)
			(xy 91.276819 -383.510899) (xy 91.251075 -383.450729) (xy 91.23365 -383.387645) (xy 91.22486 -383.322792)
			(xy 89.965866 -383.322792) (xy 89.968761 -383.329559) (xy 89.986186 -383.392641) (xy 89.994977 -383.457492)
			(xy 89.994975 -383.522936) (xy 89.98618 -383.587786) (xy 89.968752 -383.650867) (xy 89.943006 -383.711034)
			(xy 89.926668 -383.73939) (xy 89.923355 -383.745415) (xy 89.919749 -383.758679) (xy 89.919556 -383.765552)
			(xy 89.919556 -384.051556) (xy 89.919043 -384.0617) (xy 89.911273 -384.080441) (xy 89.896905 -384.094764)
			(xy 89.87814 -384.102475) (xy 89.867994 -384.102864) (xy 89.151714 -384.102864) (xy 89.141589 -384.102362)
			(xy 89.122869 -384.09464) (xy 89.108512 -384.080358) (xy 89.100692 -384.061679) (xy 89.100152 -384.051556)
			(xy 89.100152 -383.765552) (xy 89.099946 -383.75868) (xy 89.096348 -383.745417) (xy 89.09304 -383.73939)
			(xy 89.076716 -383.711026) (xy 89.050971 -383.650861) (xy 89.033543 -383.587783) (xy 89.024748 -383.522935)
			(xy 89.024746 -383.457493) (xy 89.033537 -383.392644) (xy 89.050962 -383.329565) (xy 89.076704 -383.269398)
			(xy 89.09304 -383.241042) (xy 89.096335 -383.235008) (xy 89.099954 -383.221752) (xy 89.100152 -383.21488)
			(xy 89.100152 -382.465326) (xy 89.099956 -382.458453) (xy 89.096351 -382.44519) (xy 89.09304 -382.439164)
			(xy 89.076694 -382.410813) (xy 89.050951 -382.350645) (xy 89.033525 -382.287564) (xy 89.024734 -382.222713)
			(xy 85.594927 -382.222713) (xy 85.586135 -382.287562) (xy 85.568708 -382.350642) (xy 85.542964 -382.410808)
			(xy 85.526626 -382.439164) (xy 85.523272 -382.445184) (xy 85.519531 -382.458441) (xy 85.51926 -382.465326)
			(xy 85.51926 -383.21488) (xy 85.519471 -383.221775) (xy 85.523214 -383.235047) (xy 85.526626 -383.241042)
			(xy 85.542978 -383.26939) (xy 85.565827 -383.322792) (xy 86.824824 -383.322792) (xy 86.824828 -383.257346)
			(xy 86.833626 -383.192495) (xy 86.851057 -383.129413) (xy 86.876806 -383.069246) (xy 86.893146 -383.04089)
			(xy 86.896513 -383.034876) (xy 86.900247 -383.021615) (xy 86.900512 -383.014728) (xy 86.900512 -382.728724)
			(xy 86.900936 -382.718602) (xy 86.908678 -382.699896) (xy 86.922993 -382.685581) (xy 86.941698 -382.677837)
			(xy 86.95182 -382.677416) (xy 87.6681 -382.677416) (xy 87.678224 -382.677816) (xy 87.696931 -382.685568)
			(xy 87.711246 -382.699889) (xy 87.718988 -382.718599) (xy 87.719408 -382.728724) (xy 87.719408 -383.014728)
			(xy 87.719668 -383.021617) (xy 87.723392 -383.034883) (xy 87.726774 -383.04089) (xy 87.74308 -383.069263)
			(xy 87.768827 -383.129426) (xy 87.786256 -383.192503) (xy 87.795052 -383.257349) (xy 87.795056 -383.322789)
			(xy 87.786268 -383.387637) (xy 87.768847 -383.450716) (xy 87.743109 -383.510882) (xy 87.726774 -383.539238)
			(xy 87.723398 -383.545247) (xy 87.71967 -383.558512) (xy 87.719408 -383.5654) (xy 87.719408 -384.3147)
			(xy 87.71964 -384.321591) (xy 87.723383 -384.334857) (xy 87.726774 -384.340862) (xy 87.743141 -384.369201)
			(xy 87.768882 -384.429372) (xy 87.786304 -384.492456) (xy 87.795093 -384.557308) (xy 87.795089 -384.622753)
			(xy 87.786292 -384.687605) (xy 87.768861 -384.750686) (xy 87.743113 -384.810854) (xy 87.726774 -384.83921)
			(xy 87.723408 -384.845224) (xy 87.719673 -384.858485) (xy 87.719408 -384.865372) (xy 87.719408 -385.151376)
			(xy 87.718965 -385.161496) (xy 87.711226 -385.180198) (xy 87.696918 -385.194512) (xy 87.67822 -385.20226)
			(xy 87.6681 -385.202684) (xy 86.95182 -385.202684) (xy 86.941697 -385.202267) (xy 86.922991 -385.194523)
			(xy 86.908675 -385.180206) (xy 86.900932 -385.161499) (xy 86.900512 -385.151376) (xy 86.900512 -384.865372)
			(xy 86.900284 -384.858479) (xy 86.896553 -384.845207) (xy 86.893146 -384.83921) (xy 86.876839 -384.810837)
			(xy 86.851092 -384.750674) (xy 86.833662 -384.687598) (xy 86.824865 -384.622751) (xy 86.824861 -384.557311)
			(xy 86.833649 -384.492463) (xy 86.851071 -384.429384) (xy 86.876811 -384.369218) (xy 86.893146 -384.340862)
			(xy 86.896523 -384.334853) (xy 86.90025 -384.321588) (xy 86.900512 -384.3147) (xy 86.900512 -383.5654)
			(xy 86.900312 -383.558504) (xy 86.896562 -383.545232) (xy 86.893146 -383.539238) (xy 86.876778 -383.510899)
			(xy 86.851036 -383.450728) (xy 86.833613 -383.387645) (xy 86.824824 -383.322792) (xy 85.565827 -383.322792)
			(xy 85.568722 -383.329558) (xy 85.586149 -383.39264) (xy 85.594941 -383.457491) (xy 85.594939 -383.522936)
			(xy 85.586143 -383.587787) (xy 85.568713 -383.650867) (xy 85.542966 -383.711034) (xy 85.526626 -383.73939)
			(xy 85.523263 -383.745406) (xy 85.519527 -383.758666) (xy 85.51926 -383.765552) (xy 85.51926 -384.051556)
			(xy 85.518847 -384.061681) (xy 85.511106 -384.080391) (xy 85.496787 -384.094708) (xy 85.478077 -384.102448)
			(xy 85.467952 -384.102864) (xy 84.751672 -384.102864) (xy 84.741543 -384.102506) (xy 84.722832 -384.094742)
			(xy 84.708517 -384.080407) (xy 84.70078 -384.061685) (xy 84.700364 -384.051556) (xy 84.700364 -383.765552)
			(xy 84.700137 -383.758659) (xy 84.696404 -383.745387) (xy 84.692998 -383.73939) (xy 84.676675 -383.711026)
			(xy 84.650932 -383.650861) (xy 84.633506 -383.587782) (xy 84.624712 -383.522934) (xy 84.62471 -383.457493)
			(xy 84.633501 -383.392645) (xy 84.650923 -383.329565) (xy 84.676663 -383.269399) (xy 84.692998 -383.241042)
			(xy 84.696378 -383.235035) (xy 84.700104 -383.221769) (xy 84.700364 -383.21488) (xy 84.700364 -382.465326)
			(xy 84.700147 -382.458432) (xy 84.696408 -382.44516) (xy 84.692998 -382.439164) (xy 84.676653 -382.410812)
			(xy 84.650912 -382.350644) (xy 84.633488 -382.287563) (xy 84.624697 -382.222713) (xy 81.195137 -382.222713)
			(xy 81.186345 -382.287562) (xy 81.168919 -382.350642) (xy 81.143175 -382.410808) (xy 81.126838 -382.439164)
			(xy 81.123485 -382.445185) (xy 81.119743 -382.458441) (xy 81.119472 -382.465326) (xy 81.119472 -383.21488)
			(xy 81.119681 -383.221775) (xy 81.123426 -383.235047) (xy 81.126838 -383.241042) (xy 81.14319 -383.26939)
			(xy 81.166038 -383.322792) (xy 82.424788 -383.322792) (xy 82.424792 -383.257347) (xy 82.433589 -383.192496)
			(xy 82.451018 -383.129414) (xy 82.476765 -383.069247) (xy 82.493104 -383.04089) (xy 82.496423 -383.034867)
			(xy 82.500026 -383.021602) (xy 82.500216 -383.014728) (xy 82.500216 -382.728724) (xy 82.500641 -382.718569)
			(xy 82.508432 -382.699814) (xy 82.522828 -382.68549) (xy 82.541621 -382.677792) (xy 82.551778 -382.677416)
			(xy 83.268058 -382.677416) (xy 83.278179 -382.67796) (xy 83.296895 -382.68567) (xy 83.311252 -382.699938)
			(xy 83.319076 -382.718606) (xy 83.31962 -382.728724) (xy 83.31962 -383.014728) (xy 83.319799 -383.021602)
			(xy 83.323416 -383.034865) (xy 83.326732 -383.04089) (xy 83.34304 -383.069263) (xy 83.368788 -383.129425)
			(xy 83.386219 -383.192502) (xy 83.395016 -383.257349) (xy 83.39502 -383.32279) (xy 83.386231 -383.387637)
			(xy 83.368808 -383.450716) (xy 83.343068 -383.510882) (xy 83.326732 -383.539238) (xy 83.323406 -383.545257)
			(xy 83.319807 -383.558525) (xy 83.31962 -383.5654) (xy 83.31962 -384.3147) (xy 83.31981 -384.321573)
			(xy 83.323419 -384.334836) (xy 83.326732 -384.340862) (xy 83.343101 -384.369201) (xy 83.368843 -384.429371)
			(xy 83.386268 -384.492455) (xy 83.395057 -384.557308) (xy 83.395053 -384.622754) (xy 83.386255 -384.687606)
			(xy 83.368823 -384.750687) (xy 83.343073 -384.810854) (xy 83.326732 -384.83921) (xy 83.323416 -384.845234)
			(xy 83.319811 -384.858498) (xy 83.31962 -384.865372) (xy 83.31962 -385.151376) (xy 83.319159 -385.161526)
			(xy 83.311375 -385.180274) (xy 83.296991 -385.194598) (xy 83.27821 -385.202302) (xy 83.268058 -385.202684)
			(xy 82.551778 -385.202684) (xy 82.541653 -385.202192) (xy 82.522936 -385.194462) (xy 82.508581 -385.180178)
			(xy 82.500758 -385.161499) (xy 82.500216 -385.151376) (xy 82.500216 -384.865372) (xy 82.500033 -384.858498)
			(xy 82.496418 -384.845235) (xy 82.493104 -384.83921) (xy 82.476798 -384.810837) (xy 82.451053 -384.750674)
			(xy 82.433625 -384.687597) (xy 82.424829 -384.622751) (xy 82.424825 -384.557311) (xy 82.433612 -384.492464)
			(xy 82.451033 -384.429385) (xy 82.47677 -384.369218) (xy 82.493104 -384.340862) (xy 82.496433 -384.334844)
			(xy 82.500029 -384.321575) (xy 82.500216 -384.3147) (xy 82.500216 -383.5654) (xy 82.500022 -383.558527)
			(xy 82.496415 -383.545264) (xy 82.493104 -383.539238) (xy 82.476737 -383.510898) (xy 82.450998 -383.450727)
			(xy 82.433576 -383.387644) (xy 82.424788 -383.322792) (xy 81.166038 -383.322792) (xy 81.168933 -383.329559)
			(xy 81.186359 -383.39264) (xy 81.195151 -383.457492) (xy 81.195149 -383.522936) (xy 81.186354 -383.587787)
			(xy 81.168924 -383.650867) (xy 81.143177 -383.711034) (xy 81.126838 -383.73939) (xy 81.123476 -383.745406)
			(xy 81.119739 -383.758666) (xy 81.119472 -383.765552) (xy 81.119472 -384.051556) (xy 81.119047 -384.061679)
			(xy 81.111308 -384.080387) (xy 81.096994 -384.094704) (xy 81.078287 -384.102446) (xy 81.068164 -384.102864)
			(xy 80.351884 -384.102864) (xy 80.341756 -384.102496) (xy 80.323045 -384.094736) (xy 80.30873 -384.080405)
			(xy 80.300992 -384.061685) (xy 80.300576 -384.051556) (xy 80.300576 -383.765552) (xy 80.300326 -383.758662)
			(xy 80.296596 -383.745396) (xy 80.29321 -383.73939) (xy 80.276887 -383.711026) (xy 80.251143 -383.650861)
			(xy 80.233717 -383.587782) (xy 80.224923 -383.522934) (xy 80.224921 -383.457493) (xy 80.233711 -383.392645)
			(xy 80.251134 -383.329565) (xy 80.276875 -383.269398) (xy 80.29321 -383.241042) (xy 80.296591 -383.235035)
			(xy 80.300317 -383.221769) (xy 80.300576 -383.21488) (xy 80.300576 -382.465326) (xy 80.300336 -382.458435)
			(xy 80.296599 -382.445169) (xy 80.29321 -382.439164) (xy 80.276865 -382.410812) (xy 80.251123 -382.350644)
			(xy 80.233699 -382.287563) (xy 80.224908 -382.222713) (xy 76.795087 -382.222713) (xy 76.786296 -382.287561)
			(xy 76.768872 -382.350641) (xy 76.743132 -382.410807) (xy 76.726796 -382.439164) (xy 76.723494 -382.445195)
			(xy 76.71988 -382.458454) (xy 76.719684 -382.465326) (xy 76.719684 -383.21488) (xy 76.719885 -383.221753)
			(xy 76.723487 -383.235015) (xy 76.726796 -383.241042) (xy 76.743146 -383.269391) (xy 76.765992 -383.322792)
			(xy 78.024738 -383.322792) (xy 78.024742 -383.257346) (xy 78.03354 -383.192495) (xy 78.050972 -383.129413)
			(xy 78.076722 -383.069246) (xy 78.093062 -383.04089) (xy 78.096431 -383.034877) (xy 78.100163 -383.021615)
			(xy 78.100428 -383.014728) (xy 78.100428 -382.728724) (xy 78.100836 -382.7186) (xy 78.108582 -382.699891)
			(xy 78.122901 -382.685575) (xy 78.141611 -382.677834) (xy 78.151736 -382.677416) (xy 78.868016 -382.677416)
			(xy 78.878142 -382.677803) (xy 78.896849 -382.685559) (xy 78.911163 -382.699885) (xy 78.918905 -382.718598)
			(xy 78.919324 -382.728724) (xy 78.919324 -383.014728) (xy 78.91956 -383.02162) (xy 78.923287 -383.034892)
			(xy 78.92669 -383.04089) (xy 78.942996 -383.069263) (xy 78.968741 -383.129426) (xy 78.98617 -383.192503)
			(xy 78.994966 -383.257349) (xy 78.99497 -383.322789) (xy 78.986182 -383.387637) (xy 78.968762 -383.450715)
			(xy 78.943024 -383.510882) (xy 78.92669 -383.539238) (xy 78.923316 -383.545248) (xy 78.919586 -383.558512)
			(xy 78.919324 -383.5654) (xy 78.919324 -384.3147) (xy 78.919554 -384.321592) (xy 78.923298 -384.334858)
			(xy 78.92669 -384.340862) (xy 78.943057 -384.369202) (xy 78.968796 -384.429373) (xy 78.986219 -384.492456)
			(xy 78.995007 -384.557308) (xy 78.995003 -384.622753) (xy 78.986206 -384.687605) (xy 78.968776 -384.750686)
			(xy 78.943029 -384.810853) (xy 78.92669 -384.83921) (xy 78.923325 -384.845225) (xy 78.91959 -384.858485)
			(xy 78.919324 -384.865372) (xy 78.919324 -385.151376) (xy 78.918865 -385.161494) (xy 78.911129 -385.180193)
			(xy 78.896826 -385.194507) (xy 78.878134 -385.202257) (xy 78.868016 -385.202684) (xy 78.151736 -385.202684)
			(xy 78.141614 -385.202254) (xy 78.122908 -385.194515) (xy 78.108592 -385.180202) (xy 78.100848 -385.161498)
			(xy 78.100428 -385.151376) (xy 78.100428 -384.865372) (xy 78.100198 -384.858479) (xy 78.096468 -384.845207)
			(xy 78.093062 -384.83921) (xy 78.076754 -384.810837) (xy 78.051006 -384.750675) (xy 78.033576 -384.687598)
			(xy 78.024779 -384.622751) (xy 78.024775 -384.55731) (xy 78.033563 -384.492463) (xy 78.050986 -384.429384)
			(xy 78.076726 -384.369218) (xy 78.093062 -384.340862) (xy 78.096441 -384.334854) (xy 78.100167 -384.321588)
			(xy 78.100428 -384.3147) (xy 78.100428 -383.5654) (xy 78.100226 -383.558505) (xy 78.096477 -383.545233)
			(xy 78.093062 -383.539238) (xy 78.076693 -383.510899) (xy 78.050951 -383.450728) (xy 78.033527 -383.387645)
			(xy 78.024738 -383.322792) (xy 76.765992 -383.322792) (xy 76.768887 -383.32956) (xy 76.78631 -383.392641)
			(xy 76.795101 -383.457492) (xy 76.795099 -383.522936) (xy 76.786305 -383.587786) (xy 76.768878 -383.650866)
			(xy 76.743133 -383.711033) (xy 76.726796 -383.73939) (xy 76.723485 -383.745416) (xy 76.719877 -383.758679)
			(xy 76.719684 -383.765552) (xy 76.719684 -384.051556) (xy 76.719242 -384.061709) (xy 76.711458 -384.080464)
			(xy 76.697067 -384.094789) (xy 76.678277 -384.102488) (xy 76.668122 -384.102864) (xy 75.951842 -384.102864)
			(xy 75.941718 -384.102339) (xy 75.922999 -384.094626) (xy 75.908642 -384.080351) (xy 75.90082 -384.061677)
			(xy 75.90028 -384.051556) (xy 75.90028 -383.765552) (xy 75.900071 -383.75868) (xy 75.896474 -383.745417)
			(xy 75.893168 -383.73939) (xy 75.876843 -383.711027) (xy 75.851097 -383.650862) (xy 75.833668 -383.587783)
			(xy 75.824872 -383.522935) (xy 75.824871 -383.457493) (xy 75.833662 -383.392644) (xy 75.851088 -383.329564)
			(xy 75.876831 -383.269398) (xy 75.893168 -383.241042) (xy 75.896465 -383.235009) (xy 75.900082 -383.221752)
			(xy 75.90028 -383.21488) (xy 75.90028 -382.465326) (xy 75.90008 -382.458453) (xy 75.896478 -382.44519)
			(xy 75.893168 -382.439164) (xy 75.876821 -382.410813) (xy 75.851077 -382.350645) (xy 75.83365 -382.287564)
			(xy 75.824858 -382.222713) (xy 72.395051 -382.222713) (xy 72.386259 -382.287562) (xy 72.368834 -382.350641)
			(xy 72.343091 -382.410808) (xy 72.326754 -382.439164) (xy 72.323403 -382.445186) (xy 72.319659 -382.458441)
			(xy 72.319388 -382.465326) (xy 72.319388 -383.21488) (xy 72.319595 -383.221775) (xy 72.323341 -383.235047)
			(xy 72.326754 -383.241042) (xy 72.343105 -383.269391) (xy 72.365953 -383.322792) (xy 73.624701 -383.322792)
			(xy 73.624706 -383.257347) (xy 73.633503 -383.192495) (xy 73.650933 -383.129414) (xy 73.676681 -383.069246)
			(xy 73.69302 -383.04089) (xy 73.69634 -383.034868) (xy 73.699942 -383.021602) (xy 73.700132 -383.014728)
			(xy 73.700132 -382.728724) (xy 73.700542 -382.718567) (xy 73.708335 -382.699809) (xy 73.722736 -382.685484)
			(xy 73.741535 -382.677789) (xy 73.751694 -382.677416) (xy 74.467974 -382.677416) (xy 74.478096 -382.677947)
			(xy 74.496812 -382.685662) (xy 74.511169 -382.699934) (xy 74.518993 -382.718605) (xy 74.519536 -382.728724)
			(xy 74.519536 -383.014728) (xy 74.519713 -383.021602) (xy 74.523331 -383.034865) (xy 74.526648 -383.04089)
			(xy 74.542955 -383.069263) (xy 74.568703 -383.129426) (xy 74.586133 -383.192502) (xy 74.59493 -383.257349)
			(xy 74.594934 -383.322789) (xy 74.586145 -383.387637) (xy 74.568723 -383.450716) (xy 74.542983 -383.510882)
			(xy 74.526648 -383.539238) (xy 74.523324 -383.545258) (xy 74.519724 -383.558525) (xy 74.519536 -383.5654)
			(xy 74.519536 -384.3147) (xy 74.519724 -384.321574) (xy 74.523334 -384.334837) (xy 74.526648 -384.340862)
			(xy 74.543016 -384.369201) (xy 74.568758 -384.429372) (xy 74.586182 -384.492455) (xy 74.594971 -384.557308)
			(xy 74.594967 -384.622754) (xy 74.586169 -384.687605) (xy 74.568738 -384.750687) (xy 74.542988 -384.810854)
			(xy 74.526648 -384.83921) (xy 74.523334 -384.845235) (xy 74.519727 -384.858498) (xy 74.519536 -384.865372)
			(xy 74.519536 -385.151376) (xy 74.51906 -385.161524) (xy 74.511279 -385.180269) (xy 74.496899 -385.194592)
			(xy 74.478124 -385.202299) (xy 74.467974 -385.202684) (xy 73.751694 -385.202684) (xy 73.74157 -385.202179)
			(xy 73.722853 -385.194454) (xy 73.708498 -385.180173) (xy 73.700675 -385.161497) (xy 73.700132 -385.151376)
			(xy 73.700132 -384.865372) (xy 73.699947 -384.858498) (xy 73.696333 -384.845236) (xy 73.69302 -384.83921)
			(xy 73.676714 -384.810837) (xy 73.650968 -384.750674) (xy 73.633539 -384.687597) (xy 73.624743 -384.622751)
			(xy 73.624738 -384.557311) (xy 73.633526 -384.492463) (xy 73.650948 -384.429385) (xy 73.676686 -384.369218)
			(xy 73.69302 -384.340862) (xy 73.69635 -384.334845) (xy 73.699946 -384.321575) (xy 73.700132 -384.3147)
			(xy 73.700132 -383.5654) (xy 73.699936 -383.558527) (xy 73.69633 -383.545264) (xy 73.69302 -383.539238)
			(xy 73.676653 -383.510898) (xy 73.650913 -383.450728) (xy 73.63349 -383.387644) (xy 73.624701 -383.322792)
			(xy 72.365953 -383.322792) (xy 72.368848 -383.329559) (xy 72.386273 -383.392641) (xy 72.395065 -383.457492)
			(xy 72.395063 -383.522936) (xy 72.386268 -383.587786) (xy 72.368839 -383.650867) (xy 72.343093 -383.711034)
			(xy 72.326754 -383.73939) (xy 72.323394 -383.745407) (xy 72.319656 -383.758666) (xy 72.319388 -383.765552)
			(xy 72.319388 -384.051556) (xy 72.318948 -384.061677) (xy 72.311212 -384.080382) (xy 72.296902 -384.094698)
			(xy 72.278201 -384.102443) (xy 72.26808 -384.102864) (xy 71.5518 -384.102864) (xy 71.541673 -384.102483)
			(xy 71.522963 -384.094728) (xy 71.508647 -384.0804) (xy 71.500908 -384.061683) (xy 71.500492 -384.051556)
			(xy 71.500492 -383.765552) (xy 71.50024 -383.758662) (xy 71.496511 -383.745396) (xy 71.493126 -383.73939)
			(xy 71.476803 -383.711026) (xy 71.451058 -383.650861) (xy 71.433631 -383.587783) (xy 71.424836 -383.522935)
			(xy 71.424834 -383.457493) (xy 71.433625 -383.392644) (xy 71.451049 -383.329565) (xy 71.47679 -383.269398)
			(xy 71.493126 -383.241042) (xy 71.496509 -383.235036) (xy 71.500233 -383.221769) (xy 71.500492 -383.21488)
			(xy 71.500492 -382.465326) (xy 71.50025 -382.458435) (xy 71.496514 -382.445169) (xy 71.493126 -382.439164)
			(xy 71.476781 -382.410812) (xy 71.451038 -382.350644) (xy 71.433613 -382.287563) (xy 71.424821 -382.222713)
			(xy 58.988956 -382.222713) (xy 58.993531 -382.253798) (xy 58.99404 -382.281684) (xy 58.993531 -382.30957)
			(xy 58.985411 -382.364746) (xy 58.969343 -382.418153) (xy 58.945671 -382.46865) (xy 58.914898 -382.515163)
			(xy 58.877681 -382.5567) (xy 58.834813 -382.592375) (xy 58.787207 -382.621429) (xy 58.735878 -382.643241)
			(xy 58.681921 -382.657347) (xy 58.626484 -382.663447) (xy 58.57075 -382.66141) (xy 58.515907 -382.65128)
			(xy 58.463123 -382.633273) (xy 58.413523 -382.607772) (xy 58.368165 -382.575321) (xy 58.328016 -382.536612)
			(xy 58.29393 -382.492469) (xy 58.266634 -382.443834) (xy 58.246711 -382.391743) (xy 58.234585 -382.337306)
			(xy 58.230514 -382.281684) (xy 51.556158 -382.281684) (xy 51.556158 -384.024886) (xy 59.976764 -384.024886)
			(xy 59.980835 -383.969264) (xy 59.992961 -383.914827) (xy 60.012884 -383.862736) (xy 60.04018 -383.814101)
			(xy 60.074266 -383.769958) (xy 60.114415 -383.731249) (xy 60.159773 -383.698798) (xy 60.209373 -383.673297)
			(xy 60.262157 -383.65529) (xy 60.317 -383.64516) (xy 60.372734 -383.643123) (xy 60.428171 -383.649223)
			(xy 60.482128 -383.663329) (xy 60.533457 -383.685141) (xy 60.581063 -383.714195) (xy 60.623931 -383.74987)
			(xy 60.661148 -383.791407) (xy 60.691921 -383.83792) (xy 60.715593 -383.888417) (xy 60.723333 -383.914142)
			(xy 61.475872 -383.914142) (xy 61.479943 -383.85852) (xy 61.492069 -383.804083) (xy 61.511992 -383.751992)
			(xy 61.539288 -383.703357) (xy 61.573374 -383.659214) (xy 61.613523 -383.620505) (xy 61.658881 -383.588054)
			(xy 61.708481 -383.562553) (xy 61.761265 -383.544546) (xy 61.816108 -383.534416) (xy 61.871842 -383.532379)
			(xy 61.927279 -383.538479) (xy 61.981236 -383.552585) (xy 62.032565 -383.574397) (xy 62.080171 -383.603451)
			(xy 62.123039 -383.639126) (xy 62.160256 -383.680663) (xy 62.191029 -383.727176) (xy 62.214701 -383.777673)
			(xy 62.230769 -383.83108) (xy 62.238889 -383.886256) (xy 62.239398 -383.914142) (xy 62.238889 -383.942028)
			(xy 62.230769 -383.997204) (xy 62.214701 -384.050611) (xy 62.191029 -384.101108) (xy 62.160256 -384.147621)
			(xy 62.123039 -384.189158) (xy 62.080171 -384.224833) (xy 62.032565 -384.253887) (xy 61.981236 -384.275699)
			(xy 61.927279 -384.289805) (xy 61.871842 -384.295905) (xy 61.816108 -384.293868) (xy 61.761265 -384.283738)
			(xy 61.708481 -384.265731) (xy 61.658881 -384.24023) (xy 61.613523 -384.207779) (xy 61.573374 -384.16907)
			(xy 61.539288 -384.124927) (xy 61.511992 -384.076292) (xy 61.492069 -384.024201) (xy 61.479943 -383.969764)
			(xy 61.475872 -383.914142) (xy 60.723333 -383.914142) (xy 60.731661 -383.941824) (xy 60.739781 -383.997)
			(xy 60.74029 -384.024886) (xy 60.739781 -384.052772) (xy 60.731661 -384.107948) (xy 60.715593 -384.161355)
			(xy 60.691921 -384.211852) (xy 60.661148 -384.258365) (xy 60.623931 -384.299902) (xy 60.581063 -384.335577)
			(xy 60.533457 -384.364631) (xy 60.482128 -384.386443) (xy 60.428171 -384.400549) (xy 60.372734 -384.406649)
			(xy 60.317 -384.404612) (xy 60.262157 -384.394482) (xy 60.209373 -384.376475) (xy 60.159773 -384.350974)
			(xy 60.114415 -384.318523) (xy 60.074266 -384.279814) (xy 60.04018 -384.235671) (xy 60.012884 -384.187036)
			(xy 59.992961 -384.134945) (xy 59.980835 -384.080508) (xy 59.976764 -384.024886) (xy 51.556158 -384.024886)
			(xy 51.556158 -384.702812) (xy 57.268616 -384.702812) (xy 57.272687 -384.64719) (xy 57.284813 -384.592753)
			(xy 57.304736 -384.540662) (xy 57.332032 -384.492027) (xy 57.366118 -384.447884) (xy 57.406267 -384.409175)
			(xy 57.451625 -384.376724) (xy 57.501225 -384.351223) (xy 57.554009 -384.333216) (xy 57.608852 -384.323086)
			(xy 57.664586 -384.321049) (xy 57.720023 -384.327149) (xy 57.77398 -384.341255) (xy 57.825309 -384.363067)
			(xy 57.872915 -384.392121) (xy 57.915783 -384.427796) (xy 57.953 -384.469333) (xy 57.983773 -384.515846)
			(xy 58.007445 -384.566343) (xy 58.023513 -384.61975) (xy 58.031633 -384.674926) (xy 58.032142 -384.702812)
			(xy 58.031633 -384.730698) (xy 58.023513 -384.785874) (xy 58.007445 -384.839281) (xy 57.983773 -384.889778)
			(xy 57.953 -384.936291) (xy 57.915783 -384.977828) (xy 57.872915 -385.013503) (xy 57.825309 -385.042557)
			(xy 57.77398 -385.064369) (xy 57.720023 -385.078475) (xy 57.664586 -385.084575) (xy 57.608852 -385.082538)
			(xy 57.554009 -385.072408) (xy 57.501225 -385.054401) (xy 57.451625 -385.0289) (xy 57.406267 -384.996449)
			(xy 57.366118 -384.95774) (xy 57.332032 -384.913597) (xy 57.304736 -384.864962) (xy 57.284813 -384.812871)
			(xy 57.272687 -384.758434) (xy 57.268616 -384.702812) (xy 51.556158 -384.702812) (xy 51.556158 -385.326382)
			(xy 61.974982 -385.326382) (xy 61.979053 -385.27076) (xy 61.991179 -385.216323) (xy 62.011102 -385.164232)
			(xy 62.038398 -385.115597) (xy 62.072484 -385.071454) (xy 62.112633 -385.032745) (xy 62.157991 -385.000294)
			(xy 62.207591 -384.974793) (xy 62.260375 -384.956786) (xy 62.315218 -384.946656) (xy 62.370952 -384.944619)
			(xy 62.426389 -384.950719) (xy 62.480346 -384.964825) (xy 62.531675 -384.986637) (xy 62.579281 -385.015691)
			(xy 62.622149 -385.051366) (xy 62.659366 -385.092903) (xy 62.690139 -385.139416) (xy 62.713811 -385.189913)
			(xy 62.729879 -385.24332) (xy 62.737999 -385.298496) (xy 62.738508 -385.326382) (xy 62.737999 -385.354268)
			(xy 62.729879 -385.409444) (xy 62.713811 -385.462851) (xy 62.690139 -385.513348) (xy 62.659366 -385.559861)
			(xy 62.637793 -385.583938) (xy 100.447856 -385.583938) (xy 100.447856 -384.720338) (xy 100.448346 -384.690354)
			(xy 100.456174 -384.630898) (xy 100.471695 -384.572973) (xy 100.494644 -384.517569) (xy 100.524628 -384.465635)
			(xy 100.561134 -384.418059) (xy 100.603539 -384.375654) (xy 100.651115 -384.339148) (xy 100.703049 -384.309164)
			(xy 100.758453 -384.286215) (xy 100.816378 -384.270694) (xy 100.875834 -384.262866) (xy 100.935802 -384.262866)
			(xy 100.995258 -384.270694) (xy 101.053183 -384.286215) (xy 101.108587 -384.309164) (xy 101.160521 -384.339148)
			(xy 101.208097 -384.375654) (xy 101.250502 -384.418059) (xy 101.287008 -384.465635) (xy 101.316992 -384.517569)
			(xy 101.339941 -384.572973) (xy 101.355462 -384.630898) (xy 101.36329 -384.690354) (xy 101.36378 -384.720338)
			(xy 101.36378 -385.319283) (xy 104.635826 -385.319283) (xy 104.635826 -385.259317) (xy 104.643653 -385.199864)
			(xy 104.659172 -385.141942) (xy 104.682119 -385.08654) (xy 104.7121 -385.034608) (xy 104.748603 -384.987032)
			(xy 104.791004 -384.944628) (xy 104.838576 -384.908121) (xy 104.890506 -384.878136) (xy 104.945906 -384.855184)
			(xy 105.003827 -384.83966) (xy 105.063279 -384.831828) (xy 105.093262 -384.831336) (xy 105.956862 -384.831336)
			(xy 105.986849 -384.831807) (xy 106.046311 -384.83963) (xy 106.104243 -384.855149) (xy 106.159653 -384.878097)
			(xy 106.211594 -384.908081) (xy 106.259176 -384.944589) (xy 106.301586 -384.986995) (xy 106.338098 -385.034574)
			(xy 106.368087 -385.086513) (xy 106.391039 -385.141921) (xy 106.406562 -385.199852) (xy 106.414391 -385.259313)
			(xy 106.414391 -385.319287) (xy 106.406562 -385.378748) (xy 106.391039 -385.436679) (xy 106.368087 -385.492087)
			(xy 106.338098 -385.544026) (xy 106.301586 -385.591605) (xy 106.259176 -385.634011) (xy 106.211594 -385.670519)
			(xy 106.159653 -385.700503) (xy 106.104243 -385.723451) (xy 106.046311 -385.73897) (xy 105.986849 -385.746793)
			(xy 105.956862 -385.74726) (xy 105.093262 -385.74726) (xy 105.063279 -385.746772) (xy 105.003827 -385.73894)
			(xy 104.945906 -385.723416) (xy 104.890506 -385.700464) (xy 104.838576 -385.670479) (xy 104.791004 -385.633972)
			(xy 104.748603 -385.591568) (xy 104.7121 -385.543992) (xy 104.682119 -385.49206) (xy 104.659172 -385.436658)
			(xy 104.643653 -385.378736) (xy 104.635826 -385.319283) (xy 101.36378 -385.319283) (xy 101.36378 -385.583938)
			(xy 101.36329 -385.613922) (xy 101.355462 -385.673378) (xy 101.339941 -385.731303) (xy 101.316992 -385.786707)
			(xy 101.287008 -385.838641) (xy 101.250502 -385.886217) (xy 101.208097 -385.928622) (xy 101.160521 -385.965128)
			(xy 101.108587 -385.995112) (xy 101.053183 -386.018061) (xy 100.995258 -386.033582) (xy 100.935802 -386.04141)
			(xy 100.875834 -386.04141) (xy 100.816378 -386.033582) (xy 100.758453 -386.018061) (xy 100.703049 -385.995112)
			(xy 100.651115 -385.965128) (xy 100.603539 -385.928622) (xy 100.561134 -385.886217) (xy 100.524628 -385.838641)
			(xy 100.494644 -385.786707) (xy 100.471695 -385.731303) (xy 100.456174 -385.673378) (xy 100.448346 -385.613922)
			(xy 100.447856 -385.583938) (xy 62.637793 -385.583938) (xy 62.622149 -385.601398) (xy 62.579281 -385.637073)
			(xy 62.531675 -385.666127) (xy 62.480346 -385.687939) (xy 62.426389 -385.702045) (xy 62.370952 -385.708145)
			(xy 62.315218 -385.706108) (xy 62.260375 -385.695978) (xy 62.207591 -385.677971) (xy 62.157991 -385.65247)
			(xy 62.112633 -385.620019) (xy 62.072484 -385.58131) (xy 62.038398 -385.537167) (xy 62.011102 -385.488532)
			(xy 61.991179 -385.436441) (xy 61.979053 -385.382004) (xy 61.974982 -385.326382) (xy 51.556158 -385.326382)
			(xy 51.556158 -385.718812) (xy 56.34177 -385.718812) (xy 56.345841 -385.66319) (xy 56.357967 -385.608753)
			(xy 56.37789 -385.556662) (xy 56.405186 -385.508027) (xy 56.439272 -385.463884) (xy 56.479421 -385.425175)
			(xy 56.524779 -385.392724) (xy 56.574379 -385.367223) (xy 56.627163 -385.349216) (xy 56.682006 -385.339086)
			(xy 56.73774 -385.337049) (xy 56.793177 -385.343149) (xy 56.847134 -385.357255) (xy 56.898463 -385.379067)
			(xy 56.946069 -385.408121) (xy 56.988937 -385.443796) (xy 57.026154 -385.485333) (xy 57.056927 -385.531846)
			(xy 57.080599 -385.582343) (xy 57.096667 -385.63575) (xy 57.104787 -385.690926) (xy 57.105296 -385.718812)
			(xy 57.104787 -385.746698) (xy 57.096667 -385.801874) (xy 57.080599 -385.855281) (xy 57.056927 -385.905778)
			(xy 57.026154 -385.952291) (xy 56.988937 -385.993828) (xy 56.946069 -386.029503) (xy 56.898463 -386.058557)
			(xy 56.88267 -386.065268) (xy 60.783214 -386.065268) (xy 60.787285 -386.009646) (xy 60.799411 -385.955209)
			(xy 60.819334 -385.903118) (xy 60.84663 -385.854483) (xy 60.880716 -385.81034) (xy 60.920865 -385.771631)
			(xy 60.966223 -385.73918) (xy 61.015823 -385.713679) (xy 61.068607 -385.695672) (xy 61.12345 -385.685542)
			(xy 61.179184 -385.683505) (xy 61.234621 -385.689605) (xy 61.288578 -385.703711) (xy 61.339907 -385.725523)
			(xy 61.387513 -385.754577) (xy 61.430381 -385.790252) (xy 61.467598 -385.831789) (xy 61.498371 -385.878302)
			(xy 61.522043 -385.928799) (xy 61.538111 -385.982206) (xy 61.546231 -386.037382) (xy 61.54674 -386.065268)
			(xy 61.546231 -386.093154) (xy 61.538111 -386.14833) (xy 61.522043 -386.201737) (xy 61.498371 -386.252234)
			(xy 61.467598 -386.298747) (xy 61.430381 -386.340284) (xy 61.387513 -386.375959) (xy 61.339907 -386.405013)
			(xy 61.288578 -386.426825) (xy 61.234621 -386.440931) (xy 61.179184 -386.447031) (xy 61.12345 -386.444994)
			(xy 61.068607 -386.434864) (xy 61.015823 -386.416857) (xy 60.966223 -386.391356) (xy 60.920865 -386.358905)
			(xy 60.880716 -386.320196) (xy 60.84663 -386.276053) (xy 60.819334 -386.227418) (xy 60.799411 -386.175327)
			(xy 60.787285 -386.12089) (xy 60.783214 -386.065268) (xy 56.88267 -386.065268) (xy 56.847134 -386.080369)
			(xy 56.793177 -386.094475) (xy 56.73774 -386.100575) (xy 56.682006 -386.098538) (xy 56.627163 -386.088408)
			(xy 56.574379 -386.070401) (xy 56.524779 -386.0449) (xy 56.479421 -386.012449) (xy 56.439272 -385.97374)
			(xy 56.405186 -385.929597) (xy 56.37789 -385.880962) (xy 56.357967 -385.828871) (xy 56.345841 -385.774434)
			(xy 56.34177 -385.718812) (xy 51.556158 -385.718812) (xy 51.556158 -386.734812) (xy 57.268616 -386.734812)
			(xy 57.272687 -386.67919) (xy 57.284813 -386.624753) (xy 57.304736 -386.572662) (xy 57.332032 -386.524027)
			(xy 57.366118 -386.479884) (xy 57.406267 -386.441175) (xy 57.451625 -386.408724) (xy 57.501225 -386.383223)
			(xy 57.554009 -386.365216) (xy 57.608852 -386.355086) (xy 57.664586 -386.353049) (xy 57.720023 -386.359149)
			(xy 57.77398 -386.373255) (xy 57.825309 -386.395067) (xy 57.872915 -386.424121) (xy 57.915783 -386.459796)
			(xy 57.953 -386.501333) (xy 57.983773 -386.547846) (xy 58.007445 -386.598343) (xy 58.023513 -386.65175)
			(xy 58.031633 -386.706926) (xy 58.032142 -386.734812) (xy 59.48248 -386.734812) (xy 59.486551 -386.67919)
			(xy 59.498677 -386.624753) (xy 59.5186 -386.572662) (xy 59.545896 -386.524027) (xy 59.579982 -386.479884)
			(xy 59.620131 -386.441175) (xy 59.665489 -386.408724) (xy 59.715089 -386.383223) (xy 59.767873 -386.365216)
			(xy 59.822716 -386.355086) (xy 59.87845 -386.353049) (xy 59.933887 -386.359149) (xy 59.987844 -386.373255)
			(xy 60.039173 -386.395067) (xy 60.086779 -386.424121) (xy 60.119496 -386.451348) (xy 145.01622 -386.451348)
			(xy 145.016665 -386.424798) (xy 145.024028 -386.372211) (xy 145.038619 -386.321156) (xy 145.060154 -386.272619)
			(xy 145.088218 -386.227541) (xy 145.122267 -386.186795) (xy 145.161641 -386.151168) (xy 145.183352 -386.13588)
			(xy 145.192242 -386.129784) (xy 145.203418 -386.112004) (xy 145.217642 -386.017008) (xy 145.212308 -385.996688)
			(xy 145.20545 -385.988306) (xy 145.189739 -385.967951) (xy 145.16336 -385.923815) (xy 145.143146 -385.876536)
			(xy 145.129463 -385.826971) (xy 145.122558 -385.776017) (xy 145.122138 -385.750308) (xy 145.122624 -385.723057)
			(xy 145.13038 -385.669109) (xy 145.145735 -385.616814) (xy 145.168377 -385.567237) (xy 145.197843 -385.521387)
			(xy 145.233534 -385.480196) (xy 145.274725 -385.444505) (xy 145.320575 -385.415039) (xy 145.370152 -385.392397)
			(xy 145.422447 -385.377042) (xy 145.476395 -385.369286) (xy 145.530897 -385.369286) (xy 145.584845 -385.377042)
			(xy 145.63714 -385.392397) (xy 145.686717 -385.415039) (xy 145.732567 -385.444505) (xy 145.773758 -385.480196)
			(xy 145.809449 -385.521387) (xy 145.838915 -385.567237) (xy 145.849326 -385.590034) (xy 149.95347 -385.590034)
			(xy 149.957541 -385.534412) (xy 149.969667 -385.479975) (xy 149.98959 -385.427884) (xy 150.016886 -385.379249)
			(xy 150.050972 -385.335106) (xy 150.091121 -385.296397) (xy 150.136479 -385.263946) (xy 150.186079 -385.238445)
			(xy 150.238863 -385.220438) (xy 150.293706 -385.210308) (xy 150.34944 -385.208271) (xy 150.404877 -385.214371)
			(xy 150.458834 -385.228477) (xy 150.510163 -385.250289) (xy 150.557769 -385.279343) (xy 150.600637 -385.315018)
			(xy 150.637854 -385.356555) (xy 150.668627 -385.403068) (xy 150.692299 -385.453565) (xy 150.708367 -385.506972)
			(xy 150.716487 -385.562148) (xy 150.716996 -385.590034) (xy 150.716487 -385.61792) (xy 150.708367 -385.673096)
			(xy 150.692299 -385.726503) (xy 150.668627 -385.777) (xy 150.637854 -385.823513) (xy 150.600637 -385.86505)
			(xy 150.557769 -385.900725) (xy 150.510163 -385.929779) (xy 150.458834 -385.951591) (xy 150.404877 -385.965697)
			(xy 150.34944 -385.971797) (xy 150.293706 -385.96976) (xy 150.238863 -385.95963) (xy 150.186079 -385.941623)
			(xy 150.136479 -385.916122) (xy 150.091121 -385.883671) (xy 150.050972 -385.844962) (xy 150.016886 -385.800819)
			(xy 149.98959 -385.752184) (xy 149.969667 -385.700093) (xy 149.957541 -385.645656) (xy 149.95347 -385.590034)
			(xy 145.849326 -385.590034) (xy 145.861557 -385.616814) (xy 145.876912 -385.669109) (xy 145.884668 -385.723057)
			(xy 145.885154 -385.750308) (xy 145.884687 -385.776857) (xy 145.877329 -385.829443) (xy 145.862743 -385.880499)
			(xy 145.841212 -385.929036) (xy 145.813151 -385.974114) (xy 145.779105 -386.014861) (xy 145.739732 -386.050488)
			(xy 145.718022 -386.065776) (xy 145.709132 -386.071872) (xy 145.697956 -386.089652) (xy 145.683732 -386.184648)
			(xy 145.689066 -386.204968) (xy 145.695924 -386.21335) (xy 145.711625 -386.233711) (xy 145.738003 -386.277847)
			(xy 145.758218 -386.325125) (xy 145.771904 -386.374688) (xy 145.778813 -386.425639) (xy 145.779236 -386.451348)
			(xy 145.77875 -386.478599) (xy 145.770994 -386.532547) (xy 145.755639 -386.584842) (xy 145.732997 -386.634419)
			(xy 145.703531 -386.680269) (xy 145.66784 -386.72146) (xy 145.626649 -386.757151) (xy 145.580799 -386.786617)
			(xy 145.531222 -386.809259) (xy 145.478927 -386.824614) (xy 145.424979 -386.83237) (xy 145.370477 -386.83237)
			(xy 145.316529 -386.824614) (xy 145.264234 -386.809259) (xy 145.214657 -386.786617) (xy 145.168807 -386.757151)
			(xy 145.127616 -386.72146) (xy 145.091925 -386.680269) (xy 145.062459 -386.634419) (xy 145.039817 -386.584842)
			(xy 145.024462 -386.532547) (xy 145.016706 -386.478599) (xy 145.01622 -386.451348) (xy 60.119496 -386.451348)
			(xy 60.129647 -386.459796) (xy 60.166864 -386.501333) (xy 60.197637 -386.547846) (xy 60.221309 -386.598343)
			(xy 60.237377 -386.65175) (xy 60.245497 -386.706926) (xy 60.246006 -386.734812) (xy 60.245497 -386.762698)
			(xy 60.237377 -386.817874) (xy 60.221309 -386.871281) (xy 60.197637 -386.921778) (xy 60.166864 -386.968291)
			(xy 60.129647 -387.009828) (xy 60.086779 -387.045503) (xy 60.039173 -387.074557) (xy 59.987844 -387.096369)
			(xy 59.933887 -387.110475) (xy 59.87845 -387.116575) (xy 59.822716 -387.114538) (xy 59.767873 -387.104408)
			(xy 59.715089 -387.086401) (xy 59.665489 -387.0609) (xy 59.620131 -387.028449) (xy 59.579982 -386.98974)
			(xy 59.545896 -386.945597) (xy 59.5186 -386.896962) (xy 59.498677 -386.844871) (xy 59.486551 -386.790434)
			(xy 59.48248 -386.734812) (xy 58.032142 -386.734812) (xy 58.031633 -386.762698) (xy 58.023513 -386.817874)
			(xy 58.007445 -386.871281) (xy 57.983773 -386.921778) (xy 57.953 -386.968291) (xy 57.915783 -387.009828)
			(xy 57.872915 -387.045503) (xy 57.825309 -387.074557) (xy 57.77398 -387.096369) (xy 57.720023 -387.110475)
			(xy 57.664586 -387.116575) (xy 57.608852 -387.114538) (xy 57.554009 -387.104408) (xy 57.501225 -387.086401)
			(xy 57.451625 -387.0609) (xy 57.406267 -387.028449) (xy 57.366118 -386.98974) (xy 57.332032 -386.945597)
			(xy 57.304736 -386.896962) (xy 57.284813 -386.844871) (xy 57.272687 -386.790434) (xy 57.268616 -386.734812)
			(xy 51.556158 -386.734812) (xy 51.556158 -387.156198) (xy 62.08598 -387.156198) (xy 62.090051 -387.100576)
			(xy 62.102177 -387.046139) (xy 62.1221 -386.994048) (xy 62.149396 -386.945413) (xy 62.183482 -386.90127)
			(xy 62.223631 -386.862561) (xy 62.268989 -386.83011) (xy 62.318589 -386.804609) (xy 62.371373 -386.786602)
			(xy 62.426216 -386.776472) (xy 62.48195 -386.774435) (xy 62.537387 -386.780535) (xy 62.591344 -386.794641)
			(xy 62.642673 -386.816453) (xy 62.690279 -386.845507) (xy 62.733147 -386.881182) (xy 62.770364 -386.922719)
			(xy 62.801137 -386.969232) (xy 62.824809 -387.019729) (xy 62.840877 -387.073136) (xy 62.848997 -387.128312)
			(xy 62.849506 -387.156198) (xy 62.848997 -387.184084) (xy 62.840877 -387.23926) (xy 62.824809 -387.292667)
			(xy 62.801137 -387.343164) (xy 62.770364 -387.389677) (xy 62.733147 -387.431214) (xy 62.690279 -387.466889)
			(xy 62.642673 -387.495943) (xy 62.591344 -387.517755) (xy 62.537387 -387.531861) (xy 62.48195 -387.537961)
			(xy 62.426216 -387.535924) (xy 62.371373 -387.525794) (xy 62.318589 -387.507787) (xy 62.268989 -387.482286)
			(xy 62.223631 -387.449835) (xy 62.183482 -387.411126) (xy 62.149396 -387.366983) (xy 62.1221 -387.318348)
			(xy 62.102177 -387.266257) (xy 62.090051 -387.21182) (xy 62.08598 -387.156198) (xy 51.556158 -387.156198)
			(xy 51.556158 -388.265416) (xy 59.963302 -388.265416) (xy 59.967373 -388.209794) (xy 59.979499 -388.155357)
			(xy 59.999422 -388.103266) (xy 60.026718 -388.054631) (xy 60.060804 -388.010488) (xy 60.100953 -387.971779)
			(xy 60.146311 -387.939328) (xy 60.195911 -387.913827) (xy 60.248695 -387.89582) (xy 60.303538 -387.88569)
			(xy 60.359272 -387.883653) (xy 60.414709 -387.889753) (xy 60.468666 -387.903859) (xy 60.519995 -387.925671)
			(xy 60.567601 -387.954725) (xy 60.610469 -387.9904) (xy 60.647686 -388.031937) (xy 60.678459 -388.07845)
			(xy 60.702131 -388.128947) (xy 60.708571 -388.150354) (xy 143.718278 -388.150354) (xy 143.722349 -388.094732)
			(xy 143.734475 -388.040295) (xy 143.754398 -387.988204) (xy 143.781694 -387.939569) (xy 143.81578 -387.895426)
			(xy 143.855929 -387.856717) (xy 143.901287 -387.824266) (xy 143.950887 -387.798765) (xy 144.003671 -387.780758)
			(xy 144.058514 -387.770628) (xy 144.114248 -387.768591) (xy 144.169685 -387.774691) (xy 144.223642 -387.788797)
			(xy 144.274971 -387.810609) (xy 144.322577 -387.839663) (xy 144.365445 -387.875338) (xy 144.402662 -387.916875)
			(xy 144.433435 -387.963388) (xy 144.457107 -388.013885) (xy 144.473175 -388.067292) (xy 144.481295 -388.122468)
			(xy 144.481804 -388.150354) (xy 144.481748 -388.153402) (xy 146.889468 -388.153402) (xy 146.893539 -388.09778)
			(xy 146.905665 -388.043343) (xy 146.925588 -387.991252) (xy 146.952884 -387.942617) (xy 146.98697 -387.898474)
			(xy 147.027119 -387.859765) (xy 147.072477 -387.827314) (xy 147.122077 -387.801813) (xy 147.174861 -387.783806)
			(xy 147.229704 -387.773676) (xy 147.285438 -387.771639) (xy 147.340875 -387.777739) (xy 147.394832 -387.791845)
			(xy 147.446161 -387.813657) (xy 147.493767 -387.842711) (xy 147.536635 -387.878386) (xy 147.573852 -387.919923)
			(xy 147.604625 -387.966436) (xy 147.628297 -388.016933) (xy 147.644365 -388.07034) (xy 147.652485 -388.125516)
			(xy 147.652994 -388.153402) (xy 147.652485 -388.181288) (xy 147.648141 -388.210806) (xy 148.921468 -388.210806)
			(xy 148.925539 -388.155184) (xy 148.937665 -388.100747) (xy 148.957588 -388.048656) (xy 148.984884 -388.000021)
			(xy 149.01897 -387.955878) (xy 149.059119 -387.917169) (xy 149.104477 -387.884718) (xy 149.154077 -387.859217)
			(xy 149.206861 -387.84121) (xy 149.261704 -387.83108) (xy 149.317438 -387.829043) (xy 149.372875 -387.835143)
			(xy 149.426832 -387.849249) (xy 149.478161 -387.871061) (xy 149.525767 -387.900115) (xy 149.568635 -387.93579)
			(xy 149.605852 -387.977327) (xy 149.636625 -388.02384) (xy 149.660297 -388.074337) (xy 149.676365 -388.127744)
			(xy 149.684485 -388.18292) (xy 149.684994 -388.210806) (xy 149.684485 -388.238692) (xy 149.676365 -388.293868)
			(xy 149.660297 -388.347275) (xy 149.636625 -388.397772) (xy 149.605852 -388.444285) (xy 149.568635 -388.485822)
			(xy 149.525767 -388.521497) (xy 149.478161 -388.550551) (xy 149.426832 -388.572363) (xy 149.372875 -388.586469)
			(xy 149.317438 -388.592569) (xy 149.261704 -388.590532) (xy 149.206861 -388.580402) (xy 149.154077 -388.562395)
			(xy 149.104477 -388.536894) (xy 149.059119 -388.504443) (xy 149.01897 -388.465734) (xy 148.984884 -388.421591)
			(xy 148.957588 -388.372956) (xy 148.937665 -388.320865) (xy 148.925539 -388.266428) (xy 148.921468 -388.210806)
			(xy 147.648141 -388.210806) (xy 147.644365 -388.236464) (xy 147.628297 -388.289871) (xy 147.604625 -388.340368)
			(xy 147.573852 -388.386881) (xy 147.536635 -388.428418) (xy 147.493767 -388.464093) (xy 147.446161 -388.493147)
			(xy 147.394832 -388.514959) (xy 147.340875 -388.529065) (xy 147.285438 -388.535165) (xy 147.229704 -388.533128)
			(xy 147.174861 -388.522998) (xy 147.122077 -388.504991) (xy 147.072477 -388.47949) (xy 147.027119 -388.447039)
			(xy 146.98697 -388.40833) (xy 146.952884 -388.364187) (xy 146.925588 -388.315552) (xy 146.905665 -388.263461)
			(xy 146.893539 -388.209024) (xy 146.889468 -388.153402) (xy 144.481748 -388.153402) (xy 144.481295 -388.17824)
			(xy 144.473175 -388.233416) (xy 144.457107 -388.286823) (xy 144.433435 -388.33732) (xy 144.402662 -388.383833)
			(xy 144.365445 -388.42537) (xy 144.322577 -388.461045) (xy 144.274971 -388.490099) (xy 144.223642 -388.511911)
			(xy 144.169685 -388.526017) (xy 144.114248 -388.532117) (xy 144.058514 -388.53008) (xy 144.003671 -388.51995)
			(xy 143.950887 -388.501943) (xy 143.901287 -388.476442) (xy 143.855929 -388.443991) (xy 143.81578 -388.405282)
			(xy 143.781694 -388.361139) (xy 143.754398 -388.312504) (xy 143.734475 -388.260413) (xy 143.722349 -388.205976)
			(xy 143.718278 -388.150354) (xy 60.708571 -388.150354) (xy 60.718199 -388.182354) (xy 60.726319 -388.23753)
			(xy 60.726828 -388.265416) (xy 60.726319 -388.293302) (xy 60.718199 -388.348478) (xy 60.702131 -388.401885)
			(xy 60.678459 -388.452382) (xy 60.647686 -388.498895) (xy 60.610469 -388.540432) (xy 60.567601 -388.576107)
			(xy 60.519995 -388.605161) (xy 60.468666 -388.626973) (xy 60.414709 -388.641079) (xy 60.359272 -388.647179)
			(xy 60.303538 -388.645142) (xy 60.248695 -388.635012) (xy 60.195911 -388.617005) (xy 60.146311 -388.591504)
			(xy 60.100953 -388.559053) (xy 60.060804 -388.520344) (xy 60.026718 -388.476201) (xy 59.999422 -388.427566)
			(xy 59.979499 -388.375475) (xy 59.967373 -388.321038) (xy 59.963302 -388.265416) (xy 51.556158 -388.265416)
			(xy 51.556158 -388.822438) (xy 55.493156 -388.822438) (xy 55.497227 -388.766816) (xy 55.509353 -388.712379)
			(xy 55.529276 -388.660288) (xy 55.556572 -388.611653) (xy 55.590658 -388.56751) (xy 55.630807 -388.528801)
			(xy 55.676165 -388.49635) (xy 55.725765 -388.470849) (xy 55.778549 -388.452842) (xy 55.833392 -388.442712)
			(xy 55.889126 -388.440675) (xy 55.944563 -388.446775) (xy 55.99852 -388.460881) (xy 56.049849 -388.482693)
			(xy 56.097455 -388.511747) (xy 56.140323 -388.547422) (xy 56.17754 -388.588959) (xy 56.208313 -388.635472)
			(xy 56.231985 -388.685969) (xy 56.248053 -388.739376) (xy 56.255716 -388.79145) (xy 57.41619 -388.79145)
			(xy 57.420261 -388.735828) (xy 57.432387 -388.681391) (xy 57.45231 -388.6293) (xy 57.479606 -388.580665)
			(xy 57.513692 -388.536522) (xy 57.553841 -388.497813) (xy 57.599199 -388.465362) (xy 57.648799 -388.439861)
			(xy 57.701583 -388.421854) (xy 57.756426 -388.411724) (xy 57.81216 -388.409687) (xy 57.867597 -388.415787)
			(xy 57.921554 -388.429893) (xy 57.972883 -388.451705) (xy 58.020489 -388.480759) (xy 58.063357 -388.516434)
			(xy 58.100574 -388.557971) (xy 58.131347 -388.604484) (xy 58.155019 -388.654981) (xy 58.171087 -388.708388)
			(xy 58.179207 -388.763564) (xy 58.179716 -388.79145) (xy 58.179207 -388.819336) (xy 58.171087 -388.874512)
			(xy 58.163294 -388.900416) (xy 58.70397 -388.900416) (xy 58.708041 -388.844794) (xy 58.720167 -388.790357)
			(xy 58.74009 -388.738266) (xy 58.767386 -388.689631) (xy 58.801472 -388.645488) (xy 58.841621 -388.606779)
			(xy 58.886979 -388.574328) (xy 58.936579 -388.548827) (xy 58.989363 -388.53082) (xy 59.044206 -388.52069)
			(xy 59.09994 -388.518653) (xy 59.155377 -388.524753) (xy 59.209334 -388.538859) (xy 59.260663 -388.560671)
			(xy 59.308269 -388.589725) (xy 59.351137 -388.6254) (xy 59.388354 -388.666937) (xy 59.419127 -388.71345)
			(xy 59.442799 -388.763947) (xy 59.458867 -388.817354) (xy 59.466987 -388.87253) (xy 59.467496 -388.900416)
			(xy 59.466987 -388.928302) (xy 59.458867 -388.983478) (xy 59.442799 -389.036885) (xy 59.435807 -389.0518)
			(xy 61.746382 -389.0518) (xy 61.750453 -388.996178) (xy 61.762579 -388.941741) (xy 61.782502 -388.88965)
			(xy 61.809798 -388.841015) (xy 61.843884 -388.796872) (xy 61.884033 -388.758163) (xy 61.929391 -388.725712)
			(xy 61.978991 -388.700211) (xy 62.031775 -388.682204) (xy 62.086618 -388.672074) (xy 62.142352 -388.670037)
			(xy 62.197789 -388.676137) (xy 62.251746 -388.690243) (xy 62.303075 -388.712055) (xy 62.350681 -388.741109)
			(xy 62.393549 -388.776784) (xy 62.430766 -388.818321) (xy 62.461539 -388.864834) (xy 62.483577 -388.911846)
			(xy 103.494838 -388.911846) (xy 103.498909 -388.856224) (xy 103.511035 -388.801787) (xy 103.530958 -388.749696)
			(xy 103.558254 -388.701061) (xy 103.59234 -388.656918) (xy 103.632489 -388.618209) (xy 103.677847 -388.585758)
			(xy 103.727447 -388.560257) (xy 103.780231 -388.54225) (xy 103.835074 -388.53212) (xy 103.890808 -388.530083)
			(xy 103.946245 -388.536183) (xy 104.000202 -388.550289) (xy 104.051531 -388.572101) (xy 104.099137 -388.601155)
			(xy 104.142005 -388.63683) (xy 104.179222 -388.678367) (xy 104.192533 -388.698486) (xy 144.600166 -388.698486)
			(xy 144.604237 -388.642864) (xy 144.616363 -388.588427) (xy 144.636286 -388.536336) (xy 144.663582 -388.487701)
			(xy 144.697668 -388.443558) (xy 144.737817 -388.404849) (xy 144.783175 -388.372398) (xy 144.832775 -388.346897)
			(xy 144.885559 -388.32889) (xy 144.940402 -388.31876) (xy 144.996136 -388.316723) (xy 145.051573 -388.322823)
			(xy 145.10553 -388.336929) (xy 145.156859 -388.358741) (xy 145.204465 -388.387795) (xy 145.247333 -388.42347)
			(xy 145.28455 -388.465007) (xy 145.315323 -388.51152) (xy 145.338995 -388.562017) (xy 145.355063 -388.615424)
			(xy 145.363183 -388.6706) (xy 145.363692 -388.698486) (xy 145.363183 -388.726372) (xy 145.355063 -388.781548)
			(xy 145.338995 -388.834955) (xy 145.315323 -388.885452) (xy 145.28455 -388.931965) (xy 145.247333 -388.973502)
			(xy 145.204465 -389.009177) (xy 145.156859 -389.038231) (xy 145.10553 -389.060043) (xy 145.051573 -389.074149)
			(xy 144.996136 -389.080249) (xy 144.940402 -389.078212) (xy 144.885559 -389.068082) (xy 144.832775 -389.050075)
			(xy 144.783175 -389.024574) (xy 144.737817 -388.992123) (xy 144.697668 -388.953414) (xy 144.663582 -388.909271)
			(xy 144.636286 -388.860636) (xy 144.616363 -388.808545) (xy 144.604237 -388.754108) (xy 144.600166 -388.698486)
			(xy 104.192533 -388.698486) (xy 104.209995 -388.72488) (xy 104.233667 -388.775377) (xy 104.249735 -388.828784)
			(xy 104.257855 -388.88396) (xy 104.258364 -388.911846) (xy 104.257855 -388.939732) (xy 104.249735 -388.994908)
			(xy 104.233667 -389.048315) (xy 104.209995 -389.098812) (xy 104.179222 -389.145325) (xy 104.142005 -389.186862)
			(xy 104.099137 -389.222537) (xy 104.051531 -389.251591) (xy 104.000202 -389.273403) (xy 103.946245 -389.287509)
			(xy 103.890808 -389.293609) (xy 103.835074 -389.291572) (xy 103.780231 -389.281442) (xy 103.727447 -389.263435)
			(xy 103.677847 -389.237934) (xy 103.632489 -389.205483) (xy 103.59234 -389.166774) (xy 103.558254 -389.122631)
			(xy 103.530958 -389.073996) (xy 103.511035 -389.021905) (xy 103.498909 -388.967468) (xy 103.494838 -388.911846)
			(xy 62.483577 -388.911846) (xy 62.485211 -388.915331) (xy 62.501279 -388.968738) (xy 62.509399 -389.023914)
			(xy 62.509908 -389.0518) (xy 62.509399 -389.079686) (xy 62.501279 -389.134862) (xy 62.485211 -389.188269)
			(xy 62.461539 -389.238766) (xy 62.430766 -389.285279) (xy 62.393717 -389.326628) (xy 63.340486 -389.326628)
			(xy 63.344557 -389.271006) (xy 63.356683 -389.216569) (xy 63.376606 -389.164478) (xy 63.403902 -389.115843)
			(xy 63.437988 -389.0717) (xy 63.478137 -389.032991) (xy 63.523495 -389.00054) (xy 63.573095 -388.975039)
			(xy 63.625879 -388.957032) (xy 63.680722 -388.946902) (xy 63.736456 -388.944865) (xy 63.791893 -388.950965)
			(xy 63.84585 -388.965071) (xy 63.897179 -388.986883) (xy 63.944785 -389.015937) (xy 63.987653 -389.051612)
			(xy 64.02487 -389.093149) (xy 64.055643 -389.139662) (xy 64.079315 -389.190159) (xy 64.095383 -389.243566)
			(xy 64.103503 -389.298742) (xy 64.104012 -389.326628) (xy 64.103503 -389.354514) (xy 64.095383 -389.40969)
			(xy 64.079315 -389.463097) (xy 64.055643 -389.513594) (xy 64.02487 -389.560107) (xy 63.987653 -389.601644)
			(xy 63.944785 -389.637319) (xy 63.897179 -389.666373) (xy 63.84585 -389.688185) (xy 63.791893 -389.702291)
			(xy 63.736456 -389.708391) (xy 63.680722 -389.706354) (xy 63.625879 -389.696224) (xy 63.573095 -389.678217)
			(xy 63.523495 -389.652716) (xy 63.478137 -389.620265) (xy 63.437988 -389.581556) (xy 63.403902 -389.537413)
			(xy 63.376606 -389.488778) (xy 63.356683 -389.436687) (xy 63.344557 -389.38225) (xy 63.340486 -389.326628)
			(xy 62.393717 -389.326628) (xy 62.393549 -389.326816) (xy 62.350681 -389.362491) (xy 62.303075 -389.391545)
			(xy 62.251746 -389.413357) (xy 62.197789 -389.427463) (xy 62.142352 -389.433563) (xy 62.086618 -389.431526)
			(xy 62.031775 -389.421396) (xy 61.978991 -389.403389) (xy 61.929391 -389.377888) (xy 61.884033 -389.345437)
			(xy 61.843884 -389.306728) (xy 61.809798 -389.262585) (xy 61.782502 -389.21395) (xy 61.762579 -389.161859)
			(xy 61.750453 -389.107422) (xy 61.746382 -389.0518) (xy 59.435807 -389.0518) (xy 59.419127 -389.087382)
			(xy 59.388354 -389.133895) (xy 59.351137 -389.175432) (xy 59.308269 -389.211107) (xy 59.260663 -389.240161)
			(xy 59.209334 -389.261973) (xy 59.155377 -389.276079) (xy 59.09994 -389.282179) (xy 59.044206 -389.280142)
			(xy 58.989363 -389.270012) (xy 58.936579 -389.252005) (xy 58.886979 -389.226504) (xy 58.841621 -389.194053)
			(xy 58.801472 -389.155344) (xy 58.767386 -389.111201) (xy 58.74009 -389.062566) (xy 58.720167 -389.010475)
			(xy 58.708041 -388.956038) (xy 58.70397 -388.900416) (xy 58.163294 -388.900416) (xy 58.155019 -388.927919)
			(xy 58.131347 -388.978416) (xy 58.100574 -389.024929) (xy 58.063357 -389.066466) (xy 58.020489 -389.102141)
			(xy 57.972883 -389.131195) (xy 57.921554 -389.153007) (xy 57.867597 -389.167113) (xy 57.81216 -389.173213)
			(xy 57.756426 -389.171176) (xy 57.701583 -389.161046) (xy 57.648799 -389.143039) (xy 57.599199 -389.117538)
			(xy 57.553841 -389.085087) (xy 57.513692 -389.046378) (xy 57.479606 -389.002235) (xy 57.45231 -388.9536)
			(xy 57.432387 -388.901509) (xy 57.420261 -388.847072) (xy 57.41619 -388.79145) (xy 56.255716 -388.79145)
			(xy 56.256173 -388.794552) (xy 56.256682 -388.822438) (xy 56.256173 -388.850324) (xy 56.248053 -388.9055)
			(xy 56.231985 -388.958907) (xy 56.208313 -389.009404) (xy 56.17754 -389.055917) (xy 56.140323 -389.097454)
			(xy 56.097455 -389.133129) (xy 56.049849 -389.162183) (xy 55.99852 -389.183995) (xy 55.944563 -389.198101)
			(xy 55.889126 -389.204201) (xy 55.833392 -389.202164) (xy 55.778549 -389.192034) (xy 55.725765 -389.174027)
			(xy 55.676165 -389.148526) (xy 55.630807 -389.116075) (xy 55.590658 -389.077366) (xy 55.556572 -389.033223)
			(xy 55.529276 -388.984588) (xy 55.509353 -388.932497) (xy 55.497227 -388.87806) (xy 55.493156 -388.822438)
			(xy 51.556158 -388.822438) (xy 51.556158 -389.66267) (xy 51.556626 -389.672544) (xy 51.564078 -389.690833)
			(xy 51.570636 -389.69823) (xy 51.57089 -389.698484) (xy 52.245104 -390.3726) (xy 98.601782 -390.3726)
			(xy 98.605853 -390.316978) (xy 98.617979 -390.262541) (xy 98.637902 -390.21045) (xy 98.665198 -390.161815)
			(xy 98.699284 -390.117672) (xy 98.739433 -390.078963) (xy 98.784791 -390.046512) (xy 98.834391 -390.021011)
			(xy 98.887175 -390.003004) (xy 98.942018 -389.992874) (xy 98.997752 -389.990837) (xy 99.053189 -389.996937)
			(xy 99.107146 -390.011043) (xy 99.158475 -390.032855) (xy 99.206081 -390.061909) (xy 99.248949 -390.097584)
			(xy 99.286166 -390.139121) (xy 99.316939 -390.185634) (xy 99.340611 -390.236131) (xy 99.356679 -390.289538)
			(xy 99.364799 -390.344714) (xy 99.365308 -390.3726) (xy 99.364799 -390.400486) (xy 99.356679 -390.455662)
			(xy 99.340611 -390.509069) (xy 99.316939 -390.559566) (xy 99.291747 -390.597644) (xy 99.793806 -390.597644)
			(xy 99.794296 -390.570275) (xy 99.802108 -390.516097) (xy 99.817591 -390.463594) (xy 99.840428 -390.413846)
			(xy 99.870147 -390.367878) (xy 99.887786 -390.346946) (xy 99.893882 -390.339834) (xy 99.900232 -390.322816)
			(xy 99.900232 -390.237472) (xy 99.893882 -390.220454) (xy 99.887786 -390.213342) (xy 99.870151 -390.192407)
			(xy 99.840439 -390.146435) (xy 99.817602 -390.096688) (xy 99.80211 -390.044188) (xy 99.794281 -389.990013)
			(xy 99.793806 -389.962644) (xy 99.794292 -389.935393) (xy 99.802048 -389.881445) (xy 99.817403 -389.82915)
			(xy 99.840045 -389.779573) (xy 99.869511 -389.733723) (xy 99.905202 -389.692532) (xy 99.946393 -389.656841)
			(xy 99.992243 -389.627375) (xy 100.04182 -389.604733) (xy 100.094115 -389.589378) (xy 100.148063 -389.581622)
			(xy 100.202565 -389.581622) (xy 100.256513 -389.589378) (xy 100.308808 -389.604733) (xy 100.358385 -389.627375)
			(xy 100.404235 -389.656841) (xy 100.445426 -389.692532) (xy 100.475893 -389.727694) (xy 106.942888 -389.727694)
			(xy 106.946959 -389.672072) (xy 106.959085 -389.617635) (xy 106.979008 -389.565544) (xy 107.006304 -389.516909)
			(xy 107.04039 -389.472766) (xy 107.080539 -389.434057) (xy 107.125897 -389.401606) (xy 107.175497 -389.376105)
			(xy 107.228281 -389.358098) (xy 107.283124 -389.347968) (xy 107.338858 -389.345931) (xy 107.394295 -389.352031)
			(xy 107.423431 -389.359648) (xy 145.873468 -389.359648) (xy 145.877539 -389.304026) (xy 145.889665 -389.249589)
			(xy 145.909588 -389.197498) (xy 145.936884 -389.148863) (xy 145.97097 -389.10472) (xy 146.011119 -389.066011)
			(xy 146.056477 -389.03356) (xy 146.106077 -389.008059) (xy 146.158861 -388.990052) (xy 146.213704 -388.979922)
			(xy 146.269438 -388.977885) (xy 146.324875 -388.983985) (xy 146.378832 -388.998091) (xy 146.430161 -389.019903)
			(xy 146.477767 -389.048957) (xy 146.520635 -389.084632) (xy 146.557852 -389.126169) (xy 146.588625 -389.172682)
			(xy 146.612297 -389.223179) (xy 146.628365 -389.276586) (xy 146.636485 -389.331762) (xy 146.636994 -389.359648)
			(xy 146.636485 -389.387534) (xy 146.636365 -389.38835) (xy 147.905468 -389.38835) (xy 147.909539 -389.332728)
			(xy 147.921665 -389.278291) (xy 147.941588 -389.2262) (xy 147.968884 -389.177565) (xy 148.00297 -389.133422)
			(xy 148.043119 -389.094713) (xy 148.088477 -389.062262) (xy 148.138077 -389.036761) (xy 148.190861 -389.018754)
			(xy 148.245704 -389.008624) (xy 148.301438 -389.006587) (xy 148.356875 -389.012687) (xy 148.410832 -389.026793)
			(xy 148.462161 -389.048605) (xy 148.509767 -389.077659) (xy 148.552635 -389.113334) (xy 148.589852 -389.154871)
			(xy 148.620625 -389.201384) (xy 148.644297 -389.251881) (xy 148.660365 -389.305288) (xy 148.668485 -389.360464)
			(xy 148.668994 -389.38835) (xy 148.668485 -389.416236) (xy 148.660365 -389.471412) (xy 148.644297 -389.524819)
			(xy 148.620625 -389.575316) (xy 148.589852 -389.621829) (xy 148.552635 -389.663366) (xy 148.509767 -389.699041)
			(xy 148.462161 -389.728095) (xy 148.410832 -389.749907) (xy 148.356875 -389.764013) (xy 148.301438 -389.770113)
			(xy 148.245704 -389.768076) (xy 148.190861 -389.757946) (xy 148.138077 -389.739939) (xy 148.088477 -389.714438)
			(xy 148.043119 -389.681987) (xy 148.00297 -389.643278) (xy 147.968884 -389.599135) (xy 147.941588 -389.5505)
			(xy 147.921665 -389.498409) (xy 147.909539 -389.443972) (xy 147.905468 -389.38835) (xy 146.636365 -389.38835)
			(xy 146.628365 -389.44271) (xy 146.612297 -389.496117) (xy 146.588625 -389.546614) (xy 146.557852 -389.593127)
			(xy 146.520635 -389.634664) (xy 146.477767 -389.670339) (xy 146.430161 -389.699393) (xy 146.378832 -389.721205)
			(xy 146.324875 -389.735311) (xy 146.269438 -389.741411) (xy 146.213704 -389.739374) (xy 146.158861 -389.729244)
			(xy 146.106077 -389.711237) (xy 146.056477 -389.685736) (xy 146.011119 -389.653285) (xy 145.97097 -389.614576)
			(xy 145.936884 -389.570433) (xy 145.909588 -389.521798) (xy 145.889665 -389.469707) (xy 145.877539 -389.41527)
			(xy 145.873468 -389.359648) (xy 107.423431 -389.359648) (xy 107.448252 -389.366137) (xy 107.499581 -389.387949)
			(xy 107.547187 -389.417003) (xy 107.590055 -389.452678) (xy 107.627272 -389.494215) (xy 107.658045 -389.540728)
			(xy 107.681717 -389.591225) (xy 107.697785 -389.644632) (xy 107.705905 -389.699808) (xy 107.706414 -389.727694)
			(xy 107.705905 -389.75558) (xy 107.697785 -389.810756) (xy 107.681717 -389.864163) (xy 107.658045 -389.91466)
			(xy 107.657555 -389.9154) (xy 143.229582 -389.9154) (xy 143.233653 -389.859778) (xy 143.245779 -389.805341)
			(xy 143.265702 -389.75325) (xy 143.292998 -389.704615) (xy 143.327084 -389.660472) (xy 143.367233 -389.621763)
			(xy 143.412591 -389.589312) (xy 143.462191 -389.563811) (xy 143.514975 -389.545804) (xy 143.569818 -389.535674)
			(xy 143.625552 -389.533637) (xy 143.680989 -389.539737) (xy 143.734946 -389.553843) (xy 143.786275 -389.575655)
			(xy 143.833881 -389.604709) (xy 143.876749 -389.640384) (xy 143.913966 -389.681921) (xy 143.944739 -389.728434)
			(xy 143.968411 -389.778931) (xy 143.984479 -389.832338) (xy 143.992599 -389.887514) (xy 143.993108 -389.9154)
			(xy 143.992599 -389.943286) (xy 143.984479 -389.998462) (xy 143.968411 -390.051869) (xy 143.944739 -390.102366)
			(xy 143.913966 -390.148879) (xy 143.876749 -390.190416) (xy 143.833881 -390.226091) (xy 143.786275 -390.255145)
			(xy 143.734946 -390.276957) (xy 143.680989 -390.291063) (xy 143.625552 -390.297163) (xy 143.569818 -390.295126)
			(xy 143.514975 -390.284996) (xy 143.462191 -390.266989) (xy 143.412591 -390.241488) (xy 143.367233 -390.209037)
			(xy 143.327084 -390.170328) (xy 143.292998 -390.126185) (xy 143.265702 -390.07755) (xy 143.245779 -390.025459)
			(xy 143.233653 -389.971022) (xy 143.229582 -389.9154) (xy 107.657555 -389.9154) (xy 107.627272 -389.961173)
			(xy 107.590055 -390.00271) (xy 107.547187 -390.038385) (xy 107.499581 -390.067439) (xy 107.448252 -390.089251)
			(xy 107.394295 -390.103357) (xy 107.338858 -390.109457) (xy 107.283124 -390.10742) (xy 107.228281 -390.09729)
			(xy 107.175497 -390.079283) (xy 107.125897 -390.053782) (xy 107.080539 -390.021331) (xy 107.04039 -389.982622)
			(xy 107.006304 -389.938479) (xy 106.979008 -389.889844) (xy 106.959085 -389.837753) (xy 106.946959 -389.783316)
			(xy 106.942888 -389.727694) (xy 100.475893 -389.727694) (xy 100.481117 -389.733723) (xy 100.510583 -389.779573)
			(xy 100.533225 -389.82915) (xy 100.54858 -389.881445) (xy 100.556336 -389.935393) (xy 100.556822 -389.962644)
			(xy 100.556342 -389.990014) (xy 100.548531 -390.044193) (xy 100.533046 -390.096697) (xy 100.510207 -390.146444)
			(xy 100.480483 -390.192411) (xy 100.462842 -390.213342) (xy 100.456746 -390.220454) (xy 100.450396 -390.237472)
			(xy 100.450396 -390.322816) (xy 100.456746 -390.339834) (xy 100.462842 -390.346946) (xy 100.480476 -390.367882)
			(xy 100.510187 -390.413854) (xy 100.533024 -390.463601) (xy 100.548516 -390.5161) (xy 100.556347 -390.570275)
			(xy 100.556822 -390.597644) (xy 100.556336 -390.624895) (xy 100.54858 -390.678843) (xy 100.533225 -390.731138)
			(xy 100.518558 -390.763252) (xy 143.960848 -390.763252) (xy 143.964919 -390.70763) (xy 143.977045 -390.653193)
			(xy 143.996968 -390.601102) (xy 144.024264 -390.552467) (xy 144.05835 -390.508324) (xy 144.098499 -390.469615)
			(xy 144.143857 -390.437164) (xy 144.193457 -390.411663) (xy 144.246241 -390.393656) (xy 144.301084 -390.383526)
			(xy 144.356818 -390.381489) (xy 144.412255 -390.387589) (xy 144.466212 -390.401695) (xy 144.517541 -390.423507)
			(xy 144.565147 -390.452561) (xy 144.608015 -390.488236) (xy 144.645232 -390.529773) (xy 144.676005 -390.576286)
			(xy 144.699677 -390.626783) (xy 144.715745 -390.68019) (xy 144.723865 -390.735366) (xy 144.724374 -390.763252)
			(xy 144.723865 -390.791138) (xy 144.715745 -390.846314) (xy 144.699677 -390.899721) (xy 144.676005 -390.950218)
			(xy 144.645232 -390.996731) (xy 144.608015 -391.038268) (xy 144.565147 -391.073943) (xy 144.517541 -391.102997)
			(xy 144.466212 -391.124809) (xy 144.412255 -391.138915) (xy 144.356818 -391.145015) (xy 144.301084 -391.142978)
			(xy 144.246241 -391.132848) (xy 144.193457 -391.114841) (xy 144.143857 -391.08934) (xy 144.098499 -391.056889)
			(xy 144.05835 -391.01818) (xy 144.024264 -390.974037) (xy 143.996968 -390.925402) (xy 143.977045 -390.873311)
			(xy 143.964919 -390.818874) (xy 143.960848 -390.763252) (xy 100.518558 -390.763252) (xy 100.510583 -390.780715)
			(xy 100.481117 -390.826565) (xy 100.445426 -390.867756) (xy 100.404235 -390.903447) (xy 100.358385 -390.932913)
			(xy 100.308808 -390.955555) (xy 100.256513 -390.97091) (xy 100.202565 -390.978666) (xy 100.148063 -390.978666)
			(xy 100.094115 -390.97091) (xy 100.04182 -390.955555) (xy 99.992243 -390.932913) (xy 99.946393 -390.903447)
			(xy 99.905202 -390.867756) (xy 99.869511 -390.826565) (xy 99.840045 -390.780715) (xy 99.817403 -390.731138)
			(xy 99.802048 -390.678843) (xy 99.794292 -390.624895) (xy 99.793806 -390.597644) (xy 99.291747 -390.597644)
			(xy 99.286166 -390.606079) (xy 99.248949 -390.647616) (xy 99.206081 -390.683291) (xy 99.158475 -390.712345)
			(xy 99.107146 -390.734157) (xy 99.053189 -390.748263) (xy 98.997752 -390.754363) (xy 98.942018 -390.752326)
			(xy 98.887175 -390.742196) (xy 98.834391 -390.724189) (xy 98.784791 -390.698688) (xy 98.739433 -390.666237)
			(xy 98.699284 -390.627528) (xy 98.665198 -390.583385) (xy 98.637902 -390.53475) (xy 98.617979 -390.482659)
			(xy 98.605853 -390.428222) (xy 98.601782 -390.3726) (xy 52.245104 -390.3726) (xy 53.315362 -391.442702)
			(xy 53.31587 -391.44321) (xy 53.32325 -391.449794) (xy 53.34155 -391.457245) (xy 53.35143 -391.457688)
			(xy 54.911244 -391.457688) (xy 54.911752 -391.457688) (xy 55.694326 -391.45337) (xy 55.980838 -391.451592)
			(xy 55.988966 -391.45083) (xy 55.999424 -391.448498) (xy 56.017267 -391.436679) (xy 56.02351 -391.42797)
			(xy 56.068722 -391.356596) (xy 56.073744 -391.34783) (xy 56.07713 -391.32793) (xy 56.075326 -391.317988)
			(xy 56.072532 -391.306812) (xy 56.0705 -391.30224) (xy 56.059811 -391.277423) (xy 56.044749 -391.22553)
			(xy 56.037163 -391.172031) (xy 56.036718 -391.145014) (xy 56.037204 -391.117763) (xy 56.04496 -391.063815)
			(xy 56.060315 -391.01152) (xy 56.082957 -390.961943) (xy 56.112423 -390.916093) (xy 56.148114 -390.874902)
			(xy 56.189305 -390.839211) (xy 56.235155 -390.809745) (xy 56.284732 -390.787103) (xy 56.337027 -390.771748)
			(xy 56.390975 -390.763992) (xy 56.445477 -390.763992) (xy 56.499425 -390.771748) (xy 56.55172 -390.787103)
			(xy 56.601297 -390.809745) (xy 56.647147 -390.839211) (xy 56.688338 -390.874902) (xy 56.724029 -390.916093)
			(xy 56.753495 -390.961943) (xy 56.776137 -391.01152) (xy 56.791492 -391.063815) (xy 56.799248 -391.117763)
			(xy 56.799734 -391.145014) (xy 56.799246 -391.172135) (xy 56.791532 -391.225826) (xy 56.776275 -391.277879)
			(xy 56.765444 -391.302748) (xy 56.76011 -391.314686) (xy 56.762142 -391.340594) (xy 56.815482 -391.423144)
			(xy 56.820368 -391.430116) (xy 56.833785 -391.440581) (xy 56.849898 -391.446049) (xy 56.858408 -391.446258)
			(xy 57.332626 -391.443464) (xy 57.342601 -391.442937) (xy 57.361009 -391.435236) (xy 57.375083 -391.42109)
			(xy 57.382689 -391.402642) (xy 57.383172 -391.392664) (xy 57.383172 -391.3886) (xy 57.382664 -391.367264)
			(xy 57.383201 -391.334571) (xy 57.39174 -391.269746) (xy 57.408668 -391.206589) (xy 57.433694 -391.146182)
			(xy 57.46639 -391.089559) (xy 57.506198 -391.037687) (xy 57.552436 -390.991456) (xy 57.604312 -390.951655)
			(xy 57.66094 -390.918965) (xy 57.72135 -390.893947) (xy 57.784508 -390.877028) (xy 57.849335 -390.868497)
			(xy 57.882028 -390.8679) (xy 57.88279 -390.8679) (xy 57.907922 -390.868237) (xy 57.957928 -390.873324)
			(xy 57.982612 -390.87806) (xy 57.994797 -390.879813) (xy 58.01843 -390.873059) (xy 58.027824 -390.865106)
			(xy 58.147712 -390.75106) (xy 58.15502 -390.744685) (xy 58.173003 -390.737468) (xy 58.19238 -390.737427)
			(xy 58.210394 -390.744565) (xy 58.224482 -390.757868) (xy 58.232641 -390.775444) (xy 58.233564 -390.785096)
			(xy 58.244486 -390.99871) (xy 58.244994 -391.003282) (xy 58.245756 -391.0076) (xy 58.248296 -391.015728)
			(xy 58.257694 -391.037826) (xy 58.262774 -391.043922) (xy 58.263028 -391.044176) (xy 58.281627 -391.066771)
			(xy 58.313982 -391.115537) (xy 58.340413 -391.167751) (xy 58.360557 -391.222699) (xy 58.374137 -391.279625)
			(xy 58.380968 -391.337748) (xy 58.381392 -391.36701) (xy 58.381392 -391.367264) (xy 58.381138 -391.384028)
			(xy 58.381138 -391.386568) (xy 58.381559 -391.396622) (xy 58.389272 -391.415192) (xy 58.403527 -391.429374)
			(xy 58.422136 -391.436992) (xy 58.432192 -391.437368) (xy 58.95213 -391.43432) (xy 58.96089 -391.433855)
			(xy 58.977333 -391.427774) (xy 58.990783 -391.416531) (xy 58.995564 -391.409174) (xy 59.046618 -391.321798)
			(xy 59.046872 -391.294874) (xy 59.040268 -391.28319) (xy 59.028731 -391.261776) (xy 59.010578 -391.216647)
			(xy 58.99831 -391.169577) (xy 58.992125 -391.121329) (xy 58.991754 -391.097008) (xy 58.99224 -391.069757)
			(xy 58.999996 -391.015809) (xy 59.015351 -390.963514) (xy 59.037993 -390.913937) (xy 59.067459 -390.868087)
			(xy 59.10315 -390.826896) (xy 59.144341 -390.791205) (xy 59.190191 -390.761739) (xy 59.239768 -390.739097)
			(xy 59.292063 -390.723742) (xy 59.346011 -390.715986) (xy 59.400513 -390.715986) (xy 59.454461 -390.723742)
			(xy 59.506756 -390.739097) (xy 59.556333 -390.761739) (xy 59.602183 -390.791205) (xy 59.643374 -390.826896)
			(xy 59.679065 -390.868087) (xy 59.708531 -390.913937) (xy 59.731173 -390.963514) (xy 59.746528 -391.015809)
			(xy 59.754284 -391.069757) (xy 59.75477 -391.097008) (xy 59.75477 -391.097516) (xy 59.754163 -391.128169)
			(xy 59.744359 -391.188685) (xy 59.724991 -391.24685) (xy 59.711336 -391.2743) (xy 59.708542 -391.279634)
			(xy 59.704986 -391.292588) (xy 59.703462 -391.303256) (xy 59.703406 -391.309413) (xy 59.705846 -391.321479)
			(xy 59.708288 -391.327132) (xy 59.710574 -391.331958) (xy 59.754516 -391.404602) (xy 59.759356 -391.411916)
			(xy 59.772931 -391.423001) (xy 59.789441 -391.428885) (xy 59.798204 -391.42924) (xy 59.882278 -391.428732)
			(xy 59.882532 -391.428732) (xy 60.037726 -391.42797) (xy 60.10656 -391.427462) (xy 60.25261 -391.4267)
			(xy 60.54979 -391.424922) (xy 60.57646 -391.404856) (xy 60.581286 -391.3886) (xy 60.589481 -391.362665)
			(xy 60.612194 -391.313246) (xy 60.641695 -391.267553) (xy 60.677385 -391.226512) (xy 60.718541 -391.190954)
			(xy 60.764329 -391.161602) (xy 60.813822 -391.139048) (xy 60.866015 -391.123751) (xy 60.919852 -391.11602)
			(xy 60.947046 -391.11555) (xy 60.974004 -391.116012) (xy 61.027383 -391.123598) (xy 61.079162 -391.138627)
			(xy 61.128307 -391.1608) (xy 61.17384 -391.189673) (xy 61.214852 -391.224671) (xy 61.250526 -391.265098)
			(xy 61.28015 -391.310145) (xy 61.303134 -391.358917) (xy 61.311536 -391.384536) (xy 61.316616 -391.400538)
			(xy 61.34354 -391.42035) (xy 61.838332 -391.417556) (xy 61.848005 -391.41709) (xy 61.865949 -391.409848)
			(xy 61.879939 -391.396479) (xy 61.884306 -391.387838) (xy 61.929264 -391.291064) (xy 61.9252 -391.261854)
			(xy 61.915802 -391.250424) (xy 61.898943 -391.229714) (xy 61.870575 -391.184469) (xy 61.848799 -391.135709)
			(xy 61.834039 -391.084387) (xy 61.826587 -391.031507) (xy 61.82614 -391.004806) (xy 61.826603 -390.977554)
			(xy 61.83436 -390.923605) (xy 61.849716 -390.871309) (xy 61.872358 -390.821731) (xy 61.901827 -390.775881)
			(xy 61.937521 -390.734692) (xy 61.978715 -390.699002) (xy 62.024568 -390.669538) (xy 62.074149 -390.646901)
			(xy 62.126446 -390.631551) (xy 62.180396 -390.6238) (xy 62.207648 -390.623298) (xy 62.234577 -390.623764)
			(xy 62.287898 -390.631343) (xy 62.339624 -390.646344) (xy 62.388727 -390.668469) (xy 62.434231 -390.697279)
			(xy 62.475232 -390.7322) (xy 62.510916 -390.772539) (xy 62.540574 -390.817495) (xy 62.563616 -390.866174)
			(xy 62.579585 -390.91761) (xy 62.588163 -390.970779) (xy 62.589156 -390.997694) (xy 62.589156 -391.00506)
			(xy 62.5887 -391.031231) (xy 62.581502 -391.083077) (xy 62.56729 -391.133454) (xy 62.54633 -391.181417)
			(xy 62.519015 -391.226069) (xy 62.502796 -391.246614) (xy 62.502542 -391.246868) (xy 62.502288 -391.247122)
			(xy 62.496579 -391.254815) (xy 62.490826 -391.273072) (xy 62.492162 -391.292167) (xy 62.495938 -391.30097)
			(xy 62.535562 -391.384028) (xy 62.540064 -391.392561) (xy 62.554175 -391.405694) (xy 62.572148 -391.412663)
			(xy 62.58179 -391.412984) (xy 62.809374 -391.411714) (xy 62.84595 -391.41146) (xy 63.070994 -391.41019)
			(xy 63.169546 -391.409682) (xy 63.265304 -391.409174) (xy 63.273871 -391.408801) (xy 63.290029 -391.403088)
			(xy 63.303422 -391.392397) (xy 63.30823 -391.385298) (xy 63.353696 -391.312654) (xy 63.35395 -391.312146)
			(xy 63.360808 -391.30097) (xy 63.362078 -391.27557) (xy 63.35649 -391.263632) (xy 63.345222 -391.239018)
			(xy 63.328972 -391.187381) (xy 63.32019 -391.133965) (xy 63.319152 -391.106914) (xy 63.319152 -391.094468)
			(xy 63.319932 -391.06742) (xy 63.328185 -391.013944) (xy 63.343913 -390.962171) (xy 63.366799 -390.913139)
			(xy 63.396383 -390.867834) (xy 63.432073 -390.827163) (xy 63.473152 -390.791944) (xy 63.518795 -390.762883)
			(xy 63.568086 -390.740564) (xy 63.620037 -390.725433) (xy 63.673605 -390.717796) (xy 63.70066 -390.717278)
			(xy 63.727915 -390.717738) (xy 63.781871 -390.72549) (xy 63.834175 -390.740843) (xy 63.883761 -390.763483)
			(xy 63.92962 -390.79295) (xy 63.970819 -390.828643) (xy 64.006518 -390.869837) (xy 64.035991 -390.915692)
			(xy 64.058638 -390.965275) (xy 64.073998 -391.017576) (xy 64.081758 -391.071531) (xy 64.082168 -391.098786)
			(xy 64.081675 -391.126461) (xy 64.073673 -391.181231) (xy 64.057836 -391.234268) (xy 64.046608 -391.259568)
			(xy 64.04102 -391.271506) (xy 64.042798 -391.29716) (xy 64.096392 -391.380472) (xy 64.101472 -391.387076)
			(xy 64.108838 -391.395458) (xy 64.128396 -391.40384) (xy 64.139572 -391.40384) (xy 64.729868 -391.400538)
			(xy 64.746378 -391.394442) (xy 64.75349 -391.388346) (xy 64.774302 -391.371261) (xy 64.819821 -391.342498)
			(xy 64.868928 -391.320414) (xy 64.920651 -391.305448) (xy 64.973964 -391.297896) (xy 65.000886 -391.297414)
			(xy 65.007998 -391.297414) (xy 65.033144 -391.298684) (xy 65.064808 -391.302014) (xy 65.126471 -391.317851)
			(xy 65.155826 -391.33018) (xy 65.155826 -391.330434) (xy 65.179183 -391.341197) (xy 65.22302 -391.368089)
			(xy 65.243202 -391.384028) (xy 65.244218 -391.385044) (xy 65.251451 -391.390788) (xy 65.268769 -391.397168)
			(xy 65.278 -391.39749) (xy 87.945468 -391.26541) (xy 87.946992 -391.265156) (xy 87.951056 -391.265156)
			(xy 87.988687 -391.265547) (xy 88.063726 -391.271349) (xy 88.138105 -391.282845) (xy 88.17483 -391.291064)
			(xy 88.188968 -391.294366) (xy 99.119942 -391.294366) (xy 99.124013 -391.238744) (xy 99.136139 -391.184307)
			(xy 99.156062 -391.132216) (xy 99.183358 -391.083581) (xy 99.217444 -391.039438) (xy 99.257593 -391.000729)
			(xy 99.302951 -390.968278) (xy 99.352551 -390.942777) (xy 99.405335 -390.92477) (xy 99.460178 -390.91464)
			(xy 99.515912 -390.912603) (xy 99.571349 -390.918703) (xy 99.625306 -390.932809) (xy 99.676635 -390.954621)
			(xy 99.724241 -390.983675) (xy 99.767109 -391.01935) (xy 99.804326 -391.060887) (xy 99.835099 -391.1074)
			(xy 99.857137 -391.154412) (xy 106.201208 -391.154412) (xy 106.205279 -391.09879) (xy 106.217405 -391.044353)
			(xy 106.237328 -390.992262) (xy 106.264624 -390.943627) (xy 106.29871 -390.899484) (xy 106.338859 -390.860775)
			(xy 106.384217 -390.828324) (xy 106.433817 -390.802823) (xy 106.486601 -390.784816) (xy 106.541444 -390.774686)
			(xy 106.597178 -390.772649) (xy 106.652615 -390.778749) (xy 106.706572 -390.792855) (xy 106.757901 -390.814667)
			(xy 106.805507 -390.843721) (xy 106.848375 -390.879396) (xy 106.885592 -390.920933) (xy 106.916365 -390.967446)
			(xy 106.940037 -391.017943) (xy 106.956105 -391.07135) (xy 106.964225 -391.126526) (xy 106.964734 -391.154412)
			(xy 106.964225 -391.182298) (xy 106.956105 -391.237474) (xy 106.940037 -391.290881) (xy 106.916365 -391.341378)
			(xy 106.885592 -391.387891) (xy 106.848375 -391.429428) (xy 106.805507 -391.465103) (xy 106.757901 -391.494157)
			(xy 106.706572 -391.515969) (xy 106.652615 -391.530075) (xy 106.597178 -391.536175) (xy 106.541444 -391.534138)
			(xy 106.486601 -391.524008) (xy 106.433817 -391.506001) (xy 106.384217 -391.4805) (xy 106.338859 -391.448049)
			(xy 106.29871 -391.40934) (xy 106.264624 -391.365197) (xy 106.237328 -391.316562) (xy 106.217405 -391.264471)
			(xy 106.205279 -391.210034) (xy 106.201208 -391.154412) (xy 99.857137 -391.154412) (xy 99.858771 -391.157897)
			(xy 99.874839 -391.211304) (xy 99.882959 -391.26648) (xy 99.883468 -391.294366) (xy 99.882959 -391.322252)
			(xy 99.874839 -391.377428) (xy 99.858771 -391.430835) (xy 99.835099 -391.481332) (xy 99.804326 -391.527845)
			(xy 99.767109 -391.569382) (xy 99.724241 -391.605057) (xy 99.676635 -391.634111) (xy 99.628565 -391.654538)
			(xy 108.000036 -391.654538) (xy 108.004107 -391.598916) (xy 108.016233 -391.544479) (xy 108.036156 -391.492388)
			(xy 108.063452 -391.443753) (xy 108.097538 -391.39961) (xy 108.137687 -391.360901) (xy 108.183045 -391.32845)
			(xy 108.232645 -391.302949) (xy 108.285429 -391.284942) (xy 108.340272 -391.274812) (xy 108.396006 -391.272775)
			(xy 108.451443 -391.278875) (xy 108.5054 -391.292981) (xy 108.556729 -391.314793) (xy 108.604335 -391.343847)
			(xy 108.647203 -391.379522) (xy 108.68442 -391.421059) (xy 108.715193 -391.467572) (xy 108.738865 -391.518069)
			(xy 108.741561 -391.52703) (xy 142.865854 -391.52703) (xy 142.869925 -391.471408) (xy 142.882051 -391.416971)
			(xy 142.901974 -391.36488) (xy 142.92927 -391.316245) (xy 142.963356 -391.272102) (xy 143.003505 -391.233393)
			(xy 143.048863 -391.200942) (xy 143.098463 -391.175441) (xy 143.151247 -391.157434) (xy 143.20609 -391.147304)
			(xy 143.261824 -391.145267) (xy 143.317261 -391.151367) (xy 143.371218 -391.165473) (xy 143.422547 -391.187285)
			(xy 143.470153 -391.216339) (xy 143.513021 -391.252014) (xy 143.550238 -391.293551) (xy 143.581011 -391.340064)
			(xy 143.604683 -391.390561) (xy 143.620751 -391.443968) (xy 143.628871 -391.499144) (xy 143.629055 -391.50925)
			(xy 145.03476 -391.50925) (xy 145.038831 -391.453628) (xy 145.050957 -391.399191) (xy 145.07088 -391.3471)
			(xy 145.098176 -391.298465) (xy 145.132262 -391.254322) (xy 145.172411 -391.215613) (xy 145.217769 -391.183162)
			(xy 145.267369 -391.157661) (xy 145.320153 -391.139654) (xy 145.374996 -391.129524) (xy 145.43073 -391.127487)
			(xy 145.486167 -391.133587) (xy 145.540124 -391.147693) (xy 145.591453 -391.169505) (xy 145.639059 -391.198559)
			(xy 145.681927 -391.234234) (xy 145.719144 -391.275771) (xy 145.749917 -391.322284) (xy 145.773589 -391.372781)
			(xy 145.789657 -391.426188) (xy 145.797777 -391.481364) (xy 145.798286 -391.50925) (xy 145.797777 -391.537136)
			(xy 145.793209 -391.568178) (xy 147.905468 -391.568178) (xy 147.909539 -391.512556) (xy 147.921665 -391.458119)
			(xy 147.941588 -391.406028) (xy 147.968884 -391.357393) (xy 148.00297 -391.31325) (xy 148.043119 -391.274541)
			(xy 148.088477 -391.24209) (xy 148.138077 -391.216589) (xy 148.190861 -391.198582) (xy 148.245704 -391.188452)
			(xy 148.301438 -391.186415) (xy 148.356875 -391.192515) (xy 148.410832 -391.206621) (xy 148.462161 -391.228433)
			(xy 148.509767 -391.257487) (xy 148.552635 -391.293162) (xy 148.589852 -391.334699) (xy 148.620625 -391.381212)
			(xy 148.644297 -391.431709) (xy 148.660365 -391.485116) (xy 148.668485 -391.540292) (xy 148.668994 -391.568178)
			(xy 148.668485 -391.596064) (xy 148.660365 -391.65124) (xy 148.644297 -391.704647) (xy 148.620625 -391.755144)
			(xy 148.609885 -391.771378) (xy 149.937468 -391.771378) (xy 149.941539 -391.715756) (xy 149.953665 -391.661319)
			(xy 149.973588 -391.609228) (xy 150.000884 -391.560593) (xy 150.03497 -391.51645) (xy 150.075119 -391.477741)
			(xy 150.120477 -391.44529) (xy 150.170077 -391.419789) (xy 150.222861 -391.401782) (xy 150.277704 -391.391652)
			(xy 150.333438 -391.389615) (xy 150.388875 -391.395715) (xy 150.442832 -391.409821) (xy 150.494161 -391.431633)
			(xy 150.541767 -391.460687) (xy 150.584635 -391.496362) (xy 150.621852 -391.537899) (xy 150.652625 -391.584412)
			(xy 150.676297 -391.634909) (xy 150.692365 -391.688316) (xy 150.700485 -391.743492) (xy 150.700994 -391.771378)
			(xy 150.700485 -391.799264) (xy 150.692365 -391.85444) (xy 150.676297 -391.907847) (xy 150.652625 -391.958344)
			(xy 150.621852 -392.004857) (xy 150.584635 -392.046394) (xy 150.541767 -392.082069) (xy 150.494161 -392.111123)
			(xy 150.442832 -392.132935) (xy 150.388875 -392.147041) (xy 150.333438 -392.153141) (xy 150.277704 -392.151104)
			(xy 150.222861 -392.140974) (xy 150.170077 -392.122967) (xy 150.120477 -392.097466) (xy 150.075119 -392.065015)
			(xy 150.03497 -392.026306) (xy 150.000884 -391.982163) (xy 149.973588 -391.933528) (xy 149.953665 -391.881437)
			(xy 149.941539 -391.827) (xy 149.937468 -391.771378) (xy 148.609885 -391.771378) (xy 148.589852 -391.801657)
			(xy 148.552635 -391.843194) (xy 148.509767 -391.878869) (xy 148.462161 -391.907923) (xy 148.410832 -391.929735)
			(xy 148.356875 -391.943841) (xy 148.301438 -391.949941) (xy 148.245704 -391.947904) (xy 148.190861 -391.937774)
			(xy 148.138077 -391.919767) (xy 148.088477 -391.894266) (xy 148.043119 -391.861815) (xy 148.00297 -391.823106)
			(xy 147.968884 -391.778963) (xy 147.941588 -391.730328) (xy 147.921665 -391.678237) (xy 147.909539 -391.6238)
			(xy 147.905468 -391.568178) (xy 145.793209 -391.568178) (xy 145.789657 -391.592312) (xy 145.773589 -391.645719)
			(xy 145.749917 -391.696216) (xy 145.719144 -391.742729) (xy 145.681927 -391.784266) (xy 145.639059 -391.819941)
			(xy 145.591453 -391.848995) (xy 145.540124 -391.870807) (xy 145.486167 -391.884913) (xy 145.43073 -391.891013)
			(xy 145.374996 -391.888976) (xy 145.320153 -391.878846) (xy 145.267369 -391.860839) (xy 145.217769 -391.835338)
			(xy 145.172411 -391.802887) (xy 145.132262 -391.764178) (xy 145.098176 -391.720035) (xy 145.07088 -391.6714)
			(xy 145.050957 -391.619309) (xy 145.038831 -391.564872) (xy 145.03476 -391.50925) (xy 143.629055 -391.50925)
			(xy 143.62938 -391.52703) (xy 143.628871 -391.554916) (xy 143.620751 -391.610092) (xy 143.604683 -391.663499)
			(xy 143.581011 -391.713996) (xy 143.550238 -391.760509) (xy 143.513021 -391.802046) (xy 143.470153 -391.837721)
			(xy 143.422547 -391.866775) (xy 143.371218 -391.888587) (xy 143.317261 -391.902693) (xy 143.261824 -391.908793)
			(xy 143.20609 -391.906756) (xy 143.151247 -391.896626) (xy 143.098463 -391.878619) (xy 143.048863 -391.853118)
			(xy 143.003505 -391.820667) (xy 142.963356 -391.781958) (xy 142.92927 -391.737815) (xy 142.901974 -391.68918)
			(xy 142.882051 -391.637089) (xy 142.869925 -391.582652) (xy 142.865854 -391.52703) (xy 108.741561 -391.52703)
			(xy 108.754933 -391.571476) (xy 108.763053 -391.626652) (xy 108.763562 -391.654538) (xy 108.763053 -391.682424)
			(xy 108.754933 -391.7376) (xy 108.738865 -391.791007) (xy 108.715193 -391.841504) (xy 108.68442 -391.888017)
			(xy 108.647203 -391.929554) (xy 108.604335 -391.965229) (xy 108.556729 -391.994283) (xy 108.5054 -392.016095)
			(xy 108.466005 -392.026394) (xy 141.244318 -392.026394) (xy 141.248389 -391.970772) (xy 141.260515 -391.916335)
			(xy 141.280438 -391.864244) (xy 141.307734 -391.815609) (xy 141.34182 -391.771466) (xy 141.381969 -391.732757)
			(xy 141.427327 -391.700306) (xy 141.476927 -391.674805) (xy 141.529711 -391.656798) (xy 141.584554 -391.646668)
			(xy 141.640288 -391.644631) (xy 141.695725 -391.650731) (xy 141.749682 -391.664837) (xy 141.801011 -391.686649)
			(xy 141.848617 -391.715703) (xy 141.891485 -391.751378) (xy 141.928702 -391.792915) (xy 141.959475 -391.839428)
			(xy 141.983147 -391.889925) (xy 141.999215 -391.943332) (xy 142.007335 -391.998508) (xy 142.007844 -392.026394)
			(xy 142.007335 -392.05428) (xy 141.999215 -392.109456) (xy 141.983147 -392.162863) (xy 141.975441 -392.179302)
			(xy 146.321016 -392.179302) (xy 146.325087 -392.12368) (xy 146.337213 -392.069243) (xy 146.357136 -392.017152)
			(xy 146.384432 -391.968517) (xy 146.418518 -391.924374) (xy 146.458667 -391.885665) (xy 146.504025 -391.853214)
			(xy 146.553625 -391.827713) (xy 146.606409 -391.809706) (xy 146.661252 -391.799576) (xy 146.716986 -391.797539)
			(xy 146.772423 -391.803639) (xy 146.82638 -391.817745) (xy 146.877709 -391.839557) (xy 146.925315 -391.868611)
			(xy 146.968183 -391.904286) (xy 147.0054 -391.945823) (xy 147.036173 -391.992336) (xy 147.059845 -392.042833)
			(xy 147.075913 -392.09624) (xy 147.084033 -392.151416) (xy 147.084542 -392.179302) (xy 147.084033 -392.207188)
			(xy 147.075913 -392.262364) (xy 147.059845 -392.315771) (xy 147.036173 -392.366268) (xy 147.0054 -392.412781)
			(xy 146.968183 -392.454318) (xy 146.925315 -392.489993) (xy 146.877709 -392.519047) (xy 146.82638 -392.540859)
			(xy 146.772423 -392.554965) (xy 146.716986 -392.561065) (xy 146.661252 -392.559028) (xy 146.606409 -392.548898)
			(xy 146.553625 -392.530891) (xy 146.504025 -392.50539) (xy 146.458667 -392.472939) (xy 146.418518 -392.43423)
			(xy 146.384432 -392.390087) (xy 146.357136 -392.341452) (xy 146.337213 -392.289361) (xy 146.325087 -392.234924)
			(xy 146.321016 -392.179302) (xy 141.975441 -392.179302) (xy 141.959475 -392.21336) (xy 141.928702 -392.259873)
			(xy 141.891485 -392.30141) (xy 141.848617 -392.337085) (xy 141.801011 -392.366139) (xy 141.749682 -392.387951)
			(xy 141.695725 -392.402057) (xy 141.640288 -392.408157) (xy 141.584554 -392.40612) (xy 141.529711 -392.39599)
			(xy 141.476927 -392.377983) (xy 141.427327 -392.352482) (xy 141.381969 -392.320031) (xy 141.34182 -392.281322)
			(xy 141.307734 -392.237179) (xy 141.280438 -392.188544) (xy 141.260515 -392.136453) (xy 141.248389 -392.082016)
			(xy 141.244318 -392.026394) (xy 108.466005 -392.026394) (xy 108.451443 -392.030201) (xy 108.396006 -392.036301)
			(xy 108.340272 -392.034264) (xy 108.285429 -392.024134) (xy 108.232645 -392.006127) (xy 108.183045 -391.980626)
			(xy 108.137687 -391.948175) (xy 108.097538 -391.909466) (xy 108.063452 -391.865323) (xy 108.036156 -391.816688)
			(xy 108.016233 -391.764597) (xy 108.004107 -391.71016) (xy 108.000036 -391.654538) (xy 99.628565 -391.654538)
			(xy 99.625306 -391.655923) (xy 99.571349 -391.670029) (xy 99.515912 -391.676129) (xy 99.460178 -391.674092)
			(xy 99.405335 -391.663962) (xy 99.352551 -391.645955) (xy 99.302951 -391.620454) (xy 99.257593 -391.588003)
			(xy 99.217444 -391.549294) (xy 99.183358 -391.505151) (xy 99.156062 -391.456516) (xy 99.136139 -391.404425)
			(xy 99.124013 -391.349988) (xy 99.119942 -391.294366) (xy 88.188968 -391.294366) (xy 90.394536 -391.809478)
			(xy 90.425583 -391.817002) (xy 90.486719 -391.835557) (xy 90.51671 -391.846562) (xy 91.649042 -392.270996)
			(xy 91.688404 -392.286232) (xy 91.764623 -392.322509) (xy 91.83747 -392.365154) (xy 91.857353 -392.3792)
			(xy 96.620582 -392.3792) (xy 96.624653 -392.323578) (xy 96.636779 -392.269141) (xy 96.656702 -392.21705)
			(xy 96.683998 -392.168415) (xy 96.718084 -392.124272) (xy 96.758233 -392.085563) (xy 96.803591 -392.053112)
			(xy 96.853191 -392.027611) (xy 96.905975 -392.009604) (xy 96.960818 -391.999474) (xy 97.016552 -391.997437)
			(xy 97.071989 -392.003537) (xy 97.125946 -392.017643) (xy 97.177275 -392.039455) (xy 97.224881 -392.068509)
			(xy 97.267749 -392.104184) (xy 97.304966 -392.145721) (xy 97.335739 -392.192234) (xy 97.359411 -392.242731)
			(xy 97.375479 -392.296138) (xy 97.383599 -392.351314) (xy 97.384108 -392.3792) (xy 97.383599 -392.407086)
			(xy 97.375479 -392.462262) (xy 97.359411 -392.515669) (xy 97.335739 -392.566166) (xy 97.320125 -392.589766)
			(xy 99.119942 -392.589766) (xy 99.124013 -392.534144) (xy 99.136139 -392.479707) (xy 99.156062 -392.427616)
			(xy 99.183358 -392.378981) (xy 99.217444 -392.334838) (xy 99.257593 -392.296129) (xy 99.302951 -392.263678)
			(xy 99.352551 -392.238177) (xy 99.405335 -392.22017) (xy 99.460178 -392.21004) (xy 99.515912 -392.208003)
			(xy 99.571349 -392.214103) (xy 99.625306 -392.228209) (xy 99.676635 -392.250021) (xy 99.724241 -392.279075)
			(xy 99.767109 -392.31475) (xy 99.785029 -392.33475) (xy 106.667298 -392.33475) (xy 106.671369 -392.279128)
			(xy 106.683495 -392.224691) (xy 106.703418 -392.1726) (xy 106.730714 -392.123965) (xy 106.7648 -392.079822)
			(xy 106.804949 -392.041113) (xy 106.850307 -392.008662) (xy 106.899907 -391.983161) (xy 106.952691 -391.965154)
			(xy 107.007534 -391.955024) (xy 107.063268 -391.952987) (xy 107.118705 -391.959087) (xy 107.172662 -391.973193)
			(xy 107.223991 -391.995005) (xy 107.271597 -392.024059) (xy 107.314465 -392.059734) (xy 107.351682 -392.101271)
			(xy 107.382455 -392.147784) (xy 107.406127 -392.198281) (xy 107.422195 -392.251688) (xy 107.430315 -392.306864)
			(xy 107.430824 -392.33475) (xy 107.430315 -392.362636) (xy 107.422195 -392.417812) (xy 107.406127 -392.471219)
			(xy 107.382455 -392.521716) (xy 107.351682 -392.568229) (xy 107.314465 -392.609766) (xy 107.271597 -392.645441)
			(xy 107.26918 -392.646916) (xy 148.921468 -392.646916) (xy 148.925539 -392.591294) (xy 148.937665 -392.536857)
			(xy 148.957588 -392.484766) (xy 148.984884 -392.436131) (xy 149.01897 -392.391988) (xy 149.059119 -392.353279)
			(xy 149.104477 -392.320828) (xy 149.154077 -392.295327) (xy 149.206861 -392.27732) (xy 149.261704 -392.26719)
			(xy 149.317438 -392.265153) (xy 149.372875 -392.271253) (xy 149.426832 -392.285359) (xy 149.478161 -392.307171)
			(xy 149.525767 -392.336225) (xy 149.568635 -392.3719) (xy 149.605852 -392.413437) (xy 149.636625 -392.45995)
			(xy 149.660297 -392.510447) (xy 149.676365 -392.563854) (xy 149.684485 -392.61903) (xy 149.684994 -392.646916)
			(xy 149.684485 -392.674802) (xy 149.676365 -392.729978) (xy 149.660297 -392.783385) (xy 149.636625 -392.833882)
			(xy 149.605852 -392.880395) (xy 149.568635 -392.921932) (xy 149.525767 -392.957607) (xy 149.478161 -392.986661)
			(xy 149.426832 -393.008473) (xy 149.372875 -393.022579) (xy 149.317438 -393.028679) (xy 149.261704 -393.026642)
			(xy 149.206861 -393.016512) (xy 149.154077 -392.998505) (xy 149.104477 -392.973004) (xy 149.059119 -392.940553)
			(xy 149.01897 -392.901844) (xy 148.984884 -392.857701) (xy 148.957588 -392.809066) (xy 148.937665 -392.756975)
			(xy 148.925539 -392.702538) (xy 148.921468 -392.646916) (xy 107.26918 -392.646916) (xy 107.223991 -392.674495)
			(xy 107.172662 -392.696307) (xy 107.118705 -392.710413) (xy 107.063268 -392.716513) (xy 107.007534 -392.714476)
			(xy 106.952691 -392.704346) (xy 106.899907 -392.686339) (xy 106.850307 -392.660838) (xy 106.804949 -392.628387)
			(xy 106.7648 -392.589678) (xy 106.730714 -392.545535) (xy 106.703418 -392.4969) (xy 106.683495 -392.444809)
			(xy 106.671369 -392.390372) (xy 106.667298 -392.33475) (xy 99.785029 -392.33475) (xy 99.804326 -392.356287)
			(xy 99.835099 -392.4028) (xy 99.858771 -392.453297) (xy 99.874839 -392.506704) (xy 99.882959 -392.56188)
			(xy 99.883468 -392.589766) (xy 99.882959 -392.617652) (xy 99.874839 -392.672828) (xy 99.858771 -392.726235)
			(xy 99.835099 -392.776732) (xy 99.804326 -392.823245) (xy 99.767109 -392.864782) (xy 99.724241 -392.900457)
			(xy 99.676635 -392.929511) (xy 99.625306 -392.951323) (xy 99.571349 -392.965429) (xy 99.515912 -392.971529)
			(xy 99.460178 -392.969492) (xy 99.405335 -392.959362) (xy 99.352551 -392.941355) (xy 99.302951 -392.915854)
			(xy 99.257593 -392.883403) (xy 99.217444 -392.844694) (xy 99.183358 -392.800551) (xy 99.156062 -392.751916)
			(xy 99.136139 -392.699825) (xy 99.124013 -392.645388) (xy 99.119942 -392.589766) (xy 97.320125 -392.589766)
			(xy 97.304966 -392.612679) (xy 97.267749 -392.654216) (xy 97.224881 -392.689891) (xy 97.177275 -392.718945)
			(xy 97.125946 -392.740757) (xy 97.071989 -392.754863) (xy 97.016552 -392.760963) (xy 96.960818 -392.758926)
			(xy 96.905975 -392.748796) (xy 96.853191 -392.730789) (xy 96.803591 -392.705288) (xy 96.758233 -392.672837)
			(xy 96.718084 -392.634128) (xy 96.683998 -392.589985) (xy 96.656702 -392.54135) (xy 96.636779 -392.489259)
			(xy 96.624653 -392.434822) (xy 96.620582 -392.3792) (xy 91.857353 -392.3792) (xy 91.906413 -392.413858)
			(xy 91.970951 -392.468265) (xy 92.001086 -392.497818) (xy 93.388194 -393.885166) (xy 99.119942 -393.885166)
			(xy 99.124013 -393.829544) (xy 99.136139 -393.775107) (xy 99.156062 -393.723016) (xy 99.183358 -393.674381)
			(xy 99.217444 -393.630238) (xy 99.257593 -393.591529) (xy 99.302951 -393.559078) (xy 99.352551 -393.533577)
			(xy 99.405335 -393.51557) (xy 99.460178 -393.50544) (xy 99.515912 -393.503403) (xy 99.571349 -393.509503)
			(xy 99.625306 -393.523609) (xy 99.676635 -393.545421) (xy 99.724241 -393.574475) (xy 99.767109 -393.61015)
			(xy 99.804326 -393.651687) (xy 99.835099 -393.6982) (xy 99.858771 -393.748697) (xy 99.874839 -393.802104)
			(xy 99.882959 -393.85728) (xy 99.883468 -393.885166) (xy 99.882959 -393.913052) (xy 99.874839 -393.968228)
			(xy 99.858771 -394.021635) (xy 99.835099 -394.072132) (xy 99.804326 -394.118645) (xy 99.767109 -394.160182)
			(xy 99.724241 -394.195857) (xy 99.676635 -394.224911) (xy 99.625306 -394.246723) (xy 99.571349 -394.260829)
			(xy 99.515912 -394.266929) (xy 99.460178 -394.264892) (xy 99.405335 -394.254762) (xy 99.352551 -394.236755)
			(xy 99.302951 -394.211254) (xy 99.257593 -394.178803) (xy 99.217444 -394.140094) (xy 99.183358 -394.095951)
			(xy 99.156062 -394.047316) (xy 99.136139 -393.995225) (xy 99.124013 -393.940788) (xy 99.119942 -393.885166)
			(xy 93.388194 -393.885166) (xy 93.468698 -393.965684) (xy 93.502572 -394.000408) (xy 93.564108 -394.075408)
			(xy 93.617998 -394.156077) (xy 93.663723 -394.241639) (xy 93.68282 -394.286232) (xy 93.69986 -394.32738)
			(xy 105.828336 -394.32738) (xy 105.832407 -394.271758) (xy 105.844533 -394.217321) (xy 105.864456 -394.16523)
			(xy 105.891752 -394.116595) (xy 105.925838 -394.072452) (xy 105.965987 -394.033743) (xy 106.011345 -394.001292)
			(xy 106.060945 -393.975791) (xy 106.113729 -393.957784) (xy 106.168572 -393.947654) (xy 106.224306 -393.945617)
			(xy 106.279743 -393.951717) (xy 106.3337 -393.965823) (xy 106.385029 -393.987635) (xy 106.432635 -394.016689)
			(xy 106.475503 -394.052364) (xy 106.51272 -394.093901) (xy 106.543493 -394.140414) (xy 106.567165 -394.190911)
			(xy 106.583233 -394.244318) (xy 106.591353 -394.299494) (xy 106.591862 -394.32738) (xy 106.591353 -394.355266)
			(xy 106.583233 -394.410442) (xy 106.567165 -394.463849) (xy 106.543493 -394.514346) (xy 106.51272 -394.560859)
			(xy 106.475503 -394.602396) (xy 106.432635 -394.638071) (xy 106.385029 -394.667125) (xy 106.3337 -394.688937)
			(xy 106.279743 -394.703043) (xy 106.224306 -394.709143) (xy 106.168572 -394.707106) (xy 106.113729 -394.696976)
			(xy 106.060945 -394.678969) (xy 106.011345 -394.653468) (xy 105.965987 -394.621017) (xy 105.925838 -394.582308)
			(xy 105.891752 -394.538165) (xy 105.864456 -394.48953) (xy 105.844533 -394.437439) (xy 105.832407 -394.383002)
			(xy 105.828336 -394.32738) (xy 93.69986 -394.32738) (xy 94.053173 -395.180566) (xy 99.119942 -395.180566)
			(xy 99.124013 -395.124944) (xy 99.136139 -395.070507) (xy 99.156062 -395.018416) (xy 99.183358 -394.969781)
			(xy 99.217444 -394.925638) (xy 99.257593 -394.886929) (xy 99.302951 -394.854478) (xy 99.352551 -394.828977)
			(xy 99.405335 -394.81097) (xy 99.460178 -394.80084) (xy 99.515912 -394.798803) (xy 99.571349 -394.804903)
			(xy 99.625306 -394.819009) (xy 99.676635 -394.840821) (xy 99.724241 -394.869875) (xy 99.767109 -394.90555)
			(xy 99.804326 -394.947087) (xy 99.835099 -394.9936) (xy 99.858771 -395.044097) (xy 99.874839 -395.097504)
			(xy 99.882959 -395.15268) (xy 99.883468 -395.180566) (xy 99.883347 -395.18717) (xy 101.058724 -395.18717)
			(xy 101.062795 -395.131548) (xy 101.074921 -395.077111) (xy 101.094844 -395.02502) (xy 101.12214 -394.976385)
			(xy 101.156226 -394.932242) (xy 101.196375 -394.893533) (xy 101.241733 -394.861082) (xy 101.291333 -394.835581)
			(xy 101.344117 -394.817574) (xy 101.39896 -394.807444) (xy 101.454694 -394.805407) (xy 101.510131 -394.811507)
			(xy 101.564088 -394.825613) (xy 101.615417 -394.847425) (xy 101.663023 -394.876479) (xy 101.705891 -394.912154)
			(xy 101.743108 -394.953691) (xy 101.773881 -395.000204) (xy 101.797553 -395.050701) (xy 101.813621 -395.104108)
			(xy 101.821741 -395.159284) (xy 101.82225 -395.18717) (xy 101.821741 -395.215056) (xy 101.813621 -395.270232)
			(xy 101.797553 -395.323639) (xy 101.773881 -395.374136) (xy 101.743108 -395.420649) (xy 101.705891 -395.462186)
			(xy 101.663023 -395.497861) (xy 101.615417 -395.526915) (xy 101.564088 -395.548727) (xy 101.510131 -395.562833)
			(xy 101.454694 -395.568933) (xy 101.39896 -395.566896) (xy 101.344117 -395.556766) (xy 101.291333 -395.538759)
			(xy 101.241733 -395.513258) (xy 101.196375 -395.480807) (xy 101.156226 -395.442098) (xy 101.12214 -395.397955)
			(xy 101.094844 -395.34932) (xy 101.074921 -395.297229) (xy 101.062795 -395.242792) (xy 101.058724 -395.18717)
			(xy 99.883347 -395.18717) (xy 99.882959 -395.208452) (xy 99.874839 -395.263628) (xy 99.858771 -395.317035)
			(xy 99.835099 -395.367532) (xy 99.804326 -395.414045) (xy 99.767109 -395.455582) (xy 99.724241 -395.491257)
			(xy 99.676635 -395.520311) (xy 99.625306 -395.542123) (xy 99.571349 -395.556229) (xy 99.515912 -395.562329)
			(xy 99.460178 -395.560292) (xy 99.405335 -395.550162) (xy 99.352551 -395.532155) (xy 99.302951 -395.506654)
			(xy 99.257593 -395.474203) (xy 99.217444 -395.435494) (xy 99.183358 -395.391351) (xy 99.156062 -395.342716)
			(xy 99.136139 -395.290625) (xy 99.124013 -395.236188) (xy 99.119942 -395.180566) (xy 94.053173 -395.180566)
			(xy 94.06001 -395.197076) (xy 94.074639 -395.233407) (xy 94.098795 -395.307917) (xy 94.10827 -395.34592)
			(xy 94.116892 -395.383534) (xy 94.128953 -395.45976) (xy 94.135039 -395.536695) (xy 94.135448 -395.575282)
			(xy 94.135448 -396.1638) (xy 96.6503 -396.1638) (xy 96.654371 -396.108178) (xy 96.666497 -396.053741)
			(xy 96.68642 -396.00165) (xy 96.713716 -395.953015) (xy 96.747802 -395.908872) (xy 96.787951 -395.870163)
			(xy 96.833309 -395.837712) (xy 96.882909 -395.812211) (xy 96.935693 -395.794204) (xy 96.990536 -395.784074)
			(xy 97.04627 -395.782037) (xy 97.101707 -395.788137) (xy 97.155664 -395.802243) (xy 97.206993 -395.824055)
			(xy 97.254599 -395.853109) (xy 97.297467 -395.888784) (xy 97.334684 -395.930321) (xy 97.365457 -395.976834)
			(xy 97.389129 -396.027331) (xy 97.405197 -396.080738) (xy 97.413317 -396.135914) (xy 97.413826 -396.1638)
			(xy 97.413317 -396.191686) (xy 97.405197 -396.246862) (xy 97.389129 -396.300269) (xy 97.365457 -396.350766)
			(xy 97.334684 -396.397279) (xy 97.297467 -396.438816) (xy 97.254599 -396.474491) (xy 97.212644 -396.500096)
			(xy 100.023166 -396.500096) (xy 100.027237 -396.444474) (xy 100.039363 -396.390037) (xy 100.059286 -396.337946)
			(xy 100.086582 -396.289311) (xy 100.120668 -396.245168) (xy 100.160817 -396.206459) (xy 100.206175 -396.174008)
			(xy 100.255775 -396.148507) (xy 100.308559 -396.1305) (xy 100.363402 -396.12037) (xy 100.419136 -396.118333)
			(xy 100.474573 -396.124433) (xy 100.52853 -396.138539) (xy 100.579859 -396.160351) (xy 100.627465 -396.189405)
			(xy 100.670333 -396.22508) (xy 100.70755 -396.266617) (xy 100.738323 -396.31313) (xy 100.761995 -396.363627)
			(xy 100.778063 -396.417034) (xy 100.786183 -396.47221) (xy 100.786692 -396.500096) (xy 101.318566 -396.500096)
			(xy 101.322637 -396.444474) (xy 101.334763 -396.390037) (xy 101.354686 -396.337946) (xy 101.381982 -396.289311)
			(xy 101.416068 -396.245168) (xy 101.456217 -396.206459) (xy 101.501575 -396.174008) (xy 101.551175 -396.148507)
			(xy 101.603959 -396.1305) (xy 101.658802 -396.12037) (xy 101.714536 -396.118333) (xy 101.769973 -396.124433)
			(xy 101.82393 -396.138539) (xy 101.875259 -396.160351) (xy 101.922865 -396.189405) (xy 101.965733 -396.22508)
			(xy 102.00295 -396.266617) (xy 102.033723 -396.31313) (xy 102.057395 -396.363627) (xy 102.073463 -396.417034)
			(xy 102.081583 -396.47221) (xy 102.082092 -396.500096) (xy 102.613966 -396.500096) (xy 102.618037 -396.444474)
			(xy 102.630163 -396.390037) (xy 102.650086 -396.337946) (xy 102.677382 -396.289311) (xy 102.711468 -396.245168)
			(xy 102.751617 -396.206459) (xy 102.796975 -396.174008) (xy 102.846575 -396.148507) (xy 102.899359 -396.1305)
			(xy 102.954202 -396.12037) (xy 103.009936 -396.118333) (xy 103.065373 -396.124433) (xy 103.11933 -396.138539)
			(xy 103.170659 -396.160351) (xy 103.218265 -396.189405) (xy 103.261133 -396.22508) (xy 103.29835 -396.266617)
			(xy 103.329123 -396.31313) (xy 103.352795 -396.363627) (xy 103.368863 -396.417034) (xy 103.376983 -396.47221)
			(xy 103.377492 -396.500096) (xy 103.909366 -396.500096) (xy 103.913437 -396.444474) (xy 103.925563 -396.390037)
			(xy 103.945486 -396.337946) (xy 103.972782 -396.289311) (xy 104.006868 -396.245168) (xy 104.047017 -396.206459)
			(xy 104.092375 -396.174008) (xy 104.141975 -396.148507) (xy 104.194759 -396.1305) (xy 104.249602 -396.12037)
			(xy 104.305336 -396.118333) (xy 104.360773 -396.124433) (xy 104.41473 -396.138539) (xy 104.466059 -396.160351)
			(xy 104.513665 -396.189405) (xy 104.556533 -396.22508) (xy 104.59375 -396.266617) (xy 104.624523 -396.31313)
			(xy 104.648195 -396.363627) (xy 104.664263 -396.417034) (xy 104.672383 -396.47221) (xy 104.672892 -396.500096)
			(xy 104.672383 -396.527982) (xy 104.664263 -396.583158) (xy 104.648195 -396.636565) (xy 104.624523 -396.687062)
			(xy 104.59375 -396.733575) (xy 104.556533 -396.775112) (xy 104.513665 -396.810787) (xy 104.466059 -396.839841)
			(xy 104.41473 -396.861653) (xy 104.360773 -396.875759) (xy 104.305336 -396.881859) (xy 104.249602 -396.879822)
			(xy 104.194759 -396.869692) (xy 104.141975 -396.851685) (xy 104.092375 -396.826184) (xy 104.047017 -396.793733)
			(xy 104.006868 -396.755024) (xy 103.972782 -396.710881) (xy 103.945486 -396.662246) (xy 103.925563 -396.610155)
			(xy 103.913437 -396.555718) (xy 103.909366 -396.500096) (xy 103.377492 -396.500096) (xy 103.376983 -396.527982)
			(xy 103.368863 -396.583158) (xy 103.352795 -396.636565) (xy 103.329123 -396.687062) (xy 103.29835 -396.733575)
			(xy 103.261133 -396.775112) (xy 103.218265 -396.810787) (xy 103.170659 -396.839841) (xy 103.11933 -396.861653)
			(xy 103.065373 -396.875759) (xy 103.009936 -396.881859) (xy 102.954202 -396.879822) (xy 102.899359 -396.869692)
			(xy 102.846575 -396.851685) (xy 102.796975 -396.826184) (xy 102.751617 -396.793733) (xy 102.711468 -396.755024)
			(xy 102.677382 -396.710881) (xy 102.650086 -396.662246) (xy 102.630163 -396.610155) (xy 102.618037 -396.555718)
			(xy 102.613966 -396.500096) (xy 102.082092 -396.500096) (xy 102.081583 -396.527982) (xy 102.073463 -396.583158)
			(xy 102.057395 -396.636565) (xy 102.033723 -396.687062) (xy 102.00295 -396.733575) (xy 101.965733 -396.775112)
			(xy 101.922865 -396.810787) (xy 101.875259 -396.839841) (xy 101.82393 -396.861653) (xy 101.769973 -396.875759)
			(xy 101.714536 -396.881859) (xy 101.658802 -396.879822) (xy 101.603959 -396.869692) (xy 101.551175 -396.851685)
			(xy 101.501575 -396.826184) (xy 101.456217 -396.793733) (xy 101.416068 -396.755024) (xy 101.381982 -396.710881)
			(xy 101.354686 -396.662246) (xy 101.334763 -396.610155) (xy 101.322637 -396.555718) (xy 101.318566 -396.500096)
			(xy 100.786692 -396.500096) (xy 100.786183 -396.527982) (xy 100.778063 -396.583158) (xy 100.761995 -396.636565)
			(xy 100.738323 -396.687062) (xy 100.70755 -396.733575) (xy 100.670333 -396.775112) (xy 100.627465 -396.810787)
			(xy 100.579859 -396.839841) (xy 100.52853 -396.861653) (xy 100.474573 -396.875759) (xy 100.419136 -396.881859)
			(xy 100.363402 -396.879822) (xy 100.308559 -396.869692) (xy 100.255775 -396.851685) (xy 100.206175 -396.826184)
			(xy 100.160817 -396.793733) (xy 100.120668 -396.755024) (xy 100.086582 -396.710881) (xy 100.059286 -396.662246)
			(xy 100.039363 -396.610155) (xy 100.027237 -396.555718) (xy 100.023166 -396.500096) (xy 97.212644 -396.500096)
			(xy 97.206993 -396.503545) (xy 97.155664 -396.525357) (xy 97.101707 -396.539463) (xy 97.04627 -396.545563)
			(xy 96.990536 -396.543526) (xy 96.935693 -396.533396) (xy 96.882909 -396.515389) (xy 96.833309 -396.489888)
			(xy 96.787951 -396.457437) (xy 96.747802 -396.418728) (xy 96.713716 -396.374585) (xy 96.68642 -396.32595)
			(xy 96.666497 -396.273859) (xy 96.654371 -396.219422) (xy 96.6503 -396.1638) (xy 94.135448 -396.1638)
			(xy 94.135448 -397.822891) (xy 115.424962 -397.822891) (xy 115.424967 -397.757444) (xy 115.433765 -397.692592)
			(xy 115.451199 -397.629511) (xy 115.47695 -397.569344) (xy 115.493292 -397.540988) (xy 115.49661 -397.534965)
			(xy 115.500214 -397.5217) (xy 115.500404 -397.514826) (xy 115.500404 -396.765526) (xy 115.500202 -396.758654)
			(xy 115.496601 -396.745391) (xy 115.493292 -396.739364) (xy 115.476944 -396.711013) (xy 115.451199 -396.650846)
			(xy 115.433771 -396.587765) (xy 115.424978 -396.522914) (xy 115.424979 -396.457469) (xy 115.433775 -396.392619)
			(xy 115.451204 -396.329538) (xy 115.476952 -396.269372) (xy 115.493292 -396.241016) (xy 115.4966 -396.234988)
			(xy 115.50021 -396.221727) (xy 115.500404 -396.214854) (xy 115.500404 -395.92885) (xy 115.500904 -395.918686)
			(xy 115.508666 -395.899899) (xy 115.523028 -395.885513) (xy 115.541803 -395.87772) (xy 115.551966 -395.877288)
			(xy 116.268246 -395.877288) (xy 116.278427 -395.877627) (xy 116.297232 -395.885437) (xy 116.311617 -395.899849)
			(xy 116.319392 -395.918668) (xy 116.319808 -395.92885) (xy 116.319808 -396.214854) (xy 116.320017 -396.221726)
			(xy 116.323613 -396.234989) (xy 116.32692 -396.241016) (xy 116.34325 -396.269376) (xy 116.368997 -396.329542)
			(xy 116.386426 -396.392621) (xy 116.395221 -396.45747) (xy 116.395222 -396.522913) (xy 116.386429 -396.587762)
			(xy 116.369003 -396.650842) (xy 116.343258 -396.711008) (xy 116.32692 -396.739364) (xy 116.323619 -396.745396)
			(xy 116.320004 -396.758654) (xy 116.319808 -396.765526) (xy 116.319808 -397.514826) (xy 116.319989 -397.5217)
			(xy 116.323604 -397.534963) (xy 116.32692 -397.540988) (xy 116.336287 -397.557287) (xy 117.624883 -397.557287)
			(xy 117.633676 -397.492438) (xy 117.651103 -397.429358) (xy 117.676848 -397.369192) (xy 117.693186 -397.340836)
			(xy 117.696533 -397.334812) (xy 117.70028 -397.321559) (xy 117.700552 -397.314674) (xy 117.700552 -397.028924)
			(xy 117.701103 -397.018823) (xy 117.708824 -397.000154) (xy 117.7231 -396.98586) (xy 117.741759 -396.978116)
			(xy 117.75186 -396.977616) (xy 118.46814 -396.977616) (xy 118.478253 -396.978053) (xy 118.496935 -396.985807)
			(xy 118.511229 -397.000118) (xy 118.51896 -397.01881) (xy 118.519448 -397.028924) (xy 118.519448 -397.314674)
			(xy 118.519663 -397.321568) (xy 118.523404 -397.33484) (xy 118.526814 -397.340836) (xy 118.543161 -397.369187)
			(xy 118.568907 -397.429354) (xy 118.586334 -397.492436) (xy 118.595127 -397.557286) (xy 118.595126 -397.622731)
			(xy 118.586331 -397.687581) (xy 118.568901 -397.750662) (xy 118.543154 -397.810828) (xy 118.536203 -397.82289)
			(xy 119.825012 -397.82289) (xy 119.825017 -397.757445) (xy 119.833814 -397.692593) (xy 119.851246 -397.629512)
			(xy 119.876994 -397.569344) (xy 119.893334 -397.540988) (xy 119.896701 -397.534974) (xy 119.900435 -397.521713)
			(xy 119.9007 -397.514826) (xy 119.9007 -396.765526) (xy 119.900457 -396.758635) (xy 119.896721 -396.74537)
			(xy 119.893334 -396.739364) (xy 119.876988 -396.711012) (xy 119.851245 -396.650845) (xy 119.83382 -396.587764)
			(xy 119.825028 -396.522913) (xy 119.82503 -396.45747) (xy 119.833824 -396.39262) (xy 119.851251 -396.329539)
			(xy 119.876996 -396.269372) (xy 119.893334 -396.241016) (xy 119.896691 -396.234997) (xy 119.900431 -396.22174)
			(xy 119.9007 -396.214854) (xy 119.9007 -395.92885) (xy 119.901266 -395.918731) (xy 119.90897 -395.900019)
			(xy 119.923232 -395.885662) (xy 119.941893 -395.877834) (xy 119.952008 -395.877288) (xy 120.668288 -395.877288)
			(xy 120.67844 -395.877731) (xy 120.69719 -395.885521) (xy 120.711513 -395.899911) (xy 120.719215 -395.918696)
			(xy 120.719596 -395.92885) (xy 120.719596 -396.214854) (xy 120.719848 -396.221744) (xy 120.723577 -396.23501)
			(xy 120.726962 -396.241016) (xy 120.743291 -396.269377) (xy 120.769035 -396.329542) (xy 120.786463 -396.392622)
			(xy 120.795257 -396.45747) (xy 120.795258 -396.522913) (xy 120.786466 -396.587762) (xy 120.769041 -396.650841)
			(xy 120.743299 -396.711008) (xy 120.726962 -396.739364) (xy 120.723612 -396.745386) (xy 120.719867 -396.758641)
			(xy 120.719596 -396.765526) (xy 120.719596 -397.514826) (xy 120.719858 -397.521715) (xy 120.723581 -397.534981)
			(xy 120.726962 -397.540988) (xy 120.736329 -397.557288) (xy 122.024933 -397.557288) (xy 122.033725 -397.492439)
			(xy 122.05115 -397.429359) (xy 122.076892 -397.369192) (xy 122.093228 -397.340836) (xy 122.096532 -397.334806)
			(xy 122.100144 -397.321546) (xy 122.10034 -397.314674) (xy 122.10034 -397.028924) (xy 122.100742 -397.018766)
			(xy 122.108537 -397.000007) (xy 122.122941 -396.985681) (xy 122.141742 -396.977988) (xy 122.151902 -396.977616)
			(xy 122.868182 -396.977616) (xy 122.878305 -396.978141) (xy 122.897021 -396.985858) (xy 122.911377 -397.000132)
			(xy 122.919201 -397.018804) (xy 122.919744 -397.028924) (xy 122.919744 -397.314674) (xy 122.91994 -397.321547)
			(xy 122.923545 -397.33481) (xy 122.926856 -397.340836) (xy 122.943202 -397.369187) (xy 122.968945 -397.429355)
			(xy 122.986371 -397.492436) (xy 122.995163 -397.557287) (xy 122.995162 -397.62273) (xy 122.986368 -397.687581)
			(xy 122.96894 -397.750661) (xy 122.943194 -397.810828) (xy 122.936244 -397.82289) (xy 124.225049 -397.82289)
			(xy 124.225053 -397.757444) (xy 124.233851 -397.692592) (xy 124.251284 -397.629511) (xy 124.277035 -397.569344)
			(xy 124.293376 -397.540988) (xy 124.296693 -397.534965) (xy 124.300298 -397.5217) (xy 124.300488 -397.514826)
			(xy 124.300488 -396.765526) (xy 124.300287 -396.758653) (xy 124.296685 -396.745391) (xy 124.293376 -396.739364)
			(xy 124.277029 -396.711013) (xy 124.251284 -396.650845) (xy 124.233857 -396.587764) (xy 124.225064 -396.522913)
			(xy 124.225066 -396.457469) (xy 124.233861 -396.392619) (xy 124.25129 -396.329538) (xy 124.277037 -396.269372)
			(xy 124.293376 -396.241016) (xy 124.296683 -396.234988) (xy 124.300294 -396.221727) (xy 124.300488 -396.214854)
			(xy 124.300488 -395.92885) (xy 124.300906 -395.918675) (xy 124.308684 -395.899872) (xy 124.323072 -395.885484)
			(xy 124.341875 -395.877706) (xy 124.35205 -395.877288) (xy 125.06833 -395.877288) (xy 125.07851 -395.87764)
			(xy 125.097315 -395.885445) (xy 125.1117 -395.899852) (xy 125.119475 -395.91867) (xy 125.119892 -395.92885)
			(xy 125.119892 -396.214854) (xy 125.120103 -396.221726) (xy 125.123698 -396.234989) (xy 125.127004 -396.241016)
			(xy 125.143332 -396.269377) (xy 125.169074 -396.329543) (xy 125.1865 -396.392622) (xy 125.195293 -396.457471)
			(xy 125.195294 -396.522912) (xy 125.186503 -396.587761) (xy 125.16908 -396.65084) (xy 125.143339 -396.711007)
			(xy 125.127004 -396.739364) (xy 125.123702 -396.745395) (xy 125.120088 -396.758654) (xy 125.119892 -396.765526)
			(xy 125.119892 -397.514826) (xy 125.120075 -397.5217) (xy 125.123689 -397.534963) (xy 125.127004 -397.540988)
			(xy 125.13637 -397.557287) (xy 126.42497 -397.557287) (xy 126.433762 -397.492438) (xy 126.451188 -397.429358)
			(xy 126.476932 -397.369192) (xy 126.49327 -397.340836) (xy 126.496623 -397.334816) (xy 126.500365 -397.321559)
			(xy 126.500636 -397.314674) (xy 126.500636 -397.028924) (xy 126.501036 -397.018799) (xy 126.508783 -397.000089)
			(xy 126.523105 -396.985772) (xy 126.541818 -396.978032) (xy 126.551944 -396.977616) (xy 127.268224 -396.977616)
			(xy 127.278336 -396.978066) (xy 127.297018 -396.985814) (xy 127.311313 -397.000122) (xy 127.319044 -397.018811)
			(xy 127.319532 -397.028924) (xy 127.319532 -397.314674) (xy 127.319771 -397.321565) (xy 127.323509 -397.334831)
			(xy 127.326898 -397.340836) (xy 127.343243 -397.369188) (xy 127.368984 -397.429356) (xy 127.386408 -397.492437)
			(xy 127.395199 -397.557287) (xy 127.395198 -397.62273) (xy 127.386405 -397.68758) (xy 127.368978 -397.75066)
			(xy 127.343235 -397.810827) (xy 127.336285 -397.82289) (xy 128.624838 -397.82289) (xy 128.624843 -397.757444)
			(xy 128.633641 -397.692593) (xy 128.651073 -397.629511) (xy 128.676823 -397.569344) (xy 128.693164 -397.540988)
			(xy 128.69648 -397.534964) (xy 128.700085 -397.5217) (xy 128.700276 -397.514826) (xy 128.700276 -396.765526)
			(xy 128.700077 -396.758653) (xy 128.696474 -396.74539) (xy 128.693164 -396.739364) (xy 128.676817 -396.711013)
			(xy 128.651073 -396.650845) (xy 128.633647 -396.587764) (xy 128.624854 -396.522913) (xy 128.624855 -396.457469)
			(xy 128.63365 -396.392619) (xy 128.651079 -396.329539) (xy 128.676825 -396.269372) (xy 128.693164 -396.241016)
			(xy 128.69647 -396.234987) (xy 128.700082 -396.221727) (xy 128.700276 -396.214854) (xy 128.700276 -395.92885)
			(xy 128.700706 -395.918677) (xy 128.708481 -395.899876) (xy 128.722866 -395.885488) (xy 128.741665 -395.877708)
			(xy 128.751838 -395.877288) (xy 129.468118 -395.877288) (xy 129.478297 -395.87765) (xy 129.497102 -395.885451)
			(xy 129.511487 -395.899856) (xy 129.519263 -395.91867) (xy 129.51968 -395.92885) (xy 129.51968 -396.214854)
			(xy 129.519892 -396.221726) (xy 129.523487 -396.234988) (xy 129.526792 -396.241016) (xy 129.54312 -396.269377)
			(xy 129.568863 -396.329543) (xy 129.586289 -396.392622) (xy 129.595083 -396.45747) (xy 129.595083 -396.49019)
			(xy 133.023872 -396.49019) (xy 133.027863 -396.428023) (xy 133.039772 -396.366876) (xy 133.059401 -396.307755)
			(xy 133.08643 -396.251629) (xy 133.120414 -396.19942) (xy 133.160796 -396.151985) (xy 133.206912 -396.110104)
			(xy 133.258004 -396.074464) (xy 133.313235 -396.04565) (xy 133.371697 -396.024136) (xy 133.432431 -396.010274)
			(xy 133.494438 -396.004292) (xy 133.556701 -396.006288) (xy 133.618198 -396.016231) (xy 133.677919 -396.033955)
			(xy 133.734882 -396.059172) (xy 133.788153 -396.091465) (xy 133.836858 -396.130305) (xy 133.880195 -396.175055)
			(xy 133.917455 -396.224979) (xy 133.948024 -396.279258) (xy 133.971402 -396.337001) (xy 133.987203 -396.397259)
			(xy 133.995169 -396.459042) (xy 133.995668 -396.49019) (xy 133.995169 -396.521338) (xy 133.987203 -396.583121)
			(xy 133.971402 -396.643379) (xy 133.948024 -396.701122) (xy 133.917455 -396.755401) (xy 133.880195 -396.805325)
			(xy 133.836858 -396.850075) (xy 133.788153 -396.888915) (xy 133.734882 -396.921208) (xy 133.677919 -396.946425)
			(xy 133.618198 -396.964149) (xy 133.556701 -396.974092) (xy 133.494438 -396.976088) (xy 133.432431 -396.970106)
			(xy 133.371697 -396.956244) (xy 133.313235 -396.93473) (xy 133.258004 -396.905916) (xy 133.206912 -396.870276)
			(xy 133.160796 -396.828395) (xy 133.120414 -396.78096) (xy 133.08643 -396.728751) (xy 133.059401 -396.672625)
			(xy 133.039772 -396.613504) (xy 133.027863 -396.552357) (xy 133.023872 -396.49019) (xy 129.595083 -396.49019)
			(xy 129.595084 -396.522912) (xy 129.586293 -396.587761) (xy 129.568869 -396.650841) (xy 129.543128 -396.711008)
			(xy 129.526792 -396.739364) (xy 129.523489 -396.745395) (xy 129.519876 -396.758654) (xy 129.51968 -396.765526)
			(xy 129.51968 -397.514826) (xy 129.519865 -397.5217) (xy 129.523478 -397.534962) (xy 129.526792 -397.540988)
			(xy 129.536158 -397.557288) (xy 130.82502 -397.557288) (xy 130.833811 -397.492439) (xy 130.851235 -397.429359)
			(xy 130.876976 -397.369192) (xy 130.893312 -397.340836) (xy 130.896615 -397.334806) (xy 130.900228 -397.321546)
			(xy 130.900424 -397.314674) (xy 130.900424 -397.028924) (xy 130.900842 -397.018768) (xy 130.908634 -397.000012)
			(xy 130.923032 -396.985687) (xy 130.941828 -396.97799) (xy 130.951986 -396.977616) (xy 131.668266 -396.977616)
			(xy 131.678388 -396.978154) (xy 131.697103 -396.985866) (xy 131.71146 -397.000137) (xy 131.719284 -397.018806)
			(xy 131.719828 -397.028924) (xy 131.719828 -397.314674) (xy 131.720026 -397.321547) (xy 131.72363 -397.33481)
			(xy 131.72694 -397.340836) (xy 131.743287 -397.369187) (xy 131.769031 -397.429355) (xy 131.786457 -397.492436)
			(xy 131.795249 -397.557287) (xy 131.795248 -397.622731) (xy 131.786454 -397.687581) (xy 131.769025 -397.750661)
			(xy 131.752122 -397.790162) (xy 133.023872 -397.790162) (xy 133.027863 -397.727995) (xy 133.039772 -397.666848)
			(xy 133.059401 -397.607727) (xy 133.08643 -397.551601) (xy 133.120414 -397.499392) (xy 133.160796 -397.451957)
			(xy 133.206912 -397.410076) (xy 133.258004 -397.374436) (xy 133.313235 -397.345622) (xy 133.371697 -397.324108)
			(xy 133.432431 -397.310246) (xy 133.494438 -397.304264) (xy 133.556701 -397.30626) (xy 133.618198 -397.316203)
			(xy 133.677919 -397.333927) (xy 133.734882 -397.359144) (xy 133.788153 -397.391437) (xy 133.836858 -397.430277)
			(xy 133.880195 -397.475027) (xy 133.917455 -397.524951) (xy 133.948024 -397.57923) (xy 133.952388 -397.59001)
			(xy 135.22402 -397.59001) (xy 135.228011 -397.527843) (xy 135.23992 -397.466696) (xy 135.259549 -397.407575)
			(xy 135.286578 -397.351449) (xy 135.320562 -397.29924) (xy 135.360944 -397.251805) (xy 135.40706 -397.209924)
			(xy 135.458152 -397.174284) (xy 135.513383 -397.14547) (xy 135.571845 -397.123956) (xy 135.632579 -397.110094)
			(xy 135.694586 -397.104112) (xy 135.756849 -397.106108) (xy 135.818346 -397.116051) (xy 135.878067 -397.133775)
			(xy 135.93503 -397.158992) (xy 135.988301 -397.191285) (xy 136.037006 -397.230125) (xy 136.080343 -397.274875)
			(xy 136.117603 -397.324799) (xy 136.148172 -397.379078) (xy 136.17155 -397.436821) (xy 136.187351 -397.497079)
			(xy 136.195317 -397.558862) (xy 136.195816 -397.59001) (xy 136.195317 -397.621158) (xy 136.187351 -397.682941)
			(xy 136.17155 -397.743199) (xy 136.148172 -397.800942) (xy 136.117603 -397.855221) (xy 136.080343 -397.905145)
			(xy 136.037006 -397.949895) (xy 135.988301 -397.988735) (xy 135.93503 -398.021028) (xy 135.878067 -398.046245)
			(xy 135.818346 -398.063969) (xy 135.756849 -398.073912) (xy 135.694586 -398.075908) (xy 135.632579 -398.069926)
			(xy 135.571845 -398.056064) (xy 135.513383 -398.03455) (xy 135.458152 -398.005736) (xy 135.40706 -397.970096)
			(xy 135.360944 -397.928215) (xy 135.320562 -397.88078) (xy 135.286578 -397.828571) (xy 135.259549 -397.772445)
			(xy 135.23992 -397.713324) (xy 135.228011 -397.652177) (xy 135.22402 -397.59001) (xy 133.952388 -397.59001)
			(xy 133.971402 -397.636973) (xy 133.987203 -397.697231) (xy 133.995169 -397.759014) (xy 133.995668 -397.790162)
			(xy 133.995169 -397.82131) (xy 133.987203 -397.883093) (xy 133.971402 -397.943351) (xy 133.948024 -398.001094)
			(xy 133.917455 -398.055373) (xy 133.880195 -398.105297) (xy 133.836858 -398.150047) (xy 133.788153 -398.188887)
			(xy 133.734882 -398.22118) (xy 133.677919 -398.246397) (xy 133.618198 -398.264121) (xy 133.556701 -398.274064)
			(xy 133.494438 -398.27606) (xy 133.432431 -398.270078) (xy 133.371697 -398.256216) (xy 133.313235 -398.234702)
			(xy 133.258004 -398.205888) (xy 133.206912 -398.170248) (xy 133.160796 -398.128367) (xy 133.120414 -398.080932)
			(xy 133.08643 -398.028723) (xy 133.059401 -397.972597) (xy 133.039772 -397.913476) (xy 133.027863 -397.852329)
			(xy 133.023872 -397.790162) (xy 131.752122 -397.790162) (xy 131.743279 -397.810828) (xy 131.72694 -397.839184)
			(xy 131.723634 -397.845213) (xy 131.720023 -397.858473) (xy 131.719828 -397.865346) (xy 131.719828 -398.6149)
			(xy 131.720017 -398.621774) (xy 131.723627 -398.635036) (xy 131.72694 -398.641062) (xy 131.743309 -398.669401)
			(xy 131.769051 -398.729572) (xy 131.786475 -398.792655) (xy 131.795264 -398.857508) (xy 131.795262 -398.890236)
			(xy 135.22402 -398.890236) (xy 135.228011 -398.828069) (xy 135.23992 -398.766922) (xy 135.259549 -398.707801)
			(xy 135.286578 -398.651675) (xy 135.320562 -398.599466) (xy 135.360944 -398.552031) (xy 135.40706 -398.51015)
			(xy 135.458152 -398.47451) (xy 135.513383 -398.445696) (xy 135.571845 -398.424182) (xy 135.632579 -398.41032)
			(xy 135.694586 -398.404338) (xy 135.756849 -398.406334) (xy 135.818346 -398.416277) (xy 135.878067 -398.434001)
			(xy 135.93503 -398.459218) (xy 135.988301 -398.491511) (xy 136.037006 -398.530351) (xy 136.080343 -398.575101)
			(xy 136.117603 -398.625025) (xy 136.148172 -398.679304) (xy 136.17155 -398.737047) (xy 136.187351 -398.797305)
			(xy 136.195317 -398.859088) (xy 136.195816 -398.890236) (xy 136.195317 -398.921384) (xy 136.187351 -398.983167)
			(xy 136.17155 -399.043425) (xy 136.148172 -399.101168) (xy 136.117603 -399.155447) (xy 136.080343 -399.205371)
			(xy 136.037006 -399.250121) (xy 135.988301 -399.288961) (xy 135.93503 -399.321254) (xy 135.878067 -399.346471)
			(xy 135.818346 -399.364195) (xy 135.756849 -399.374138) (xy 135.694586 -399.376134) (xy 135.632579 -399.370152)
			(xy 135.571845 -399.35629) (xy 135.513383 -399.334776) (xy 135.458152 -399.305962) (xy 135.40706 -399.270322)
			(xy 135.360944 -399.228441) (xy 135.320562 -399.181006) (xy 135.286578 -399.128797) (xy 135.259549 -399.072671)
			(xy 135.23992 -399.01355) (xy 135.228011 -398.952403) (xy 135.22402 -398.890236) (xy 131.795262 -398.890236)
			(xy 131.79526 -398.922954) (xy 131.786462 -398.987805) (xy 131.76903 -399.050887) (xy 131.74328 -399.111054)
			(xy 131.72694 -399.13941) (xy 131.723625 -399.145435) (xy 131.720019 -399.158698) (xy 131.719828 -399.165572)
			(xy 131.719828 -399.451576) (xy 131.719359 -399.461725) (xy 131.711577 -399.480472) (xy 131.697195 -399.494795)
			(xy 131.678417 -399.502501) (xy 131.668266 -399.502884) (xy 130.951986 -399.502884) (xy 130.941861 -399.502385)
			(xy 130.923145 -399.494657) (xy 130.90879 -399.480375) (xy 130.900967 -399.461698) (xy 130.900424 -399.451576)
			(xy 130.900424 -399.165572) (xy 130.90024 -399.158698) (xy 130.896626 -399.145436) (xy 130.893312 -399.13941)
			(xy 130.877006 -399.111037) (xy 130.851261 -399.050874) (xy 130.833832 -398.987797) (xy 130.825036 -398.922951)
			(xy 130.825031 -398.857511) (xy 130.833819 -398.792663) (xy 130.85124 -398.729585) (xy 130.876978 -398.669418)
			(xy 130.893312 -398.641062) (xy 130.896641 -398.635044) (xy 130.900237 -398.621775) (xy 130.900424 -398.6149)
			(xy 130.900424 -397.865346) (xy 130.900212 -397.858474) (xy 130.896617 -397.845212) (xy 130.893312 -397.839184)
			(xy 130.876984 -397.810823) (xy 130.851241 -397.750657) (xy 130.833814 -397.687578) (xy 130.825021 -397.62273)
			(xy 130.82502 -397.557288) (xy 129.536158 -397.557288) (xy 129.543096 -397.569362) (xy 129.568841 -397.629525)
			(xy 129.58627 -397.692601) (xy 129.595067 -397.757447) (xy 129.595071 -397.822887) (xy 129.586283 -397.887735)
			(xy 129.568863 -397.950813) (xy 129.543126 -398.01098) (xy 129.526792 -398.039336) (xy 129.523464 -398.045354)
			(xy 129.519867 -398.058623) (xy 129.51968 -398.065498) (xy 129.51968 -398.351502) (xy 129.519169 -398.361658)
			(xy 129.511397 -398.380423) (xy 129.497037 -398.394788) (xy 129.478274 -398.402565) (xy 129.468118 -398.403064)
			(xy 128.751838 -398.403064) (xy 128.741669 -398.402605) (xy 128.722876 -398.394833) (xy 128.70849 -398.380458)
			(xy 128.700703 -398.361671) (xy 128.700276 -398.351502) (xy 128.700276 -398.065498) (xy 128.700088 -398.058624)
			(xy 128.696477 -398.045362) (xy 128.693164 -398.039336) (xy 128.676794 -398.010998) (xy 128.651051 -397.950827)
			(xy 128.633628 -397.887743) (xy 128.624838 -397.82289) (xy 127.336285 -397.82289) (xy 127.326898 -397.839184)
			(xy 127.323543 -397.845204) (xy 127.319801 -397.85846) (xy 127.319532 -397.865346) (xy 127.319532 -398.6149)
			(xy 127.319761 -398.621792) (xy 127.323506 -398.635058) (xy 127.326898 -398.641062) (xy 127.343265 -398.669402)
			(xy 127.369004 -398.729573) (xy 127.386426 -398.792656) (xy 127.395214 -398.857508) (xy 127.39521 -398.922953)
			(xy 127.386413 -398.987804) (xy 127.368983 -399.050886) (xy 127.343237 -399.111053) (xy 127.326898 -399.13941)
			(xy 127.323534 -399.145425) (xy 127.319798 -399.158685) (xy 127.319532 -399.165572) (xy 127.319532 -399.451576)
			(xy 127.318996 -399.461679) (xy 127.311272 -399.480351) (xy 127.296991 -399.494645) (xy 127.278327 -399.502387)
			(xy 127.268224 -399.502884) (xy 126.551944 -399.502884) (xy 126.541822 -399.502447) (xy 126.523117 -399.494711)
			(xy 126.5088 -399.4804) (xy 126.501056 -399.461697) (xy 126.500636 -399.451576) (xy 126.500636 -399.165572)
			(xy 126.500405 -399.158679) (xy 126.496675 -399.145407) (xy 126.49327 -399.13941) (xy 126.476962 -399.111037)
			(xy 126.451214 -399.050875) (xy 126.433783 -398.987798) (xy 126.424986 -398.922951) (xy 126.424981 -398.85751)
			(xy 126.43377 -398.792662) (xy 126.451193 -398.729584) (xy 126.476934 -398.669418) (xy 126.49327 -398.641062)
			(xy 126.496649 -398.635054) (xy 126.500375 -398.621788) (xy 126.500636 -398.6149) (xy 126.500636 -397.865346)
			(xy 126.500416 -397.858452) (xy 126.496679 -397.84518) (xy 126.49327 -397.839184) (xy 126.47694 -397.810823)
			(xy 126.451194 -397.750658) (xy 126.433765 -397.687579) (xy 126.424971 -397.62273) (xy 126.42497 -397.557287)
			(xy 125.13637 -397.557287) (xy 125.143308 -397.569362) (xy 125.169052 -397.629525) (xy 125.186481 -397.692602)
			(xy 125.195277 -397.757448) (xy 125.195281 -397.822887) (xy 125.186494 -397.887734) (xy 125.169074 -397.950813)
			(xy 125.143337 -398.010979) (xy 125.127004 -398.039336) (xy 125.123677 -398.045355) (xy 125.120079 -398.058623)
			(xy 125.119892 -398.065498) (xy 125.119892 -398.351502) (xy 125.119369 -398.361656) (xy 125.111599 -398.38042)
			(xy 125.097243 -398.394784) (xy 125.078484 -398.402563) (xy 125.06833 -398.403064) (xy 124.35205 -398.403064)
			(xy 124.341882 -398.402595) (xy 124.323089 -398.394827) (xy 124.308702 -398.380455) (xy 124.300915 -398.36167)
			(xy 124.300488 -398.351502) (xy 124.300488 -398.065498) (xy 124.300299 -398.058625) (xy 124.296689 -398.045362)
			(xy 124.293376 -398.039336) (xy 124.277005 -398.010998) (xy 124.251262 -397.950827) (xy 124.233838 -397.887744)
			(xy 124.225049 -397.82289) (xy 122.936244 -397.82289) (xy 122.926856 -397.839184) (xy 122.923551 -397.845214)
			(xy 122.919939 -397.858473) (xy 122.919744 -397.865346) (xy 122.919744 -398.6149) (xy 122.919931 -398.621774)
			(xy 122.923542 -398.635037) (xy 122.926856 -398.641062) (xy 122.943224 -398.669401) (xy 122.968965 -398.729572)
			(xy 122.986389 -398.792655) (xy 122.995178 -398.857508) (xy 122.995174 -398.922954) (xy 122.986376 -398.987805)
			(xy 122.968945 -399.050887) (xy 122.943196 -399.111054) (xy 122.926856 -399.13941) (xy 122.923542 -399.145435)
			(xy 122.919935 -399.158698) (xy 122.919744 -399.165572) (xy 122.919744 -399.451576) (xy 122.91926 -399.461723)
			(xy 122.91148 -399.480467) (xy 122.897103 -399.494789) (xy 122.878331 -399.502498) (xy 122.868182 -399.502884)
			(xy 122.151902 -399.502884) (xy 122.141778 -399.502372) (xy 122.123062 -399.49465) (xy 122.108706 -399.480371)
			(xy 122.100883 -399.461697) (xy 122.10034 -399.451576) (xy 122.10034 -399.165572) (xy 122.100154 -399.158698)
			(xy 122.096541 -399.145436) (xy 122.093228 -399.13941) (xy 122.076921 -399.111037) (xy 122.051175 -399.050874)
			(xy 122.033746 -398.987797) (xy 122.024949 -398.922951) (xy 122.024945 -398.857511) (xy 122.033734 -398.792663)
			(xy 122.051155 -398.729584) (xy 122.076893 -398.669418) (xy 122.093228 -398.641062) (xy 122.096558 -398.635045)
			(xy 122.100154 -398.621775) (xy 122.10034 -398.6149) (xy 122.10034 -397.865346) (xy 122.100126 -397.858474)
			(xy 122.096532 -397.845212) (xy 122.093228 -397.839184) (xy 122.076899 -397.810823) (xy 122.051155 -397.750657)
			(xy 122.033728 -397.687578) (xy 122.024935 -397.62273) (xy 122.024933 -397.557288) (xy 120.736329 -397.557288)
			(xy 120.743267 -397.569362) (xy 120.769014 -397.629525) (xy 120.786444 -397.692601) (xy 120.795241 -397.757447)
			(xy 120.795245 -397.822888) (xy 120.786457 -397.887735) (xy 120.769036 -397.950814) (xy 120.743297 -398.01098)
			(xy 120.726962 -398.039336) (xy 120.723586 -398.045345) (xy 120.719858 -398.05861) (xy 120.719596 -398.065498)
			(xy 120.719596 -398.351502) (xy 120.719076 -398.361624) (xy 120.711354 -398.380339) (xy 120.697079 -398.394694)
			(xy 120.678408 -398.402519) (xy 120.668288 -398.403064) (xy 119.952008 -398.403064) (xy 119.94185 -398.402671)
			(xy 119.923091 -398.394871) (xy 119.908766 -398.380465) (xy 119.901072 -398.361662) (xy 119.9007 -398.351502)
			(xy 119.9007 -398.065498) (xy 119.900467 -398.058607) (xy 119.896725 -398.045341) (xy 119.893334 -398.039336)
			(xy 119.876965 -398.010998) (xy 119.851224 -397.950827) (xy 119.833801 -397.887743) (xy 119.825012 -397.82289)
			(xy 118.536203 -397.82289) (xy 118.526814 -397.839184) (xy 118.52346 -397.845204) (xy 118.519717 -397.85846)
			(xy 118.519448 -397.865346) (xy 118.519448 -398.6149) (xy 118.519653 -398.621795) (xy 118.523401 -398.635067)
			(xy 118.526814 -398.641062) (xy 118.543183 -398.669401) (xy 118.568927 -398.729571) (xy 118.586352 -398.792655)
			(xy 118.595142 -398.857508) (xy 118.595138 -398.922954) (xy 118.586339 -398.987806) (xy 118.568906 -399.050887)
			(xy 118.543155 -399.111054) (xy 118.526814 -399.13941) (xy 118.523451 -399.145426) (xy 118.519714 -399.158685)
			(xy 118.519448 -399.165572) (xy 118.519448 -399.451576) (xy 118.518897 -399.461677) (xy 118.511176 -399.480346)
			(xy 118.4969 -399.49464) (xy 118.478241 -399.502384) (xy 118.46814 -399.502884) (xy 117.75186 -399.502884)
			(xy 117.741747 -399.502447) (xy 117.723065 -399.494693) (xy 117.708771 -399.480382) (xy 117.70104 -399.46169)
			(xy 117.700552 -399.451576) (xy 117.700552 -399.165572) (xy 117.700319 -399.158679) (xy 117.696591 -399.145407)
			(xy 117.693186 -399.13941) (xy 117.676878 -399.111037) (xy 117.651128 -399.050875) (xy 117.633697 -398.987798)
			(xy 117.624899 -398.922951) (xy 117.624895 -398.85751) (xy 117.633685 -398.792662) (xy 117.651108 -398.729583)
			(xy 117.67685 -398.669418) (xy 117.693186 -398.641062) (xy 117.696559 -398.635051) (xy 117.70029 -398.621788)
			(xy 117.700552 -398.6149) (xy 117.700552 -397.865346) (xy 117.700329 -397.858452) (xy 117.696594 -397.84518)
			(xy 117.693186 -397.839184) (xy 117.676856 -397.810824) (xy 117.651108 -397.750658) (xy 117.633679 -397.687579)
			(xy 117.624885 -397.62273) (xy 117.624883 -397.557287) (xy 116.336287 -397.557287) (xy 116.343226 -397.569362)
			(xy 116.368975 -397.629524) (xy 116.386407 -397.6926) (xy 116.395205 -397.757447) (xy 116.395209 -397.822888)
			(xy 116.38642 -397.887736) (xy 116.368997 -397.950815) (xy 116.343256 -398.01098) (xy 116.32692 -398.039336)
			(xy 116.323594 -398.045355) (xy 116.319995 -398.058623) (xy 116.319808 -398.065498) (xy 116.319808 -398.351502)
			(xy 116.319269 -398.361654) (xy 116.311503 -398.380415) (xy 116.297152 -398.394778) (xy 116.278398 -398.402561)
			(xy 116.268246 -398.403064) (xy 115.551966 -398.403064) (xy 115.541806 -398.402595) (xy 115.523037 -398.394809)
			(xy 115.508673 -398.380436) (xy 115.500899 -398.361662) (xy 115.500404 -398.351502) (xy 115.500404 -398.065498)
			(xy 115.500212 -398.058625) (xy 115.496604 -398.045362) (xy 115.493292 -398.039336) (xy 115.476921 -398.010998)
			(xy 115.451177 -397.950828) (xy 115.433752 -397.887744) (xy 115.424962 -397.822891) (xy 94.135448 -397.822891)
			(xy 94.135448 -398.66824) (xy 100.573076 -398.66824) (xy 100.577147 -398.612618) (xy 100.589273 -398.558181)
			(xy 100.609196 -398.50609) (xy 100.636492 -398.457455) (xy 100.670578 -398.413312) (xy 100.710727 -398.374603)
			(xy 100.756085 -398.342152) (xy 100.805685 -398.316651) (xy 100.858469 -398.298644) (xy 100.913312 -398.288514)
			(xy 100.969046 -398.286477) (xy 101.024483 -398.292577) (xy 101.07844 -398.306683) (xy 101.129769 -398.328495)
			(xy 101.177375 -398.357549) (xy 101.220243 -398.393224) (xy 101.25746 -398.434761) (xy 101.288233 -398.481274)
			(xy 101.311905 -398.531771) (xy 101.327973 -398.585178) (xy 101.336093 -398.640354) (xy 101.336602 -398.66824)
			(xy 101.589076 -398.66824) (xy 101.593147 -398.612618) (xy 101.605273 -398.558181) (xy 101.625196 -398.50609)
			(xy 101.652492 -398.457455) (xy 101.686578 -398.413312) (xy 101.726727 -398.374603) (xy 101.772085 -398.342152)
			(xy 101.821685 -398.316651) (xy 101.874469 -398.298644) (xy 101.929312 -398.288514) (xy 101.985046 -398.286477)
			(xy 102.040483 -398.292577) (xy 102.09444 -398.306683) (xy 102.145769 -398.328495) (xy 102.193375 -398.357549)
			(xy 102.236243 -398.393224) (xy 102.27346 -398.434761) (xy 102.304233 -398.481274) (xy 102.327905 -398.531771)
			(xy 102.343973 -398.585178) (xy 102.352093 -398.640354) (xy 102.352602 -398.66824) (xy 102.352491 -398.674336)
			(xy 105.653076 -398.674336) (xy 105.657147 -398.618714) (xy 105.669273 -398.564277) (xy 105.689196 -398.512186)
			(xy 105.716492 -398.463551) (xy 105.750578 -398.419408) (xy 105.790727 -398.380699) (xy 105.836085 -398.348248)
			(xy 105.885685 -398.322747) (xy 105.938469 -398.30474) (xy 105.993312 -398.29461) (xy 106.049046 -398.292573)
			(xy 106.104483 -398.298673) (xy 106.15844 -398.312779) (xy 106.209769 -398.334591) (xy 106.257375 -398.363645)
			(xy 106.300243 -398.39932) (xy 106.33746 -398.440857) (xy 106.368233 -398.48737) (xy 106.391905 -398.537867)
			(xy 106.407973 -398.591274) (xy 106.416093 -398.64645) (xy 106.416602 -398.674336) (xy 106.416093 -398.702222)
			(xy 106.407973 -398.757398) (xy 106.391905 -398.810805) (xy 106.368233 -398.861302) (xy 106.33746 -398.907815)
			(xy 106.300243 -398.949352) (xy 106.257375 -398.985027) (xy 106.209769 -399.014081) (xy 106.15844 -399.035893)
			(xy 106.104483 -399.049999) (xy 106.049046 -399.056099) (xy 105.993312 -399.054062) (xy 105.938469 -399.043932)
			(xy 105.885685 -399.025925) (xy 105.836085 -399.000424) (xy 105.790727 -398.967973) (xy 105.750578 -398.929264)
			(xy 105.716492 -398.885121) (xy 105.689196 -398.836486) (xy 105.669273 -398.784395) (xy 105.657147 -398.729958)
			(xy 105.653076 -398.674336) (xy 102.352491 -398.674336) (xy 102.352093 -398.696126) (xy 102.343973 -398.751302)
			(xy 102.327905 -398.804709) (xy 102.304233 -398.855206) (xy 102.27346 -398.901719) (xy 102.236243 -398.943256)
			(xy 102.193375 -398.978931) (xy 102.145769 -399.007985) (xy 102.09444 -399.029797) (xy 102.040483 -399.043903)
			(xy 101.985046 -399.050003) (xy 101.929312 -399.047966) (xy 101.874469 -399.037836) (xy 101.821685 -399.019829)
			(xy 101.772085 -398.994328) (xy 101.726727 -398.961877) (xy 101.686578 -398.923168) (xy 101.652492 -398.879025)
			(xy 101.625196 -398.83039) (xy 101.605273 -398.778299) (xy 101.593147 -398.723862) (xy 101.589076 -398.66824)
			(xy 101.336602 -398.66824) (xy 101.336093 -398.696126) (xy 101.327973 -398.751302) (xy 101.311905 -398.804709)
			(xy 101.288233 -398.855206) (xy 101.25746 -398.901719) (xy 101.220243 -398.943256) (xy 101.177375 -398.978931)
			(xy 101.129769 -399.007985) (xy 101.07844 -399.029797) (xy 101.024483 -399.043903) (xy 100.969046 -399.050003)
			(xy 100.913312 -399.047966) (xy 100.858469 -399.037836) (xy 100.805685 -399.019829) (xy 100.756085 -398.994328)
			(xy 100.710727 -398.961877) (xy 100.670578 -398.923168) (xy 100.636492 -398.879025) (xy 100.609196 -398.83039)
			(xy 100.589273 -398.778299) (xy 100.577147 -398.723862) (xy 100.573076 -398.66824) (xy 94.135448 -398.66824)
			(xy 94.135448 -401.722804) (xy 115.424971 -401.722804) (xy 115.424974 -401.657359) (xy 115.433771 -401.592507)
			(xy 115.451202 -401.529426) (xy 115.476952 -401.46926) (xy 115.493292 -401.440904) (xy 115.496605 -401.434878)
			(xy 115.500212 -401.421615) (xy 115.500404 -401.414742) (xy 115.500404 -400.665442) (xy 115.500195 -400.65857)
			(xy 115.496598 -400.645307) (xy 115.493292 -400.63928) (xy 115.476958 -400.610922) (xy 115.451211 -400.550756)
			(xy 115.433782 -400.487676) (xy 115.424987 -400.422827) (xy 115.424987 -400.357384) (xy 115.43378 -400.292534)
			(xy 115.451207 -400.229454) (xy 115.476953 -400.169288) (xy 115.493292 -400.140932) (xy 115.496595 -400.134902)
			(xy 115.500208 -400.121642) (xy 115.500404 -400.11477) (xy 115.500404 -399.828766) (xy 115.500905 -399.81861)
			(xy 115.508684 -399.799847) (xy 115.523047 -399.785484) (xy 115.54181 -399.777705) (xy 115.551966 -399.777204)
			(xy 116.268246 -399.777204) (xy 116.278403 -399.777695) (xy 116.297166 -399.785478) (xy 116.311529 -399.799844)
			(xy 116.319307 -399.818609) (xy 116.319808 -399.828766) (xy 116.319808 -400.11477) (xy 116.320011 -400.121642)
			(xy 116.323612 -400.134905) (xy 116.32692 -400.140932) (xy 116.343264 -400.169285) (xy 116.369009 -400.229452)
			(xy 116.386437 -400.292533) (xy 116.39523 -400.357383) (xy 116.395229 -400.422827) (xy 116.386435 -400.487677)
			(xy 116.369006 -400.550758) (xy 116.343259 -400.610924) (xy 116.32692 -400.63928) (xy 116.323614 -400.645309)
			(xy 116.320002 -400.658569) (xy 116.319808 -400.665442) (xy 116.319808 -401.414742) (xy 116.320021 -401.421614)
			(xy 116.323615 -401.434876) (xy 116.32692 -401.440904) (xy 116.34324 -401.46927) (xy 116.368988 -401.529434)
			(xy 116.386418 -401.592512) (xy 116.395214 -401.65736) (xy 116.395216 -401.722802) (xy 116.386425 -401.787651)
			(xy 116.369 -401.85073) (xy 116.343257 -401.910896) (xy 116.32692 -401.939252) (xy 116.323588 -401.945268)
			(xy 116.319993 -401.958538) (xy 116.319808 -401.965414) (xy 116.319808 -402.251418) (xy 116.319283 -402.261571)
			(xy 116.311511 -402.280332) (xy 116.297156 -402.294695) (xy 116.278399 -402.302477) (xy 116.268246 -402.30298)
			(xy 115.551966 -402.30298) (xy 115.541808 -402.302495) (xy 115.523042 -402.294713) (xy 115.508678 -402.280345)
			(xy 115.500902 -402.261576) (xy 115.500404 -402.251418) (xy 115.500404 -401.965414) (xy 115.500206 -401.958541)
			(xy 115.496602 -401.945278) (xy 115.493292 -401.939252) (xy 115.476934 -401.910907) (xy 115.451189 -401.850738)
			(xy 115.433763 -401.787656) (xy 115.424971 -401.722804) (xy 94.135448 -401.722804) (xy 94.135448 -402.822882)
			(xy 117.624851 -402.822882) (xy 117.624857 -402.757435) (xy 117.633657 -402.692583) (xy 117.651091 -402.629501)
			(xy 117.676844 -402.569334) (xy 117.693186 -402.540978) (xy 117.696553 -402.534964) (xy 117.700288 -402.521703)
			(xy 117.700552 -402.514816) (xy 117.700552 -401.765516) (xy 117.700341 -401.758621) (xy 117.696597 -401.74535)
			(xy 117.693186 -401.739354) (xy 117.67683 -401.711008) (xy 117.651085 -401.650839) (xy 117.633659 -401.587757)
			(xy 117.624867 -401.522905) (xy 117.62487 -401.45746) (xy 117.633666 -401.392609) (xy 117.651097 -401.329528)
			(xy 117.676846 -401.269362) (xy 117.693186 -401.241006) (xy 117.696543 -401.234987) (xy 117.700284 -401.22173)
			(xy 117.700552 -401.214844) (xy 117.700552 -400.92884) (xy 117.701117 -400.91874) (xy 117.708832 -400.900072)
			(xy 117.723105 -400.885777) (xy 117.741761 -400.878033) (xy 117.75186 -400.877532) (xy 118.46814 -400.877532)
			(xy 118.478255 -400.877953) (xy 118.49694 -400.88571) (xy 118.511235 -400.900027) (xy 118.518963 -400.918724)
			(xy 118.519448 -400.92884) (xy 118.519448 -401.214844) (xy 118.519674 -401.221737) (xy 118.523407 -401.235009)
			(xy 118.526814 -401.241006) (xy 118.543136 -401.269371) (xy 118.568884 -401.329535) (xy 118.586314 -401.392613)
			(xy 118.59511 -401.457462) (xy 118.595112 -401.522904) (xy 118.586321 -401.587753) (xy 118.568895 -401.650832)
			(xy 118.543151 -401.710998) (xy 118.53635 -401.722803) (xy 119.825022 -401.722803) (xy 119.825024 -401.657359)
			(xy 119.83382 -401.592508) (xy 119.851249 -401.529427) (xy 119.876995 -401.46926) (xy 119.893334 -401.440904)
			(xy 119.896695 -401.434888) (xy 119.900433 -401.421628) (xy 119.9007 -401.414742) (xy 119.9007 -400.665442)
			(xy 119.900451 -400.658552) (xy 119.896719 -400.645286) (xy 119.893334 -400.63928) (xy 119.877002 -400.610921)
			(xy 119.851258 -400.550755) (xy 119.833831 -400.487675) (xy 119.825037 -400.422826) (xy 119.825037 -400.357384)
			(xy 119.833829 -400.292535) (xy 119.851254 -400.229455) (xy 119.876997 -400.169288) (xy 119.893334 -400.140932)
			(xy 119.896686 -400.134911) (xy 119.900429 -400.121655) (xy 119.9007 -400.11477) (xy 119.9007 -399.828766)
			(xy 119.901197 -399.818642) (xy 119.908929 -399.799928) (xy 119.923211 -399.785574) (xy 119.941887 -399.777749)
			(xy 119.952008 -399.777204) (xy 120.668288 -399.777204) (xy 120.678442 -399.777631) (xy 120.697195 -399.785424)
			(xy 120.711519 -399.799819) (xy 120.719218 -399.81861) (xy 120.719596 -399.828766) (xy 120.719596 -400.11477)
			(xy 120.719841 -400.12166) (xy 120.723576 -400.134926) (xy 120.726962 -400.140932) (xy 120.743304 -400.169285)
			(xy 120.769048 -400.229453) (xy 120.786474 -400.292533) (xy 120.795266 -400.357383) (xy 120.795265 -400.422827)
			(xy 120.786472 -400.487677) (xy 120.769044 -400.550757) (xy 120.7433 -400.610924) (xy 120.726962 -400.63928)
			(xy 120.723606 -400.645299) (xy 120.719865 -400.658556) (xy 120.719596 -400.665442) (xy 120.719596 -401.414742)
			(xy 120.719852 -401.421632) (xy 120.723579 -401.434898) (xy 120.726962 -401.440904) (xy 120.743281 -401.46927)
			(xy 120.769026 -401.529435) (xy 120.786455 -401.592513) (xy 120.79525 -401.65736) (xy 120.795253 -401.722802)
			(xy 120.786462 -401.78765) (xy 120.769039 -401.85073) (xy 120.743298 -401.910896) (xy 120.726962 -401.939252)
			(xy 120.723581 -401.945259) (xy 120.719856 -401.958525) (xy 120.719596 -401.965414) (xy 120.719596 -402.251418)
			(xy 120.719089 -402.261541) (xy 120.711362 -402.280256) (xy 120.697083 -402.294611) (xy 120.678409 -402.302436)
			(xy 120.668288 -402.30298) (xy 119.952008 -402.30298) (xy 119.941852 -402.302571) (xy 119.923096 -402.294775)
			(xy 119.908771 -402.280374) (xy 119.901075 -402.261576) (xy 119.9007 -402.251418) (xy 119.9007 -401.965414)
			(xy 119.900461 -401.958523) (xy 119.896723 -401.945257) (xy 119.893334 -401.939252) (xy 119.876978 -401.910906)
			(xy 119.851236 -401.850737) (xy 119.833812 -401.787655) (xy 119.825022 -401.722803) (xy 118.53635 -401.722803)
			(xy 118.526814 -401.739354) (xy 118.523436 -401.745362) (xy 118.519708 -401.758628) (xy 118.519448 -401.765516)
			(xy 118.519448 -402.514816) (xy 118.519685 -402.521708) (xy 118.523411 -402.534981) (xy 118.526814 -402.540978)
			(xy 118.543112 -402.569356) (xy 118.568862 -402.629517) (xy 118.586295 -402.692593) (xy 118.595094 -402.757439)
			(xy 118.595099 -402.822879) (xy 118.595099 -402.822882) (xy 122.024902 -402.822882) (xy 122.024907 -402.757436)
			(xy 122.033706 -402.692584) (xy 122.051138 -402.629502) (xy 122.076888 -402.569334) (xy 122.093228 -402.540978)
			(xy 122.096553 -402.534958) (xy 122.100151 -402.521691) (xy 122.10034 -402.514816) (xy 122.10034 -401.765516)
			(xy 122.100137 -401.758644) (xy 122.096536 -401.745381) (xy 122.093228 -401.739354) (xy 122.076874 -401.711007)
			(xy 122.051132 -401.650838) (xy 122.033708 -401.587756) (xy 122.024917 -401.522905) (xy 122.02492 -401.457461)
			(xy 122.033715 -401.39261) (xy 122.051144 -401.329529) (xy 122.07689 -401.269362) (xy 122.093228 -401.241006)
			(xy 122.096543 -401.234981) (xy 122.100148 -401.221718) (xy 122.10034 -401.214844) (xy 122.10034 -400.92884)
			(xy 122.100755 -400.918684) (xy 122.108545 -400.899924) (xy 122.122945 -400.885598) (xy 122.141743 -400.877904)
			(xy 122.151902 -400.877532) (xy 122.868182 -400.877532) (xy 122.878307 -400.878041) (xy 122.897026 -400.885761)
			(xy 122.911383 -400.900041) (xy 122.919204 -400.918718) (xy 122.919744 -400.92884) (xy 122.919744 -401.214844)
			(xy 122.919952 -401.221716) (xy 122.923549 -401.234979) (xy 122.926856 -401.241006) (xy 122.943177 -401.269371)
			(xy 122.968922 -401.329536) (xy 122.986351 -401.392614) (xy 122.995146 -401.457462) (xy 122.995148 -401.522904)
			(xy 122.986358 -401.587752) (xy 122.968934 -401.650832) (xy 122.943192 -401.710998) (xy 122.936391 -401.722804)
			(xy 124.225058 -401.722804) (xy 124.22506 -401.657359) (xy 124.233857 -401.592508) (xy 124.251287 -401.529427)
			(xy 124.277036 -401.46926) (xy 124.293376 -401.440904) (xy 124.296688 -401.434878) (xy 124.300296 -401.421615)
			(xy 124.300488 -401.414742) (xy 124.300488 -400.665442) (xy 124.300281 -400.65857) (xy 124.296683 -400.645307)
			(xy 124.293376 -400.63928) (xy 124.277043 -400.610921) (xy 124.251296 -400.550756) (xy 124.233868 -400.487676)
			(xy 124.225074 -400.422827) (xy 124.225073 -400.357384) (xy 124.233866 -400.292534) (xy 124.251293 -400.229454)
			(xy 124.277038 -400.169288) (xy 124.293376 -400.140932) (xy 124.296678 -400.134901) (xy 124.300292 -400.121642)
			(xy 124.300488 -400.11477) (xy 124.300488 -399.828766) (xy 124.300837 -399.818586) (xy 124.308643 -399.799781)
			(xy 124.323052 -399.785395) (xy 124.341869 -399.777621) (xy 124.35205 -399.777204) (xy 125.06833 -399.777204)
			(xy 125.078486 -399.777708) (xy 125.097249 -399.785486) (xy 125.111612 -399.799848) (xy 125.119391 -399.818611)
			(xy 125.119892 -399.828766) (xy 125.119892 -400.11477) (xy 125.120096 -400.121642) (xy 125.123696 -400.134905)
			(xy 125.127004 -400.140932) (xy 125.143345 -400.169286) (xy 125.169086 -400.229454) (xy 125.186511 -400.292534)
			(xy 125.195302 -400.357384) (xy 125.195301 -400.422827) (xy 125.186508 -400.487676) (xy 125.169083 -400.550756)
			(xy 125.14334 -400.610923) (xy 125.127004 -400.63928) (xy 125.123697 -400.645308) (xy 125.120086 -400.658569)
			(xy 125.119892 -400.665442) (xy 125.119892 -401.414742) (xy 125.120107 -401.421614) (xy 125.1237 -401.434876)
			(xy 125.127004 -401.440904) (xy 125.143321 -401.469271) (xy 125.169065 -401.529436) (xy 125.186492 -401.592513)
			(xy 125.195286 -401.657361) (xy 125.195289 -401.722802) (xy 125.186499 -401.78765) (xy 125.169077 -401.850729)
			(xy 125.143339 -401.910895) (xy 125.127004 -401.939252) (xy 125.123671 -401.945268) (xy 125.120077 -401.958538)
			(xy 125.119892 -401.965414) (xy 125.119892 -402.251418) (xy 125.119382 -402.261573) (xy 125.111608 -402.280337)
			(xy 125.097247 -402.294701) (xy 125.078485 -402.30248) (xy 125.06833 -402.30298) (xy 124.35205 -402.30298)
			(xy 124.341884 -402.302496) (xy 124.323094 -402.29473) (xy 124.308708 -402.280363) (xy 124.300918 -402.261584)
			(xy 124.300488 -402.251418) (xy 124.300488 -401.965414) (xy 124.300292 -401.958541) (xy 124.296687 -401.945278)
			(xy 124.293376 -401.939252) (xy 124.277019 -401.910907) (xy 124.251275 -401.850738) (xy 124.233849 -401.787655)
			(xy 124.225058 -401.722804) (xy 122.936391 -401.722804) (xy 122.926856 -401.739354) (xy 122.923562 -401.745389)
			(xy 122.919943 -401.758645) (xy 122.919744 -401.765516) (xy 122.919744 -402.514816) (xy 122.919924 -402.52169)
			(xy 122.92354 -402.534953) (xy 122.926856 -402.540978) (xy 122.943153 -402.569357) (xy 122.968901 -402.629518)
			(xy 122.986332 -402.692593) (xy 122.99513 -402.757439) (xy 122.995136 -402.822879) (xy 122.995136 -402.822882)
			(xy 126.424938 -402.822882) (xy 126.424943 -402.757436) (xy 126.433743 -402.692583) (xy 126.451177 -402.629501)
			(xy 126.476928 -402.569334) (xy 126.49327 -402.540978) (xy 126.496644 -402.534968) (xy 126.500373 -402.521704)
			(xy 126.500636 -402.514816) (xy 126.500636 -401.765516) (xy 126.500427 -401.758621) (xy 126.496682 -401.745349)
			(xy 126.49327 -401.739354) (xy 126.476915 -401.711008) (xy 126.451171 -401.650839) (xy 126.433745 -401.587757)
			(xy 126.424954 -401.522905) (xy 126.424956 -401.45746) (xy 126.433752 -401.39261) (xy 126.451182 -401.329529)
			(xy 126.47693 -401.269362) (xy 126.49327 -401.241006) (xy 126.496634 -401.234991) (xy 126.500369 -401.221731)
			(xy 126.500636 -401.214844) (xy 126.500636 -400.92884) (xy 126.50105 -400.918716) (xy 126.508791 -400.900006)
			(xy 126.523109 -400.885689) (xy 126.54182 -400.877949) (xy 126.551944 -400.877532) (xy 127.268224 -400.877532)
			(xy 127.278352 -400.877897) (xy 127.297062 -400.885659) (xy 127.311377 -400.899991) (xy 127.319116 -400.918711)
			(xy 127.319532 -400.92884) (xy 127.319532 -401.214844) (xy 127.319761 -401.221737) (xy 127.323492 -401.235009)
			(xy 127.326898 -401.241006) (xy 127.343217 -401.269372) (xy 127.368961 -401.329537) (xy 127.386388 -401.392615)
			(xy 127.395182 -401.457462) (xy 127.395184 -401.522903) (xy 127.386395 -401.587752) (xy 127.368972 -401.650831)
			(xy 127.343233 -401.710997) (xy 127.336432 -401.722804) (xy 128.624847 -401.722804) (xy 128.62485 -401.657359)
			(xy 128.633646 -401.592508) (xy 128.651076 -401.529427) (xy 128.676824 -401.46926) (xy 128.693164 -401.440904)
			(xy 128.696474 -401.434877) (xy 128.700083 -401.421615) (xy 128.700276 -401.414742) (xy 128.700276 -400.665442)
			(xy 128.700071 -400.65857) (xy 128.696472 -400.645307) (xy 128.693164 -400.63928) (xy 128.676831 -400.610921)
			(xy 128.651085 -400.550755) (xy 128.633657 -400.487676) (xy 128.624863 -400.422827) (xy 128.624863 -400.357384)
			(xy 128.633655 -400.292534) (xy 128.651082 -400.229454) (xy 128.676826 -400.169288) (xy 128.693164 -400.140932)
			(xy 128.696464 -400.1349) (xy 128.700079 -400.121642) (xy 128.700276 -400.11477) (xy 128.700276 -399.828766)
			(xy 128.700637 -399.818587) (xy 128.70844 -399.799785) (xy 128.722845 -399.7854) (xy 128.741659 -399.777623)
			(xy 128.751838 -399.777204) (xy 129.468118 -399.777204) (xy 129.478273 -399.777718) (xy 129.497036 -399.785492)
			(xy 129.511399 -399.799851) (xy 129.519179 -399.818611) (xy 129.51968 -399.828766) (xy 129.51968 -400.11477)
			(xy 129.519886 -400.121642) (xy 129.523485 -400.134905) (xy 129.526792 -400.140932) (xy 129.543133 -400.169286)
			(xy 129.568875 -400.229453) (xy 129.5863 -400.292534) (xy 129.595092 -400.357384) (xy 129.595091 -400.390106)
			(xy 133.023872 -400.390106) (xy 133.027863 -400.327939) (xy 133.039772 -400.266792) (xy 133.059401 -400.207671)
			(xy 133.08643 -400.151545) (xy 133.120414 -400.099336) (xy 133.160796 -400.051901) (xy 133.206912 -400.01002)
			(xy 133.258004 -399.97438) (xy 133.313235 -399.945566) (xy 133.371697 -399.924052) (xy 133.432431 -399.91019)
			(xy 133.494438 -399.904208) (xy 133.556701 -399.906204) (xy 133.618198 -399.916147) (xy 133.677919 -399.933871)
			(xy 133.734882 -399.959088) (xy 133.788153 -399.991381) (xy 133.836858 -400.030221) (xy 133.880195 -400.074971)
			(xy 133.917455 -400.124895) (xy 133.948024 -400.179174) (xy 133.971402 -400.236917) (xy 133.987203 -400.297175)
			(xy 133.995169 -400.358958) (xy 133.995668 -400.390106) (xy 133.995169 -400.421254) (xy 133.987203 -400.483037)
			(xy 133.971402 -400.543295) (xy 133.948024 -400.601038) (xy 133.917455 -400.655317) (xy 133.880195 -400.705241)
			(xy 133.836858 -400.749991) (xy 133.788153 -400.788831) (xy 133.734882 -400.821124) (xy 133.677919 -400.846341)
			(xy 133.618198 -400.864065) (xy 133.556701 -400.874008) (xy 133.494438 -400.876004) (xy 133.432431 -400.870022)
			(xy 133.371697 -400.85616) (xy 133.313235 -400.834646) (xy 133.258004 -400.805832) (xy 133.206912 -400.770192)
			(xy 133.160796 -400.728311) (xy 133.120414 -400.680876) (xy 133.08643 -400.628667) (xy 133.059401 -400.572541)
			(xy 133.039772 -400.51342) (xy 133.027863 -400.452273) (xy 133.023872 -400.390106) (xy 129.595091 -400.390106)
			(xy 129.595091 -400.422827) (xy 129.586298 -400.487676) (xy 129.568872 -400.550756) (xy 129.543129 -400.610923)
			(xy 129.526792 -400.63928) (xy 129.523484 -400.645308) (xy 129.519874 -400.658569) (xy 129.51968 -400.665442)
			(xy 129.51968 -401.414742) (xy 129.519897 -401.421613) (xy 129.523489 -401.434876) (xy 129.526792 -401.440904)
			(xy 129.54311 -401.469271) (xy 129.568854 -401.529435) (xy 129.586281 -401.592513) (xy 129.595076 -401.657361)
			(xy 129.595078 -401.722802) (xy 129.586289 -401.78765) (xy 129.568866 -401.850729) (xy 129.543127 -401.910896)
			(xy 129.526792 -401.939252) (xy 129.523458 -401.945267) (xy 129.519865 -401.958538) (xy 129.51968 -401.965414)
			(xy 129.51968 -402.251418) (xy 129.519182 -402.261575) (xy 129.511405 -402.280341) (xy 129.497041 -402.294705)
			(xy 129.478275 -402.302482) (xy 129.468118 -402.30298) (xy 128.751838 -402.30298) (xy 128.741671 -402.302505)
			(xy 128.722881 -402.294736) (xy 128.708495 -402.280366) (xy 128.700706 -402.261584) (xy 128.700276 -402.251418)
			(xy 128.700276 -401.965414) (xy 128.700082 -401.958541) (xy 128.696475 -401.945278) (xy 128.693164 -401.939252)
			(xy 128.676807 -401.910906) (xy 128.651064 -401.850738) (xy 128.633638 -401.787655) (xy 128.624847 -401.722804)
			(xy 127.336432 -401.722804) (xy 127.326898 -401.739354) (xy 127.323519 -401.745362) (xy 127.319792 -401.758628)
			(xy 127.319532 -401.765516) (xy 127.319532 -402.514816) (xy 127.319771 -402.521708) (xy 127.323496 -402.53498)
			(xy 127.326898 -402.540978) (xy 127.343194 -402.569357) (xy 127.368939 -402.629519) (xy 127.386369 -402.692594)
			(xy 127.395166 -402.757439) (xy 127.395172 -402.822878) (xy 127.395171 -402.822882) (xy 130.824988 -402.822882)
			(xy 130.824993 -402.757436) (xy 130.833792 -402.692584) (xy 130.851223 -402.629502) (xy 130.876972 -402.569335)
			(xy 130.893312 -402.540978) (xy 130.896635 -402.534958) (xy 130.900235 -402.521691) (xy 130.900424 -402.514816)
			(xy 130.900424 -401.765516) (xy 130.900223 -401.758643) (xy 130.896621 -401.745381) (xy 130.893312 -401.739354)
			(xy 130.876959 -401.711007) (xy 130.851218 -401.650838) (xy 130.833794 -401.587756) (xy 130.825004 -401.522905)
			(xy 130.825006 -401.457461) (xy 130.833801 -401.392611) (xy 130.851229 -401.32953) (xy 130.876974 -401.269362)
			(xy 130.893312 -401.241006) (xy 130.896625 -401.234981) (xy 130.900232 -401.221717) (xy 130.900424 -401.214844)
			(xy 130.900424 -400.92884) (xy 130.900855 -400.918686) (xy 130.908642 -400.899929) (xy 130.923036 -400.885604)
			(xy 130.94183 -400.877907) (xy 130.951986 -400.877532) (xy 131.668266 -400.877532) (xy 131.67839 -400.878054)
			(xy 131.697108 -400.88577) (xy 131.711465 -400.900045) (xy 131.719287 -400.918719) (xy 131.719828 -400.92884)
			(xy 131.719828 -401.214844) (xy 131.720038 -401.221716) (xy 131.723634 -401.234979) (xy 131.72694 -401.241006)
			(xy 131.743261 -401.269371) (xy 131.769008 -401.329536) (xy 131.786437 -401.392614) (xy 131.795232 -401.457462)
			(xy 131.795234 -401.522904) (xy 131.786444 -401.587752) (xy 131.769019 -401.650832) (xy 131.752228 -401.690078)
			(xy 133.023872 -401.690078) (xy 133.027863 -401.627911) (xy 133.039772 -401.566764) (xy 133.059401 -401.507643)
			(xy 133.08643 -401.451517) (xy 133.120414 -401.399308) (xy 133.160796 -401.351873) (xy 133.206912 -401.309992)
			(xy 133.258004 -401.274352) (xy 133.313235 -401.245538) (xy 133.371697 -401.224024) (xy 133.432431 -401.210162)
			(xy 133.494438 -401.20418) (xy 133.556701 -401.206176) (xy 133.618198 -401.216119) (xy 133.677919 -401.233843)
			(xy 133.734882 -401.25906) (xy 133.788153 -401.291353) (xy 133.836858 -401.330193) (xy 133.880195 -401.374943)
			(xy 133.917455 -401.424867) (xy 133.948024 -401.479146) (xy 133.952491 -401.49018) (xy 135.22402 -401.49018)
			(xy 135.228011 -401.428013) (xy 135.23992 -401.366866) (xy 135.259549 -401.307745) (xy 135.286578 -401.251619)
			(xy 135.320562 -401.19941) (xy 135.360944 -401.151975) (xy 135.40706 -401.110094) (xy 135.458152 -401.074454)
			(xy 135.513383 -401.04564) (xy 135.571845 -401.024126) (xy 135.632579 -401.010264) (xy 135.694586 -401.004282)
			(xy 135.756849 -401.006278) (xy 135.818346 -401.016221) (xy 135.878067 -401.033945) (xy 135.93503 -401.059162)
			(xy 135.988301 -401.091455) (xy 136.037006 -401.130295) (xy 136.080343 -401.175045) (xy 136.117603 -401.224969)
			(xy 136.148172 -401.279248) (xy 136.17155 -401.336991) (xy 136.187351 -401.397249) (xy 136.195317 -401.459032)
			(xy 136.195816 -401.49018) (xy 136.195317 -401.521328) (xy 136.187351 -401.583111) (xy 136.17155 -401.643369)
			(xy 136.148172 -401.701112) (xy 136.117603 -401.755391) (xy 136.080343 -401.805315) (xy 136.037006 -401.850065)
			(xy 135.988301 -401.888905) (xy 135.93503 -401.921198) (xy 135.878067 -401.946415) (xy 135.818346 -401.964139)
			(xy 135.756849 -401.974082) (xy 135.694586 -401.976078) (xy 135.632579 -401.970096) (xy 135.571845 -401.956234)
			(xy 135.513383 -401.93472) (xy 135.458152 -401.905906) (xy 135.40706 -401.870266) (xy 135.360944 -401.828385)
			(xy 135.320562 -401.78095) (xy 135.286578 -401.728741) (xy 135.259549 -401.672615) (xy 135.23992 -401.613494)
			(xy 135.228011 -401.552347) (xy 135.22402 -401.49018) (xy 133.952491 -401.49018) (xy 133.971402 -401.536889)
			(xy 133.987203 -401.597147) (xy 133.995169 -401.65893) (xy 133.995668 -401.690078) (xy 133.995169 -401.721226)
			(xy 133.987203 -401.783009) (xy 133.971402 -401.843267) (xy 133.948024 -401.90101) (xy 133.917455 -401.955289)
			(xy 133.880195 -402.005213) (xy 133.836858 -402.049963) (xy 133.788153 -402.088803) (xy 133.734882 -402.121096)
			(xy 133.677919 -402.146313) (xy 133.618198 -402.164037) (xy 133.556701 -402.17398) (xy 133.494438 -402.175976)
			(xy 133.432431 -402.169994) (xy 133.371697 -402.156132) (xy 133.313235 -402.134618) (xy 133.258004 -402.105804)
			(xy 133.206912 -402.070164) (xy 133.160796 -402.028283) (xy 133.120414 -401.980848) (xy 133.08643 -401.928639)
			(xy 133.059401 -401.872513) (xy 133.039772 -401.813392) (xy 133.027863 -401.752245) (xy 133.023872 -401.690078)
			(xy 131.752228 -401.690078) (xy 131.743277 -401.710998) (xy 131.72694 -401.739354) (xy 131.723645 -401.745388)
			(xy 131.720026 -401.758645) (xy 131.719828 -401.765516) (xy 131.719828 -402.514816) (xy 131.720011 -402.52169)
			(xy 131.723625 -402.534953) (xy 131.72694 -402.540978) (xy 131.743237 -402.569356) (xy 131.768986 -402.629518)
			(xy 131.786418 -402.692593) (xy 131.795216 -402.757439) (xy 131.795219 -402.790152) (xy 135.22402 -402.790152)
			(xy 135.228011 -402.727985) (xy 135.23992 -402.666838) (xy 135.259549 -402.607717) (xy 135.286578 -402.551591)
			(xy 135.320562 -402.499382) (xy 135.360944 -402.451947) (xy 135.40706 -402.410066) (xy 135.458152 -402.374426)
			(xy 135.513383 -402.345612) (xy 135.571845 -402.324098) (xy 135.632579 -402.310236) (xy 135.694586 -402.304254)
			(xy 135.756849 -402.30625) (xy 135.818346 -402.316193) (xy 135.878067 -402.333917) (xy 135.93503 -402.359134)
			(xy 135.988301 -402.391427) (xy 136.037006 -402.430267) (xy 136.080343 -402.475017) (xy 136.117603 -402.524941)
			(xy 136.148172 -402.57922) (xy 136.17155 -402.636963) (xy 136.187351 -402.697221) (xy 136.195317 -402.759004)
			(xy 136.195816 -402.790152) (xy 136.195317 -402.8213) (xy 136.187351 -402.883083) (xy 136.17155 -402.943341)
			(xy 136.148172 -403.001084) (xy 136.117603 -403.055363) (xy 136.080343 -403.105287) (xy 136.037006 -403.150037)
			(xy 135.988301 -403.188877) (xy 135.93503 -403.22117) (xy 135.878067 -403.246387) (xy 135.818346 -403.264111)
			(xy 135.756849 -403.274054) (xy 135.694586 -403.27605) (xy 135.632579 -403.270068) (xy 135.571845 -403.256206)
			(xy 135.513383 -403.234692) (xy 135.458152 -403.205878) (xy 135.40706 -403.170238) (xy 135.360944 -403.128357)
			(xy 135.320562 -403.080922) (xy 135.286578 -403.028713) (xy 135.259549 -402.972587) (xy 135.23992 -402.913466)
			(xy 135.228011 -402.852319) (xy 135.22402 -402.790152) (xy 131.795219 -402.790152) (xy 131.795222 -402.822879)
			(xy 131.786434 -402.887726) (xy 131.769013 -402.950804) (xy 131.743275 -403.01097) (xy 131.72694 -403.039326)
			(xy 131.723619 -403.045348) (xy 131.720017 -403.058614) (xy 131.719828 -403.065488) (xy 131.719828 -403.351492)
			(xy 131.719372 -403.361642) (xy 131.711585 -403.380389) (xy 131.697199 -403.394712) (xy 131.678418 -403.402417)
			(xy 131.668266 -403.4028) (xy 130.951986 -403.4028) (xy 130.941863 -403.402286) (xy 130.92315 -403.394561)
			(xy 130.908795 -403.380284) (xy 130.90097 -403.361612) (xy 130.900424 -403.351492) (xy 130.900424 -403.065488)
			(xy 130.900234 -403.058615) (xy 130.896624 -403.045352) (xy 130.893312 -403.039326) (xy 130.876935 -403.010992)
			(xy 130.851196 -402.95082) (xy 130.833775 -402.887735) (xy 130.824988 -402.822882) (xy 127.395171 -402.822882)
			(xy 127.386385 -402.887725) (xy 127.368967 -402.950803) (xy 127.343231 -403.01097) (xy 127.326898 -403.039326)
			(xy 127.323528 -403.045338) (xy 127.319796 -403.058601) (xy 127.319532 -403.065488) (xy 127.319532 -403.351492)
			(xy 127.319009 -403.361596) (xy 127.31128 -403.380268) (xy 127.296995 -403.394562) (xy 127.278328 -403.402303)
			(xy 127.268224 -403.4028) (xy 126.551944 -403.4028) (xy 126.541824 -403.402348) (xy 126.523122 -403.394614)
			(xy 126.508806 -403.380308) (xy 126.501059 -403.361611) (xy 126.500636 -403.351492) (xy 126.500636 -403.065488)
			(xy 126.500399 -403.058596) (xy 126.496673 -403.045323) (xy 126.49327 -403.039326) (xy 126.476891 -403.010993)
			(xy 126.451149 -402.950821) (xy 126.433726 -402.887736) (xy 126.424938 -402.822882) (xy 122.995136 -402.822882)
			(xy 122.986348 -402.887726) (xy 122.968928 -402.950804) (xy 122.94319 -403.01097) (xy 122.926856 -403.039326)
			(xy 122.923536 -403.045348) (xy 122.919933 -403.058614) (xy 122.919744 -403.065488) (xy 122.919744 -403.351492)
			(xy 122.919273 -403.36164) (xy 122.911488 -403.380384) (xy 122.897107 -403.394706) (xy 122.878332 -403.402414)
			(xy 122.868182 -403.4028) (xy 122.151902 -403.4028) (xy 122.14178 -403.402273) (xy 122.123067 -403.394553)
			(xy 122.108712 -403.38028) (xy 122.100886 -403.361611) (xy 122.10034 -403.351492) (xy 122.10034 -403.065488)
			(xy 122.100148 -403.058615) (xy 122.096539 -403.045352) (xy 122.093228 -403.039326) (xy 122.07685 -403.010992)
			(xy 122.051111 -402.95082) (xy 122.033689 -402.887735) (xy 122.024902 -402.822882) (xy 118.595099 -402.822882)
			(xy 118.586312 -402.887726) (xy 118.56889 -402.950805) (xy 118.54315 -403.01097) (xy 118.526814 -403.039326)
			(xy 118.523446 -403.045339) (xy 118.519712 -403.058601) (xy 118.519448 -403.065488) (xy 118.519448 -403.351492)
			(xy 118.51891 -403.361594) (xy 118.511183 -403.380263) (xy 118.496903 -403.394557) (xy 118.478242 -403.4023)
			(xy 118.46814 -403.4028) (xy 117.75186 -403.4028) (xy 117.741749 -403.402348) (xy 117.72307 -403.394597)
			(xy 117.708776 -403.38029) (xy 117.701043 -403.361604) (xy 117.700552 -403.351492) (xy 117.700552 -403.065488)
			(xy 117.700313 -403.058596) (xy 117.696589 -403.045324) (xy 117.693186 -403.039326) (xy 117.676806 -403.010993)
			(xy 117.651064 -402.950821) (xy 117.63364 -402.887736) (xy 117.624851 -402.822882) (xy 94.135448 -402.822882)
			(xy 94.135448 -405.622717) (xy 115.424981 -405.622717) (xy 115.424981 -405.557273) (xy 115.433776 -405.492422)
			(xy 115.451205 -405.429342) (xy 115.476953 -405.369176) (xy 115.493292 -405.34082) (xy 115.496599 -405.334792)
			(xy 115.50021 -405.321531) (xy 115.500404 -405.314658) (xy 115.500404 -404.565358) (xy 115.500189 -404.558486)
			(xy 115.496596 -404.545224) (xy 115.493292 -404.539196) (xy 115.476972 -404.51083) (xy 115.451223 -404.450666)
			(xy 115.433793 -404.387588) (xy 115.424997 -404.32274) (xy 115.424994 -404.257298) (xy 115.433785 -404.192449)
			(xy 115.451211 -404.129369) (xy 115.476954 -404.069204) (xy 115.493292 -404.040848) (xy 115.496625 -404.034832)
			(xy 115.500219 -404.021562) (xy 115.500404 -404.014686) (xy 115.500404 -403.728682) (xy 115.500918 -403.718527)
			(xy 115.508692 -403.699764) (xy 115.523051 -403.685401) (xy 115.541811 -403.677621) (xy 115.551966 -403.67712)
			(xy 116.268246 -403.67712) (xy 116.278404 -403.677595) (xy 116.297171 -403.685382) (xy 116.311534 -403.699752)
			(xy 116.31931 -403.718523) (xy 116.319808 -403.728682) (xy 116.319808 -404.014686) (xy 116.320005 -404.021559)
			(xy 116.32361 -404.034822) (xy 116.32692 -404.040848) (xy 116.343277 -404.069193) (xy 116.369022 -404.129362)
			(xy 116.386448 -404.192445) (xy 116.395239 -404.257296) (xy 116.395236 -404.322741) (xy 116.38644 -404.387592)
			(xy 116.369009 -404.450673) (xy 116.34326 -404.51084) (xy 116.32692 -404.539196) (xy 116.323608 -404.545222)
			(xy 116.32 -404.558485) (xy 116.319808 -404.565358) (xy 116.319808 -405.314658) (xy 116.320015 -405.32153)
			(xy 116.323613 -405.334793) (xy 116.32692 -405.34082) (xy 116.343254 -405.369179) (xy 116.369 -405.429344)
			(xy 116.386429 -405.492424) (xy 116.395223 -405.557273) (xy 116.395224 -405.622716) (xy 116.386431 -405.687566)
			(xy 116.369004 -405.750646) (xy 116.343258 -405.810812) (xy 116.32692 -405.839168) (xy 116.323618 -405.845199)
			(xy 116.320004 -405.858458) (xy 116.319808 -405.86533) (xy 116.319808 -406.151334) (xy 116.319296 -406.161488)
			(xy 116.311519 -406.180249) (xy 116.297159 -406.194612) (xy 116.2784 -406.202393) (xy 116.268246 -406.202896)
			(xy 115.551966 -406.202896) (xy 115.54181 -406.202395) (xy 115.523047 -406.194616) (xy 115.508684 -406.180253)
			(xy 115.500905 -406.16149) (xy 115.500404 -406.151334) (xy 115.500404 -405.86533) (xy 115.5002 -405.858458)
			(xy 115.4966 -405.845195) (xy 115.493292 -405.839168) (xy 115.476948 -405.810815) (xy 115.451202 -405.750648)
			(xy 115.433774 -405.687567) (xy 115.424981 -405.622717) (xy 94.135448 -405.622717) (xy 94.135448 -406.722795)
			(xy 117.624861 -406.722795) (xy 117.624864 -406.65735) (xy 117.633662 -406.592498) (xy 117.651094 -406.529417)
			(xy 117.676845 -406.46925) (xy 117.693186 -406.440894) (xy 117.696547 -406.434877) (xy 117.700286 -406.421618)
			(xy 117.700552 -406.414732) (xy 117.700552 -405.665432) (xy 117.700335 -405.658538) (xy 117.696596 -405.645266)
			(xy 117.693186 -405.63927) (xy 117.676844 -405.610916) (xy 117.651098 -405.550749) (xy 117.63367 -405.487669)
			(xy 117.624877 -405.422818) (xy 117.624877 -405.357375) (xy 117.633671 -405.292524) (xy 117.6511 -405.229444)
			(xy 117.676847 -405.169278) (xy 117.693186 -405.140922) (xy 117.696538 -405.134901) (xy 117.700282 -405.121645)
			(xy 117.700552 -405.11476) (xy 117.700552 -404.828756) (xy 117.701048 -404.81865) (xy 117.708791 -404.79998)
			(xy 117.723084 -404.785689) (xy 117.741754 -404.777947) (xy 117.75186 -404.777448) (xy 118.46814 -404.777448)
			(xy 118.478245 -404.777951) (xy 118.496914 -404.785692) (xy 118.511206 -404.799983) (xy 118.518948 -404.818651)
			(xy 118.519448 -404.828756) (xy 118.519448 -405.11476) (xy 118.519668 -405.121654) (xy 118.523405 -405.134926)
			(xy 118.526814 -405.140922) (xy 118.543149 -405.16928) (xy 118.568896 -405.229445) (xy 118.586325 -405.292525)
			(xy 118.595119 -405.357375) (xy 118.595119 -405.422818) (xy 118.586326 -405.487668) (xy 118.568898 -405.550748)
			(xy 118.543153 -405.610914) (xy 118.536352 -405.622717) (xy 119.825031 -405.622717) (xy 119.825031 -405.557273)
			(xy 119.833825 -405.492423) (xy 119.851252 -405.429343) (xy 119.876996 -405.369176) (xy 119.893334 -405.34082)
			(xy 119.89669 -405.334801) (xy 119.900431 -405.321544) (xy 119.9007 -405.314658) (xy 119.9007 -404.565358)
			(xy 119.900444 -404.558468) (xy 119.896717 -404.545202) (xy 119.893334 -404.539196) (xy 119.877015 -404.510829)
			(xy 119.85127 -404.450665) (xy 119.833842 -404.387587) (xy 119.825047 -404.32274) (xy 119.825044 -404.257298)
			(xy 119.833834 -404.19245) (xy 119.851258 -404.129371) (xy 119.876998 -404.069204) (xy 119.893334 -404.040848)
			(xy 119.896715 -404.034841) (xy 119.90044 -404.021575) (xy 119.9007 -404.014686) (xy 119.9007 -403.728682)
			(xy 119.90121 -403.718559) (xy 119.908937 -403.699845) (xy 119.923215 -403.685491) (xy 119.941888 -403.677665)
			(xy 119.952008 -403.67712) (xy 120.668288 -403.67712) (xy 120.678444 -403.677532) (xy 120.6972 -403.685327)
			(xy 120.711524 -403.699727) (xy 120.719221 -403.718524) (xy 120.719596 -403.728682) (xy 120.719596 -404.014686)
			(xy 120.719835 -404.021577) (xy 120.723574 -404.034843) (xy 120.726962 -404.040848) (xy 120.743318 -404.069194)
			(xy 120.76906 -404.129363) (xy 120.786484 -404.192445) (xy 120.795275 -404.257297) (xy 120.795273 -404.322741)
			(xy 120.786477 -404.387592) (xy 120.769048 -404.450673) (xy 120.743301 -404.51084) (xy 120.726962 -404.539196)
			(xy 120.7236 -404.545212) (xy 120.719863 -404.558472) (xy 120.719596 -404.565358) (xy 120.719596 -405.314658)
			(xy 120.719846 -405.321548) (xy 120.723577 -405.334814) (xy 120.726962 -405.34082) (xy 120.743294 -405.369179)
			(xy 120.769039 -405.429345) (xy 120.786466 -405.492425) (xy 120.795259 -405.557274) (xy 120.79526 -405.622716)
			(xy 120.786468 -405.687565) (xy 120.769042 -405.750645) (xy 120.743299 -405.810812) (xy 120.726962 -405.839168)
			(xy 120.72361 -405.845189) (xy 120.719867 -405.858445) (xy 120.719596 -405.86533) (xy 120.719596 -406.151334)
			(xy 120.719102 -406.161458) (xy 120.71137 -406.180174) (xy 120.697087 -406.194527) (xy 120.67841 -406.202352)
			(xy 120.668288 -406.202896) (xy 119.952008 -406.202896) (xy 119.941854 -406.202472) (xy 119.923101 -406.194678)
			(xy 119.908777 -406.180282) (xy 119.901078 -406.16149) (xy 119.9007 -406.151334) (xy 119.9007 -405.86533)
			(xy 119.900455 -405.85844) (xy 119.896721 -405.845174) (xy 119.893334 -405.839168) (xy 119.876992 -405.810815)
			(xy 119.851249 -405.750647) (xy 119.833823 -405.687567) (xy 119.825031 -405.622717) (xy 118.536352 -405.622717)
			(xy 118.526814 -405.63927) (xy 118.523465 -405.645293) (xy 118.519719 -405.658547) (xy 118.519448 -405.665432)
			(xy 118.519448 -406.414732) (xy 118.519679 -406.421625) (xy 118.523409 -406.434897) (xy 118.526814 -406.440894)
			(xy 118.543126 -406.469265) (xy 118.568875 -406.529427) (xy 118.586306 -406.592505) (xy 118.595103 -406.657352)
			(xy 118.595107 -406.722793) (xy 118.595107 -406.722795) (xy 122.024911 -406.722795) (xy 122.024914 -406.65735)
			(xy 122.033711 -406.592499) (xy 122.051141 -406.529418) (xy 122.076889 -406.46925) (xy 122.093228 -406.440894)
			(xy 122.096547 -406.434871) (xy 122.100149 -406.421606) (xy 122.10034 -406.414732) (xy 122.10034 -405.665432)
			(xy 122.100131 -405.65856) (xy 122.096534 -405.645297) (xy 122.093228 -405.63927) (xy 122.076888 -405.610916)
			(xy 122.051145 -405.550748) (xy 122.033719 -405.487668) (xy 122.024927 -405.422818) (xy 122.024927 -405.357375)
			(xy 122.03372 -405.292525) (xy 122.051147 -405.229445) (xy 122.076891 -405.169278) (xy 122.093228 -405.140922)
			(xy 122.096537 -405.134895) (xy 122.100146 -405.121633) (xy 122.10034 -405.11476) (xy 122.10034 -404.828756)
			(xy 122.100686 -404.818594) (xy 122.108504 -404.799833) (xy 122.122924 -404.78551) (xy 122.141737 -404.777819)
			(xy 122.151902 -404.777448) (xy 122.868182 -404.777448) (xy 122.878309 -404.777941) (xy 122.897031 -404.785665)
			(xy 122.911388 -404.799949) (xy 122.919207 -404.818632) (xy 122.919744 -404.828756) (xy 122.919744 -405.11476)
			(xy 122.919946 -405.121633) (xy 122.923547 -405.134896) (xy 122.926856 -405.140922) (xy 122.94319 -405.16928)
			(xy 122.968935 -405.229446) (xy 122.986362 -405.292526) (xy 122.995155 -405.357375) (xy 122.995156 -405.422818)
			(xy 122.986363 -405.487667) (xy 122.968937 -405.550747) (xy 122.943193 -405.610914) (xy 122.936393 -405.622717)
			(xy 124.225067 -405.622717) (xy 124.225067 -405.557273) (xy 124.233862 -405.492423) (xy 124.25129 -405.429342)
			(xy 124.277037 -405.369176) (xy 124.293376 -405.34082) (xy 124.296682 -405.334791) (xy 124.300294 -405.321531)
			(xy 124.300488 -405.314658) (xy 124.300488 -404.565358) (xy 124.300275 -404.558486) (xy 124.296681 -404.545223)
			(xy 124.293376 -404.539196) (xy 124.277056 -404.51083) (xy 124.251309 -404.450666) (xy 124.233879 -404.387588)
			(xy 124.225083 -404.32274) (xy 124.22508 -404.257298) (xy 124.233871 -404.192449) (xy 124.251296 -404.12937)
			(xy 124.277039 -404.069204) (xy 124.293376 -404.040848) (xy 124.296708 -404.034832) (xy 124.300303 -404.021562)
			(xy 124.300488 -404.014686) (xy 124.300488 -403.728682) (xy 124.30085 -403.718503) (xy 124.308651 -403.699698)
			(xy 124.323056 -403.685313) (xy 124.34187 -403.677537) (xy 124.35205 -403.67712) (xy 125.06833 -403.67712)
			(xy 125.078487 -403.677608) (xy 125.097254 -403.685389) (xy 125.111617 -403.699756) (xy 125.119394 -403.718524)
			(xy 125.119892 -403.728682) (xy 125.119892 -404.014686) (xy 125.12009 -404.021559) (xy 125.123694 -404.034822)
			(xy 125.127004 -404.040848) (xy 125.143359 -404.069194) (xy 125.169099 -404.129364) (xy 125.186521 -404.192446)
			(xy 125.195311 -404.257297) (xy 125.195309 -404.322741) (xy 125.186514 -404.387591) (xy 125.169086 -404.450672)
			(xy 125.143341 -404.510839) (xy 125.127004 -404.539196) (xy 125.123691 -404.545221) (xy 125.120084 -404.558485)
			(xy 125.119892 -404.565358) (xy 125.119892 -405.314658) (xy 125.120101 -405.32153) (xy 125.123698 -405.334793)
			(xy 125.127004 -405.34082) (xy 125.143335 -405.369179) (xy 125.169077 -405.429346) (xy 125.186502 -405.492425)
			(xy 125.195295 -405.557274) (xy 125.195296 -405.622716) (xy 125.186505 -405.687565) (xy 125.16908 -405.750644)
			(xy 125.14334 -405.810811) (xy 125.127004 -405.839168) (xy 125.123701 -405.845198) (xy 125.120088 -405.858458)
			(xy 125.119892 -405.86533) (xy 125.119892 -406.151334) (xy 125.119395 -406.16149) (xy 125.111615 -406.180254)
			(xy 125.097251 -406.194617) (xy 125.078486 -406.202396) (xy 125.06833 -406.202896) (xy 124.35205 -406.202896)
			(xy 124.341886 -406.202396) (xy 124.323099 -406.194634) (xy 124.308713 -406.180272) (xy 124.30092 -406.161497)
			(xy 124.300488 -406.151334) (xy 124.300488 -405.86533) (xy 124.300286 -405.858458) (xy 124.296685 -405.845195)
			(xy 124.293376 -405.839168) (xy 124.277032 -405.810815) (xy 124.251287 -405.750648) (xy 124.23386 -405.687567)
			(xy 124.225067 -405.622717) (xy 122.936393 -405.622717) (xy 122.926856 -405.63927) (xy 122.923556 -405.645302)
			(xy 122.91994 -405.65856) (xy 122.919744 -405.665432) (xy 122.919744 -406.414732) (xy 122.919918 -406.421607)
			(xy 122.923538 -406.43487) (xy 122.926856 -406.440894) (xy 122.943166 -406.469265) (xy 122.968913 -406.529428)
			(xy 122.986343 -406.592505) (xy 122.995139 -406.657352) (xy 122.995143 -406.722793) (xy 122.995143 -406.722795)
			(xy 126.424947 -406.722795) (xy 126.42495 -406.65735) (xy 126.433748 -406.592498) (xy 126.45118 -406.529417)
			(xy 126.47693 -406.46925) (xy 126.49327 -406.440894) (xy 126.496638 -406.434881) (xy 126.500371 -406.421619)
			(xy 126.500636 -406.414732) (xy 126.500636 -405.665432) (xy 126.500421 -405.658538) (xy 126.496681 -405.645266)
			(xy 126.49327 -405.63927) (xy 126.476928 -405.610916) (xy 126.451183 -405.550749) (xy 126.433756 -405.487669)
			(xy 126.424963 -405.422818) (xy 126.424963 -405.357375) (xy 126.433757 -405.292525) (xy 126.451185 -405.229444)
			(xy 126.476931 -405.169278) (xy 126.49327 -405.140922) (xy 126.496628 -405.134904) (xy 126.500367 -405.121646)
			(xy 126.500636 -405.11476) (xy 126.500636 -404.828756) (xy 126.50105 -404.81864) (xy 126.508809 -404.799954)
			(xy 126.523128 -404.785659) (xy 126.541827 -404.777933) (xy 126.551944 -404.777448) (xy 127.268224 -404.777448)
			(xy 127.278328 -404.777964) (xy 127.296997 -404.7857) (xy 127.311289 -404.799986) (xy 127.319032 -404.818652)
			(xy 127.319532 -404.828756) (xy 127.319532 -405.11476) (xy 127.319755 -405.121654) (xy 127.32349 -405.134925)
			(xy 127.326898 -405.140922) (xy 127.343231 -405.16928) (xy 127.368973 -405.229447) (xy 127.386399 -405.292527)
			(xy 127.395191 -405.357375) (xy 127.395192 -405.422818) (xy 127.3864 -405.487667) (xy 127.368975 -405.550746)
			(xy 127.343234 -405.610913) (xy 127.336434 -405.622717) (xy 128.624856 -405.622717) (xy 128.624857 -405.557273)
			(xy 128.633651 -405.492423) (xy 128.651079 -405.429343) (xy 128.676825 -405.369176) (xy 128.693164 -405.34082)
			(xy 128.696469 -405.33479) (xy 128.700081 -405.321531) (xy 128.700276 -405.314658) (xy 128.700276 -404.565358)
			(xy 128.700065 -404.558486) (xy 128.69647 -404.545223) (xy 128.693164 -404.539196) (xy 128.676845 -404.51083)
			(xy 128.651098 -404.450666) (xy 128.633668 -404.387588) (xy 128.624872 -404.32274) (xy 128.62487 -404.257298)
			(xy 128.633661 -404.192449) (xy 128.651085 -404.12937) (xy 128.676827 -404.069204) (xy 128.693164 -404.040848)
			(xy 128.696494 -404.034831) (xy 128.70009 -404.021561) (xy 128.700276 -404.014686) (xy 128.700276 -403.728682)
			(xy 128.70065 -403.718505) (xy 128.708448 -403.699702) (xy 128.722849 -403.685317) (xy 128.74166 -403.677539)
			(xy 128.751838 -403.67712) (xy 129.468118 -403.67712) (xy 129.478275 -403.677618) (xy 129.497041 -403.685395)
			(xy 129.511405 -403.699759) (xy 129.519182 -403.718525) (xy 129.51968 -403.728682) (xy 129.51968 -404.014686)
			(xy 129.51988 -404.021559) (xy 129.523483 -404.034821) (xy 129.526792 -404.040848) (xy 129.543147 -404.069194)
			(xy 129.568888 -404.129364) (xy 129.586311 -404.192446) (xy 129.595101 -404.257297) (xy 129.595099 -404.290022)
			(xy 133.023872 -404.290022) (xy 133.027863 -404.227855) (xy 133.039772 -404.166708) (xy 133.059401 -404.107587)
			(xy 133.08643 -404.051461) (xy 133.120414 -403.999252) (xy 133.160796 -403.951817) (xy 133.206912 -403.909936)
			(xy 133.258004 -403.874296) (xy 133.313235 -403.845482) (xy 133.371697 -403.823968) (xy 133.432431 -403.810106)
			(xy 133.494438 -403.804124) (xy 133.556701 -403.80612) (xy 133.618198 -403.816063) (xy 133.677919 -403.833787)
			(xy 133.734882 -403.859004) (xy 133.788153 -403.891297) (xy 133.836858 -403.930137) (xy 133.880195 -403.974887)
			(xy 133.917455 -404.024811) (xy 133.948024 -404.07909) (xy 133.971402 -404.136833) (xy 133.987203 -404.197091)
			(xy 133.995169 -404.258874) (xy 133.995668 -404.290022) (xy 133.995169 -404.32117) (xy 133.987203 -404.382953)
			(xy 133.971402 -404.443211) (xy 133.948024 -404.500954) (xy 133.917455 -404.555233) (xy 133.880195 -404.605157)
			(xy 133.836858 -404.649907) (xy 133.788153 -404.688747) (xy 133.734882 -404.72104) (xy 133.677919 -404.746257)
			(xy 133.618198 -404.763981) (xy 133.556701 -404.773924) (xy 133.494438 -404.77592) (xy 133.432431 -404.769938)
			(xy 133.371697 -404.756076) (xy 133.313235 -404.734562) (xy 133.258004 -404.705748) (xy 133.206912 -404.670108)
			(xy 133.160796 -404.628227) (xy 133.120414 -404.580792) (xy 133.08643 -404.528583) (xy 133.059401 -404.472457)
			(xy 133.039772 -404.413336) (xy 133.027863 -404.352189) (xy 133.023872 -404.290022) (xy 129.595099 -404.290022)
			(xy 129.595098 -404.322741) (xy 129.586303 -404.387591) (xy 129.568875 -404.450672) (xy 129.54313 -404.510839)
			(xy 129.526792 -404.539196) (xy 129.523478 -404.545221) (xy 129.519872 -404.558484) (xy 129.51968 -404.565358)
			(xy 129.51968 -405.314658) (xy 129.51989 -405.32153) (xy 129.523486 -405.334793) (xy 129.526792 -405.34082)
			(xy 129.543123 -405.369179) (xy 129.568866 -405.429346) (xy 129.586292 -405.492425) (xy 129.595085 -405.557274)
			(xy 129.595086 -405.622716) (xy 129.586294 -405.687565) (xy 129.568869 -405.750645) (xy 129.543128 -405.810812)
			(xy 129.526792 -405.839168) (xy 129.523488 -405.845198) (xy 129.519876 -405.858458) (xy 129.51968 -405.86533)
			(xy 129.51968 -406.151334) (xy 129.519195 -406.161492) (xy 129.511413 -406.180258) (xy 129.497045 -406.194622)
			(xy 129.478276 -406.202398) (xy 129.468118 -406.202896) (xy 128.751838 -406.202896) (xy 128.741673 -406.202406)
			(xy 128.722886 -406.19464) (xy 128.708501 -406.180275) (xy 128.700708 -406.161498) (xy 128.700276 -406.151334)
			(xy 128.700276 -405.86533) (xy 128.700075 -405.858457) (xy 128.696473 -405.845194) (xy 128.693164 -405.839168)
			(xy 128.676821 -405.810815) (xy 128.651076 -405.750648) (xy 128.633649 -405.687567) (xy 128.624856 -405.622717)
			(xy 127.336434 -405.622717) (xy 127.326898 -405.63927) (xy 127.323548 -405.645292) (xy 127.319803 -405.658547)
			(xy 127.319532 -405.665432) (xy 127.319532 -406.414732) (xy 127.319765 -406.421625) (xy 127.323494 -406.434897)
			(xy 127.326898 -406.440894) (xy 127.343207 -406.469266) (xy 127.368952 -406.529429) (xy 127.38638 -406.592506)
			(xy 127.395175 -406.657352) (xy 127.395179 -406.722793) (xy 127.395179 -406.722795) (xy 130.824997 -406.722795)
			(xy 130.825001 -406.65735) (xy 130.833797 -406.592499) (xy 130.851227 -406.529418) (xy 130.876973 -406.469251)
			(xy 130.893312 -406.440894) (xy 130.89663 -406.434871) (xy 130.900233 -406.421606) (xy 130.900424 -406.414732)
			(xy 130.900424 -405.665432) (xy 130.900217 -405.65856) (xy 130.896619 -405.645297) (xy 130.893312 -405.63927)
			(xy 130.876972 -405.610915) (xy 130.85123 -405.550748) (xy 130.833805 -405.487668) (xy 130.825013 -405.422818)
			(xy 130.825013 -405.357375) (xy 130.833806 -405.292526) (xy 130.851232 -405.229445) (xy 130.876975 -405.169278)
			(xy 130.893312 -405.140922) (xy 130.89662 -405.134894) (xy 130.90023 -405.121633) (xy 130.900424 -405.11476)
			(xy 130.900424 -404.828756) (xy 130.900786 -404.818596) (xy 130.908601 -404.799838) (xy 130.923016 -404.785515)
			(xy 130.941823 -404.777822) (xy 130.951986 -404.777448) (xy 131.668266 -404.777448) (xy 131.678391 -404.777955)
			(xy 131.697113 -404.785673) (xy 131.711471 -404.799953) (xy 131.71929 -404.818633) (xy 131.719828 -404.828756)
			(xy 131.719828 -405.11476) (xy 131.720032 -405.121632) (xy 131.723632 -405.134895) (xy 131.72694 -405.140922)
			(xy 131.743275 -405.16928) (xy 131.76902 -405.229446) (xy 131.786448 -405.292526) (xy 131.795241 -405.357375)
			(xy 131.795242 -405.422818) (xy 131.786449 -405.487668) (xy 131.769022 -405.550748) (xy 131.752229 -405.589994)
			(xy 133.023872 -405.589994) (xy 133.027863 -405.527827) (xy 133.039772 -405.46668) (xy 133.059401 -405.407559)
			(xy 133.08643 -405.351433) (xy 133.120414 -405.299224) (xy 133.160796 -405.251789) (xy 133.206912 -405.209908)
			(xy 133.258004 -405.174268) (xy 133.313235 -405.145454) (xy 133.371697 -405.12394) (xy 133.432431 -405.110078)
			(xy 133.494438 -405.104096) (xy 133.556701 -405.106092) (xy 133.618198 -405.116035) (xy 133.677919 -405.133759)
			(xy 133.734882 -405.158976) (xy 133.788153 -405.191269) (xy 133.836858 -405.230109) (xy 133.880195 -405.274859)
			(xy 133.917455 -405.324783) (xy 133.948024 -405.379062) (xy 133.952491 -405.390096) (xy 135.22402 -405.390096)
			(xy 135.228011 -405.327929) (xy 135.23992 -405.266782) (xy 135.259549 -405.207661) (xy 135.286578 -405.151535)
			(xy 135.320562 -405.099326) (xy 135.360944 -405.051891) (xy 135.40706 -405.01001) (xy 135.458152 -404.97437)
			(xy 135.513383 -404.945556) (xy 135.571845 -404.924042) (xy 135.632579 -404.91018) (xy 135.694586 -404.904198)
			(xy 135.756849 -404.906194) (xy 135.818346 -404.916137) (xy 135.878067 -404.933861) (xy 135.93503 -404.959078)
			(xy 135.988301 -404.991371) (xy 136.037006 -405.030211) (xy 136.080343 -405.074961) (xy 136.117603 -405.124885)
			(xy 136.148172 -405.179164) (xy 136.17155 -405.236907) (xy 136.187351 -405.297165) (xy 136.195317 -405.358948)
			(xy 136.195816 -405.390096) (xy 136.195317 -405.421244) (xy 136.187351 -405.483027) (xy 136.17155 -405.543285)
			(xy 136.148172 -405.601028) (xy 136.117603 -405.655307) (xy 136.080343 -405.705231) (xy 136.037006 -405.749981)
			(xy 135.988301 -405.788821) (xy 135.93503 -405.821114) (xy 135.878067 -405.846331) (xy 135.818346 -405.864055)
			(xy 135.756849 -405.873998) (xy 135.694586 -405.875994) (xy 135.632579 -405.870012) (xy 135.571845 -405.85615)
			(xy 135.513383 -405.834636) (xy 135.458152 -405.805822) (xy 135.40706 -405.770182) (xy 135.360944 -405.728301)
			(xy 135.320562 -405.680866) (xy 135.286578 -405.628657) (xy 135.259549 -405.572531) (xy 135.23992 -405.51341)
			(xy 135.228011 -405.452263) (xy 135.22402 -405.390096) (xy 133.952491 -405.390096) (xy 133.971402 -405.436805)
			(xy 133.987203 -405.497063) (xy 133.995169 -405.558846) (xy 133.995668 -405.589994) (xy 133.995169 -405.621142)
			(xy 133.987203 -405.682925) (xy 133.971402 -405.743183) (xy 133.948024 -405.800926) (xy 133.917455 -405.855205)
			(xy 133.880195 -405.905129) (xy 133.836858 -405.949879) (xy 133.788153 -405.988719) (xy 133.734882 -406.021012)
			(xy 133.677919 -406.046229) (xy 133.618198 -406.063953) (xy 133.556701 -406.073896) (xy 133.494438 -406.075892)
			(xy 133.432431 -406.06991) (xy 133.371697 -406.056048) (xy 133.313235 -406.034534) (xy 133.258004 -406.00572)
			(xy 133.206912 -405.97008) (xy 133.160796 -405.928199) (xy 133.120414 -405.880764) (xy 133.08643 -405.828555)
			(xy 133.059401 -405.772429) (xy 133.039772 -405.713308) (xy 133.027863 -405.652161) (xy 133.023872 -405.589994)
			(xy 131.752229 -405.589994) (xy 131.743278 -405.610914) (xy 131.72694 -405.63927) (xy 131.723639 -405.645302)
			(xy 131.720024 -405.65856) (xy 131.719828 -405.665432) (xy 131.719828 -406.414732) (xy 131.720004 -406.421606)
			(xy 131.723623 -406.434869) (xy 131.72694 -406.440894) (xy 131.743251 -406.469265) (xy 131.768998 -406.529428)
			(xy 131.786429 -406.592505) (xy 131.795225 -406.657352) (xy 131.795227 -406.690068) (xy 135.22402 -406.690068)
			(xy 135.228011 -406.627901) (xy 135.23992 -406.566754) (xy 135.259549 -406.507633) (xy 135.286578 -406.451507)
			(xy 135.320562 -406.399298) (xy 135.360944 -406.351863) (xy 135.40706 -406.309982) (xy 135.458152 -406.274342)
			(xy 135.513383 -406.245528) (xy 135.571845 -406.224014) (xy 135.632579 -406.210152) (xy 135.694586 -406.20417)
			(xy 135.756849 -406.206166) (xy 135.818346 -406.216109) (xy 135.878067 -406.233833) (xy 135.93503 -406.25905)
			(xy 135.988301 -406.291343) (xy 136.037006 -406.330183) (xy 136.080343 -406.374933) (xy 136.117603 -406.424857)
			(xy 136.148172 -406.479136) (xy 136.17155 -406.536879) (xy 136.187351 -406.597137) (xy 136.195317 -406.65892)
			(xy 136.195816 -406.690068) (xy 136.195317 -406.721216) (xy 136.187351 -406.782999) (xy 136.17155 -406.843257)
			(xy 136.148172 -406.901) (xy 136.117603 -406.955279) (xy 136.080343 -407.005203) (xy 136.037006 -407.049953)
			(xy 135.988301 -407.088793) (xy 135.93503 -407.121086) (xy 135.878067 -407.146303) (xy 135.818346 -407.164027)
			(xy 135.756849 -407.17397) (xy 135.694586 -407.175966) (xy 135.632579 -407.169984) (xy 135.571845 -407.156122)
			(xy 135.513383 -407.134608) (xy 135.458152 -407.105794) (xy 135.40706 -407.070154) (xy 135.360944 -407.028273)
			(xy 135.320562 -406.980838) (xy 135.286578 -406.928629) (xy 135.259549 -406.872503) (xy 135.23992 -406.813382)
			(xy 135.228011 -406.752235) (xy 135.22402 -406.690068) (xy 131.795227 -406.690068) (xy 131.795229 -406.722793)
			(xy 131.78644 -406.787641) (xy 131.769017 -406.85072) (xy 131.743276 -406.910886) (xy 131.72694 -406.939242)
			(xy 131.723614 -406.945261) (xy 131.720015 -406.958529) (xy 131.719828 -406.965404) (xy 131.719828 -407.251408)
			(xy 131.719385 -407.261559) (xy 131.711592 -407.280306) (xy 131.697203 -407.294628) (xy 131.678419 -407.302333)
			(xy 131.668266 -407.302716) (xy 130.951986 -407.302716) (xy 130.941853 -407.302283) (xy 130.923123 -407.294543)
			(xy 130.908766 -407.28024) (xy 130.900955 -407.261539) (xy 130.900424 -407.251408) (xy 130.900424 -406.965404)
			(xy 130.900228 -406.958531) (xy 130.896622 -406.945268) (xy 130.893312 -406.939242) (xy 130.876948 -406.910901)
			(xy 130.851208 -406.85073) (xy 130.833786 -406.787647) (xy 130.824997 -406.722795) (xy 127.395179 -406.722795)
			(xy 127.386391 -406.78764) (xy 127.36897 -406.850719) (xy 127.343232 -406.910885) (xy 127.326898 -406.939242)
			(xy 127.323523 -406.945252) (xy 127.319794 -406.958516) (xy 127.319532 -406.965404) (xy 127.319532 -407.251408)
			(xy 127.319022 -407.261513) (xy 127.311288 -407.280185) (xy 127.296999 -407.294479) (xy 127.278329 -407.302219)
			(xy 127.268224 -407.302716) (xy 126.551944 -407.302716) (xy 126.541826 -407.302248) (xy 126.523127 -407.294518)
			(xy 126.508812 -407.280217) (xy 126.501062 -407.261525) (xy 126.500636 -407.251408) (xy 126.500636 -406.965404)
			(xy 126.500432 -406.958509) (xy 126.496684 -406.945237) (xy 126.49327 -406.939242) (xy 126.476905 -406.910901)
			(xy 126.451162 -406.850731) (xy 126.433737 -406.787648) (xy 126.424947 -406.722795) (xy 122.995143 -406.722795)
			(xy 122.986354 -406.787641) (xy 122.968931 -406.85072) (xy 122.943191 -406.910886) (xy 122.926856 -406.939242)
			(xy 122.923531 -406.945262) (xy 122.919931 -406.958529) (xy 122.919744 -406.965404) (xy 122.919744 -407.251408)
			(xy 122.919286 -407.261557) (xy 122.911496 -407.280301) (xy 122.897111 -407.294623) (xy 122.878333 -407.30233)
			(xy 122.868182 -407.302716) (xy 122.151902 -407.302716) (xy 122.14177 -407.30227) (xy 122.123041 -407.294535)
			(xy 122.108683 -407.280236) (xy 122.100871 -407.261538) (xy 122.10034 -407.251408) (xy 122.10034 -406.965404)
			(xy 122.100141 -406.958531) (xy 122.096537 -406.945269) (xy 122.093228 -406.939242) (xy 122.076864 -406.910901)
			(xy 122.051123 -406.85073) (xy 122.0337 -406.787647) (xy 122.024911 -406.722795) (xy 118.595107 -406.722795)
			(xy 118.586317 -406.787642) (xy 118.568893 -406.850721) (xy 118.543151 -406.910886) (xy 118.526814 -406.939242)
			(xy 118.52344 -406.945252) (xy 118.51971 -406.958516) (xy 118.519448 -406.965404) (xy 118.519448 -407.251408)
			(xy 118.518922 -407.261511) (xy 118.511191 -407.28018) (xy 118.496907 -407.294473) (xy 118.478243 -407.302216)
			(xy 118.46814 -407.302716) (xy 117.75186 -407.302716) (xy 117.741751 -407.302248) (xy 117.723075 -407.2945)
			(xy 117.708782 -407.280198) (xy 117.701046 -407.261518) (xy 117.700552 -407.251408) (xy 117.700552 -406.965404)
			(xy 117.700345 -406.958509) (xy 117.696599 -406.945237) (xy 117.693186 -406.939242) (xy 117.67682 -406.910901)
			(xy 117.651076 -406.850732) (xy 117.633651 -406.787648) (xy 117.624861 -406.722795) (xy 94.135448 -406.722795)
			(xy 94.135448 -409.109926) (xy 94.134994 -409.153069) (xy 94.127479 -409.239026) (xy 94.1125 -409.324001)
			(xy 94.090171 -409.407347) (xy 94.060662 -409.488429) (xy 94.044592 -409.522892) (xy 115.424963 -409.522892)
			(xy 115.424968 -409.457446) (xy 115.433766 -409.392594) (xy 115.451199 -409.329513) (xy 115.476951 -409.269346)
			(xy 115.493292 -409.24099) (xy 115.49661 -409.234967) (xy 115.500214 -409.221702) (xy 115.500404 -409.214828)
			(xy 115.500404 -408.465528) (xy 115.500201 -408.458656) (xy 115.4966 -408.445393) (xy 115.493292 -408.439366)
			(xy 115.476946 -408.411014) (xy 115.4512 -408.350847) (xy 115.433773 -408.287766) (xy 115.424979 -408.222915)
			(xy 115.42498 -408.157471) (xy 115.433775 -408.092621) (xy 115.451205 -408.02954) (xy 115.476952 -407.969374)
			(xy 115.493292 -407.941018) (xy 115.4966 -407.93499) (xy 115.50021 -407.921729) (xy 115.500404 -407.914856)
			(xy 115.500404 -407.628852) (xy 115.500783 -407.618694) (xy 115.508595 -407.59994) (xy 115.523004 -407.585618)
			(xy 115.541806 -407.577921) (xy 115.551966 -407.577544) (xy 116.268246 -407.577544) (xy 116.278376 -407.577989)
			(xy 116.297099 -407.585733) (xy 116.311454 -407.600031) (xy 116.319271 -407.618724) (xy 116.319808 -407.628852)
			(xy 116.319808 -407.914856) (xy 116.320016 -407.921728) (xy 116.323613 -407.934991) (xy 116.32692 -407.941018)
			(xy 116.343252 -407.969377) (xy 116.368999 -408.029543) (xy 116.386427 -408.092622) (xy 116.395222 -408.157472)
			(xy 116.395223 -408.222915) (xy 116.38643 -408.287764) (xy 116.369003 -408.350844) (xy 116.343258 -408.41101)
			(xy 116.32692 -408.439366) (xy 116.323619 -408.445397) (xy 116.320004 -408.458656) (xy 116.319808 -408.465528)
			(xy 116.319808 -409.214828) (xy 116.319988 -409.221702) (xy 116.323604 -409.234965) (xy 116.32692 -409.24099)
			(xy 116.343228 -409.269363) (xy 116.368977 -409.329525) (xy 116.386408 -409.392602) (xy 116.395206 -409.457449)
			(xy 116.39521 -409.52289) (xy 116.386421 -409.587738) (xy 116.368997 -409.650817) (xy 116.343256 -409.710982)
			(xy 116.32692 -409.739338) (xy 116.323593 -409.745357) (xy 116.319995 -409.758625) (xy 116.319808 -409.7655)
			(xy 116.319808 -410.051504) (xy 116.319382 -410.061657) (xy 116.311586 -410.080408) (xy 116.297191 -410.094731)
			(xy 116.278401 -410.102432) (xy 116.268246 -410.102812) (xy 115.551966 -410.102812) (xy 115.541844 -410.102303)
			(xy 115.523131 -410.094574) (xy 115.508778 -410.080295) (xy 115.500951 -410.061624) (xy 115.500404 -410.051504)
			(xy 115.500404 -409.7655) (xy 115.500212 -409.758627) (xy 115.496604 -409.745364) (xy 115.493292 -409.739338)
			(xy 115.476922 -409.710999) (xy 115.451179 -409.650829) (xy 115.433754 -409.587745) (xy 115.424963 -409.522892)
			(xy 94.044592 -409.522892) (xy 94.024198 -409.56663) (xy 93.981055 -409.641355) (xy 93.931564 -409.712035)
			(xy 93.876099 -409.778132) (xy 93.845888 -409.808934) (xy 93.032113 -410.622709) (xy 117.62487 -410.622709)
			(xy 117.624872 -410.557264) (xy 117.633667 -410.492413) (xy 117.651098 -410.429332) (xy 117.676846 -410.369166)
			(xy 117.693186 -410.34081) (xy 117.696542 -410.334791) (xy 117.700284 -410.321534) (xy 117.700552 -410.314648)
			(xy 117.700552 -409.565348) (xy 117.700329 -409.558454) (xy 117.696594 -409.545182) (xy 117.693186 -409.539186)
			(xy 117.676857 -409.510825) (xy 117.65111 -409.45066) (xy 117.633681 -409.387581) (xy 117.624886 -409.322732)
			(xy 117.624884 -409.257289) (xy 117.633677 -409.19244) (xy 117.651103 -409.12936) (xy 117.676848 -409.069194)
			(xy 117.693186 -409.040838) (xy 117.696567 -409.034831) (xy 117.700293 -409.021565) (xy 117.700552 -409.014676)
			(xy 117.700552 -408.728672) (xy 117.701061 -408.718567) (xy 117.708799 -408.699898) (xy 117.723088 -408.685606)
			(xy 117.741756 -408.677863) (xy 117.75186 -408.677364) (xy 118.46814 -408.677364) (xy 118.478247 -408.677852)
			(xy 118.496919 -408.685596) (xy 118.511211 -408.699891) (xy 118.518951 -408.718565) (xy 118.519448 -408.728672)
			(xy 118.519448 -409.014676) (xy 118.519662 -409.02157) (xy 118.523404 -409.034842) (xy 118.526814 -409.040838)
			(xy 118.543163 -409.069188) (xy 118.568908 -409.129356) (xy 118.586335 -409.192437) (xy 118.595128 -409.257288)
			(xy 118.595127 -409.322732) (xy 118.586331 -409.387583) (xy 118.568902 -409.450664) (xy 118.543154 -409.51083)
			(xy 118.536203 -409.522892) (xy 119.825014 -409.522892) (xy 119.825018 -409.457446) (xy 119.833815 -409.392595)
			(xy 119.851246 -409.329514) (xy 119.876994 -409.269346) (xy 119.893334 -409.24099) (xy 119.8967 -409.234976)
			(xy 119.900435 -409.221715) (xy 119.9007 -409.214828) (xy 119.9007 -408.465528) (xy 119.900456 -408.458638)
			(xy 119.896721 -408.445372) (xy 119.893334 -408.439366) (xy 119.87699 -408.411014) (xy 119.851247 -408.350846)
			(xy 119.833822 -408.287765) (xy 119.825029 -408.222915) (xy 119.82503 -408.157471) (xy 119.833824 -408.092621)
			(xy 119.851252 -408.029541) (xy 119.876996 -407.969374) (xy 119.893334 -407.941018) (xy 119.89669 -407.934999)
			(xy 119.900431 -407.921742) (xy 119.9007 -407.914856) (xy 119.9007 -407.628852) (xy 119.901146 -407.61874)
			(xy 119.908899 -407.600061) (xy 119.923208 -407.585768) (xy 119.941896 -407.578035) (xy 119.952008 -407.577544)
			(xy 120.668288 -407.577544) (xy 120.678389 -407.578094) (xy 120.697056 -407.585817) (xy 120.71135 -407.600093)
			(xy 120.719095 -407.618752) (xy 120.719596 -407.628852) (xy 120.719596 -407.914856) (xy 120.719847 -407.921746)
			(xy 120.723577 -407.935012) (xy 120.726962 -407.941018) (xy 120.743293 -407.969378) (xy 120.769037 -408.029544)
			(xy 120.786464 -408.092623) (xy 120.795258 -408.157472) (xy 120.795259 -408.222914) (xy 120.786467 -408.287763)
			(xy 120.769042 -408.350843) (xy 120.743299 -408.41101) (xy 120.726962 -408.439366) (xy 120.723611 -408.445388)
			(xy 120.719867 -408.458643) (xy 120.719596 -408.465528) (xy 120.719596 -409.214828) (xy 120.719857 -409.221717)
			(xy 120.723581 -409.234983) (xy 120.726962 -409.24099) (xy 120.743269 -409.269363) (xy 120.769016 -409.329526)
			(xy 120.786445 -409.392602) (xy 120.795242 -409.457449) (xy 120.795246 -409.522889) (xy 120.786458 -409.587737)
			(xy 120.769036 -409.650816) (xy 120.743297 -409.710982) (xy 120.726962 -409.739338) (xy 120.723586 -409.745347)
			(xy 120.719858 -409.758612) (xy 120.719596 -409.7655) (xy 120.719596 -410.051504) (xy 120.719187 -410.061627)
			(xy 120.711437 -410.080332) (xy 120.697118 -410.094646) (xy 120.678411 -410.10239) (xy 120.668288 -410.102812)
			(xy 119.952008 -410.102812) (xy 119.941888 -410.102378) (xy 119.923186 -410.094634) (xy 119.908872 -410.080324)
			(xy 119.901125 -410.061624) (xy 119.9007 -410.051504) (xy 119.9007 -409.7655) (xy 119.900467 -409.758609)
			(xy 119.896724 -409.745343) (xy 119.893334 -409.739338) (xy 119.876966 -409.710999) (xy 119.851225 -409.650828)
			(xy 119.833803 -409.587744) (xy 119.825014 -409.522892) (xy 118.536203 -409.522892) (xy 118.526814 -409.539186)
			(xy 118.52346 -409.545206) (xy 118.519717 -409.558462) (xy 118.519448 -409.565348) (xy 118.519448 -410.314648)
			(xy 118.519673 -410.321541) (xy 118.523407 -410.334813) (xy 118.526814 -410.34081) (xy 118.543139 -410.369173)
			(xy 118.568887 -410.429338) (xy 118.586317 -410.492416) (xy 118.595112 -410.557265) (xy 118.595114 -410.622708)
			(xy 122.02492 -410.622708) (xy 122.024922 -410.557264) (xy 122.033716 -410.492414) (xy 122.051144 -410.429333)
			(xy 122.07689 -410.369166) (xy 122.093228 -410.34081) (xy 122.096541 -410.334785) (xy 122.100147 -410.321521)
			(xy 122.10034 -410.314648) (xy 122.10034 -409.565348) (xy 122.100125 -409.558477) (xy 122.096532 -409.545214)
			(xy 122.093228 -409.539186) (xy 122.076901 -409.510824) (xy 122.051157 -409.450659) (xy 122.03373 -409.38758)
			(xy 122.024936 -409.322731) (xy 122.024934 -409.257289) (xy 122.033726 -409.19244) (xy 122.05115 -409.129361)
			(xy 122.076892 -409.069194) (xy 122.093228 -409.040838) (xy 122.096531 -409.034808) (xy 122.100144 -409.021548)
			(xy 122.10034 -409.014676) (xy 122.10034 -408.728672) (xy 122.100699 -408.718511) (xy 122.108512 -408.69975)
			(xy 122.122928 -408.685426) (xy 122.141738 -408.677735) (xy 122.151902 -408.677364) (xy 122.868182 -408.677364)
			(xy 122.878311 -408.677842) (xy 122.897036 -408.685568) (xy 122.911394 -408.699858) (xy 122.919209 -408.718546)
			(xy 122.919744 -408.728672) (xy 122.919744 -409.014676) (xy 122.91994 -409.021549) (xy 122.923545 -409.034812)
			(xy 122.926856 -409.040838) (xy 122.943204 -409.069189) (xy 122.968947 -409.129356) (xy 122.986372 -409.192438)
			(xy 122.995164 -409.257288) (xy 122.995163 -409.322732) (xy 122.986368 -409.387582) (xy 122.96894 -409.450663)
			(xy 122.943194 -409.51083) (xy 122.936244 -409.522892) (xy 124.22505 -409.522892) (xy 124.225054 -409.457446)
			(xy 124.233852 -409.392594) (xy 124.251284 -409.329513) (xy 124.277035 -409.269346) (xy 124.293376 -409.24099)
			(xy 124.296693 -409.234966) (xy 124.300298 -409.221702) (xy 124.300488 -409.214828) (xy 124.300488 -408.465528)
			(xy 124.300287 -408.458655) (xy 124.296685 -408.445393) (xy 124.293376 -408.439366) (xy 124.277031 -408.411014)
			(xy 124.251285 -408.350847) (xy 124.233858 -408.287766) (xy 124.225066 -408.222915) (xy 124.225067 -408.157471)
			(xy 124.233861 -408.092621) (xy 124.25129 -408.02954) (xy 124.277037 -407.969374) (xy 124.293376 -407.941018)
			(xy 124.296683 -407.934989) (xy 124.300294 -407.921729) (xy 124.300488 -407.914856) (xy 124.300488 -407.628852)
			(xy 124.300882 -407.618696) (xy 124.308691 -407.599945) (xy 124.323096 -407.585624) (xy 124.341892 -407.577924)
			(xy 124.35205 -407.577544) (xy 125.06833 -407.577544) (xy 125.078459 -407.578002) (xy 125.097182 -407.58574)
			(xy 125.111537 -407.600035) (xy 125.119355 -407.618725) (xy 125.119892 -407.628852) (xy 125.119892 -407.914856)
			(xy 125.120102 -407.921728) (xy 125.123698 -407.934991) (xy 125.127004 -407.941018) (xy 125.143333 -407.969378)
			(xy 125.169076 -408.029545) (xy 125.186501 -408.092624) (xy 125.195294 -408.157472) (xy 125.195295 -408.222914)
			(xy 125.186504 -408.287763) (xy 125.16908 -408.350842) (xy 125.143339 -408.411009) (xy 125.127004 -408.439366)
			(xy 125.123702 -408.445397) (xy 125.120088 -408.458656) (xy 125.119892 -408.465528) (xy 125.119892 -409.214828)
			(xy 125.120074 -409.221702) (xy 125.123689 -409.234965) (xy 125.127004 -409.24099) (xy 125.14331 -409.269363)
			(xy 125.169054 -409.329527) (xy 125.186482 -409.392603) (xy 125.195278 -409.457449) (xy 125.195282 -409.522889)
			(xy 125.186495 -409.587736) (xy 125.169074 -409.650815) (xy 125.143338 -409.710981) (xy 125.127004 -409.739338)
			(xy 125.123676 -409.745356) (xy 125.120079 -409.758625) (xy 125.119892 -409.7655) (xy 125.119892 -410.051504)
			(xy 125.119481 -410.061659) (xy 125.111683 -410.080413) (xy 125.097283 -410.094737) (xy 125.078487 -410.102435)
			(xy 125.06833 -410.102812) (xy 124.35205 -410.102812) (xy 124.341933 -410.102234) (xy 124.323223 -410.094532)
			(xy 124.308867 -410.080274) (xy 124.301036 -410.061618) (xy 124.300488 -410.051504) (xy 124.300488 -409.7655)
			(xy 124.300297 -409.758627) (xy 124.296688 -409.745364) (xy 124.293376 -409.739338) (xy 124.277007 -409.710999)
			(xy 124.251264 -409.650829) (xy 124.23384 -409.587745) (xy 124.22505 -409.522892) (xy 122.936244 -409.522892)
			(xy 122.926856 -409.539186) (xy 122.923551 -409.545215) (xy 122.919938 -409.558475) (xy 122.919744 -409.565348)
			(xy 122.919744 -410.314648) (xy 122.91995 -410.32152) (xy 122.923548 -410.334783) (xy 122.926856 -410.34081)
			(xy 122.94318 -410.369174) (xy 122.968925 -410.429339) (xy 122.986353 -410.492417) (xy 122.995148 -410.557265)
			(xy 122.99515 -410.622707) (xy 122.99515 -410.622709) (xy 126.424956 -410.622709) (xy 126.424958 -410.557264)
			(xy 126.433753 -410.492413) (xy 126.451183 -410.429333) (xy 126.476931 -410.369166) (xy 126.49327 -410.34081)
			(xy 126.496632 -410.334794) (xy 126.500369 -410.321534) (xy 126.500636 -410.314648) (xy 126.500636 -409.565348)
			(xy 126.500415 -409.558454) (xy 126.496679 -409.545182) (xy 126.49327 -409.539186) (xy 126.476942 -409.510825)
			(xy 126.451195 -409.450659) (xy 126.433767 -409.38758) (xy 126.424972 -409.322732) (xy 126.42497 -409.257289)
			(xy 126.433763 -409.19244) (xy 126.451189 -409.12936) (xy 126.476932 -409.069194) (xy 126.49327 -409.040838)
			(xy 126.496658 -409.034835) (xy 126.500378 -409.021565) (xy 126.500636 -409.014676) (xy 126.500636 -408.728672)
			(xy 126.500994 -408.718543) (xy 126.508758 -408.699832) (xy 126.523093 -408.685517) (xy 126.541815 -408.67778)
			(xy 126.551944 -408.677364) (xy 127.268224 -408.677364) (xy 127.27833 -408.677864) (xy 127.297002 -408.685603)
			(xy 127.311294 -408.699895) (xy 127.319035 -408.718566) (xy 127.319532 -408.728672) (xy 127.319532 -409.014676)
			(xy 127.31977 -409.021567) (xy 127.323509 -409.034833) (xy 127.326898 -409.040838) (xy 127.343244 -409.069189)
			(xy 127.368985 -409.129357) (xy 127.386409 -409.192438) (xy 127.3952 -409.257289) (xy 127.395199 -409.322732)
			(xy 127.386405 -409.387582) (xy 127.368979 -409.450662) (xy 127.343235 -409.510829) (xy 127.336285 -409.522892)
			(xy 128.624839 -409.522892) (xy 128.624844 -409.457446) (xy 128.633641 -409.392595) (xy 128.651073 -409.329513)
			(xy 128.676823 -409.269346) (xy 128.693164 -409.24099) (xy 128.696479 -409.234966) (xy 128.700085 -409.221702)
			(xy 128.700276 -409.214828) (xy 128.700276 -408.465528) (xy 128.700076 -408.458655) (xy 128.696474 -408.445392)
			(xy 128.693164 -408.439366) (xy 128.676819 -408.411014) (xy 128.651074 -408.350846) (xy 128.633648 -408.287766)
			(xy 128.624855 -408.222915) (xy 128.624856 -408.157471) (xy 128.633651 -408.092621) (xy 128.651079 -408.029541)
			(xy 128.676825 -407.969374) (xy 128.693164 -407.941018) (xy 128.696469 -407.934989) (xy 128.700081 -407.921729)
			(xy 128.700276 -407.914856) (xy 128.700276 -407.628852) (xy 128.700682 -407.618698) (xy 128.708489 -407.599949)
			(xy 128.72289 -407.585628) (xy 128.741682 -407.577926) (xy 128.751838 -407.577544) (xy 129.468118 -407.577544)
			(xy 129.478246 -407.578012) (xy 129.496969 -407.585746) (xy 129.511325 -407.600038) (xy 129.519143 -407.618726)
			(xy 129.51968 -407.628852) (xy 129.51968 -407.914856) (xy 129.519891 -407.921728) (xy 129.523486 -407.934991)
			(xy 129.526792 -407.941018) (xy 129.543122 -407.969378) (xy 129.568865 -408.029544) (xy 129.586291 -408.092624)
			(xy 129.595084 -408.157472) (xy 129.595084 -408.190192) (xy 133.023872 -408.190192) (xy 133.027863 -408.128025)
			(xy 133.039772 -408.066878) (xy 133.059401 -408.007757) (xy 133.08643 -407.951631) (xy 133.120414 -407.899422)
			(xy 133.160796 -407.851987) (xy 133.206912 -407.810106) (xy 133.258004 -407.774466) (xy 133.313235 -407.745652)
			(xy 133.371697 -407.724138) (xy 133.432431 -407.710276) (xy 133.494438 -407.704294) (xy 133.556701 -407.70629)
			(xy 133.618198 -407.716233) (xy 133.677919 -407.733957) (xy 133.734882 -407.759174) (xy 133.788153 -407.791467)
			(xy 133.836858 -407.830307) (xy 133.880195 -407.875057) (xy 133.917455 -407.924981) (xy 133.948024 -407.97926)
			(xy 133.971402 -408.037003) (xy 133.987203 -408.097261) (xy 133.995169 -408.159044) (xy 133.995668 -408.190192)
			(xy 133.995169 -408.22134) (xy 133.987203 -408.283123) (xy 133.971402 -408.343381) (xy 133.948024 -408.401124)
			(xy 133.917455 -408.455403) (xy 133.880195 -408.505327) (xy 133.836858 -408.550077) (xy 133.788153 -408.588917)
			(xy 133.734882 -408.62121) (xy 133.677919 -408.646427) (xy 133.618198 -408.664151) (xy 133.556701 -408.674094)
			(xy 133.494438 -408.67609) (xy 133.432431 -408.670108) (xy 133.371697 -408.656246) (xy 133.313235 -408.634732)
			(xy 133.258004 -408.605918) (xy 133.206912 -408.570278) (xy 133.160796 -408.528397) (xy 133.120414 -408.480962)
			(xy 133.08643 -408.428753) (xy 133.059401 -408.372627) (xy 133.039772 -408.313506) (xy 133.027863 -408.252359)
			(xy 133.023872 -408.190192) (xy 129.595084 -408.190192) (xy 129.595085 -408.222914) (xy 129.586293 -408.287763)
			(xy 129.568869 -408.350843) (xy 129.543128 -408.41101) (xy 129.526792 -408.439366) (xy 129.523489 -408.445396)
			(xy 129.519876 -408.458656) (xy 129.51968 -408.465528) (xy 129.51968 -409.214828) (xy 129.519864 -409.221702)
			(xy 129.523478 -409.234964) (xy 129.526792 -409.24099) (xy 129.543098 -409.269363) (xy 129.568843 -409.329526)
			(xy 129.586272 -409.392603) (xy 129.595068 -409.457449) (xy 129.595072 -409.522889) (xy 129.586284 -409.587737)
			(xy 129.568863 -409.650815) (xy 129.543126 -409.710982) (xy 129.526792 -409.739338) (xy 129.523463 -409.745356)
			(xy 129.519867 -409.758625) (xy 129.51968 -409.7655) (xy 129.51968 -410.051504) (xy 129.519281 -410.061661)
			(xy 129.511481 -410.080417) (xy 129.497077 -410.094741) (xy 129.478277 -410.102437) (xy 129.468118 -410.102812)
			(xy 128.751838 -410.102812) (xy 128.74172 -410.102244) (xy 128.72301 -410.094538) (xy 128.708654 -410.080277)
			(xy 128.700824 -410.061618) (xy 128.700276 -410.051504) (xy 128.700276 -409.7655) (xy 128.700087 -409.758627)
			(xy 128.696477 -409.745364) (xy 128.693164 -409.739338) (xy 128.676795 -409.710999) (xy 128.651053 -409.650829)
			(xy 128.633629 -409.587745) (xy 128.624839 -409.522892) (xy 127.336285 -409.522892) (xy 127.326898 -409.539186)
			(xy 127.323542 -409.545205) (xy 127.319801 -409.558462) (xy 127.319532 -409.565348) (xy 127.319532 -410.314648)
			(xy 127.319759 -410.321541) (xy 127.323492 -410.334813) (xy 127.326898 -410.34081) (xy 127.343221 -410.369174)
			(xy 127.368964 -410.429339) (xy 127.38639 -410.492418) (xy 127.395184 -410.557266) (xy 127.395186 -410.622707)
			(xy 127.395186 -410.622708) (xy 130.825006 -410.622708) (xy 130.825008 -410.557264) (xy 130.833802 -410.492414)
			(xy 130.85123 -410.429334) (xy 130.876974 -410.369166) (xy 130.893312 -410.34081) (xy 130.896624 -410.334784)
			(xy 130.900231 -410.321521) (xy 130.900424 -410.314648) (xy 130.900424 -409.565348) (xy 130.900211 -409.558476)
			(xy 130.896617 -409.545214) (xy 130.893312 -409.539186) (xy 130.876986 -409.510824) (xy 130.851242 -409.450658)
			(xy 130.833816 -409.387579) (xy 130.825022 -409.322731) (xy 130.825021 -409.257289) (xy 130.833812 -409.192441)
			(xy 130.851235 -409.129361) (xy 130.876976 -409.069194) (xy 130.893312 -409.040838) (xy 130.896614 -409.034807)
			(xy 130.900227 -409.021548) (xy 130.900424 -409.014676) (xy 130.900424 -408.728672) (xy 130.900799 -408.718513)
			(xy 130.908608 -408.699755) (xy 130.92302 -408.685432) (xy 130.941825 -408.677738) (xy 130.951986 -408.677364)
			(xy 131.668266 -408.677364) (xy 131.678393 -408.677855) (xy 131.697118 -408.685576) (xy 131.711477 -408.699862)
			(xy 131.719293 -408.718547) (xy 131.719828 -408.728672) (xy 131.719828 -409.014676) (xy 131.720026 -409.021549)
			(xy 131.72363 -409.034812) (xy 131.72694 -409.040838) (xy 131.743288 -409.069188) (xy 131.769032 -409.129356)
			(xy 131.786458 -409.192437) (xy 131.79525 -409.257288) (xy 131.795249 -409.322732) (xy 131.786454 -409.387583)
			(xy 131.769025 -409.450663) (xy 131.752122 -409.490164) (xy 133.023872 -409.490164) (xy 133.027863 -409.427997)
			(xy 133.039772 -409.36685) (xy 133.059401 -409.307729) (xy 133.08643 -409.251603) (xy 133.120414 -409.199394)
			(xy 133.160796 -409.151959) (xy 133.206912 -409.110078) (xy 133.258004 -409.074438) (xy 133.313235 -409.045624)
			(xy 133.371697 -409.02411) (xy 133.432431 -409.010248) (xy 133.494438 -409.004266) (xy 133.556701 -409.006262)
			(xy 133.618198 -409.016205) (xy 133.677919 -409.033929) (xy 133.734882 -409.059146) (xy 133.788153 -409.091439)
			(xy 133.836858 -409.130279) (xy 133.880195 -409.175029) (xy 133.917455 -409.224953) (xy 133.948024 -409.279232)
			(xy 133.952388 -409.290012) (xy 135.22402 -409.290012) (xy 135.228011 -409.227845) (xy 135.23992 -409.166698)
			(xy 135.259549 -409.107577) (xy 135.286578 -409.051451) (xy 135.320562 -408.999242) (xy 135.360944 -408.951807)
			(xy 135.40706 -408.909926) (xy 135.458152 -408.874286) (xy 135.513383 -408.845472) (xy 135.571845 -408.823958)
			(xy 135.632579 -408.810096) (xy 135.694586 -408.804114) (xy 135.756849 -408.80611) (xy 135.818346 -408.816053)
			(xy 135.878067 -408.833777) (xy 135.93503 -408.858994) (xy 135.988301 -408.891287) (xy 136.037006 -408.930127)
			(xy 136.080343 -408.974877) (xy 136.117603 -409.024801) (xy 136.148172 -409.07908) (xy 136.17155 -409.136823)
			(xy 136.187351 -409.197081) (xy 136.195317 -409.258864) (xy 136.195816 -409.290012) (xy 136.195317 -409.32116)
			(xy 136.187351 -409.382943) (xy 136.17155 -409.443201) (xy 136.148172 -409.500944) (xy 136.117603 -409.555223)
			(xy 136.080343 -409.605147) (xy 136.037006 -409.649897) (xy 135.988301 -409.688737) (xy 135.93503 -409.72103)
			(xy 135.878067 -409.746247) (xy 135.818346 -409.763971) (xy 135.756849 -409.773914) (xy 135.694586 -409.77591)
			(xy 135.632579 -409.769928) (xy 135.571845 -409.756066) (xy 135.513383 -409.734552) (xy 135.458152 -409.705738)
			(xy 135.40706 -409.670098) (xy 135.360944 -409.628217) (xy 135.320562 -409.580782) (xy 135.286578 -409.528573)
			(xy 135.259549 -409.472447) (xy 135.23992 -409.413326) (xy 135.228011 -409.352179) (xy 135.22402 -409.290012)
			(xy 133.952388 -409.290012) (xy 133.971402 -409.336975) (xy 133.987203 -409.397233) (xy 133.995169 -409.459016)
			(xy 133.995668 -409.490164) (xy 133.995169 -409.521312) (xy 133.987203 -409.583095) (xy 133.971402 -409.643353)
			(xy 133.948024 -409.701096) (xy 133.917455 -409.755375) (xy 133.880195 -409.805299) (xy 133.836858 -409.850049)
			(xy 133.788153 -409.888889) (xy 133.734882 -409.921182) (xy 133.677919 -409.946399) (xy 133.618198 -409.964123)
			(xy 133.556701 -409.974066) (xy 133.494438 -409.976062) (xy 133.432431 -409.97008) (xy 133.371697 -409.956218)
			(xy 133.313235 -409.934704) (xy 133.258004 -409.90589) (xy 133.206912 -409.87025) (xy 133.160796 -409.828369)
			(xy 133.120414 -409.780934) (xy 133.08643 -409.728725) (xy 133.059401 -409.672599) (xy 133.039772 -409.613478)
			(xy 133.027863 -409.552331) (xy 133.023872 -409.490164) (xy 131.752122 -409.490164) (xy 131.743279 -409.51083)
			(xy 131.72694 -409.539186) (xy 131.723634 -409.545215) (xy 131.720022 -409.558475) (xy 131.719828 -409.565348)
			(xy 131.719828 -410.314648) (xy 131.720036 -410.32152) (xy 131.723633 -410.334783) (xy 131.72694 -410.34081)
			(xy 131.743264 -410.369173) (xy 131.769011 -410.429338) (xy 131.786439 -410.492417) (xy 131.795234 -410.557265)
			(xy 131.795235 -410.589984) (xy 135.22402 -410.589984) (xy 135.228011 -410.527817) (xy 135.23992 -410.46667)
			(xy 135.259549 -410.407549) (xy 135.286578 -410.351423) (xy 135.320562 -410.299214) (xy 135.360944 -410.251779)
			(xy 135.40706 -410.209898) (xy 135.458152 -410.174258) (xy 135.513383 -410.145444) (xy 135.571845 -410.12393)
			(xy 135.632579 -410.110068) (xy 135.694586 -410.104086) (xy 135.756849 -410.106082) (xy 135.818346 -410.116025)
			(xy 135.878067 -410.133749) (xy 135.93503 -410.158966) (xy 135.988301 -410.191259) (xy 136.037006 -410.230099)
			(xy 136.080343 -410.274849) (xy 136.117603 -410.324773) (xy 136.148172 -410.379052) (xy 136.17155 -410.436795)
			(xy 136.187351 -410.497053) (xy 136.195317 -410.558836) (xy 136.195816 -410.589984) (xy 136.195317 -410.621132)
			(xy 136.187351 -410.682915) (xy 136.17155 -410.743173) (xy 136.148172 -410.800916) (xy 136.117603 -410.855195)
			(xy 136.080343 -410.905119) (xy 136.037006 -410.949869) (xy 135.988301 -410.988709) (xy 135.93503 -411.021002)
			(xy 135.878067 -411.046219) (xy 135.818346 -411.063943) (xy 135.756849 -411.073886) (xy 135.694586 -411.075882)
			(xy 135.632579 -411.0699) (xy 135.571845 -411.056038) (xy 135.513383 -411.034524) (xy 135.458152 -411.00571)
			(xy 135.40706 -410.97007) (xy 135.360944 -410.928189) (xy 135.320562 -410.880754) (xy 135.286578 -410.828545)
			(xy 135.259549 -410.772419) (xy 135.23992 -410.713298) (xy 135.228011 -410.652151) (xy 135.22402 -410.589984)
			(xy 131.795235 -410.589984) (xy 131.795236 -410.622707) (xy 131.786445 -410.687556) (xy 131.76902 -410.750636)
			(xy 131.743277 -410.810802) (xy 131.72694 -410.839158) (xy 131.723643 -410.845192) (xy 131.720026 -410.858448)
			(xy 131.719828 -410.86532) (xy 131.719828 -411.151324) (xy 131.719399 -411.161476) (xy 131.7116 -411.180224)
			(xy 131.697207 -411.194545) (xy 131.67842 -411.202249) (xy 131.668266 -411.202632) (xy 130.951986 -411.202632)
			(xy 130.941855 -411.202184) (xy 130.923128 -411.194446) (xy 130.908772 -411.180148) (xy 130.900958 -411.161453)
			(xy 130.900424 -411.151324) (xy 130.900424 -410.86532) (xy 130.900221 -410.858448) (xy 130.89662 -410.845185)
			(xy 130.893312 -410.839158) (xy 130.876962 -410.810809) (xy 130.851221 -410.75064) (xy 130.833797 -410.687559)
			(xy 130.825006 -410.622708) (xy 127.395186 -410.622708) (xy 127.386396 -410.687555) (xy 127.368973 -410.750635)
			(xy 127.343233 -410.810801) (xy 127.326898 -410.839158) (xy 127.323517 -410.845165) (xy 127.319791 -410.858431)
			(xy 127.319532 -410.86532) (xy 127.319532 -411.151324) (xy 127.319035 -411.16143) (xy 127.311296 -411.180103)
			(xy 127.297003 -411.194396) (xy 127.27833 -411.202135) (xy 127.268224 -411.202632) (xy 126.551944 -411.202632)
			(xy 126.541828 -411.202149) (xy 126.523132 -411.194421) (xy 126.508817 -411.180125) (xy 126.501065 -411.161439)
			(xy 126.500636 -411.151324) (xy 126.500636 -410.86532) (xy 126.500426 -410.858425) (xy 126.496682 -410.845153)
			(xy 126.49327 -410.839158) (xy 126.476918 -410.81081) (xy 126.451174 -410.750641) (xy 126.433748 -410.68756)
			(xy 126.424956 -410.622709) (xy 122.99515 -410.622709) (xy 122.986359 -410.687556) (xy 122.968934 -410.750636)
			(xy 122.943192 -410.810802) (xy 122.926856 -410.839158) (xy 122.923561 -410.845192) (xy 122.919942 -410.858448)
			(xy 122.919744 -410.86532) (xy 122.919744 -411.151324) (xy 122.919299 -411.161474) (xy 122.911504 -411.180219)
			(xy 122.897115 -411.19454) (xy 122.878334 -411.202246) (xy 122.868182 -411.202632) (xy 122.151902 -411.202632)
			(xy 122.141772 -411.202171) (xy 122.123046 -411.194439) (xy 122.108688 -411.180144) (xy 122.100874 -411.161452)
			(xy 122.10034 -411.151324) (xy 122.10034 -410.86532) (xy 122.100135 -410.858448) (xy 122.096535 -410.845185)
			(xy 122.093228 -410.839158) (xy 122.076877 -410.810809) (xy 122.051135 -410.750641) (xy 122.033711 -410.687559)
			(xy 122.02492 -410.622708) (xy 118.595114 -410.622708) (xy 118.586322 -410.687557) (xy 118.568896 -410.750636)
			(xy 118.543152 -410.810802) (xy 118.526814 -410.839158) (xy 118.523434 -410.845165) (xy 118.519708 -410.858432)
			(xy 118.519448 -410.86532) (xy 118.519448 -411.151324) (xy 118.518936 -411.161428) (xy 118.511199 -411.180098)
			(xy 118.496911 -411.19439) (xy 118.478244 -411.202133) (xy 118.46814 -411.202632) (xy 117.75186 -411.202632)
			(xy 117.741753 -411.202148) (xy 117.72308 -411.194404) (xy 117.708787 -411.180107) (xy 117.701048 -411.161431)
			(xy 117.700552 -411.151324) (xy 117.700552 -410.86532) (xy 117.700339 -410.858426) (xy 117.696597 -410.845154)
			(xy 117.693186 -410.839158) (xy 117.676834 -410.81081) (xy 117.651088 -410.750642) (xy 117.633662 -410.68756)
			(xy 117.62487 -410.622709) (xy 93.032113 -410.622709) (xy 92.878656 -410.776166) (xy 92.845196 -410.808881)
			(xy 92.773085 -410.868532) (xy 92.695652 -410.921089) (xy 92.654882 -410.94406) (xy 92.647519 -410.948518)
			(xy 92.636085 -410.961368) (xy 92.63253 -410.969206) (xy 92.61483 -411.010911) (xy 92.572917 -411.09124)
			(xy 92.52389 -411.167435) (xy 92.468153 -411.238868) (xy 92.406166 -411.30495) (xy 92.338439 -411.365137)
			(xy 92.265532 -411.418932) (xy 92.188045 -411.465892) (xy 92.106618 -411.505628) (xy 92.021922 -411.537814)
			(xy 91.934656 -411.562184) (xy 91.845538 -411.578537) (xy 91.755305 -411.586739) (xy 91.710002 -411.587188)
			(xy 91.666479 -411.586714) (xy 91.579765 -411.579129) (xy 91.494041 -411.564016) (xy 91.409961 -411.541491)
			(xy 91.328163 -411.511725) (xy 91.24927 -411.474945) (xy 91.173882 -411.431429) (xy 91.102573 -411.38151)
			(xy 91.035886 -411.325567) (xy 90.974326 -411.264025) (xy 90.918364 -411.197354) (xy 90.868424 -411.126059)
			(xy 90.824887 -411.050684) (xy 90.788084 -410.971801) (xy 90.758295 -410.890012) (xy 90.735746 -410.805938)
			(xy 90.720609 -410.720219) (xy 90.712999 -410.633507) (xy 90.712544 -410.589984) (xy 90.712544 -410.204158)
			(xy 90.713007 -410.161784) (xy 90.720216 -410.077343) (xy 90.734555 -409.993817) (xy 90.744802 -409.952698)
			(xy 90.746231 -409.946427) (xy 90.746231 -409.933569) (xy 90.744802 -409.927298) (xy 90.734531 -409.886184)
			(xy 90.720185 -409.802657) (xy 90.712988 -409.718213) (xy 90.712544 -409.675838) (xy 90.712544 -409.290012)
			(xy 90.713049 -409.244751) (xy 90.721242 -409.154601) (xy 90.737573 -409.065564) (xy 90.761906 -408.978374)
			(xy 90.79404 -408.893748) (xy 90.833713 -408.812382) (xy 90.880596 -408.734947) (xy 90.934304 -408.66208)
			(xy 90.994395 -408.59438) (xy 91.060374 -408.532405) (xy 91.131699 -408.476665) (xy 91.207782 -408.427618)
			(xy 91.287997 -408.385669) (xy 91.371684 -408.351162) (xy 91.458154 -408.324381) (xy 91.546695 -408.305548)
			(xy 91.636578 -408.294817) (xy 91.681808 -408.293062) (xy 91.692984 -408.292808) (xy 91.712796 -408.282902)
			(xy 91.760802 -408.223466) (xy 91.767229 -408.214753) (xy 91.772737 -408.193834) (xy 91.77147 -408.18308)
			(xy 91.764936 -408.142118) (xy 91.757938 -408.059458) (xy 91.7575 -408.01798) (xy 91.7575 -407.750264)
			(xy 91.757112 -407.741435) (xy 91.751124 -407.72482) (xy 91.745816 -407.717752) (xy 91.744292 -407.715974)
			(xy 91.723464 -407.695146) (xy 91.705176 -407.687526) (xy 91.69527 -407.687272) (xy 91.650547 -407.686107)
			(xy 91.561566 -407.676772) (xy 91.473777 -407.659507) (xy 91.387887 -407.63445) (xy 91.304586 -407.601803)
			(xy 91.224543 -407.561829) (xy 91.148401 -407.514847) (xy 91.076771 -407.461236) (xy 91.01023 -407.401427)
			(xy 90.949311 -407.3359) (xy 90.894505 -407.265181) (xy 90.846251 -407.189839) (xy 90.804937 -407.110478)
			(xy 90.787474 -407.06929) (xy 90.783897 -407.061465) (xy 90.772476 -407.04861) (xy 90.765122 -407.044144)
			(xy 90.724364 -407.021155) (xy 90.646939 -406.968589) (xy 90.57482 -406.908951) (xy 90.541348 -406.87625)
			(xy 89.750138 -406.08504) (xy 89.734898 -406.069292) (xy 89.733628 -406.068022) (xy 89.730135 -406.064562)
			(xy 89.722081 -406.058926) (xy 89.717626 -406.056846) (xy 89.704672 -406.051258) (xy 89.696057 -406.047815)
			(xy 89.67755 -406.046767) (xy 89.668604 -406.049226) (xy 89.668096 -406.04948) (xy 89.642764 -406.057766)
			(xy 89.590749 -406.069399) (xy 89.537774 -406.075268) (xy 89.511124 -406.075642) (xy 89.509854 -406.075642)
			(xy 89.478059 -406.075119) (xy 89.415014 -406.066814) (xy 89.353592 -406.05035) (xy 89.294845 -406.026011)
			(xy 89.239777 -405.994213) (xy 89.18933 -405.955498) (xy 89.144367 -405.910531) (xy 89.105659 -405.86008)
			(xy 89.073866 -405.805009) (xy 89.049533 -405.746258) (xy 89.033076 -405.684835) (xy 89.024777 -405.621789)
			(xy 89.024206 -405.589994) (xy 89.024253 -405.577271) (xy 89.025521 -405.551858) (xy 89.026746 -405.539194)
			(xy 89.030422 -405.508755) (xy 89.044465 -405.449071) (xy 89.065905 -405.391627) (xy 89.0944 -405.337337)
			(xy 89.129499 -405.287064) (xy 89.170643 -405.241604) (xy 89.21718 -405.201682) (xy 89.268368 -405.167932)
			(xy 89.323396 -405.140889) (xy 89.381389 -405.120983) (xy 89.411302 -405.114252) (xy 89.429082 -405.110696)
			(xy 89.451688 -405.082756) (xy 89.451688 -404.79726) (xy 89.429082 -404.76932) (xy 89.411302 -404.765764)
			(xy 89.380436 -404.758849) (xy 89.320689 -404.738084) (xy 89.264141 -404.709741) (xy 89.211749 -404.674299)
			(xy 89.1644 -404.632359) (xy 89.122893 -404.584628) (xy 89.087932 -404.531915) (xy 89.060107 -404.475111)
			(xy 89.039888 -404.415176) (xy 89.027619 -404.353124) (xy 89.023505 -404.290004) (xy 89.027617 -404.226885)
			(xy 89.039886 -404.164833) (xy 89.060103 -404.104898) (xy 89.087927 -404.048093) (xy 89.122888 -403.995379)
			(xy 89.164393 -403.947648) (xy 89.211742 -403.905706) (xy 89.264133 -403.870264) (xy 89.32068 -403.84192)
			(xy 89.380428 -403.821154) (xy 89.411302 -403.81428) (xy 89.429082 -403.810724) (xy 89.451688 -403.782784)
			(xy 89.451688 -403.593554) (xy 89.428066 -403.565106) (xy 89.409778 -403.562058) (xy 89.376538 -403.555759)
			(xy 89.311703 -403.536431) (xy 89.249552 -403.509699) (xy 89.190928 -403.475927) (xy 89.136626 -403.435572)
			(xy 89.08738 -403.389181) (xy 89.043859 -403.337382) (xy 89.006651 -403.280876) (xy 88.976261 -403.22043)
			(xy 88.953101 -403.156862) (xy 88.937483 -403.091034) (xy 88.929621 -403.023836) (xy 88.92962 -402.956181)
			(xy 88.93748 -402.888983) (xy 88.953096 -402.823154) (xy 88.976254 -402.759586) (xy 89.006642 -402.699139)
			(xy 89.043848 -402.642632) (xy 89.087368 -402.590832) (xy 89.136612 -402.544439) (xy 89.190914 -402.504082)
			(xy 89.249536 -402.470308) (xy 89.311686 -402.443575) (xy 89.376522 -402.424245) (xy 89.409778 -402.418042)
			(xy 89.428066 -402.414994) (xy 89.451688 -402.386546) (xy 89.451688 -402.197316) (xy 89.429082 -402.169376)
			(xy 89.411302 -402.16582) (xy 89.380439 -402.158904) (xy 89.320697 -402.13814) (xy 89.264155 -402.109799)
			(xy 89.211769 -402.07436) (xy 89.164424 -402.032422) (xy 89.122923 -401.984695) (xy 89.087965 -401.931986)
			(xy 89.060144 -401.875186) (xy 89.039928 -401.815256) (xy 89.027661 -401.753209) (xy 89.023549 -401.690096)
			(xy 89.027662 -401.626982) (xy 89.03993 -401.564935) (xy 89.060147 -401.505006) (xy 89.08797 -401.448207)
			(xy 89.122928 -401.395498) (xy 89.164431 -401.347772) (xy 89.211776 -401.305835) (xy 89.264163 -401.270397)
			(xy 89.320706 -401.242056) (xy 89.380448 -401.221293) (xy 89.411302 -401.214336) (xy 89.429082 -401.21078)
			(xy 89.451688 -401.18284) (xy 89.451688 -400.897344) (xy 89.429082 -400.869404) (xy 89.411302 -400.865848)
			(xy 89.380438 -400.858932) (xy 89.320692 -400.838168) (xy 89.264146 -400.809825) (xy 89.211756 -400.774385)
			(xy 89.164409 -400.732445) (xy 89.122904 -400.684716) (xy 89.087944 -400.632004) (xy 89.06012 -400.575202)
			(xy 89.039903 -400.515268) (xy 89.027634 -400.453219) (xy 89.023521 -400.390101) (xy 89.027634 -400.326984)
			(xy 89.039902 -400.264934) (xy 89.060119 -400.205001) (xy 89.087943 -400.148198) (xy 89.122903 -400.095486)
			(xy 89.164407 -400.047757) (xy 89.211755 -400.005817) (xy 89.264144 -399.970376) (xy 89.32069 -399.942033)
			(xy 89.380435 -399.921268) (xy 89.411302 -399.914364) (xy 89.429082 -399.910808) (xy 89.451688 -399.882868)
			(xy 89.451688 -399.693638) (xy 89.428066 -399.66519) (xy 89.409778 -399.662142) (xy 89.376539 -399.655843)
			(xy 89.311705 -399.636515) (xy 89.249556 -399.609784) (xy 89.190934 -399.576013) (xy 89.136634 -399.535659)
			(xy 89.08739 -399.489268) (xy 89.04387 -399.43747) (xy 89.006663 -399.380966) (xy 88.976274 -399.320521)
			(xy 88.953115 -399.256955) (xy 88.937498 -399.191128) (xy 88.929637 -399.123933) (xy 88.929636 -399.056279)
			(xy 88.937496 -398.989083) (xy 88.953112 -398.923256) (xy 88.97627 -398.85969) (xy 89.006657 -398.799244)
			(xy 89.043863 -398.742739) (xy 89.087382 -398.69094) (xy 89.136625 -398.644549) (xy 89.190925 -398.604194)
			(xy 89.249546 -398.570421) (xy 89.311694 -398.543689) (xy 89.376528 -398.52436) (xy 89.409778 -398.518126)
			(xy 89.428066 -398.515078) (xy 89.451688 -398.48663) (xy 89.451688 -398.424908) (xy 89.444191 -398.415111)
			(xy 89.422356 -398.403687) (xy 89.410032 -398.403064) (xy 89.151714 -398.403064) (xy 89.14154 -398.402641)
			(xy 89.122741 -398.394858) (xy 89.108351 -398.380473) (xy 89.100563 -398.361675) (xy 89.100152 -398.351502)
			(xy 89.100152 -398.0688) (xy 89.100089 -398.064527) (xy 89.098678 -398.0561) (xy 89.097358 -398.052036)
			(xy 89.09304 -398.039336) (xy 89.0905 -398.035018) (xy 89.07476 -398.007046) (xy 89.049972 -397.947841)
			(xy 89.033205 -397.885885) (xy 89.024749 -397.82226) (xy 89.024754 -397.758075) (xy 89.033218 -397.694451)
			(xy 89.049994 -397.632497) (xy 89.074789 -397.573295) (xy 89.0905 -397.545306) (xy 89.09304 -397.540988)
			(xy 89.097358 -397.528288) (xy 89.098654 -397.524219) (xy 89.100052 -397.515794) (xy 89.100152 -397.511524)
			(xy 89.100152 -396.768828) (xy 89.100091 -396.764555) (xy 89.098685 -396.756126) (xy 89.097358 -396.752064)
			(xy 89.09304 -396.739364) (xy 89.0905 -396.735046) (xy 89.074758 -396.707074) (xy 89.049967 -396.647868)
			(xy 89.033196 -396.585911) (xy 89.024737 -396.522285) (xy 89.024738 -396.458098) (xy 89.033199 -396.394472)
			(xy 89.049973 -396.332515) (xy 89.074766 -396.273311) (xy 89.0905 -396.245334) (xy 89.09304 -396.241016)
			(xy 89.097358 -396.228316) (xy 89.098656 -396.224247) (xy 89.100059 -396.215822) (xy 89.100152 -396.211552)
			(xy 89.100152 -395.92885) (xy 89.100569 -395.918673) (xy 89.108346 -395.899863) (xy 89.122733 -395.885466)
			(xy 89.141537 -395.877676) (xy 89.151714 -395.877288) (xy 89.400888 -395.877288) (xy 89.41091 -395.87687)
			(xy 89.429429 -395.869202) (xy 89.443602 -395.855029) (xy 89.45127 -395.83651) (xy 89.451688 -395.826488)
			(xy 89.451688 -395.793722) (xy 89.428066 -395.765274) (xy 89.409778 -395.762226) (xy 89.376539 -395.755931)
			(xy 89.311705 -395.73661) (xy 89.249555 -395.709886) (xy 89.190932 -395.676119) (xy 89.136631 -395.635768)
			(xy 89.087387 -395.589379) (xy 89.043869 -395.537582) (xy 89.006665 -395.481078) (xy 88.97628 -395.420633)
			(xy 88.953126 -395.357066) (xy 88.937517 -395.291239) (xy 88.929664 -395.224044) (xy 88.92921 -395.190218)
			(xy 88.92921 -395.18336) (xy 88.929464 -395.171676) (xy 88.929464 -395.169136) (xy 88.929718 -395.165326)
			(xy 88.929718 -395.164056) (xy 88.929972 -395.16177) (xy 88.929972 -395.149832) (xy 88.927178 -395.141958)
			(xy 88.924068 -395.133912) (xy 88.913416 -395.120357) (xy 88.898897 -395.111062) (xy 88.890602 -395.108684)
			(xy 88.676734 -395.058646) (xy 88.636787 -395.04888) (xy 88.558533 -395.023581) (xy 88.482651 -394.991869)
			(xy 88.409666 -394.953963) (xy 88.340081 -394.910125) (xy 88.274379 -394.860659) (xy 88.24341 -394.833602)
			(xy 88.23833 -394.829284) (xy 88.232996 -394.82649) (xy 88.221312 -394.822172) (xy 88.20658 -394.81887)
			(xy 88.194642 -394.817346) (xy 87.718392 -394.82014) (xy 87.706708 -394.822934) (xy 87.701374 -394.825982)
			(xy 87.659365 -394.847075) (xy 87.572156 -394.882174) (xy 87.482032 -394.908914) (xy 87.389792 -394.927056)
			(xy 87.296254 -394.93644) (xy 87.249254 -394.937234) (xy 86.7537 -394.940282) (xy 86.747604 -394.940536)
			(xy 86.701125 -394.939988) (xy 86.608571 -394.931311) (xy 86.517226 -394.91406) (xy 86.427883 -394.888384)
			(xy 86.341317 -394.854507) (xy 86.299548 -394.83411) (xy 86.294214 -394.831316) (xy 86.28253 -394.828776)
			(xy 70.695312 -394.9192) (xy 70.685343 -394.919738) (xy 70.666949 -394.927448) (xy 70.652887 -394.941591)
			(xy 70.64528 -394.960028) (xy 70.644766 -394.97) (xy 70.644766 -397.82289) (xy 71.424806 -397.82289)
			(xy 71.42481 -397.757445) (xy 71.433607 -397.692593) (xy 71.451038 -397.629512) (xy 71.476786 -397.569344)
			(xy 71.493126 -397.540988) (xy 71.496492 -397.534974) (xy 71.500227 -397.521713) (xy 71.500492 -397.514826)
			(xy 71.500492 -396.765526) (xy 71.50025 -396.758635) (xy 71.496514 -396.745369) (xy 71.493126 -396.739364)
			(xy 71.476781 -396.711012) (xy 71.451038 -396.650844) (xy 71.433613 -396.587763) (xy 71.424821 -396.522913)
			(xy 71.424823 -396.45747) (xy 71.433617 -396.39262) (xy 71.451044 -396.329539) (xy 71.476788 -396.269372)
			(xy 71.493126 -396.241016) (xy 71.496483 -396.234997) (xy 71.500223 -396.22174) (xy 71.500492 -396.214854)
			(xy 71.500492 -395.92885) (xy 71.501066 -395.918732) (xy 71.508769 -395.900021) (xy 71.523028 -395.885665)
			(xy 71.541686 -395.877836) (xy 71.5518 -395.877288) (xy 72.26808 -395.877288) (xy 72.278231 -395.877738)
			(xy 72.296981 -395.885524) (xy 72.311305 -395.899912) (xy 72.319007 -395.918697) (xy 72.319388 -395.92885)
			(xy 72.319388 -396.214854) (xy 72.319606 -396.221748) (xy 72.323344 -396.23502) (xy 72.326754 -396.241016)
			(xy 72.343083 -396.269377) (xy 72.368828 -396.329542) (xy 72.386256 -396.392621) (xy 72.39505 -396.45747)
			(xy 72.395051 -396.522913) (xy 72.386259 -396.587762) (xy 72.368834 -396.650841) (xy 72.343091 -396.711008)
			(xy 72.326754 -396.739364) (xy 72.323403 -396.745386) (xy 72.319659 -396.758641) (xy 72.319388 -396.765526)
			(xy 72.319388 -397.514826) (xy 72.319616 -397.521719) (xy 72.323348 -397.534991) (xy 72.326754 -397.540988)
			(xy 72.336121 -397.557288) (xy 73.624727 -397.557288) (xy 73.633518 -397.492439) (xy 73.650942 -397.429359)
			(xy 73.676684 -397.369192) (xy 73.69302 -397.340836) (xy 73.696323 -397.334806) (xy 73.699936 -397.321546)
			(xy 73.700132 -397.314674) (xy 73.700132 -397.028924) (xy 73.700542 -397.018767) (xy 73.708335 -397.000009)
			(xy 73.722736 -396.985684) (xy 73.741535 -396.977989) (xy 73.751694 -396.977616) (xy 74.467974 -396.977616)
			(xy 74.478096 -396.978147) (xy 74.496812 -396.985862) (xy 74.511169 -397.000134) (xy 74.518993 -397.018805)
			(xy 74.519536 -397.028924) (xy 74.519536 -397.314674) (xy 74.519733 -397.321547) (xy 74.523337 -397.33481)
			(xy 74.526648 -397.340836) (xy 74.542994 -397.369187) (xy 74.568738 -397.429355) (xy 74.586164 -397.492436)
			(xy 74.594956 -397.557287) (xy 74.594955 -397.62273) (xy 74.586161 -397.687581) (xy 74.568732 -397.750661)
			(xy 74.542986 -397.810828) (xy 74.536036 -397.82289) (xy 75.824842 -397.82289) (xy 75.824846 -397.757444)
			(xy 75.833644 -397.692593) (xy 75.851077 -397.629511) (xy 75.876827 -397.569344) (xy 75.893168 -397.540988)
			(xy 75.896484 -397.534964) (xy 75.900089 -397.5217) (xy 75.90028 -397.514826) (xy 75.90028 -396.765526)
			(xy 75.90008 -396.758653) (xy 75.896478 -396.74539) (xy 75.893168 -396.739364) (xy 75.876821 -396.711013)
			(xy 75.851077 -396.650845) (xy 75.83365 -396.587764) (xy 75.824858 -396.522913) (xy 75.824859 -396.457469)
			(xy 75.833653 -396.392619) (xy 75.851082 -396.329539) (xy 75.876829 -396.269372) (xy 75.893168 -396.241016)
			(xy 75.896474 -396.234987) (xy 75.900086 -396.221727) (xy 75.90028 -396.214854) (xy 75.90028 -395.92885)
			(xy 75.900706 -395.918676) (xy 75.908482 -395.899875) (xy 75.922868 -395.885487) (xy 75.941668 -395.877707)
			(xy 75.951842 -395.877288) (xy 76.668122 -395.877288) (xy 76.678301 -395.877647) (xy 76.697106 -395.885449)
			(xy 76.711492 -395.899855) (xy 76.719267 -395.91867) (xy 76.719684 -395.92885) (xy 76.719684 -396.214854)
			(xy 76.719895 -396.221726) (xy 76.72349 -396.234989) (xy 76.726796 -396.241016) (xy 76.743124 -396.269377)
			(xy 76.768867 -396.329543) (xy 76.786293 -396.392622) (xy 76.795086 -396.457471) (xy 76.795087 -396.522912)
			(xy 76.786296 -396.587761) (xy 76.768872 -396.650841) (xy 76.743132 -396.711007) (xy 76.726796 -396.739364)
			(xy 76.723494 -396.745395) (xy 76.71988 -396.758654) (xy 76.719684 -396.765526) (xy 76.719684 -397.514826)
			(xy 76.719868 -397.5217) (xy 76.723482 -397.534963) (xy 76.726796 -397.540988) (xy 76.736162 -397.557287)
			(xy 78.024763 -397.557287) (xy 78.033555 -397.492438) (xy 78.050981 -397.429358) (xy 78.076725 -397.369192)
			(xy 78.093062 -397.340836) (xy 78.096415 -397.334815) (xy 78.100157 -397.321559) (xy 78.100428 -397.314674)
			(xy 78.100428 -397.028924) (xy 78.100836 -397.0188) (xy 78.108582 -397.000091) (xy 78.122901 -396.985775)
			(xy 78.141611 -396.978034) (xy 78.151736 -396.977616) (xy 78.868016 -396.977616) (xy 78.878142 -396.978003)
			(xy 78.896849 -396.985759) (xy 78.911163 -397.000085) (xy 78.918905 -397.018798) (xy 78.919324 -397.028924)
			(xy 78.919324 -397.314674) (xy 78.919564 -397.321565) (xy 78.923301 -397.334831) (xy 78.92669 -397.340836)
			(xy 78.943035 -397.369188) (xy 78.968777 -397.429356) (xy 78.986201 -397.492437) (xy 78.994992 -397.557287)
			(xy 78.994991 -397.62273) (xy 78.986198 -397.68758) (xy 78.968771 -397.75066) (xy 78.943027 -397.810828)
			(xy 78.936078 -397.82289) (xy 80.224892 -397.82289) (xy 80.224896 -397.757445) (xy 80.233693 -397.692594)
			(xy 80.251124 -397.629512) (xy 80.276871 -397.569345) (xy 80.29321 -397.540988) (xy 80.296575 -397.534973)
			(xy 80.300311 -397.521713) (xy 80.300576 -397.514826) (xy 80.300576 -396.765526) (xy 80.300336 -396.758635)
			(xy 80.296599 -396.745369) (xy 80.29321 -396.739364) (xy 80.276865 -396.711012) (xy 80.251123 -396.650844)
			(xy 80.233699 -396.587763) (xy 80.224908 -396.522913) (xy 80.224909 -396.45747) (xy 80.233702 -396.39262)
			(xy 80.251129 -396.32954) (xy 80.276873 -396.269372) (xy 80.29321 -396.241016) (xy 80.296565 -396.234997)
			(xy 80.300307 -396.22174) (xy 80.300576 -396.214854) (xy 80.300576 -395.92885) (xy 80.301069 -395.918722)
			(xy 80.308787 -395.899995) (xy 80.323072 -395.885636) (xy 80.341759 -395.877821) (xy 80.351884 -395.877288)
			(xy 81.068164 -395.877288) (xy 81.078314 -395.877751) (xy 81.097063 -395.885532) (xy 81.111388 -395.899917)
			(xy 81.119091 -395.918698) (xy 81.119472 -395.92885) (xy 81.119472 -396.214854) (xy 81.119691 -396.221748)
			(xy 81.123429 -396.23502) (xy 81.126838 -396.241016) (xy 81.143168 -396.269377) (xy 81.168914 -396.329542)
			(xy 81.186342 -396.392621) (xy 81.195136 -396.45747) (xy 81.195137 -396.522913) (xy 81.186345 -396.587762)
			(xy 81.168919 -396.650842) (xy 81.143175 -396.711008) (xy 81.126838 -396.739364) (xy 81.123485 -396.745385)
			(xy 81.119743 -396.758641) (xy 81.119472 -396.765526) (xy 81.119472 -397.514826) (xy 81.119703 -397.521719)
			(xy 81.123433 -397.534991) (xy 81.126838 -397.540988) (xy 81.136205 -397.557288) (xy 82.424813 -397.557288)
			(xy 82.433604 -397.492439) (xy 82.451028 -397.429359) (xy 82.476768 -397.369193) (xy 82.493104 -397.340836)
			(xy 82.496406 -397.334805) (xy 82.50002 -397.321546) (xy 82.500216 -397.314674) (xy 82.500216 -397.028924)
			(xy 82.500641 -397.018769) (xy 82.508432 -397.000014) (xy 82.522828 -396.98569) (xy 82.541621 -396.977992)
			(xy 82.551778 -396.977616) (xy 83.268058 -396.977616) (xy 83.278179 -396.97816) (xy 83.296895 -396.98587)
			(xy 83.311252 -397.000138) (xy 83.319076 -397.018806) (xy 83.31962 -397.028924) (xy 83.31962 -397.314674)
			(xy 83.31982 -397.321547) (xy 83.323422 -397.33481) (xy 83.326732 -397.340836) (xy 83.343079 -397.369187)
			(xy 83.368823 -397.429355) (xy 83.38625 -397.492436) (xy 83.395042 -397.557287) (xy 83.395041 -397.622731)
			(xy 83.386247 -397.687581) (xy 83.368818 -397.750661) (xy 83.343071 -397.810828) (xy 83.336121 -397.82289)
			(xy 84.624681 -397.82289) (xy 84.624686 -397.757445) (xy 84.633483 -397.692594) (xy 84.650913 -397.629512)
			(xy 84.676659 -397.569345) (xy 84.692998 -397.540988) (xy 84.696362 -397.534973) (xy 84.700099 -397.521713)
			(xy 84.700364 -397.514826) (xy 84.700364 -396.765526) (xy 84.700147 -396.758632) (xy 84.696408 -396.74536)
			(xy 84.692998 -396.739364) (xy 84.676653 -396.711012) (xy 84.650912 -396.650844) (xy 84.633488 -396.587763)
			(xy 84.624697 -396.522913) (xy 84.624699 -396.45747) (xy 84.633492 -396.39262) (xy 84.650918 -396.32954)
			(xy 84.676661 -396.269373) (xy 84.692998 -396.241016) (xy 84.696353 -396.234996) (xy 84.700095 -396.22174)
			(xy 84.700364 -396.214854) (xy 84.700364 -395.92885) (xy 84.700868 -395.918724) (xy 84.708584 -395.899999)
			(xy 84.722866 -395.88564) (xy 84.741548 -395.877823) (xy 84.751672 -395.877288) (xy 85.467952 -395.877288)
			(xy 85.478102 -395.877761) (xy 85.496851 -395.885538) (xy 85.511175 -395.899919) (xy 85.518879 -395.918699)
			(xy 85.51926 -395.92885) (xy 85.51926 -396.214854) (xy 85.519481 -396.221748) (xy 85.523217 -396.23502)
			(xy 85.526626 -396.241016) (xy 85.542956 -396.269376) (xy 85.568703 -396.329542) (xy 85.586131 -396.392621)
			(xy 85.594926 -396.45747) (xy 85.594927 -396.522913) (xy 85.586135 -396.587762) (xy 85.568708 -396.650842)
			(xy 85.542964 -396.711008) (xy 85.526626 -396.739364) (xy 85.523272 -396.745384) (xy 85.519531 -396.758641)
			(xy 85.51926 -396.765526) (xy 85.51926 -397.514826) (xy 85.519492 -397.521719) (xy 85.523221 -397.534991)
			(xy 85.526626 -397.540988) (xy 85.535993 -397.557287) (xy 86.824849 -397.557287) (xy 86.833641 -397.492438)
			(xy 86.851066 -397.429359) (xy 86.876809 -397.369192) (xy 86.893146 -397.340836) (xy 86.896497 -397.334814)
			(xy 86.900241 -397.321559) (xy 86.900512 -397.314674) (xy 86.900512 -397.028924) (xy 86.900936 -397.018802)
			(xy 86.908678 -397.000096) (xy 86.922993 -396.985781) (xy 86.941698 -396.978037) (xy 86.95182 -396.977616)
			(xy 87.6681 -396.977616) (xy 87.678224 -396.978016) (xy 87.696931 -396.985768) (xy 87.711246 -397.000089)
			(xy 87.718988 -397.018799) (xy 87.719408 -397.028924) (xy 87.719408 -397.314674) (xy 87.71965 -397.321565)
			(xy 87.723386 -397.334831) (xy 87.726774 -397.340836) (xy 87.743119 -397.369188) (xy 87.768862 -397.429356)
			(xy 87.786287 -397.492437) (xy 87.795079 -397.557287) (xy 87.795077 -397.62273) (xy 87.786283 -397.68758)
			(xy 87.768856 -397.750661) (xy 87.743112 -397.810828) (xy 87.726774 -397.839184) (xy 87.723417 -397.845203)
			(xy 87.719677 -397.85846) (xy 87.719408 -397.865346) (xy 87.719408 -398.6149) (xy 87.71964 -398.621791)
			(xy 87.723383 -398.635057) (xy 87.726774 -398.641062) (xy 87.743141 -398.669401) (xy 87.768882 -398.729572)
			(xy 87.786304 -398.792656) (xy 87.795093 -398.857508) (xy 87.795089 -398.922953) (xy 87.786292 -398.987805)
			(xy 87.768861 -399.050886) (xy 87.743113 -399.111054) (xy 87.726774 -399.13941) (xy 87.723408 -399.145424)
			(xy 87.719673 -399.158685) (xy 87.719408 -399.165572) (xy 87.719408 -399.451576) (xy 87.718965 -399.461696)
			(xy 87.711226 -399.480398) (xy 87.696918 -399.494712) (xy 87.67822 -399.50246) (xy 87.6681 -399.502884)
			(xy 86.95182 -399.502884) (xy 86.941697 -399.502467) (xy 86.922991 -399.494723) (xy 86.908675 -399.480406)
			(xy 86.900932 -399.461699) (xy 86.900512 -399.451576) (xy 86.900512 -399.165572) (xy 86.900284 -399.158679)
			(xy 86.896553 -399.145407) (xy 86.893146 -399.13941) (xy 86.876839 -399.111037) (xy 86.851092 -399.050874)
			(xy 86.833662 -398.987798) (xy 86.824865 -398.922951) (xy 86.824861 -398.857511) (xy 86.833649 -398.792663)
			(xy 86.851071 -398.729584) (xy 86.876811 -398.669418) (xy 86.893146 -398.641062) (xy 86.896523 -398.635053)
			(xy 86.90025 -398.621788) (xy 86.900512 -398.6149) (xy 86.900512 -397.865346) (xy 86.900294 -397.858452)
			(xy 86.896556 -397.84518) (xy 86.893146 -397.839184) (xy 86.876817 -397.810823) (xy 86.851072 -397.750658)
			(xy 86.833644 -397.687579) (xy 86.82485 -397.62273) (xy 86.824849 -397.557287) (xy 85.535993 -397.557287)
			(xy 85.542932 -397.569362) (xy 85.568681 -397.629524) (xy 85.586112 -397.6926) (xy 85.59491 -397.757447)
			(xy 85.594914 -397.822888) (xy 85.586125 -397.887736) (xy 85.568703 -397.950815) (xy 85.542962 -398.01098)
			(xy 85.526626 -398.039336) (xy 85.523247 -398.045344) (xy 85.519521 -398.05861) (xy 85.51926 -398.065498)
			(xy 85.51926 -398.351502) (xy 85.518775 -398.361629) (xy 85.511047 -398.38035) (xy 85.49676 -398.394706)
			(xy 85.478076 -398.402525) (xy 85.467952 -398.403064) (xy 84.751672 -398.403064) (xy 84.741512 -398.402701)
			(xy 84.722752 -398.394889) (xy 84.708428 -398.380474) (xy 84.700736 -398.361665) (xy 84.700364 -398.351502)
			(xy 84.700364 -398.065498) (xy 84.700136 -398.058606) (xy 84.696391 -398.04534) (xy 84.692998 -398.039336)
			(xy 84.67663 -398.010997) (xy 84.650891 -397.950826) (xy 84.63347 -397.887742) (xy 84.624681 -397.82289)
			(xy 83.336121 -397.82289) (xy 83.326732 -397.839184) (xy 83.323426 -397.845213) (xy 83.319814 -397.858473)
			(xy 83.31962 -397.865346) (xy 83.31962 -398.6149) (xy 83.31981 -398.621773) (xy 83.323419 -398.635036)
			(xy 83.326732 -398.641062) (xy 83.343101 -398.669401) (xy 83.368843 -398.729571) (xy 83.386268 -398.792655)
			(xy 83.395057 -398.857508) (xy 83.395053 -398.922954) (xy 83.386255 -398.987806) (xy 83.368823 -399.050887)
			(xy 83.343073 -399.111054) (xy 83.326732 -399.13941) (xy 83.323416 -399.145434) (xy 83.319811 -399.158698)
			(xy 83.31962 -399.165572) (xy 83.31962 -399.451576) (xy 83.319159 -399.461726) (xy 83.311375 -399.480474)
			(xy 83.296991 -399.494798) (xy 83.27821 -399.502502) (xy 83.268058 -399.502884) (xy 82.551778 -399.502884)
			(xy 82.541653 -399.502392) (xy 82.522936 -399.494662) (xy 82.508581 -399.480378) (xy 82.500758 -399.461699)
			(xy 82.500216 -399.451576) (xy 82.500216 -399.165572) (xy 82.500033 -399.158698) (xy 82.496418 -399.145435)
			(xy 82.493104 -399.13941) (xy 82.476798 -399.111037) (xy 82.451053 -399.050874) (xy 82.433625 -398.987797)
			(xy 82.424829 -398.922951) (xy 82.424825 -398.857511) (xy 82.433612 -398.792664) (xy 82.451033 -398.729585)
			(xy 82.47677 -398.669418) (xy 82.493104 -398.641062) (xy 82.496433 -398.635044) (xy 82.500029 -398.621775)
			(xy 82.500216 -398.6149) (xy 82.500216 -397.865346) (xy 82.500005 -397.858474) (xy 82.49641 -397.845211)
			(xy 82.493104 -397.839184) (xy 82.476776 -397.810823) (xy 82.451033 -397.750657) (xy 82.433607 -397.687578)
			(xy 82.424814 -397.622729) (xy 82.424813 -397.557288) (xy 81.136205 -397.557288) (xy 81.143144 -397.569362)
			(xy 81.168892 -397.629524) (xy 81.186323 -397.692601) (xy 81.19512 -397.757447) (xy 81.195125 -397.822888)
			(xy 81.186336 -397.887736) (xy 81.168914 -397.950814) (xy 81.143174 -398.01098) (xy 81.126838 -398.039336)
			(xy 81.12346 -398.045344) (xy 81.119733 -398.05861) (xy 81.119472 -398.065498) (xy 81.119472 -398.351502)
			(xy 81.118975 -398.361627) (xy 81.111249 -398.380346) (xy 81.096966 -398.394702) (xy 81.078287 -398.402523)
			(xy 81.068164 -398.403064) (xy 80.351884 -398.403064) (xy 80.341724 -398.402691) (xy 80.322965 -398.394883)
			(xy 80.30864 -398.380471) (xy 80.300948 -398.361664) (xy 80.300576 -398.351502) (xy 80.300576 -398.065498)
			(xy 80.300347 -398.058606) (xy 80.296602 -398.04534) (xy 80.29321 -398.039336) (xy 80.276841 -398.010997)
			(xy 80.251102 -397.950826) (xy 80.23368 -397.887742) (xy 80.224892 -397.82289) (xy 78.936078 -397.82289)
			(xy 78.92669 -397.839184) (xy 78.923335 -397.845203) (xy 78.919593 -397.85846) (xy 78.919324 -397.865346)
			(xy 78.919324 -398.6149) (xy 78.919554 -398.621792) (xy 78.923298 -398.635058) (xy 78.92669 -398.641062)
			(xy 78.943057 -398.669402) (xy 78.968796 -398.729573) (xy 78.986219 -398.792656) (xy 78.995007 -398.857508)
			(xy 78.995003 -398.922953) (xy 78.986206 -398.987805) (xy 78.968776 -399.050886) (xy 78.943029 -399.111053)
			(xy 78.92669 -399.13941) (xy 78.923325 -399.145425) (xy 78.91959 -399.158685) (xy 78.919324 -399.165572)
			(xy 78.919324 -399.451576) (xy 78.918865 -399.461694) (xy 78.911129 -399.480393) (xy 78.896826 -399.494707)
			(xy 78.878134 -399.502457) (xy 78.868016 -399.502884) (xy 78.151736 -399.502884) (xy 78.141614 -399.502454)
			(xy 78.122908 -399.494715) (xy 78.108592 -399.480402) (xy 78.100848 -399.461698) (xy 78.100428 -399.451576)
			(xy 78.100428 -399.165572) (xy 78.100198 -399.158679) (xy 78.096468 -399.145407) (xy 78.093062 -399.13941)
			(xy 78.076754 -399.111037) (xy 78.051006 -399.050875) (xy 78.033576 -398.987798) (xy 78.024779 -398.922951)
			(xy 78.024775 -398.85751) (xy 78.033563 -398.792663) (xy 78.050986 -398.729584) (xy 78.076726 -398.669418)
			(xy 78.093062 -398.641062) (xy 78.096441 -398.635054) (xy 78.100167 -398.621788) (xy 78.100428 -398.6149)
			(xy 78.100428 -397.865346) (xy 78.100209 -397.858452) (xy 78.096471 -397.84518) (xy 78.093062 -397.839184)
			(xy 78.076732 -397.810823) (xy 78.050986 -397.750658) (xy 78.033558 -397.687579) (xy 78.024764 -397.62273)
			(xy 78.024763 -397.557287) (xy 76.736162 -397.557287) (xy 76.7431 -397.569362) (xy 76.768845 -397.629525)
			(xy 76.786274 -397.692601) (xy 76.79507 -397.757447) (xy 76.795075 -397.822887) (xy 76.786287 -397.887735)
			(xy 76.768867 -397.950813) (xy 76.74313 -398.01098) (xy 76.726796 -398.039336) (xy 76.723468 -398.045354)
			(xy 76.719871 -398.058623) (xy 76.719684 -398.065498) (xy 76.719684 -398.351502) (xy 76.719169 -398.361657)
			(xy 76.711398 -398.380422) (xy 76.697039 -398.394787) (xy 76.678277 -398.402565) (xy 76.668122 -398.403064)
			(xy 75.951842 -398.403064) (xy 75.941673 -398.402602) (xy 75.92288 -398.394831) (xy 75.908494 -398.380457)
			(xy 75.900707 -398.36167) (xy 75.90028 -398.351502) (xy 75.90028 -398.065498) (xy 75.900091 -398.058625)
			(xy 75.896481 -398.045362) (xy 75.893168 -398.039336) (xy 75.876798 -398.010998) (xy 75.851055 -397.950827)
			(xy 75.833631 -397.887743) (xy 75.824842 -397.82289) (xy 74.536036 -397.82289) (xy 74.526648 -397.839184)
			(xy 74.523343 -397.845213) (xy 74.519731 -397.858473) (xy 74.519536 -397.865346) (xy 74.519536 -398.6149)
			(xy 74.519724 -398.621774) (xy 74.523334 -398.635037) (xy 74.526648 -398.641062) (xy 74.543016 -398.669401)
			(xy 74.568758 -398.729572) (xy 74.586182 -398.792655) (xy 74.594971 -398.857508) (xy 74.594967 -398.922954)
			(xy 74.586169 -398.987805) (xy 74.568738 -399.050887) (xy 74.542988 -399.111054) (xy 74.526648 -399.13941)
			(xy 74.523334 -399.145435) (xy 74.519727 -399.158698) (xy 74.519536 -399.165572) (xy 74.519536 -399.451576)
			(xy 74.51906 -399.461724) (xy 74.511279 -399.480469) (xy 74.496899 -399.494792) (xy 74.478124 -399.502499)
			(xy 74.467974 -399.502884) (xy 73.751694 -399.502884) (xy 73.74157 -399.502379) (xy 73.722853 -399.494654)
			(xy 73.708498 -399.480373) (xy 73.700675 -399.461697) (xy 73.700132 -399.451576) (xy 73.700132 -399.165572)
			(xy 73.699947 -399.158698) (xy 73.696333 -399.145436) (xy 73.69302 -399.13941) (xy 73.676714 -399.111037)
			(xy 73.650968 -399.050874) (xy 73.633539 -398.987797) (xy 73.624743 -398.922951) (xy 73.624738 -398.857511)
			(xy 73.633526 -398.792663) (xy 73.650948 -398.729585) (xy 73.676686 -398.669418) (xy 73.69302 -398.641062)
			(xy 73.69635 -398.635045) (xy 73.699946 -398.621775) (xy 73.700132 -398.6149) (xy 73.700132 -397.865346)
			(xy 73.699919 -397.858474) (xy 73.696325 -397.845212) (xy 73.69302 -397.839184) (xy 73.676692 -397.810823)
			(xy 73.650948 -397.750657) (xy 73.633521 -397.687578) (xy 73.624728 -397.62273) (xy 73.624727 -397.557288)
			(xy 72.336121 -397.557288) (xy 72.343059 -397.569362) (xy 72.368807 -397.629524) (xy 72.386237 -397.692601)
			(xy 72.395034 -397.757447) (xy 72.395038 -397.822888) (xy 72.38625 -397.887735) (xy 72.368828 -397.950814)
			(xy 72.343089 -398.01098) (xy 72.326754 -398.039336) (xy 72.323378 -398.045345) (xy 72.31965 -398.05861)
			(xy 72.319388 -398.065498) (xy 72.319388 -398.351502) (xy 72.318876 -398.361625) (xy 72.311153 -398.380341)
			(xy 72.296875 -398.394696) (xy 72.278201 -398.40252) (xy 72.26808 -398.403064) (xy 71.5518 -398.403064)
			(xy 71.541641 -398.402678) (xy 71.522882 -398.394875) (xy 71.508557 -398.380467) (xy 71.500864 -398.361663)
			(xy 71.500492 -398.351502) (xy 71.500492 -398.065498) (xy 71.50026 -398.058606) (xy 71.496517 -398.045341)
			(xy 71.493126 -398.039336) (xy 71.476757 -398.010997) (xy 71.451017 -397.950827) (xy 71.433594 -397.887743)
			(xy 71.424806 -397.82289) (xy 70.644766 -397.82289) (xy 70.644766 -401.722803) (xy 71.424815 -401.722803)
			(xy 71.424817 -401.657359) (xy 71.433613 -401.592508) (xy 71.451041 -401.529428) (xy 71.476788 -401.46926)
			(xy 71.493126 -401.440904) (xy 71.496487 -401.434887) (xy 71.500225 -401.421628) (xy 71.500492 -401.414742)
			(xy 71.500492 -400.665442) (xy 71.500244 -400.658552) (xy 71.496512 -400.645286) (xy 71.493126 -400.63928)
			(xy 71.476794 -400.610921) (xy 71.45105 -400.550755) (xy 71.433624 -400.487675) (xy 71.424831 -400.422826)
			(xy 71.42483 -400.357384) (xy 71.433622 -400.292535) (xy 71.451047 -400.229455) (xy 71.476789 -400.169288)
			(xy 71.493126 -400.140932) (xy 71.496477 -400.13491) (xy 71.500221 -400.121655) (xy 71.500492 -400.11477)
			(xy 71.500492 -399.828766) (xy 71.500997 -399.818643) (xy 71.508727 -399.79993) (xy 71.523007 -399.785577)
			(xy 71.54168 -399.77775) (xy 71.5518 -399.777204) (xy 72.26808 -399.777204) (xy 72.278233 -399.777638)
			(xy 72.296986 -399.785428) (xy 72.31131 -399.799821) (xy 72.31901 -399.818611) (xy 72.319388 -399.828766)
			(xy 72.319388 -400.11477) (xy 72.3196 -400.121665) (xy 72.323342 -400.134937) (xy 72.326754 -400.140932)
			(xy 72.343097 -400.169285) (xy 72.36884 -400.229453) (xy 72.386267 -400.292533) (xy 72.395059 -400.357383)
			(xy 72.395058 -400.422827) (xy 72.386265 -400.487677) (xy 72.368837 -400.550757) (xy 72.343092 -400.610924)
			(xy 72.326754 -400.63928) (xy 72.323397 -400.645299) (xy 72.319657 -400.658556) (xy 72.319388 -400.665442)
			(xy 72.319388 -401.414742) (xy 72.31961 -401.421636) (xy 72.323346 -401.434908) (xy 72.326754 -401.440904)
			(xy 72.343073 -401.46927) (xy 72.368819 -401.529435) (xy 72.386248 -401.592513) (xy 72.395043 -401.65736)
			(xy 72.395046 -401.722802) (xy 72.386255 -401.78765) (xy 72.368831 -401.85073) (xy 72.34309 -401.910896)
			(xy 72.326754 -401.939252) (xy 72.323372 -401.945258) (xy 72.319648 -401.958525) (xy 72.319388 -401.965414)
			(xy 72.319388 -402.251418) (xy 72.318889 -402.261542) (xy 72.311161 -402.280259) (xy 72.296879 -402.294614)
			(xy 72.278202 -402.302437) (xy 72.26808 -402.30298) (xy 71.5518 -402.30298) (xy 71.541643 -402.302578)
			(xy 71.522887 -402.294779) (xy 71.508563 -402.280376) (xy 71.500867 -402.261577) (xy 71.500492 -402.251418)
			(xy 71.500492 -401.965414) (xy 71.500254 -401.958523) (xy 71.496515 -401.945257) (xy 71.493126 -401.939252)
			(xy 71.47677 -401.910906) (xy 71.451029 -401.850737) (xy 71.433605 -401.787655) (xy 71.424815 -401.722803)
			(xy 70.644766 -401.722803) (xy 70.644766 -402.822882) (xy 73.624695 -402.822882) (xy 73.6247 -402.757436)
			(xy 73.633499 -402.692584) (xy 73.650931 -402.629502) (xy 73.67668 -402.569334) (xy 73.69302 -402.540978)
			(xy 73.696344 -402.534958) (xy 73.699943 -402.521691) (xy 73.700132 -402.514816) (xy 73.700132 -401.765516)
			(xy 73.69993 -401.758644) (xy 73.696328 -401.745381) (xy 73.69302 -401.739354) (xy 73.676666 -401.711007)
			(xy 73.650925 -401.650838) (xy 73.633501 -401.587756) (xy 73.624711 -401.522905) (xy 73.624713 -401.457461)
			(xy 73.633508 -401.39261) (xy 73.650936 -401.32953) (xy 73.676682 -401.269362) (xy 73.69302 -401.241006)
			(xy 73.696334 -401.234981) (xy 73.69994 -401.221718) (xy 73.700132 -401.214844) (xy 73.700132 -400.92884)
			(xy 73.700555 -400.918685) (xy 73.708343 -400.899927) (xy 73.722741 -400.885601) (xy 73.741537 -400.877906)
			(xy 73.751694 -400.877532) (xy 74.467974 -400.877532) (xy 74.478098 -400.878047) (xy 74.496817 -400.885765)
			(xy 74.511174 -400.900043) (xy 74.518996 -400.918719) (xy 74.519536 -400.92884) (xy 74.519536 -401.214844)
			(xy 74.519745 -401.221716) (xy 74.523341 -401.234979) (xy 74.526648 -401.241006) (xy 74.542969 -401.269371)
			(xy 74.568715 -401.329536) (xy 74.586144 -401.392614) (xy 74.594939 -401.457462) (xy 74.594941 -401.522904)
			(xy 74.586151 -401.587752) (xy 74.568726 -401.650832) (xy 74.542984 -401.710998) (xy 74.536183 -401.722804)
			(xy 75.824851 -401.722804) (xy 75.824853 -401.657359) (xy 75.83365 -401.592508) (xy 75.85108 -401.529427)
			(xy 75.876828 -401.46926) (xy 75.893168 -401.440904) (xy 75.896479 -401.434877) (xy 75.900087 -401.421615)
			(xy 75.90028 -401.414742) (xy 75.90028 -400.665442) (xy 75.900074 -400.65857) (xy 75.896476 -400.645307)
			(xy 75.893168 -400.63928) (xy 75.876835 -400.610921) (xy 75.851089 -400.550756) (xy 75.833661 -400.487676)
			(xy 75.824867 -400.422827) (xy 75.824866 -400.357384) (xy 75.833659 -400.292534) (xy 75.851086 -400.229454)
			(xy 75.87683 -400.169288) (xy 75.893168 -400.140932) (xy 75.896469 -400.1349) (xy 75.900083 -400.121642)
			(xy 75.90028 -400.11477) (xy 75.90028 -399.828766) (xy 75.900637 -399.818587) (xy 75.908441 -399.799783)
			(xy 75.922847 -399.785398) (xy 75.941662 -399.777622) (xy 75.951842 -399.777204) (xy 76.668122 -399.777204)
			(xy 76.678277 -399.777714) (xy 76.69704 -399.78549) (xy 76.711404 -399.79985) (xy 76.719183 -399.818611)
			(xy 76.719684 -399.828766) (xy 76.719684 -400.11477) (xy 76.719889 -400.121642) (xy 76.723489 -400.134905)
			(xy 76.726796 -400.140932) (xy 76.743137 -400.169286) (xy 76.768879 -400.229453) (xy 76.786304 -400.292534)
			(xy 76.795095 -400.357384) (xy 76.795094 -400.422827) (xy 76.786301 -400.487676) (xy 76.768876 -400.550756)
			(xy 76.743133 -400.610923) (xy 76.726796 -400.63928) (xy 76.723488 -400.645308) (xy 76.719878 -400.658569)
			(xy 76.719684 -400.665442) (xy 76.719684 -401.414742) (xy 76.7199 -401.421613) (xy 76.723492 -401.434876)
			(xy 76.726796 -401.440904) (xy 76.743114 -401.469271) (xy 76.768857 -401.529435) (xy 76.786285 -401.592513)
			(xy 76.795079 -401.657361) (xy 76.795082 -401.722802) (xy 76.786292 -401.78765) (xy 76.76887 -401.850729)
			(xy 76.743131 -401.910895) (xy 76.726796 -401.939252) (xy 76.723462 -401.945267) (xy 76.719869 -401.958538)
			(xy 76.719684 -401.965414) (xy 76.719684 -402.251418) (xy 76.719182 -402.261574) (xy 76.711406 -402.28034)
			(xy 76.697043 -402.294704) (xy 76.678278 -402.302481) (xy 76.668122 -402.30298) (xy 75.951842 -402.30298)
			(xy 75.941675 -402.302502) (xy 75.922885 -402.294734) (xy 75.908499 -402.280365) (xy 75.90071 -402.261584)
			(xy 75.90028 -402.251418) (xy 75.90028 -401.965414) (xy 75.900085 -401.958541) (xy 75.896479 -401.945278)
			(xy 75.893168 -401.939252) (xy 75.876811 -401.910906) (xy 75.851067 -401.850738) (xy 75.833642 -401.787655)
			(xy 75.824851 -401.722804) (xy 74.536183 -401.722804) (xy 74.526648 -401.739354) (xy 74.523353 -401.745389)
			(xy 74.519735 -401.758645) (xy 74.519536 -401.765516) (xy 74.519536 -402.514816) (xy 74.519717 -402.52169)
			(xy 74.523332 -402.534953) (xy 74.526648 -402.540978) (xy 74.542945 -402.569356) (xy 74.568693 -402.629518)
			(xy 74.586125 -402.692593) (xy 74.594923 -402.757439) (xy 74.594929 -402.822879) (xy 74.594929 -402.822882)
			(xy 78.024731 -402.822882) (xy 78.024736 -402.757436) (xy 78.033536 -402.692583) (xy 78.050969 -402.629501)
			(xy 78.076721 -402.569334) (xy 78.093062 -402.540978) (xy 78.096435 -402.534967) (xy 78.100165 -402.521704)
			(xy 78.100428 -402.514816) (xy 78.100428 -401.765516) (xy 78.10022 -401.758621) (xy 78.096475 -401.745349)
			(xy 78.093062 -401.739354) (xy 78.076707 -401.711007) (xy 78.050963 -401.650839) (xy 78.033538 -401.587757)
			(xy 78.024747 -401.522905) (xy 78.024749 -401.457461) (xy 78.033545 -401.39261) (xy 78.050975 -401.329529)
			(xy 78.076723 -401.269362) (xy 78.093062 -401.241006) (xy 78.096425 -401.23499) (xy 78.100161 -401.22173)
			(xy 78.100428 -401.214844) (xy 78.100428 -400.92884) (xy 78.10085 -400.918717) (xy 78.10859 -400.900009)
			(xy 78.122905 -400.885692) (xy 78.141613 -400.87795) (xy 78.151736 -400.877532) (xy 78.868016 -400.877532)
			(xy 78.878144 -400.877903) (xy 78.896854 -400.885663) (xy 78.911169 -400.899993) (xy 78.918908 -400.918712)
			(xy 78.919324 -400.92884) (xy 78.919324 -401.214844) (xy 78.919576 -401.221734) (xy 78.923305 -401.235)
			(xy 78.92669 -401.241006) (xy 78.94301 -401.269372) (xy 78.968753 -401.329537) (xy 78.986181 -401.392615)
			(xy 78.994975 -401.457462) (xy 78.994978 -401.522903) (xy 78.986188 -401.587752) (xy 78.968765 -401.650831)
			(xy 78.943025 -401.710998) (xy 78.936225 -401.722803) (xy 80.224901 -401.722803) (xy 80.224903 -401.657359)
			(xy 80.233699 -401.592509) (xy 80.251127 -401.529428) (xy 80.276872 -401.469261) (xy 80.29321 -401.440904)
			(xy 80.29657 -401.434887) (xy 80.300309 -401.421628) (xy 80.300576 -401.414742) (xy 80.300576 -400.665442)
			(xy 80.30033 -400.658552) (xy 80.296597 -400.645286) (xy 80.29321 -400.63928) (xy 80.276879 -400.610921)
			(xy 80.251136 -400.550754) (xy 80.23371 -400.487675) (xy 80.224917 -400.422826) (xy 80.224916 -400.357384)
			(xy 80.233708 -400.292535) (xy 80.251132 -400.229455) (xy 80.276874 -400.169288) (xy 80.29321 -400.140932)
			(xy 80.29656 -400.13491) (xy 80.300305 -400.121655) (xy 80.300576 -400.11477) (xy 80.300576 -399.828766)
			(xy 80.301 -399.818633) (xy 80.308745 -399.799904) (xy 80.323051 -399.785548) (xy 80.341753 -399.777736)
			(xy 80.351884 -399.777204) (xy 81.068164 -399.777204) (xy 81.078316 -399.777651) (xy 81.097069 -399.785436)
			(xy 81.111393 -399.799825) (xy 81.119094 -399.818612) (xy 81.119472 -399.828766) (xy 81.119472 -400.11477)
			(xy 81.119685 -400.121664) (xy 81.123427 -400.134937) (xy 81.126838 -400.140932) (xy 81.143181 -400.169285)
			(xy 81.168926 -400.229452) (xy 81.186353 -400.292533) (xy 81.195145 -400.357383) (xy 81.195145 -400.422827)
			(xy 81.18635 -400.487677) (xy 81.168922 -400.550757) (xy 81.143176 -400.610924) (xy 81.126838 -400.63928)
			(xy 81.12348 -400.645298) (xy 81.119741 -400.658556) (xy 81.119472 -400.665442) (xy 81.119472 -401.414742)
			(xy 81.119696 -401.421635) (xy 81.123431 -401.434908) (xy 81.126838 -401.440904) (xy 81.143157 -401.46927)
			(xy 81.168904 -401.529434) (xy 81.186334 -401.592512) (xy 81.195129 -401.65736) (xy 81.195132 -401.722802)
			(xy 81.186341 -401.787651) (xy 81.168917 -401.85073) (xy 81.143175 -401.910896) (xy 81.126838 -401.939252)
			(xy 81.123455 -401.945257) (xy 81.119731 -401.958525) (xy 81.119472 -401.965414) (xy 81.119472 -402.251418)
			(xy 81.118989 -402.261544) (xy 81.111257 -402.280264) (xy 81.09697 -402.294619) (xy 81.078288 -402.30244)
			(xy 81.068164 -402.30298) (xy 80.351884 -402.30298) (xy 80.341726 -402.302591) (xy 80.32297 -402.294787)
			(xy 80.308646 -402.28038) (xy 80.30095 -402.261578) (xy 80.300576 -402.251418) (xy 80.300576 -401.965414)
			(xy 80.300341 -401.958523) (xy 80.2966 -401.945257) (xy 80.29321 -401.939252) (xy 80.276855 -401.910906)
			(xy 80.251114 -401.850736) (xy 80.233691 -401.787654) (xy 80.224901 -401.722803) (xy 78.936225 -401.722803)
			(xy 78.92669 -401.739354) (xy 78.92331 -401.745361) (xy 78.919584 -401.758628) (xy 78.919324 -401.765516)
			(xy 78.919324 -402.514816) (xy 78.919564 -402.521708) (xy 78.923288 -402.53498) (xy 78.92669 -402.540978)
			(xy 78.942986 -402.569357) (xy 78.968732 -402.629519) (xy 78.986162 -402.692594) (xy 78.994959 -402.757439)
			(xy 78.994965 -402.822878) (xy 78.994964 -402.822882) (xy 82.424781 -402.822882) (xy 82.424786 -402.757436)
			(xy 82.433585 -402.692584) (xy 82.451016 -402.629502) (xy 82.476765 -402.569335) (xy 82.493104 -402.540978)
			(xy 82.496427 -402.534957) (xy 82.500027 -402.521691) (xy 82.500216 -402.514816) (xy 82.500216 -401.765516)
			(xy 82.500016 -401.758643) (xy 82.496413 -401.745381) (xy 82.493104 -401.739354) (xy 82.476751 -401.711007)
			(xy 82.45101 -401.650838) (xy 82.433587 -401.587756) (xy 82.424797 -401.522905) (xy 82.424799 -401.457461)
			(xy 82.433594 -401.392611) (xy 82.451022 -401.32953) (xy 82.476766 -401.269363) (xy 82.493104 -401.241006)
			(xy 82.496417 -401.23498) (xy 82.500024 -401.221717) (xy 82.500216 -401.214844) (xy 82.500216 -400.92884)
			(xy 82.500655 -400.918687) (xy 82.50844 -400.899932) (xy 82.522832 -400.885607) (xy 82.541623 -400.877908)
			(xy 82.551778 -400.877532) (xy 83.268058 -400.877532) (xy 83.278181 -400.878061) (xy 83.2969 -400.885773)
			(xy 83.311257 -400.900047) (xy 83.319079 -400.91872) (xy 83.31962 -400.92884) (xy 83.31962 -401.214844)
			(xy 83.319831 -401.221716) (xy 83.323426 -401.234979) (xy 83.326732 -401.241006) (xy 83.343053 -401.269371)
			(xy 83.3688 -401.329535) (xy 83.38623 -401.392614) (xy 83.395025 -401.457462) (xy 83.395028 -401.522904)
			(xy 83.386237 -401.587753) (xy 83.368812 -401.650832) (xy 83.343069 -401.710998) (xy 83.336268 -401.722803)
			(xy 84.624691 -401.722803) (xy 84.624693 -401.657359) (xy 84.633488 -401.592509) (xy 84.650916 -401.529428)
			(xy 84.67666 -401.469261) (xy 84.692998 -401.440904) (xy 84.696357 -401.434886) (xy 84.700096 -401.421628)
			(xy 84.700364 -401.414742) (xy 84.700364 -400.665442) (xy 84.700141 -400.658548) (xy 84.696406 -400.645277)
			(xy 84.692998 -400.63928) (xy 84.676667 -400.610921) (xy 84.650925 -400.550754) (xy 84.633499 -400.487675)
			(xy 84.624706 -400.422826) (xy 84.624706 -400.357384) (xy 84.633497 -400.292535) (xy 84.650921 -400.229456)
			(xy 84.676662 -400.169289) (xy 84.692998 -400.140932) (xy 84.696347 -400.134909) (xy 84.700093 -400.121655)
			(xy 84.700364 -400.11477) (xy 84.700364 -399.828766) (xy 84.700799 -399.818634) (xy 84.708543 -399.799908)
			(xy 84.722845 -399.785552) (xy 84.741542 -399.777738) (xy 84.751672 -399.777204) (xy 85.467952 -399.777204)
			(xy 85.478104 -399.777661) (xy 85.496856 -399.785442) (xy 85.511181 -399.799828) (xy 85.518881 -399.818613)
			(xy 85.51926 -399.828766) (xy 85.51926 -400.11477) (xy 85.519475 -400.121664) (xy 85.523215 -400.134936)
			(xy 85.526626 -400.140932) (xy 85.54297 -400.169285) (xy 85.568715 -400.229452) (xy 85.586142 -400.292533)
			(xy 85.594935 -400.357383) (xy 85.594934 -400.422827) (xy 85.58614 -400.487677) (xy 85.568711 -400.550758)
			(xy 85.542965 -400.610924) (xy 85.526626 -400.63928) (xy 85.523267 -400.645297) (xy 85.519528 -400.658556)
			(xy 85.51926 -400.665442) (xy 85.51926 -401.414742) (xy 85.519486 -401.421635) (xy 85.523219 -401.434907)
			(xy 85.526626 -401.440904) (xy 85.542946 -401.46927) (xy 85.568693 -401.529434) (xy 85.586123 -401.592512)
			(xy 85.594919 -401.65736) (xy 85.594922 -401.722802) (xy 85.586131 -401.787651) (xy 85.568706 -401.85073)
			(xy 85.542963 -401.910896) (xy 85.526626 -401.939252) (xy 85.523242 -401.945257) (xy 85.519519 -401.958525)
			(xy 85.51926 -401.965414) (xy 85.51926 -402.251418) (xy 85.518788 -402.261546) (xy 85.511055 -402.280268)
			(xy 85.496764 -402.294623) (xy 85.478078 -402.302442) (xy 85.467952 -402.30298) (xy 84.751672 -402.30298)
			(xy 84.741514 -402.302601) (xy 84.722757 -402.294792) (xy 84.708434 -402.280383) (xy 84.700738 -402.261579)
			(xy 84.700364 -402.251418) (xy 84.700364 -401.965414) (xy 84.70013 -401.958523) (xy 84.696389 -401.945257)
			(xy 84.692998 -401.939252) (xy 84.676643 -401.910906) (xy 84.650903 -401.850736) (xy 84.63348 -401.787654)
			(xy 84.624691 -401.722803) (xy 83.336268 -401.722803) (xy 83.326732 -401.739354) (xy 83.323436 -401.745388)
			(xy 83.319818 -401.758644) (xy 83.31962 -401.765516) (xy 83.31962 -402.514816) (xy 83.319803 -402.52169)
			(xy 83.323417 -402.534953) (xy 83.326732 -402.540978) (xy 83.34303 -402.569356) (xy 83.368779 -402.629518)
			(xy 83.386211 -402.692593) (xy 83.395009 -402.757439) (xy 83.395015 -402.822879) (xy 83.395015 -402.822882)
			(xy 86.824817 -402.822882) (xy 86.824823 -402.757436) (xy 86.833622 -402.692584) (xy 86.851055 -402.629502)
			(xy 86.876805 -402.569334) (xy 86.893146 -402.540978) (xy 86.896517 -402.534967) (xy 86.900248 -402.521703)
			(xy 86.900512 -402.514816) (xy 86.900512 -401.765516) (xy 86.900306 -401.758621) (xy 86.89656 -401.745349)
			(xy 86.893146 -401.739354) (xy 86.876791 -401.711007) (xy 86.851049 -401.650838) (xy 86.833624 -401.587756)
			(xy 86.824833 -401.522905) (xy 86.824835 -401.457461) (xy 86.833631 -401.39261) (xy 86.85106 -401.329529)
			(xy 86.876807 -401.269362) (xy 86.893146 -401.241006) (xy 86.896508 -401.23499) (xy 86.900245 -401.22173)
			(xy 86.900512 -401.214844) (xy 86.900512 -400.92884) (xy 86.900949 -400.918719) (xy 86.908686 -400.900014)
			(xy 86.922997 -400.885698) (xy 86.941699 -400.877953) (xy 86.95182 -400.877532) (xy 87.6681 -400.877532)
			(xy 87.678226 -400.877917) (xy 87.696936 -400.885671) (xy 87.711252 -400.899997) (xy 87.718991 -400.918713)
			(xy 87.719408 -400.92884) (xy 87.719408 -401.214844) (xy 87.719662 -401.221734) (xy 87.72339 -401.235)
			(xy 87.726774 -401.241006) (xy 87.743094 -401.269372) (xy 87.768839 -401.329536) (xy 87.786267 -401.392614)
			(xy 87.795061 -401.457462) (xy 87.795064 -401.522904) (xy 87.786274 -401.587752) (xy 87.76885 -401.650831)
			(xy 87.74311 -401.710998) (xy 87.726774 -401.739354) (xy 87.723393 -401.745361) (xy 87.719668 -401.758627)
			(xy 87.719408 -401.765516) (xy 87.719408 -402.514816) (xy 87.719673 -402.521705) (xy 87.723394 -402.534971)
			(xy 87.726774 -402.540978) (xy 87.74307 -402.569357) (xy 87.768817 -402.629518) (xy 87.786248 -402.692594)
			(xy 87.795045 -402.757439) (xy 87.795051 -402.822879) (xy 87.786264 -402.887725) (xy 87.768845 -402.950804)
			(xy 87.743108 -403.01097) (xy 87.726774 -403.039326) (xy 87.723403 -403.045338) (xy 87.719671 -403.058601)
			(xy 87.719408 -403.065488) (xy 87.719408 -403.351492) (xy 87.718978 -403.361613) (xy 87.711234 -403.380315)
			(xy 87.696922 -403.394629) (xy 87.678221 -403.402376) (xy 87.6681 -403.4028) (xy 86.95182 -403.4028)
			(xy 86.941699 -403.402368) (xy 86.922996 -403.394626) (xy 86.908681 -403.380315) (xy 86.900935 -403.361613)
			(xy 86.900512 -403.351492) (xy 86.900512 -403.065488) (xy 86.900278 -403.058595) (xy 86.896551 -403.045323)
			(xy 86.893146 -403.039326) (xy 86.876768 -403.010992) (xy 86.851027 -402.95082) (xy 86.833605 -402.887736)
			(xy 86.824817 -402.822882) (xy 83.395015 -402.822882) (xy 83.386227 -402.887726) (xy 83.368806 -402.950805)
			(xy 83.343067 -403.01097) (xy 83.326732 -403.039326) (xy 83.323411 -403.045347) (xy 83.319809 -403.058614)
			(xy 83.31962 -403.065488) (xy 83.31962 -403.351492) (xy 83.319172 -403.361643) (xy 83.311383 -403.380391)
			(xy 83.296995 -403.394714) (xy 83.278211 -403.402418) (xy 83.268058 -403.4028) (xy 82.551778 -403.4028)
			(xy 82.541655 -403.402293) (xy 82.522941 -403.394565) (xy 82.508586 -403.380286) (xy 82.500761 -403.361613)
			(xy 82.500216 -403.351492) (xy 82.500216 -403.065488) (xy 82.500027 -403.058615) (xy 82.496416 -403.045352)
			(xy 82.493104 -403.039326) (xy 82.476727 -403.010992) (xy 82.450989 -402.95082) (xy 82.433568 -402.887735)
			(xy 82.424781 -402.822882) (xy 78.994964 -402.822882) (xy 78.986178 -402.887725) (xy 78.968759 -402.950803)
			(xy 78.943023 -403.01097) (xy 78.92669 -403.039326) (xy 78.92332 -403.045338) (xy 78.919588 -403.058601)
			(xy 78.919324 -403.065488) (xy 78.919324 -403.351492) (xy 78.918809 -403.361597) (xy 78.911078 -403.380271)
			(xy 78.896791 -403.394565) (xy 78.878121 -403.402304) (xy 78.868016 -403.4028) (xy 78.151736 -403.4028)
			(xy 78.141616 -403.402354) (xy 78.122913 -403.394618) (xy 78.108598 -403.38031) (xy 78.100851 -403.361612)
			(xy 78.100428 -403.351492) (xy 78.100428 -403.065488) (xy 78.100192 -403.058595) (xy 78.096466 -403.045323)
			(xy 78.093062 -403.039326) (xy 78.076683 -403.010993) (xy 78.050942 -402.950821) (xy 78.033519 -402.887736)
			(xy 78.024731 -402.822882) (xy 74.594929 -402.822882) (xy 74.586141 -402.887726) (xy 74.568721 -402.950804)
			(xy 74.542983 -403.01097) (xy 74.526648 -403.039326) (xy 74.523328 -403.045348) (xy 74.519725 -403.058614)
			(xy 74.519536 -403.065488) (xy 74.519536 -403.351492) (xy 74.519073 -403.361641) (xy 74.511286 -403.380386)
			(xy 74.496903 -403.394709) (xy 74.478125 -403.402415) (xy 74.467974 -403.4028) (xy 73.751694 -403.4028)
			(xy 73.741572 -403.402279) (xy 73.722858 -403.394557) (xy 73.708504 -403.380282) (xy 73.700678 -403.361611)
			(xy 73.700132 -403.351492) (xy 73.700132 -403.065488) (xy 73.699941 -403.058615) (xy 73.696332 -403.045352)
			(xy 73.69302 -403.039326) (xy 73.676643 -403.010992) (xy 73.650903 -402.95082) (xy 73.633482 -402.887735)
			(xy 73.624695 -402.822882) (xy 70.644766 -402.822882) (xy 70.644766 -405.622716) (xy 71.424824 -405.622716)
			(xy 71.424824 -405.557273) (xy 71.433618 -405.492424) (xy 71.451045 -405.429343) (xy 71.476789 -405.369176)
			(xy 71.493126 -405.34082) (xy 71.496481 -405.3348) (xy 71.500223 -405.321544) (xy 71.500492 -405.314658)
			(xy 71.500492 -404.565358) (xy 71.500238 -404.558468) (xy 71.49651 -404.545202) (xy 71.493126 -404.539196)
			(xy 71.476808 -404.510829) (xy 71.451063 -404.450665) (xy 71.433635 -404.387587) (xy 71.42484 -404.322739)
			(xy 71.424837 -404.257298) (xy 71.433627 -404.19245) (xy 71.45105 -404.129371) (xy 71.476791 -404.069204)
			(xy 71.493126 -404.040848) (xy 71.496506 -404.034841) (xy 71.500232 -404.021575) (xy 71.500492 -404.014686)
			(xy 71.500492 -403.728682) (xy 71.50101 -403.71856) (xy 71.508735 -403.699847) (xy 71.523011 -403.685493)
			(xy 71.541681 -403.677666) (xy 71.5518 -403.67712) (xy 72.26808 -403.67712) (xy 72.278235 -403.677538)
			(xy 72.296991 -403.685331) (xy 72.311316 -403.699729) (xy 72.319013 -403.718525) (xy 72.319388 -403.728682)
			(xy 72.319388 -404.014686) (xy 72.319593 -404.021581) (xy 72.32334 -404.034853) (xy 72.326754 -404.040848)
			(xy 72.34311 -404.069194) (xy 72.368853 -404.129363) (xy 72.386277 -404.192445) (xy 72.395068 -404.257297)
			(xy 72.395066 -404.322741) (xy 72.38627 -404.387592) (xy 72.36884 -404.450673) (xy 72.343093 -404.51084)
			(xy 72.326754 -404.539196) (xy 72.323392 -404.545212) (xy 72.319655 -404.558472) (xy 72.319388 -404.565358)
			(xy 72.319388 -405.314658) (xy 72.319604 -405.321552) (xy 72.323344 -405.334824) (xy 72.326754 -405.34082)
			(xy 72.343087 -405.369179) (xy 72.368831 -405.429345) (xy 72.386258 -405.492424) (xy 72.395052 -405.557274)
			(xy 72.395053 -405.622716) (xy 72.386261 -405.687565) (xy 72.368835 -405.750645) (xy 72.343091 -405.810812)
			(xy 72.326754 -405.839168) (xy 72.323402 -405.845189) (xy 72.319659 -405.858445) (xy 72.319388 -405.86533)
			(xy 72.319388 -406.151334) (xy 72.318902 -406.161459) (xy 72.311168 -406.180176) (xy 72.296883 -406.19453)
			(xy 72.278203 -406.202353) (xy 72.26808 -406.202896) (xy 71.5518 -406.202896) (xy 71.541645 -406.202478)
			(xy 71.522892 -406.194682) (xy 71.508569 -406.180284) (xy 71.50087 -406.161491) (xy 71.500492 -406.151334)
			(xy 71.500492 -405.86533) (xy 71.500248 -405.858439) (xy 71.496513 -405.845173) (xy 71.493126 -405.839168)
			(xy 71.476784 -405.810814) (xy 71.451041 -405.750647) (xy 71.433616 -405.687566) (xy 71.424824 -405.622716)
			(xy 70.644766 -405.622716) (xy 70.644766 -406.722795) (xy 73.624704 -406.722795) (xy 73.624707 -406.65735)
			(xy 73.633504 -406.592499) (xy 73.650934 -406.529418) (xy 73.676681 -406.46925) (xy 73.69302 -406.440894)
			(xy 73.696338 -406.434871) (xy 73.699941 -406.421606) (xy 73.700132 -406.414732) (xy 73.700132 -405.665432)
			(xy 73.699924 -405.65856) (xy 73.696326 -405.645297) (xy 73.69302 -405.63927) (xy 73.67668 -405.610915)
			(xy 73.650937 -405.550748) (xy 73.633512 -405.487668) (xy 73.62472 -405.422818) (xy 73.62472 -405.357375)
			(xy 73.633513 -405.292526) (xy 73.65094 -405.229445) (xy 73.676683 -405.169278) (xy 73.69302 -405.140922)
			(xy 73.696328 -405.134894) (xy 73.699938 -405.121633) (xy 73.700132 -405.11476) (xy 73.700132 -404.828756)
			(xy 73.700486 -404.818595) (xy 73.708302 -404.799836) (xy 73.72272 -404.785513) (xy 73.74153 -404.77782)
			(xy 73.751694 -404.777448) (xy 74.467974 -404.777448) (xy 74.4781 -404.777948) (xy 74.496822 -404.785669)
			(xy 74.51118 -404.799951) (xy 74.518998 -404.818633) (xy 74.519536 -404.828756) (xy 74.519536 -405.11476)
			(xy 74.519739 -405.121633) (xy 74.523339 -405.134895) (xy 74.526648 -405.140922) (xy 74.542982 -405.16928)
			(xy 74.568727 -405.229446) (xy 74.586155 -405.292526) (xy 74.594948 -405.357375) (xy 74.594949 -405.422818)
			(xy 74.586156 -405.487667) (xy 74.56873 -405.550747) (xy 74.542986 -405.610914) (xy 74.536185 -405.622717)
			(xy 75.82486 -405.622717) (xy 75.824861 -405.557273) (xy 75.833655 -405.492423) (xy 75.851083 -405.429342)
			(xy 75.876829 -405.369176) (xy 75.893168 -405.34082) (xy 75.896473 -405.334791) (xy 75.900085 -405.321531)
			(xy 75.90028 -405.314658) (xy 75.90028 -404.565358) (xy 75.900068 -404.558486) (xy 75.896474 -404.545223)
			(xy 75.893168 -404.539196) (xy 75.876848 -404.51083) (xy 75.851101 -404.450666) (xy 75.833672 -404.387588)
			(xy 75.824876 -404.32274) (xy 75.824873 -404.257298) (xy 75.833664 -404.192449) (xy 75.851089 -404.12937)
			(xy 75.876831 -404.069204) (xy 75.893168 -404.040848) (xy 75.896499 -404.034831) (xy 75.900094 -404.021561)
			(xy 75.90028 -404.014686) (xy 75.90028 -403.728682) (xy 75.90065 -403.718504) (xy 75.908449 -403.699701)
			(xy 75.922851 -403.685315) (xy 75.941664 -403.677538) (xy 75.951842 -403.67712) (xy 76.668122 -403.67712)
			(xy 76.678279 -403.677615) (xy 76.697045 -403.685393) (xy 76.711409 -403.699758) (xy 76.719186 -403.718525)
			(xy 76.719684 -403.728682) (xy 76.719684 -404.014686) (xy 76.719883 -404.021559) (xy 76.723487 -404.034821)
			(xy 76.726796 -404.040848) (xy 76.743151 -404.069194) (xy 76.768891 -404.129364) (xy 76.786314 -404.192446)
			(xy 76.795104 -404.257297) (xy 76.795102 -404.322741) (xy 76.786307 -404.387591) (xy 76.768879 -404.450672)
			(xy 76.743134 -404.510839) (xy 76.726796 -404.539196) (xy 76.723482 -404.545221) (xy 76.719876 -404.558485)
			(xy 76.719684 -404.565358) (xy 76.719684 -405.314658) (xy 76.719894 -405.32153) (xy 76.72349 -405.334793)
			(xy 76.726796 -405.34082) (xy 76.743127 -405.369179) (xy 76.76887 -405.429346) (xy 76.786295 -405.492425)
			(xy 76.795088 -405.557274) (xy 76.795089 -405.622716) (xy 76.786297 -405.687565) (xy 76.768873 -405.750645)
			(xy 76.743132 -405.810811) (xy 76.726796 -405.839168) (xy 76.723492 -405.845198) (xy 76.71988 -405.858458)
			(xy 76.719684 -405.86533) (xy 76.719684 -406.151334) (xy 76.719195 -406.161491) (xy 76.711414 -406.180257)
			(xy 76.697047 -406.19462) (xy 76.678279 -406.202397) (xy 76.668122 -406.202896) (xy 75.951842 -406.202896)
			(xy 75.941677 -406.202403) (xy 75.92289 -406.194638) (xy 75.908505 -406.180274) (xy 75.900712 -406.161498)
			(xy 75.90028 -406.151334) (xy 75.90028 -405.86533) (xy 75.900079 -405.858457) (xy 75.896477 -405.845195)
			(xy 75.893168 -405.839168) (xy 75.876825 -405.810815) (xy 75.85108 -405.750648) (xy 75.833653 -405.687567)
			(xy 75.82486 -405.622717) (xy 74.536185 -405.622717) (xy 74.526648 -405.63927) (xy 74.523348 -405.645302)
			(xy 74.519732 -405.65856) (xy 74.519536 -405.665432) (xy 74.519536 -406.414732) (xy 74.519711 -406.421607)
			(xy 74.523331 -406.434869) (xy 74.526648 -406.440894) (xy 74.542959 -406.469265) (xy 74.568706 -406.529428)
			(xy 74.586136 -406.592505) (xy 74.594932 -406.657352) (xy 74.594936 -406.722793) (xy 74.594936 -406.722795)
			(xy 78.02474 -406.722795) (xy 78.024744 -406.65735) (xy 78.033541 -406.592498) (xy 78.050972 -406.529417)
			(xy 78.076722 -406.46925) (xy 78.093062 -406.440894) (xy 78.096429 -406.434881) (xy 78.100163 -406.421619)
			(xy 78.100428 -406.414732) (xy 78.100428 -405.665432) (xy 78.100214 -405.658538) (xy 78.096473 -405.645266)
			(xy 78.093062 -405.63927) (xy 78.076721 -405.610916) (xy 78.050976 -405.550749) (xy 78.033549 -405.487668)
			(xy 78.024756 -405.422818) (xy 78.024756 -405.357375) (xy 78.03355 -405.292525) (xy 78.050978 -405.229445)
			(xy 78.076724 -405.169278) (xy 78.093062 -405.140922) (xy 78.09642 -405.134904) (xy 78.100159 -405.121646)
			(xy 78.100428 -405.11476) (xy 78.100428 -404.828756) (xy 78.10085 -404.818641) (xy 78.108607 -404.799956)
			(xy 78.122924 -404.785662) (xy 78.14162 -404.777934) (xy 78.151736 -404.777448) (xy 78.868016 -404.777448)
			(xy 78.878119 -404.777971) (xy 78.896788 -404.785704) (xy 78.91108 -404.799989) (xy 78.918823 -404.818653)
			(xy 78.919324 -404.828756) (xy 78.919324 -405.11476) (xy 78.919569 -405.12165) (xy 78.923303 -405.134917)
			(xy 78.92669 -405.140922) (xy 78.943023 -405.16928) (xy 78.968766 -405.229447) (xy 78.986192 -405.292526)
			(xy 78.994984 -405.357375) (xy 78.994985 -405.422818) (xy 78.986193 -405.487667) (xy 78.968768 -405.550747)
			(xy 78.943026 -405.610914) (xy 78.936227 -405.622716) (xy 80.22491 -405.622716) (xy 80.224911 -405.557273)
			(xy 80.233704 -405.492424) (xy 80.25113 -405.429344) (xy 80.276873 -405.369176) (xy 80.29321 -405.34082)
			(xy 80.296564 -405.3348) (xy 80.300306 -405.321544) (xy 80.300576 -405.314658) (xy 80.300576 -404.565358)
			(xy 80.300323 -404.558468) (xy 80.296594 -404.545202) (xy 80.29321 -404.539196) (xy 80.276892 -404.510829)
			(xy 80.251148 -404.450665) (xy 80.233721 -404.387587) (xy 80.224926 -404.322739) (xy 80.224923 -404.257298)
			(xy 80.233713 -404.19245) (xy 80.251136 -404.129371) (xy 80.276875 -404.069204) (xy 80.29321 -404.040848)
			(xy 80.296589 -404.03484) (xy 80.300316 -404.021574) (xy 80.300576 -404.014686) (xy 80.300576 -403.728682)
			(xy 80.301013 -403.71855) (xy 80.308753 -403.699821) (xy 80.323055 -403.685464) (xy 80.341754 -403.677652)
			(xy 80.351884 -403.67712) (xy 81.068164 -403.67712) (xy 81.078318 -403.677552) (xy 81.097074 -403.685339)
			(xy 81.111399 -403.699733) (xy 81.119096 -403.718526) (xy 81.119472 -403.728682) (xy 81.119472 -404.014686)
			(xy 81.119679 -404.021581) (xy 81.123425 -404.034853) (xy 81.126838 -404.040848) (xy 81.143195 -404.069194)
			(xy 81.168938 -404.129363) (xy 81.186363 -404.192445) (xy 81.195154 -404.257296) (xy 81.195152 -404.322741)
			(xy 81.186356 -404.387592) (xy 81.168926 -404.450673) (xy 81.143178 -404.51084) (xy 81.126838 -404.539196)
			(xy 81.123474 -404.545211) (xy 81.119738 -404.558471) (xy 81.119472 -404.565358) (xy 81.119472 -405.314658)
			(xy 81.11969 -405.321552) (xy 81.123428 -405.334824) (xy 81.126838 -405.34082) (xy 81.143171 -405.369179)
			(xy 81.168917 -405.429345) (xy 81.186344 -405.492424) (xy 81.195138 -405.557273) (xy 81.195139 -405.622716)
			(xy 81.186346 -405.687566) (xy 81.16892 -405.750646) (xy 81.143176 -405.810812) (xy 81.126838 -405.839168)
			(xy 81.123484 -405.845188) (xy 81.119742 -405.858445) (xy 81.119472 -405.86533) (xy 81.119472 -406.151334)
			(xy 81.119002 -406.161461) (xy 81.111265 -406.180181) (xy 81.096974 -406.194536) (xy 81.078289 -406.202356)
			(xy 81.068164 -406.202896) (xy 80.351884 -406.202896) (xy 80.341728 -406.202492) (xy 80.322975 -406.19469)
			(xy 80.308652 -406.180288) (xy 80.300953 -406.161492) (xy 80.300576 -406.151334) (xy 80.300576 -405.86533)
			(xy 80.300334 -405.858439) (xy 80.296598 -405.845173) (xy 80.29321 -405.839168) (xy 80.276868 -405.810814)
			(xy 80.251127 -405.750647) (xy 80.233702 -405.687566) (xy 80.22491 -405.622716) (xy 78.936227 -405.622716)
			(xy 78.92669 -405.63927) (xy 78.923339 -405.645292) (xy 78.919595 -405.658547) (xy 78.919324 -405.665432)
			(xy 78.919324 -406.414732) (xy 78.919558 -406.421625) (xy 78.923286 -406.434897) (xy 78.92669 -406.440894)
			(xy 78.942999 -406.469265) (xy 78.968744 -406.529429) (xy 78.986173 -406.592506) (xy 78.994968 -406.657352)
			(xy 78.994972 -406.722793) (xy 78.994972 -406.722795) (xy 82.42479 -406.722795) (xy 82.424794 -406.65735)
			(xy 82.43359 -406.592499) (xy 82.451019 -406.529418) (xy 82.476766 -406.469251) (xy 82.493104 -406.440894)
			(xy 82.496421 -406.434871) (xy 82.500025 -406.421606) (xy 82.500216 -406.414732) (xy 82.500216 -405.665432)
			(xy 82.50001 -405.65856) (xy 82.496411 -405.645297) (xy 82.493104 -405.63927) (xy 82.476764 -405.610915)
			(xy 82.451023 -405.550748) (xy 82.433598 -405.487667) (xy 82.424806 -405.422818) (xy 82.424806 -405.357375)
			(xy 82.433599 -405.292526) (xy 82.451025 -405.229446) (xy 82.476767 -405.169279) (xy 82.493104 -405.140922)
			(xy 82.496411 -405.134894) (xy 82.500022 -405.121633) (xy 82.500216 -405.11476) (xy 82.500216 -404.828756)
			(xy 82.500586 -404.818597) (xy 82.508399 -404.799841) (xy 82.522811 -404.785518) (xy 82.541617 -404.777823)
			(xy 82.551778 -404.777448) (xy 83.268058 -404.777448) (xy 83.278183 -404.777961) (xy 83.296905 -404.785677)
			(xy 83.311263 -404.799955) (xy 83.319082 -404.818634) (xy 83.31962 -404.828756) (xy 83.31962 -405.11476)
			(xy 83.319825 -405.121632) (xy 83.323424 -405.134895) (xy 83.326732 -405.140922) (xy 83.343067 -405.16928)
			(xy 83.368813 -405.229446) (xy 83.38624 -405.292526) (xy 83.395034 -405.357375) (xy 83.395035 -405.422818)
			(xy 83.386242 -405.487668) (xy 83.368815 -405.550748) (xy 83.34307 -405.610914) (xy 83.33627 -405.622716)
			(xy 84.6247 -405.622716) (xy 84.6247 -405.557273) (xy 84.633493 -405.492424) (xy 84.650919 -405.429344)
			(xy 84.676662 -405.369177) (xy 84.692998 -405.34082) (xy 84.696351 -405.334799) (xy 84.700094 -405.321543)
			(xy 84.700364 -405.314658) (xy 84.700364 -404.565358) (xy 84.700135 -404.558465) (xy 84.696404 -404.545193)
			(xy 84.692998 -404.539196) (xy 84.676681 -404.510829) (xy 84.650937 -404.450664) (xy 84.63351 -404.387587)
			(xy 84.624716 -404.322739) (xy 84.624713 -404.257298) (xy 84.633503 -404.19245) (xy 84.650925 -404.129371)
			(xy 84.676663 -404.069205) (xy 84.692998 -404.040848) (xy 84.696376 -404.03484) (xy 84.700104 -404.021574)
			(xy 84.700364 -404.014686) (xy 84.700364 -403.728682) (xy 84.700812 -403.718551) (xy 84.70855 -403.699825)
			(xy 84.722849 -403.685468) (xy 84.741543 -403.677654) (xy 84.751672 -403.67712) (xy 85.467952 -403.67712)
			(xy 85.478105 -403.677561) (xy 85.496861 -403.685345) (xy 85.511186 -403.699736) (xy 85.518884 -403.718527)
			(xy 85.51926 -403.728682) (xy 85.51926 -404.014686) (xy 85.519469 -404.021581) (xy 85.523214 -404.034853)
			(xy 85.526626 -404.040848) (xy 85.542983 -404.069194) (xy 85.568727 -404.129362) (xy 85.586153 -404.192445)
			(xy 85.594944 -404.257296) (xy 85.594942 -404.322741) (xy 85.586145 -404.387592) (xy 85.568715 -404.450673)
			(xy 85.542966 -404.51084) (xy 85.526626 -404.539196) (xy 85.523261 -404.545211) (xy 85.519526 -404.558471)
			(xy 85.51926 -404.565358) (xy 85.51926 -405.314658) (xy 85.519479 -405.321552) (xy 85.523217 -405.334824)
			(xy 85.526626 -405.34082) (xy 85.542959 -405.369179) (xy 85.568706 -405.429344) (xy 85.586134 -405.492424)
			(xy 85.594928 -405.557273) (xy 85.594929 -405.622716) (xy 85.586136 -405.687566) (xy 85.568709 -405.750646)
			(xy 85.542964 -405.810812) (xy 85.526626 -405.839168) (xy 85.523271 -405.845188) (xy 85.51953 -405.858444)
			(xy 85.51926 -405.86533) (xy 85.51926 -406.151334) (xy 85.518801 -406.161463) (xy 85.511062 -406.180185)
			(xy 85.496768 -406.19454) (xy 85.478079 -406.202358) (xy 85.467952 -406.202896) (xy 84.751672 -406.202896)
			(xy 84.741516 -406.202501) (xy 84.722762 -406.194696) (xy 84.708439 -406.180291) (xy 84.700741 -406.161493)
			(xy 84.700364 -406.151334) (xy 84.700364 -405.86533) (xy 84.700146 -405.858436) (xy 84.696407 -405.845164)
			(xy 84.692998 -405.839168) (xy 84.676657 -405.810814) (xy 84.650916 -405.750646) (xy 84.633491 -405.687566)
			(xy 84.6247 -405.622716) (xy 83.33627 -405.622716) (xy 83.326732 -405.63927) (xy 83.323431 -405.645301)
			(xy 83.319816 -405.65856) (xy 83.31962 -405.665432) (xy 83.31962 -406.414732) (xy 83.319797 -406.421606)
			(xy 83.323415 -406.434869) (xy 83.326732 -406.440894) (xy 83.343043 -406.469265) (xy 83.368791 -406.529428)
			(xy 83.386222 -406.592505) (xy 83.395018 -406.657352) (xy 83.395022 -406.722793) (xy 83.395022 -406.722795)
			(xy 86.824826 -406.722795) (xy 86.82483 -406.65735) (xy 86.833627 -406.592499) (xy 86.851058 -406.529417)
			(xy 86.876806 -406.46925) (xy 86.893146 -406.440894) (xy 86.896512 -406.43488) (xy 86.900246 -406.421619)
			(xy 86.900512 -406.414732) (xy 86.900512 -405.665432) (xy 86.9003 -405.658538) (xy 86.896558 -405.645265)
			(xy 86.893146 -405.63927) (xy 86.876805 -405.610916) (xy 86.851061 -405.550749) (xy 86.833635 -405.487668)
			(xy 86.824842 -405.422818) (xy 86.824843 -405.357375) (xy 86.833636 -405.292525) (xy 86.851063 -405.229445)
			(xy 86.876808 -405.169278) (xy 86.893146 -405.140922) (xy 86.896502 -405.134903) (xy 86.900243 -405.121646)
			(xy 86.900512 -405.11476) (xy 86.900512 -404.828756) (xy 86.900949 -404.818643) (xy 86.908704 -404.799961)
			(xy 86.923015 -404.785668) (xy 86.941706 -404.777937) (xy 86.95182 -404.777448) (xy 87.6681 -404.777448)
			(xy 87.678202 -404.777984) (xy 87.696871 -404.785712) (xy 87.711163 -404.799993) (xy 87.718907 -404.818654)
			(xy 87.719408 -404.828756) (xy 87.719408 -405.11476) (xy 87.719656 -405.12165) (xy 87.723388 -405.134916)
			(xy 87.726774 -405.140922) (xy 87.743108 -405.16928) (xy 87.768851 -405.229447) (xy 87.786277 -405.292526)
			(xy 87.795071 -405.357375) (xy 87.795071 -405.422818) (xy 87.786279 -405.487667) (xy 87.768853 -405.550747)
			(xy 87.743111 -405.610914) (xy 87.726774 -405.63927) (xy 87.723422 -405.645291) (xy 87.719679 -405.658547)
			(xy 87.719408 -405.665432) (xy 87.719408 -406.414732) (xy 87.719666 -406.421621) (xy 87.723391 -406.434887)
			(xy 87.726774 -406.440894) (xy 87.743084 -406.469265) (xy 87.76883 -406.529429) (xy 87.786259 -406.592506)
			(xy 87.795055 -406.657352) (xy 87.795058 -406.722793) (xy 87.78627 -406.787641) (xy 87.768848 -406.850719)
			(xy 87.743109 -406.910886) (xy 87.726774 -406.939242) (xy 87.723397 -406.945251) (xy 87.719669 -406.958516)
			(xy 87.719408 -406.965404) (xy 87.719408 -407.251408) (xy 87.718921 -407.261516) (xy 87.711183 -407.280193)
			(xy 87.696886 -407.294487) (xy 87.678208 -407.302223) (xy 87.6681 -407.302716) (xy 86.95182 -407.302716)
			(xy 86.941701 -407.302268) (xy 86.923001 -407.29453) (xy 86.908686 -407.280223) (xy 86.900937 -407.261527)
			(xy 86.900512 -407.251408) (xy 86.900512 -406.965404) (xy 86.900311 -406.958509) (xy 86.896561 -406.945236)
			(xy 86.893146 -406.939242) (xy 86.876781 -406.910901) (xy 86.85104 -406.850731) (xy 86.833616 -406.787648)
			(xy 86.824826 -406.722795) (xy 83.395022 -406.722795) (xy 83.386233 -406.787641) (xy 83.368809 -406.85072)
			(xy 83.343068 -406.910886) (xy 83.326732 -406.939242) (xy 83.323405 -406.945261) (xy 83.319807 -406.958529)
			(xy 83.31962 -406.965404) (xy 83.31962 -407.251408) (xy 83.319185 -407.26156) (xy 83.311391 -407.280309)
			(xy 83.296998 -407.294631) (xy 83.278212 -407.302334) (xy 83.268058 -407.302716) (xy 82.551778 -407.302716)
			(xy 82.541644 -407.30229) (xy 82.522914 -407.294547) (xy 82.508557 -407.280242) (xy 82.500747 -407.26154)
			(xy 82.500216 -407.251408) (xy 82.500216 -406.965404) (xy 82.500021 -406.958531) (xy 82.496415 -406.945268)
			(xy 82.493104 -406.939242) (xy 82.476741 -406.9109) (xy 82.451001 -406.85073) (xy 82.433579 -406.787647)
			(xy 82.42479 -406.722795) (xy 78.994972 -406.722795) (xy 78.986184 -406.78764) (xy 78.968762 -406.850719)
			(xy 78.943024 -406.910886) (xy 78.92669 -406.939242) (xy 78.923314 -406.945251) (xy 78.919585 -406.958516)
			(xy 78.919324 -406.965404) (xy 78.919324 -407.251408) (xy 78.918822 -407.261514) (xy 78.911086 -407.280188)
			(xy 78.896795 -407.294482) (xy 78.878122 -407.30222) (xy 78.868016 -407.302716) (xy 78.151736 -407.302716)
			(xy 78.141618 -407.302255) (xy 78.122918 -407.294521) (xy 78.108603 -407.280219) (xy 78.100854 -407.261526)
			(xy 78.100428 -407.251408) (xy 78.100428 -406.965404) (xy 78.100225 -406.958509) (xy 78.096476 -406.945237)
			(xy 78.093062 -406.939242) (xy 78.076697 -406.910901) (xy 78.050954 -406.850731) (xy 78.03353 -406.787648)
			(xy 78.02474 -406.722795) (xy 74.594936 -406.722795) (xy 74.586147 -406.787641) (xy 74.568724 -406.85072)
			(xy 74.542984 -406.910886) (xy 74.526648 -406.939242) (xy 74.523322 -406.945261) (xy 74.519723 -406.958529)
			(xy 74.519536 -406.965404) (xy 74.519536 -407.251408) (xy 74.519085 -407.261558) (xy 74.511294 -407.280304)
			(xy 74.496907 -407.294625) (xy 74.478126 -407.302331) (xy 74.467974 -407.302716) (xy 73.751694 -407.302716)
			(xy 73.741562 -407.302277) (xy 73.722832 -407.294539) (xy 73.708474 -407.280238) (xy 73.700663 -407.261538)
			(xy 73.700132 -407.251408) (xy 73.700132 -406.965404) (xy 73.699935 -406.958531) (xy 73.69633 -406.945269)
			(xy 73.69302 -406.939242) (xy 73.676656 -406.910901) (xy 73.650916 -406.85073) (xy 73.633493 -406.787647)
			(xy 73.624704 -406.722795) (xy 70.644766 -406.722795) (xy 70.644766 -409.522892) (xy 71.424807 -409.522892)
			(xy 71.424811 -409.457447) (xy 71.433608 -409.392595) (xy 71.451039 -409.329514) (xy 71.476787 -409.269346)
			(xy 71.493126 -409.24099) (xy 71.496492 -409.234976) (xy 71.500227 -409.221715) (xy 71.500492 -409.214828)
			(xy 71.500492 -408.465528) (xy 71.500249 -408.458637) (xy 71.496513 -408.445371) (xy 71.493126 -408.439366)
			(xy 71.476782 -408.411013) (xy 71.45104 -408.350846) (xy 71.433614 -408.287765) (xy 71.424823 -408.222915)
			(xy 71.424824 -408.157471) (xy 71.433617 -408.092622) (xy 71.451044 -408.029541) (xy 71.476789 -407.969374)
			(xy 71.493126 -407.941018) (xy 71.496482 -407.934999) (xy 71.500223 -407.921742) (xy 71.500492 -407.914856)
			(xy 71.500492 -407.628852) (xy 71.500946 -407.618741) (xy 71.508698 -407.600063) (xy 71.523004 -407.585771)
			(xy 71.541689 -407.578036) (xy 71.5518 -407.577544) (xy 72.26808 -407.577544) (xy 72.278181 -407.5781)
			(xy 72.296848 -407.585821) (xy 72.311141 -407.600095) (xy 72.318887 -407.618752) (xy 72.319388 -407.628852)
			(xy 72.319388 -407.914856) (xy 72.319605 -407.92175) (xy 72.323344 -407.935022) (xy 72.326754 -407.941018)
			(xy 72.343085 -407.969378) (xy 72.36883 -408.029544) (xy 72.386257 -408.092623) (xy 72.395051 -408.157472)
			(xy 72.395052 -408.222914) (xy 72.38626 -408.287764) (xy 72.368834 -408.350843) (xy 72.343091 -408.41101)
			(xy 72.326754 -408.439366) (xy 72.323402 -408.445387) (xy 72.319659 -408.458643) (xy 72.319388 -408.465528)
			(xy 72.319388 -409.214828) (xy 72.319616 -409.221721) (xy 72.323347 -409.234993) (xy 72.326754 -409.24099)
			(xy 72.343061 -409.269363) (xy 72.368808 -409.329526) (xy 72.386238 -409.392602) (xy 72.395035 -409.457449)
			(xy 72.395039 -409.522889) (xy 72.386251 -409.587737) (xy 72.368829 -409.650816) (xy 72.343089 -409.710982)
			(xy 72.326754 -409.739338) (xy 72.323377 -409.745347) (xy 72.31965 -409.758612) (xy 72.319388 -409.7655)
			(xy 72.319388 -410.051504) (xy 72.318987 -410.061628) (xy 72.311235 -410.080334) (xy 72.296914 -410.094649)
			(xy 72.278204 -410.102392) (xy 72.26808 -410.102812) (xy 71.5518 -410.102812) (xy 71.541693 -410.102315)
			(xy 71.523017 -410.09458) (xy 71.508723 -410.080286) (xy 71.500986 -410.061611) (xy 71.500492 -410.051504)
			(xy 71.500492 -409.7655) (xy 71.50026 -409.758609) (xy 71.496517 -409.745343) (xy 71.493126 -409.739338)
			(xy 71.476759 -409.710999) (xy 71.451018 -409.650828) (xy 71.433596 -409.587744) (xy 71.424807 -409.522892)
			(xy 70.644766 -409.522892) (xy 70.644766 -410.622708) (xy 73.624713 -410.622708) (xy 73.624715 -410.557264)
			(xy 73.633509 -410.492414) (xy 73.650937 -410.429334) (xy 73.676682 -410.369166) (xy 73.69302 -410.34081)
			(xy 73.696333 -410.334784) (xy 73.699939 -410.321521) (xy 73.700132 -410.314648) (xy 73.700132 -409.565348)
			(xy 73.699918 -409.558476) (xy 73.696324 -409.545214) (xy 73.69302 -409.539186) (xy 73.676693 -409.510824)
			(xy 73.65095 -409.450658) (xy 73.633523 -409.38758) (xy 73.624729 -409.322731) (xy 73.624727 -409.257289)
			(xy 73.633519 -409.192441) (xy 73.650943 -409.129361) (xy 73.676684 -409.069194) (xy 73.69302 -409.040838)
			(xy 73.696323 -409.034807) (xy 73.699936 -409.021548) (xy 73.700132 -409.014676) (xy 73.700132 -408.728672)
			(xy 73.700499 -408.718512) (xy 73.70831 -408.699753) (xy 73.722724 -408.685429) (xy 73.741532 -408.677736)
			(xy 73.751694 -408.677364) (xy 74.467974 -408.677364) (xy 74.478102 -408.677848) (xy 74.496827 -408.685572)
			(xy 74.511185 -408.69986) (xy 74.519001 -408.718546) (xy 74.519536 -408.728672) (xy 74.519536 -409.014676)
			(xy 74.519733 -409.021549) (xy 74.523337 -409.034812) (xy 74.526648 -409.040838) (xy 74.542996 -409.069188)
			(xy 74.56874 -409.129356) (xy 74.586165 -409.192438) (xy 74.594957 -409.257288) (xy 74.594956 -409.322732)
			(xy 74.586161 -409.387583) (xy 74.568733 -409.450663) (xy 74.542987 -409.51083) (xy 74.536037 -409.522892)
			(xy 75.824843 -409.522892) (xy 75.824847 -409.457446) (xy 75.833645 -409.392594) (xy 75.851077 -409.329513)
			(xy 75.876827 -409.269346) (xy 75.893168 -409.24099) (xy 75.896484 -409.234966) (xy 75.900089 -409.221702)
			(xy 75.90028 -409.214828) (xy 75.90028 -408.465528) (xy 75.90008 -408.458655) (xy 75.896477 -408.445393)
			(xy 75.893168 -408.439366) (xy 75.876823 -408.411014) (xy 75.851078 -408.350847) (xy 75.833651 -408.287766)
			(xy 75.824859 -408.222915) (xy 75.82486 -408.157471) (xy 75.833654 -408.092621) (xy 75.851083 -408.02954)
			(xy 75.876829 -407.969374) (xy 75.893168 -407.941018) (xy 75.896474 -407.934989) (xy 75.900085 -407.921729)
			(xy 75.90028 -407.914856) (xy 75.90028 -407.628852) (xy 75.900682 -407.618697) (xy 75.90849 -407.599948)
			(xy 75.922892 -407.585627) (xy 75.941685 -407.577925) (xy 75.951842 -407.577544) (xy 76.668122 -407.577544)
			(xy 76.678251 -407.578008) (xy 76.696973 -407.585744) (xy 76.711329 -407.600037) (xy 76.719147 -407.618726)
			(xy 76.719684 -407.628852) (xy 76.719684 -407.914856) (xy 76.719895 -407.921728) (xy 76.72349 -407.934991)
			(xy 76.726796 -407.941018) (xy 76.743125 -407.969378) (xy 76.768868 -408.029544) (xy 76.786294 -408.092624)
			(xy 76.795087 -408.157472) (xy 76.795088 -408.222914) (xy 76.786297 -408.287763) (xy 76.768873 -408.350843)
			(xy 76.743132 -408.411009) (xy 76.726796 -408.439366) (xy 76.723493 -408.445396) (xy 76.71988 -408.458656)
			(xy 76.719684 -408.465528) (xy 76.719684 -409.214828) (xy 76.719867 -409.221702) (xy 76.723482 -409.234965)
			(xy 76.726796 -409.24099) (xy 76.743102 -409.269363) (xy 76.768847 -409.329526) (xy 76.786275 -409.392603)
			(xy 76.795071 -409.457449) (xy 76.795075 -409.522889) (xy 76.786288 -409.587736) (xy 76.768867 -409.650815)
			(xy 76.74313 -409.710982) (xy 76.726796 -409.739338) (xy 76.723467 -409.745356) (xy 76.719871 -409.758625)
			(xy 76.719684 -409.7655) (xy 76.719684 -410.051504) (xy 76.719281 -410.06166) (xy 76.711481 -410.080416)
			(xy 76.697079 -410.09474) (xy 76.678281 -410.102436) (xy 76.668122 -410.102812) (xy 75.951842 -410.102812)
			(xy 75.941724 -410.10224) (xy 75.923014 -410.094536) (xy 75.908658 -410.080276) (xy 75.900828 -410.061618)
			(xy 75.90028 -410.051504) (xy 75.90028 -409.7655) (xy 75.90009 -409.758627) (xy 75.896481 -409.745364)
			(xy 75.893168 -409.739338) (xy 75.876799 -409.710999) (xy 75.851057 -409.650829) (xy 75.833632 -409.587745)
			(xy 75.824843 -409.522892) (xy 74.536037 -409.522892) (xy 74.526648 -409.539186) (xy 74.523342 -409.545215)
			(xy 74.51973 -409.558475) (xy 74.519536 -409.565348) (xy 74.519536 -410.314648) (xy 74.519743 -410.32152)
			(xy 74.523341 -410.334783) (xy 74.526648 -410.34081) (xy 74.542972 -410.369174) (xy 74.568718 -410.429338)
			(xy 74.586146 -410.492417) (xy 74.594941 -410.557265) (xy 74.594943 -410.622707) (xy 74.594943 -410.622708)
			(xy 78.024749 -410.622708) (xy 78.024751 -410.557264) (xy 78.033546 -410.492413) (xy 78.050976 -410.429333)
			(xy 78.076723 -410.369166) (xy 78.093062 -410.34081) (xy 78.096424 -410.334794) (xy 78.100161 -410.321534)
			(xy 78.100428 -410.314648) (xy 78.100428 -409.565348) (xy 78.100208 -409.558454) (xy 78.096471 -409.545182)
			(xy 78.093062 -409.539186) (xy 78.076734 -409.510824) (xy 78.050988 -409.450659) (xy 78.03356 -409.38758)
			(xy 78.024765 -409.322731) (xy 78.024764 -409.257289) (xy 78.033555 -409.19244) (xy 78.050981 -409.12936)
			(xy 78.076725 -409.069194) (xy 78.093062 -409.040838) (xy 78.096449 -409.034834) (xy 78.10017 -409.021565)
			(xy 78.100428 -409.014676) (xy 78.100428 -408.728672) (xy 78.100794 -408.718544) (xy 78.108556 -408.699835)
			(xy 78.122888 -408.68552) (xy 78.141608 -408.677781) (xy 78.151736 -408.677364) (xy 78.868016 -408.677364)
			(xy 78.878121 -408.677871) (xy 78.896793 -408.685608) (xy 78.911086 -408.699897) (xy 78.918826 -408.718567)
			(xy 78.919324 -408.728672) (xy 78.919324 -409.014676) (xy 78.919563 -409.021567) (xy 78.923301 -409.034833)
			(xy 78.92669 -409.040838) (xy 78.943037 -409.069189) (xy 78.968778 -409.129357) (xy 78.986202 -409.192438)
			(xy 78.994993 -409.257289) (xy 78.994992 -409.322732) (xy 78.986198 -409.387582) (xy 78.968771 -409.450662)
			(xy 78.943027 -409.51083) (xy 78.936078 -409.522892) (xy 80.224893 -409.522892) (xy 80.224897 -409.457447)
			(xy 80.233694 -409.392595) (xy 80.251124 -409.329514) (xy 80.276871 -409.269347) (xy 80.29321 -409.24099)
			(xy 80.296575 -409.234975) (xy 80.30031 -409.221715) (xy 80.300576 -409.214828) (xy 80.300576 -408.465528)
			(xy 80.300335 -408.458637) (xy 80.296598 -408.445371) (xy 80.29321 -408.439366) (xy 80.276867 -408.411013)
			(xy 80.251125 -408.350845) (xy 80.2337 -408.287765) (xy 80.224909 -408.222915) (xy 80.22491 -408.157472)
			(xy 80.233703 -408.092622) (xy 80.25113 -408.029542) (xy 80.276873 -407.969374) (xy 80.29321 -407.941018)
			(xy 80.296565 -407.934998) (xy 80.300307 -407.921742) (xy 80.300576 -407.914856) (xy 80.300576 -407.628852)
			(xy 80.301045 -407.618743) (xy 80.308794 -407.600069) (xy 80.323095 -407.585776) (xy 80.341775 -407.578039)
			(xy 80.351884 -407.577544) (xy 81.068164 -407.577544) (xy 81.078264 -407.578113) (xy 81.09693 -407.585829)
			(xy 81.111224 -407.600099) (xy 81.11897 -407.618753) (xy 81.119472 -407.628852) (xy 81.119472 -407.914856)
			(xy 81.119691 -407.92175) (xy 81.123428 -407.935022) (xy 81.126838 -407.941018) (xy 81.143169 -407.969378)
			(xy 81.168915 -408.029543) (xy 81.186343 -408.092623) (xy 81.195137 -408.157472) (xy 81.195138 -408.222914)
			(xy 81.186346 -408.287764) (xy 81.16892 -408.350844) (xy 81.143176 -408.41101) (xy 81.126838 -408.439366)
			(xy 81.123485 -408.445386) (xy 81.119742 -408.458643) (xy 81.119472 -408.465528) (xy 81.119472 -409.214828)
			(xy 81.119702 -409.221721) (xy 81.123432 -409.234993) (xy 81.126838 -409.24099) (xy 81.143146 -409.269363)
			(xy 81.168894 -409.329525) (xy 81.186324 -409.392602) (xy 81.195121 -409.457449) (xy 81.195125 -409.52289)
			(xy 81.186337 -409.587737) (xy 81.168914 -409.650816) (xy 81.143174 -409.710982) (xy 81.126838 -409.739338)
			(xy 81.123459 -409.745346) (xy 81.119733 -409.758612) (xy 81.119472 -409.7655) (xy 81.119472 -410.051504)
			(xy 81.119086 -410.06163) (xy 81.111332 -410.080339) (xy 81.097006 -410.094654) (xy 81.078291 -410.102394)
			(xy 81.068164 -410.102812) (xy 80.351884 -410.102812) (xy 80.341776 -410.102328) (xy 80.3231 -410.094587)
			(xy 80.308806 -410.08029) (xy 80.30107 -410.061612) (xy 80.300576 -410.051504) (xy 80.300576 -409.7655)
			(xy 80.300346 -409.758608) (xy 80.296602 -409.745342) (xy 80.29321 -409.739338) (xy 80.276843 -409.710998)
			(xy 80.251104 -409.650827) (xy 80.233681 -409.587744) (xy 80.224893 -409.522892) (xy 78.936078 -409.522892)
			(xy 78.92669 -409.539186) (xy 78.923334 -409.545205) (xy 78.919593 -409.558462) (xy 78.919324 -409.565348)
			(xy 78.919324 -410.314648) (xy 78.919574 -410.321538) (xy 78.923304 -410.334804) (xy 78.92669 -410.34081)
			(xy 78.943013 -410.369174) (xy 78.968757 -410.429339) (xy 78.986183 -410.492418) (xy 78.994977 -410.557266)
			(xy 78.994979 -410.622707) (xy 78.994979 -410.622708) (xy 82.424799 -410.622708) (xy 82.424801 -410.557264)
			(xy 82.433595 -410.492414) (xy 82.451022 -410.429334) (xy 82.476767 -410.369167) (xy 82.493104 -410.34081)
			(xy 82.496415 -410.334784) (xy 82.500023 -410.321521) (xy 82.500216 -410.314648) (xy 82.500216 -409.565348)
			(xy 82.500003 -409.558476) (xy 82.496409 -409.545214) (xy 82.493104 -409.539186) (xy 82.476778 -409.510824)
			(xy 82.451035 -409.450658) (xy 82.433609 -409.387579) (xy 82.424815 -409.322731) (xy 82.424814 -409.257289)
			(xy 82.433604 -409.192441) (xy 82.451028 -409.129361) (xy 82.476769 -409.069195) (xy 82.493104 -409.040838)
			(xy 82.496406 -409.034807) (xy 82.500019 -409.021548) (xy 82.500216 -409.014676) (xy 82.500216 -408.728672)
			(xy 82.500599 -408.718514) (xy 82.508407 -408.699758) (xy 82.522815 -408.685435) (xy 82.541618 -408.677739)
			(xy 82.551778 -408.677364) (xy 83.268058 -408.677364) (xy 83.278185 -408.677862) (xy 83.29691 -408.68558)
			(xy 83.311268 -408.699864) (xy 83.319085 -408.718548) (xy 83.31962 -408.728672) (xy 83.31962 -409.014676)
			(xy 83.319819 -409.021549) (xy 83.323422 -409.034812) (xy 83.326732 -409.040838) (xy 83.34308 -409.069188)
			(xy 83.368825 -409.129356) (xy 83.386251 -409.192437) (xy 83.395044 -409.257288) (xy 83.395042 -409.322732)
			(xy 83.386247 -409.387583) (xy 83.368818 -409.450663) (xy 83.343071 -409.51083) (xy 83.336121 -409.522892)
			(xy 84.624683 -409.522892) (xy 84.624687 -409.457447) (xy 84.633483 -409.392596) (xy 84.650913 -409.329514)
			(xy 84.67666 -409.269347) (xy 84.692998 -409.24099) (xy 84.696362 -409.234975) (xy 84.700098 -409.221715)
			(xy 84.700364 -409.214828) (xy 84.700364 -408.465528) (xy 84.700147 -408.458634) (xy 84.696407 -408.445362)
			(xy 84.692998 -408.439366) (xy 84.676655 -408.411013) (xy 84.650914 -408.350845) (xy 84.63349 -408.287764)
			(xy 84.624699 -408.222915) (xy 84.624699 -408.157472) (xy 84.633493 -408.092622) (xy 84.650919 -408.029542)
			(xy 84.676661 -407.969375) (xy 84.692998 -407.941018) (xy 84.696352 -407.934998) (xy 84.700095 -407.921742)
			(xy 84.700364 -407.914856) (xy 84.700364 -407.628852) (xy 84.700845 -407.618745) (xy 84.708592 -407.600072)
			(xy 84.722889 -407.585781) (xy 84.741564 -407.578041) (xy 84.751672 -407.577544) (xy 85.467952 -407.577544)
			(xy 85.478051 -407.578123) (xy 85.496717 -407.585835) (xy 85.511012 -407.600102) (xy 85.518758 -407.618754)
			(xy 85.51926 -407.628852) (xy 85.51926 -407.914856) (xy 85.51948 -407.92175) (xy 85.523217 -407.935022)
			(xy 85.526626 -407.941018) (xy 85.542958 -407.969378) (xy 85.568704 -408.029543) (xy 85.586133 -408.092622)
			(xy 85.594927 -408.157472) (xy 85.594927 -408.190192) (xy 89.023706 -408.190192) (xy 89.027697 -408.128025)
			(xy 89.039606 -408.066878) (xy 89.059235 -408.007757) (xy 89.086264 -407.951631) (xy 89.120248 -407.899422)
			(xy 89.16063 -407.851987) (xy 89.206746 -407.810106) (xy 89.257838 -407.774466) (xy 89.313069 -407.745652)
			(xy 89.371531 -407.724138) (xy 89.432265 -407.710276) (xy 89.494272 -407.704294) (xy 89.556535 -407.70629)
			(xy 89.618032 -407.716233) (xy 89.677753 -407.733957) (xy 89.734716 -407.759174) (xy 89.787987 -407.791467)
			(xy 89.836692 -407.830307) (xy 89.880029 -407.875057) (xy 89.917289 -407.924981) (xy 89.947858 -407.97926)
			(xy 89.971236 -408.037003) (xy 89.987037 -408.097261) (xy 89.995003 -408.159044) (xy 89.995502 -408.190192)
			(xy 89.995003 -408.22134) (xy 89.987037 -408.283123) (xy 89.971236 -408.343381) (xy 89.947858 -408.401124)
			(xy 89.917289 -408.455403) (xy 89.880029 -408.505327) (xy 89.836692 -408.550077) (xy 89.787987 -408.588917)
			(xy 89.734716 -408.62121) (xy 89.677753 -408.646427) (xy 89.618032 -408.664151) (xy 89.556535 -408.674094)
			(xy 89.494272 -408.67609) (xy 89.432265 -408.670108) (xy 89.371531 -408.656246) (xy 89.313069 -408.634732)
			(xy 89.257838 -408.605918) (xy 89.206746 -408.570278) (xy 89.16063 -408.528397) (xy 89.120248 -408.480962)
			(xy 89.086264 -408.428753) (xy 89.059235 -408.372627) (xy 89.039606 -408.313506) (xy 89.027697 -408.252359)
			(xy 89.023706 -408.190192) (xy 85.594927 -408.190192) (xy 85.594928 -408.222915) (xy 85.586135 -408.287764)
			(xy 85.568709 -408.350844) (xy 85.542964 -408.41101) (xy 85.526626 -408.439366) (xy 85.523272 -408.445386)
			(xy 85.51953 -408.458643) (xy 85.51926 -408.465528) (xy 85.51926 -409.214828) (xy 85.519491 -409.221721)
			(xy 85.523221 -409.234993) (xy 85.526626 -409.24099) (xy 85.542934 -409.269363) (xy 85.568683 -409.329525)
			(xy 85.586114 -409.392602) (xy 85.594911 -409.457449) (xy 85.594915 -409.52289) (xy 85.586126 -409.587738)
			(xy 85.568703 -409.650817) (xy 85.542962 -409.710982) (xy 85.526626 -409.739338) (xy 85.523247 -409.745345)
			(xy 85.519521 -409.758612) (xy 85.51926 -409.7655) (xy 85.51926 -410.051504) (xy 85.518886 -410.061632)
			(xy 85.511129 -410.080343) (xy 85.496799 -410.094659) (xy 85.47808 -410.102396) (xy 85.467952 -410.102812)
			(xy 84.751672 -410.102812) (xy 84.741563 -410.102338) (xy 84.722886 -410.094594) (xy 84.708593 -410.080293)
			(xy 84.700857 -410.061613) (xy 84.700364 -410.051504) (xy 84.700364 -409.7655) (xy 84.700136 -409.758608)
			(xy 84.69639 -409.745342) (xy 84.692998 -409.739338) (xy 84.676631 -409.710998) (xy 84.650893 -409.650827)
			(xy 84.633471 -409.587744) (xy 84.624683 -409.522892) (xy 83.336121 -409.522892) (xy 83.326732 -409.539186)
			(xy 83.323425 -409.545214) (xy 83.319814 -409.558475) (xy 83.31962 -409.565348) (xy 83.31962 -410.314648)
			(xy 83.319829 -410.32152) (xy 83.323426 -410.334783) (xy 83.326732 -410.34081) (xy 83.343057 -410.369173)
			(xy 83.368803 -410.429338) (xy 83.386232 -410.492417) (xy 83.395028 -410.557265) (xy 83.395029 -410.622707)
			(xy 83.395029 -410.622708) (xy 86.824835 -410.622708) (xy 86.824837 -410.557264) (xy 86.833632 -410.492414)
			(xy 86.851061 -410.429333) (xy 86.876807 -410.369166) (xy 86.893146 -410.34081) (xy 86.896506 -410.334793)
			(xy 86.900244 -410.321534) (xy 86.900512 -410.314648) (xy 86.900512 -409.565348) (xy 86.900294 -409.558454)
			(xy 86.896556 -409.545182) (xy 86.893146 -409.539186) (xy 86.876819 -409.510824) (xy 86.851073 -409.450659)
			(xy 86.833646 -409.38758) (xy 86.824851 -409.322731) (xy 86.82485 -409.257289) (xy 86.833641 -409.19244)
			(xy 86.851067 -409.129361) (xy 86.876809 -409.069194) (xy 86.893146 -409.040838) (xy 86.896531 -409.034834)
			(xy 86.900253 -409.021565) (xy 86.900512 -409.014676) (xy 86.900512 -408.728672) (xy 86.900962 -408.71856)
			(xy 86.908711 -408.699879) (xy 86.923019 -408.685585) (xy 86.941708 -408.677853) (xy 86.95182 -408.677364)
			(xy 87.6681 -408.677364) (xy 87.678204 -408.677884) (xy 87.696876 -408.685615) (xy 87.711169 -408.699901)
			(xy 87.71891 -408.718568) (xy 87.719408 -408.728672) (xy 87.719408 -409.014676) (xy 87.719649 -409.021567)
			(xy 87.723386 -409.034833) (xy 87.726774 -409.040838) (xy 87.743121 -409.069189) (xy 87.768863 -409.129357)
			(xy 87.786288 -409.192438) (xy 87.79508 -409.257288) (xy 87.795078 -409.322732) (xy 87.786284 -409.387582)
			(xy 87.768857 -409.450663) (xy 87.751955 -409.490164) (xy 89.023706 -409.490164) (xy 89.027697 -409.427997)
			(xy 89.039606 -409.36685) (xy 89.059235 -409.307729) (xy 89.086264 -409.251603) (xy 89.120248 -409.199394)
			(xy 89.16063 -409.151959) (xy 89.206746 -409.110078) (xy 89.257838 -409.074438) (xy 89.313069 -409.045624)
			(xy 89.371531 -409.02411) (xy 89.432265 -409.010248) (xy 89.494272 -409.004266) (xy 89.556535 -409.006262)
			(xy 89.618032 -409.016205) (xy 89.677753 -409.033929) (xy 89.734716 -409.059146) (xy 89.787987 -409.091439)
			(xy 89.836692 -409.130279) (xy 89.880029 -409.175029) (xy 89.917289 -409.224953) (xy 89.947858 -409.279232)
			(xy 89.971236 -409.336975) (xy 89.987037 -409.397233) (xy 89.995003 -409.459016) (xy 89.995502 -409.490164)
			(xy 89.995003 -409.521312) (xy 89.987037 -409.583095) (xy 89.971236 -409.643353) (xy 89.947858 -409.701096)
			(xy 89.917289 -409.755375) (xy 89.880029 -409.805299) (xy 89.836692 -409.850049) (xy 89.787987 -409.888889)
			(xy 89.734716 -409.921182) (xy 89.677753 -409.946399) (xy 89.618032 -409.964123) (xy 89.556535 -409.974066)
			(xy 89.494272 -409.976062) (xy 89.432265 -409.97008) (xy 89.371531 -409.956218) (xy 89.313069 -409.934704)
			(xy 89.257838 -409.90589) (xy 89.206746 -409.87025) (xy 89.16063 -409.828369) (xy 89.120248 -409.780934)
			(xy 89.086264 -409.728725) (xy 89.059235 -409.672599) (xy 89.039606 -409.613478) (xy 89.027697 -409.552331)
			(xy 89.023706 -409.490164) (xy 87.751955 -409.490164) (xy 87.743112 -409.51083) (xy 87.726774 -409.539186)
			(xy 87.723417 -409.545205) (xy 87.719677 -409.558462) (xy 87.719408 -409.565348) (xy 87.719408 -410.314648)
			(xy 87.71966 -410.321538) (xy 87.723389 -410.334804) (xy 87.726774 -410.34081) (xy 87.743097 -410.369174)
			(xy 87.768842 -410.429339) (xy 87.786269 -410.492417) (xy 87.795064 -410.557265) (xy 87.795066 -410.622707)
			(xy 87.786275 -410.687556) (xy 87.768851 -410.750635) (xy 87.74311 -410.810802) (xy 87.726774 -410.839158)
			(xy 87.723391 -410.845164) (xy 87.719667 -410.858431) (xy 87.719408 -410.86532) (xy 87.719408 -411.151324)
			(xy 87.718935 -411.161433) (xy 87.711191 -411.180111) (xy 87.69689 -411.194404) (xy 87.67821 -411.20214)
			(xy 87.6681 -411.202632) (xy 86.95182 -411.202632) (xy 86.941716 -411.202099) (xy 86.923045 -411.194374)
			(xy 86.90875 -411.180092) (xy 86.901009 -411.161427) (xy 86.900512 -411.151324) (xy 86.900512 -410.86532)
			(xy 86.900305 -410.858425) (xy 86.896559 -410.845153) (xy 86.893146 -410.839158) (xy 86.876795 -410.810809)
			(xy 86.851052 -410.750641) (xy 86.833627 -410.687559) (xy 86.824835 -410.622708) (xy 83.395029 -410.622708)
			(xy 83.386238 -410.687556) (xy 83.368812 -410.750636) (xy 83.343069 -410.810802) (xy 83.326732 -410.839158)
			(xy 83.323435 -410.845191) (xy 83.319818 -410.858448) (xy 83.31962 -410.86532) (xy 83.31962 -411.151324)
			(xy 83.319199 -411.161477) (xy 83.311399 -411.180226) (xy 83.297003 -411.194548) (xy 83.278213 -411.202251)
			(xy 83.268058 -411.202632) (xy 82.551778 -411.202632) (xy 82.541646 -411.202191) (xy 82.522919 -411.194451)
			(xy 82.508563 -411.18015) (xy 82.500749 -411.161454) (xy 82.500216 -411.151324) (xy 82.500216 -410.86532)
			(xy 82.500015 -410.858447) (xy 82.496413 -410.845185) (xy 82.493104 -410.839158) (xy 82.476754 -410.810809)
			(xy 82.451013 -410.75064) (xy 82.43359 -410.687559) (xy 82.424799 -410.622708) (xy 78.994979 -410.622708)
			(xy 78.986189 -410.687555) (xy 78.968766 -410.750635) (xy 78.943025 -410.810802) (xy 78.92669 -410.839158)
			(xy 78.923309 -410.845165) (xy 78.919583 -410.858431) (xy 78.919324 -410.86532) (xy 78.919324 -411.151324)
			(xy 78.918835 -411.161431) (xy 78.911094 -411.180106) (xy 78.896799 -411.194399) (xy 78.878123 -411.202137)
			(xy 78.868016 -411.202632) (xy 78.151736 -411.202632) (xy 78.14162 -411.202155) (xy 78.122923 -411.194425)
			(xy 78.108609 -411.180127) (xy 78.100857 -411.16144) (xy 78.100428 -411.151324) (xy 78.100428 -410.86532)
			(xy 78.100219 -410.858425) (xy 78.096474 -410.845153) (xy 78.093062 -410.839158) (xy 78.07671 -410.81081)
			(xy 78.050967 -410.750641) (xy 78.033541 -410.68756) (xy 78.024749 -410.622708) (xy 74.594943 -410.622708)
			(xy 74.586152 -410.687556) (xy 74.568727 -410.750636) (xy 74.542985 -410.810802) (xy 74.526648 -410.839158)
			(xy 74.523352 -410.845192) (xy 74.519734 -410.858448) (xy 74.519536 -410.86532) (xy 74.519536 -411.151324)
			(xy 74.519099 -411.161475) (xy 74.511302 -411.180221) (xy 74.496911 -411.194542) (xy 74.478127 -411.202248)
			(xy 74.467974 -411.202632) (xy 73.751694 -411.202632) (xy 73.741563 -411.202177) (xy 73.722837 -411.194442)
			(xy 73.70848 -411.180146) (xy 73.700666 -411.161452) (xy 73.700132 -411.151324) (xy 73.700132 -410.86532)
			(xy 73.699928 -410.858448) (xy 73.696328 -410.845185) (xy 73.69302 -410.839158) (xy 73.67667 -410.810809)
			(xy 73.650928 -410.75064) (xy 73.633504 -410.687559) (xy 73.624713 -410.622708) (xy 70.644766 -410.622708)
			(xy 70.644766 -412.090108) (xy 71.423792 -412.090108) (xy 71.427783 -412.027941) (xy 71.439692 -411.966794)
			(xy 71.459321 -411.907673) (xy 71.48635 -411.851547) (xy 71.520334 -411.799338) (xy 71.560716 -411.751903)
			(xy 71.606832 -411.710022) (xy 71.657924 -411.674382) (xy 71.713155 -411.645568) (xy 71.771617 -411.624054)
			(xy 71.832351 -411.610192) (xy 71.894358 -411.60421) (xy 71.956621 -411.606206) (xy 72.018118 -411.616149)
			(xy 72.077839 -411.633873) (xy 72.134802 -411.65909) (xy 72.188073 -411.691383) (xy 72.236778 -411.730223)
			(xy 72.280115 -411.774973) (xy 72.317375 -411.824897) (xy 72.347944 -411.879176) (xy 72.371322 -411.936919)
			(xy 72.387123 -411.997177) (xy 72.395089 -412.05896) (xy 72.395588 -412.090108) (xy 75.823834 -412.090108)
			(xy 75.827825 -412.027941) (xy 75.839734 -411.966794) (xy 75.859363 -411.907673) (xy 75.886392 -411.851547)
			(xy 75.920376 -411.799338) (xy 75.960758 -411.751903) (xy 76.006874 -411.710022) (xy 76.057966 -411.674382)
			(xy 76.113197 -411.645568) (xy 76.171659 -411.624054) (xy 76.232393 -411.610192) (xy 76.2944 -411.60421)
			(xy 76.356663 -411.606206) (xy 76.41816 -411.616149) (xy 76.477881 -411.633873) (xy 76.534844 -411.65909)
			(xy 76.588115 -411.691383) (xy 76.63682 -411.730223) (xy 76.680157 -411.774973) (xy 76.717417 -411.824897)
			(xy 76.747986 -411.879176) (xy 76.771364 -411.936919) (xy 76.787165 -411.997177) (xy 76.795131 -412.05896)
			(xy 76.79563 -412.090108) (xy 80.223876 -412.090108) (xy 80.227867 -412.027941) (xy 80.239776 -411.966794)
			(xy 80.259405 -411.907673) (xy 80.286434 -411.851547) (xy 80.320418 -411.799338) (xy 80.3608 -411.751903)
			(xy 80.406916 -411.710022) (xy 80.458008 -411.674382) (xy 80.513239 -411.645568) (xy 80.571701 -411.624054)
			(xy 80.632435 -411.610192) (xy 80.694442 -411.60421) (xy 80.756705 -411.606206) (xy 80.818202 -411.616149)
			(xy 80.877923 -411.633873) (xy 80.934886 -411.65909) (xy 80.988157 -411.691383) (xy 81.036862 -411.730223)
			(xy 81.080199 -411.774973) (xy 81.117459 -411.824897) (xy 81.148028 -411.879176) (xy 81.171406 -411.936919)
			(xy 81.187207 -411.997177) (xy 81.195173 -412.05896) (xy 81.195672 -412.090108) (xy 84.623664 -412.090108)
			(xy 84.627655 -412.027941) (xy 84.639564 -411.966794) (xy 84.659193 -411.907673) (xy 84.686222 -411.851547)
			(xy 84.720206 -411.799338) (xy 84.760588 -411.751903) (xy 84.806704 -411.710022) (xy 84.857796 -411.674382)
			(xy 84.913027 -411.645568) (xy 84.971489 -411.624054) (xy 85.032223 -411.610192) (xy 85.09423 -411.60421)
			(xy 85.156493 -411.606206) (xy 85.21799 -411.616149) (xy 85.277711 -411.633873) (xy 85.334674 -411.65909)
			(xy 85.387945 -411.691383) (xy 85.43665 -411.730223) (xy 85.479987 -411.774973) (xy 85.517247 -411.824897)
			(xy 85.547816 -411.879176) (xy 85.571194 -411.936919) (xy 85.586995 -411.997177) (xy 85.594961 -412.05896)
			(xy 85.59546 -412.090108) (xy 89.023706 -412.090108) (xy 89.027697 -412.027941) (xy 89.039606 -411.966794)
			(xy 89.059235 -411.907673) (xy 89.086264 -411.851547) (xy 89.120248 -411.799338) (xy 89.16063 -411.751903)
			(xy 89.206746 -411.710022) (xy 89.257838 -411.674382) (xy 89.313069 -411.645568) (xy 89.371531 -411.624054)
			(xy 89.432265 -411.610192) (xy 89.494272 -411.60421) (xy 89.556535 -411.606206) (xy 89.618032 -411.616149)
			(xy 89.677753 -411.633873) (xy 89.734716 -411.65909) (xy 89.787987 -411.691383) (xy 89.836692 -411.730223)
			(xy 89.880029 -411.774973) (xy 89.917289 -411.824897) (xy 89.947858 -411.879176) (xy 89.971236 -411.936919)
			(xy 89.987037 -411.997177) (xy 89.995003 -412.05896) (xy 89.995502 -412.090108) (xy 115.423958 -412.090108)
			(xy 115.427949 -412.027941) (xy 115.439858 -411.966794) (xy 115.459487 -411.907673) (xy 115.486516 -411.851547)
			(xy 115.5205 -411.799338) (xy 115.560882 -411.751903) (xy 115.606998 -411.710022) (xy 115.65809 -411.674382)
			(xy 115.713321 -411.645568) (xy 115.771783 -411.624054) (xy 115.832517 -411.610192) (xy 115.894524 -411.60421)
			(xy 115.956787 -411.606206) (xy 116.018284 -411.616149) (xy 116.078005 -411.633873) (xy 116.134968 -411.65909)
			(xy 116.188239 -411.691383) (xy 116.236944 -411.730223) (xy 116.280281 -411.774973) (xy 116.317541 -411.824897)
			(xy 116.34811 -411.879176) (xy 116.371488 -411.936919) (xy 116.387289 -411.997177) (xy 116.395255 -412.05896)
			(xy 116.395754 -412.090108) (xy 119.824 -412.090108) (xy 119.827991 -412.027941) (xy 119.8399 -411.966794)
			(xy 119.859529 -411.907673) (xy 119.886558 -411.851547) (xy 119.920542 -411.799338) (xy 119.960924 -411.751903)
			(xy 120.00704 -411.710022) (xy 120.058132 -411.674382) (xy 120.113363 -411.645568) (xy 120.171825 -411.624054)
			(xy 120.232559 -411.610192) (xy 120.294566 -411.60421) (xy 120.356829 -411.606206) (xy 120.418326 -411.616149)
			(xy 120.478047 -411.633873) (xy 120.53501 -411.65909) (xy 120.588281 -411.691383) (xy 120.636986 -411.730223)
			(xy 120.680323 -411.774973) (xy 120.717583 -411.824897) (xy 120.748152 -411.879176) (xy 120.77153 -411.936919)
			(xy 120.787331 -411.997177) (xy 120.795297 -412.05896) (xy 120.795796 -412.090108) (xy 124.224042 -412.090108)
			(xy 124.228033 -412.027941) (xy 124.239942 -411.966794) (xy 124.259571 -411.907673) (xy 124.2866 -411.851547)
			(xy 124.320584 -411.799338) (xy 124.360966 -411.751903) (xy 124.407082 -411.710022) (xy 124.458174 -411.674382)
			(xy 124.513405 -411.645568) (xy 124.571867 -411.624054) (xy 124.632601 -411.610192) (xy 124.694608 -411.60421)
			(xy 124.756871 -411.606206) (xy 124.818368 -411.616149) (xy 124.878089 -411.633873) (xy 124.935052 -411.65909)
			(xy 124.988323 -411.691383) (xy 125.037028 -411.730223) (xy 125.080365 -411.774973) (xy 125.117625 -411.824897)
			(xy 125.148194 -411.879176) (xy 125.171572 -411.936919) (xy 125.187373 -411.997177) (xy 125.195339 -412.05896)
			(xy 125.195838 -412.090108) (xy 128.62383 -412.090108) (xy 128.627821 -412.027941) (xy 128.63973 -411.966794)
			(xy 128.659359 -411.907673) (xy 128.686388 -411.851547) (xy 128.720372 -411.799338) (xy 128.760754 -411.751903)
			(xy 128.80687 -411.710022) (xy 128.857962 -411.674382) (xy 128.913193 -411.645568) (xy 128.971655 -411.624054)
			(xy 129.032389 -411.610192) (xy 129.094396 -411.60421) (xy 129.156659 -411.606206) (xy 129.218156 -411.616149)
			(xy 129.277877 -411.633873) (xy 129.33484 -411.65909) (xy 129.388111 -411.691383) (xy 129.436816 -411.730223)
			(xy 129.480153 -411.774973) (xy 129.517413 -411.824897) (xy 129.547982 -411.879176) (xy 129.57136 -411.936919)
			(xy 129.587161 -411.997177) (xy 129.595127 -412.05896) (xy 129.595626 -412.090108) (xy 133.023872 -412.090108)
			(xy 133.027863 -412.027941) (xy 133.039772 -411.966794) (xy 133.059401 -411.907673) (xy 133.08643 -411.851547)
			(xy 133.120414 -411.799338) (xy 133.160796 -411.751903) (xy 133.206912 -411.710022) (xy 133.258004 -411.674382)
			(xy 133.313235 -411.645568) (xy 133.371697 -411.624054) (xy 133.432431 -411.610192) (xy 133.494438 -411.60421)
			(xy 133.556701 -411.606206) (xy 133.618198 -411.616149) (xy 133.677919 -411.633873) (xy 133.734882 -411.65909)
			(xy 133.788153 -411.691383) (xy 133.836858 -411.730223) (xy 133.880195 -411.774973) (xy 133.917455 -411.824897)
			(xy 133.948024 -411.879176) (xy 133.971402 -411.936919) (xy 133.987203 -411.997177) (xy 133.995169 -412.05896)
			(xy 133.995668 -412.090108) (xy 133.995169 -412.121256) (xy 133.987203 -412.183039) (xy 133.971402 -412.243297)
			(xy 133.948024 -412.30104) (xy 133.917455 -412.355319) (xy 133.880195 -412.405243) (xy 133.836858 -412.449993)
			(xy 133.788153 -412.488833) (xy 133.734882 -412.521126) (xy 133.677919 -412.546343) (xy 133.618198 -412.564067)
			(xy 133.556701 -412.57401) (xy 133.494438 -412.576006) (xy 133.432431 -412.570024) (xy 133.371697 -412.556162)
			(xy 133.313235 -412.534648) (xy 133.258004 -412.505834) (xy 133.206912 -412.470194) (xy 133.160796 -412.428313)
			(xy 133.120414 -412.380878) (xy 133.08643 -412.328669) (xy 133.059401 -412.272543) (xy 133.039772 -412.213422)
			(xy 133.027863 -412.152275) (xy 133.023872 -412.090108) (xy 129.595626 -412.090108) (xy 129.595127 -412.121256)
			(xy 129.587161 -412.183039) (xy 129.57136 -412.243297) (xy 129.547982 -412.30104) (xy 129.517413 -412.355319)
			(xy 129.480153 -412.405243) (xy 129.436816 -412.449993) (xy 129.388111 -412.488833) (xy 129.33484 -412.521126)
			(xy 129.277877 -412.546343) (xy 129.218156 -412.564067) (xy 129.156659 -412.57401) (xy 129.094396 -412.576006)
			(xy 129.032389 -412.570024) (xy 128.971655 -412.556162) (xy 128.913193 -412.534648) (xy 128.857962 -412.505834)
			(xy 128.80687 -412.470194) (xy 128.760754 -412.428313) (xy 128.720372 -412.380878) (xy 128.686388 -412.328669)
			(xy 128.659359 -412.272543) (xy 128.63973 -412.213422) (xy 128.627821 -412.152275) (xy 128.62383 -412.090108)
			(xy 125.195838 -412.090108) (xy 125.195339 -412.121256) (xy 125.187373 -412.183039) (xy 125.171572 -412.243297)
			(xy 125.148194 -412.30104) (xy 125.117625 -412.355319) (xy 125.080365 -412.405243) (xy 125.037028 -412.449993)
			(xy 124.988323 -412.488833) (xy 124.935052 -412.521126) (xy 124.878089 -412.546343) (xy 124.818368 -412.564067)
			(xy 124.756871 -412.57401) (xy 124.694608 -412.576006) (xy 124.632601 -412.570024) (xy 124.571867 -412.556162)
			(xy 124.513405 -412.534648) (xy 124.458174 -412.505834) (xy 124.407082 -412.470194) (xy 124.360966 -412.428313)
			(xy 124.320584 -412.380878) (xy 124.2866 -412.328669) (xy 124.259571 -412.272543) (xy 124.239942 -412.213422)
			(xy 124.228033 -412.152275) (xy 124.224042 -412.090108) (xy 120.795796 -412.090108) (xy 120.795297 -412.121256)
			(xy 120.787331 -412.183039) (xy 120.77153 -412.243297) (xy 120.748152 -412.30104) (xy 120.717583 -412.355319)
			(xy 120.680323 -412.405243) (xy 120.636986 -412.449993) (xy 120.588281 -412.488833) (xy 120.53501 -412.521126)
			(xy 120.478047 -412.546343) (xy 120.418326 -412.564067) (xy 120.356829 -412.57401) (xy 120.294566 -412.576006)
			(xy 120.232559 -412.570024) (xy 120.171825 -412.556162) (xy 120.113363 -412.534648) (xy 120.058132 -412.505834)
			(xy 120.00704 -412.470194) (xy 119.960924 -412.428313) (xy 119.920542 -412.380878) (xy 119.886558 -412.328669)
			(xy 119.859529 -412.272543) (xy 119.8399 -412.213422) (xy 119.827991 -412.152275) (xy 119.824 -412.090108)
			(xy 116.395754 -412.090108) (xy 116.395255 -412.121256) (xy 116.387289 -412.183039) (xy 116.371488 -412.243297)
			(xy 116.34811 -412.30104) (xy 116.317541 -412.355319) (xy 116.280281 -412.405243) (xy 116.236944 -412.449993)
			(xy 116.188239 -412.488833) (xy 116.134968 -412.521126) (xy 116.078005 -412.546343) (xy 116.018284 -412.564067)
			(xy 115.956787 -412.57401) (xy 115.894524 -412.576006) (xy 115.832517 -412.570024) (xy 115.771783 -412.556162)
			(xy 115.713321 -412.534648) (xy 115.65809 -412.505834) (xy 115.606998 -412.470194) (xy 115.560882 -412.428313)
			(xy 115.5205 -412.380878) (xy 115.486516 -412.328669) (xy 115.459487 -412.272543) (xy 115.439858 -412.213422)
			(xy 115.427949 -412.152275) (xy 115.423958 -412.090108) (xy 89.995502 -412.090108) (xy 89.995003 -412.121256)
			(xy 89.987037 -412.183039) (xy 89.971236 -412.243297) (xy 89.947858 -412.30104) (xy 89.917289 -412.355319)
			(xy 89.880029 -412.405243) (xy 89.836692 -412.449993) (xy 89.787987 -412.488833) (xy 89.734716 -412.521126)
			(xy 89.677753 -412.546343) (xy 89.618032 -412.564067) (xy 89.556535 -412.57401) (xy 89.494272 -412.576006)
			(xy 89.432265 -412.570024) (xy 89.371531 -412.556162) (xy 89.313069 -412.534648) (xy 89.257838 -412.505834)
			(xy 89.206746 -412.470194) (xy 89.16063 -412.428313) (xy 89.120248 -412.380878) (xy 89.086264 -412.328669)
			(xy 89.059235 -412.272543) (xy 89.039606 -412.213422) (xy 89.027697 -412.152275) (xy 89.023706 -412.090108)
			(xy 85.59546 -412.090108) (xy 85.594961 -412.121256) (xy 85.586995 -412.183039) (xy 85.571194 -412.243297)
			(xy 85.547816 -412.30104) (xy 85.517247 -412.355319) (xy 85.479987 -412.405243) (xy 85.43665 -412.449993)
			(xy 85.387945 -412.488833) (xy 85.334674 -412.521126) (xy 85.277711 -412.546343) (xy 85.21799 -412.564067)
			(xy 85.156493 -412.57401) (xy 85.09423 -412.576006) (xy 85.032223 -412.570024) (xy 84.971489 -412.556162)
			(xy 84.913027 -412.534648) (xy 84.857796 -412.505834) (xy 84.806704 -412.470194) (xy 84.760588 -412.428313)
			(xy 84.720206 -412.380878) (xy 84.686222 -412.328669) (xy 84.659193 -412.272543) (xy 84.639564 -412.213422)
			(xy 84.627655 -412.152275) (xy 84.623664 -412.090108) (xy 81.195672 -412.090108) (xy 81.195173 -412.121256)
			(xy 81.187207 -412.183039) (xy 81.171406 -412.243297) (xy 81.148028 -412.30104) (xy 81.117459 -412.355319)
			(xy 81.080199 -412.405243) (xy 81.036862 -412.449993) (xy 80.988157 -412.488833) (xy 80.934886 -412.521126)
			(xy 80.877923 -412.546343) (xy 80.818202 -412.564067) (xy 80.756705 -412.57401) (xy 80.694442 -412.576006)
			(xy 80.632435 -412.570024) (xy 80.571701 -412.556162) (xy 80.513239 -412.534648) (xy 80.458008 -412.505834)
			(xy 80.406916 -412.470194) (xy 80.3608 -412.428313) (xy 80.320418 -412.380878) (xy 80.286434 -412.328669)
			(xy 80.259405 -412.272543) (xy 80.239776 -412.213422) (xy 80.227867 -412.152275) (xy 80.223876 -412.090108)
			(xy 76.79563 -412.090108) (xy 76.795131 -412.121256) (xy 76.787165 -412.183039) (xy 76.771364 -412.243297)
			(xy 76.747986 -412.30104) (xy 76.717417 -412.355319) (xy 76.680157 -412.405243) (xy 76.63682 -412.449993)
			(xy 76.588115 -412.488833) (xy 76.534844 -412.521126) (xy 76.477881 -412.546343) (xy 76.41816 -412.564067)
			(xy 76.356663 -412.57401) (xy 76.2944 -412.576006) (xy 76.232393 -412.570024) (xy 76.171659 -412.556162)
			(xy 76.113197 -412.534648) (xy 76.057966 -412.505834) (xy 76.006874 -412.470194) (xy 75.960758 -412.428313)
			(xy 75.920376 -412.380878) (xy 75.886392 -412.328669) (xy 75.859363 -412.272543) (xy 75.839734 -412.213422)
			(xy 75.827825 -412.152275) (xy 75.823834 -412.090108) (xy 72.395588 -412.090108) (xy 72.395089 -412.121256)
			(xy 72.387123 -412.183039) (xy 72.371322 -412.243297) (xy 72.347944 -412.30104) (xy 72.317375 -412.355319)
			(xy 72.280115 -412.405243) (xy 72.236778 -412.449993) (xy 72.188073 -412.488833) (xy 72.134802 -412.521126)
			(xy 72.077839 -412.546343) (xy 72.018118 -412.564067) (xy 71.956621 -412.57401) (xy 71.894358 -412.576006)
			(xy 71.832351 -412.570024) (xy 71.771617 -412.556162) (xy 71.713155 -412.534648) (xy 71.657924 -412.505834)
			(xy 71.606832 -412.470194) (xy 71.560716 -412.428313) (xy 71.520334 -412.380878) (xy 71.48635 -412.328669)
			(xy 71.459321 -412.272543) (xy 71.439692 -412.213422) (xy 71.427783 -412.152275) (xy 71.423792 -412.090108)
			(xy 70.644766 -412.090108) (xy 70.644766 -413.91078) (xy 70.644328 -413.920843) (xy 70.636589 -413.939423)
			(xy 70.62978 -413.946848) (xy 70.16496 -414.411668) (xy 70.158269 -414.419078) (xy 70.150661 -414.437515)
			(xy 70.150656 -414.45746) (xy 70.158255 -414.4759) (xy 70.16496 -414.483296) (xy 71.662036 -415.980372)
			(xy 71.662544 -415.98088) (xy 71.669926 -415.987461) (xy 71.688225 -415.99491) (xy 71.698104 -415.995358)
		)
		(stroke
			(width 0)
			(type solid)
		)
		(fill yes)
		(layer "In11.Cu")
		(net "GND")
	)
	(gr_poly
		(pts
			(xy 400.378422 -416.614356) (xy 400.388437 -416.613932) (xy 400.406939 -416.606257) (xy 400.421094 -416.592083)
			(xy 400.428745 -416.573572) (xy 400.429222 -416.563556) (xy 400.429222 -416.395916) (xy 400.429661 -416.385853)
			(xy 400.437399 -416.367273) (xy 400.444208 -416.359848) (xy 400.73707 -416.066986) (xy 400.742053 -416.061485)
			(xy 400.748891 -416.048317) (xy 400.750532 -416.041078) (xy 400.751548 -416.031426) (xy 400.751548 -394.116052)
			(xy 400.751981 -394.105987) (xy 400.759713 -394.0874) (xy 400.766534 -394.079984) (xy 401.065238 -393.78128)
			(xy 401.072635 -393.774431) (xy 401.091234 -393.766698) (xy 401.101306 -393.766294) (xy 413.940752 -393.766294)
			(xy 413.950818 -393.766726) (xy 413.96941 -393.774453) (xy 413.97682 -393.78128) (xy 414.462722 -394.267182)
			(xy 414.465299 -394.26969) (xy 414.471036 -394.274023) (xy 414.474152 -394.275818) (xy 414.47974 -394.278866)
			(xy 414.486598 -394.280644) (xy 414.486852 -394.280644) (xy 414.497665 -394.283945) (xy 414.515148 -394.298236)
			(xy 414.524838 -394.318631) (xy 414.52546 -394.32992) (xy 414.52546 -394.353034) (xy 414.525968 -394.353542)
			(xy 414.525968 -405.622714) (xy 419.004836 -405.622714) (xy 419.004837 -405.557276) (xy 419.013622 -405.492431)
			(xy 419.031032 -405.429352) (xy 419.056752 -405.369181) (xy 419.073076 -405.34082) (xy 419.076382 -405.334791)
			(xy 419.079994 -405.321531) (xy 419.080188 -405.314658) (xy 419.080188 -404.565358) (xy 419.079975 -404.558486)
			(xy 419.076381 -404.545223) (xy 419.073076 -404.539196) (xy 419.056771 -404.510825) (xy 419.03105 -404.450656)
			(xy 419.013638 -404.38758) (xy 419.004852 -404.322737) (xy 419.004849 -404.257301) (xy 419.013631 -404.192457)
			(xy 419.031037 -404.129379) (xy 419.056754 -404.069209) (xy 419.073076 -404.040848) (xy 419.076408 -404.034832)
			(xy 419.080003 -404.021562) (xy 419.080188 -404.014686) (xy 419.080188 -403.728682) (xy 419.08055 -403.718503)
			(xy 419.088351 -403.699698) (xy 419.102756 -403.685313) (xy 419.12157 -403.677537) (xy 419.13175 -403.67712)
			(xy 419.84803 -403.67712) (xy 419.858187 -403.677608) (xy 419.876954 -403.685389) (xy 419.891317 -403.699756)
			(xy 419.899094 -403.718524) (xy 419.899592 -403.728682) (xy 419.899592 -404.014686) (xy 419.89979 -404.021559)
			(xy 419.903394 -404.034822) (xy 419.906704 -404.040848) (xy 419.923044 -404.069199) (xy 419.948757 -404.129373)
			(xy 419.966162 -404.192454) (xy 419.974942 -404.2573) (xy 419.974939 -404.322738) (xy 419.966154 -404.387583)
			(xy 419.948745 -404.450662) (xy 419.923026 -404.510834) (xy 419.906704 -404.539196) (xy 419.903391 -404.545221)
			(xy 419.899784 -404.558485) (xy 419.899592 -404.565358) (xy 419.899592 -405.314658) (xy 419.899801 -405.32153)
			(xy 419.903398 -405.334793) (xy 419.906704 -405.34082) (xy 419.92302 -405.369185) (xy 419.948736 -405.429355)
			(xy 419.966143 -405.492433) (xy 419.974926 -405.557277) (xy 419.974927 -405.622713) (xy 419.966145 -405.687557)
			(xy 419.948739 -405.750635) (xy 419.923024 -405.810806) (xy 419.906704 -405.839168) (xy 419.903401 -405.845198)
			(xy 419.899788 -405.858458) (xy 419.899592 -405.86533) (xy 419.899592 -406.151334) (xy 419.899095 -406.16149)
			(xy 419.891315 -406.180254) (xy 419.876951 -406.194617) (xy 419.858186 -406.202396) (xy 419.84803 -406.202896)
			(xy 419.13175 -406.202896) (xy 419.121586 -406.202396) (xy 419.102799 -406.194634) (xy 419.088413 -406.180272)
			(xy 419.08062 -406.161497) (xy 419.080188 -406.151334) (xy 419.080188 -405.86533) (xy 419.079986 -405.858458)
			(xy 419.076385 -405.845195) (xy 419.073076 -405.839168) (xy 419.056748 -405.81081) (xy 419.031028 -405.750638)
			(xy 419.01362 -405.687559) (xy 419.004836 -405.622714) (xy 414.525968 -405.622714) (xy 414.525968 -406.690068)
			(xy 421.204136 -406.690068) (xy 421.204718 -406.657339) (xy 421.213571 -406.592482) (xy 421.231056 -406.529402)
			(xy 421.256858 -406.469243) (xy 421.273224 -406.440894) (xy 421.276543 -406.434871) (xy 421.280145 -406.421606)
			(xy 421.280336 -406.414732) (xy 421.280336 -405.665432) (xy 421.280127 -405.65856) (xy 421.27653 -405.645297)
			(xy 421.273224 -405.63927) (xy 421.256849 -405.610926) (xy 421.231049 -405.550765) (xy 421.213562 -405.487684)
			(xy 421.204705 -405.422825) (xy 421.204136 -405.390096) (xy 421.204686 -405.357366) (xy 421.213548 -405.292507)
			(xy 421.231043 -405.229428) (xy 421.256854 -405.16927) (xy 421.273224 -405.140922) (xy 421.276533 -405.134894)
			(xy 421.280142 -405.121633) (xy 421.280336 -405.11476) (xy 421.280336 -404.828756) (xy 421.28075 -404.81864)
			(xy 421.288509 -404.799954) (xy 421.302828 -404.785659) (xy 421.321527 -404.777933) (xy 421.331644 -404.777448)
			(xy 422.047924 -404.777448) (xy 422.058028 -404.777964) (xy 422.076697 -404.7857) (xy 422.090989 -404.799986)
			(xy 422.098732 -404.818652) (xy 422.099232 -404.828756) (xy 422.099232 -405.11476) (xy 422.099435 -405.121632)
			(xy 422.103035 -405.134895) (xy 422.106344 -405.140922) (xy 422.122713 -405.169269) (xy 422.148515 -405.229429)
			(xy 422.166004 -405.292509) (xy 422.174863 -405.357367) (xy 422.175432 -405.390096) (xy 422.174883 -405.422826)
			(xy 422.166021 -405.487685) (xy 422.148526 -405.550765) (xy 422.131694 -405.589994) (xy 423.404284 -405.589994)
			(xy 423.404872 -405.557265) (xy 423.413721 -405.492408) (xy 423.431205 -405.429328) (xy 423.457007 -405.369169)
			(xy 423.473372 -405.34082) (xy 423.476678 -405.334791) (xy 423.48029 -405.321531) (xy 423.480484 -405.314658)
			(xy 423.480484 -404.565358) (xy 423.480272 -404.558486) (xy 423.476678 -404.545223) (xy 423.473372 -404.539196)
			(xy 423.457002 -404.510849) (xy 423.431202 -404.450689) (xy 423.413714 -404.387608) (xy 423.404854 -404.322751)
			(xy 423.404284 -404.290022) (xy 423.404839 -404.257292) (xy 423.413698 -404.192434) (xy 423.431192 -404.129353)
			(xy 423.457002 -404.069196) (xy 423.473372 -404.040848) (xy 423.476703 -404.034831) (xy 423.480299 -404.021561)
			(xy 423.480484 -404.014686) (xy 423.480484 -403.728682) (xy 423.480913 -403.718549) (xy 423.488655 -403.699819)
			(xy 423.502959 -403.685461) (xy 423.521661 -403.677651) (xy 423.531792 -403.67712) (xy 424.248072 -403.67712)
			(xy 424.258227 -403.677545) (xy 424.276983 -403.685335) (xy 424.291308 -403.699731) (xy 424.299005 -403.718525)
			(xy 424.29938 -403.728682) (xy 424.29938 -404.014686) (xy 424.29958 -404.021559) (xy 424.303183 -404.034821)
			(xy 424.306492 -404.040848) (xy 424.322876 -404.069187) (xy 424.348674 -404.12935) (xy 424.366158 -404.192433)
			(xy 424.375013 -404.257292) (xy 424.37558 -404.290022) (xy 424.375004 -404.322751) (xy 424.366152 -404.387609)
			(xy 424.348665 -404.450689) (xy 424.322859 -404.510848) (xy 424.306492 -404.539196) (xy 424.303178 -404.545221)
			(xy 424.299572 -404.558484) (xy 424.29938 -404.565358) (xy 424.29938 -405.314658) (xy 424.29959 -405.32153)
			(xy 424.303186 -405.334793) (xy 424.306492 -405.34082) (xy 424.322865 -405.369165) (xy 424.348665 -405.429326)
			(xy 424.366153 -405.492407) (xy 424.375011 -405.557265) (xy 424.37558 -405.589994) (xy 424.375037 -405.622724)
			(xy 424.366174 -405.687583) (xy 424.348678 -405.750664) (xy 424.322864 -405.810821) (xy 424.306492 -405.839168)
			(xy 424.303188 -405.845198) (xy 424.299576 -405.858458) (xy 424.29938 -405.86533) (xy 424.29938 -406.151334)
			(xy 424.298902 -406.16146) (xy 424.291167 -406.180179) (xy 424.276878 -406.194533) (xy 424.258196 -406.202355)
			(xy 424.248072 -406.202896) (xy 423.531792 -406.202896) (xy 423.521637 -406.202485) (xy 423.502884 -406.194686)
			(xy 423.48856 -406.180286) (xy 423.480862 -406.161491) (xy 423.480484 -406.151334) (xy 423.480484 -405.86533)
			(xy 423.480282 -405.858457) (xy 423.476681 -405.845195) (xy 423.473372 -405.839168) (xy 423.456991 -405.810827)
			(xy 423.431194 -405.750664) (xy 423.413708 -405.687582) (xy 423.404852 -405.622724) (xy 423.404284 -405.589994)
			(xy 422.131694 -405.589994) (xy 422.122715 -405.610922) (xy 422.106344 -405.63927) (xy 422.103043 -405.645302)
			(xy 422.099428 -405.65856) (xy 422.099232 -405.665432) (xy 422.099232 -406.414732) (xy 422.099408 -406.421606)
			(xy 422.103027 -406.434869) (xy 422.106344 -406.440894) (xy 422.122702 -406.469248) (xy 422.148507 -406.529405)
			(xy 422.165999 -406.592483) (xy 422.174861 -406.657339) (xy 422.175432 -406.690068) (xy 422.17487 -406.722792)
			(xy 425.604766 -406.722792) (xy 425.60477 -406.657353) (xy 425.613557 -406.592507) (xy 425.630968 -406.529428)
			(xy 425.656688 -406.469256) (xy 425.673012 -406.440894) (xy 425.67633 -406.434871) (xy 425.679933 -406.421606)
			(xy 425.680124 -406.414732) (xy 425.680124 -405.665432) (xy 425.679917 -405.65856) (xy 425.676319 -405.645297)
			(xy 425.673012 -405.63927) (xy 425.656687 -405.61091) (xy 425.630971 -405.550738) (xy 425.613565 -405.487659)
			(xy 425.604782 -405.422815) (xy 425.604782 -405.357378) (xy 425.613566 -405.292534) (xy 425.630974 -405.229455)
			(xy 425.65669 -405.169284) (xy 425.673012 -405.140922) (xy 425.67632 -405.134894) (xy 425.67993 -405.121633)
			(xy 425.680124 -405.11476) (xy 425.680124 -404.828756) (xy 425.680486 -404.818596) (xy 425.688301 -404.799838)
			(xy 425.702716 -404.785515) (xy 425.721523 -404.777822) (xy 425.731686 -404.777448) (xy 426.447966 -404.777448)
			(xy 426.458091 -404.777955) (xy 426.476813 -404.785673) (xy 426.491171 -404.799953) (xy 426.49899 -404.818633)
			(xy 426.499528 -404.828756) (xy 426.499528 -405.11476) (xy 426.499732 -405.121632) (xy 426.503332 -405.134895)
			(xy 426.50664 -405.140922) (xy 426.522959 -405.169285) (xy 426.548679 -405.229455) (xy 426.566088 -405.292534)
			(xy 426.574872 -405.357378) (xy 426.574873 -405.422815) (xy 426.566089 -405.487659) (xy 426.548681 -405.550738)
			(xy 426.522963 -405.610909) (xy 426.516169 -405.622714) (xy 427.804922 -405.622714) (xy 427.804923 -405.557276)
			(xy 427.813708 -405.492431) (xy 427.831117 -405.429352) (xy 427.856837 -405.369181) (xy 427.87316 -405.34082)
			(xy 427.876464 -405.33479) (xy 427.880077 -405.321531) (xy 427.880272 -405.314658) (xy 427.880272 -404.565358)
			(xy 427.880061 -404.558486) (xy 427.876466 -404.545223) (xy 427.87316 -404.539196) (xy 427.856856 -404.510825)
			(xy 427.831135 -404.450656) (xy 427.813724 -404.387579) (xy 427.804938 -404.322737) (xy 427.804936 -404.257301)
			(xy 427.813717 -404.192458) (xy 427.831123 -404.12938) (xy 427.856839 -404.069209) (xy 427.87316 -404.040848)
			(xy 427.87649 -404.034831) (xy 427.880086 -404.021561) (xy 427.880272 -404.014686) (xy 427.880272 -403.728682)
			(xy 427.88065 -403.718505) (xy 427.888447 -403.699703) (xy 427.902847 -403.685318) (xy 427.921657 -403.67754)
			(xy 427.931834 -403.67712) (xy 428.648114 -403.67712) (xy 428.65827 -403.677622) (xy 428.677036 -403.685397)
			(xy 428.6914 -403.69976) (xy 428.699178 -403.718526) (xy 428.699676 -403.728682) (xy 428.699676 -404.014686)
			(xy 428.699876 -404.021559) (xy 428.703479 -404.034821) (xy 428.706788 -404.040848) (xy 428.723128 -404.069199)
			(xy 428.748842 -404.129373) (xy 428.766248 -404.192454) (xy 428.775028 -404.2573) (xy 428.775026 -404.322738)
			(xy 428.76624 -404.387583) (xy 428.74883 -404.450663) (xy 428.723111 -404.510834) (xy 428.706788 -404.539196)
			(xy 428.703474 -404.545221) (xy 428.699868 -404.558484) (xy 428.699676 -404.565358) (xy 428.699676 -405.314658)
			(xy 428.699887 -405.32153) (xy 428.703482 -405.334793) (xy 428.706788 -405.34082) (xy 428.723104 -405.369184)
			(xy 428.748821 -405.429355) (xy 428.766229 -405.492433) (xy 428.775012 -405.557277) (xy 428.775013 -405.622713)
			(xy 428.766231 -405.687557) (xy 428.748824 -405.750635) (xy 428.723109 -405.810806) (xy 428.706788 -405.839168)
			(xy 428.703484 -405.845198) (xy 428.699872 -405.858458) (xy 428.699676 -405.86533) (xy 428.699676 -406.151334)
			(xy 428.699195 -406.161492) (xy 428.691412 -406.180259) (xy 428.677043 -406.194623) (xy 428.658272 -406.202399)
			(xy 428.648114 -406.202896) (xy 427.931834 -406.202896) (xy 427.921683 -406.202339) (xy 427.902921 -406.194583)
			(xy 427.888556 -406.180236) (xy 427.880774 -406.161485) (xy 427.880272 -406.151334) (xy 427.880272 -405.86533)
			(xy 427.880072 -405.858457) (xy 427.87647 -405.845194) (xy 427.87316 -405.839168) (xy 427.856832 -405.81081)
			(xy 427.831114 -405.750638) (xy 427.813705 -405.687559) (xy 427.804922 -405.622714) (xy 426.516169 -405.622714)
			(xy 426.50664 -405.63927) (xy 426.503339 -405.645302) (xy 426.499724 -405.65856) (xy 426.499528 -405.665432)
			(xy 426.499528 -406.414732) (xy 426.499704 -406.421606) (xy 426.503323 -406.434869) (xy 426.50664 -406.440894)
			(xy 426.522936 -406.46927) (xy 426.548657 -406.529437) (xy 426.566069 -406.592513) (xy 426.574856 -406.657355)
			(xy 426.574858 -406.690068) (xy 430.00422 -406.690068) (xy 430.004791 -406.657339) (xy 430.013645 -406.59248)
			(xy 430.031134 -406.5294) (xy 430.05694 -406.469242) (xy 430.073308 -406.440894) (xy 430.076625 -406.434871)
			(xy 430.080229 -406.421606) (xy 430.08042 -406.414732) (xy 430.08042 -405.665432) (xy 430.080213 -405.65856)
			(xy 430.076615 -405.645297) (xy 430.073308 -405.63927) (xy 430.056931 -405.610927) (xy 430.031132 -405.550765)
			(xy 430.013645 -405.487684) (xy 430.004788 -405.422826) (xy 430.00422 -405.390096) (xy 430.004759 -405.357365)
			(xy 430.013622 -405.292506) (xy 430.03112 -405.229426) (xy 430.056936 -405.169269) (xy 430.073308 -405.140922)
			(xy 430.076615 -405.134894) (xy 430.080226 -405.121633) (xy 430.08042 -405.11476) (xy 430.08042 -404.828756)
			(xy 430.08085 -404.818642) (xy 430.088605 -404.799959) (xy 430.102919 -404.785665) (xy 430.121613 -404.777935)
			(xy 430.131728 -404.777448) (xy 430.848008 -404.777448) (xy 430.858111 -404.777977) (xy 430.876779 -404.785708)
			(xy 430.891072 -404.799991) (xy 430.898815 -404.818654) (xy 430.899316 -404.828756) (xy 430.899316 -405.11476)
			(xy 430.899521 -405.121632) (xy 430.90312 -405.134895) (xy 430.906428 -405.140922) (xy 430.922805 -405.169265)
			(xy 430.948603 -405.229427) (xy 430.96609 -405.292508) (xy 430.974947 -405.357366) (xy 430.975516 -405.390096)
			(xy 430.974969 -405.422826) (xy 430.966107 -405.487685) (xy 430.948612 -405.550765) (xy 430.922799 -405.610923)
			(xy 430.91599 -405.622713) (xy 432.204712 -405.622713) (xy 432.204713 -405.557276) (xy 432.213497 -405.492431)
			(xy 432.230906 -405.429352) (xy 432.256625 -405.369181) (xy 432.272948 -405.34082) (xy 432.276251 -405.33479)
			(xy 432.279865 -405.32153) (xy 432.28006 -405.314658) (xy 432.28006 -404.565358) (xy 432.279851 -404.558486)
			(xy 432.276255 -404.545223) (xy 432.272948 -404.539196) (xy 432.256644 -404.510825) (xy 432.230924 -404.450656)
			(xy 432.213514 -404.387579) (xy 432.204728 -404.322737) (xy 432.204725 -404.257301) (xy 432.213506 -404.192458)
			(xy 432.230912 -404.12938) (xy 432.256627 -404.069209) (xy 432.272948 -404.040848) (xy 432.276277 -404.03483)
			(xy 432.279874 -404.021561) (xy 432.28006 -404.014686) (xy 432.28006 -403.728682) (xy 432.28045 -403.718507)
			(xy 432.288245 -403.699707) (xy 432.302641 -403.685322) (xy 432.321446 -403.677542) (xy 432.331622 -403.67712)
			(xy 433.047902 -403.67712) (xy 433.058058 -403.677631) (xy 433.076823 -403.685403) (xy 433.091188 -403.699763)
			(xy 433.098965 -403.718526) (xy 433.099464 -403.728682) (xy 433.099464 -404.014686) (xy 433.099666 -404.021558)
			(xy 433.103268 -404.034821) (xy 433.106576 -404.040848) (xy 433.122916 -404.069199) (xy 433.148631 -404.129373)
			(xy 433.166037 -404.192454) (xy 433.174818 -404.2573) (xy 433.174816 -404.290022) (xy 436.603656 -404.290022)
			(xy 436.607647 -404.227855) (xy 436.619556 -404.166708) (xy 436.639185 -404.107587) (xy 436.666214 -404.051461)
			(xy 436.700198 -403.999252) (xy 436.74058 -403.951817) (xy 436.786696 -403.909936) (xy 436.837788 -403.874296)
			(xy 436.893019 -403.845482) (xy 436.951481 -403.823968) (xy 437.012215 -403.810106) (xy 437.074222 -403.804124)
			(xy 437.136485 -403.80612) (xy 437.197982 -403.816063) (xy 437.257703 -403.833787) (xy 437.314666 -403.859004)
			(xy 437.367937 -403.891297) (xy 437.416642 -403.930137) (xy 437.459979 -403.974887) (xy 437.497239 -404.024811)
			(xy 437.507272 -404.042626) (xy 446.93027 -404.042626) (xy 446.934341 -403.987004) (xy 446.946467 -403.932567)
			(xy 446.96639 -403.880476) (xy 446.993686 -403.831841) (xy 447.027772 -403.787698) (xy 447.067921 -403.748989)
			(xy 447.113279 -403.716538) (xy 447.162879 -403.691037) (xy 447.215663 -403.67303) (xy 447.270506 -403.6629)
			(xy 447.32624 -403.660863) (xy 447.381677 -403.666963) (xy 447.435634 -403.681069) (xy 447.486963 -403.702881)
			(xy 447.534569 -403.731935) (xy 447.577437 -403.76761) (xy 447.614654 -403.809147) (xy 447.645427 -403.85566)
			(xy 447.669099 -403.906157) (xy 447.685167 -403.959564) (xy 447.693287 -404.01474) (xy 447.693796 -404.042626)
			(xy 447.693287 -404.070512) (xy 447.685167 -404.125688) (xy 447.669099 -404.179095) (xy 447.645427 -404.229592)
			(xy 447.614654 -404.276105) (xy 447.577437 -404.317642) (xy 447.534569 -404.353317) (xy 447.486963 -404.382371)
			(xy 447.435634 -404.404183) (xy 447.381677 -404.418289) (xy 447.32624 -404.424389) (xy 447.270506 -404.422352)
			(xy 447.215663 -404.412222) (xy 447.162879 -404.394215) (xy 447.113279 -404.368714) (xy 447.067921 -404.336263)
			(xy 447.027772 -404.297554) (xy 446.993686 -404.253411) (xy 446.96639 -404.204776) (xy 446.946467 -404.152685)
			(xy 446.934341 -404.098248) (xy 446.93027 -404.042626) (xy 437.507272 -404.042626) (xy 437.527808 -404.07909)
			(xy 437.551186 -404.136833) (xy 437.566987 -404.197091) (xy 437.574953 -404.258874) (xy 437.575452 -404.290022)
			(xy 437.574953 -404.32117) (xy 437.566987 -404.382953) (xy 437.551186 -404.443211) (xy 437.527808 -404.500954)
			(xy 437.497239 -404.555233) (xy 437.459979 -404.605157) (xy 437.416642 -404.649907) (xy 437.367937 -404.688747)
			(xy 437.314666 -404.72104) (xy 437.257703 -404.746257) (xy 437.197982 -404.763981) (xy 437.136485 -404.773924)
			(xy 437.074222 -404.77592) (xy 437.012215 -404.769938) (xy 436.951481 -404.756076) (xy 436.893019 -404.734562)
			(xy 436.837788 -404.705748) (xy 436.786696 -404.670108) (xy 436.74058 -404.628227) (xy 436.700198 -404.580792)
			(xy 436.666214 -404.528583) (xy 436.639185 -404.472457) (xy 436.619556 -404.413336) (xy 436.607647 -404.352189)
			(xy 436.603656 -404.290022) (xy 433.174816 -404.290022) (xy 433.174815 -404.322738) (xy 433.166029 -404.387583)
			(xy 433.148619 -404.450663) (xy 433.122899 -404.510835) (xy 433.106576 -404.539196) (xy 433.103261 -404.54522)
			(xy 433.099656 -404.558484) (xy 433.099464 -404.565358) (xy 433.099464 -405.314658) (xy 433.099676 -405.32153)
			(xy 433.103271 -405.334792) (xy 433.106576 -405.34082) (xy 433.122893 -405.369184) (xy 433.14861 -405.429355)
			(xy 433.166018 -405.492433) (xy 433.174802 -405.557277) (xy 433.174803 -405.622713) (xy 433.16602 -405.687557)
			(xy 433.148613 -405.750635) (xy 433.122897 -405.810807) (xy 433.106576 -405.839168) (xy 433.103271 -405.845197)
			(xy 433.09966 -405.858457) (xy 433.099464 -405.86533) (xy 433.099464 -406.151334) (xy 433.098995 -406.161494)
			(xy 433.091209 -406.180263) (xy 433.076836 -406.194627) (xy 433.058062 -406.202401) (xy 433.047902 -406.202896)
			(xy 432.331622 -406.202896) (xy 432.32147 -406.20235) (xy 432.302708 -406.194589) (xy 432.288343 -406.180239)
			(xy 432.280561 -406.161486) (xy 432.28006 -406.151334) (xy 432.28006 -405.86533) (xy 432.279862 -405.858457)
			(xy 432.276258 -405.845194) (xy 432.272948 -405.839168) (xy 432.25662 -405.81081) (xy 432.230903 -405.750638)
			(xy 432.213495 -405.687559) (xy 432.204712 -405.622713) (xy 430.91599 -405.622713) (xy 430.906428 -405.63927)
			(xy 430.903126 -405.645301) (xy 430.899512 -405.65856) (xy 430.899316 -405.665432) (xy 430.899316 -406.414732)
			(xy 430.899494 -406.421606) (xy 430.903111 -406.434869) (xy 430.906428 -406.440894) (xy 430.922794 -406.469243)
			(xy 430.948595 -406.529403) (xy 430.966084 -406.592482) (xy 430.974945 -406.657339) (xy 430.975516 -406.690068)
			(xy 430.974956 -406.722792) (xy 434.404852 -406.722792) (xy 434.404856 -406.657353) (xy 434.413643 -406.592508)
			(xy 434.431053 -406.529428) (xy 434.456773 -406.469256) (xy 434.473096 -406.440894) (xy 434.476413 -406.43487)
			(xy 434.480017 -406.421606) (xy 434.480208 -406.414732) (xy 434.480208 -405.665432) (xy 434.480003 -405.65856)
			(xy 434.476404 -405.645297) (xy 434.473096 -405.63927) (xy 434.456772 -405.61091) (xy 434.431057 -405.550738)
			(xy 434.413651 -405.487659) (xy 434.404868 -405.422815) (xy 434.404869 -405.357378) (xy 434.413652 -405.292534)
			(xy 434.431059 -405.229455) (xy 434.456775 -405.169284) (xy 434.473096 -405.140922) (xy 434.476403 -405.134893)
			(xy 434.480013 -405.121633) (xy 434.480208 -405.11476) (xy 434.480208 -404.828756) (xy 434.480586 -404.818598)
			(xy 434.488397 -404.799843) (xy 434.502807 -404.785521) (xy 434.52161 -404.777824) (xy 434.53177 -404.777448)
			(xy 435.24805 -404.777448) (xy 435.258175 -404.777968) (xy 435.276896 -404.785681) (xy 435.291254 -404.799957)
			(xy 435.299074 -404.818634) (xy 435.299612 -404.828756) (xy 435.299612 -405.11476) (xy 435.299818 -405.121632)
			(xy 435.303417 -405.134895) (xy 435.306724 -405.140922) (xy 435.323044 -405.169285) (xy 435.348764 -405.229455)
			(xy 435.366174 -405.292534) (xy 435.374958 -405.357378) (xy 435.374959 -405.422815) (xy 435.366175 -405.48766)
			(xy 435.348766 -405.550738) (xy 435.331987 -405.589994) (xy 436.603656 -405.589994) (xy 436.607647 -405.527827)
			(xy 436.619556 -405.46668) (xy 436.639185 -405.407559) (xy 436.666214 -405.351433) (xy 436.700198 -405.299224)
			(xy 436.74058 -405.251789) (xy 436.786696 -405.209908) (xy 436.837788 -405.174268) (xy 436.893019 -405.145454)
			(xy 436.951481 -405.12394) (xy 437.012215 -405.110078) (xy 437.074222 -405.104096) (xy 437.136485 -405.106092)
			(xy 437.197982 -405.116035) (xy 437.257703 -405.133759) (xy 437.314666 -405.158976) (xy 437.367937 -405.191269)
			(xy 437.416642 -405.230109) (xy 437.459979 -405.274859) (xy 437.497239 -405.324783) (xy 437.527808 -405.379062)
			(xy 437.532275 -405.390096) (xy 438.803804 -405.390096) (xy 438.807795 -405.327929) (xy 438.819704 -405.266782)
			(xy 438.839333 -405.207661) (xy 438.866362 -405.151535) (xy 438.900346 -405.099326) (xy 438.940728 -405.051891)
			(xy 438.986844 -405.01001) (xy 439.037936 -404.97437) (xy 439.093167 -404.945556) (xy 439.151629 -404.924042)
			(xy 439.212363 -404.91018) (xy 439.27437 -404.904198) (xy 439.336633 -404.906194) (xy 439.39813 -404.916137)
			(xy 439.457851 -404.933861) (xy 439.514814 -404.959078) (xy 439.568085 -404.991371) (xy 439.61679 -405.030211)
			(xy 439.660127 -405.074961) (xy 439.697387 -405.124885) (xy 439.727956 -405.179164) (xy 439.751334 -405.236907)
			(xy 439.767135 -405.297165) (xy 439.775101 -405.358948) (xy 439.7756 -405.390096) (xy 439.775101 -405.421244)
			(xy 439.767135 -405.483027) (xy 439.751334 -405.543285) (xy 439.727956 -405.601028) (xy 439.697387 -405.655307)
			(xy 439.660127 -405.705231) (xy 439.61679 -405.749981) (xy 439.568085 -405.788821) (xy 439.514814 -405.821114)
			(xy 439.457851 -405.846331) (xy 439.39813 -405.864055) (xy 439.336633 -405.873998) (xy 439.27437 -405.875994)
			(xy 439.212363 -405.870012) (xy 439.151629 -405.85615) (xy 439.093167 -405.834636) (xy 439.037936 -405.805822)
			(xy 438.986844 -405.770182) (xy 438.940728 -405.728301) (xy 438.900346 -405.680866) (xy 438.866362 -405.628657)
			(xy 438.839333 -405.572531) (xy 438.819704 -405.51341) (xy 438.807795 -405.452263) (xy 438.803804 -405.390096)
			(xy 437.532275 -405.390096) (xy 437.551186 -405.436805) (xy 437.566987 -405.497063) (xy 437.574953 -405.558846)
			(xy 437.575452 -405.589994) (xy 437.574953 -405.621142) (xy 437.566987 -405.682925) (xy 437.551186 -405.743183)
			(xy 437.527808 -405.800926) (xy 437.497239 -405.855205) (xy 437.459979 -405.905129) (xy 437.416642 -405.949879)
			(xy 437.367937 -405.988719) (xy 437.314666 -406.021012) (xy 437.257703 -406.046229) (xy 437.197982 -406.063953)
			(xy 437.136485 -406.073896) (xy 437.074222 -406.075892) (xy 437.012215 -406.06991) (xy 436.951481 -406.056048)
			(xy 436.893019 -406.034534) (xy 436.837788 -406.00572) (xy 436.786696 -405.97008) (xy 436.74058 -405.928199)
			(xy 436.700198 -405.880764) (xy 436.666214 -405.828555) (xy 436.639185 -405.772429) (xy 436.619556 -405.713308)
			(xy 436.607647 -405.652161) (xy 436.603656 -405.589994) (xy 435.331987 -405.589994) (xy 435.323047 -405.610909)
			(xy 435.306724 -405.63927) (xy 435.303422 -405.645301) (xy 435.299808 -405.65856) (xy 435.299612 -405.665432)
			(xy 435.299612 -406.153366) (xy 446.64452 -406.153366) (xy 446.648591 -406.097744) (xy 446.660717 -406.043307)
			(xy 446.68064 -405.991216) (xy 446.707936 -405.942581) (xy 446.742022 -405.898438) (xy 446.782171 -405.859729)
			(xy 446.827529 -405.827278) (xy 446.877129 -405.801777) (xy 446.929913 -405.78377) (xy 446.984756 -405.77364)
			(xy 447.04049 -405.771603) (xy 447.095927 -405.777703) (xy 447.149884 -405.791809) (xy 447.201213 -405.813621)
			(xy 447.248819 -405.842675) (xy 447.291687 -405.87835) (xy 447.328904 -405.919887) (xy 447.359677 -405.9664)
			(xy 447.383349 -406.016897) (xy 447.399417 -406.070304) (xy 447.407537 -406.12548) (xy 447.408046 -406.153366)
			(xy 447.407537 -406.181252) (xy 447.399417 -406.236428) (xy 447.387573 -406.275794) (xy 447.938142 -406.275794)
			(xy 447.942213 -406.220172) (xy 447.954339 -406.165735) (xy 447.974262 -406.113644) (xy 448.001558 -406.065009)
			(xy 448.035644 -406.020866) (xy 448.075793 -405.982157) (xy 448.121151 -405.949706) (xy 448.170751 -405.924205)
			(xy 448.223535 -405.906198) (xy 448.278378 -405.896068) (xy 448.334112 -405.894031) (xy 448.389549 -405.900131)
			(xy 448.443506 -405.914237) (xy 448.494835 -405.936049) (xy 448.542441 -405.965103) (xy 448.585309 -406.000778)
			(xy 448.622526 -406.042315) (xy 448.653299 -406.088828) (xy 448.676971 -406.139325) (xy 448.693039 -406.192732)
			(xy 448.701159 -406.247908) (xy 448.701668 -406.275794) (xy 448.701159 -406.30368) (xy 448.693039 -406.358856)
			(xy 448.676971 -406.412263) (xy 448.653299 -406.46276) (xy 448.622526 -406.509273) (xy 448.585309 -406.55081)
			(xy 448.542441 -406.586485) (xy 448.494835 -406.615539) (xy 448.443506 -406.637351) (xy 448.389549 -406.651457)
			(xy 448.334112 -406.657557) (xy 448.278378 -406.65552) (xy 448.223535 -406.64539) (xy 448.170751 -406.627383)
			(xy 448.121151 -406.601882) (xy 448.075793 -406.569431) (xy 448.035644 -406.530722) (xy 448.001558 -406.486579)
			(xy 447.974262 -406.437944) (xy 447.954339 -406.385853) (xy 447.942213 -406.331416) (xy 447.938142 -406.275794)
			(xy 447.387573 -406.275794) (xy 447.383349 -406.289835) (xy 447.359677 -406.340332) (xy 447.328904 -406.386845)
			(xy 447.291687 -406.428382) (xy 447.248819 -406.464057) (xy 447.201213 -406.493111) (xy 447.149884 -406.514923)
			(xy 447.095927 -406.529029) (xy 447.04049 -406.535129) (xy 446.984756 -406.533092) (xy 446.929913 -406.522962)
			(xy 446.877129 -406.504955) (xy 446.827529 -406.479454) (xy 446.782171 -406.447003) (xy 446.742022 -406.408294)
			(xy 446.707936 -406.364151) (xy 446.68064 -406.315516) (xy 446.660717 -406.263425) (xy 446.648591 -406.208988)
			(xy 446.64452 -406.153366) (xy 435.299612 -406.153366) (xy 435.299612 -406.414732) (xy 435.29979 -406.421606)
			(xy 435.303408 -406.434869) (xy 435.306724 -406.440894) (xy 435.32302 -406.46927) (xy 435.348742 -406.529437)
			(xy 435.366155 -406.592513) (xy 435.374942 -406.657355) (xy 435.374944 -406.690068) (xy 438.803804 -406.690068)
			(xy 438.807795 -406.627901) (xy 438.819704 -406.566754) (xy 438.839333 -406.507633) (xy 438.866362 -406.451507)
			(xy 438.900346 -406.399298) (xy 438.940728 -406.351863) (xy 438.986844 -406.309982) (xy 439.037936 -406.274342)
			(xy 439.093167 -406.245528) (xy 439.151629 -406.224014) (xy 439.212363 -406.210152) (xy 439.27437 -406.20417)
			(xy 439.336633 -406.206166) (xy 439.39813 -406.216109) (xy 439.457851 -406.233833) (xy 439.514814 -406.25905)
			(xy 439.568085 -406.291343) (xy 439.61679 -406.330183) (xy 439.660127 -406.374933) (xy 439.697387 -406.424857)
			(xy 439.727956 -406.479136) (xy 439.751334 -406.536879) (xy 439.767135 -406.597137) (xy 439.775101 -406.65892)
			(xy 439.7756 -406.690068) (xy 439.775101 -406.721216) (xy 439.767135 -406.782999) (xy 439.751334 -406.843257)
			(xy 439.727956 -406.901) (xy 439.697387 -406.955279) (xy 439.660127 -407.005203) (xy 439.61679 -407.049953)
			(xy 439.568085 -407.088793) (xy 439.514814 -407.121086) (xy 439.457851 -407.146303) (xy 439.39813 -407.164027)
			(xy 439.336633 -407.17397) (xy 439.27437 -407.175966) (xy 439.212363 -407.169984) (xy 439.151629 -407.156122)
			(xy 439.093167 -407.134608) (xy 439.037936 -407.105794) (xy 438.986844 -407.070154) (xy 438.940728 -407.028273)
			(xy 438.900346 -406.980838) (xy 438.866362 -406.928629) (xy 438.839333 -406.872503) (xy 438.819704 -406.813382)
			(xy 438.807795 -406.752235) (xy 438.803804 -406.690068) (xy 435.374944 -406.690068) (xy 435.374946 -406.72279)
			(xy 435.366166 -406.787633) (xy 435.348761 -406.850711) (xy 435.323045 -406.910881) (xy 435.306724 -406.939242)
			(xy 435.303396 -406.94526) (xy 435.299798 -406.958529) (xy 435.299612 -406.965404) (xy 435.299612 -407.251408)
			(xy 435.299185 -407.261561) (xy 435.291389 -407.280311) (xy 435.276994 -407.294634) (xy 435.258205 -407.302335)
			(xy 435.24805 -407.302716) (xy 434.53177 -407.302716) (xy 434.521636 -407.302297) (xy 434.502906 -407.294551)
			(xy 434.488549 -407.280244) (xy 434.480739 -407.26154) (xy 434.480208 -407.251408) (xy 434.480208 -406.965404)
			(xy 434.480014 -406.958531) (xy 434.476407 -406.945268) (xy 434.473096 -406.939242) (xy 434.456748 -406.910895)
			(xy 434.431035 -406.85072) (xy 434.413632 -406.787639) (xy 434.404852 -406.722792) (xy 430.974956 -406.722792)
			(xy 430.974956 -406.722798) (xy 430.966099 -406.787656) (xy 430.948606 -406.850736) (xy 430.922797 -406.910894)
			(xy 430.906428 -406.939242) (xy 430.9031 -406.94526) (xy 430.899502 -406.958529) (xy 430.899316 -406.965404)
			(xy 430.899316 -407.251408) (xy 430.898822 -407.261515) (xy 430.891084 -407.28019) (xy 430.87679 -407.294484)
			(xy 430.858115 -407.302222) (xy 430.848008 -407.302716) (xy 430.131728 -407.302716) (xy 430.121609 -407.302262)
			(xy 430.102909 -407.294526) (xy 430.088595 -407.280221) (xy 430.080845 -407.261526) (xy 430.08042 -407.251408)
			(xy 430.08042 -406.965404) (xy 430.080224 -406.958531) (xy 430.076618 -406.945268) (xy 430.073308 -406.939242)
			(xy 430.05696 -406.910883) (xy 430.031154 -406.850727) (xy 430.013659 -406.787651) (xy 430.004793 -406.722796)
			(xy 430.00422 -406.690068) (xy 426.574858 -406.690068) (xy 426.57486 -406.72279) (xy 426.56608 -406.787633)
			(xy 426.548675 -406.850711) (xy 426.522961 -406.910881) (xy 426.50664 -406.939242) (xy 426.503314 -406.945261)
			(xy 426.499715 -406.958529) (xy 426.499528 -406.965404) (xy 426.499528 -407.251408) (xy 426.499085 -407.261559)
			(xy 426.491292 -407.280306) (xy 426.476903 -407.294628) (xy 426.458119 -407.302333) (xy 426.447966 -407.302716)
			(xy 425.731686 -407.302716) (xy 425.721553 -407.302283) (xy 425.702823 -407.294543) (xy 425.688466 -407.28024)
			(xy 425.680655 -407.261539) (xy 425.680124 -407.251408) (xy 425.680124 -406.965404) (xy 425.679928 -406.958531)
			(xy 425.676322 -406.945268) (xy 425.673012 -406.939242) (xy 425.656663 -406.910895) (xy 425.63095 -406.850721)
			(xy 425.613546 -406.787639) (xy 425.604766 -406.722792) (xy 422.17487 -406.722792) (xy 422.17487 -406.722798)
			(xy 422.166013 -406.787656) (xy 422.148521 -406.850736) (xy 422.122713 -406.910894) (xy 422.106344 -406.939242)
			(xy 422.103018 -406.945261) (xy 422.099419 -406.958529) (xy 422.099232 -406.965404) (xy 422.099232 -407.251408)
			(xy 422.098722 -407.261513) (xy 422.090988 -407.280185) (xy 422.076699 -407.294479) (xy 422.058029 -407.302219)
			(xy 422.047924 -407.302716) (xy 421.331644 -407.302716) (xy 421.321526 -407.302248) (xy 421.302827 -407.294518)
			(xy 421.288512 -407.280217) (xy 421.280762 -407.261525) (xy 421.280336 -407.251408) (xy 421.280336 -406.965404)
			(xy 421.280138 -406.958531) (xy 421.276533 -406.945269) (xy 421.273224 -406.939242) (xy 421.256877 -406.910882)
			(xy 421.23107 -406.850727) (xy 421.213575 -406.78765) (xy 421.204709 -406.722796) (xy 421.204136 -406.690068)
			(xy 414.525968 -406.690068) (xy 414.525968 -409.522889) (xy 419.004819 -409.522889) (xy 419.004823 -409.457449)
			(xy 419.013612 -409.392602) (xy 419.031026 -409.329522) (xy 419.05675 -409.269351) (xy 419.073076 -409.24099)
			(xy 419.076393 -409.234966) (xy 419.079998 -409.221702) (xy 419.080188 -409.214828) (xy 419.080188 -408.465528)
			(xy 419.079987 -408.458655) (xy 419.076385 -408.445393) (xy 419.073076 -408.439366) (xy 419.056746 -408.411009)
			(xy 419.031027 -408.350837) (xy 419.013618 -408.287758) (xy 419.004835 -408.222912) (xy 419.004836 -408.157474)
			(xy 419.013621 -408.092629) (xy 419.031031 -408.02955) (xy 419.056752 -407.969379) (xy 419.073076 -407.941018)
			(xy 419.076383 -407.934989) (xy 419.079994 -407.921729) (xy 419.080188 -407.914856) (xy 419.080188 -407.628852)
			(xy 419.080582 -407.618696) (xy 419.088391 -407.599945) (xy 419.102796 -407.585624) (xy 419.121592 -407.577924)
			(xy 419.13175 -407.577544) (xy 419.84803 -407.577544) (xy 419.858159 -407.578002) (xy 419.876882 -407.58574)
			(xy 419.891237 -407.600035) (xy 419.899055 -407.618725) (xy 419.899592 -407.628852) (xy 419.899592 -407.914856)
			(xy 419.899802 -407.921728) (xy 419.903398 -407.934991) (xy 419.906704 -407.941018) (xy 419.923018 -407.969383)
			(xy 419.948734 -408.029554) (xy 419.966141 -408.092632) (xy 419.974925 -408.157475) (xy 419.974926 -408.222911)
			(xy 419.966144 -408.287755) (xy 419.948739 -408.350833) (xy 419.923024 -408.411004) (xy 419.906704 -408.439366)
			(xy 419.903402 -408.445397) (xy 419.899788 -408.458656) (xy 419.899592 -408.465528) (xy 419.899592 -409.214828)
			(xy 419.899774 -409.221702) (xy 419.903389 -409.234965) (xy 419.906704 -409.24099) (xy 419.922994 -409.269369)
			(xy 419.948713 -409.329536) (xy 419.966122 -409.392611) (xy 419.974909 -409.457452) (xy 419.974913 -409.522886)
			(xy 419.966135 -409.587728) (xy 419.948733 -409.650805) (xy 419.923022 -409.710976) (xy 419.906704 -409.739338)
			(xy 419.903376 -409.745356) (xy 419.899779 -409.758625) (xy 419.899592 -409.7655) (xy 419.899592 -410.051504)
			(xy 419.899181 -410.061659) (xy 419.891383 -410.080413) (xy 419.876983 -410.094737) (xy 419.858187 -410.102435)
			(xy 419.84803 -410.102812) (xy 419.13175 -410.102812) (xy 419.121633 -410.102234) (xy 419.102923 -410.094532)
			(xy 419.088567 -410.080274) (xy 419.080736 -410.061618) (xy 419.080188 -410.051504) (xy 419.080188 -409.7655)
			(xy 419.079997 -409.758627) (xy 419.076388 -409.745364) (xy 419.073076 -409.739338) (xy 419.056722 -409.710994)
			(xy 419.031005 -409.650819) (xy 419.013599 -409.587737) (xy 419.004819 -409.522889) (xy 414.525968 -409.522889)
			(xy 414.525968 -410.589984) (xy 421.204136 -410.589984) (xy 421.204725 -410.557255) (xy 421.213576 -410.492398)
			(xy 421.231059 -410.429318) (xy 421.256859 -410.369159) (xy 421.273224 -410.34081) (xy 421.276537 -410.334785)
			(xy 421.280143 -410.321521) (xy 421.280336 -410.314648) (xy 421.280336 -409.565348) (xy 421.280121 -409.558476)
			(xy 421.276528 -409.545214) (xy 421.273224 -409.539186) (xy 421.256855 -409.510839) (xy 421.231054 -409.450679)
			(xy 421.213565 -409.387598) (xy 421.204706 -409.322741) (xy 421.204136 -409.290012) (xy 421.204693 -409.257282)
			(xy 421.213553 -409.192424) (xy 421.231046 -409.129344) (xy 421.256855 -409.069186) (xy 421.273224 -409.040838)
			(xy 421.276527 -409.034808) (xy 421.28014 -409.021548) (xy 421.280336 -409.014676) (xy 421.280336 -408.728672)
			(xy 421.280694 -408.718543) (xy 421.288458 -408.699832) (xy 421.302793 -408.685517) (xy 421.321515 -408.67778)
			(xy 421.331644 -408.677364) (xy 422.047924 -408.677364) (xy 422.05803 -408.677864) (xy 422.076702 -408.685603)
			(xy 422.090994 -408.699895) (xy 422.098735 -408.718566) (xy 422.099232 -408.728672) (xy 422.099232 -409.014676)
			(xy 422.099429 -409.021549) (xy 422.103033 -409.034812) (xy 422.106344 -409.040838) (xy 422.122719 -409.069182)
			(xy 422.14852 -409.129343) (xy 422.166007 -409.192424) (xy 422.174864 -409.257282) (xy 422.175432 -409.290012)
			(xy 422.174845 -409.322741) (xy 422.165995 -409.387598) (xy 422.14851 -409.450678) (xy 422.131575 -409.490164)
			(xy 423.404284 -409.490164) (xy 423.404858 -409.457435) (xy 423.413712 -409.392577) (xy 423.4312 -409.329497)
			(xy 423.457005 -409.269338) (xy 423.473372 -409.24099) (xy 423.476688 -409.234966) (xy 423.480293 -409.221702)
			(xy 423.480484 -409.214828) (xy 423.480484 -408.465528) (xy 423.480283 -408.458655) (xy 423.476681 -408.445393)
			(xy 423.473372 -408.439366) (xy 423.45699 -408.411026) (xy 423.431193 -408.350863) (xy 423.413708 -408.287781)
			(xy 423.404852 -408.222922) (xy 423.404284 -408.190192) (xy 423.404871 -408.157463) (xy 423.413721 -408.092606)
			(xy 423.431205 -408.029526) (xy 423.457006 -407.969367) (xy 423.473372 -407.941018) (xy 423.476678 -407.934989)
			(xy 423.48029 -407.921729) (xy 423.480484 -407.914856) (xy 423.480484 -407.628852) (xy 423.480946 -407.618742)
			(xy 423.488696 -407.600066) (xy 423.503 -407.585774) (xy 423.521682 -407.578038) (xy 423.531792 -407.577544)
			(xy 424.248072 -407.577544) (xy 424.258172 -407.578106) (xy 424.276839 -407.585825) (xy 424.291133 -407.600097)
			(xy 424.298879 -407.618753) (xy 424.29938 -407.628852) (xy 424.29938 -407.914856) (xy 424.299591 -407.921728)
			(xy 424.303186 -407.934991) (xy 424.306492 -407.941018) (xy 424.322864 -407.969364) (xy 424.348664 -408.029524)
			(xy 424.366152 -408.092605) (xy 424.375011 -408.157463) (xy 424.37558 -408.190192) (xy 424.375036 -408.222922)
			(xy 424.366174 -408.287781) (xy 424.348677 -408.350862) (xy 424.322864 -408.411019) (xy 424.306492 -408.439366)
			(xy 424.303189 -408.445396) (xy 424.299576 -408.458656) (xy 424.29938 -408.465528) (xy 424.29938 -409.214828)
			(xy 424.299564 -409.221702) (xy 424.303178 -409.234964) (xy 424.306492 -409.24099) (xy 424.322853 -409.269342)
			(xy 424.348656 -409.3295) (xy 424.366147 -409.392579) (xy 424.375009 -409.457435) (xy 424.37558 -409.490164)
			(xy 424.375023 -409.522894) (xy 424.366165 -409.587753) (xy 424.348672 -409.650833) (xy 424.322862 -409.71099)
			(xy 424.306492 -409.739338) (xy 424.303163 -409.745356) (xy 424.299567 -409.758625) (xy 424.29938 -409.7655)
			(xy 424.29938 -410.051504) (xy 424.298987 -410.061629) (xy 424.291234 -410.080337) (xy 424.27691 -410.094651)
			(xy 424.258197 -410.102393) (xy 424.248072 -410.102812) (xy 423.531792 -410.102812) (xy 423.521684 -410.102322)
			(xy 423.503008 -410.094584) (xy 423.488714 -410.080288) (xy 423.480978 -410.061612) (xy 423.480484 -410.051504)
			(xy 423.480484 -409.7655) (xy 423.480294 -409.758627) (xy 423.476684 -409.745364) (xy 423.473372 -409.739338)
			(xy 423.457019 -409.710982) (xy 423.431215 -409.650825) (xy 423.413722 -409.587747) (xy 423.404857 -409.522892)
			(xy 423.404284 -409.490164) (xy 422.131575 -409.490164) (xy 422.122709 -409.510837) (xy 422.106344 -409.539186)
			(xy 422.103038 -409.545215) (xy 422.099426 -409.558475) (xy 422.099232 -409.565348) (xy 422.099232 -410.314648)
			(xy 422.09944 -410.32152) (xy 422.103037 -410.334783) (xy 422.106344 -410.34081) (xy 422.122708 -410.36916)
			(xy 422.148512 -410.429319) (xy 422.166002 -410.492398) (xy 422.174862 -410.557255) (xy 422.175432 -410.589984)
			(xy 422.174877 -410.622705) (xy 425.604775 -410.622705) (xy 425.604777 -410.557268) (xy 425.613562 -410.492422)
			(xy 425.630971 -410.429343) (xy 425.65669 -410.369172) (xy 425.673012 -410.34081) (xy 425.676324 -410.334784)
			(xy 425.679931 -410.321521) (xy 425.680124 -410.314648) (xy 425.680124 -409.565348) (xy 425.679911 -409.558476)
			(xy 425.676317 -409.545214) (xy 425.673012 -409.539186) (xy 425.656701 -409.510819) (xy 425.630984 -409.450649)
			(xy 425.613575 -409.387571) (xy 425.604791 -409.322728) (xy 425.60479 -409.257293) (xy 425.613571 -409.192449)
			(xy 425.630977 -409.129371) (xy 425.656691 -409.0692) (xy 425.673012 -409.040838) (xy 425.676314 -409.034807)
			(xy 425.679927 -409.021548) (xy 425.680124 -409.014676) (xy 425.680124 -408.728672) (xy 425.680499 -408.718513)
			(xy 425.688308 -408.699755) (xy 425.70272 -408.685432) (xy 425.721525 -408.677738) (xy 425.731686 -408.677364)
			(xy 426.447966 -408.677364) (xy 426.458093 -408.677855) (xy 426.476818 -408.685576) (xy 426.491177 -408.699862)
			(xy 426.498993 -408.718547) (xy 426.499528 -408.728672) (xy 426.499528 -409.014676) (xy 426.499726 -409.021549)
			(xy 426.50333 -409.034812) (xy 426.50664 -409.040838) (xy 426.522973 -409.069193) (xy 426.548691 -409.129366)
			(xy 426.566099 -409.192446) (xy 426.574881 -409.257291) (xy 426.57488 -409.322729) (xy 426.566094 -409.387575)
			(xy 426.548684 -409.450654) (xy 426.522964 -409.510825) (xy 426.51602 -409.522889) (xy 427.804905 -409.522889)
			(xy 427.804909 -409.457449) (xy 427.813698 -409.392603) (xy 427.831111 -409.329523) (xy 427.856835 -409.269351)
			(xy 427.87316 -409.24099) (xy 427.876475 -409.234965) (xy 427.880081 -409.221702) (xy 427.880272 -409.214828)
			(xy 427.880272 -408.465528) (xy 427.880073 -408.458655) (xy 427.87647 -408.445392) (xy 427.87316 -408.439366)
			(xy 427.85683 -408.411009) (xy 427.831112 -408.350837) (xy 427.813704 -408.287757) (xy 427.804921 -408.222912)
			(xy 427.804922 -408.157474) (xy 427.813707 -408.092629) (xy 427.831117 -408.02955) (xy 427.856837 -407.969379)
			(xy 427.87316 -407.941018) (xy 427.876465 -407.934989) (xy 427.880077 -407.921729) (xy 427.880272 -407.914856)
			(xy 427.880272 -407.628852) (xy 427.880682 -407.618698) (xy 427.888488 -407.59995) (xy 427.902887 -407.58563)
			(xy 427.921678 -407.577927) (xy 427.931834 -407.577544) (xy 428.648114 -407.577544) (xy 428.658242 -407.578015)
			(xy 428.676964 -407.585749) (xy 428.69132 -407.600039) (xy 428.699138 -407.618726) (xy 428.699676 -407.628852)
			(xy 428.699676 -407.914856) (xy 428.699888 -407.921728) (xy 428.703483 -407.93499) (xy 428.706788 -407.941018)
			(xy 428.723103 -407.969383) (xy 428.748819 -408.029554) (xy 428.766227 -408.092632) (xy 428.775011 -408.157475)
			(xy 428.775012 -408.222911) (xy 428.76623 -408.287755) (xy 428.748824 -408.350833) (xy 428.723109 -408.411004)
			(xy 428.706788 -408.439366) (xy 428.703485 -408.445396) (xy 428.699872 -408.458656) (xy 428.699676 -408.465528)
			(xy 428.699676 -409.214828) (xy 428.69986 -409.221702) (xy 428.703474 -409.234964) (xy 428.706788 -409.24099)
			(xy 428.723079 -409.269368) (xy 428.748798 -409.329536) (xy 428.766208 -409.392611) (xy 428.774995 -409.457452)
			(xy 428.774999 -409.522886) (xy 428.766221 -409.587728) (xy 428.748818 -409.650806) (xy 428.723107 -409.710977)
			(xy 428.706788 -409.739338) (xy 428.703459 -409.745356) (xy 428.699863 -409.758625) (xy 428.699676 -409.7655)
			(xy 428.699676 -410.051504) (xy 428.699281 -410.061661) (xy 428.69148 -410.080418) (xy 428.677074 -410.094742)
			(xy 428.658274 -410.102438) (xy 428.648114 -410.102812) (xy 427.931834 -410.102812) (xy 427.921716 -410.102247)
			(xy 427.903005 -410.09454) (xy 427.88865 -410.080278) (xy 427.88082 -410.061619) (xy 427.880272 -410.051504)
			(xy 427.880272 -409.7655) (xy 427.880083 -409.758626) (xy 427.876473 -409.745364) (xy 427.87316 -409.739338)
			(xy 427.856807 -409.710994) (xy 427.831091 -409.650819) (xy 427.813685 -409.587737) (xy 427.804905 -409.522889)
			(xy 426.51602 -409.522889) (xy 426.50664 -409.539186) (xy 426.503334 -409.545215) (xy 426.499722 -409.558475)
			(xy 426.499528 -409.565348) (xy 426.499528 -410.314648) (xy 426.499736 -410.32152) (xy 426.503333 -410.334783)
			(xy 426.50664 -410.34081) (xy 426.522949 -410.369179) (xy 426.548669 -410.429348) (xy 426.56608 -410.492425)
			(xy 426.574865 -410.557268) (xy 426.574866 -410.589984) (xy 430.00422 -410.589984) (xy 430.004798 -410.557255)
			(xy 430.01365 -410.492397) (xy 430.031136 -410.429317) (xy 430.056941 -410.369158) (xy 430.073308 -410.34081)
			(xy 430.07662 -410.334784) (xy 430.080227 -410.321521) (xy 430.08042 -410.314648) (xy 430.08042 -409.565348)
			(xy 430.080207 -409.558476) (xy 430.076613 -409.545214) (xy 430.073308 -409.539186) (xy 430.056938 -409.510839)
			(xy 430.031137 -409.450679) (xy 430.013648 -409.387599) (xy 430.00479 -409.322741) (xy 430.00422 -409.290012)
			(xy 430.004766 -409.257282) (xy 430.013627 -409.192423) (xy 430.031123 -409.129343) (xy 430.056937 -409.069185)
			(xy 430.073308 -409.040838) (xy 430.07661 -409.034807) (xy 430.080223 -409.021548) (xy 430.08042 -409.014676)
			(xy 430.08042 -408.728672) (xy 430.080863 -408.718559) (xy 430.088613 -408.699876) (xy 430.102923 -408.685582)
			(xy 430.121614 -408.677852) (xy 430.131728 -408.677364) (xy 430.848008 -408.677364) (xy 430.858113 -408.677878)
			(xy 430.876784 -408.685611) (xy 430.891077 -408.699899) (xy 430.898818 -408.718567) (xy 430.899316 -408.728672)
			(xy 430.899316 -409.014676) (xy 430.899515 -409.021549) (xy 430.903118 -409.034812) (xy 430.906428 -409.040838)
			(xy 430.922811 -409.069177) (xy 430.948608 -409.129341) (xy 430.966093 -409.192423) (xy 430.974948 -409.257282)
			(xy 430.975516 -409.290012) (xy 430.974931 -409.322741) (xy 430.966081 -409.387598) (xy 430.948596 -409.450678)
			(xy 430.922794 -409.510837) (xy 430.915836 -409.522889) (xy 432.204695 -409.522889) (xy 432.204699 -409.457449)
			(xy 432.213487 -409.392603) (xy 432.2309 -409.329523) (xy 432.256623 -409.269351) (xy 432.272948 -409.24099)
			(xy 432.276262 -409.234965) (xy 432.279869 -409.221702) (xy 432.28006 -409.214828) (xy 432.28006 -408.465528)
			(xy 432.279862 -408.458655) (xy 432.276259 -408.445392) (xy 432.272948 -408.439366) (xy 432.256619 -408.411009)
			(xy 432.230901 -408.350837) (xy 432.213494 -408.287757) (xy 432.204711 -408.222912) (xy 432.204712 -408.157474)
			(xy 432.213496 -408.092629) (xy 432.230906 -408.02955) (xy 432.256625 -407.969379) (xy 432.272948 -407.941018)
			(xy 432.276252 -407.934988) (xy 432.279865 -407.921729) (xy 432.28006 -407.914856) (xy 432.28006 -407.628852)
			(xy 432.280482 -407.6187) (xy 432.288286 -407.599954) (xy 432.302681 -407.585634) (xy 432.321468 -407.577929)
			(xy 432.331622 -407.577544) (xy 433.047902 -407.577544) (xy 433.058029 -407.578025) (xy 433.076751 -407.585754)
			(xy 433.091108 -407.600042) (xy 433.098926 -407.618727) (xy 433.099464 -407.628852) (xy 433.099464 -407.914856)
			(xy 433.099677 -407.921728) (xy 433.103271 -407.93499) (xy 433.106576 -407.941018) (xy 433.122891 -407.969383)
			(xy 433.148608 -408.029554) (xy 433.166017 -408.092631) (xy 433.174801 -408.157475) (xy 433.174801 -408.190192)
			(xy 436.603656 -408.190192) (xy 436.607647 -408.128025) (xy 436.619556 -408.066878) (xy 436.639185 -408.007757)
			(xy 436.666214 -407.951631) (xy 436.700198 -407.899422) (xy 436.74058 -407.851987) (xy 436.786696 -407.810106)
			(xy 436.837788 -407.774466) (xy 436.893019 -407.745652) (xy 436.951481 -407.724138) (xy 437.012215 -407.710276)
			(xy 437.074222 -407.704294) (xy 437.136485 -407.70629) (xy 437.197982 -407.716233) (xy 437.257703 -407.733957)
			(xy 437.314666 -407.759174) (xy 437.367937 -407.791467) (xy 437.416642 -407.830307) (xy 437.459979 -407.875057)
			(xy 437.497239 -407.924981) (xy 437.527808 -407.97926) (xy 437.551186 -408.037003) (xy 437.566987 -408.097261)
			(xy 437.574953 -408.159044) (xy 437.575452 -408.190192) (xy 437.574953 -408.22134) (xy 437.566987 -408.283123)
			(xy 437.551186 -408.343381) (xy 437.527808 -408.401124) (xy 437.497239 -408.455403) (xy 437.459979 -408.505327)
			(xy 437.416642 -408.550077) (xy 437.367937 -408.588917) (xy 437.314666 -408.62121) (xy 437.257703 -408.646427)
			(xy 437.197982 -408.664151) (xy 437.136485 -408.674094) (xy 437.074222 -408.67609) (xy 437.012215 -408.670108)
			(xy 436.951481 -408.656246) (xy 436.893019 -408.634732) (xy 436.837788 -408.605918) (xy 436.786696 -408.570278)
			(xy 436.74058 -408.528397) (xy 436.700198 -408.480962) (xy 436.666214 -408.428753) (xy 436.639185 -408.372627)
			(xy 436.619556 -408.313506) (xy 436.607647 -408.252359) (xy 436.603656 -408.190192) (xy 433.174801 -408.190192)
			(xy 433.174802 -408.222911) (xy 433.16602 -408.287755) (xy 433.148613 -408.350833) (xy 433.122897 -408.411005)
			(xy 433.106576 -408.439366) (xy 433.103272 -408.445396) (xy 433.09966 -408.458656) (xy 433.099464 -408.465528)
			(xy 433.099464 -409.214828) (xy 433.09965 -409.221702) (xy 433.103263 -409.234964) (xy 433.106576 -409.24099)
			(xy 433.122867 -409.269368) (xy 433.148587 -409.329536) (xy 433.165998 -409.392611) (xy 433.174785 -409.457452)
			(xy 433.174789 -409.522886) (xy 433.16601 -409.587729) (xy 433.148607 -409.650806) (xy 433.122895 -409.710977)
			(xy 433.106576 -409.739338) (xy 433.103246 -409.745355) (xy 433.09965 -409.758625) (xy 433.099464 -409.7655)
			(xy 433.099464 -410.051504) (xy 433.099081 -410.061663) (xy 433.091277 -410.080422) (xy 433.076868 -410.094747)
			(xy 433.058063 -410.10244) (xy 433.047902 -410.102812) (xy 432.331622 -410.102812) (xy 432.321503 -410.102257)
			(xy 432.302792 -410.094546) (xy 432.288437 -410.080281) (xy 432.280608 -410.06162) (xy 432.28006 -410.051504)
			(xy 432.28006 -409.7655) (xy 432.279873 -409.758626) (xy 432.276262 -409.745363) (xy 432.272948 -409.739338)
			(xy 432.256595 -409.710994) (xy 432.23088 -409.650819) (xy 432.213475 -409.587736) (xy 432.204695 -409.522889)
			(xy 430.915836 -409.522889) (xy 430.906428 -409.539186) (xy 430.90312 -409.545214) (xy 430.89951 -409.558475)
			(xy 430.899316 -409.565348) (xy 430.899316 -410.314648) (xy 430.899526 -410.32152) (xy 430.903122 -410.334783)
			(xy 430.906428 -410.34081) (xy 430.9228 -410.369156) (xy 430.9486 -410.429317) (xy 430.966087 -410.492397)
			(xy 430.974946 -410.557255) (xy 430.975516 -410.589984) (xy 430.974964 -410.622705) (xy 434.404861 -410.622705)
			(xy 434.404863 -410.557268) (xy 434.413648 -410.492423) (xy 434.431057 -410.429344) (xy 434.456774 -410.369172)
			(xy 434.473096 -410.34081) (xy 434.476407 -410.334783) (xy 434.480015 -410.321521) (xy 434.480208 -410.314648)
			(xy 434.480208 -409.565348) (xy 434.479996 -409.558476) (xy 434.476401 -409.545214) (xy 434.473096 -409.539186)
			(xy 434.456785 -409.510819) (xy 434.431069 -409.450648) (xy 434.413661 -409.387571) (xy 434.404877 -409.322728)
			(xy 434.404876 -409.257293) (xy 434.413657 -409.192449) (xy 434.431062 -409.129371) (xy 434.456776 -409.0692)
			(xy 434.473096 -409.040838) (xy 434.476397 -409.034807) (xy 434.480011 -409.021548) (xy 434.480208 -409.014676)
			(xy 434.480208 -408.728672) (xy 434.480599 -408.718515) (xy 434.488405 -408.69976) (xy 434.502811 -408.685438)
			(xy 434.521611 -408.67774) (xy 434.53177 -408.677364) (xy 435.24805 -408.677364) (xy 435.258176 -408.677868)
			(xy 435.276901 -408.685584) (xy 435.29126 -408.699866) (xy 435.299077 -408.718548) (xy 435.299612 -408.728672)
			(xy 435.299612 -409.014676) (xy 435.299812 -409.021549) (xy 435.303415 -409.034811) (xy 435.306724 -409.040838)
			(xy 435.323058 -409.069193) (xy 435.348776 -409.129365) (xy 435.366185 -409.192445) (xy 435.374967 -409.257291)
			(xy 435.374966 -409.322729) (xy 435.36618 -409.387575) (xy 435.348769 -409.450654) (xy 435.33188 -409.490164)
			(xy 436.603656 -409.490164) (xy 436.607647 -409.427997) (xy 436.619556 -409.36685) (xy 436.639185 -409.307729)
			(xy 436.666214 -409.251603) (xy 436.700198 -409.199394) (xy 436.74058 -409.151959) (xy 436.786696 -409.110078)
			(xy 436.837788 -409.074438) (xy 436.893019 -409.045624) (xy 436.951481 -409.02411) (xy 437.012215 -409.010248)
			(xy 437.074222 -409.004266) (xy 437.136485 -409.006262) (xy 437.197982 -409.016205) (xy 437.257703 -409.033929)
			(xy 437.314666 -409.059146) (xy 437.367937 -409.091439) (xy 437.416642 -409.130279) (xy 437.459979 -409.175029)
			(xy 437.497239 -409.224953) (xy 437.527808 -409.279232) (xy 437.532172 -409.290012) (xy 438.803804 -409.290012)
			(xy 438.807795 -409.227845) (xy 438.819704 -409.166698) (xy 438.839333 -409.107577) (xy 438.866362 -409.051451)
			(xy 438.900346 -408.999242) (xy 438.940728 -408.951807) (xy 438.986844 -408.909926) (xy 439.037936 -408.874286)
			(xy 439.093167 -408.845472) (xy 439.151629 -408.823958) (xy 439.212363 -408.810096) (xy 439.27437 -408.804114)
			(xy 439.336633 -408.80611) (xy 439.39813 -408.816053) (xy 439.457851 -408.833777) (xy 439.514814 -408.858994)
			(xy 439.568085 -408.891287) (xy 439.61679 -408.930127) (xy 439.660127 -408.974877) (xy 439.697387 -409.024801)
			(xy 439.727956 -409.07908) (xy 439.751334 -409.136823) (xy 439.767135 -409.197081) (xy 439.775101 -409.258864)
			(xy 439.7756 -409.290012) (xy 439.775101 -409.32116) (xy 439.767135 -409.382943) (xy 439.751334 -409.443201)
			(xy 439.727956 -409.500944) (xy 439.697387 -409.555223) (xy 439.660127 -409.605147) (xy 439.61679 -409.649897)
			(xy 439.568085 -409.688737) (xy 439.514814 -409.72103) (xy 439.457851 -409.746247) (xy 439.39813 -409.763971)
			(xy 439.336633 -409.773914) (xy 439.27437 -409.77591) (xy 439.212363 -409.769928) (xy 439.151629 -409.756066)
			(xy 439.093167 -409.734552) (xy 439.037936 -409.705738) (xy 438.986844 -409.670098) (xy 438.940728 -409.628217)
			(xy 438.900346 -409.580782) (xy 438.866362 -409.528573) (xy 438.839333 -409.472447) (xy 438.819704 -409.413326)
			(xy 438.807795 -409.352179) (xy 438.803804 -409.290012) (xy 437.532172 -409.290012) (xy 437.551186 -409.336975)
			(xy 437.566987 -409.397233) (xy 437.574953 -409.459016) (xy 437.575452 -409.490164) (xy 437.574953 -409.521312)
			(xy 437.566987 -409.583095) (xy 437.551186 -409.643353) (xy 437.527808 -409.701096) (xy 437.497239 -409.755375)
			(xy 437.459979 -409.805299) (xy 437.416642 -409.850049) (xy 437.367937 -409.888889) (xy 437.314666 -409.921182)
			(xy 437.257703 -409.946399) (xy 437.197982 -409.964123) (xy 437.136485 -409.974066) (xy 437.074222 -409.976062)
			(xy 437.012215 -409.97008) (xy 436.951481 -409.956218) (xy 436.893019 -409.934704) (xy 436.837788 -409.90589)
			(xy 436.786696 -409.87025) (xy 436.74058 -409.828369) (xy 436.700198 -409.780934) (xy 436.666214 -409.728725)
			(xy 436.639185 -409.672599) (xy 436.619556 -409.613478) (xy 436.607647 -409.552331) (xy 436.603656 -409.490164)
			(xy 435.33188 -409.490164) (xy 435.323048 -409.510825) (xy 435.306724 -409.539186) (xy 435.303416 -409.545214)
			(xy 435.299806 -409.558475) (xy 435.299612 -409.565348) (xy 435.299612 -410.314648) (xy 435.299822 -410.32152)
			(xy 435.303418 -410.334783) (xy 435.306724 -410.34081) (xy 435.323034 -410.369178) (xy 435.348755 -410.429347)
			(xy 435.366166 -410.492425) (xy 435.374952 -410.557268) (xy 435.374952 -410.589984) (xy 438.803804 -410.589984)
			(xy 438.807795 -410.527817) (xy 438.819704 -410.46667) (xy 438.839333 -410.407549) (xy 438.866362 -410.351423)
			(xy 438.900346 -410.299214) (xy 438.940728 -410.251779) (xy 438.986844 -410.209898) (xy 439.037936 -410.174258)
			(xy 439.093167 -410.145444) (xy 439.151629 -410.12393) (xy 439.212363 -410.110068) (xy 439.27437 -410.104086)
			(xy 439.336633 -410.106082) (xy 439.39813 -410.116025) (xy 439.457851 -410.133749) (xy 439.514814 -410.158966)
			(xy 439.568085 -410.191259) (xy 439.61679 -410.230099) (xy 439.660127 -410.274849) (xy 439.697387 -410.324773)
			(xy 439.727956 -410.379052) (xy 439.751334 -410.436795) (xy 439.767135 -410.497053) (xy 439.775101 -410.558836)
			(xy 439.7756 -410.589984) (xy 439.775101 -410.621132) (xy 439.767135 -410.682915) (xy 439.751334 -410.743173)
			(xy 439.727956 -410.800916) (xy 439.697387 -410.855195) (xy 439.660127 -410.905119) (xy 439.61679 -410.949869)
			(xy 439.568085 -410.988709) (xy 439.514814 -411.021002) (xy 439.457851 -411.046219) (xy 439.39813 -411.063943)
			(xy 439.336633 -411.073886) (xy 439.27437 -411.075882) (xy 439.212363 -411.0699) (xy 439.151629 -411.056038)
			(xy 439.093167 -411.034524) (xy 439.037936 -411.00571) (xy 438.986844 -410.97007) (xy 438.940728 -410.928189)
			(xy 438.900346 -410.880754) (xy 438.866362 -410.828545) (xy 438.839333 -410.772419) (xy 438.819704 -410.713298)
			(xy 438.807795 -410.652151) (xy 438.803804 -410.589984) (xy 435.374952 -410.589984) (xy 435.374953 -410.622704)
			(xy 435.366171 -410.687548) (xy 435.348764 -410.750627) (xy 435.323046 -410.810797) (xy 435.306724 -410.839158)
			(xy 435.303426 -410.845191) (xy 435.299809 -410.858448) (xy 435.299612 -410.86532) (xy 435.299612 -411.151324)
			(xy 435.299198 -411.161478) (xy 435.291397 -411.180229) (xy 435.276998 -411.194551) (xy 435.258206 -411.202252)
			(xy 435.24805 -411.202632) (xy 434.53177 -411.202632) (xy 434.521638 -411.202197) (xy 434.502911 -411.194454)
			(xy 434.488554 -411.180152) (xy 434.480741 -411.161454) (xy 434.480208 -411.151324) (xy 434.480208 -410.86532)
			(xy 434.480008 -410.858447) (xy 434.476405 -410.845185) (xy 434.473096 -410.839158) (xy 434.456762 -410.810804)
			(xy 434.431047 -410.75063) (xy 434.413642 -410.68755) (xy 434.404861 -410.622705) (xy 430.974964 -410.622705)
			(xy 430.974964 -410.622714) (xy 430.966104 -410.687573) (xy 430.948609 -410.750653) (xy 430.922798 -410.81081)
			(xy 430.906428 -410.839158) (xy 430.90313 -410.845191) (xy 430.899513 -410.858448) (xy 430.899316 -410.86532)
			(xy 430.899316 -411.151324) (xy 430.898835 -411.161432) (xy 430.891092 -411.180108) (xy 430.876795 -411.194401)
			(xy 430.858116 -411.202138) (xy 430.848008 -411.202632) (xy 430.131728 -411.202632) (xy 430.121611 -411.202162)
			(xy 430.102914 -411.194429) (xy 430.0886 -411.180129) (xy 430.080848 -411.16144) (xy 430.08042 -411.151324)
			(xy 430.08042 -410.86532) (xy 430.080218 -410.858448) (xy 430.076616 -410.845185) (xy 430.073308 -410.839158)
			(xy 430.056926 -410.810818) (xy 430.031128 -410.750655) (xy 430.013643 -410.687573) (xy 430.004788 -410.622714)
			(xy 430.00422 -410.589984) (xy 426.574866 -410.589984) (xy 426.574867 -410.622704) (xy 426.566085 -410.687548)
			(xy 426.548678 -410.750626) (xy 426.522962 -410.810797) (xy 426.50664 -410.839158) (xy 426.503343 -410.845192)
			(xy 426.499726 -410.858448) (xy 426.499528 -410.86532) (xy 426.499528 -411.151324) (xy 426.499099 -411.161476)
			(xy 426.4913 -411.180224) (xy 426.476907 -411.194545) (xy 426.45812 -411.202249) (xy 426.447966 -411.202632)
			(xy 425.731686 -411.202632) (xy 425.721555 -411.202184) (xy 425.702828 -411.194446) (xy 425.688472 -411.180148)
			(xy 425.680658 -411.161453) (xy 425.680124 -411.151324) (xy 425.680124 -410.86532) (xy 425.679921 -410.858448)
			(xy 425.67632 -410.845185) (xy 425.673012 -410.839158) (xy 425.656677 -410.810804) (xy 425.630962 -410.750631)
			(xy 425.613557 -410.687551) (xy 425.604775 -410.622705) (xy 422.174877 -410.622705) (xy 422.174877 -410.622714)
			(xy 422.166018 -410.687572) (xy 422.148524 -410.750652) (xy 422.122714 -410.81081) (xy 422.106344 -410.839158)
			(xy 422.103048 -410.845192) (xy 422.09943 -410.858448) (xy 422.099232 -410.86532) (xy 422.099232 -411.151324)
			(xy 422.098735 -411.16143) (xy 422.090996 -411.180103) (xy 422.076703 -411.194396) (xy 422.05803 -411.202135)
			(xy 422.047924 -411.202632) (xy 421.331644 -411.202632) (xy 421.321528 -411.202149) (xy 421.302832 -411.194421)
			(xy 421.288517 -411.180125) (xy 421.280765 -411.161439) (xy 421.280336 -411.151324) (xy 421.280336 -410.86532)
			(xy 421.280132 -410.858448) (xy 421.276531 -410.845185) (xy 421.273224 -410.839158) (xy 421.256844 -410.810817)
			(xy 421.231045 -410.750654) (xy 421.213559 -410.687572) (xy 421.204704 -410.622714) (xy 421.204136 -410.589984)
			(xy 414.525968 -410.589984) (xy 414.525968 -412.090108) (xy 419.003742 -412.090108) (xy 419.007733 -412.027941)
			(xy 419.019642 -411.966794) (xy 419.039271 -411.907673) (xy 419.0663 -411.851547) (xy 419.100284 -411.799338)
			(xy 419.140666 -411.751903) (xy 419.186782 -411.710022) (xy 419.237874 -411.674382) (xy 419.293105 -411.645568)
			(xy 419.351567 -411.624054) (xy 419.412301 -411.610192) (xy 419.474308 -411.60421) (xy 419.536571 -411.606206)
			(xy 419.598068 -411.616149) (xy 419.657789 -411.633873) (xy 419.714752 -411.65909) (xy 419.768023 -411.691383)
			(xy 419.816728 -411.730223) (xy 419.860065 -411.774973) (xy 419.897325 -411.824897) (xy 419.927894 -411.879176)
			(xy 419.951272 -411.936919) (xy 419.967073 -411.997177) (xy 419.975039 -412.05896) (xy 419.975538 -412.090108)
			(xy 423.403784 -412.090108) (xy 423.407775 -412.027941) (xy 423.419684 -411.966794) (xy 423.439313 -411.907673)
			(xy 423.466342 -411.851547) (xy 423.500326 -411.799338) (xy 423.540708 -411.751903) (xy 423.586824 -411.710022)
			(xy 423.637916 -411.674382) (xy 423.693147 -411.645568) (xy 423.751609 -411.624054) (xy 423.812343 -411.610192)
			(xy 423.87435 -411.60421) (xy 423.936613 -411.606206) (xy 423.99811 -411.616149) (xy 424.057831 -411.633873)
			(xy 424.114794 -411.65909) (xy 424.168065 -411.691383) (xy 424.21677 -411.730223) (xy 424.260107 -411.774973)
			(xy 424.297367 -411.824897) (xy 424.327936 -411.879176) (xy 424.351314 -411.936919) (xy 424.367115 -411.997177)
			(xy 424.375081 -412.05896) (xy 424.37558 -412.090108) (xy 427.803826 -412.090108) (xy 427.807817 -412.027941)
			(xy 427.819726 -411.966794) (xy 427.839355 -411.907673) (xy 427.866384 -411.851547) (xy 427.900368 -411.799338)
			(xy 427.94075 -411.751903) (xy 427.986866 -411.710022) (xy 428.037958 -411.674382) (xy 428.093189 -411.645568)
			(xy 428.151651 -411.624054) (xy 428.212385 -411.610192) (xy 428.274392 -411.60421) (xy 428.336655 -411.606206)
			(xy 428.398152 -411.616149) (xy 428.457873 -411.633873) (xy 428.514836 -411.65909) (xy 428.568107 -411.691383)
			(xy 428.616812 -411.730223) (xy 428.660149 -411.774973) (xy 428.697409 -411.824897) (xy 428.727978 -411.879176)
			(xy 428.751356 -411.936919) (xy 428.767157 -411.997177) (xy 428.775123 -412.05896) (xy 428.775622 -412.090108)
			(xy 432.203614 -412.090108) (xy 432.207605 -412.027941) (xy 432.219514 -411.966794) (xy 432.239143 -411.907673)
			(xy 432.266172 -411.851547) (xy 432.300156 -411.799338) (xy 432.340538 -411.751903) (xy 432.386654 -411.710022)
			(xy 432.437746 -411.674382) (xy 432.492977 -411.645568) (xy 432.551439 -411.624054) (xy 432.612173 -411.610192)
			(xy 432.67418 -411.60421) (xy 432.736443 -411.606206) (xy 432.79794 -411.616149) (xy 432.857661 -411.633873)
			(xy 432.914624 -411.65909) (xy 432.967895 -411.691383) (xy 433.0166 -411.730223) (xy 433.059937 -411.774973)
			(xy 433.097197 -411.824897) (xy 433.127766 -411.879176) (xy 433.151144 -411.936919) (xy 433.166945 -411.997177)
			(xy 433.174911 -412.05896) (xy 433.17541 -412.090108) (xy 436.603656 -412.090108) (xy 436.607647 -412.027941)
			(xy 436.619556 -411.966794) (xy 436.639185 -411.907673) (xy 436.666214 -411.851547) (xy 436.700198 -411.799338)
			(xy 436.74058 -411.751903) (xy 436.786696 -411.710022) (xy 436.837788 -411.674382) (xy 436.893019 -411.645568)
			(xy 436.951481 -411.624054) (xy 437.012215 -411.610192) (xy 437.074222 -411.60421) (xy 437.136485 -411.606206)
			(xy 437.197982 -411.616149) (xy 437.257703 -411.633873) (xy 437.314666 -411.65909) (xy 437.367937 -411.691383)
			(xy 437.416642 -411.730223) (xy 437.459979 -411.774973) (xy 437.497239 -411.824897) (xy 437.527808 -411.879176)
			(xy 437.536286 -411.900116) (xy 444.291972 -411.900116) (xy 444.296043 -411.844494) (xy 444.308169 -411.790057)
			(xy 444.328092 -411.737966) (xy 444.355388 -411.689331) (xy 444.389474 -411.645188) (xy 444.429623 -411.606479)
			(xy 444.474981 -411.574028) (xy 444.524581 -411.548527) (xy 444.577365 -411.53052) (xy 444.632208 -411.52039)
			(xy 444.687942 -411.518353) (xy 444.743379 -411.524453) (xy 444.797336 -411.538559) (xy 444.848665 -411.560371)
			(xy 444.896271 -411.589425) (xy 444.939139 -411.6251) (xy 444.976356 -411.666637) (xy 445.007129 -411.71315)
			(xy 445.030801 -411.763647) (xy 445.046869 -411.817054) (xy 445.054989 -411.87223) (xy 445.055498 -411.900116)
			(xy 445.054989 -411.928002) (xy 445.046869 -411.983178) (xy 445.030801 -412.036585) (xy 445.007129 -412.087082)
			(xy 444.976356 -412.133595) (xy 444.939139 -412.175132) (xy 444.896271 -412.210807) (xy 444.848665 -412.239861)
			(xy 444.797336 -412.261673) (xy 444.743379 -412.275779) (xy 444.687942 -412.281879) (xy 444.632208 -412.279842)
			(xy 444.577365 -412.269712) (xy 444.524581 -412.251705) (xy 444.474981 -412.226204) (xy 444.429623 -412.193753)
			(xy 444.389474 -412.155044) (xy 444.355388 -412.110901) (xy 444.328092 -412.062266) (xy 444.308169 -412.010175)
			(xy 444.296043 -411.955738) (xy 444.291972 -411.900116) (xy 437.536286 -411.900116) (xy 437.551186 -411.936919)
			(xy 437.566987 -411.997177) (xy 437.574953 -412.05896) (xy 437.575452 -412.090108) (xy 437.574953 -412.121256)
			(xy 437.566987 -412.183039) (xy 437.551186 -412.243297) (xy 437.527808 -412.30104) (xy 437.497239 -412.355319)
			(xy 437.459979 -412.405243) (xy 437.416642 -412.449993) (xy 437.367937 -412.488833) (xy 437.314666 -412.521126)
			(xy 437.257703 -412.546343) (xy 437.197982 -412.564067) (xy 437.136485 -412.57401) (xy 437.074222 -412.576006)
			(xy 437.012215 -412.570024) (xy 436.951481 -412.556162) (xy 436.893019 -412.534648) (xy 436.837788 -412.505834)
			(xy 436.786696 -412.470194) (xy 436.74058 -412.428313) (xy 436.700198 -412.380878) (xy 436.666214 -412.328669)
			(xy 436.639185 -412.272543) (xy 436.619556 -412.213422) (xy 436.607647 -412.152275) (xy 436.603656 -412.090108)
			(xy 433.17541 -412.090108) (xy 433.174911 -412.121256) (xy 433.166945 -412.183039) (xy 433.151144 -412.243297)
			(xy 433.127766 -412.30104) (xy 433.097197 -412.355319) (xy 433.059937 -412.405243) (xy 433.0166 -412.449993)
			(xy 432.967895 -412.488833) (xy 432.914624 -412.521126) (xy 432.857661 -412.546343) (xy 432.79794 -412.564067)
			(xy 432.736443 -412.57401) (xy 432.67418 -412.576006) (xy 432.612173 -412.570024) (xy 432.551439 -412.556162)
			(xy 432.492977 -412.534648) (xy 432.437746 -412.505834) (xy 432.386654 -412.470194) (xy 432.340538 -412.428313)
			(xy 432.300156 -412.380878) (xy 432.266172 -412.328669) (xy 432.239143 -412.272543) (xy 432.219514 -412.213422)
			(xy 432.207605 -412.152275) (xy 432.203614 -412.090108) (xy 428.775622 -412.090108) (xy 428.775123 -412.121256)
			(xy 428.767157 -412.183039) (xy 428.751356 -412.243297) (xy 428.727978 -412.30104) (xy 428.697409 -412.355319)
			(xy 428.660149 -412.405243) (xy 428.616812 -412.449993) (xy 428.568107 -412.488833) (xy 428.514836 -412.521126)
			(xy 428.457873 -412.546343) (xy 428.398152 -412.564067) (xy 428.336655 -412.57401) (xy 428.274392 -412.576006)
			(xy 428.212385 -412.570024) (xy 428.151651 -412.556162) (xy 428.093189 -412.534648) (xy 428.037958 -412.505834)
			(xy 427.986866 -412.470194) (xy 427.94075 -412.428313) (xy 427.900368 -412.380878) (xy 427.866384 -412.328669)
			(xy 427.839355 -412.272543) (xy 427.819726 -412.213422) (xy 427.807817 -412.152275) (xy 427.803826 -412.090108)
			(xy 424.37558 -412.090108) (xy 424.375081 -412.121256) (xy 424.367115 -412.183039) (xy 424.351314 -412.243297)
			(xy 424.327936 -412.30104) (xy 424.297367 -412.355319) (xy 424.260107 -412.405243) (xy 424.21677 -412.449993)
			(xy 424.168065 -412.488833) (xy 424.114794 -412.521126) (xy 424.057831 -412.546343) (xy 423.99811 -412.564067)
			(xy 423.936613 -412.57401) (xy 423.87435 -412.576006) (xy 423.812343 -412.570024) (xy 423.751609 -412.556162)
			(xy 423.693147 -412.534648) (xy 423.637916 -412.505834) (xy 423.586824 -412.470194) (xy 423.540708 -412.428313)
			(xy 423.500326 -412.380878) (xy 423.466342 -412.328669) (xy 423.439313 -412.272543) (xy 423.419684 -412.213422)
			(xy 423.407775 -412.152275) (xy 423.403784 -412.090108) (xy 419.975538 -412.090108) (xy 419.975039 -412.121256)
			(xy 419.967073 -412.183039) (xy 419.951272 -412.243297) (xy 419.927894 -412.30104) (xy 419.897325 -412.355319)
			(xy 419.860065 -412.405243) (xy 419.816728 -412.449993) (xy 419.768023 -412.488833) (xy 419.714752 -412.521126)
			(xy 419.657789 -412.546343) (xy 419.598068 -412.564067) (xy 419.536571 -412.57401) (xy 419.474308 -412.576006)
			(xy 419.412301 -412.570024) (xy 419.351567 -412.556162) (xy 419.293105 -412.534648) (xy 419.237874 -412.505834)
			(xy 419.186782 -412.470194) (xy 419.140666 -412.428313) (xy 419.100284 -412.380878) (xy 419.0663 -412.328669)
			(xy 419.039271 -412.272543) (xy 419.019642 -412.213422) (xy 419.007733 -412.152275) (xy 419.003742 -412.090108)
			(xy 414.525968 -412.090108) (xy 414.525968 -414.403794) (xy 447.176396 -414.403794) (xy 447.180467 -414.348172)
			(xy 447.192593 -414.293735) (xy 447.212516 -414.241644) (xy 447.239812 -414.193009) (xy 447.273898 -414.148866)
			(xy 447.314047 -414.110157) (xy 447.359405 -414.077706) (xy 447.409005 -414.052205) (xy 447.461789 -414.034198)
			(xy 447.516632 -414.024068) (xy 447.572366 -414.022031) (xy 447.627803 -414.028131) (xy 447.68176 -414.042237)
			(xy 447.733089 -414.064049) (xy 447.780695 -414.093103) (xy 447.823563 -414.128778) (xy 447.86078 -414.170315)
			(xy 447.891553 -414.216828) (xy 447.915225 -414.267325) (xy 447.931293 -414.320732) (xy 447.939413 -414.375908)
			(xy 447.939922 -414.403794) (xy 447.939413 -414.43168) (xy 447.931293 -414.486856) (xy 447.915225 -414.540263)
			(xy 447.891801 -414.59023) (xy 448.79717 -414.59023) (xy 448.801241 -414.534608) (xy 448.813367 -414.480171)
			(xy 448.83329 -414.42808) (xy 448.860586 -414.379445) (xy 448.894672 -414.335302) (xy 448.934821 -414.296593)
			(xy 448.980179 -414.264142) (xy 449.029779 -414.238641) (xy 449.082563 -414.220634) (xy 449.137406 -414.210504)
			(xy 449.19314 -414.208467) (xy 449.248577 -414.214567) (xy 449.302534 -414.228673) (xy 449.353863 -414.250485)
			(xy 449.401469 -414.279539) (xy 449.444337 -414.315214) (xy 449.461574 -414.334452) (xy 450.168262 -414.334452)
			(xy 450.172333 -414.27883) (xy 450.184459 -414.224393) (xy 450.204382 -414.172302) (xy 450.231678 -414.123667)
			(xy 450.265764 -414.079524) (xy 450.305913 -414.040815) (xy 450.351271 -414.008364) (xy 450.400871 -413.982863)
			(xy 450.453655 -413.964856) (xy 450.508498 -413.954726) (xy 450.564232 -413.952689) (xy 450.619669 -413.958789)
			(xy 450.673626 -413.972895) (xy 450.724955 -413.994707) (xy 450.772561 -414.023761) (xy 450.815429 -414.059436)
			(xy 450.852646 -414.100973) (xy 450.883419 -414.147486) (xy 450.907091 -414.197983) (xy 450.923159 -414.25139)
			(xy 450.931279 -414.306566) (xy 450.931788 -414.334452) (xy 450.931279 -414.362338) (xy 450.923159 -414.417514)
			(xy 450.907091 -414.470921) (xy 450.883419 -414.521418) (xy 450.852646 -414.567931) (xy 450.815429 -414.609468)
			(xy 450.772561 -414.645143) (xy 450.724955 -414.674197) (xy 450.673626 -414.696009) (xy 450.619669 -414.710115)
			(xy 450.564232 -414.716215) (xy 450.508498 -414.714178) (xy 450.453655 -414.704048) (xy 450.400871 -414.686041)
			(xy 450.351271 -414.66054) (xy 450.305913 -414.628089) (xy 450.265764 -414.58938) (xy 450.231678 -414.545237)
			(xy 450.204382 -414.496602) (xy 450.184459 -414.444511) (xy 450.172333 -414.390074) (xy 450.168262 -414.334452)
			(xy 449.461574 -414.334452) (xy 449.481554 -414.356751) (xy 449.512327 -414.403264) (xy 449.535999 -414.453761)
			(xy 449.552067 -414.507168) (xy 449.560187 -414.562344) (xy 449.560696 -414.59023) (xy 449.560187 -414.618116)
			(xy 449.552067 -414.673292) (xy 449.535999 -414.726699) (xy 449.512327 -414.777196) (xy 449.481554 -414.823709)
			(xy 449.444337 -414.865246) (xy 449.401469 -414.900921) (xy 449.353863 -414.929975) (xy 449.302534 -414.951787)
			(xy 449.248577 -414.965893) (xy 449.19314 -414.971993) (xy 449.137406 -414.969956) (xy 449.082563 -414.959826)
			(xy 449.029779 -414.941819) (xy 448.980179 -414.916318) (xy 448.934821 -414.883867) (xy 448.894672 -414.845158)
			(xy 448.860586 -414.801015) (xy 448.83329 -414.75238) (xy 448.813367 -414.700289) (xy 448.801241 -414.645852)
			(xy 448.79717 -414.59023) (xy 447.891801 -414.59023) (xy 447.891553 -414.59076) (xy 447.86078 -414.637273)
			(xy 447.823563 -414.67881) (xy 447.780695 -414.714485) (xy 447.733089 -414.743539) (xy 447.68176 -414.765351)
			(xy 447.627803 -414.779457) (xy 447.572366 -414.785557) (xy 447.516632 -414.78352) (xy 447.461789 -414.77339)
			(xy 447.409005 -414.755383) (xy 447.359405 -414.729882) (xy 447.314047 -414.697431) (xy 447.273898 -414.658722)
			(xy 447.239812 -414.614579) (xy 447.212516 -414.565944) (xy 447.192593 -414.513853) (xy 447.180467 -414.459416)
			(xy 447.176396 -414.403794) (xy 414.525968 -414.403794) (xy 414.525968 -416.569652) (xy 414.527426 -416.578781)
			(xy 414.535942 -416.595172) (xy 414.549747 -416.607445) (xy 414.567023 -416.613982) (xy 414.57626 -416.614356)
			(xy 445.705484 -416.614356) (xy 445.717318 -416.613675) (xy 445.738445 -416.602987) (xy 445.752576 -416.583991)
			(xy 445.755268 -416.572446) (xy 445.755268 -416.572192) (xy 445.760538 -416.544561) (xy 445.778126 -416.491131)
			(xy 445.80337 -416.440864) (xy 445.835722 -416.394848) (xy 445.87448 -416.354083) (xy 445.918805 -416.319451)
			(xy 445.967735 -416.291705) (xy 446.02021 -416.271444) (xy 446.075091 -416.259109) (xy 446.131188 -416.254968)
			(xy 446.187285 -416.259109) (xy 446.242166 -416.271444) (xy 446.294641 -416.291705) (xy 446.343571 -416.319451)
			(xy 446.387896 -416.354083) (xy 446.426654 -416.394848) (xy 446.459006 -416.440864) (xy 446.48425 -416.491131)
			(xy 446.501838 -416.544561) (xy 446.507108 -416.572192) (xy 446.507108 -416.572446) (xy 446.509782 -416.584001)
			(xy 446.523909 -416.603015) (xy 446.545051 -416.6137) (xy 446.556892 -416.614356) (xy 446.721484 -416.614356)
			(xy 446.733318 -416.613675) (xy 446.754445 -416.602987) (xy 446.768576 -416.583991) (xy 446.771268 -416.572446)
			(xy 446.771268 -416.572192) (xy 446.776538 -416.544561) (xy 446.794126 -416.491131) (xy 446.81937 -416.440864)
			(xy 446.851722 -416.394848) (xy 446.89048 -416.354083) (xy 446.934805 -416.319451) (xy 446.983735 -416.291705)
			(xy 447.03621 -416.271444) (xy 447.091091 -416.259109) (xy 447.147188 -416.254968) (xy 447.203285 -416.259109)
			(xy 447.258166 -416.271444) (xy 447.310641 -416.291705) (xy 447.359571 -416.319451) (xy 447.403896 -416.354083)
			(xy 447.442654 -416.394848) (xy 447.475006 -416.440864) (xy 447.50025 -416.491131) (xy 447.517838 -416.544561)
			(xy 447.523108 -416.572192) (xy 447.523108 -416.572446) (xy 447.525782 -416.584001) (xy 447.539909 -416.603015)
			(xy 447.561051 -416.6137) (xy 447.572892 -416.614356) (xy 447.737484 -416.614356) (xy 447.749318 -416.613675)
			(xy 447.770445 -416.602987) (xy 447.784576 -416.583991) (xy 447.787268 -416.572446) (xy 447.787268 -416.572192)
			(xy 447.792538 -416.544561) (xy 447.810126 -416.491131) (xy 447.83537 -416.440864) (xy 447.867722 -416.394848)
			(xy 447.90648 -416.354083) (xy 447.950805 -416.319451) (xy 447.999735 -416.291705) (xy 448.05221 -416.271444)
			(xy 448.107091 -416.259109) (xy 448.163188 -416.254968) (xy 448.219285 -416.259109) (xy 448.274166 -416.271444)
			(xy 448.326641 -416.291705) (xy 448.375571 -416.319451) (xy 448.419896 -416.354083) (xy 448.458654 -416.394848)
			(xy 448.491006 -416.440864) (xy 448.51625 -416.491131) (xy 448.533838 -416.544561) (xy 448.539108 -416.572192)
			(xy 448.539108 -416.572446) (xy 448.541782 -416.584001) (xy 448.555909 -416.603015) (xy 448.577051 -416.6137)
			(xy 448.588892 -416.614356) (xy 448.753484 -416.614356) (xy 448.765318 -416.613675) (xy 448.786445 -416.602987)
			(xy 448.800576 -416.583991) (xy 448.803268 -416.572446) (xy 448.803268 -416.572192) (xy 448.808538 -416.544561)
			(xy 448.826126 -416.491131) (xy 448.85137 -416.440864) (xy 448.883722 -416.394848) (xy 448.92248 -416.354083)
			(xy 448.966805 -416.319451) (xy 449.015735 -416.291705) (xy 449.06821 -416.271444) (xy 449.123091 -416.259109)
			(xy 449.179188 -416.254968) (xy 449.235285 -416.259109) (xy 449.290166 -416.271444) (xy 449.342641 -416.291705)
			(xy 449.391571 -416.319451) (xy 449.435896 -416.354083) (xy 449.474654 -416.394848) (xy 449.507006 -416.440864)
			(xy 449.53225 -416.491131) (xy 449.549838 -416.544561) (xy 449.555108 -416.572192) (xy 449.555108 -416.572446)
			(xy 449.557782 -416.584001) (xy 449.571909 -416.603015) (xy 449.593051 -416.6137) (xy 449.604892 -416.614356)
			(xy 449.769484 -416.614356) (xy 449.781318 -416.613675) (xy 449.802445 -416.602987) (xy 449.816576 -416.583991)
			(xy 449.819268 -416.572446) (xy 449.819268 -416.572192) (xy 449.824538 -416.544561) (xy 449.842126 -416.491131)
			(xy 449.86737 -416.440864) (xy 449.899722 -416.394848) (xy 449.93848 -416.354083) (xy 449.982805 -416.319451)
			(xy 450.031735 -416.291705) (xy 450.08421 -416.271444) (xy 450.139091 -416.259109) (xy 450.195188 -416.254968)
			(xy 450.251285 -416.259109) (xy 450.306166 -416.271444) (xy 450.358641 -416.291705) (xy 450.407571 -416.319451)
			(xy 450.451896 -416.354083) (xy 450.490654 -416.394848) (xy 450.523006 -416.440864) (xy 450.54825 -416.491131)
			(xy 450.565838 -416.544561) (xy 450.571108 -416.572192) (xy 450.571108 -416.572446) (xy 450.573782 -416.584001)
			(xy 450.587909 -416.603015) (xy 450.609051 -416.6137) (xy 450.620892 -416.614356) (xy 450.785484 -416.614356)
			(xy 450.797318 -416.613675) (xy 450.818445 -416.602987) (xy 450.832576 -416.583991) (xy 450.835268 -416.572446)
			(xy 450.835268 -416.572192) (xy 450.840538 -416.544561) (xy 450.858126 -416.491131) (xy 450.88337 -416.440864)
			(xy 450.915722 -416.394848) (xy 450.95448 -416.354083) (xy 450.998805 -416.319451) (xy 451.047735 -416.291705)
			(xy 451.10021 -416.271444) (xy 451.155091 -416.259109) (xy 451.211188 -416.254968) (xy 451.267285 -416.259109)
			(xy 451.322166 -416.271444) (xy 451.374641 -416.291705) (xy 451.423571 -416.319451) (xy 451.467896 -416.354083)
			(xy 451.506654 -416.394848) (xy 451.539006 -416.440864) (xy 451.56425 -416.491131) (xy 451.581838 -416.544561)
			(xy 451.587108 -416.572192) (xy 451.587108 -416.572446) (xy 451.589782 -416.584001) (xy 451.603909 -416.603015)
			(xy 451.625051 -416.6137) (xy 451.636892 -416.614356) (xy 464.263486 -416.614356) (xy 464.273138 -416.61334)
			(xy 464.280382 -416.611713) (xy 464.293552 -416.604872) (xy 464.299046 -416.599878) (xy 466.198712 -414.700212)
			(xy 466.203703 -414.694715) (xy 466.210555 -414.68155) (xy 466.212174 -414.674304) (xy 466.21319 -414.664652)
			(xy 466.21319 -410.749496) (xy 466.213016 -410.743488) (xy 466.210181 -410.731812) (xy 466.207602 -410.726382)
			(xy 466.205762 -410.722908) (xy 466.201169 -410.716529) (xy 466.198458 -410.713682) (xy 466.171026 -410.68625)
			(xy 466.164185 -410.67885) (xy 466.156465 -410.660252) (xy 466.15604 -410.650182) (xy 466.15604 -324.714362)
			(xy 466.155874 -324.708352) (xy 466.153055 -324.696667) (xy 466.150452 -324.691248) (xy 466.148609 -324.687776)
			(xy 466.144009 -324.681403) (xy 466.141308 -324.678548) (xy 463.577178 -322.114418) (xy 463.573448 -322.110895)
			(xy 463.564875 -322.105264) (xy 463.56016 -322.103242) (xy 463.551524 -322.099686) (xy 445.629792 -322.099686)
			(xy 445.623781 -322.099848) (xy 445.612094 -322.102663) (xy 445.606678 -322.105274) (xy 445.603203 -322.107113)
			(xy 445.596823 -322.111705) (xy 445.593978 -322.114418) (xy 441.751212 -325.957184) (xy 441.743815 -325.964034)
			(xy 441.725217 -325.971776) (xy 441.715144 -325.97217) (xy 435.12613 -325.97217) (xy 435.116066 -325.971733)
			(xy 435.097483 -325.963998) (xy 435.090062 -325.957184) (xy 434.952902 -325.820024) (xy 434.946067 -325.812621)
			(xy 434.93836 -325.794023) (xy 434.937916 -325.783956) (xy 434.937916 -325.771256) (xy 434.937434 -325.761292)
			(xy 434.929854 -325.74286) (xy 434.923184 -325.735442) (xy 433.882038 -324.694296) (xy 433.879053 -324.691392)
			(xy 433.872283 -324.686542) (xy 433.868576 -324.684644) (xy 433.855622 -324.678294) (xy 433.851812 -324.677024)
			(xy 433.851558 -324.677024) (xy 433.845809 -324.674953) (xy 433.835412 -324.668535) (xy 433.830984 -324.664324)
			(xy 429.526954 -320.360294) (xy 429.523223 -320.356774) (xy 429.514647 -320.351149) (xy 429.509936 -320.349118)
			(xy 429.5013 -320.345562) (xy 404.976076 -320.345562) (xy 404.970065 -320.345726) (xy 404.958379 -320.348543)
			(xy 404.952962 -320.35115) (xy 404.94949 -320.352992) (xy 404.943116 -320.357591) (xy 404.940262 -320.360294)
			(xy 404.350728 -320.949828) (xy 404.347205 -320.953557) (xy 404.341573 -320.962131) (xy 404.339552 -320.966846)
			(xy 404.335996 -320.975482) (xy 404.335996 -322.076826) (xy 404.337012 -322.086478) (xy 404.338642 -322.093721)
			(xy 404.345487 -322.106887) (xy 404.350474 -322.112386) (xy 405.005032 -322.766944) (xy 405.010533 -322.771928)
			(xy 405.023701 -322.778764) (xy 405.03094 -322.780406) (xy 405.040592 -322.781422) (xy 425.460668 -322.781422)
			(xy 425.470732 -322.781858) (xy 425.489317 -322.789592) (xy 425.496736 -322.796408) (xy 432.417728 -329.7174)
			(xy 432.423227 -329.722387) (xy 432.436394 -329.729231) (xy 432.443636 -329.730862) (xy 432.453288 -329.731878)
			(xy 443.419484 -329.731878) (xy 443.429534 -329.732384) (xy 443.448093 -329.740107) (xy 443.455552 -329.746864)
			(xy 443.589664 -329.880976) (xy 459.363064 -329.880976) (xy 459.363527 -329.854662) (xy 459.370764 -329.802534)
			(xy 459.385085 -329.751891) (xy 459.406218 -329.703693) (xy 459.433765 -329.658849) (xy 459.467203 -329.618209)
			(xy 459.486254 -329.600052) (xy 459.493672 -329.592544) (xy 459.502188 -329.573254) (xy 459.502764 -329.562714)
			(xy 459.502764 -329.488038) (xy 459.502238 -329.477488) (xy 459.493702 -329.458192) (xy 459.486254 -329.4507)
			(xy 459.467197 -329.432546) (xy 459.433741 -329.391915) (xy 459.406184 -329.347074) (xy 459.385046 -329.298873)
			(xy 459.370729 -329.248226) (xy 459.363503 -329.196092) (xy 459.363064 -329.169776) (xy 459.363555 -329.142525)
			(xy 459.371314 -329.088579) (xy 459.386671 -329.036286) (xy 459.409313 -328.986711) (xy 459.438779 -328.940862)
			(xy 459.47447 -328.899673) (xy 459.515659 -328.863982) (xy 459.561507 -328.834515) (xy 459.611083 -328.811873)
			(xy 459.663375 -328.796515) (xy 459.717321 -328.788756) (xy 459.744572 -328.788268) (xy 459.770887 -328.788698)
			(xy 459.823017 -328.795942) (xy 459.87366 -328.810269) (xy 459.921858 -328.831408) (xy 459.966701 -328.858961)
			(xy 460.00734 -328.892404) (xy 460.025496 -328.911458) (xy 460.033023 -328.918853) (xy 460.052299 -328.927383)
			(xy 460.062834 -328.927968) (xy 460.13751 -328.927968) (xy 460.148063 -328.927467) (xy 460.167359 -328.918913)
			(xy 460.174848 -328.911458) (xy 460.194668 -328.89067) (xy 460.23944 -328.854695) (xy 460.289098 -328.825835)
			(xy 460.34252 -328.804742) (xy 460.398499 -328.791893) (xy 460.455772 -328.787578) (xy 460.513045 -328.791893)
			(xy 460.569024 -328.804742) (xy 460.622446 -328.825835) (xy 460.672104 -328.854695) (xy 460.716876 -328.89067)
			(xy 460.736696 -328.911458) (xy 460.744223 -328.918853) (xy 460.763499 -328.927383) (xy 460.774034 -328.927968)
			(xy 460.84871 -328.927968) (xy 460.859263 -328.927467) (xy 460.878559 -328.918913) (xy 460.886048 -328.911458)
			(xy 460.904179 -328.892378) (xy 460.944815 -328.858925) (xy 460.989661 -328.83137) (xy 461.037866 -328.810236)
			(xy 461.088517 -328.795924) (xy 461.140655 -328.788704) (xy 461.166972 -328.788268) (xy 461.194223 -328.788781)
			(xy 461.248171 -328.796534) (xy 461.300466 -328.811885) (xy 461.350045 -328.834523) (xy 461.395897 -328.863985)
			(xy 461.437089 -328.899674) (xy 461.472783 -328.940861) (xy 461.502252 -328.986709) (xy 461.524897 -329.036285)
			(xy 461.540255 -329.088578) (xy 461.548015 -329.142525) (xy 461.54848 -329.169776) (xy 461.548003 -329.19609)
			(xy 461.540771 -329.248218) (xy 461.526454 -329.298861) (xy 461.505324 -329.34706) (xy 461.477779 -329.391904)
			(xy 461.444341 -329.432543) (xy 461.42529 -329.4507) (xy 461.417885 -329.458218) (xy 461.409363 -329.477501)
			(xy 461.40878 -329.488038) (xy 461.40878 -329.562714) (xy 461.409294 -329.573265) (xy 461.41784 -329.59256)
			(xy 461.42529 -329.600052) (xy 461.444362 -329.618191) (xy 461.477818 -329.658824) (xy 461.505375 -329.703668)
			(xy 461.526511 -329.751872) (xy 461.540824 -329.802522) (xy 461.548044 -329.854659) (xy 461.54848 -329.880976)
			(xy 461.548022 -329.90823) (xy 461.540268 -329.962182) (xy 461.524913 -330.014482) (xy 461.502272 -330.064064)
			(xy 461.472804 -330.109918) (xy 461.437109 -330.151112) (xy 461.395915 -330.186806) (xy 461.35006 -330.216274)
			(xy 461.300478 -330.238915) (xy 461.248178 -330.254269) (xy 461.194226 -330.262023) (xy 461.166972 -330.262484)
			(xy 461.140657 -330.26204) (xy 461.088527 -330.254801) (xy 461.037884 -330.240478) (xy 460.989685 -330.219341)
			(xy 460.944842 -330.191791) (xy 460.904204 -330.158348) (xy 460.886048 -330.139294) (xy 460.878548 -330.131867)
			(xy 460.859252 -330.123357) (xy 460.84871 -330.122784) (xy 460.774034 -330.122784) (xy 460.763486 -330.123323)
			(xy 460.74419 -330.131852) (xy 460.736696 -330.139294) (xy 460.716876 -330.160082) (xy 460.672104 -330.196057)
			(xy 460.622446 -330.224917) (xy 460.569024 -330.24601) (xy 460.513045 -330.258859) (xy 460.455772 -330.263174)
			(xy 460.398499 -330.258859) (xy 460.34252 -330.24601) (xy 460.289098 -330.224917) (xy 460.23944 -330.196057)
			(xy 460.194668 -330.160082) (xy 460.174848 -330.139294) (xy 460.167348 -330.131867) (xy 460.148052 -330.123357)
			(xy 460.13751 -330.122784) (xy 460.062834 -330.122784) (xy 460.052286 -330.123323) (xy 460.03299 -330.131852)
			(xy 460.025496 -330.139294) (xy 460.007334 -330.158343) (xy 459.966706 -330.191801) (xy 459.921867 -330.219361)
			(xy 459.873667 -330.240501) (xy 459.823021 -330.254819) (xy 459.770888 -330.262045) (xy 459.744572 -330.262484)
			(xy 459.717319 -330.262048) (xy 459.663368 -330.254287) (xy 459.611071 -330.238927) (xy 459.561492 -330.216281)
			(xy 459.515641 -330.18681) (xy 459.47445 -330.151113) (xy 459.438759 -330.109918) (xy 459.409294 -330.064062)
			(xy 459.386654 -330.01448) (xy 459.371302 -329.962181) (xy 459.363548 -329.908229) (xy 459.363064 -329.880976)
			(xy 443.589664 -329.880976) (xy 448.519042 -334.810354) (xy 448.525886 -334.817753) (xy 448.53361 -334.836351)
			(xy 448.534028 -334.846422) (xy 448.534028 -362.087922) (xy 448.533602 -362.097991) (xy 448.525885 -362.116592)
			(xy 448.519042 -362.12399) (xy 447.837306 -362.805726) (xy 449.753734 -362.805726) (xy 449.757805 -362.750104)
			(xy 449.769931 -362.695667) (xy 449.789854 -362.643576) (xy 449.81715 -362.594941) (xy 449.851236 -362.550798)
			(xy 449.891385 -362.512089) (xy 449.936743 -362.479638) (xy 449.986343 -362.454137) (xy 450.039127 -362.43613)
			(xy 450.09397 -362.426) (xy 450.149704 -362.423963) (xy 450.205141 -362.430063) (xy 450.259098 -362.444169)
			(xy 450.310427 -362.465981) (xy 450.358033 -362.495035) (xy 450.400901 -362.53071) (xy 450.438118 -362.572247)
			(xy 450.468891 -362.61876) (xy 450.492563 -362.669257) (xy 450.508631 -362.722664) (xy 450.516751 -362.77784)
			(xy 450.51726 -362.805726) (xy 450.516751 -362.833612) (xy 450.508631 -362.888788) (xy 450.492563 -362.942195)
			(xy 450.468891 -362.992692) (xy 450.438118 -363.039205) (xy 450.400901 -363.080742) (xy 450.358033 -363.116417)
			(xy 450.310427 -363.145471) (xy 450.259098 -363.167283) (xy 450.205141 -363.181389) (xy 450.149704 -363.187489)
			(xy 450.09397 -363.185452) (xy 450.039127 -363.175322) (xy 449.986343 -363.157315) (xy 449.936743 -363.131814)
			(xy 449.891385 -363.099363) (xy 449.851236 -363.060654) (xy 449.81715 -363.016511) (xy 449.789854 -362.967876)
			(xy 449.769931 -362.915785) (xy 449.757805 -362.861348) (xy 449.753734 -362.805726) (xy 447.837306 -362.805726)
			(xy 446.756536 -363.886496) (xy 459.91729 -363.886496) (xy 459.921361 -363.830874) (xy 459.933487 -363.776437)
			(xy 459.95341 -363.724346) (xy 459.980706 -363.675711) (xy 460.014792 -363.631568) (xy 460.054941 -363.592859)
			(xy 460.100299 -363.560408) (xy 460.149899 -363.534907) (xy 460.202683 -363.5169) (xy 460.257526 -363.50677)
			(xy 460.31326 -363.504733) (xy 460.368697 -363.510833) (xy 460.422654 -363.524939) (xy 460.473983 -363.546751)
			(xy 460.521589 -363.575805) (xy 460.564457 -363.61148) (xy 460.601674 -363.653017) (xy 460.632447 -363.69953)
			(xy 460.656119 -363.750027) (xy 460.672187 -363.803434) (xy 460.680307 -363.85861) (xy 460.680816 -363.886496)
			(xy 460.680307 -363.914382) (xy 460.672187 -363.969558) (xy 460.656119 -364.022965) (xy 460.632447 -364.073462)
			(xy 460.601674 -364.119975) (xy 460.564457 -364.161512) (xy 460.521589 -364.197187) (xy 460.473983 -364.226241)
			(xy 460.422654 -364.248053) (xy 460.368697 -364.262159) (xy 460.31326 -364.268259) (xy 460.257526 -364.266222)
			(xy 460.202683 -364.256092) (xy 460.149899 -364.238085) (xy 460.100299 -364.212584) (xy 460.054941 -364.180133)
			(xy 460.014792 -364.141424) (xy 459.980706 -364.097281) (xy 459.95341 -364.048646) (xy 459.933487 -363.996555)
			(xy 459.921361 -363.942118) (xy 459.91729 -363.886496) (xy 446.756536 -363.886496) (xy 446.563242 -364.07979)
			(xy 446.555841 -364.086629) (xy 446.537243 -364.094343) (xy 446.527174 -364.094776) (xy 442.281818 -364.094776)
			(xy 442.275809 -364.094947) (xy 442.26413 -364.097776) (xy 442.258704 -364.100364) (xy 442.255228 -364.102201)
			(xy 442.248845 -364.10679) (xy 442.246004 -364.109508) (xy 441.853828 -364.501684) (xy 457.804772 -364.501684)
			(xy 457.808843 -364.446062) (xy 457.820969 -364.391625) (xy 457.840892 -364.339534) (xy 457.868188 -364.290899)
			(xy 457.902274 -364.246756) (xy 457.942423 -364.208047) (xy 457.987781 -364.175596) (xy 458.037381 -364.150095)
			(xy 458.090165 -364.132088) (xy 458.145008 -364.121958) (xy 458.200742 -364.119921) (xy 458.256179 -364.126021)
			(xy 458.310136 -364.140127) (xy 458.361465 -364.161939) (xy 458.409071 -364.190993) (xy 458.451939 -364.226668)
			(xy 458.489156 -364.268205) (xy 458.519929 -364.314718) (xy 458.543601 -364.365215) (xy 458.559669 -364.418622)
			(xy 458.567789 -364.473798) (xy 458.568298 -364.501684) (xy 458.567789 -364.52957) (xy 458.559669 -364.584746)
			(xy 458.543601 -364.638153) (xy 458.519929 -364.68865) (xy 458.489156 -364.735163) (xy 458.451939 -364.7767)
			(xy 458.409071 -364.812375) (xy 458.361465 -364.841429) (xy 458.310136 -364.863241) (xy 458.256179 -364.877347)
			(xy 458.200742 -364.883447) (xy 458.145008 -364.88141) (xy 458.090165 -364.87128) (xy 458.037381 -364.853273)
			(xy 457.987781 -364.827772) (xy 457.942423 -364.795321) (xy 457.902274 -364.756612) (xy 457.868188 -364.712469)
			(xy 457.840892 -364.663834) (xy 457.820969 -364.611743) (xy 457.808843 -364.557306) (xy 457.804772 -364.501684)
			(xy 441.853828 -364.501684) (xy 441.078366 -365.277146) (xy 451.28764 -365.277146) (xy 451.291711 -365.221524)
			(xy 451.303837 -365.167087) (xy 451.32376 -365.114996) (xy 451.351056 -365.066361) (xy 451.385142 -365.022218)
			(xy 451.425291 -364.983509) (xy 451.470649 -364.951058) (xy 451.520249 -364.925557) (xy 451.573033 -364.90755)
			(xy 451.627876 -364.89742) (xy 451.68361 -364.895383) (xy 451.739047 -364.901483) (xy 451.793004 -364.915589)
			(xy 451.844333 -364.937401) (xy 451.891939 -364.966455) (xy 451.934807 -365.00213) (xy 451.972024 -365.043667)
			(xy 452.002797 -365.09018) (xy 452.025073 -365.1377) (xy 452.545194 -365.1377) (xy 452.549265 -365.082078)
			(xy 452.561391 -365.027641) (xy 452.581314 -364.97555) (xy 452.60861 -364.926915) (xy 452.642696 -364.882772)
			(xy 452.682845 -364.844063) (xy 452.728203 -364.811612) (xy 452.777803 -364.786111) (xy 452.830587 -364.768104)
			(xy 452.88543 -364.757974) (xy 452.941164 -364.755937) (xy 452.996601 -364.762037) (xy 453.050558 -364.776143)
			(xy 453.101887 -364.797955) (xy 453.149493 -364.827009) (xy 453.192361 -364.862684) (xy 453.229578 -364.904221)
			(xy 453.260351 -364.950734) (xy 453.284023 -365.001231) (xy 453.300091 -365.054638) (xy 453.308211 -365.109814)
			(xy 453.30872 -365.1377) (xy 453.308211 -365.165586) (xy 453.304278 -365.19231) (xy 453.705212 -365.19231)
			(xy 453.709283 -365.136688) (xy 453.721409 -365.082251) (xy 453.741332 -365.03016) (xy 453.768628 -364.981525)
			(xy 453.802714 -364.937382) (xy 453.842863 -364.898673) (xy 453.888221 -364.866222) (xy 453.937821 -364.840721)
			(xy 453.990605 -364.822714) (xy 454.045448 -364.812584) (xy 454.101182 -364.810547) (xy 454.156619 -364.816647)
			(xy 454.210576 -364.830753) (xy 454.261905 -364.852565) (xy 454.309511 -364.881619) (xy 454.352379 -364.917294)
			(xy 454.389596 -364.958831) (xy 454.420369 -365.005344) (xy 454.444041 -365.055841) (xy 454.460109 -365.109248)
			(xy 454.468229 -365.164424) (xy 454.468738 -365.19231) (xy 454.468229 -365.220196) (xy 454.460109 -365.275372)
			(xy 454.444041 -365.328779) (xy 454.420369 -365.379276) (xy 454.389596 -365.425789) (xy 454.352379 -365.467326)
			(xy 454.309511 -365.503001) (xy 454.261905 -365.532055) (xy 454.210576 -365.553867) (xy 454.156619 -365.567973)
			(xy 454.101182 -365.574073) (xy 454.045448 -365.572036) (xy 453.990605 -365.561906) (xy 453.937821 -365.543899)
			(xy 453.888221 -365.518398) (xy 453.842863 -365.485947) (xy 453.802714 -365.447238) (xy 453.768628 -365.403095)
			(xy 453.741332 -365.35446) (xy 453.721409 -365.302369) (xy 453.709283 -365.247932) (xy 453.705212 -365.19231)
			(xy 453.304278 -365.19231) (xy 453.300091 -365.220762) (xy 453.284023 -365.274169) (xy 453.260351 -365.324666)
			(xy 453.229578 -365.371179) (xy 453.192361 -365.412716) (xy 453.149493 -365.448391) (xy 453.101887 -365.477445)
			(xy 453.050558 -365.499257) (xy 452.996601 -365.513363) (xy 452.941164 -365.519463) (xy 452.88543 -365.517426)
			(xy 452.830587 -365.507296) (xy 452.777803 -365.489289) (xy 452.728203 -365.463788) (xy 452.682845 -365.431337)
			(xy 452.642696 -365.392628) (xy 452.60861 -365.348485) (xy 452.581314 -365.29985) (xy 452.561391 -365.247759)
			(xy 452.549265 -365.193322) (xy 452.545194 -365.1377) (xy 452.025073 -365.1377) (xy 452.026469 -365.140677)
			(xy 452.042537 -365.194084) (xy 452.050657 -365.24926) (xy 452.051166 -365.277146) (xy 452.050657 -365.305032)
			(xy 452.042537 -365.360208) (xy 452.026469 -365.413615) (xy 452.002797 -365.464112) (xy 451.972024 -365.510625)
			(xy 451.934807 -365.552162) (xy 451.891939 -365.587837) (xy 451.844333 -365.616891) (xy 451.793004 -365.638703)
			(xy 451.739047 -365.652809) (xy 451.68361 -365.658909) (xy 451.627876 -365.656872) (xy 451.573033 -365.646742)
			(xy 451.520249 -365.628735) (xy 451.470649 -365.603234) (xy 451.425291 -365.570783) (xy 451.385142 -365.532074)
			(xy 451.351056 -365.487931) (xy 451.32376 -365.439296) (xy 451.303837 -365.387205) (xy 451.291711 -365.332768)
			(xy 451.28764 -365.277146) (xy 441.078366 -365.277146) (xy 439.651902 -366.70361) (xy 453.285096 -366.70361)
			(xy 453.289167 -366.647988) (xy 453.301293 -366.593551) (xy 453.321216 -366.54146) (xy 453.348512 -366.492825)
			(xy 453.382598 -366.448682) (xy 453.422747 -366.409973) (xy 453.468105 -366.377522) (xy 453.517705 -366.352021)
			(xy 453.570489 -366.334014) (xy 453.625332 -366.323884) (xy 453.681066 -366.321847) (xy 453.736503 -366.327947)
			(xy 453.79046 -366.342053) (xy 453.841789 -366.363865) (xy 453.889395 -366.392919) (xy 453.932263 -366.428594)
			(xy 453.96948 -366.470131) (xy 454.000253 -366.516644) (xy 454.023925 -366.567141) (xy 454.039993 -366.620548)
			(xy 454.048113 -366.675724) (xy 454.048622 -366.70361) (xy 454.048113 -366.731496) (xy 454.039993 -366.786672)
			(xy 454.023925 -366.840079) (xy 454.000253 -366.890576) (xy 453.984807 -366.913922) (xy 455.642978 -366.913922)
			(xy 455.647049 -366.8583) (xy 455.659175 -366.803863) (xy 455.679098 -366.751772) (xy 455.706394 -366.703137)
			(xy 455.74048 -366.658994) (xy 455.780629 -366.620285) (xy 455.825987 -366.587834) (xy 455.875587 -366.562333)
			(xy 455.928371 -366.544326) (xy 455.983214 -366.534196) (xy 456.038948 -366.532159) (xy 456.094385 -366.538259)
			(xy 456.148342 -366.552365) (xy 456.199671 -366.574177) (xy 456.247277 -366.603231) (xy 456.290145 -366.638906)
			(xy 456.327362 -366.680443) (xy 456.358135 -366.726956) (xy 456.381807 -366.777453) (xy 456.397875 -366.83086)
			(xy 456.405995 -366.886036) (xy 456.406504 -366.913922) (xy 458.450694 -366.913922) (xy 458.454765 -366.8583)
			(xy 458.466891 -366.803863) (xy 458.486814 -366.751772) (xy 458.51411 -366.703137) (xy 458.548196 -366.658994)
			(xy 458.588345 -366.620285) (xy 458.633703 -366.587834) (xy 458.683303 -366.562333) (xy 458.736087 -366.544326)
			(xy 458.79093 -366.534196) (xy 458.846664 -366.532159) (xy 458.902101 -366.538259) (xy 458.956058 -366.552365)
			(xy 459.007387 -366.574177) (xy 459.054993 -366.603231) (xy 459.097861 -366.638906) (xy 459.135078 -366.680443)
			(xy 459.165851 -366.726956) (xy 459.189523 -366.777453) (xy 459.205591 -366.83086) (xy 459.213711 -366.886036)
			(xy 459.21422 -366.913922) (xy 459.213711 -366.941808) (xy 459.205591 -366.996984) (xy 459.189523 -367.050391)
			(xy 459.165851 -367.100888) (xy 459.135078 -367.147401) (xy 459.097861 -367.188938) (xy 459.054993 -367.224613)
			(xy 459.007387 -367.253667) (xy 458.956058 -367.275479) (xy 458.902101 -367.289585) (xy 458.846664 -367.295685)
			(xy 458.79093 -367.293648) (xy 458.736087 -367.283518) (xy 458.683303 -367.265511) (xy 458.633703 -367.24001)
			(xy 458.588345 -367.207559) (xy 458.548196 -367.16885) (xy 458.51411 -367.124707) (xy 458.486814 -367.076072)
			(xy 458.466891 -367.023981) (xy 458.454765 -366.969544) (xy 458.450694 -366.913922) (xy 456.406504 -366.913922)
			(xy 456.405995 -366.941808) (xy 456.397875 -366.996984) (xy 456.381807 -367.050391) (xy 456.358135 -367.100888)
			(xy 456.327362 -367.147401) (xy 456.290145 -367.188938) (xy 456.247277 -367.224613) (xy 456.199671 -367.253667)
			(xy 456.148342 -367.275479) (xy 456.094385 -367.289585) (xy 456.038948 -367.295685) (xy 455.983214 -367.293648)
			(xy 455.928371 -367.283518) (xy 455.875587 -367.265511) (xy 455.825987 -367.24001) (xy 455.780629 -367.207559)
			(xy 455.74048 -367.16885) (xy 455.706394 -367.124707) (xy 455.679098 -367.076072) (xy 455.659175 -367.023981)
			(xy 455.647049 -366.969544) (xy 455.642978 -366.913922) (xy 453.984807 -366.913922) (xy 453.96948 -366.937089)
			(xy 453.932263 -366.978626) (xy 453.889395 -367.014301) (xy 453.841789 -367.043355) (xy 453.79046 -367.065167)
			(xy 453.736503 -367.079273) (xy 453.681066 -367.085373) (xy 453.625332 -367.083336) (xy 453.570489 -367.073206)
			(xy 453.517705 -367.055199) (xy 453.468105 -367.029698) (xy 453.422747 -366.997247) (xy 453.382598 -366.958538)
			(xy 453.348512 -366.914395) (xy 453.321216 -366.86576) (xy 453.301293 -366.813669) (xy 453.289167 -366.759232)
			(xy 453.285096 -366.70361) (xy 439.651902 -366.70361) (xy 437.568086 -368.787426) (xy 437.561964 -368.79399)
			(xy 437.554417 -368.810263) (xy 437.553354 -368.819176) (xy 437.553354 -368.81943) (xy 437.552984 -368.828236)
			(xy 437.557545 -368.845246) (xy 437.562244 -368.852704) (xy 437.562498 -368.852958) (xy 437.582818 -368.882374)
			(xy 437.616889 -368.94523) (xy 437.634481 -368.990118) (xy 438.803804 -368.990118) (xy 438.807795 -368.927951)
			(xy 438.819704 -368.866804) (xy 438.839333 -368.807683) (xy 438.866362 -368.751557) (xy 438.900346 -368.699348)
			(xy 438.940728 -368.651913) (xy 438.986844 -368.610032) (xy 439.037936 -368.574392) (xy 439.093167 -368.545578)
			(xy 439.151629 -368.524064) (xy 439.212363 -368.510202) (xy 439.27437 -368.50422) (xy 439.336633 -368.506216)
			(xy 439.39813 -368.516159) (xy 439.457851 -368.533883) (xy 439.514814 -368.5591) (xy 439.568085 -368.591393)
			(xy 439.61679 -368.630233) (xy 439.660127 -368.674983) (xy 439.697387 -368.724907) (xy 439.727956 -368.779186)
			(xy 439.751334 -368.836929) (xy 439.767135 -368.897187) (xy 439.775101 -368.95897) (xy 439.7756 -368.990118)
			(xy 439.775101 -369.021266) (xy 439.767135 -369.083049) (xy 439.751334 -369.143307) (xy 439.727956 -369.20105)
			(xy 439.697387 -369.255329) (xy 439.660127 -369.305253) (xy 439.61679 -369.350003) (xy 439.568085 -369.388843)
			(xy 439.514814 -369.421136) (xy 439.457851 -369.446353) (xy 439.39813 -369.464077) (xy 439.336633 -369.47402)
			(xy 439.27437 -369.476016) (xy 439.212363 -369.470034) (xy 439.151629 -369.456172) (xy 439.093167 -369.434658)
			(xy 439.037936 -369.405844) (xy 438.986844 -369.370204) (xy 438.940728 -369.328323) (xy 438.900346 -369.280888)
			(xy 438.866362 -369.228679) (xy 438.839333 -369.172553) (xy 438.819704 -369.113432) (xy 438.807795 -369.052285)
			(xy 438.803804 -368.990118) (xy 437.634481 -368.990118) (xy 437.642977 -369.011797) (xy 437.660687 -369.081065)
			(xy 437.66975 -369.151984) (xy 437.670448 -369.18773) (xy 437.670448 -369.193572) (xy 437.669711 -369.228522)
			(xy 437.660891 -369.297871) (xy 437.643808 -369.36566) (xy 437.618709 -369.430907) (xy 437.585958 -369.492668)
			(xy 437.546029 -369.550051) (xy 437.499498 -369.602224) (xy 437.44704 -369.648433) (xy 437.389414 -369.688009)
			(xy 437.327452 -369.72038) (xy 437.262052 -369.745077) (xy 437.19416 -369.761743) (xy 437.124758 -369.770137)
			(xy 437.089804 -369.77066) (xy 437.086756 -369.77066) (xy 437.076751 -369.771155) (xy 437.058268 -369.778821)
			(xy 437.044119 -369.792971) (xy 437.036454 -369.811455) (xy 437.035956 -369.82146) (xy 437.035956 -369.932458)
			(xy 437.036391 -369.942522) (xy 437.044127 -369.961106) (xy 437.050942 -369.968526) (xy 437.055768 -369.973352)
			(xy 437.07304 -369.990116) (xy 437.076408 -369.993315) (xy 437.084076 -369.998555) (xy 437.08828 -370.00053)
			(xy 437.096662 -370.004086) (xy 437.106568 -370.004594) (xy 437.137633 -370.006163) (xy 437.199014 -370.01623)
			(xy 437.258608 -370.03405) (xy 437.315439 -370.059334) (xy 437.368577 -370.091666) (xy 437.417151 -370.130518)
			(xy 437.460369 -370.175254) (xy 437.49752 -370.225141) (xy 437.527999 -370.279363) (xy 437.551305 -370.337033)
			(xy 437.567058 -370.397207) (xy 437.575 -370.458899) (xy 437.575 -370.5211) (xy 437.567058 -370.582792)
			(xy 437.551306 -370.642966) (xy 437.527999 -370.700636) (xy 437.497521 -370.754858) (xy 437.460369 -370.804745)
			(xy 437.417152 -370.849481) (xy 437.368577 -370.888333) (xy 437.31544 -370.920666) (xy 437.258609 -370.945949)
			(xy 437.199015 -370.96377) (xy 437.137634 -370.973837) (xy 437.106568 -370.975382) (xy 437.096662 -370.97589)
			(xy 437.08828 -370.979446) (xy 437.084076 -370.981421) (xy 437.07641 -370.986663) (xy 437.07304 -370.98986)
			(xy 437.055768 -371.006624) (xy 437.050942 -371.01145) (xy 437.044099 -371.018849) (xy 437.036376 -371.037448)
			(xy 437.035956 -371.047518) (xy 437.035956 -371.232684) (xy 437.036396 -371.242746) (xy 437.044138 -371.261323)
			(xy 437.050942 -371.268752) (xy 437.055768 -371.273578) (xy 437.07304 -371.290342) (xy 437.076409 -371.29354)
			(xy 437.084078 -371.298777) (xy 437.08828 -371.300756) (xy 437.096662 -371.304312) (xy 437.106568 -371.30482)
			(xy 437.137631 -371.306389) (xy 437.199009 -371.316455) (xy 437.2586 -371.334275) (xy 437.315428 -371.359557)
			(xy 437.368562 -371.391888) (xy 437.417135 -371.430738) (xy 437.460349 -371.475471) (xy 437.497499 -371.525356)
			(xy 437.527976 -371.579576) (xy 437.532214 -371.590062) (xy 438.803804 -371.590062) (xy 438.807795 -371.527895)
			(xy 438.819704 -371.466748) (xy 438.839333 -371.407627) (xy 438.866362 -371.351501) (xy 438.900346 -371.299292)
			(xy 438.940728 -371.251857) (xy 438.986844 -371.209976) (xy 439.037936 -371.174336) (xy 439.093167 -371.145522)
			(xy 439.151629 -371.124008) (xy 439.212363 -371.110146) (xy 439.27437 -371.104164) (xy 439.336633 -371.10616)
			(xy 439.39813 -371.116103) (xy 439.457851 -371.133827) (xy 439.514814 -371.159044) (xy 439.568085 -371.191337)
			(xy 439.61679 -371.230177) (xy 439.660127 -371.274927) (xy 439.697387 -371.324851) (xy 439.727956 -371.37913)
			(xy 439.751334 -371.436873) (xy 439.767135 -371.497131) (xy 439.775101 -371.558914) (xy 439.7756 -371.590062)
			(xy 439.775101 -371.62121) (xy 439.767135 -371.682993) (xy 439.751334 -371.743251) (xy 439.727956 -371.800994)
			(xy 439.697387 -371.855273) (xy 439.694001 -371.85981) (xy 457.532994 -371.85981) (xy 457.53348 -371.832559)
			(xy 457.541236 -371.778611) (xy 457.556591 -371.726316) (xy 457.579233 -371.676739) (xy 457.608699 -371.630889)
			(xy 457.64439 -371.589698) (xy 457.685581 -371.554007) (xy 457.731431 -371.524541) (xy 457.781008 -371.501899)
			(xy 457.833303 -371.486544) (xy 457.887251 -371.478788) (xy 457.941753 -371.478788) (xy 457.995701 -371.486544)
			(xy 458.047996 -371.501899) (xy 458.097573 -371.524541) (xy 458.143423 -371.554007) (xy 458.184614 -371.589698)
			(xy 458.220305 -371.630889) (xy 458.249771 -371.676739) (xy 458.272413 -371.726316) (xy 458.287768 -371.778611)
			(xy 458.295524 -371.832559) (xy 458.29601 -371.85981) (xy 458.29539 -371.890148) (xy 458.285787 -371.950059)
			(xy 458.266823 -372.007696) (xy 458.238976 -372.061604) (xy 458.202949 -372.110427) (xy 458.18171 -372.132098)
			(xy 458.17212 -372.141991) (xy 458.1583 -372.165823) (xy 458.151349 -372.192479) (xy 458.151771 -372.220024)
			(xy 458.159536 -372.246455) (xy 458.174079 -372.269852) (xy 458.194344 -372.288513) (xy 458.218858 -372.301083)
			(xy 458.232256 -372.30431) (xy 458.260571 -372.310664) (xy 458.314998 -372.330791) (xy 458.365747 -372.358932)
			(xy 458.411647 -372.394436) (xy 458.451638 -372.436485) (xy 458.484797 -372.484106) (xy 458.510358 -372.536202)
			(xy 458.527732 -372.591569) (xy 458.536517 -372.648929) (xy 458.537056 -372.677944) (xy 458.53657 -372.705195)
			(xy 458.528814 -372.759143) (xy 458.513459 -372.811438) (xy 458.490817 -372.861015) (xy 458.461351 -372.906865)
			(xy 458.42566 -372.948056) (xy 458.384469 -372.983747) (xy 458.338619 -373.013213) (xy 458.289042 -373.035855)
			(xy 458.236747 -373.05121) (xy 458.182799 -373.058966) (xy 458.128297 -373.058966) (xy 458.074349 -373.05121)
			(xy 458.022054 -373.035855) (xy 457.972477 -373.013213) (xy 457.926627 -372.983747) (xy 457.885436 -372.948056)
			(xy 457.849745 -372.906865) (xy 457.820279 -372.861015) (xy 457.797637 -372.811438) (xy 457.782282 -372.759143)
			(xy 457.774526 -372.705195) (xy 457.77404 -372.677944) (xy 457.774616 -372.647604) (xy 457.784228 -372.58769)
			(xy 457.803202 -372.530053) (xy 457.831058 -372.476145) (xy 457.867095 -372.427325) (xy 457.88834 -372.405656)
			(xy 457.897843 -372.395687) (xy 457.911655 -372.371873) (xy 457.918606 -372.345236) (xy 457.918191 -372.317709)
			(xy 457.910439 -372.291294) (xy 457.895914 -372.267908) (xy 457.875672 -372.24925) (xy 457.851181 -372.236677)
			(xy 457.837794 -372.233444) (xy 457.809476 -372.227098) (xy 457.755046 -372.206974) (xy 457.704294 -372.178835)
			(xy 457.658391 -372.143331) (xy 457.618399 -372.101281) (xy 457.58524 -372.053657) (xy 457.55968 -372.001559)
			(xy 457.54231 -371.946188) (xy 457.53353 -371.888826) (xy 457.532994 -371.85981) (xy 439.694001 -371.85981)
			(xy 439.660127 -371.905197) (xy 439.61679 -371.949947) (xy 439.568085 -371.988787) (xy 439.514814 -372.02108)
			(xy 439.457851 -372.046297) (xy 439.39813 -372.064021) (xy 439.336633 -372.073964) (xy 439.27437 -372.07596)
			(xy 439.212363 -372.069978) (xy 439.151629 -372.056116) (xy 439.093167 -372.034602) (xy 439.037936 -372.005788)
			(xy 438.986844 -371.970148) (xy 438.940728 -371.928267) (xy 438.900346 -371.880832) (xy 438.866362 -371.828623)
			(xy 438.839333 -371.772497) (xy 438.819704 -371.713376) (xy 438.807795 -371.652229) (xy 438.803804 -371.590062)
			(xy 437.532214 -371.590062) (xy 437.551281 -371.637242) (xy 437.567033 -371.697413) (xy 437.574974 -371.759102)
			(xy 437.574974 -371.821299) (xy 437.567033 -371.882988) (xy 437.551281 -371.943159) (xy 437.527976 -372.000825)
			(xy 437.497499 -372.055045) (xy 437.460349 -372.104929) (xy 437.417134 -372.149663) (xy 437.368562 -372.188512)
			(xy 437.315427 -372.220843) (xy 437.258599 -372.246125) (xy 437.199008 -372.263945) (xy 437.13763 -372.274011)
			(xy 437.106568 -372.275608) (xy 437.096662 -372.276116) (xy 437.08828 -372.279672) (xy 437.084074 -372.281645)
			(xy 437.076403 -372.286882) (xy 437.07304 -372.290086) (xy 437.055768 -372.30685) (xy 437.050942 -372.311676)
			(xy 437.044103 -372.319077) (xy 437.036389 -372.337675) (xy 437.035956 -372.347744) (xy 437.035956 -372.890034)
			(xy 438.803804 -372.890034) (xy 438.807795 -372.827867) (xy 438.819704 -372.76672) (xy 438.839333 -372.707599)
			(xy 438.866362 -372.651473) (xy 438.900346 -372.599264) (xy 438.940728 -372.551829) (xy 438.986844 -372.509948)
			(xy 439.037936 -372.474308) (xy 439.093167 -372.445494) (xy 439.151629 -372.42398) (xy 439.212363 -372.410118)
			(xy 439.27437 -372.404136) (xy 439.336633 -372.406132) (xy 439.39813 -372.416075) (xy 439.457851 -372.433799)
			(xy 439.514814 -372.459016) (xy 439.568085 -372.491309) (xy 439.61679 -372.530149) (xy 439.660127 -372.574899)
			(xy 439.697387 -372.624823) (xy 439.727956 -372.679102) (xy 439.751334 -372.736845) (xy 439.767135 -372.797103)
			(xy 439.775101 -372.858886) (xy 439.7756 -372.890034) (xy 439.775101 -372.921182) (xy 439.767135 -372.982965)
			(xy 439.751334 -373.043223) (xy 439.727956 -373.100966) (xy 439.697387 -373.155245) (xy 439.660127 -373.205169)
			(xy 439.61679 -373.249919) (xy 439.568085 -373.288759) (xy 439.514814 -373.321052) (xy 439.457851 -373.346269)
			(xy 439.39813 -373.363993) (xy 439.336633 -373.373936) (xy 439.27437 -373.375932) (xy 439.212363 -373.36995)
			(xy 439.151629 -373.356088) (xy 439.093167 -373.334574) (xy 439.037936 -373.30576) (xy 438.986844 -373.27012)
			(xy 438.940728 -373.228239) (xy 438.900346 -373.180804) (xy 438.866362 -373.128595) (xy 438.839333 -373.072469)
			(xy 438.819704 -373.013348) (xy 438.807795 -372.952201) (xy 438.803804 -372.890034) (xy 437.035956 -372.890034)
			(xy 437.035956 -373.453406) (xy 451.256398 -373.453406) (xy 451.260469 -373.397784) (xy 451.272595 -373.343347)
			(xy 451.292518 -373.291256) (xy 451.319814 -373.242621) (xy 451.3539 -373.198478) (xy 451.394049 -373.159769)
			(xy 451.439407 -373.127318) (xy 451.489007 -373.101817) (xy 451.541791 -373.08381) (xy 451.596634 -373.07368)
			(xy 451.652368 -373.071643) (xy 451.707805 -373.077743) (xy 451.761762 -373.091849) (xy 451.813091 -373.113661)
			(xy 451.860697 -373.142715) (xy 451.903565 -373.17839) (xy 451.940782 -373.219927) (xy 451.971555 -373.26644)
			(xy 451.995227 -373.316937) (xy 452.011295 -373.370344) (xy 452.019415 -373.42552) (xy 452.019924 -373.453406)
			(xy 452.019415 -373.481292) (xy 452.011295 -373.536468) (xy 451.995227 -373.589875) (xy 451.971555 -373.640372)
			(xy 451.940782 -373.686885) (xy 451.903565 -373.728422) (xy 451.860697 -373.764097) (xy 451.813091 -373.793151)
			(xy 451.761762 -373.814963) (xy 451.707805 -373.829069) (xy 451.652368 -373.835169) (xy 451.596634 -373.833132)
			(xy 451.541791 -373.823002) (xy 451.489007 -373.804995) (xy 451.439407 -373.779494) (xy 451.394049 -373.747043)
			(xy 451.3539 -373.708334) (xy 451.319814 -373.664191) (xy 451.292518 -373.615556) (xy 451.272595 -373.563465)
			(xy 451.260469 -373.509028) (xy 451.256398 -373.453406) (xy 437.035956 -373.453406) (xy 437.035956 -373.832628)
			(xy 437.036386 -373.842695) (xy 437.044114 -373.861286) (xy 437.050942 -373.868696) (xy 437.055768 -373.873522)
			(xy 437.07304 -373.890286) (xy 437.07641 -373.893481) (xy 437.084081 -373.898715) (xy 437.08828 -373.9007)
			(xy 437.096662 -373.904256) (xy 437.106568 -373.904764) (xy 437.137635 -373.906333) (xy 437.19902 -373.9164)
			(xy 437.258617 -373.934222) (xy 437.315452 -373.959507) (xy 437.368593 -373.991841) (xy 437.417171 -374.030695)
			(xy 437.460391 -374.075434) (xy 437.497545 -374.125324) (xy 437.528026 -374.17955) (xy 437.551334 -374.237223)
			(xy 437.567088 -374.2974) (xy 437.57503 -374.359096) (xy 437.57503 -374.421301) (xy 437.567088 -374.482997)
			(xy 437.551334 -374.543174) (xy 437.528027 -374.600848) (xy 437.497547 -374.655074) (xy 437.460393 -374.704964)
			(xy 437.417173 -374.749703) (xy 437.368595 -374.788557) (xy 437.315454 -374.820892) (xy 437.25862 -374.846177)
			(xy 437.199023 -374.863999) (xy 437.137638 -374.874067) (xy 437.106568 -374.875552) (xy 437.096662 -374.87606)
			(xy 437.08828 -374.879616) (xy 437.084075 -374.88159) (xy 437.076407 -374.88683) (xy 437.07304 -374.89003)
			(xy 437.055768 -374.906794) (xy 437.050942 -374.91162) (xy 437.044094 -374.919018) (xy 437.03636 -374.937616)
			(xy 437.035956 -374.947688) (xy 437.035956 -375.1326) (xy 437.036381 -375.142669) (xy 437.044101 -375.161268)
			(xy 437.050942 -375.168668) (xy 437.055768 -375.173494) (xy 437.07304 -375.190258) (xy 437.076409 -375.193455)
			(xy 437.084079 -375.198691) (xy 437.08828 -375.200672) (xy 437.096662 -375.204228) (xy 437.106568 -375.204736)
			(xy 437.137631 -375.206305) (xy 437.19901 -375.216372) (xy 437.2586 -375.234192) (xy 437.315428 -375.259476)
			(xy 437.368563 -375.291808) (xy 437.417134 -375.330659) (xy 437.460348 -375.375394) (xy 437.497496 -375.42528)
			(xy 437.527971 -375.479501) (xy 437.532307 -375.490232) (xy 438.803804 -375.490232) (xy 438.807795 -375.428065)
			(xy 438.819704 -375.366918) (xy 438.839333 -375.307797) (xy 438.866362 -375.251671) (xy 438.900346 -375.199462)
			(xy 438.940728 -375.152027) (xy 438.986844 -375.110146) (xy 439.037936 -375.074506) (xy 439.093167 -375.045692)
			(xy 439.151629 -375.024178) (xy 439.212363 -375.010316) (xy 439.27437 -375.004334) (xy 439.336633 -375.00633)
			(xy 439.39813 -375.016273) (xy 439.457851 -375.033997) (xy 439.514814 -375.059214) (xy 439.565899 -375.090182)
			(xy 459.19085 -375.090182) (xy 459.194921 -375.03456) (xy 459.207047 -374.980123) (xy 459.22697 -374.928032)
			(xy 459.254266 -374.879397) (xy 459.288352 -374.835254) (xy 459.328501 -374.796545) (xy 459.373859 -374.764094)
			(xy 459.423459 -374.738593) (xy 459.476243 -374.720586) (xy 459.531086 -374.710456) (xy 459.58682 -374.708419)
			(xy 459.642257 -374.714519) (xy 459.696214 -374.728625) (xy 459.747543 -374.750437) (xy 459.795149 -374.779491)
			(xy 459.838017 -374.815166) (xy 459.875234 -374.856703) (xy 459.906007 -374.903216) (xy 459.929679 -374.953713)
			(xy 459.945747 -375.00712) (xy 459.953867 -375.062296) (xy 459.954376 -375.090182) (xy 459.953867 -375.118068)
			(xy 459.945747 -375.173244) (xy 459.929679 -375.226651) (xy 459.906007 -375.277148) (xy 459.875234 -375.323661)
			(xy 459.838017 -375.365198) (xy 459.795149 -375.400873) (xy 459.747543 -375.429927) (xy 459.696214 -375.451739)
			(xy 459.642257 -375.465845) (xy 459.58682 -375.471945) (xy 459.531086 -375.469908) (xy 459.476243 -375.459778)
			(xy 459.423459 -375.441771) (xy 459.373859 -375.41627) (xy 459.328501 -375.383819) (xy 459.288352 -375.34511)
			(xy 459.254266 -375.300967) (xy 459.22697 -375.252332) (xy 459.207047 -375.200241) (xy 459.194921 -375.145804)
			(xy 459.19085 -375.090182) (xy 439.565899 -375.090182) (xy 439.568085 -375.091507) (xy 439.61679 -375.130347)
			(xy 439.660127 -375.175097) (xy 439.697387 -375.225021) (xy 439.727956 -375.2793) (xy 439.751334 -375.337043)
			(xy 439.767135 -375.397301) (xy 439.775101 -375.459084) (xy 439.7756 -375.490232) (xy 439.775101 -375.52138)
			(xy 439.767135 -375.583163) (xy 439.751334 -375.643421) (xy 439.727956 -375.701164) (xy 439.697387 -375.755443)
			(xy 439.660127 -375.805367) (xy 439.61679 -375.850117) (xy 439.568085 -375.888957) (xy 439.514814 -375.92125)
			(xy 439.457851 -375.946467) (xy 439.39813 -375.964191) (xy 439.336633 -375.974134) (xy 439.27437 -375.97613)
			(xy 439.212363 -375.970148) (xy 439.151629 -375.956286) (xy 439.093167 -375.934772) (xy 439.037936 -375.905958)
			(xy 438.986844 -375.870318) (xy 438.940728 -375.828437) (xy 438.900346 -375.781002) (xy 438.866362 -375.728793)
			(xy 438.839333 -375.672667) (xy 438.819704 -375.613546) (xy 438.807795 -375.552399) (xy 438.803804 -375.490232)
			(xy 437.532307 -375.490232) (xy 437.551273 -375.53717) (xy 437.567022 -375.597341) (xy 437.57496 -375.659031)
			(xy 437.575452 -375.69013) (xy 437.57493 -375.721926) (xy 437.566626 -375.784973) (xy 437.550164 -375.846397)
			(xy 437.525826 -375.905147) (xy 437.494028 -375.960218) (xy 437.455315 -376.010667) (xy 437.410347 -376.055632)
			(xy 437.359896 -376.094343) (xy 437.304824 -376.126138) (xy 437.246072 -376.150473) (xy 437.184647 -376.166931)
			(xy 437.1216 -376.175232) (xy 437.089804 -376.175778) (xy 437.089042 -376.175778) (xy 437.058684 -376.17534)
			(xy 436.998436 -376.167821) (xy 436.9689 -376.160792) (xy 436.96636 -376.160284) (xy 436.956962 -376.159776)
			(xy 436.947052 -376.187326) (xy 436.924431 -376.241336) (xy 436.91175 -376.267726) (xy 436.906924 -376.28449)
			(xy 436.902936 -376.314662) (xy 436.886613 -376.37329) (xy 436.861174 -376.428576) (xy 436.844694 -376.454162)
			(xy 436.827876 -376.47837) (xy 436.787992 -376.521769) (xy 436.741894 -376.558501) (xy 436.690685 -376.587687)
			(xy 436.663338 -376.598688) (xy 436.653178 -376.602498) (xy 436.465348 -376.790204) (xy 438.803804 -376.790204)
			(xy 438.807795 -376.728037) (xy 438.819704 -376.66689) (xy 438.839333 -376.607769) (xy 438.866362 -376.551643)
			(xy 438.900346 -376.499434) (xy 438.940728 -376.451999) (xy 438.986844 -376.410118) (xy 439.037936 -376.374478)
			(xy 439.093167 -376.345664) (xy 439.151629 -376.32415) (xy 439.212363 -376.310288) (xy 439.27437 -376.304306)
			(xy 439.336633 -376.306302) (xy 439.39813 -376.316245) (xy 439.457851 -376.333969) (xy 439.514814 -376.359186)
			(xy 439.568085 -376.391479) (xy 439.61679 -376.430319) (xy 439.660127 -376.475069) (xy 439.697387 -376.524993)
			(xy 439.727956 -376.579272) (xy 439.751334 -376.637015) (xy 439.767135 -376.697273) (xy 439.775101 -376.759056)
			(xy 439.7756 -376.790204) (xy 439.775101 -376.821352) (xy 439.767135 -376.883135) (xy 439.751334 -376.943393)
			(xy 439.727956 -377.001136) (xy 439.697387 -377.055415) (xy 439.660127 -377.105339) (xy 439.61679 -377.150089)
			(xy 439.568085 -377.188929) (xy 439.514814 -377.221222) (xy 439.457851 -377.246439) (xy 439.39813 -377.264163)
			(xy 439.336633 -377.274106) (xy 439.27437 -377.276102) (xy 439.212363 -377.27012) (xy 439.151629 -377.256258)
			(xy 439.093167 -377.234744) (xy 439.037936 -377.20593) (xy 438.986844 -377.17029) (xy 438.940728 -377.128409)
			(xy 438.900346 -377.080974) (xy 438.866362 -377.028765) (xy 438.839333 -376.972639) (xy 438.819704 -376.913518)
			(xy 438.807795 -376.852371) (xy 438.803804 -376.790204) (xy 436.465348 -376.790204) (xy 436.26913 -376.986292)
			(xy 436.236233 -377.018479) (xy 436.165463 -377.077329) (xy 436.08957 -377.129406) (xy 436.0092 -377.174266)
			(xy 435.925037 -377.211527) (xy 435.837799 -377.240873) (xy 435.793134 -377.251976) (xy 435.760622 -377.276614)
			(xy 435.738677 -377.314879) (xy 435.689003 -377.387783) (xy 435.633085 -377.456014) (xy 435.571359 -377.519041)
			(xy 435.504308 -377.576369) (xy 435.432456 -377.627551) (xy 435.356364 -377.672188) (xy 435.276627 -377.709929)
			(xy 435.193869 -377.740481) (xy 435.108736 -377.763604) (xy 435.021893 -377.779118) (xy 434.934019 -377.786902)
			(xy 434.88991 -377.787408) (xy 434.889148 -377.787408) (xy 434.846161 -377.786936) (xy 434.76051 -377.77949)
			(xy 434.675819 -377.764693) (xy 434.592717 -377.742654) (xy 434.511824 -377.713537) (xy 434.472588 -377.695968)
			(xy 434.46954 -377.696222) (xy 434.446921 -377.704854) (xy 434.400047 -377.716977) (xy 434.352016 -377.723063)
			(xy 434.327808 -377.7234) (xy 434.327554 -377.7234) (xy 434.300314 -377.722897) (xy 434.246394 -377.715112)
			(xy 434.194129 -377.699736) (xy 434.144583 -377.677081) (xy 434.098764 -377.647608) (xy 434.057604 -377.611916)
			(xy 434.02194 -377.570732) (xy 433.992497 -377.524894) (xy 433.969875 -377.475333) (xy 433.954533 -377.423058)
			(xy 433.946784 -377.369132) (xy 433.9463 -377.341892) (xy 433.9463 -377.341384) (xy 433.946633 -377.316998)
			(xy 433.95275 -377.268613) (xy 433.964999 -377.221407) (xy 433.973732 -377.198636) (xy 433.975764 -377.188984)
			(xy 433.95972 -377.151214) (xy 433.933163 -377.07356) (xy 433.913083 -376.993986) (xy 433.899618 -376.913029)
			(xy 433.892858 -376.831238) (xy 433.892452 -376.790204) (xy 433.892452 -376.408188) (xy 433.892924 -376.365198)
			(xy 433.900364 -376.279541) (xy 433.915144 -376.194841) (xy 433.925726 -376.153172) (xy 433.927504 -376.140218)
			(xy 433.925726 -376.127264) (xy 433.92217 -376.113294) (xy 433.918892 -376.102146) (xy 433.904077 -376.084276)
			(xy 433.893722 -376.079004) (xy 433.865274 -376.066304) (xy 433.860377 -376.06427) (xy 433.850002 -376.062088)
			(xy 433.8447 -376.061986) (xy 433.821332 -376.067574) (xy 433.784996 -376.085863) (xy 433.709892 -376.117139)
			(xy 433.632488 -376.142183) (xy 433.592986 -376.151902) (xy 433.560474 -376.17654) (xy 433.538543 -376.214822)
			(xy 433.488892 -376.28776) (xy 433.432991 -376.356025) (xy 433.371277 -376.419084) (xy 433.304231 -376.476442)
			(xy 433.23238 -376.527652) (xy 433.156284 -376.572313) (xy 433.07654 -376.610075) (xy 432.993771 -376.640642)
			(xy 432.908625 -376.663777) (xy 432.821768 -376.679297) (xy 432.733879 -376.687081) (xy 432.689762 -376.687588)
			(xy 432.649172 -376.687168) (xy 432.568262 -376.680549) (xy 432.488158 -376.667375) (xy 432.40939 -376.647733)
			(xy 432.332479 -376.621753) (xy 432.295046 -376.606054) (xy 432.273202 -376.596656) (xy 432.271932 -376.59691)
			(xy 432.263804 -376.598434) (xy 432.259486 -376.599958) (xy 432.253644 -376.60199) (xy 431.869088 -376.986292)
			(xy 431.836192 -377.018481) (xy 431.765423 -377.077334) (xy 431.689532 -377.129415) (xy 431.609163 -377.17428)
			(xy 431.525001 -377.211547) (xy 431.437763 -377.240898) (xy 431.393092 -377.251976) (xy 431.36058 -377.276614)
			(xy 431.338635 -377.314881) (xy 431.288963 -377.387788) (xy 431.233046 -377.456022) (xy 431.171321 -377.519052)
			(xy 431.10427 -377.576384) (xy 431.032419 -377.627571) (xy 430.956327 -377.672212) (xy 430.87659 -377.709958)
			(xy 430.793831 -377.740514) (xy 430.708697 -377.763642) (xy 430.621853 -377.779161) (xy 430.533978 -377.78695)
			(xy 430.489868 -377.787408) (xy 430.489106 -377.787408) (xy 430.446068 -377.786958) (xy 430.360311 -377.779542)
			(xy 430.275514 -377.764757) (xy 430.192308 -377.742713) (xy 430.111313 -377.713574) (xy 430.072038 -377.695968)
			(xy 430.06391 -377.698254) (xy 430.031941 -377.709674) (xy 429.965252 -377.722322) (xy 429.931322 -377.7234)
			(xy 429.925734 -377.7234) (xy 429.898579 -377.722774) (xy 429.844856 -377.714779) (xy 429.792809 -377.699246)
			(xy 429.743491 -377.676488) (xy 429.6979 -377.646965) (xy 429.656957 -377.611275) (xy 429.62149 -377.570138)
			(xy 429.592215 -377.524387) (xy 429.569725 -377.474946) (xy 429.554475 -377.422816) (xy 429.546773 -377.36905)
			(xy 429.546258 -377.341892) (xy 429.546258 -377.340876) (xy 429.546258 -377.340368) (xy 429.546665 -377.317099)
			(xy 429.552455 -377.270922) (xy 429.563835 -377.225796) (xy 429.571912 -377.20397) (xy 429.575468 -377.194826)
			(xy 429.575468 -377.188222) (xy 429.559536 -377.150555) (xy 429.533165 -377.073132) (xy 429.513221 -376.993809)
			(xy 429.499835 -376.913121) (xy 429.493099 -376.831607) (xy 429.492664 -376.790712) (xy 429.492664 -376.407426)
			(xy 429.493134 -376.364569) (xy 429.500513 -376.279174) (xy 429.515191 -376.194727) (xy 429.525684 -376.153172)
			(xy 429.527462 -376.140218) (xy 429.525684 -376.127264) (xy 429.522128 -376.113294) (xy 429.518744 -376.102306)
			(xy 429.504103 -376.08462) (xy 429.493934 -376.079258) (xy 429.465486 -376.066558) (xy 429.460477 -376.064432)
			(xy 429.449844 -376.062134) (xy 429.444404 -376.061986) (xy 429.421036 -376.067574) (xy 429.384773 -376.085829)
			(xy 429.309836 -376.117085) (xy 429.232608 -376.142151) (xy 429.193198 -376.151902) (xy 429.160686 -376.17654)
			(xy 429.138755 -376.214823) (xy 429.089105 -376.287761) (xy 429.033204 -376.356027) (xy 428.971489 -376.419086)
			(xy 428.904444 -376.476446) (xy 428.832593 -376.527656) (xy 428.756497 -376.572318) (xy 428.676753 -376.610081)
			(xy 428.593984 -376.640649) (xy 428.508838 -376.663785) (xy 428.42198 -376.679306) (xy 428.334091 -376.687091)
			(xy 428.289974 -376.687588) (xy 428.249379 -376.687147) (xy 428.168461 -376.680484) (xy 428.088354 -376.66726)
			(xy 428.009588 -376.647565) (xy 427.932686 -376.621527) (xy 427.895258 -376.6058) (xy 427.89475 -376.6058)
			(xy 427.873414 -376.596656) (xy 427.872144 -376.59691) (xy 427.864016 -376.598434) (xy 427.859698 -376.599958)
			(xy 427.853348 -376.602244) (xy 427.469046 -376.986292) (xy 427.436149 -377.018479) (xy 427.365379 -377.07733)
			(xy 427.289487 -377.129408) (xy 427.209117 -377.17427) (xy 427.124955 -377.211533) (xy 427.037717 -377.24088)
			(xy 426.99305 -377.251976) (xy 426.960538 -377.276614) (xy 426.938593 -377.31488) (xy 426.88892 -377.387784)
			(xy 426.833002 -377.456017) (xy 426.771276 -377.519044) (xy 426.704225 -377.576373) (xy 426.632373 -377.627557)
			(xy 426.556282 -377.672194) (xy 426.476545 -377.709937) (xy 426.393786 -377.74049) (xy 426.308653 -377.763615)
			(xy 426.221809 -377.77913) (xy 426.133935 -377.786915) (xy 426.089826 -377.787408) (xy 426.089064 -377.787408)
			(xy 426.046077 -377.786937) (xy 425.960425 -377.779492) (xy 425.875734 -377.764696) (xy 425.792632 -377.742658)
			(xy 425.711737 -377.713543) (xy 425.672504 -377.695968) (xy 425.669456 -377.696222) (xy 425.646916 -377.704823)
			(xy 425.600212 -377.716914) (xy 425.552354 -377.72301) (xy 425.528232 -377.7234) (xy 425.527724 -377.7234)
			(xy 425.50047 -377.722938) (xy 425.446517 -377.715184) (xy 425.394217 -377.69983) (xy 425.344634 -377.677189)
			(xy 425.298779 -377.647721) (xy 425.257584 -377.612028) (xy 425.221888 -377.570834) (xy 425.192419 -377.52498)
			(xy 425.169776 -377.475398) (xy 425.154419 -377.423099) (xy 425.146663 -377.369146) (xy 425.146216 -377.341892)
			(xy 425.146216 -377.341384) (xy 425.146549 -377.316998) (xy 425.152667 -377.268614) (xy 425.164916 -377.221407)
			(xy 425.173648 -377.198636) (xy 425.17568 -377.188984) (xy 425.159636 -377.151214) (xy 425.133078 -377.07356)
			(xy 425.112998 -376.993986) (xy 425.099533 -376.913029) (xy 425.092773 -376.831239) (xy 425.092368 -376.790204)
			(xy 425.092368 -376.408188) (xy 425.09284 -376.365198) (xy 425.10028 -376.279541) (xy 425.115061 -376.194842)
			(xy 425.125642 -376.153172) (xy 425.12742 -376.140218) (xy 425.125642 -376.127264) (xy 425.122086 -376.113294)
			(xy 425.118699 -376.102309) (xy 425.104053 -376.084633) (xy 425.093892 -376.079258) (xy 425.065444 -376.066558)
			(xy 425.060436 -376.064426) (xy 425.049803 -376.062116) (xy 425.044362 -376.061986) (xy 425.020994 -376.067574)
			(xy 424.98473 -376.085828) (xy 424.909793 -376.11708) (xy 424.832564 -376.142143) (xy 424.793156 -376.151902)
			(xy 424.760644 -376.17654) (xy 424.738713 -376.214824) (xy 424.689064 -376.287766) (xy 424.633164 -376.356035)
			(xy 424.571451 -376.419098) (xy 424.504406 -376.476461) (xy 424.432556 -376.527676) (xy 424.35646 -376.572342)
			(xy 424.276716 -376.610109) (xy 424.193947 -376.640682) (xy 424.1088 -376.663823) (xy 424.021941 -376.679349)
			(xy 423.93405 -376.687139) (xy 423.889932 -376.687588) (xy 423.849337 -376.687145) (xy 423.768421 -376.680479)
			(xy 423.688315 -376.667252) (xy 423.60955 -376.647554) (xy 423.532649 -376.621513) (xy 423.495216 -376.6058)
			(xy 423.494708 -376.6058) (xy 423.473372 -376.596656) (xy 423.472102 -376.59691) (xy 423.463974 -376.598434)
			(xy 423.459656 -376.599958) (xy 423.453306 -376.602244) (xy 423.069004 -376.986292) (xy 423.036106 -377.018478)
			(xy 422.965335 -377.077326) (xy 422.889442 -377.129401) (xy 422.809071 -377.174259) (xy 422.724909 -377.211519)
			(xy 422.63767 -377.240862) (xy 422.593008 -377.251976) (xy 422.560496 -377.276614) (xy 422.53855 -377.314879)
			(xy 422.488876 -377.387781) (xy 422.432958 -377.456011) (xy 422.371232 -377.519035) (xy 422.30418 -377.576362)
			(xy 422.232328 -377.627542) (xy 422.156236 -377.672177) (xy 422.076499 -377.709916) (xy 421.993741 -377.740466)
			(xy 421.908608 -377.763587) (xy 421.821766 -377.779099) (xy 421.733893 -377.78688) (xy 421.689784 -377.787408)
			(xy 421.689022 -377.787408) (xy 421.645984 -377.786954) (xy 421.56023 -377.779532) (xy 421.475435 -377.76474)
			(xy 421.392232 -377.742689) (xy 421.311242 -377.713544) (xy 421.271954 -377.695968) (xy 421.263826 -377.698254)
			(xy 421.231858 -377.709675) (xy 421.165168 -377.722326) (xy 421.131238 -377.7234) (xy 421.12565 -377.7234)
			(xy 421.098495 -377.722775) (xy 421.044769 -377.714782) (xy 420.99272 -377.69925) (xy 420.943401 -377.676493)
			(xy 420.897808 -377.646971) (xy 420.856863 -377.61128) (xy 420.821394 -377.570143) (xy 420.792118 -377.524391)
			(xy 420.769627 -377.47495) (xy 420.754376 -377.422818) (xy 420.746673 -377.36905) (xy 420.746174 -377.341892)
			(xy 420.746174 -377.340876) (xy 420.746174 -377.340368) (xy 420.746581 -377.317099) (xy 420.752372 -377.270922)
			(xy 420.763752 -377.225796) (xy 420.771828 -377.20397) (xy 420.775384 -377.194826) (xy 420.775384 -377.188222)
			(xy 420.759452 -377.150555) (xy 420.733081 -377.073132) (xy 420.713136 -376.993809) (xy 420.69975 -376.913121)
			(xy 420.693014 -376.831607) (xy 420.69258 -376.790712) (xy 420.69258 -376.407426) (xy 420.69305 -376.364569)
			(xy 420.700429 -376.279174) (xy 420.715107 -376.194727) (xy 420.7256 -376.153172) (xy 420.727378 -376.140218)
			(xy 420.7256 -376.127264) (xy 420.722044 -376.113294) (xy 420.718654 -376.102312) (xy 420.704003 -376.084647)
			(xy 420.69385 -376.079258) (xy 420.665402 -376.066558) (xy 420.660393 -376.064431) (xy 420.64976 -376.062129)
			(xy 420.64432 -376.061986) (xy 420.620952 -376.067574) (xy 420.584689 -376.08583) (xy 420.509753 -376.117086)
			(xy 420.432525 -376.142154) (xy 420.393114 -376.151902) (xy 420.360602 -376.17654) (xy 420.344299 -376.205109)
			(xy 420.308456 -376.260273) (xy 420.288974 -376.286776) (xy 420.282624 -376.295412) (xy 420.08806 -377.146566)
			(xy 419.900608 -377.966478) (xy 419.899592 -377.976892) (xy 419.899592 -378.015246) (xy 419.90137 -378.028454)
			(xy 419.903148 -378.034804) (xy 419.906704 -378.0409) (xy 419.923045 -378.069255) (xy 419.948795 -378.129421)
			(xy 419.966227 -378.192501) (xy 419.975024 -378.257352) (xy 419.975538 -378.290074) (xy 419.975538 -378.306584)
			(xy 419.973973 -378.337572) (xy 419.963951 -378.398806) (xy 419.946223 -378.458268) (xy 419.921078 -378.514992)
			(xy 419.905434 -378.541788) (xy 419.900608 -378.55525) (xy 419.899592 -378.56541) (xy 419.899592 -379.31725)
			(xy 419.900026 -379.322815) (xy 419.902965 -379.333581) (xy 419.905434 -379.338586) (xy 419.922057 -379.367155)
			(xy 419.948272 -379.427832) (xy 419.966021 -379.491502) (xy 419.974975 -379.55699) (xy 419.97497 -379.623088)
			(xy 419.966005 -379.688575) (xy 419.948246 -379.752242) (xy 419.922021 -379.812915) (xy 419.905434 -379.841506)
			(xy 419.902938 -379.846503) (xy 419.899982 -379.857271) (xy 419.899592 -379.862842) (xy 419.899592 -380.151386)
			(xy 419.8991 -380.161548) (xy 419.891329 -380.180327) (xy 419.876964 -380.194704) (xy 419.858191 -380.202491)
			(xy 419.84803 -380.202948) (xy 419.429692 -380.202948) (xy 419.421024 -380.20325) (xy 419.404662 -380.208967)
			(xy 419.397688 -380.214124) (xy 419.391084 -380.219458) (xy 419.382194 -380.233682) (xy 419.380162 -380.242572)
			(xy 419.349428 -380.377446) (xy 419.316408 -380.522988) (xy 419.315138 -380.533656) (xy 419.313428 -380.69012)
			(xy 421.204136 -380.69012) (xy 421.204697 -380.65739) (xy 421.213556 -380.592532) (xy 421.231047 -380.529452)
			(xy 421.256855 -380.469294) (xy 421.273224 -380.440946) (xy 421.276524 -380.434914) (xy 421.280139 -380.421656)
			(xy 421.280336 -380.414784) (xy 421.280336 -379.665484) (xy 421.280146 -379.658611) (xy 421.276536 -379.645348)
			(xy 421.273224 -379.639322) (xy 421.256869 -379.610967) (xy 421.231064 -379.55081) (xy 421.213572 -379.487732)
			(xy 421.204708 -379.422877) (xy 421.204136 -379.390148) (xy 421.204709 -379.357419) (xy 421.213564 -379.292561)
			(xy 421.231052 -379.229481) (xy 421.256857 -379.169323) (xy 421.273224 -379.140974) (xy 421.27655 -379.134955)
			(xy 421.280148 -379.121687) (xy 421.280336 -379.114812) (xy 421.280336 -378.828554) (xy 421.280789 -378.818425)
			(xy 421.288531 -378.799703) (xy 421.302827 -378.785349) (xy 421.321517 -378.777531) (xy 421.331644 -378.776992)
			(xy 422.047924 -378.776992) (xy 422.058079 -378.777402) (xy 422.07683 -378.785204) (xy 422.091152 -378.799604)
			(xy 422.098853 -378.818397) (xy 422.099232 -378.828554) (xy 422.099232 -379.114812) (xy 422.099416 -379.121686)
			(xy 422.103029 -379.134949) (xy 422.106344 -379.140974) (xy 422.122694 -379.169332) (xy 422.148501 -379.229488)
			(xy 422.165995 -379.292565) (xy 422.17486 -379.35742) (xy 422.175432 -379.390148) (xy 422.174861 -379.422877)
			(xy 422.166006 -379.487735) (xy 422.148517 -379.550815) (xy 422.131689 -379.590046) (xy 423.404284 -379.590046)
			(xy 423.40485 -379.557317) (xy 423.413706 -379.492458) (xy 423.431197 -379.429378) (xy 423.457004 -379.36922)
			(xy 423.473372 -379.340872) (xy 423.476695 -379.334851) (xy 423.480296 -379.321585) (xy 423.480484 -379.31471)
			(xy 423.480484 -378.56541) (xy 423.48029 -378.558537) (xy 423.476683 -378.545274) (xy 423.473372 -378.539248)
			(xy 423.456983 -378.510912) (xy 423.431187 -378.450747) (xy 423.413705 -378.387664) (xy 423.404851 -378.322804)
			(xy 423.404284 -378.290074) (xy 423.404863 -378.257345) (xy 423.413715 -378.192487) (xy 423.431202 -378.129407)
			(xy 423.457005 -378.069249) (xy 423.473372 -378.0409) (xy 423.476685 -378.034874) (xy 423.480292 -378.021611)
			(xy 423.480484 -378.014738) (xy 423.480484 -377.728734) (xy 423.480956 -377.718604) (xy 423.488681 -377.699875)
			(xy 423.502972 -377.685516) (xy 423.521664 -377.677704) (xy 423.531792 -377.677172) (xy 424.248072 -377.677172)
			(xy 424.258221 -377.677644) (xy 424.276967 -377.685425) (xy 424.291291 -377.699806) (xy 424.298996 -377.718584)
			(xy 424.29938 -377.728734) (xy 424.29938 -378.014738) (xy 424.299598 -378.021609) (xy 424.303189 -378.034872)
			(xy 424.306492 -378.0409) (xy 424.322857 -378.06925) (xy 424.348659 -378.129409) (xy 424.366149 -378.192488)
			(xy 424.37501 -378.257345) (xy 424.37558 -378.290074) (xy 424.375028 -378.322797) (xy 427.804911 -378.322797)
			(xy 427.804914 -378.257358) (xy 427.813701 -378.192512) (xy 427.831113 -378.129433) (xy 427.856835 -378.069261)
			(xy 427.87316 -378.0409) (xy 427.876471 -378.034874) (xy 427.88008 -378.021611) (xy 427.880272 -378.014738)
			(xy 427.880272 -377.728734) (xy 427.880693 -377.71856) (xy 427.888473 -377.69976) (xy 427.90286 -377.685373)
			(xy 427.92166 -377.677593) (xy 427.931834 -377.677172) (xy 428.648114 -377.677172) (xy 428.658291 -377.677553)
			(xy 428.677092 -377.685349) (xy 428.691478 -377.699748) (xy 428.699256 -377.718557) (xy 428.699676 -377.728734)
			(xy 428.699676 -378.014738) (xy 428.699895 -378.021609) (xy 428.703485 -378.034872) (xy 428.706788 -378.0409)
			(xy 428.723087 -378.069274) (xy 428.748806 -378.129442) (xy 428.766215 -378.192518) (xy 428.775001 -378.25736)
			(xy 428.775004 -378.322795) (xy 428.775004 -378.322797) (xy 432.2047 -378.322797) (xy 432.204703 -378.257358)
			(xy 432.21349 -378.192512) (xy 432.230902 -378.129433) (xy 432.256624 -378.069261) (xy 432.272948 -378.0409)
			(xy 432.276259 -378.034873) (xy 432.279867 -378.021611) (xy 432.28006 -378.014738) (xy 432.28006 -377.728734)
			(xy 432.280492 -377.718562) (xy 432.28827 -377.699764) (xy 432.302654 -377.685377) (xy 432.32145 -377.677595)
			(xy 432.331622 -377.677172) (xy 433.047902 -377.677172) (xy 433.058078 -377.677563) (xy 433.076879 -377.685355)
			(xy 433.091265 -377.699751) (xy 433.099044 -377.718558) (xy 433.099464 -377.728734) (xy 433.099464 -378.014738)
			(xy 433.099684 -378.021609) (xy 433.103274 -378.034872) (xy 433.106576 -378.0409) (xy 433.122876 -378.069274)
			(xy 433.148595 -378.129442) (xy 433.166005 -378.192518) (xy 433.174791 -378.25736) (xy 433.174792 -378.290074)
			(xy 436.603656 -378.290074) (xy 436.607647 -378.227907) (xy 436.619556 -378.16676) (xy 436.639185 -378.107639)
			(xy 436.666214 -378.051513) (xy 436.700198 -377.999304) (xy 436.74058 -377.951869) (xy 436.786696 -377.909988)
			(xy 436.837788 -377.874348) (xy 436.893019 -377.845534) (xy 436.951481 -377.82402) (xy 437.012215 -377.810158)
			(xy 437.074222 -377.804176) (xy 437.136485 -377.806172) (xy 437.197982 -377.816115) (xy 437.257703 -377.833839)
			(xy 437.314666 -377.859056) (xy 437.367937 -377.891349) (xy 437.416642 -377.930189) (xy 437.459979 -377.974939)
			(xy 437.497239 -378.024863) (xy 437.527808 -378.079142) (xy 437.551186 -378.136885) (xy 437.566987 -378.197143)
			(xy 437.574953 -378.258926) (xy 437.575452 -378.290074) (xy 437.574953 -378.321222) (xy 437.566987 -378.383005)
			(xy 437.551186 -378.443263) (xy 437.527808 -378.501006) (xy 437.497239 -378.555285) (xy 437.459979 -378.605209)
			(xy 437.416642 -378.649959) (xy 437.367937 -378.688799) (xy 437.314666 -378.721092) (xy 437.257703 -378.746309)
			(xy 437.197982 -378.764033) (xy 437.136485 -378.773976) (xy 437.074222 -378.775972) (xy 437.012215 -378.76999)
			(xy 436.951481 -378.756128) (xy 436.893019 -378.734614) (xy 436.837788 -378.7058) (xy 436.786696 -378.67016)
			(xy 436.74058 -378.628279) (xy 436.700198 -378.580844) (xy 436.666214 -378.528635) (xy 436.639185 -378.472509)
			(xy 436.619556 -378.413388) (xy 436.607647 -378.352241) (xy 436.603656 -378.290074) (xy 433.174792 -378.290074)
			(xy 433.174794 -378.322795) (xy 433.166014 -378.387638) (xy 433.148609 -378.450716) (xy 433.122896 -378.510887)
			(xy 433.106576 -378.539248) (xy 433.103243 -378.545263) (xy 433.099649 -378.558534) (xy 433.099464 -378.56541)
			(xy 433.099464 -379.31471) (xy 433.099657 -379.321583) (xy 433.103265 -379.334846) (xy 433.106576 -379.340872)
			(xy 433.122937 -379.369212) (xy 433.14865 -379.429388) (xy 433.166053 -379.492471) (xy 433.174832 -379.55732)
			(xy 433.174826 -379.622759) (xy 433.166037 -379.687606) (xy 433.148624 -379.750686) (xy 433.122901 -379.810859)
			(xy 433.106576 -379.83922) (xy 433.103252 -379.84524) (xy 433.099653 -379.858507) (xy 433.099464 -379.865382)
			(xy 433.099464 -380.151386) (xy 433.099025 -380.161556) (xy 433.091245 -380.180351) (xy 433.076864 -380.194736)
			(xy 433.058072 -380.202522) (xy 433.047902 -380.202948) (xy 432.331622 -380.202948) (xy 432.32145 -380.202518)
			(xy 432.302653 -380.194737) (xy 432.288267 -380.180353) (xy 432.280484 -380.161558) (xy 432.28006 -380.151386)
			(xy 432.28006 -379.865382) (xy 432.27988 -379.858508) (xy 432.276264 -379.845245) (xy 432.272948 -379.83922)
			(xy 432.256664 -379.810837) (xy 432.230943 -379.750671) (xy 432.21353 -379.687597) (xy 432.204741 -379.622756)
			(xy 432.204736 -379.557323) (xy 432.213514 -379.49248) (xy 432.230917 -379.429403) (xy 432.256629 -379.369233)
			(xy 432.272948 -379.340872) (xy 432.276269 -379.33485) (xy 432.279871 -379.321584) (xy 432.28006 -379.31471)
			(xy 432.28006 -378.56541) (xy 432.279869 -378.558537) (xy 432.276261 -378.545274) (xy 432.272948 -378.539248)
			(xy 432.256603 -378.510899) (xy 432.230887 -378.450725) (xy 432.213481 -378.387644) (xy 432.2047 -378.322797)
			(xy 428.775004 -378.322797) (xy 428.766224 -378.387638) (xy 428.74882 -378.450716) (xy 428.723108 -378.510886)
			(xy 428.706788 -378.539248) (xy 428.703455 -378.545264) (xy 428.699861 -378.558534) (xy 428.699676 -378.56541)
			(xy 428.699676 -379.31471) (xy 428.699867 -379.321583) (xy 428.703476 -379.334846) (xy 428.706788 -379.340872)
			(xy 428.723148 -379.369212) (xy 428.748861 -379.429388) (xy 428.766264 -379.492472) (xy 428.775042 -379.55732)
			(xy 428.775037 -379.622759) (xy 428.766248 -379.687606) (xy 428.748835 -379.750686) (xy 428.723112 -379.810858)
			(xy 428.706788 -379.83922) (xy 428.703465 -379.845241) (xy 428.699865 -379.858508) (xy 428.699676 -379.865382)
			(xy 428.699676 -380.151386) (xy 428.699156 -380.161541) (xy 428.691388 -380.180307) (xy 428.677031 -380.194673)
			(xy 428.658269 -380.20245) (xy 428.648114 -380.202948) (xy 427.931834 -380.202948) (xy 427.921663 -380.202508)
			(xy 427.902866 -380.194731) (xy 427.88848 -380.180351) (xy 427.880696 -380.161557) (xy 427.880272 -380.151386)
			(xy 427.880272 -379.865382) (xy 427.88009 -379.858508) (xy 427.876475 -379.845245) (xy 427.87316 -379.83922)
			(xy 427.856876 -379.810837) (xy 427.831154 -379.750672) (xy 427.813741 -379.687597) (xy 427.804952 -379.622756)
			(xy 427.804946 -379.557323) (xy 427.813725 -379.49248) (xy 427.831128 -379.429403) (xy 427.85684 -379.369233)
			(xy 427.87316 -379.340872) (xy 427.876481 -379.334851) (xy 427.880083 -379.321584) (xy 427.880272 -379.31471)
			(xy 427.880272 -378.56541) (xy 427.88008 -378.558537) (xy 427.876472 -378.545274) (xy 427.87316 -378.539248)
			(xy 427.856815 -378.510899) (xy 427.831098 -378.450725) (xy 427.813692 -378.387644) (xy 427.804911 -378.322797)
			(xy 424.375028 -378.322797) (xy 424.375028 -378.322804) (xy 424.366168 -378.387663) (xy 424.348674 -378.450743)
			(xy 424.322863 -378.5109) (xy 424.306492 -378.539248) (xy 424.30316 -378.545264) (xy 424.299565 -378.558534)
			(xy 424.29938 -378.56541) (xy 424.29938 -379.31471) (xy 424.299571 -379.321583) (xy 424.30318 -379.334846)
			(xy 424.306492 -379.340872) (xy 424.322846 -379.369228) (xy 424.348651 -379.429385) (xy 424.366144 -379.492462)
			(xy 424.375008 -379.557318) (xy 424.37558 -379.590046) (xy 424.375015 -379.622776) (xy 424.366159 -379.687634)
			(xy 424.348669 -379.750714) (xy 424.322861 -379.810872) (xy 424.306492 -379.83922) (xy 424.30317 -379.845241)
			(xy 424.299569 -379.858508) (xy 424.29938 -379.865382) (xy 424.29938 -380.151386) (xy 424.298863 -380.161509)
			(xy 424.291143 -380.180226) (xy 424.276866 -380.194583) (xy 424.258193 -380.202406) (xy 424.248072 -380.202948)
			(xy 423.531792 -380.202948) (xy 423.521643 -380.202486) (xy 423.5029 -380.194697) (xy 423.488579 -380.180313)
			(xy 423.480871 -380.161536) (xy 423.480484 -380.151386) (xy 423.480484 -379.865382) (xy 423.480301 -379.858508)
			(xy 423.476687 -379.845245) (xy 423.473372 -379.83922) (xy 423.457012 -379.810868) (xy 423.431209 -379.750709)
			(xy 423.413718 -379.687631) (xy 423.404856 -379.622775) (xy 423.404284 -379.590046) (xy 422.131689 -379.590046)
			(xy 422.122712 -379.610974) (xy 422.106344 -379.639322) (xy 422.103025 -379.645345) (xy 422.099422 -379.65861)
			(xy 422.099232 -379.665484) (xy 422.099232 -380.414784) (xy 422.099426 -380.421657) (xy 422.103033 -380.43492)
			(xy 422.106344 -380.440946) (xy 422.122723 -380.469288) (xy 422.148523 -380.52945) (xy 422.166009 -380.592532)
			(xy 422.174864 -380.65739) (xy 422.174864 -380.6574) (xy 425.604793 -380.6574) (xy 425.613574 -380.592556)
			(xy 425.630978 -380.529479) (xy 425.656692 -380.469308) (xy 425.673012 -380.440946) (xy 425.676311 -380.434914)
			(xy 425.679926 -380.421656) (xy 425.680124 -380.414784) (xy 425.680124 -379.665484) (xy 425.679935 -379.658611)
			(xy 425.676324 -379.645348) (xy 425.673012 -379.639322) (xy 425.656731 -379.610938) (xy 425.631011 -379.550772)
			(xy 425.6136 -379.487698) (xy 425.604812 -379.422858) (xy 425.604806 -379.357425) (xy 425.613583 -379.292583)
			(xy 425.630984 -379.229506) (xy 425.656694 -379.169335) (xy 425.673012 -379.140974) (xy 425.676337 -379.134954)
			(xy 425.679936 -379.121687) (xy 425.680124 -379.114812) (xy 425.680124 -378.828554) (xy 425.680595 -378.818395)
			(xy 425.688382 -378.799628) (xy 425.702754 -378.785264) (xy 425.721527 -378.777489) (xy 425.731686 -378.776992)
			(xy 426.447966 -378.776992) (xy 426.458116 -378.77756) (xy 426.476875 -378.785315) (xy 426.49124 -378.799657)
			(xy 426.499024 -378.818405) (xy 426.499528 -378.828554) (xy 426.499528 -379.114812) (xy 426.499712 -379.121686)
			(xy 426.503325 -379.134949) (xy 426.50664 -379.140974) (xy 426.523004 -379.169313) (xy 426.548718 -379.229489)
			(xy 426.566123 -379.292572) (xy 426.574902 -379.357421) (xy 426.574896 -379.422861) (xy 426.566106 -379.487709)
			(xy 426.548691 -379.550789) (xy 426.522966 -379.610961) (xy 426.50664 -379.639322) (xy 426.503321 -379.645344)
			(xy 426.499718 -379.65861) (xy 426.499528 -379.665484) (xy 426.499528 -380.414784) (xy 426.499723 -380.421657)
			(xy 426.503329 -380.43492) (xy 426.50664 -380.440946) (xy 426.52298 -380.469298) (xy 426.548697 -380.529471)
			(xy 426.566104 -380.592552) (xy 426.574886 -380.657398) (xy 426.574884 -380.69012) (xy 430.00422 -380.69012)
			(xy 430.00477 -380.65739) (xy 430.01363 -380.592531) (xy 430.031125 -380.529451) (xy 430.056937 -380.469293)
			(xy 430.073308 -380.440946) (xy 430.076607 -380.434914) (xy 430.080222 -380.421656) (xy 430.08042 -380.414784)
			(xy 430.08042 -379.665484) (xy 430.080232 -379.658611) (xy 430.076621 -379.645348) (xy 430.073308 -379.639322)
			(xy 430.056952 -379.610968) (xy 430.031148 -379.55081) (xy 430.013655 -379.487732) (xy 430.004792 -379.422877)
			(xy 430.00422 -379.390148) (xy 430.004782 -379.357418) (xy 430.013639 -379.29256) (xy 430.03113 -379.22948)
			(xy 430.056939 -379.169322) (xy 430.073308 -379.140974) (xy 430.076633 -379.134954) (xy 430.080232 -379.121687)
			(xy 430.08042 -379.114812) (xy 430.08042 -378.828554) (xy 430.080888 -378.818427) (xy 430.088628 -378.799708)
			(xy 430.102919 -378.785354) (xy 430.121603 -378.777533) (xy 430.131728 -378.776992) (xy 430.848008 -378.776992)
			(xy 430.858162 -378.777415) (xy 430.876913 -378.785212) (xy 430.891235 -378.799608) (xy 430.898936 -378.818398)
			(xy 430.899316 -378.828554) (xy 430.899316 -379.114812) (xy 430.899501 -379.121686) (xy 430.903114 -379.134949)
			(xy 430.906428 -379.140974) (xy 430.922786 -379.169327) (xy 430.948589 -379.229486) (xy 430.966081 -379.292564)
			(xy 430.974944 -379.357419) (xy 430.975516 -379.390148) (xy 430.974947 -379.422877) (xy 430.966092 -379.487735)
			(xy 430.948602 -379.550816) (xy 430.922796 -379.610974) (xy 430.906428 -379.639322) (xy 430.903107 -379.645344)
			(xy 430.899505 -379.65861) (xy 430.899316 -379.665484) (xy 430.899316 -380.414784) (xy 430.899512 -380.421657)
			(xy 430.903117 -380.43492) (xy 430.906428 -380.440946) (xy 430.922815 -380.469284) (xy 430.948611 -380.529448)
			(xy 430.966094 -380.592531) (xy 430.974949 -380.65739) (xy 430.974949 -380.6574) (xy 434.40488 -380.6574)
			(xy 434.41366 -380.592557) (xy 434.431064 -380.529479) (xy 434.456776 -380.469308) (xy 434.473096 -380.440946)
			(xy 434.476394 -380.434913) (xy 434.48001 -380.421656) (xy 434.480208 -380.414784) (xy 434.480208 -379.665484)
			(xy 434.480021 -379.65861) (xy 434.476409 -379.645348) (xy 434.473096 -379.639322) (xy 434.456816 -379.610938)
			(xy 434.431097 -379.550772) (xy 434.413686 -379.487698) (xy 434.404898 -379.422858) (xy 434.404892 -379.357425)
			(xy 434.413669 -379.292583) (xy 434.431069 -379.229506) (xy 434.456778 -379.169336) (xy 434.473096 -379.140974)
			(xy 434.47642 -379.134954) (xy 434.48002 -379.121687) (xy 434.480208 -379.114812) (xy 434.480208 -378.828554)
			(xy 434.480695 -378.818397) (xy 434.488479 -378.799633) (xy 434.502846 -378.78527) (xy 434.521613 -378.777492)
			(xy 434.53177 -378.776992) (xy 435.24805 -378.776992) (xy 435.258213 -378.777504) (xy 435.276998 -378.785264)
			(xy 435.291383 -378.799622) (xy 435.299177 -378.818392) (xy 435.299612 -378.828554) (xy 435.299612 -379.114812)
			(xy 435.299798 -379.121686) (xy 435.30341 -379.134949) (xy 435.306724 -379.140974) (xy 435.323088 -379.169312)
			(xy 435.348804 -379.229489) (xy 435.366209 -379.292572) (xy 435.374988 -379.357421) (xy 435.374982 -379.422861)
			(xy 435.366192 -379.487709) (xy 435.348777 -379.550789) (xy 435.331993 -379.590046) (xy 436.603656 -379.590046)
			(xy 436.607647 -379.527879) (xy 436.619556 -379.466732) (xy 436.639185 -379.407611) (xy 436.666214 -379.351485)
			(xy 436.700198 -379.299276) (xy 436.74058 -379.251841) (xy 436.786696 -379.20996) (xy 436.837788 -379.17432)
			(xy 436.893019 -379.145506) (xy 436.951481 -379.123992) (xy 437.012215 -379.11013) (xy 437.074222 -379.104148)
			(xy 437.136485 -379.106144) (xy 437.197982 -379.116087) (xy 437.257703 -379.133811) (xy 437.314666 -379.159028)
			(xy 437.367937 -379.191321) (xy 437.416642 -379.230161) (xy 437.459979 -379.274911) (xy 437.497239 -379.324835)
			(xy 437.527808 -379.379114) (xy 437.532275 -379.390148) (xy 438.803804 -379.390148) (xy 438.807795 -379.327981)
			(xy 438.819704 -379.266834) (xy 438.839333 -379.207713) (xy 438.866362 -379.151587) (xy 438.900346 -379.099378)
			(xy 438.940728 -379.051943) (xy 438.986844 -379.010062) (xy 439.037936 -378.974422) (xy 439.093167 -378.945608)
			(xy 439.151629 -378.924094) (xy 439.212363 -378.910232) (xy 439.27437 -378.90425) (xy 439.336633 -378.906246)
			(xy 439.39813 -378.916189) (xy 439.457851 -378.933913) (xy 439.514814 -378.95913) (xy 439.568085 -378.991423)
			(xy 439.61679 -379.030263) (xy 439.660127 -379.075013) (xy 439.697387 -379.124937) (xy 439.727956 -379.179216)
			(xy 439.751334 -379.236959) (xy 439.767135 -379.297217) (xy 439.775101 -379.359) (xy 439.7756 -379.390148)
			(xy 439.775101 -379.421296) (xy 439.767135 -379.483079) (xy 439.751334 -379.543337) (xy 439.727956 -379.60108)
			(xy 439.697387 -379.655359) (xy 439.660127 -379.705283) (xy 439.61679 -379.750033) (xy 439.568085 -379.788873)
			(xy 439.514814 -379.821166) (xy 439.457851 -379.846383) (xy 439.39813 -379.864107) (xy 439.336633 -379.87405)
			(xy 439.27437 -379.876046) (xy 439.212363 -379.870064) (xy 439.151629 -379.856202) (xy 439.093167 -379.834688)
			(xy 439.037936 -379.805874) (xy 438.986844 -379.770234) (xy 438.940728 -379.728353) (xy 438.900346 -379.680918)
			(xy 438.866362 -379.628709) (xy 438.839333 -379.572583) (xy 438.819704 -379.513462) (xy 438.807795 -379.452315)
			(xy 438.803804 -379.390148) (xy 437.532275 -379.390148) (xy 437.551186 -379.436857) (xy 437.566987 -379.497115)
			(xy 437.574953 -379.558898) (xy 437.575452 -379.590046) (xy 437.574953 -379.621194) (xy 437.566987 -379.682977)
			(xy 437.551186 -379.743235) (xy 437.527808 -379.800978) (xy 437.497239 -379.855257) (xy 437.459979 -379.905181)
			(xy 437.416642 -379.949931) (xy 437.367937 -379.988771) (xy 437.314666 -380.021064) (xy 437.257703 -380.046281)
			(xy 437.197982 -380.064005) (xy 437.136485 -380.073948) (xy 437.074222 -380.075944) (xy 437.012215 -380.069962)
			(xy 436.951481 -380.0561) (xy 436.893019 -380.034586) (xy 436.837788 -380.005772) (xy 436.786696 -379.970132)
			(xy 436.74058 -379.928251) (xy 436.700198 -379.880816) (xy 436.666214 -379.828607) (xy 436.639185 -379.772481)
			(xy 436.619556 -379.71336) (xy 436.607647 -379.652213) (xy 436.603656 -379.590046) (xy 435.331993 -379.590046)
			(xy 435.323051 -379.610961) (xy 435.306724 -379.639322) (xy 435.303403 -379.645344) (xy 435.299801 -379.65861)
			(xy 435.299612 -379.665484) (xy 435.299612 -380.414784) (xy 435.299809 -380.421657) (xy 435.303414 -380.43492)
			(xy 435.306724 -380.440946) (xy 435.323064 -380.469298) (xy 435.348782 -380.529471) (xy 435.36619 -380.592551)
			(xy 435.374972 -380.657398) (xy 435.374971 -380.69012) (xy 438.803804 -380.69012) (xy 438.807795 -380.627953)
			(xy 438.819704 -380.566806) (xy 438.839333 -380.507685) (xy 438.866362 -380.451559) (xy 438.900346 -380.39935)
			(xy 438.940728 -380.351915) (xy 438.986844 -380.310034) (xy 439.037936 -380.274394) (xy 439.093167 -380.24558)
			(xy 439.151629 -380.224066) (xy 439.212363 -380.210204) (xy 439.27437 -380.204222) (xy 439.336633 -380.206218)
			(xy 439.39813 -380.216161) (xy 439.457851 -380.233885) (xy 439.514814 -380.259102) (xy 439.568085 -380.291395)
			(xy 439.61679 -380.330235) (xy 439.660127 -380.374985) (xy 439.697387 -380.424909) (xy 439.727956 -380.479188)
			(xy 439.751334 -380.536931) (xy 439.767135 -380.597189) (xy 439.775101 -380.658972) (xy 439.7756 -380.69012)
			(xy 439.775101 -380.721268) (xy 439.767135 -380.783051) (xy 439.751334 -380.843309) (xy 439.727956 -380.901052)
			(xy 439.697387 -380.955331) (xy 439.660127 -381.005255) (xy 439.61679 -381.050005) (xy 439.568085 -381.088845)
			(xy 439.514814 -381.121138) (xy 439.457851 -381.146355) (xy 439.39813 -381.164079) (xy 439.336633 -381.174022)
			(xy 439.27437 -381.176018) (xy 439.212363 -381.170036) (xy 439.151629 -381.156174) (xy 439.093167 -381.13466)
			(xy 439.037936 -381.105846) (xy 438.986844 -381.070206) (xy 438.940728 -381.028325) (xy 438.900346 -380.98089)
			(xy 438.866362 -380.928681) (xy 438.839333 -380.872555) (xy 438.819704 -380.813434) (xy 438.807795 -380.752287)
			(xy 438.803804 -380.69012) (xy 435.374971 -380.69012) (xy 435.37497 -380.722836) (xy 435.366183 -380.787682)
			(xy 435.348771 -380.850762) (xy 435.323049 -380.910933) (xy 435.306724 -380.939294) (xy 435.303413 -380.945321)
			(xy 435.299805 -380.958583) (xy 435.299612 -380.965456) (xy 435.299612 -381.251206) (xy 435.29924 -381.261384)
			(xy 435.291444 -381.280189) (xy 435.277041 -381.294575) (xy 435.258229 -381.302351) (xy 435.24805 -381.302768)
			(xy 434.53177 -381.302768) (xy 434.521611 -381.302291) (xy 434.502842 -381.294508) (xy 434.488478 -381.280138)
			(xy 434.480704 -381.261365) (xy 434.480208 -381.251206) (xy 434.480208 -380.965456) (xy 434.479993 -380.958584)
			(xy 434.4764 -380.945322) (xy 434.473096 -380.939294) (xy 434.456792 -380.910923) (xy 434.431075 -380.850754)
			(xy 434.413667 -380.787677) (xy 434.404882 -380.722835) (xy 434.40488 -380.6574) (xy 430.974949 -380.6574)
			(xy 430.975516 -380.69012) (xy 430.974935 -380.722849) (xy 430.966083 -380.787707) (xy 430.948597 -380.850787)
			(xy 430.922794 -380.910945) (xy 430.906428 -380.939294) (xy 430.903117 -380.945321) (xy 430.899509 -380.958583)
			(xy 430.899316 -380.965456) (xy 430.899316 -381.251206) (xy 430.898877 -381.261338) (xy 430.891139 -381.280068)
			(xy 430.876838 -381.294426) (xy 430.858138 -381.302237) (xy 430.848008 -381.302768) (xy 430.131728 -381.302768)
			(xy 430.121572 -381.302355) (xy 430.102814 -381.294563) (xy 430.088488 -381.280163) (xy 430.080793 -381.261364)
			(xy 430.08042 -381.251206) (xy 430.08042 -380.965456) (xy 430.080204 -380.958585) (xy 430.076612 -380.945322)
			(xy 430.073308 -380.939294) (xy 430.056941 -380.910946) (xy 430.031139 -380.850786) (xy 430.01365 -380.787706)
			(xy 430.00479 -380.722849) (xy 430.00422 -380.69012) (xy 426.574884 -380.69012) (xy 426.574883 -380.722836)
			(xy 426.566097 -380.787682) (xy 426.548686 -380.850762) (xy 426.522964 -380.910933) (xy 426.50664 -380.939294)
			(xy 426.503331 -380.945321) (xy 426.499721 -380.958583) (xy 426.499528 -380.965456) (xy 426.499528 -381.251206)
			(xy 426.49914 -381.261382) (xy 426.491347 -381.280184) (xy 426.47695 -381.294569) (xy 426.458143 -381.302348)
			(xy 426.447966 -381.302768) (xy 425.731686 -381.302768) (xy 425.721528 -381.302278) (xy 425.70276 -381.2945)
			(xy 425.688395 -381.280133) (xy 425.68062 -381.261364) (xy 425.680124 -381.251206) (xy 425.680124 -380.965456)
			(xy 425.679908 -380.958585) (xy 425.676316 -380.945322) (xy 425.673012 -380.939294) (xy 425.656708 -380.910923)
			(xy 425.63099 -380.850754) (xy 425.613581 -380.787677) (xy 425.604796 -380.722835) (xy 425.604793 -380.6574)
			(xy 422.174864 -380.6574) (xy 422.175432 -380.69012) (xy 422.174848 -380.722849) (xy 422.165997 -380.787706)
			(xy 422.148512 -380.850786) (xy 422.12271 -380.910945) (xy 422.106344 -380.939294) (xy 422.103035 -380.945321)
			(xy 422.099425 -380.958583) (xy 422.099232 -380.965456) (xy 422.099232 -381.251206) (xy 422.098777 -381.261337)
			(xy 422.091042 -381.280063) (xy 422.076746 -381.29442) (xy 422.058052 -381.302234) (xy 422.047924 -381.302768)
			(xy 421.331644 -381.302768) (xy 421.321489 -381.302342) (xy 421.302731 -381.294555) (xy 421.288405 -381.280159)
			(xy 421.28071 -381.261363) (xy 421.280336 -381.251206) (xy 421.280336 -380.965456) (xy 421.280118 -380.958585)
			(xy 421.276527 -380.945322) (xy 421.273224 -380.939294) (xy 421.256858 -380.910945) (xy 421.231056 -380.850785)
			(xy 421.213566 -380.787706) (xy 421.204706 -380.722849) (xy 421.204136 -380.69012) (xy 419.313428 -380.69012)
			(xy 419.303962 -381.556006) (xy 419.310443 -381.564294) (xy 419.328412 -381.575194) (xy 419.33876 -381.577088)
			(xy 419.345618 -381.577596) (xy 419.853872 -381.577596) (xy 419.863172 -381.579058) (xy 419.879889 -381.58768)
			(xy 419.892443 -381.601688) (xy 419.899189 -381.619246) (xy 419.899592 -381.62865) (xy 419.899592 -381.915162)
			(xy 419.90137 -381.92837) (xy 419.903148 -381.93472) (xy 419.91834 -381.960159) (xy 419.943112 -382.013986)
			(xy 419.961155 -382.070426) (xy 419.972198 -382.128641) (xy 419.97608 -382.187768) (xy 419.972741 -382.246927)
			(xy 419.962232 -382.305242) (xy 419.944709 -382.361845) (xy 419.920432 -382.415897) (xy 419.905434 -382.44145)
			(xy 419.902942 -382.446448) (xy 419.899996 -382.457216) (xy 419.899592 -382.462786) (xy 419.899592 -383.21742)
			(xy 419.900033 -383.222983) (xy 419.902985 -383.233742) (xy 419.905434 -383.238756) (xy 419.922053 -383.267328)
			(xy 419.948263 -383.328008) (xy 419.966014 -383.391679) (xy 419.974978 -383.457167) (xy 419.975538 -383.490216)
			(xy 419.975001 -383.522937) (xy 419.966207 -383.587786) (xy 419.94878 -383.650865) (xy 419.923037 -383.711031)
			(xy 419.906704 -383.73939) (xy 419.903148 -383.745486) (xy 419.90137 -383.751836) (xy 419.899592 -383.765044)
			(xy 419.899592 -384.051556) (xy 419.899169 -384.061714) (xy 419.891383 -384.080477) (xy 419.876986 -384.09481)
			(xy 419.858189 -384.102513) (xy 419.84803 -384.102864) (xy 419.410134 -384.102864) (xy 419.399599 -384.10345)
			(xy 419.380327 -384.111983) (xy 419.372796 -384.119374) (xy 419.36543 -384.127248) (xy 419.358572 -384.147568)
			(xy 419.364922 -384.21818) (xy 419.366446 -384.218688) (xy 419.416484 -384.214116) (xy 419.416738 -384.214116)
			(xy 419.434191 -384.21204) (xy 419.469267 -384.209754) (xy 419.486842 -384.209544) (xy 419.491668 -384.209544)
			(xy 419.526455 -384.210162) (xy 419.595508 -384.218686) (xy 419.663048 -384.235402) (xy 419.728106 -384.260069)
			(xy 419.78975 -384.292334) (xy 419.847097 -384.331734) (xy 419.899324 -384.377704) (xy 419.945684 -384.429587)
			(xy 419.985511 -384.486637) (xy 420.018236 -384.548039) (xy 420.034519 -384.590036) (xy 421.204136 -384.590036)
			(xy 421.204704 -384.557307) (xy 421.213561 -384.492449) (xy 421.23105 -384.429369) (xy 421.256856 -384.36921)
			(xy 421.273224 -384.340862) (xy 421.276554 -384.334845) (xy 421.28015 -384.321575) (xy 421.280336 -384.3147)
			(xy 421.280336 -383.5654) (xy 421.28014 -383.558527) (xy 421.276534 -383.545265) (xy 421.273224 -383.539238)
			(xy 421.256876 -383.510879) (xy 421.231069 -383.450723) (xy 421.213575 -383.387647) (xy 421.204709 -383.322792)
			(xy 421.204136 -383.290064) (xy 421.204717 -383.257335) (xy 421.213569 -383.192478) (xy 421.231055 -383.129398)
			(xy 421.256858 -383.069239) (xy 421.273224 -383.04089) (xy 421.276544 -383.034868) (xy 421.280146 -383.021602)
			(xy 421.280336 -383.014728) (xy 421.280336 -382.728724) (xy 421.280736 -382.718599) (xy 421.288483 -382.699889)
			(xy 421.302805 -382.685572) (xy 421.321518 -382.677832) (xy 421.331644 -382.677416) (xy 422.047924 -382.677416)
			(xy 422.058036 -382.677866) (xy 422.076718 -382.685614) (xy 422.091013 -382.699922) (xy 422.098744 -382.718611)
			(xy 422.099232 -382.728724) (xy 422.099232 -383.014728) (xy 422.099409 -383.021602) (xy 422.103027 -383.034865)
			(xy 422.106344 -383.04089) (xy 422.1227 -383.069244) (xy 422.148506 -383.129402) (xy 422.165998 -383.19248)
			(xy 422.174861 -383.257335) (xy 422.175432 -383.290064) (xy 422.174868 -383.322794) (xy 422.166011 -383.387652)
			(xy 422.14852 -383.450732) (xy 422.131582 -383.490216) (xy 423.404284 -383.490216) (xy 423.404836 -383.457486)
			(xy 423.413696 -383.392627) (xy 423.431191 -383.329547) (xy 423.457002 -383.26939) (xy 423.473372 -383.241042)
			(xy 423.47667 -383.235009) (xy 423.480287 -383.221752) (xy 423.480484 -383.21488) (xy 423.480484 -382.465326)
			(xy 423.480284 -382.458453) (xy 423.476681 -382.445191) (xy 423.473372 -382.439164) (xy 423.456989 -382.410824)
			(xy 423.431192 -382.350661) (xy 423.413708 -382.287579) (xy 423.404852 -382.22272) (xy 423.404284 -382.18999)
			(xy 423.40487 -382.157261) (xy 423.41372 -382.092404) (xy 423.431205 -382.029324) (xy 423.457006 -381.969165)
			(xy 423.473372 -381.940816) (xy 423.476679 -381.934788) (xy 423.48029 -381.921527) (xy 423.480484 -381.914654)
			(xy 423.480484 -381.628904) (xy 423.480988 -381.618798) (xy 423.488721 -381.600122) (xy 423.503012 -381.585828)
			(xy 423.521686 -381.57809) (xy 423.531792 -381.577596) (xy 424.248072 -381.577596) (xy 424.258192 -381.578039)
			(xy 424.276895 -381.585777) (xy 424.29121 -381.600085) (xy 424.298957 -381.618784) (xy 424.29938 -381.628904)
			(xy 424.29938 -381.914654) (xy 424.299592 -381.921526) (xy 424.303187 -381.934788) (xy 424.306492 -381.940816)
			(xy 424.322863 -381.969162) (xy 424.348664 -382.029323) (xy 424.366152 -382.092403) (xy 424.375011 -382.157261)
			(xy 424.37558 -382.18999) (xy 424.375035 -382.22271) (xy 427.80492 -382.22271) (xy 427.804921 -382.157273)
			(xy 427.813706 -382.092427) (xy 427.831116 -382.029348) (xy 427.856836 -381.969177) (xy 427.87316 -381.940816)
			(xy 427.876466 -381.934787) (xy 427.880077 -381.921527) (xy 427.880272 -381.914654) (xy 427.880272 -381.628904)
			(xy 427.880724 -381.618754) (xy 427.888513 -381.600007) (xy 427.9029 -381.585684) (xy 427.921682 -381.577979)
			(xy 427.931834 -381.577596) (xy 428.648114 -381.577596) (xy 428.658236 -381.578114) (xy 428.676949 -381.585838)
			(xy 428.691303 -381.600114) (xy 428.69913 -381.618785) (xy 428.699676 -381.628904) (xy 428.699676 -381.914654)
			(xy 428.699888 -381.921526) (xy 428.703483 -381.934788) (xy 428.706788 -381.940816) (xy 428.723101 -381.969182)
			(xy 428.748818 -382.029353) (xy 428.766226 -382.09243) (xy 428.77501 -382.157274) (xy 428.775011 -382.222709)
			(xy 428.775011 -382.22271) (xy 432.20471 -382.22271) (xy 432.204711 -382.157273) (xy 432.213496 -382.092428)
			(xy 432.230905 -382.029348) (xy 432.256625 -381.969177) (xy 432.272948 -381.940816) (xy 432.276253 -381.934786)
			(xy 432.279865 -381.921527) (xy 432.28006 -381.914654) (xy 432.28006 -381.628904) (xy 432.280524 -381.618755)
			(xy 432.288311 -381.600011) (xy 432.302694 -381.585689) (xy 432.321471 -381.577981) (xy 432.331622 -381.577596)
			(xy 433.047902 -381.577596) (xy 433.058023 -381.578124) (xy 433.076736 -381.585844) (xy 433.091091 -381.600117)
			(xy 433.098918 -381.618786) (xy 433.099464 -381.628904) (xy 433.099464 -381.914654) (xy 433.099678 -381.921526)
			(xy 433.103272 -381.934788) (xy 433.106576 -381.940816) (xy 433.122889 -381.969182) (xy 433.148607 -382.029352)
			(xy 433.166015 -382.09243) (xy 433.1748 -382.157274) (xy 433.1748 -382.18999) (xy 436.603656 -382.18999)
			(xy 436.607647 -382.127823) (xy 436.619556 -382.066676) (xy 436.639185 -382.007555) (xy 436.666214 -381.951429)
			(xy 436.700198 -381.89922) (xy 436.74058 -381.851785) (xy 436.786696 -381.809904) (xy 436.837788 -381.774264)
			(xy 436.893019 -381.74545) (xy 436.951481 -381.723936) (xy 437.012215 -381.710074) (xy 437.074222 -381.704092)
			(xy 437.136485 -381.706088) (xy 437.197982 -381.716031) (xy 437.257703 -381.733755) (xy 437.314666 -381.758972)
			(xy 437.367937 -381.791265) (xy 437.416642 -381.830105) (xy 437.459979 -381.874855) (xy 437.497239 -381.924779)
			(xy 437.527808 -381.979058) (xy 437.551186 -382.036801) (xy 437.566987 -382.097059) (xy 437.574953 -382.158842)
			(xy 437.575452 -382.18999) (xy 437.574953 -382.221138) (xy 437.566987 -382.282921) (xy 437.551186 -382.343179)
			(xy 437.527808 -382.400922) (xy 437.497239 -382.455201) (xy 437.459979 -382.505125) (xy 437.416642 -382.549875)
			(xy 437.367937 -382.588715) (xy 437.314666 -382.621008) (xy 437.257703 -382.646225) (xy 437.197982 -382.663949)
			(xy 437.136485 -382.673892) (xy 437.074222 -382.675888) (xy 437.012215 -382.669906) (xy 436.951481 -382.656044)
			(xy 436.893019 -382.63453) (xy 436.837788 -382.605716) (xy 436.786696 -382.570076) (xy 436.74058 -382.528195)
			(xy 436.700198 -382.48076) (xy 436.666214 -382.428551) (xy 436.639185 -382.372425) (xy 436.619556 -382.313304)
			(xy 436.607647 -382.252157) (xy 436.603656 -382.18999) (xy 433.1748 -382.18999) (xy 433.174801 -382.222709)
			(xy 433.166019 -382.287553) (xy 433.148613 -382.350631) (xy 433.122897 -382.410803) (xy 433.106576 -382.439164)
			(xy 433.103272 -382.445194) (xy 433.09966 -382.458454) (xy 433.099464 -382.465326) (xy 433.099464 -383.21488)
			(xy 433.099668 -383.221752) (xy 433.103269 -383.235015) (xy 433.106576 -383.241042) (xy 433.122911 -383.269396)
			(xy 433.145729 -383.322788) (xy 434.40485 -383.322788) (xy 434.404854 -383.25735) (xy 434.413641 -383.192504)
			(xy 434.431053 -383.129424) (xy 434.456773 -383.069252) (xy 434.473096 -383.04089) (xy 434.476414 -383.034867)
			(xy 434.480018 -383.021602) (xy 434.480208 -383.014728) (xy 434.480208 -382.728724) (xy 434.480641 -382.71857)
			(xy 434.48843 -382.699817) (xy 434.502824 -382.685492) (xy 434.521614 -382.677793) (xy 434.53177 -382.677416)
			(xy 435.24805 -382.677416) (xy 435.258171 -382.677967) (xy 435.276886 -382.685674) (xy 435.291243 -382.69994)
			(xy 435.299068 -382.718607) (xy 435.299612 -382.728724) (xy 435.299612 -383.014728) (xy 435.299792 -383.021602)
			(xy 435.303408 -383.034865) (xy 435.306724 -383.04089) (xy 435.323017 -383.069268) (xy 435.348739 -383.129435)
			(xy 435.366152 -383.19251) (xy 435.37494 -383.257352) (xy 435.374944 -383.322786) (xy 435.366165 -383.387629)
			(xy 435.34876 -383.450707) (xy 435.331875 -383.490216) (xy 436.603656 -383.490216) (xy 436.607647 -383.428049)
			(xy 436.619556 -383.366902) (xy 436.639185 -383.307781) (xy 436.666214 -383.251655) (xy 436.700198 -383.199446)
			(xy 436.74058 -383.152011) (xy 436.786696 -383.11013) (xy 436.837788 -383.07449) (xy 436.893019 -383.045676)
			(xy 436.951481 -383.024162) (xy 437.012215 -383.0103) (xy 437.074222 -383.004318) (xy 437.136485 -383.006314)
			(xy 437.197982 -383.016257) (xy 437.257703 -383.033981) (xy 437.314666 -383.059198) (xy 437.367937 -383.091491)
			(xy 437.416642 -383.130331) (xy 437.459979 -383.175081) (xy 437.497239 -383.225005) (xy 437.527808 -383.279284)
			(xy 437.532172 -383.290064) (xy 438.803804 -383.290064) (xy 438.807795 -383.227897) (xy 438.819704 -383.16675)
			(xy 438.839333 -383.107629) (xy 438.866362 -383.051503) (xy 438.900346 -382.999294) (xy 438.940728 -382.951859)
			(xy 438.986844 -382.909978) (xy 439.037936 -382.874338) (xy 439.093167 -382.845524) (xy 439.151629 -382.82401)
			(xy 439.212363 -382.810148) (xy 439.27437 -382.804166) (xy 439.336633 -382.806162) (xy 439.39813 -382.816105)
			(xy 439.457851 -382.833829) (xy 439.514814 -382.859046) (xy 439.568085 -382.891339) (xy 439.61679 -382.930179)
			(xy 439.660127 -382.974929) (xy 439.697387 -383.024853) (xy 439.727956 -383.079132) (xy 439.751334 -383.136875)
			(xy 439.767135 -383.197133) (xy 439.775101 -383.258916) (xy 439.7756 -383.290064) (xy 439.775101 -383.321212)
			(xy 439.767135 -383.382995) (xy 439.751334 -383.443253) (xy 439.727956 -383.500996) (xy 439.697387 -383.555275)
			(xy 439.660127 -383.605199) (xy 439.61679 -383.649949) (xy 439.568085 -383.688789) (xy 439.514814 -383.721082)
			(xy 439.457851 -383.746299) (xy 439.39813 -383.764023) (xy 439.336633 -383.773966) (xy 439.27437 -383.775962)
			(xy 439.212363 -383.76998) (xy 439.151629 -383.756118) (xy 439.093167 -383.734604) (xy 439.037936 -383.70579)
			(xy 438.986844 -383.67015) (xy 438.940728 -383.628269) (xy 438.900346 -383.580834) (xy 438.866362 -383.528625)
			(xy 438.839333 -383.472499) (xy 438.819704 -383.413378) (xy 438.807795 -383.352231) (xy 438.803804 -383.290064)
			(xy 437.532172 -383.290064) (xy 437.551186 -383.337027) (xy 437.566987 -383.397285) (xy 437.574953 -383.459068)
			(xy 437.575452 -383.490216) (xy 437.574953 -383.521364) (xy 437.566987 -383.583147) (xy 437.551186 -383.643405)
			(xy 437.527808 -383.701148) (xy 437.497239 -383.755427) (xy 437.459979 -383.805351) (xy 437.416642 -383.850101)
			(xy 437.367937 -383.888941) (xy 437.314666 -383.921234) (xy 437.257703 -383.946451) (xy 437.197982 -383.964175)
			(xy 437.136485 -383.974118) (xy 437.074222 -383.976114) (xy 437.012215 -383.970132) (xy 436.951481 -383.95627)
			(xy 436.893019 -383.934756) (xy 436.837788 -383.905942) (xy 436.786696 -383.870302) (xy 436.74058 -383.828421)
			(xy 436.700198 -383.780986) (xy 436.666214 -383.728777) (xy 436.639185 -383.672651) (xy 436.619556 -383.61353)
			(xy 436.607647 -383.552383) (xy 436.603656 -383.490216) (xy 435.331875 -383.490216) (xy 435.323045 -383.510877)
			(xy 435.306724 -383.539238) (xy 435.303397 -383.545257) (xy 435.299799 -383.558525) (xy 435.299612 -383.5654)
			(xy 435.299612 -384.3147) (xy 435.299803 -384.321573) (xy 435.303412 -384.334836) (xy 435.306724 -384.340862)
			(xy 435.323078 -384.369206) (xy 435.348795 -384.429381) (xy 435.366201 -384.492463) (xy 435.374981 -384.557311)
			(xy 435.374979 -384.590036) (xy 438.803804 -384.590036) (xy 438.807795 -384.527869) (xy 438.819704 -384.466722)
			(xy 438.839333 -384.407601) (xy 438.866362 -384.351475) (xy 438.900346 -384.299266) (xy 438.940728 -384.251831)
			(xy 438.986844 -384.20995) (xy 439.037936 -384.17431) (xy 439.093167 -384.145496) (xy 439.151629 -384.123982)
			(xy 439.212363 -384.11012) (xy 439.27437 -384.104138) (xy 439.336633 -384.106134) (xy 439.39813 -384.116077)
			(xy 439.457851 -384.133801) (xy 439.514814 -384.159018) (xy 439.568085 -384.191311) (xy 439.61679 -384.230151)
			(xy 439.660127 -384.274901) (xy 439.697387 -384.324825) (xy 439.727956 -384.379104) (xy 439.751334 -384.436847)
			(xy 439.767135 -384.497105) (xy 439.775101 -384.558888) (xy 439.7756 -384.590036) (xy 439.775101 -384.621184)
			(xy 439.767135 -384.682967) (xy 439.751334 -384.743225) (xy 439.727956 -384.800968) (xy 439.697387 -384.855247)
			(xy 439.660127 -384.905171) (xy 439.61679 -384.949921) (xy 439.568085 -384.988761) (xy 439.514814 -385.021054)
			(xy 439.457851 -385.046271) (xy 439.39813 -385.063995) (xy 439.336633 -385.073938) (xy 439.27437 -385.075934)
			(xy 439.212363 -385.069952) (xy 439.151629 -385.05609) (xy 439.093167 -385.034576) (xy 439.037936 -385.005762)
			(xy 438.986844 -384.970122) (xy 438.940728 -384.928241) (xy 438.900346 -384.880806) (xy 438.866362 -384.828597)
			(xy 438.839333 -384.772471) (xy 438.819704 -384.71335) (xy 438.807795 -384.652203) (xy 438.803804 -384.590036)
			(xy 435.374979 -384.590036) (xy 435.374977 -384.622751) (xy 435.366188 -384.687598) (xy 435.348774 -384.750678)
			(xy 435.32305 -384.810849) (xy 435.306724 -384.83921) (xy 435.303407 -384.845234) (xy 435.299802 -384.858498)
			(xy 435.299612 -384.865372) (xy 435.299612 -385.151376) (xy 435.299159 -385.161527) (xy 435.291374 -385.180277)
			(xy 435.276987 -385.194601) (xy 435.258203 -385.202303) (xy 435.24805 -385.202684) (xy 434.53177 -385.202684)
			(xy 434.521644 -385.202199) (xy 434.502927 -385.194466) (xy 434.488573 -385.180179) (xy 434.48075 -385.161499)
			(xy 434.480208 -385.151376) (xy 434.480208 -384.865372) (xy 434.480026 -384.858498) (xy 434.476411 -384.845235)
			(xy 434.473096 -384.83921) (xy 434.456806 -384.810831) (xy 434.431087 -384.750664) (xy 434.413678 -384.687589)
			(xy 434.404891 -384.622748) (xy 434.404887 -384.557314) (xy 434.413665 -384.492472) (xy 434.431067 -384.429395)
			(xy 434.456778 -384.369224) (xy 434.473096 -384.340862) (xy 434.476424 -384.334844) (xy 434.480021 -384.321575)
			(xy 434.480208 -384.3147) (xy 434.480208 -383.5654) (xy 434.480015 -383.558527) (xy 434.476408 -383.545264)
			(xy 434.473096 -383.539238) (xy 434.456745 -383.510893) (xy 434.431032 -383.450718) (xy 434.413629 -383.387636)
			(xy 434.40485 -383.322788) (xy 433.145729 -383.322788) (xy 433.148627 -383.329569) (xy 433.166033 -383.392649)
			(xy 433.174815 -383.457495) (xy 433.174813 -383.522933) (xy 433.166027 -383.587778) (xy 433.148618 -383.650857)
			(xy 433.122899 -383.711029) (xy 433.106576 -383.73939) (xy 433.103263 -383.745415) (xy 433.099657 -383.758679)
			(xy 433.099464 -383.765552) (xy 433.099464 -384.051556) (xy 433.099042 -384.061712) (xy 433.091254 -384.08047)
			(xy 433.076856 -384.094796) (xy 433.05806 -384.102491) (xy 433.047902 -384.102864) (xy 432.331622 -384.102864)
			(xy 432.321497 -384.102356) (xy 432.302777 -384.094636) (xy 432.28842 -384.080356) (xy 432.2806 -384.061678)
			(xy 432.28006 -384.051556) (xy 432.28006 -383.765552) (xy 432.279853 -383.75868) (xy 432.276256 -383.745417)
			(xy 432.272948 -383.73939) (xy 432.256639 -383.711021) (xy 432.23092 -383.650852) (xy 432.21351 -383.587775)
			(xy 432.204724 -383.522932) (xy 432.204723 -383.457496) (xy 432.213504 -383.392652) (xy 432.230911 -383.329574)
			(xy 432.256627 -383.269403) (xy 432.272948 -383.241042) (xy 432.276244 -383.235008) (xy 432.279862 -383.221752)
			(xy 432.28006 -383.21488) (xy 432.28006 -382.465326) (xy 432.279863 -382.458453) (xy 432.276259 -382.44519)
			(xy 432.272948 -382.439164) (xy 432.256617 -382.410808) (xy 432.2309 -382.350635) (xy 432.213492 -382.287556)
			(xy 432.20471 -382.22271) (xy 428.775011 -382.22271) (xy 428.766229 -382.287553) (xy 428.748824 -382.350631)
			(xy 428.723109 -382.410802) (xy 428.706788 -382.439164) (xy 428.703485 -382.445194) (xy 428.699872 -382.458454)
			(xy 428.699676 -382.465326) (xy 428.699676 -383.21488) (xy 428.699879 -383.221752) (xy 428.70348 -383.235015)
			(xy 428.706788 -383.241042) (xy 428.723123 -383.269396) (xy 428.748838 -383.329569) (xy 428.766243 -383.392649)
			(xy 428.775025 -383.457495) (xy 428.775023 -383.522932) (xy 428.766238 -383.587778) (xy 428.748829 -383.650857)
			(xy 428.72311 -383.711028) (xy 428.706788 -383.73939) (xy 428.703476 -383.745416) (xy 428.699869 -383.758679)
			(xy 428.699676 -383.765552) (xy 428.699676 -384.051556) (xy 428.699242 -384.06171) (xy 428.691456 -384.080466)
			(xy 428.677063 -384.094792) (xy 428.65827 -384.102489) (xy 428.648114 -384.102864) (xy 427.931834 -384.102864)
			(xy 427.92171 -384.102345) (xy 427.90299 -384.09463) (xy 427.888633 -384.080353) (xy 427.880812 -384.061677)
			(xy 427.880272 -384.051556) (xy 427.880272 -383.765552) (xy 427.880064 -383.75868) (xy 427.876467 -383.745417)
			(xy 427.87316 -383.73939) (xy 427.856851 -383.711021) (xy 427.831131 -383.650852) (xy 427.81372 -383.587775)
			(xy 427.804935 -383.522932) (xy 427.804933 -383.457496) (xy 427.813715 -383.392652) (xy 427.831122 -383.329574)
			(xy 427.856838 -383.269403) (xy 427.87316 -383.241042) (xy 427.876457 -383.235008) (xy 427.880074 -383.221752)
			(xy 427.880272 -383.21488) (xy 427.880272 -382.465326) (xy 427.880074 -382.458453) (xy 427.87647 -382.44519)
			(xy 427.87316 -382.439164) (xy 427.856829 -382.410808) (xy 427.831111 -382.350636) (xy 427.813703 -382.287556)
			(xy 427.80492 -382.22271) (xy 424.375035 -382.22271) (xy 424.375035 -382.22272) (xy 424.366173 -382.287579)
			(xy 424.348677 -382.35066) (xy 424.322863 -382.410817) (xy 424.306492 -382.439164) (xy 424.303189 -382.445195)
			(xy 424.299576 -382.458454) (xy 424.29938 -382.465326) (xy 424.29938 -383.21488) (xy 424.299582 -383.221752)
			(xy 424.303184 -383.235015) (xy 424.306492 -383.241042) (xy 424.322874 -383.269382) (xy 424.345775 -383.322789)
			(xy 425.604764 -383.322789) (xy 425.604768 -383.25735) (xy 425.613555 -383.192504) (xy 425.630967 -383.129424)
			(xy 425.656688 -383.069252) (xy 425.673012 -383.04089) (xy 425.676331 -383.034868) (xy 425.679934 -383.021602)
			(xy 425.680124 -383.014728) (xy 425.680124 -382.728724) (xy 425.680542 -382.718568) (xy 425.688334 -382.699812)
			(xy 425.702732 -382.685487) (xy 425.721528 -382.67779) (xy 425.731686 -382.677416) (xy 426.447966 -382.677416)
			(xy 426.458088 -382.677954) (xy 426.476803 -382.685666) (xy 426.49116 -382.699937) (xy 426.498984 -382.718606)
			(xy 426.499528 -382.728724) (xy 426.499528 -383.014728) (xy 426.499705 -383.021602) (xy 426.503323 -383.034865)
			(xy 426.50664 -383.04089) (xy 426.522932 -383.069268) (xy 426.548654 -383.129435) (xy 426.566066 -383.19251)
			(xy 426.574854 -383.257352) (xy 426.574858 -383.322786) (xy 426.566079 -383.387629) (xy 426.548674 -383.450707)
			(xy 426.52296 -383.510877) (xy 426.50664 -383.539238) (xy 426.503315 -383.545258) (xy 426.499715 -383.558525)
			(xy 426.499528 -383.5654) (xy 426.499528 -384.3147) (xy 426.499717 -384.321574) (xy 426.503327 -384.334836)
			(xy 426.50664 -384.340862) (xy 426.522993 -384.369206) (xy 426.548709 -384.429381) (xy 426.566115 -384.492463)
			(xy 426.574895 -384.557311) (xy 426.574893 -384.590036) (xy 430.00422 -384.590036) (xy 430.004777 -384.557306)
			(xy 430.013635 -384.492447) (xy 430.031128 -384.429367) (xy 430.056938 -384.36921) (xy 430.073308 -384.340862)
			(xy 430.076637 -384.334844) (xy 430.080233 -384.321575) (xy 430.08042 -384.3147) (xy 430.08042 -383.5654)
			(xy 430.080226 -383.558527) (xy 430.076619 -383.545264) (xy 430.073308 -383.539238) (xy 430.056958 -383.51088)
			(xy 430.031152 -383.450724) (xy 430.013658 -383.387647) (xy 430.004793 -383.322792) (xy 430.00422 -383.290064)
			(xy 430.004789 -383.257335) (xy 430.013644 -383.192476) (xy 430.031133 -383.129396) (xy 430.05694 -383.069238)
			(xy 430.073308 -383.04089) (xy 430.076627 -383.034867) (xy 430.08023 -383.021602) (xy 430.08042 -383.014728)
			(xy 430.08042 -382.728724) (xy 430.080836 -382.718601) (xy 430.08858 -382.699894) (xy 430.102897 -382.685578)
			(xy 430.121605 -382.677835) (xy 430.131728 -382.677416) (xy 430.848008 -382.677416) (xy 430.858133 -382.67781)
			(xy 430.87684 -382.685564) (xy 430.891154 -382.699887) (xy 430.898896 -382.718599) (xy 430.899316 -382.728724)
			(xy 430.899316 -383.014728) (xy 430.899495 -383.021602) (xy 430.903112 -383.034865) (xy 430.906428 -383.04089)
			(xy 430.922792 -383.06924) (xy 430.948594 -383.129399) (xy 430.966084 -383.192479) (xy 430.974945 -383.257335)
			(xy 430.975516 -383.290064) (xy 430.974955 -383.322794) (xy 430.966097 -383.387652) (xy 430.948606 -383.450732)
			(xy 430.922797 -383.51089) (xy 430.906428 -383.539238) (xy 430.903102 -383.545257) (xy 430.899503 -383.558525)
			(xy 430.899316 -383.5654) (xy 430.899316 -384.3147) (xy 430.899506 -384.321573) (xy 430.903116 -384.334836)
			(xy 430.906428 -384.340862) (xy 430.922781 -384.369218) (xy 430.948585 -384.429375) (xy 430.966078 -384.492453)
			(xy 430.974943 -384.557308) (xy 430.975516 -384.590036) (xy 430.974942 -384.622765) (xy 430.966088 -384.687623)
			(xy 430.9486 -384.750703) (xy 430.922795 -384.810862) (xy 430.906428 -384.83921) (xy 430.903112 -384.845234)
			(xy 430.899507 -384.858498) (xy 430.899316 -384.865372) (xy 430.899316 -385.151376) (xy 430.898865 -385.161495)
			(xy 430.891128 -385.180195) (xy 430.876822 -385.19451) (xy 430.858127 -385.202259) (xy 430.848008 -385.202684)
			(xy 430.131728 -385.202684) (xy 430.121605 -385.202261) (xy 430.102899 -385.194519) (xy 430.088583 -385.180204)
			(xy 430.08084 -385.161499) (xy 430.08042 -385.151376) (xy 430.08042 -384.865372) (xy 430.080236 -384.858498)
			(xy 430.076622 -384.845236) (xy 430.073308 -384.83921) (xy 430.056947 -384.810858) (xy 430.031144 -384.7507)
			(xy 430.013653 -384.687621) (xy 430.004791 -384.622765) (xy 430.00422 -384.590036) (xy 426.574893 -384.590036)
			(xy 426.574891 -384.622751) (xy 426.566102 -384.687597) (xy 426.548689 -384.750677) (xy 426.522965 -384.810849)
			(xy 426.50664 -384.83921) (xy 426.503325 -384.845235) (xy 426.499719 -384.858498) (xy 426.499528 -384.865372)
			(xy 426.499528 -385.151376) (xy 426.499059 -385.161525) (xy 426.491277 -385.180272) (xy 426.476895 -385.194595)
			(xy 426.458117 -385.202301) (xy 426.447966 -385.202684) (xy 425.731686 -385.202684) (xy 425.721561 -385.202185)
			(xy 425.702845 -385.194457) (xy 425.68849 -385.180175) (xy 425.680667 -385.161498) (xy 425.680124 -385.151376)
			(xy 425.680124 -384.865372) (xy 425.67994 -384.858498) (xy 425.676326 -384.845236) (xy 425.673012 -384.83921)
			(xy 425.656721 -384.810832) (xy 425.631002 -384.750664) (xy 425.613592 -384.687589) (xy 425.604805 -384.622748)
			(xy 425.604801 -384.557314) (xy 425.613579 -384.492472) (xy 425.630982 -384.429394) (xy 425.656693 -384.369223)
			(xy 425.673012 -384.340862) (xy 425.676341 -384.334844) (xy 425.679937 -384.321575) (xy 425.680124 -384.3147)
			(xy 425.680124 -383.5654) (xy 425.679929 -383.558527) (xy 425.676323 -383.545264) (xy 425.673012 -383.539238)
			(xy 425.65666 -383.510893) (xy 425.630947 -383.450718) (xy 425.613543 -383.387636) (xy 425.604764 -383.322789)
			(xy 424.345775 -383.322789) (xy 424.348672 -383.329545) (xy 424.366157 -383.392627) (xy 424.375012 -383.457486)
			(xy 424.37558 -383.490216) (xy 424.375002 -383.522945) (xy 424.36615 -383.587803) (xy 424.348664 -383.650883)
			(xy 424.322859 -383.711042) (xy 424.306492 -383.73939) (xy 424.30318 -383.745416) (xy 424.299573 -383.758679)
			(xy 424.29938 -383.765552) (xy 424.29938 -384.051556) (xy 424.298947 -384.061678) (xy 424.29121 -384.080385)
			(xy 424.276898 -384.094701) (xy 424.258194 -384.102444) (xy 424.248072 -384.102864) (xy 423.531792 -384.102864)
			(xy 423.521665 -384.10249) (xy 423.502954 -384.094732) (xy 423.488639 -384.080402) (xy 423.4809 -384.061684)
			(xy 423.480484 -384.051556) (xy 423.480484 -383.765552) (xy 423.480274 -383.75868) (xy 423.476678 -383.745417)
			(xy 423.473372 -383.73939) (xy 423.457 -383.711044) (xy 423.4312 -383.650883) (xy 423.413713 -383.587803)
			(xy 423.404854 -383.522945) (xy 423.404284 -383.490216) (xy 422.131582 -383.490216) (xy 422.122713 -383.51089)
			(xy 422.106344 -383.539238) (xy 422.103019 -383.545258) (xy 422.099419 -383.558525) (xy 422.099232 -383.5654)
			(xy 422.099232 -384.3147) (xy 422.09942 -384.321574) (xy 422.103031 -384.334836) (xy 422.106344 -384.340862)
			(xy 422.122689 -384.369223) (xy 422.148497 -384.429378) (xy 422.165993 -384.492454) (xy 422.174859 -384.557308)
			(xy 422.175432 -384.590036) (xy 422.174856 -384.622765) (xy 422.166003 -384.687623) (xy 422.148515 -384.750703)
			(xy 422.122711 -384.810862) (xy 422.106344 -384.83921) (xy 422.103029 -384.845235) (xy 422.099423 -384.858498)
			(xy 422.099232 -384.865372) (xy 422.099232 -385.151376) (xy 422.098696 -385.161479) (xy 422.090972 -385.180151)
			(xy 422.076691 -385.194445) (xy 422.058027 -385.202187) (xy 422.047924 -385.202684) (xy 421.331644 -385.202684)
			(xy 421.321522 -385.202247) (xy 421.302817 -385.194511) (xy 421.2885 -385.1802) (xy 421.280756 -385.161497)
			(xy 421.280336 -385.151376) (xy 421.280336 -384.865372) (xy 421.28015 -384.858498) (xy 421.276537 -384.845236)
			(xy 421.273224 -384.83921) (xy 421.256865 -384.810857) (xy 421.231061 -384.750699) (xy 421.213569 -384.687621)
			(xy 421.204707 -384.622765) (xy 421.204136 -384.590036) (xy 420.034519 -384.590036) (xy 420.043388 -384.61291)
			(xy 420.060608 -384.680323) (xy 420.069649 -384.749311) (xy 420.070534 -384.784092) (xy 420.070534 -384.790188)
			(xy 420.069264 -384.83032) (xy 420.067994 -384.84556) (xy 420.083234 -384.872484) (xy 421.254174 -385.4577)
			(xy 421.25956 -385.460179) (xy 421.271106 -385.462865) (xy 421.277034 -385.463034) (xy 421.310054 -385.450842)
			(xy 421.336474 -385.42864) (xy 421.393653 -385.389996) (xy 421.45501 -385.358405) (xy 421.519681 -385.334312)
			(xy 421.586752 -385.318058) (xy 421.655278 -385.309873) (xy 421.689784 -385.309364) (xy 421.724876 -385.309872)
			(xy 421.794549 -385.31833) (xy 421.862694 -385.335125) (xy 421.928318 -385.360011) (xy 421.990464 -385.392627)
			(xy 422.048225 -385.432495) (xy 422.100759 -385.479036) (xy 422.1473 -385.531569) (xy 422.187169 -385.589329)
			(xy 422.197165 -385.608376) (xy 454.303373 -385.608376) (xy 454.303373 -385.479236) (xy 454.311323 -385.350341)
			(xy 454.327193 -385.222181) (xy 454.350922 -385.09524) (xy 454.382421 -384.970001) (xy 454.42157 -384.846938)
			(xy 454.468221 -384.726519) (xy 454.522196 -384.6092) (xy 454.583291 -384.495426) (xy 454.651274 -384.385629)
			(xy 454.725888 -384.280226) (xy 454.806849 -384.179616) (xy 454.893849 -384.084181) (xy 454.98656 -383.994282)
			(xy 455.08463 -383.910261) (xy 455.187685 -383.832437) (xy 455.295336 -383.761105) (xy 455.407175 -383.696535)
			(xy 455.522776 -383.638973) (xy 455.641701 -383.588636) (xy 455.7635 -383.545716) (xy 455.88771 -383.510375)
			(xy 456.013859 -383.482748) (xy 456.141471 -383.462939) (xy 456.27006 -383.451023) (xy 456.399138 -383.447047)
			(xy 456.528216 -383.451023) (xy 456.656805 -383.462939) (xy 456.784417 -383.482748) (xy 456.910566 -383.510375)
			(xy 457.034776 -383.545716) (xy 457.156575 -383.588636) (xy 457.2755 -383.638973) (xy 457.391101 -383.696535)
			(xy 457.50294 -383.761105) (xy 457.610591 -383.832437) (xy 457.713646 -383.910261) (xy 457.811716 -383.994282)
			(xy 457.904427 -384.084181) (xy 457.991427 -384.179616) (xy 458.072388 -384.280226) (xy 458.147002 -384.385629)
			(xy 458.214985 -384.495426) (xy 458.27608 -384.6092) (xy 458.330055 -384.726519) (xy 458.376706 -384.846938)
			(xy 458.415855 -384.970001) (xy 458.447354 -385.09524) (xy 458.471083 -385.222181) (xy 458.486953 -385.350341)
			(xy 458.494903 -385.479236) (xy 458.4954 -385.543806) (xy 458.494903 -385.608376) (xy 458.486953 -385.737271)
			(xy 458.471083 -385.865431) (xy 458.447354 -385.992372) (xy 458.415855 -386.117611) (xy 458.376706 -386.240674)
			(xy 458.330055 -386.361093) (xy 458.27608 -386.478412) (xy 458.214985 -386.592186) (xy 458.147002 -386.701983)
			(xy 458.072388 -386.807386) (xy 457.991427 -386.907996) (xy 457.904427 -387.003431) (xy 457.811716 -387.09333)
			(xy 457.713646 -387.177351) (xy 457.610591 -387.255175) (xy 457.50294 -387.326507) (xy 457.391101 -387.391077)
			(xy 457.2755 -387.448639) (xy 457.156575 -387.498976) (xy 457.034776 -387.541896) (xy 456.910566 -387.577237)
			(xy 456.784417 -387.604864) (xy 456.656805 -387.624673) (xy 456.528216 -387.636589) (xy 456.399138 -387.640566)
			(xy 456.27006 -387.636589) (xy 456.141471 -387.624673) (xy 456.013859 -387.604864) (xy 455.88771 -387.577237)
			(xy 455.7635 -387.541896) (xy 455.641701 -387.498976) (xy 455.522776 -387.448639) (xy 455.407175 -387.391077)
			(xy 455.295336 -387.326507) (xy 455.187685 -387.255175) (xy 455.08463 -387.177351) (xy 454.98656 -387.09333)
			(xy 454.893849 -387.003431) (xy 454.806849 -386.907996) (xy 454.725888 -386.807386) (xy 454.651274 -386.701983)
			(xy 454.583291 -386.592186) (xy 454.522196 -386.478412) (xy 454.468221 -386.361093) (xy 454.42157 -386.240674)
			(xy 454.382421 -386.117611) (xy 454.350922 -385.992372) (xy 454.327193 -385.865431) (xy 454.311323 -385.737271)
			(xy 454.303373 -385.608376) (xy 422.197165 -385.608376) (xy 422.219785 -385.651475) (xy 422.244673 -385.717098)
			(xy 422.261469 -385.785243) (xy 422.269928 -385.854916) (xy 422.270428 -385.890008) (xy 422.269158 -385.930394)
			(xy 422.269158 -385.933696) (xy 422.269469 -385.943112) (xy 422.276179 -385.960702) (xy 422.288832 -385.974644)
			(xy 422.297098 -385.979162) (xy 424.123358 -386.892546) (xy 424.130216 -386.89534) (xy 425.188888 -387.245098)
			(xy 425.216211 -387.254322) (xy 425.269839 -387.275548) (xy 425.296076 -387.287516) (xy 430.54651 -389.730488)
			(xy 430.572529 -389.742835) (xy 430.623236 -389.770156) (xy 430.647856 -389.785098) (xy 433.11826 -391.307066)
			(xy 433.118514 -391.30732) (xy 433.123594 -391.310368) (xy 433.127658 -391.312908) (xy 433.127912 -391.312908)
			(xy 433.135024 -391.317226) (xy 433.753514 -391.698734) (xy 433.829206 -391.745216) (xy 433.834286 -391.746994)
			(xy 433.876603 -391.762241) (xy 433.958555 -391.799331) (xy 434.036831 -391.843656) (xy 434.110792 -391.894856)
			(xy 434.179839 -391.952514) (xy 434.211984 -391.983976) (xy 436.720996 -394.492988) (xy 436.75143 -394.524096)
			(xy 436.807371 -394.59077) (xy 436.857289 -394.662064) (xy 436.900805 -394.737437) (xy 436.937588 -394.816315)
			(xy 436.967358 -394.898098) (xy 436.989888 -394.982165) (xy 437.005008 -395.067874) (xy 437.012601 -395.154576)
			(xy 437.013096 -395.198092) (xy 437.013096 -395.235938) (xy 437.014112 -395.24051) (xy 437.014366 -395.241526)
			(xy 437.024526 -395.297406) (xy 437.02985 -395.334451) (xy 437.035571 -395.40908) (xy 437.035956 -395.446504)
			(xy 437.035956 -395.93266) (xy 437.036392 -395.942724) (xy 437.044128 -395.961307) (xy 437.050942 -395.968728)
			(xy 437.055768 -395.973554) (xy 437.07304 -395.990318) (xy 437.076408 -395.993517) (xy 437.084076 -395.998757)
			(xy 437.08828 -396.000732) (xy 437.096662 -396.004288) (xy 437.106568 -396.004796) (xy 437.137633 -396.006365)
			(xy 437.199014 -396.016432) (xy 437.258607 -396.034252) (xy 437.315438 -396.059536) (xy 437.368575 -396.091868)
			(xy 437.41715 -396.13072) (xy 437.460367 -396.175455) (xy 437.497519 -396.225342) (xy 437.527997 -396.279564)
			(xy 437.551304 -396.337234) (xy 437.567056 -396.397407) (xy 437.574998 -396.459099) (xy 437.574998 -396.5213)
			(xy 437.567057 -396.582992) (xy 437.551304 -396.643165) (xy 437.527998 -396.700835) (xy 437.497519 -396.755057)
			(xy 437.460368 -396.804944) (xy 437.417151 -396.84968) (xy 437.368576 -396.888532) (xy 437.315439 -396.920864)
			(xy 437.258608 -396.946147) (xy 437.199015 -396.963968) (xy 437.137634 -396.974035) (xy 437.106568 -396.975584)
			(xy 437.096662 -396.976092) (xy 437.08828 -396.979648) (xy 437.084076 -396.981623) (xy 437.07641 -396.986866)
			(xy 437.07304 -396.990062) (xy 437.055768 -397.006826) (xy 437.050942 -397.011652) (xy 437.044099 -397.019051)
			(xy 437.036377 -397.03765) (xy 437.035956 -397.04772) (xy 437.035956 -397.232632) (xy 437.036387 -397.242698)
			(xy 437.044115 -397.261289) (xy 437.050942 -397.2687) (xy 437.055768 -397.273526) (xy 437.07304 -397.29029)
			(xy 437.07641 -397.293485) (xy 437.084081 -397.298718) (xy 437.08828 -397.300704) (xy 437.096662 -397.30426)
			(xy 437.106568 -397.304768) (xy 437.137635 -397.306337) (xy 437.199019 -397.316404) (xy 437.258616 -397.334226)
			(xy 437.31545 -397.359511) (xy 437.368591 -397.391845) (xy 437.417168 -397.430698) (xy 437.460388 -397.475436)
			(xy 437.497542 -397.525326) (xy 437.528022 -397.579551) (xy 437.532249 -397.59001) (xy 438.803804 -397.59001)
			(xy 438.807795 -397.527843) (xy 438.819704 -397.466696) (xy 438.839333 -397.407575) (xy 438.866362 -397.351449)
			(xy 438.900346 -397.29924) (xy 438.940728 -397.251805) (xy 438.986844 -397.209924) (xy 439.037936 -397.174284)
			(xy 439.093167 -397.14547) (xy 439.151629 -397.123956) (xy 439.212363 -397.110094) (xy 439.27437 -397.104112)
			(xy 439.336633 -397.106108) (xy 439.39813 -397.116051) (xy 439.457851 -397.133775) (xy 439.514814 -397.158992)
			(xy 439.568085 -397.191285) (xy 439.61679 -397.230125) (xy 439.660127 -397.274875) (xy 439.697387 -397.324799)
			(xy 439.727956 -397.379078) (xy 439.751334 -397.436821) (xy 439.767135 -397.497079) (xy 439.775101 -397.558862)
			(xy 439.7756 -397.59001) (xy 439.775101 -397.621158) (xy 439.767135 -397.682941) (xy 439.751334 -397.743199)
			(xy 439.727956 -397.800942) (xy 439.697387 -397.855221) (xy 439.660127 -397.905145) (xy 439.61679 -397.949895)
			(xy 439.568085 -397.988735) (xy 439.514814 -398.021028) (xy 439.457851 -398.046245) (xy 439.39813 -398.063969)
			(xy 439.336633 -398.073912) (xy 439.27437 -398.075908) (xy 439.212363 -398.069926) (xy 439.151629 -398.056064)
			(xy 439.093167 -398.03455) (xy 439.037936 -398.005736) (xy 438.986844 -397.970096) (xy 438.940728 -397.928215)
			(xy 438.900346 -397.88078) (xy 438.866362 -397.828571) (xy 438.839333 -397.772445) (xy 438.819704 -397.713324)
			(xy 438.807795 -397.652177) (xy 438.803804 -397.59001) (xy 437.532249 -397.59001) (xy 437.55133 -397.637224)
			(xy 437.567084 -397.697401) (xy 437.575026 -397.759096) (xy 437.575026 -397.821301) (xy 437.567084 -397.882997)
			(xy 437.551331 -397.943173) (xy 437.528023 -398.000846) (xy 437.497543 -398.055071) (xy 437.464053 -398.100042)
			(xy 459.541382 -398.100042) (xy 459.545364 -397.972056) (xy 459.557296 -397.844565) (xy 459.57713 -397.718062)
			(xy 459.604791 -397.593037) (xy 459.640171 -397.469974) (xy 459.683133 -397.349348) (xy 459.733511 -397.231627)
			(xy 459.791111 -397.117265) (xy 459.855709 -397.006706) (xy 459.927056 -396.900376) (xy 460.004875 -396.798688)
			(xy 460.088865 -396.702034) (xy 460.178702 -396.610789) (xy 460.274038 -396.525306) (xy 460.374503 -396.445915)
			(xy 460.479711 -396.372923) (xy 460.589252 -396.306614) (xy 460.702704 -396.247243) (xy 460.819628 -396.195039)
			(xy 460.939571 -396.150206) (xy 461.062069 -396.112917) (xy 461.186649 -396.083315) (xy 461.312827 -396.061516)
			(xy 461.440117 -396.047603) (xy 461.568026 -396.041631) (xy 461.696059 -396.043622) (xy 461.82372 -396.05357)
			(xy 461.950516 -396.071434) (xy 462.075955 -396.097147) (xy 462.199554 -396.130609) (xy 462.320833 -396.17169)
			(xy 462.439324 -396.220232) (xy 462.554568 -396.276046) (xy 462.666118 -396.338917) (xy 462.773545 -396.408601)
			(xy 462.876431 -396.484829) (xy 462.974379 -396.567306) (xy 463.06701 -396.655713) (xy 463.153966 -396.749708)
			(xy 463.23491 -396.848927) (xy 463.309529 -396.952986) (xy 463.377534 -397.061483) (xy 463.438662 -397.173998)
			(xy 463.492677 -397.290096) (xy 463.53937 -397.409327) (xy 463.57856 -397.531231) (xy 463.610096 -397.655335)
			(xy 463.633855 -397.781159) (xy 463.649745 -397.908218) (xy 463.657706 -398.036018) (xy 463.658204 -398.100042)
			(xy 463.657706 -398.164066) (xy 463.649745 -398.291866) (xy 463.633855 -398.418925) (xy 463.610096 -398.544749)
			(xy 463.57856 -398.668853) (xy 463.53937 -398.790757) (xy 463.492677 -398.909988) (xy 463.438662 -399.026086)
			(xy 463.377534 -399.138601) (xy 463.309529 -399.247098) (xy 463.23491 -399.351157) (xy 463.153966 -399.450376)
			(xy 463.06701 -399.544371) (xy 462.974379 -399.632778) (xy 462.876431 -399.715255) (xy 462.773545 -399.791483)
			(xy 462.666118 -399.861167) (xy 462.554568 -399.924038) (xy 462.439324 -399.979852) (xy 462.320833 -400.028394)
			(xy 462.199554 -400.069475) (xy 462.075955 -400.102937) (xy 461.950516 -400.12865) (xy 461.82372 -400.146514)
			(xy 461.696059 -400.156462) (xy 461.568026 -400.158453) (xy 461.440117 -400.152481) (xy 461.312827 -400.138568)
			(xy 461.186649 -400.116769) (xy 461.062069 -400.087167) (xy 460.939571 -400.049878) (xy 460.819628 -400.005045)
			(xy 460.702704 -399.952841) (xy 460.589252 -399.89347) (xy 460.479711 -399.827161) (xy 460.374503 -399.754169)
			(xy 460.274038 -399.674778) (xy 460.178702 -399.589295) (xy 460.088865 -399.49805) (xy 460.004875 -399.401396)
			(xy 459.927056 -399.299708) (xy 459.855709 -399.193378) (xy 459.791111 -399.082819) (xy 459.733511 -398.968457)
			(xy 459.683133 -398.850736) (xy 459.640171 -398.73011) (xy 459.604791 -398.607047) (xy 459.57713 -398.482022)
			(xy 459.557296 -398.355519) (xy 459.545364 -398.228028) (xy 459.541382 -398.100042) (xy 437.464053 -398.100042)
			(xy 437.460389 -398.104962) (xy 437.41717 -398.1497) (xy 437.368593 -398.188554) (xy 437.315452 -398.220888)
			(xy 437.258619 -398.246173) (xy 437.199022 -398.263995) (xy 437.137637 -398.274063) (xy 437.106568 -398.275556)
			(xy 437.096662 -398.276064) (xy 437.08828 -398.27962) (xy 437.084075 -398.281594) (xy 437.076408 -398.286835)
			(xy 437.07304 -398.290034) (xy 437.055768 -398.306798) (xy 437.050942 -398.311624) (xy 437.044095 -398.319022)
			(xy 437.036362 -398.33762) (xy 437.035956 -398.347692) (xy 437.035956 -398.890236) (xy 438.803804 -398.890236)
			(xy 438.807795 -398.828069) (xy 438.819704 -398.766922) (xy 438.839333 -398.707801) (xy 438.866362 -398.651675)
			(xy 438.900346 -398.599466) (xy 438.940728 -398.552031) (xy 438.986844 -398.51015) (xy 439.037936 -398.47451)
			(xy 439.093167 -398.445696) (xy 439.151629 -398.424182) (xy 439.212363 -398.41032) (xy 439.27437 -398.404338)
			(xy 439.336633 -398.406334) (xy 439.39813 -398.416277) (xy 439.457851 -398.434001) (xy 439.514814 -398.459218)
			(xy 439.568085 -398.491511) (xy 439.61679 -398.530351) (xy 439.660127 -398.575101) (xy 439.697387 -398.625025)
			(xy 439.727956 -398.679304) (xy 439.751334 -398.737047) (xy 439.767135 -398.797305) (xy 439.775101 -398.859088)
			(xy 439.7756 -398.890236) (xy 439.775101 -398.921384) (xy 439.767135 -398.983167) (xy 439.751334 -399.043425)
			(xy 439.727956 -399.101168) (xy 439.697387 -399.155447) (xy 439.660127 -399.205371) (xy 439.61679 -399.250121)
			(xy 439.568085 -399.288961) (xy 439.514814 -399.321254) (xy 439.457851 -399.346471) (xy 439.39813 -399.364195)
			(xy 439.336633 -399.374138) (xy 439.27437 -399.376134) (xy 439.212363 -399.370152) (xy 439.151629 -399.35629)
			(xy 439.093167 -399.334776) (xy 439.037936 -399.305962) (xy 438.986844 -399.270322) (xy 438.940728 -399.228441)
			(xy 438.900346 -399.181006) (xy 438.866362 -399.128797) (xy 438.839333 -399.072671) (xy 438.819704 -399.01355)
			(xy 438.807795 -398.952403) (xy 438.803804 -398.890236) (xy 437.035956 -398.890236) (xy 437.035956 -399.832576)
			(xy 437.036395 -399.842639) (xy 437.044135 -399.861218) (xy 437.050942 -399.868644) (xy 437.055768 -399.87347)
			(xy 437.07304 -399.890234) (xy 437.076408 -399.893432) (xy 437.084077 -399.898671) (xy 437.08828 -399.900648)
			(xy 437.096662 -399.904204) (xy 437.106568 -399.904712) (xy 437.13763 -399.906281) (xy 437.199004 -399.916348)
			(xy 437.258591 -399.93417) (xy 437.315414 -399.959454) (xy 437.368544 -399.991787) (xy 437.41711 -400.03064)
			(xy 437.460317 -400.075376) (xy 437.497459 -400.125263) (xy 437.527926 -400.179484) (xy 437.55122 -400.237151)
			(xy 437.56696 -400.297321) (xy 437.574889 -400.359009) (xy 437.575452 -400.390106) (xy 437.574932 -400.421903)
			(xy 437.56663 -400.484952) (xy 437.550171 -400.546379) (xy 437.525834 -400.605132) (xy 437.494037 -400.660205)
			(xy 437.455323 -400.710657) (xy 437.410356 -400.755625) (xy 437.368332 -400.78787) (xy 446.249042 -400.78787)
			(xy 446.253113 -400.732248) (xy 446.265239 -400.677811) (xy 446.285162 -400.62572) (xy 446.312458 -400.577085)
			(xy 446.346544 -400.532942) (xy 446.386693 -400.494233) (xy 446.432051 -400.461782) (xy 446.481651 -400.436281)
			(xy 446.534435 -400.418274) (xy 446.589278 -400.408144) (xy 446.645012 -400.406107) (xy 446.700449 -400.412207)
			(xy 446.754406 -400.426313) (xy 446.805735 -400.448125) (xy 446.853341 -400.477179) (xy 446.896209 -400.512854)
			(xy 446.933426 -400.554391) (xy 446.964199 -400.600904) (xy 446.987871 -400.651401) (xy 447.003939 -400.704808)
			(xy 447.012059 -400.759984) (xy 447.012568 -400.78787) (xy 447.012059 -400.815756) (xy 447.003939 -400.870932)
			(xy 446.987871 -400.924339) (xy 446.964199 -400.974836) (xy 446.933426 -401.021349) (xy 446.896209 -401.062886)
			(xy 446.853341 -401.098561) (xy 446.805735 -401.127615) (xy 446.754406 -401.149427) (xy 446.700449 -401.163533)
			(xy 446.645012 -401.169633) (xy 446.589278 -401.167596) (xy 446.534435 -401.157466) (xy 446.481651 -401.139459)
			(xy 446.432051 -401.113958) (xy 446.386693 -401.081507) (xy 446.346544 -401.042798) (xy 446.312458 -400.998655)
			(xy 446.285162 -400.95002) (xy 446.265239 -400.897929) (xy 446.253113 -400.843492) (xy 446.249042 -400.78787)
			(xy 437.368332 -400.78787) (xy 437.359903 -400.794338) (xy 437.30483 -400.826135) (xy 437.246077 -400.850471)
			(xy 437.18465 -400.866931) (xy 437.121601 -400.875232) (xy 437.089804 -400.875754) (xy 437.086756 -400.875754)
			(xy 437.076751 -400.876249) (xy 437.058266 -400.883915) (xy 437.044116 -400.898065) (xy 437.036449 -400.916549)
			(xy 437.035956 -400.926554) (xy 437.035956 -401.15363) (xy 437.036449 -401.163637) (xy 437.044112 -401.182126)
			(xy 437.058262 -401.19628) (xy 437.076749 -401.203949) (xy 437.086756 -401.20443) (xy 437.089804 -401.20443)
			(xy 437.121602 -401.20495) (xy 437.184655 -401.213252) (xy 437.246084 -401.229712) (xy 437.304839 -401.25405)
			(xy 437.359915 -401.285848) (xy 437.41037 -401.324564) (xy 437.455339 -401.369533) (xy 437.494054 -401.419988)
			(xy 437.525852 -401.475064) (xy 437.532113 -401.49018) (xy 438.803804 -401.49018) (xy 438.807795 -401.428013)
			(xy 438.819704 -401.366866) (xy 438.839333 -401.307745) (xy 438.866362 -401.251619) (xy 438.900346 -401.19941)
			(xy 438.940728 -401.151975) (xy 438.986844 -401.110094) (xy 439.037936 -401.074454) (xy 439.093167 -401.04564)
			(xy 439.151629 -401.024126) (xy 439.212363 -401.010264) (xy 439.27437 -401.004282) (xy 439.336633 -401.006278)
			(xy 439.39813 -401.016221) (xy 439.457851 -401.033945) (xy 439.514814 -401.059162) (xy 439.568085 -401.091455)
			(xy 439.61679 -401.130295) (xy 439.660127 -401.175045) (xy 439.697387 -401.224969) (xy 439.727956 -401.279248)
			(xy 439.751334 -401.336991) (xy 439.760066 -401.370292) (xy 448.261484 -401.370292) (xy 448.265555 -401.31467)
			(xy 448.277681 -401.260233) (xy 448.297604 -401.208142) (xy 448.3249 -401.159507) (xy 448.358986 -401.115364)
			(xy 448.399135 -401.076655) (xy 448.444493 -401.044204) (xy 448.494093 -401.018703) (xy 448.546877 -401.000696)
			(xy 448.60172 -400.990566) (xy 448.657454 -400.988529) (xy 448.712891 -400.994629) (xy 448.766848 -401.008735)
			(xy 448.818177 -401.030547) (xy 448.865783 -401.059601) (xy 448.908651 -401.095276) (xy 448.945868 -401.136813)
			(xy 448.976641 -401.183326) (xy 449.000313 -401.233823) (xy 449.016381 -401.28723) (xy 449.024501 -401.342406)
			(xy 449.02501 -401.370292) (xy 449.024501 -401.398178) (xy 449.016381 -401.453354) (xy 449.000313 -401.506761)
			(xy 448.976641 -401.557258) (xy 448.945868 -401.603771) (xy 448.908651 -401.645308) (xy 448.865783 -401.680983)
			(xy 448.818177 -401.710037) (xy 448.766848 -401.731849) (xy 448.712891 -401.745955) (xy 448.657454 -401.752055)
			(xy 448.60172 -401.750018) (xy 448.546877 -401.739888) (xy 448.494093 -401.721881) (xy 448.444493 -401.69638)
			(xy 448.399135 -401.663929) (xy 448.358986 -401.62522) (xy 448.3249 -401.581077) (xy 448.297604 -401.532442)
			(xy 448.277681 -401.480351) (xy 448.265555 -401.425914) (xy 448.261484 -401.370292) (xy 439.760066 -401.370292)
			(xy 439.767135 -401.397249) (xy 439.775101 -401.459032) (xy 439.7756 -401.49018) (xy 439.775101 -401.521328)
			(xy 439.767135 -401.583111) (xy 439.751334 -401.643369) (xy 439.727956 -401.701112) (xy 439.697387 -401.755391)
			(xy 439.660127 -401.805315) (xy 439.61679 -401.850065) (xy 439.568085 -401.888905) (xy 439.514814 -401.921198)
			(xy 439.457851 -401.946415) (xy 439.39813 -401.964139) (xy 439.336633 -401.974082) (xy 439.27437 -401.976078)
			(xy 439.212363 -401.970096) (xy 439.151629 -401.956234) (xy 439.093167 -401.93472) (xy 439.037936 -401.905906)
			(xy 438.986844 -401.870266) (xy 438.940728 -401.828385) (xy 438.900346 -401.78095) (xy 438.866362 -401.728741)
			(xy 438.839333 -401.672615) (xy 438.819704 -401.613494) (xy 438.807795 -401.552347) (xy 438.803804 -401.49018)
			(xy 437.532113 -401.49018) (xy 437.550189 -401.53382) (xy 437.566649 -401.595249) (xy 437.57495 -401.658302)
			(xy 437.57495 -401.721898) (xy 437.566649 -401.784951) (xy 437.550189 -401.84638) (xy 437.525852 -401.905136)
			(xy 437.494054 -401.960212) (xy 437.455339 -402.010667) (xy 437.41037 -402.055636) (xy 437.359915 -402.094352)
			(xy 437.304839 -402.12615) (xy 437.246084 -402.150488) (xy 437.184655 -402.166948) (xy 437.121602 -402.17525)
			(xy 437.089804 -402.175726) (xy 437.089042 -402.175726) (xy 437.058882 -402.175318) (xy 436.999017 -402.167928)
			(xy 436.969662 -402.160994) (xy 436.96636 -402.160486) (xy 436.958994 -402.159978) (xy 436.956962 -402.159978)
			(xy 436.947049 -402.187465) (xy 436.924428 -402.241348) (xy 436.91175 -402.267674) (xy 436.906924 -402.284438)
			(xy 436.903494 -402.310643) (xy 436.89034 -402.361828) (xy 436.870253 -402.410711) (xy 436.843618 -402.456356)
			(xy 436.810942 -402.497893) (xy 436.772851 -402.534527) (xy 436.730073 -402.565559) (xy 436.683424 -402.590395)
			(xy 436.658766 -402.599906) (xy 436.653432 -402.602192) (xy 436.465348 -402.790152) (xy 438.803804 -402.790152)
			(xy 438.807795 -402.727985) (xy 438.819704 -402.666838) (xy 438.839333 -402.607717) (xy 438.866362 -402.551591)
			(xy 438.900346 -402.499382) (xy 438.940728 -402.451947) (xy 438.986844 -402.410066) (xy 439.037936 -402.374426)
			(xy 439.093167 -402.345612) (xy 439.151629 -402.324098) (xy 439.212363 -402.310236) (xy 439.27437 -402.304254)
			(xy 439.336633 -402.30625) (xy 439.39813 -402.316193) (xy 439.457851 -402.333917) (xy 439.514814 -402.359134)
			(xy 439.568085 -402.391427) (xy 439.61679 -402.430267) (xy 439.660127 -402.475017) (xy 439.697387 -402.524941)
			(xy 439.727956 -402.57922) (xy 439.751334 -402.636963) (xy 439.767135 -402.697221) (xy 439.775101 -402.759004)
			(xy 439.7756 -402.790152) (xy 439.775101 -402.8213) (xy 439.767135 -402.883083) (xy 439.751334 -402.943341)
			(xy 439.727956 -403.001084) (xy 439.697387 -403.055363) (xy 439.660127 -403.105287) (xy 439.61679 -403.150037)
			(xy 439.568085 -403.188877) (xy 439.514814 -403.22117) (xy 439.457851 -403.246387) (xy 439.39813 -403.264111)
			(xy 439.336633 -403.274054) (xy 439.27437 -403.27605) (xy 439.212363 -403.270068) (xy 439.151629 -403.256206)
			(xy 439.093167 -403.234692) (xy 439.037936 -403.205878) (xy 438.986844 -403.170238) (xy 438.940728 -403.128357)
			(xy 438.900346 -403.080922) (xy 438.866362 -403.028713) (xy 438.839333 -402.972587) (xy 438.819704 -402.913466)
			(xy 438.807795 -402.852319) (xy 438.803804 -402.790152) (xy 436.465348 -402.790152) (xy 436.26913 -402.98624)
			(xy 436.236232 -403.018426) (xy 436.165461 -403.077273) (xy 436.089567 -403.129347) (xy 436.009196 -403.174205)
			(xy 435.925034 -403.211465) (xy 435.837796 -403.240809) (xy 435.793134 -403.251924) (xy 435.760622 -403.276562)
			(xy 435.738678 -403.314829) (xy 435.689007 -403.387736) (xy 435.63309 -403.455971) (xy 435.571365 -403.519)
			(xy 435.504315 -403.576331) (xy 435.432463 -403.627517) (xy 435.356371 -403.672155) (xy 435.276633 -403.709899)
			(xy 435.193874 -403.740453) (xy 435.108739 -403.763577) (xy 435.021895 -403.779092) (xy 434.93402 -403.786876)
			(xy 434.88991 -403.787356) (xy 434.889148 -403.787356) (xy 434.846161 -403.786884) (xy 434.76051 -403.779438)
			(xy 434.675818 -403.764642) (xy 434.592716 -403.742604) (xy 434.511822 -403.713488) (xy 434.472588 -403.695916)
			(xy 434.46954 -403.69617) (xy 434.446921 -403.704803) (xy 434.400048 -403.716928) (xy 434.352016 -403.723014)
			(xy 434.327808 -403.723348) (xy 434.327554 -403.723348) (xy 434.300313 -403.722845) (xy 434.24639 -403.715061)
			(xy 434.194122 -403.699685) (xy 434.144574 -403.67703) (xy 434.098751 -403.647558) (xy 434.057587 -403.611867)
			(xy 434.021919 -403.570684) (xy 433.992471 -403.524845) (xy 433.969843 -403.475284) (xy 433.954495 -403.423008)
			(xy 433.94674 -403.369081) (xy 433.9463 -403.34184) (xy 433.9463 -403.341332) (xy 433.946636 -403.316947)
			(xy 433.95276 -403.268564) (xy 433.965014 -403.22136) (xy 433.973732 -403.198584) (xy 433.975764 -403.188932)
			(xy 433.959722 -403.151161) (xy 433.933169 -403.073507) (xy 433.913094 -402.993932) (xy 433.899633 -402.912976)
			(xy 433.892877 -402.831186) (xy 433.892452 -402.790152) (xy 433.892452 -402.408136) (xy 433.892927 -402.365147)
			(xy 433.900371 -402.27949) (xy 433.915155 -402.194792) (xy 433.925726 -402.15312) (xy 433.927504 -402.140166)
			(xy 433.925726 -402.127212) (xy 433.92217 -402.113242) (xy 433.918883 -402.102101) (xy 433.904061 -402.084249)
			(xy 433.893722 -402.078952) (xy 433.865274 -402.066252) (xy 433.860376 -402.06422) (xy 433.850001 -402.06204)
			(xy 433.8447 -402.061934) (xy 433.821332 -402.067522) (xy 433.784995 -402.085811) (xy 433.709892 -402.117085)
			(xy 433.632487 -402.142128) (xy 433.592986 -402.15185) (xy 433.560474 -402.176488) (xy 433.538542 -402.214769)
			(xy 433.488889 -402.287703) (xy 433.432986 -402.355966) (xy 433.371271 -402.419021) (xy 433.304225 -402.476377)
			(xy 433.232373 -402.527584) (xy 433.156278 -402.572243) (xy 433.076535 -402.610002) (xy 432.993767 -402.640568)
			(xy 432.908622 -402.663702) (xy 432.821766 -402.679221) (xy 432.733878 -402.687005) (xy 432.689762 -402.687536)
			(xy 432.649172 -402.687116) (xy 432.568262 -402.680498) (xy 432.488158 -402.667324) (xy 432.409389 -402.647683)
			(xy 432.332478 -402.621704) (xy 432.295046 -402.606002) (xy 432.273202 -402.596604) (xy 432.271932 -402.596858)
			(xy 432.263804 -402.598382) (xy 432.259486 -402.599906) (xy 432.253644 -402.601938) (xy 431.869088 -402.98624)
			(xy 431.836191 -403.018427) (xy 431.765421 -403.077279) (xy 431.689529 -403.129357) (xy 431.60916 -403.17422)
			(xy 431.524998 -403.211484) (xy 431.43776 -403.240834) (xy 431.393092 -403.251924) (xy 431.36058 -403.276562)
			(xy 431.338637 -403.31483) (xy 431.288966 -403.387741) (xy 431.233051 -403.455979) (xy 431.171327 -403.519012)
			(xy 431.104277 -403.576347) (xy 431.032426 -403.627536) (xy 430.956334 -403.672179) (xy 430.876596 -403.709928)
			(xy 430.793836 -403.740486) (xy 430.708701 -403.763615) (xy 430.621855 -403.779135) (xy 430.533979 -403.786924)
			(xy 430.489868 -403.787356) (xy 430.489106 -403.787356) (xy 430.446068 -403.786906) (xy 430.360311 -403.779491)
			(xy 430.275513 -403.764706) (xy 430.192307 -403.742663) (xy 430.111312 -403.713525) (xy 430.072038 -403.695916)
			(xy 430.06391 -403.698202) (xy 430.031941 -403.709621) (xy 429.965252 -403.722267) (xy 429.931322 -403.723348)
			(xy 429.925734 -403.723348) (xy 429.898578 -403.722722) (xy 429.844852 -403.714728) (xy 429.792802 -403.699195)
			(xy 429.743482 -403.676437) (xy 429.697887 -403.646915) (xy 429.65694 -403.611226) (xy 429.621468 -403.57009)
			(xy 429.592189 -403.524339) (xy 429.569693 -403.474898) (xy 429.554437 -403.422767) (xy 429.546728 -403.368999)
			(xy 429.546258 -403.34184) (xy 429.546258 -403.340824) (xy 429.546258 -403.340316) (xy 429.546668 -403.317048)
			(xy 429.552464 -403.270872) (xy 429.56385 -403.225749) (xy 429.571912 -403.203918) (xy 429.575468 -403.194774)
			(xy 429.575468 -403.18817) (xy 429.559534 -403.150504) (xy 429.53316 -403.07308) (xy 429.513211 -402.993758)
			(xy 429.499822 -402.91307) (xy 429.493082 -402.831556) (xy 429.492664 -402.79066) (xy 429.492664 -402.407374)
			(xy 429.493132 -402.364517) (xy 429.500507 -402.279121) (xy 429.515181 -402.194672) (xy 429.525684 -402.15312)
			(xy 429.527462 -402.140166) (xy 429.525684 -402.127212) (xy 429.522128 -402.113242) (xy 429.518752 -402.102247)
			(xy 429.504118 -402.084545) (xy 429.493934 -402.079206) (xy 429.465486 -402.066506) (xy 429.460477 -402.064382)
			(xy 429.449843 -402.062086) (xy 429.444404 -402.061934) (xy 429.421036 -402.067522) (xy 429.384773 -402.085777)
			(xy 429.309835 -402.11703) (xy 429.232608 -402.142095) (xy 429.193198 -402.15185) (xy 429.160686 -402.176488)
			(xy 429.138754 -402.214769) (xy 429.089102 -402.287704) (xy 429.033199 -402.355967) (xy 428.971484 -402.419024)
			(xy 428.904438 -402.47638) (xy 428.832586 -402.527588) (xy 428.756491 -402.572248) (xy 428.676748 -402.610008)
			(xy 428.59398 -402.640575) (xy 428.508834 -402.663709) (xy 428.421978 -402.67923) (xy 428.33409 -402.687015)
			(xy 428.289974 -402.687536) (xy 428.249379 -402.687095) (xy 428.168462 -402.680431) (xy 428.088355 -402.667207)
			(xy 428.009589 -402.647511) (xy 427.932687 -402.621472) (xy 427.895258 -402.605748) (xy 427.89475 -402.605748)
			(xy 427.873414 -402.596604) (xy 427.872144 -402.596858) (xy 427.864016 -402.598382) (xy 427.859698 -402.599906)
			(xy 427.853348 -402.602192) (xy 427.469046 -402.98624) (xy 427.436148 -403.018426) (xy 427.365377 -403.077274)
			(xy 427.289484 -403.12935) (xy 427.209114 -403.174209) (xy 427.124952 -403.21147) (xy 427.037713 -403.240816)
			(xy 426.99305 -403.251924) (xy 426.960538 -403.276562) (xy 426.938594 -403.314829) (xy 426.888923 -403.387737)
			(xy 426.833007 -403.455973) (xy 426.771282 -403.519003) (xy 426.704232 -403.576336) (xy 426.63238 -403.627522)
			(xy 426.556288 -403.672162) (xy 426.476551 -403.709907) (xy 426.393791 -403.740462) (xy 426.308656 -403.763588)
			(xy 426.221812 -403.779104) (xy 426.133936 -403.786889) (xy 426.089826 -403.787356) (xy 426.089064 -403.787356)
			(xy 426.046077 -403.786885) (xy 425.960425 -403.77944) (xy 425.875733 -403.764645) (xy 425.792631 -403.742608)
			(xy 425.711736 -403.713494) (xy 425.672504 -403.695916) (xy 425.669456 -403.69617) (xy 425.646916 -403.704772)
			(xy 425.600212 -403.716864) (xy 425.552354 -403.722962) (xy 425.528232 -403.723348) (xy 425.527724 -403.723348)
			(xy 425.500471 -403.722864) (xy 425.446518 -403.71511) (xy 425.394218 -403.699758) (xy 425.344635 -403.677118)
			(xy 425.298779 -403.647654) (xy 425.257583 -403.611963) (xy 425.221885 -403.570772) (xy 425.192412 -403.524921)
			(xy 425.169765 -403.475342) (xy 425.154403 -403.423044) (xy 425.146641 -403.369093) (xy 425.146216 -403.34184)
			(xy 425.146216 -403.341332) (xy 425.146552 -403.316947) (xy 425.152676 -403.268564) (xy 425.164931 -403.221361)
			(xy 425.173648 -403.198584) (xy 425.17568 -403.188932) (xy 425.159638 -403.151161) (xy 425.133084 -403.073508)
			(xy 425.113009 -402.993933) (xy 425.099547 -402.912976) (xy 425.092792 -402.831186) (xy 425.092368 -402.790152)
			(xy 425.092368 -402.408136) (xy 425.092843 -402.365147) (xy 425.100287 -402.279491) (xy 425.115072 -402.194792)
			(xy 425.125642 -402.15312) (xy 425.12742 -402.140166) (xy 425.125642 -402.127212) (xy 425.122086 -402.113242)
			(xy 425.118707 -402.102251) (xy 425.104068 -402.084559) (xy 425.093892 -402.079206) (xy 425.065444 -402.066506)
			(xy 425.060436 -402.064376) (xy 425.049803 -402.062068) (xy 425.044362 -402.061934) (xy 425.020994 -402.067522)
			(xy 424.98473 -402.085775) (xy 424.909792 -402.117026) (xy 424.832564 -402.142088) (xy 424.793156 -402.15185)
			(xy 424.760644 -402.176488) (xy 424.738712 -402.214771) (xy 424.689061 -402.287709) (xy 424.63316 -402.355975)
			(xy 424.571445 -402.419035) (xy 424.5044 -402.476396) (xy 424.432549 -402.527608) (xy 424.356454 -402.572272)
			(xy 424.276711 -402.610037) (xy 424.193942 -402.640608) (xy 424.108796 -402.663747) (xy 424.021939 -402.679273)
			(xy 423.934049 -402.687063) (xy 423.889932 -402.687536) (xy 423.849337 -402.687093) (xy 423.768421 -402.680426)
			(xy 423.688315 -402.667199) (xy 423.609551 -402.6475) (xy 423.532651 -402.621458) (xy 423.495216 -402.605748)
			(xy 423.494708 -402.605748) (xy 423.473372 -402.596604) (xy 423.472102 -402.596858) (xy 423.463974 -402.598382)
			(xy 423.459656 -402.599906) (xy 423.453306 -402.602192) (xy 423.069004 -402.98624) (xy 423.036106 -403.018425)
			(xy 422.965333 -403.07727) (xy 422.889439 -403.129343) (xy 422.809068 -403.174199) (xy 422.724905 -403.211456)
			(xy 422.637667 -403.240799) (xy 422.593008 -403.251924) (xy 422.560496 -403.276562) (xy 422.538552 -403.314828)
			(xy 422.48888 -403.387734) (xy 422.432963 -403.455967) (xy 422.371238 -403.518995) (xy 422.304187 -403.576324)
			(xy 422.232335 -403.627508) (xy 422.156243 -403.672145) (xy 422.076505 -403.709886) (xy 421.993746 -403.740438)
			(xy 421.908612 -403.76356) (xy 421.821768 -403.779073) (xy 421.733893 -403.786855) (xy 421.689784 -403.787356)
			(xy 421.689022 -403.787356) (xy 421.646009 -403.786895) (xy 421.560305 -403.779464) (xy 421.475561 -403.764673)
			(xy 421.392407 -403.742632) (xy 421.311463 -403.713505) (xy 421.272208 -403.695916) (xy 421.263826 -403.698202)
			(xy 421.231857 -403.709622) (xy 421.165168 -403.722271) (xy 421.131238 -403.723348) (xy 421.12565 -403.723348)
			(xy 421.098493 -403.722723) (xy 421.044765 -403.714731) (xy 420.992714 -403.699199) (xy 420.943391 -403.676443)
			(xy 420.897795 -403.646921) (xy 420.856846 -403.611231) (xy 420.821372 -403.570095) (xy 420.792091 -403.524343)
			(xy 420.769595 -403.474901) (xy 420.754338 -403.422769) (xy 420.746628 -403.369) (xy 420.746174 -403.34184)
			(xy 420.746174 -403.340824) (xy 420.746174 -403.340316) (xy 420.746584 -403.317048) (xy 420.752381 -403.270873)
			(xy 420.763767 -403.225749) (xy 420.771828 -403.203918) (xy 420.775384 -403.194774) (xy 420.775384 -403.18817)
			(xy 420.75945 -403.150504) (xy 420.733075 -403.073081) (xy 420.713126 -402.993758) (xy 420.699737 -402.91307)
			(xy 420.692996 -402.831556) (xy 420.69258 -402.79066) (xy 420.69258 -402.407374) (xy 420.693048 -402.364517)
			(xy 420.700423 -402.279121) (xy 420.715097 -402.194673) (xy 420.7256 -402.15312) (xy 420.727378 -402.140166)
			(xy 420.7256 -402.127212) (xy 420.722044 -402.113242) (xy 420.718662 -402.102254) (xy 420.704018 -402.084572)
			(xy 420.69385 -402.079206) (xy 420.665402 -402.066506) (xy 420.660393 -402.06438) (xy 420.64976 -402.062081)
			(xy 420.64432 -402.061934) (xy 420.620952 -402.067522) (xy 420.584689 -402.085777) (xy 420.509752 -402.117032)
			(xy 420.432524 -402.142098) (xy 420.393114 -402.15185) (xy 420.360602 -402.176488) (xy 420.33867 -402.214769)
			(xy 420.289018 -402.287706) (xy 420.233116 -402.355969) (xy 420.171401 -402.419027) (xy 420.104355 -402.476385)
			(xy 420.032504 -402.527594) (xy 419.956409 -402.572254) (xy 419.876665 -402.610016) (xy 419.793897 -402.640584)
			(xy 419.708751 -402.66372) (xy 419.621895 -402.679242) (xy 419.534006 -402.687028) (xy 419.48989 -402.687536)
			(xy 419.446965 -402.687091) (xy 419.361431 -402.679717) (xy 419.276848 -402.665015) (xy 419.193843 -402.643095)
			(xy 419.11303 -402.614119) (xy 419.073838 -402.596604) (xy 419.07206 -402.596858) (xy 419.063932 -402.598382)
			(xy 419.059614 -402.599906) (xy 419.027949 -402.610803) (xy 418.96203 -402.622564) (xy 418.92855 -402.623274)
			(xy 418.927788 -402.623274) (xy 418.900697 -402.622799) (xy 418.84706 -402.615133) (xy 418.795047 -402.599956)
			(xy 418.745704 -402.577575) (xy 418.700023 -402.548439) (xy 418.658923 -402.513133) (xy 418.62323 -402.472369)
			(xy 418.593663 -402.426966) (xy 418.570816 -402.377837) (xy 418.555148 -402.32597) (xy 418.546975 -402.272408)
			(xy 418.54628 -402.245322) (xy 418.54628 -402.241512) (xy 418.546671 -402.217121) (xy 418.55289 -402.168736)
			(xy 418.565218 -402.121536) (xy 418.573966 -402.098764) (xy 418.575744 -402.090128) (xy 418.575998 -402.089112)
			(xy 418.559934 -402.051318) (xy 418.533333 -401.973617) (xy 418.513205 -401.893994) (xy 418.499686 -401.812986)
			(xy 418.492867 -401.731142) (xy 418.492432 -401.690078) (xy 418.492432 -401.308062) (xy 418.492906 -401.265073)
			(xy 418.500348 -401.179416) (xy 418.515132 -401.094717) (xy 418.525706 -401.053046) (xy 418.527484 -401.040092)
			(xy 418.525706 -401.027138) (xy 418.515127 -400.985467) (xy 418.500336 -400.900769) (xy 418.492894 -400.815112)
			(xy 418.492432 -400.772122) (xy 418.492432 -400.390106) (xy 418.492868 -400.349041) (xy 418.499662 -400.267193)
			(xy 418.513171 -400.186182) (xy 418.533303 -400.106558) (xy 418.559921 -400.028861) (xy 418.575998 -399.991072)
			(xy 418.575744 -399.99031) (xy 418.573966 -399.98142) (xy 418.565375 -399.959132) (xy 418.553179 -399.912947)
			(xy 418.546848 -399.8656) (xy 418.54628 -399.84172) (xy 418.54628 -399.834862) (xy 418.547005 -399.807787)
			(xy 418.555161 -399.754243) (xy 418.570807 -399.702392) (xy 418.593629 -399.653273) (xy 418.623167 -399.607876)
			(xy 418.658829 -399.567112) (xy 418.699897 -399.531802) (xy 418.745546 -399.502654) (xy 418.794858 -399.480254)
			(xy 418.846842 -399.465053) (xy 418.900454 -399.457356) (xy 418.927534 -399.45691) (xy 418.928042 -399.45691)
			(xy 418.93998 -399.457164) (xy 418.947092 -399.457418) (xy 418.961316 -399.453862) (xy 418.967412 -399.450052)
			(xy 418.973322 -399.446183) (xy 418.982968 -399.435873) (xy 418.986462 -399.429732) (xy 418.986716 -399.429478)
			(xy 418.990752 -399.420784) (xy 418.992705 -399.401729) (xy 418.990526 -399.392394) (xy 418.987224 -399.381218)
			(xy 418.984176 -399.375884) (xy 418.966409 -399.34317) (xy 418.93842 -399.274187) (xy 418.919469 -399.202195)
			(xy 418.909867 -399.128372) (xy 418.909246 -399.09115) (xy 418.909641 -399.058326) (xy 418.916929 -398.993087)
			(xy 418.931531 -398.929086) (xy 418.95326 -398.867141) (xy 418.98184 -398.808043) (xy 419.016904 -398.752546)
			(xy 419.058006 -398.70136) (xy 419.10462 -398.655138) (xy 419.156151 -398.61447) (xy 419.211941 -398.579876)
			(xy 419.271279 -398.551797) (xy 419.302184 -398.540732) (xy 419.302438 -398.540732) (xy 419.312234 -398.536814)
			(xy 419.32775 -398.52255) (xy 419.336246 -398.503263) (xy 419.336728 -398.492726) (xy 419.336728 -398.453864)
			(xy 419.336234 -398.443859) (xy 419.328569 -398.425375) (xy 419.314419 -398.411226) (xy 419.295933 -398.403564)
			(xy 419.285928 -398.403064) (xy 419.13175 -398.403064) (xy 419.121572 -398.402647) (xy 419.102759 -398.394871)
			(xy 419.088358 -398.380484) (xy 419.080563 -398.36168) (xy 419.080188 -398.351502) (xy 419.080188 -398.062958)
			(xy 419.079755 -398.057393) (xy 419.076816 -398.046627) (xy 419.074346 -398.041622) (xy 419.05772 -398.013053)
			(xy 419.031499 -397.952377) (xy 419.013747 -397.888707) (xy 419.00479 -397.823217) (xy 419.004794 -397.757118)
			(xy 419.01376 -397.69163) (xy 419.031521 -397.627961) (xy 419.05775 -397.567289) (xy 419.074346 -397.538702)
			(xy 419.076844 -397.533706) (xy 419.079802 -397.522938) (xy 419.080188 -397.517366) (xy 419.080188 -396.762986)
			(xy 419.079748 -396.757423) (xy 419.076796 -396.746664) (xy 419.074346 -396.74165) (xy 419.057727 -396.713078)
			(xy 419.031517 -396.652398) (xy 419.013766 -396.588727) (xy 419.004802 -396.523239) (xy 419.004242 -396.49019)
			(xy 419.004335 -396.475869) (xy 419.005988 -396.447276) (xy 419.007544 -396.43304) (xy 419.007544 -396.432532)
			(xy 419.008208 -396.42219) (xy 419.002189 -396.402382) (xy 418.99586 -396.394178) (xy 418.984684 -396.380716)
			(xy 418.984176 -396.380208) (xy 418.948108 -396.33779) (xy 418.9476 -396.337282) (xy 418.940488 -396.329154)
			(xy 418.9222 -396.320264) (xy 418.911532 -396.319756) (xy 418.885035 -396.318169) (xy 418.832827 -396.308583)
			(xy 418.78245 -396.291857) (xy 418.734876 -396.268314) (xy 418.691021 -396.238408) (xy 418.651732 -396.202716)
			(xy 418.634418 -396.182596) (xy 418.631624 -396.179548) (xy 418.628322 -396.176246) (xy 418.625744 -396.173739)
			(xy 418.620007 -396.169407) (xy 418.616892 -396.16761) (xy 418.59454 -396.156688) (xy 418.5897 -396.154687)
			(xy 418.579456 -396.152513) (xy 418.57422 -396.15237) (xy 418.1475 -396.15237) (xy 418.138982 -396.152052)
			(xy 418.122883 -396.14648) (xy 418.116004 -396.141448) (xy 414.16605 -393.008866) (xy 414.15589 -393.002516)
			(xy 413.224218 -392.569446) (xy 413.183452 -392.549944) (xy 413.105277 -392.504599) (xy 413.031526 -392.452366)
			(xy 412.962804 -392.393672) (xy 412.899676 -392.329) (xy 412.84266 -392.258881) (xy 412.792223 -392.18389)
			(xy 412.770066 -392.144504) (xy 412.53918 -391.72388) (xy 412.536634 -391.719531) (xy 412.530108 -391.711854)
			(xy 412.526226 -391.70864) (xy 410.86024 -390.387078) (xy 410.853463 -390.381203) (xy 410.844223 -390.365845)
			(xy 410.842206 -390.357106) (xy 410.842206 -390.356852) (xy 410.298646 -387.64337) (xy 410.297798 -387.639589)
			(xy 410.295119 -387.632319) (xy 410.293312 -387.628892) (xy 410.104844 -387.284722) (xy 410.068014 -387.272022)
			(xy 410.054552 -387.27761) (xy 410.054044 -387.27761) (xy 410.030084 -387.28748) (xy 409.980166 -387.301387)
			(xy 409.928824 -387.308406) (xy 409.902914 -387.308852) (xy 409.90266 -387.308852) (xy 409.875373 -387.308363)
			(xy 409.821356 -387.300591) (xy 409.768995 -387.285213) (xy 409.719354 -387.26254) (xy 409.673445 -387.233034)
			(xy 409.632202 -387.197295) (xy 409.596464 -387.156052) (xy 409.566958 -387.110142) (xy 409.544286 -387.060502)
			(xy 409.528908 -387.00814) (xy 409.521137 -386.954123) (xy 409.520644 -386.926836) (xy 409.521152 -386.89856)
			(xy 409.529483 -386.842625) (xy 409.545969 -386.788529) (xy 409.570248 -386.737454) (xy 409.601791 -386.690516)
			(xy 409.639909 -386.64874) (xy 409.683768 -386.61304) (xy 409.732411 -386.584195) (xy 409.758388 -386.573014)
			(xy 409.775152 -386.566156) (xy 409.79217 -386.535422) (xy 409.74264 -386.235448) (xy 409.736036 -386.221732)
			(xy 409.733496 -386.219192) (xy 409.713322 -386.197693) (xy 409.679174 -386.149634) (xy 409.652825 -386.096895)
			(xy 409.634903 -386.040731) (xy 409.625834 -385.982477) (xy 409.625292 -385.953) (xy 409.62537 -385.940262)
			(xy 409.627024 -385.914841) (xy 409.628594 -385.9022) (xy 409.632924 -385.873825) (xy 409.64899 -385.818723)
			(xy 409.660598 -385.792472) (xy 409.663537 -385.785433) (xy 409.665593 -385.770326) (xy 409.664662 -385.762754)
			(xy 409.327096 -383.719832) (xy 409.323777 -383.698915) (xy 409.318698 -383.656863) (xy 409.316936 -383.635758)
			(xy 409.20035 -382.159256) (xy 409.199588 -382.15316) (xy 409.120594 -381.758698) (xy 407.04135 -371.372638)
			(xy 407.029666 -371.35562) (xy 407.02357 -371.35181) (xy 406.997363 -371.334713) (xy 406.949699 -371.294174)
			(xy 406.908362 -371.247201) (xy 406.874211 -371.19477) (xy 406.847958 -371.137972) (xy 406.830147 -371.077988)
			(xy 406.821149 -371.016066) (xy 406.820624 -370.98478) (xy 406.820624 -370.984526) (xy 406.821181 -370.952027)
			(xy 406.830841 -370.887751) (xy 406.849994 -370.82564) (xy 406.87821 -370.767087) (xy 406.896062 -370.739924)
			(xy 406.901904 -370.731288) (xy 406.905968 -370.711222) (xy 406.826466 -370.327428) (xy 406.831546 -370.326412)
			(xy 406.662128 -369.480592) (xy 406.653746 -369.466622) (xy 406.64765 -369.461034) (xy 406.627678 -369.442805)
			(xy 406.592557 -369.401691) (xy 406.56358 -369.356039) (xy 406.541322 -369.306759) (xy 406.526229 -369.254836)
			(xy 406.518602 -369.201304) (xy 406.51811 -369.174268) (xy 406.518635 -369.145375) (xy 406.527329 -369.088248)
			(xy 406.544528 -369.033082) (xy 406.556718 -369.006882) (xy 406.560274 -368.99977) (xy 406.56256 -368.98326)
			(xy 406.49144 -368.62766) (xy 406.458674 -368.464084) (xy 406.436068 -368.44224) (xy 406.428956 -368.44097)
			(xy 406.402113 -368.436528) (xy 406.349959 -368.421036) (xy 406.300533 -368.398296) (xy 406.254835 -368.368769)
			(xy 406.213793 -368.333054) (xy 406.178238 -368.291872) (xy 406.148889 -368.24606) (xy 406.126342 -368.196546)
			(xy 406.111053 -368.144331) (xy 406.103333 -368.090475) (xy 406.10282 -368.063272) (xy 406.103308 -368.035355)
			(xy 406.111451 -367.980118) (xy 406.127559 -367.926658) (xy 406.151287 -367.876116) (xy 406.182129 -367.829574)
			(xy 406.219426 -367.788024) (xy 406.262381 -367.752354) (xy 406.285954 -367.73739) (xy 406.28697 -367.736882)
			(xy 406.294082 -367.73231) (xy 406.306274 -367.703354) (xy 406.131014 -366.828578) (xy 406.094438 -366.644936)
			(xy 406.091972 -366.635073) (xy 406.080523 -366.618293) (xy 406.063469 -366.607255) (xy 406.053544 -366.605058)
			(xy 405.96058 -366.58804) (xy 405.950536 -366.586705) (xy 405.930779 -366.591122) (xy 405.914241 -366.6028)
			(xy 405.90851 -366.611154) (xy 405.893482 -366.634356) (xy 405.857793 -366.676571) (xy 405.816384 -366.713192)
			(xy 405.770123 -366.743453) (xy 405.719979 -366.76672) (xy 405.667001 -366.782506) (xy 405.6123 -366.790479)
			(xy 405.58466 -366.790986) (xy 405.557412 -366.790497) (xy 405.503472 -366.782736) (xy 405.451185 -366.767379)
			(xy 405.401616 -366.744737) (xy 405.355773 -366.715271) (xy 405.31459 -366.679582) (xy 405.278905 -366.638395)
			(xy 405.249444 -366.592549) (xy 405.226807 -366.542977) (xy 405.211455 -366.490689) (xy 405.2037 -366.436748)
			(xy 405.2037 -366.382252) (xy 405.211455 -366.328311) (xy 405.226807 -366.276023) (xy 405.249444 -366.226451)
			(xy 405.278905 -366.180605) (xy 405.31459 -366.139418) (xy 405.355773 -366.103729) (xy 405.401616 -366.074263)
			(xy 405.451185 -366.051621) (xy 405.503472 -366.036264) (xy 405.557412 -366.028503) (xy 405.58466 -366.02797)
			(xy 405.584914 -366.02797) (xy 405.614392 -366.028548) (xy 405.672639 -366.037663) (xy 405.728796 -366.055615)
			(xy 405.781531 -366.081976) (xy 405.805894 -366.098582) (xy 405.835358 -366.10798) (xy 405.842692 -366.107775)
			(xy 405.85676 -366.103639) (xy 405.863044 -366.099852) (xy 405.942292 -366.048544) (xy 405.95057 -366.042662)
			(xy 405.96199 -366.02589) (xy 405.96598 -366.005996) (xy 405.96439 -365.995966) (xy 405.186134 -362.10875)
			(xy 405.186134 -362.107988) (xy 403.660864 -355.089714) (xy 403.659166 -355.082916) (xy 403.652586 -355.07055)
			(xy 403.64791 -355.06533) (xy 403.643084 -355.06025) (xy 403.6314 -355.053392) (xy 403.624288 -355.05136)
			(xy 403.594072 -355.042493) (xy 403.537426 -355.015004) (xy 403.511766 -354.99675) (xy 403.506686 -354.993448)
			(xy 403.497034 -354.98786) (xy 403.491964 -354.986054) (xy 403.481332 -354.984396) (xy 403.475952 -354.984558)
			(xy 403.475444 -354.984558) (xy 403.4536 -354.986082) (xy 403.448936 -354.986493) (xy 403.439859 -354.988787)
			(xy 403.435566 -354.990654) (xy 403.41169 -355.001576) (xy 403.408134 -355.004878) (xy 403.386608 -355.025178)
			(xy 403.338452 -355.059553) (xy 403.285567 -355.086081) (xy 403.22922 -355.104127) (xy 403.170763 -355.113258)
			(xy 403.14118 -355.113844) (xy 402.27758 -355.113844) (xy 402.250313 -355.113356) (xy 402.196334 -355.105593)
			(xy 402.144009 -355.090226) (xy 402.094404 -355.06757) (xy 402.048528 -355.038085) (xy 402.007314 -355.002371)
			(xy 401.971603 -354.961156) (xy 401.94212 -354.915278) (xy 401.919467 -354.865672) (xy 401.904103 -354.813346)
			(xy 401.896342 -354.759367) (xy 401.896342 -354.704833) (xy 401.904103 -354.650854) (xy 401.919467 -354.598528)
			(xy 401.94212 -354.548922) (xy 401.971603 -354.503044) (xy 402.007314 -354.461829) (xy 402.048528 -354.426115)
			(xy 402.094404 -354.39663) (xy 402.144009 -354.373974) (xy 402.196334 -354.358607) (xy 402.250313 -354.350844)
			(xy 402.27758 -354.35032) (xy 403.14118 -354.35032) (xy 403.170765 -354.350876) (xy 403.229226 -354.360008)
			(xy 403.285575 -354.378058) (xy 403.338462 -354.404592) (xy 403.386618 -354.438973) (xy 403.408134 -354.459286)
			(xy 403.41169 -354.462588) (xy 403.435566 -354.47351) (xy 403.439855 -354.475392) (xy 403.448933 -354.477693)
			(xy 403.4536 -354.478082) (xy 403.461982 -354.478844) (xy 403.473771 -354.478954) (xy 403.495481 -354.469829)
			(xy 403.503638 -354.461318) (xy 403.519386 -354.44303) (xy 403.519894 -354.441252) (xy 403.264624 -353.26701)
			(xy 403.254718 -353.214686) (xy 403.24884 -353.175583) (xy 403.242607 -353.096747) (xy 403.242272 -353.057206)
			(xy 403.242272 -352.62439) (xy 403.242012 -352.616746) (xy 403.237485 -352.602143) (xy 403.233382 -352.595688)
			(xy 403.229318 -352.589846) (xy 403.21738 -352.580448) (xy 403.20976 -352.5774) (xy 403.185187 -352.567327)
			(xy 403.13909 -352.540956) (xy 403.097421 -352.508032) (xy 403.061104 -352.469284) (xy 403.030945 -352.425571)
			(xy 403.007613 -352.377864) (xy 402.991626 -352.327221) (xy 402.983338 -352.274765) (xy 402.982684 -352.248216)
			(xy 402.982684 -352.244914) (xy 402.983303 -352.215129) (xy 402.993254 -352.156395) (xy 403.002496 -352.128074)
			(xy 403.002496 -352.12782) (xy 403.004287 -352.122095) (xy 403.005443 -352.11016) (xy 403.004782 -352.104198)
			(xy 403.003258 -352.09226) (xy 402.968968 -352.043746) (xy 402.94687 -352.012758) (xy 402.93933 -352.003966)
			(xy 402.918559 -351.993775) (xy 402.906992 -351.9932) (xy 402.27758 -351.9932) (xy 402.250309 -351.992712)
			(xy 402.196322 -351.984947) (xy 402.14399 -351.969579) (xy 402.094377 -351.946919) (xy 402.048494 -351.91743)
			(xy 402.007275 -351.881711) (xy 401.971558 -351.84049) (xy 401.942071 -351.794605) (xy 401.919414 -351.744992)
			(xy 401.904048 -351.692658) (xy 401.896286 -351.638671) (xy 401.896286 -351.584129) (xy 401.904048 -351.530142)
			(xy 401.919414 -351.477808) (xy 401.942071 -351.428195) (xy 401.971558 -351.38231) (xy 402.007275 -351.341089)
			(xy 402.048494 -351.30537) (xy 402.094377 -351.275881) (xy 402.14399 -351.253221) (xy 402.196322 -351.237853)
			(xy 402.250309 -351.230088) (xy 402.27758 -351.229676) (xy 402.946362 -351.229676) (xy 402.957604 -351.229097)
			(xy 402.977919 -351.219474) (xy 402.985478 -351.211134) (xy 402.989034 -351.206816) (xy 402.994114 -351.196656)
			(xy 402.995384 -351.191322) (xy 402.996585 -351.185873) (xy 402.996849 -351.174721) (xy 402.995892 -351.169224)
			(xy 402.56333 -349.008192) (xy 402.560437 -348.996872) (xy 402.546171 -348.9784) (xy 402.525216 -348.968121)
			(xy 402.513546 -348.967552) (xy 402.27758 -348.967552) (xy 402.250312 -348.967064) (xy 402.196332 -348.9593)
			(xy 402.144006 -348.943934) (xy 402.0944 -348.921277) (xy 402.048523 -348.891791) (xy 402.007309 -348.856077)
			(xy 401.971597 -348.814861) (xy 401.942113 -348.768982) (xy 401.919459 -348.719375) (xy 401.904095 -348.667048)
			(xy 401.896334 -348.613068) (xy 401.896334 -348.558532) (xy 401.904095 -348.504552) (xy 401.919459 -348.452225)
			(xy 401.942113 -348.402618) (xy 401.971597 -348.356739) (xy 402.007309 -348.315523) (xy 402.048523 -348.279809)
			(xy 402.0944 -348.250323) (xy 402.144006 -348.227666) (xy 402.196332 -348.2123) (xy 402.250312 -348.204536)
			(xy 402.27758 -348.204028) (xy 402.408898 -348.204028) (xy 402.418908 -348.203541) (xy 402.437405 -348.195883)
			(xy 402.451566 -348.181731) (xy 402.459235 -348.163238) (xy 402.459698 -348.153228) (xy 402.459698 -345.897708)
			(xy 402.45928 -345.887686) (xy 402.451611 -345.869166) (xy 402.437439 -345.854992) (xy 402.41892 -345.847321)
			(xy 402.408898 -345.846908) (xy 402.27758 -345.846908) (xy 402.250308 -345.84642) (xy 402.19632 -345.838655)
			(xy 402.143987 -345.823286) (xy 402.094373 -345.800626) (xy 402.048489 -345.771136) (xy 402.007269 -345.735417)
			(xy 401.971552 -345.694195) (xy 401.942064 -345.648309) (xy 401.919407 -345.598694) (xy 401.904041 -345.54636)
			(xy 401.896278 -345.492372) (xy 401.896278 -345.437828) (xy 401.904041 -345.38384) (xy 401.919407 -345.331506)
			(xy 401.942064 -345.281891) (xy 401.971552 -345.236005) (xy 402.007269 -345.194783) (xy 402.048489 -345.159064)
			(xy 402.094373 -345.129574) (xy 402.143987 -345.106914) (xy 402.19632 -345.091545) (xy 402.250308 -345.08378)
			(xy 402.27758 -345.083384) (xy 402.408898 -345.083384) (xy 402.418918 -345.082965) (xy 402.437433 -345.075295)
			(xy 402.451602 -345.061122) (xy 402.459268 -345.042605) (xy 402.459698 -345.032584) (xy 402.459698 -342.87206)
			(xy 402.459203 -342.862058) (xy 402.451536 -342.84358) (xy 402.437385 -342.82944) (xy 402.418901 -342.821789)
			(xy 402.408898 -342.82126) (xy 402.27758 -342.82126) (xy 402.250312 -342.820772) (xy 402.196331 -342.813008)
			(xy 402.144004 -342.797641) (xy 402.094396 -342.774984) (xy 402.048518 -342.745498) (xy 402.007303 -342.709783)
			(xy 401.97159 -342.668566) (xy 401.942106 -342.622686) (xy 401.919452 -342.573078) (xy 401.904087 -342.52075)
			(xy 401.896326 -342.466768) (xy 401.896326 -342.412232) (xy 401.904087 -342.35825) (xy 401.919452 -342.305922)
			(xy 401.942106 -342.256314) (xy 401.97159 -342.210434) (xy 402.007303 -342.169217) (xy 402.048518 -342.133502)
			(xy 402.094396 -342.104016) (xy 402.144004 -342.081359) (xy 402.196331 -342.065992) (xy 402.250312 -342.058228)
			(xy 402.27758 -342.057736) (xy 402.401278 -342.057736) (xy 402.411291 -342.057252) (xy 402.429797 -342.049598)
			(xy 402.443965 -342.035445) (xy 402.451641 -342.016949) (xy 402.452078 -342.006936) (xy 402.452078 -341.486236)
			(xy 402.451156 -341.475829) (xy 402.442101 -341.457023) (xy 402.426324 -341.443357) (xy 402.416518 -341.439754)
			(xy 402.41601 -341.439754) (xy 402.413724 -341.438992) (xy 387.147816 -337.594194) (xy 387.146292 -337.593686)
			(xy 376.352054 -335.236566) (xy 376.327383 -335.230995) (xy 376.278592 -335.217652) (xy 376.254518 -335.209896)
			(xy 374.973342 -334.789018) (xy 374.968262 -334.787748) (xy 372.945914 -334.346042) (xy 372.89972 -334.335386)
			(xy 372.809442 -334.306426) (xy 372.722328 -334.269012) (xy 372.680484 -334.246728) (xy 369.081558 -332.279244)
			(xy 369.040237 -332.256005) (xy 368.961746 -332.202826) (xy 368.888652 -332.142442) (xy 368.854736 -332.109318)
			(xy 365.70793 -328.962512) (xy 365.673712 -328.927492) (xy 365.61154 -328.851846) (xy 365.557079 -328.770472)
			(xy 365.510851 -328.684155) (xy 365.491522 -328.63917) (xy 364.661958 -326.635872) (xy 364.657132 -326.627236)
			(xy 364.557564 -326.478138) (xy 364.45825 -326.329294) (xy 364.450734 -326.319235) (xy 364.428625 -326.30739)
			(xy 364.416086 -326.306688) (xy 332.473554 -326.306688) (xy 332.46568 -326.30745) (xy 332.451964 -326.311514)
			(xy 332.426765 -326.325645) (xy 332.373075 -326.346976) (xy 332.316785 -326.359973) (xy 332.259178 -326.364338)
			(xy 332.201571 -326.359973) (xy 332.145281 -326.346976) (xy 332.091591 -326.325645) (xy 332.066392 -326.311514)
			(xy 332.052676 -326.30745) (xy 332.044802 -326.306688) (xy 331.78115 -326.306688) (xy 331.771717 -326.307058)
			(xy 331.754126 -326.313871) (xy 331.740196 -326.326591) (xy 331.735684 -326.334882) (xy 331.470762 -326.865996)
			(xy 331.474318 -326.895968) (xy 331.48397 -326.907652) (xy 331.500587 -326.928331) (xy 331.528552 -326.97341)
			(xy 331.550014 -327.021923) (xy 331.564561 -327.072939) (xy 331.571911 -327.125476) (xy 331.572362 -327.152)
			(xy 331.571876 -327.179269) (xy 331.564114 -327.233253) (xy 331.548749 -327.285583) (xy 331.526092 -327.335193)
			(xy 331.496606 -327.381074) (xy 331.460891 -327.422291) (xy 331.419674 -327.458006) (xy 331.373793 -327.487492)
			(xy 331.324183 -327.510149) (xy 331.271853 -327.525514) (xy 331.217869 -327.533276) (xy 331.1906 -327.533762)
			(xy 331.168248 -327.533) (xy 331.167232 -327.533) (xy 331.156564 -327.532492) (xy 331.13091 -327.547732)
			(xy 330.899833 -328.010774) (xy 334.46288 -328.010774) (xy 334.466951 -327.955152) (xy 334.479077 -327.900715)
			(xy 334.499 -327.848624) (xy 334.526296 -327.799989) (xy 334.560382 -327.755846) (xy 334.600531 -327.717137)
			(xy 334.645889 -327.684686) (xy 334.695489 -327.659185) (xy 334.748273 -327.641178) (xy 334.803116 -327.631048)
			(xy 334.85885 -327.629011) (xy 334.914287 -327.635111) (xy 334.968244 -327.649217) (xy 335.019573 -327.671029)
			(xy 335.067179 -327.700083) (xy 335.110047 -327.735758) (xy 335.147264 -327.777295) (xy 335.178037 -327.823808)
			(xy 335.201709 -327.874305) (xy 335.217777 -327.927712) (xy 335.225897 -327.982888) (xy 335.226406 -328.010774)
			(xy 335.225897 -328.03866) (xy 335.217777 -328.093836) (xy 335.201709 -328.147243) (xy 335.178037 -328.19774)
			(xy 335.147264 -328.244253) (xy 335.110047 -328.28579) (xy 335.067179 -328.321465) (xy 335.019573 -328.350519)
			(xy 334.968244 -328.372331) (xy 334.914287 -328.386437) (xy 334.85885 -328.392537) (xy 334.803116 -328.3905)
			(xy 334.748273 -328.38037) (xy 334.695489 -328.362363) (xy 334.645889 -328.336862) (xy 334.600531 -328.304411)
			(xy 334.560382 -328.265702) (xy 334.526296 -328.221559) (xy 334.499 -328.172924) (xy 334.479077 -328.120833)
			(xy 334.466951 -328.066396) (xy 334.46288 -328.010774) (xy 330.899833 -328.010774) (xy 330.86675 -328.077068)
			(xy 330.848696 -328.112345) (xy 330.807775 -328.180218) (xy 330.7616 -328.24463) (xy 330.710461 -328.305178)
			(xy 330.682854 -328.333608) (xy 329.996405 -329.026774) (xy 334.46288 -329.026774) (xy 334.466951 -328.971152)
			(xy 334.479077 -328.916715) (xy 334.499 -328.864624) (xy 334.526296 -328.815989) (xy 334.560382 -328.771846)
			(xy 334.600531 -328.733137) (xy 334.645889 -328.700686) (xy 334.695489 -328.675185) (xy 334.748273 -328.657178)
			(xy 334.803116 -328.647048) (xy 334.85885 -328.645011) (xy 334.914287 -328.651111) (xy 334.968244 -328.665217)
			(xy 335.019573 -328.687029) (xy 335.067179 -328.716083) (xy 335.110047 -328.751758) (xy 335.147264 -328.793295)
			(xy 335.178037 -328.839808) (xy 335.201709 -328.890305) (xy 335.217777 -328.943712) (xy 335.225897 -328.998888)
			(xy 335.226406 -329.026774) (xy 335.225897 -329.05466) (xy 335.217777 -329.109836) (xy 335.201709 -329.163243)
			(xy 335.178037 -329.21374) (xy 335.147264 -329.260253) (xy 335.110047 -329.30179) (xy 335.067179 -329.337465)
			(xy 335.019573 -329.366519) (xy 334.968244 -329.388331) (xy 334.914287 -329.402437) (xy 334.85885 -329.408537)
			(xy 334.803116 -329.4065) (xy 334.748273 -329.39637) (xy 334.695489 -329.378363) (xy 334.645889 -329.352862)
			(xy 334.600531 -329.320411) (xy 334.560382 -329.281702) (xy 334.526296 -329.237559) (xy 334.499 -329.188924)
			(xy 334.479077 -329.136833) (xy 334.466951 -329.082396) (xy 334.46288 -329.026774) (xy 329.996405 -329.026774)
			(xy 328.044967 -330.997306) (xy 351.42119 -330.997306) (xy 351.425261 -330.941684) (xy 351.437387 -330.887247)
			(xy 351.45731 -330.835156) (xy 351.484606 -330.786521) (xy 351.518692 -330.742378) (xy 351.558841 -330.703669)
			(xy 351.604199 -330.671218) (xy 351.653799 -330.645717) (xy 351.706583 -330.62771) (xy 351.761426 -330.61758)
			(xy 351.81716 -330.615543) (xy 351.872597 -330.621643) (xy 351.926554 -330.635749) (xy 351.977883 -330.657561)
			(xy 352.025489 -330.686615) (xy 352.068357 -330.72229) (xy 352.105574 -330.763827) (xy 352.136347 -330.81034)
			(xy 352.160019 -330.860837) (xy 352.176087 -330.914244) (xy 352.184207 -330.96942) (xy 352.184716 -330.997306)
			(xy 352.43719 -330.997306) (xy 352.441261 -330.941684) (xy 352.453387 -330.887247) (xy 352.47331 -330.835156)
			(xy 352.500606 -330.786521) (xy 352.534692 -330.742378) (xy 352.574841 -330.703669) (xy 352.620199 -330.671218)
			(xy 352.669799 -330.645717) (xy 352.722583 -330.62771) (xy 352.777426 -330.61758) (xy 352.83316 -330.615543)
			(xy 352.888597 -330.621643) (xy 352.942554 -330.635749) (xy 352.950595 -330.639166) (xy 359.716576 -330.639166)
			(xy 359.720647 -330.583544) (xy 359.732773 -330.529107) (xy 359.752696 -330.477016) (xy 359.779992 -330.428381)
			(xy 359.814078 -330.384238) (xy 359.854227 -330.345529) (xy 359.899585 -330.313078) (xy 359.949185 -330.287577)
			(xy 360.001969 -330.26957) (xy 360.056812 -330.25944) (xy 360.112546 -330.257403) (xy 360.167983 -330.263503)
			(xy 360.22194 -330.277609) (xy 360.273269 -330.299421) (xy 360.320875 -330.328475) (xy 360.363743 -330.36415)
			(xy 360.40096 -330.405687) (xy 360.431733 -330.4522) (xy 360.455405 -330.502697) (xy 360.471473 -330.556104)
			(xy 360.479593 -330.61128) (xy 360.480023 -330.634848) (xy 360.612434 -330.634848) (xy 360.616505 -330.579226)
			(xy 360.628631 -330.524789) (xy 360.648554 -330.472698) (xy 360.67585 -330.424063) (xy 360.709936 -330.37992)
			(xy 360.750085 -330.341211) (xy 360.795443 -330.30876) (xy 360.845043 -330.283259) (xy 360.897827 -330.265252)
			(xy 360.95267 -330.255122) (xy 361.008404 -330.253085) (xy 361.063841 -330.259185) (xy 361.117798 -330.273291)
			(xy 361.169127 -330.295103) (xy 361.216733 -330.324157) (xy 361.259601 -330.359832) (xy 361.296818 -330.401369)
			(xy 361.327591 -330.447882) (xy 361.351263 -330.498379) (xy 361.367331 -330.551786) (xy 361.375451 -330.606962)
			(xy 361.375953 -330.634457) (xy 361.500817 -330.634457) (xy 361.500817 -330.579943) (xy 361.508575 -330.525984)
			(xy 361.523934 -330.473679) (xy 361.546581 -330.424092) (xy 361.576055 -330.378233) (xy 361.611755 -330.337035)
			(xy 361.652955 -330.301338) (xy 361.698817 -330.271868) (xy 361.748405 -330.249225) (xy 361.800712 -330.23387)
			(xy 361.854671 -330.226115) (xy 361.881928 -330.225654) (xy 361.907882 -330.226066) (xy 361.959312 -330.233101)
			(xy 362.00931 -330.24705) (xy 362.056954 -330.267655) (xy 362.10136 -330.294536) (xy 362.141708 -330.327193)
			(xy 362.17725 -330.365025) (xy 362.20733 -330.407329) (xy 362.219748 -330.430124) (xy 362.226098 -330.442062)
			(xy 362.248704 -330.45654) (xy 362.363512 -330.462128) (xy 362.387388 -330.449936) (xy 362.394754 -330.438506)
			(xy 362.409906 -330.416079) (xy 362.445615 -330.375404) (xy 362.48671 -330.340181) (xy 362.532369 -330.311115)
			(xy 362.581676 -330.288789) (xy 362.633641 -330.273651) (xy 362.687223 -330.266005) (xy 362.714286 -330.265532)
			(xy 362.743578 -330.266126) (xy 362.801473 -330.275085) (xy 362.857321 -330.292781) (xy 362.909811 -330.318797)
			(xy 362.957713 -330.352524) (xy 362.999902 -330.39317) (xy 363.01807 -330.416154) (xy 363.025436 -330.425806)
			(xy 363.04728 -330.436474) (xy 363.141514 -330.434696) (xy 363.153412 -330.43383) (xy 363.174477 -330.422698)
			(xy 363.1819 -330.41336) (xy 363.182154 -330.413106) (xy 363.197551 -330.391988) (xy 363.233128 -330.353707)
			(xy 363.273599 -330.320643) (xy 363.318205 -330.293413) (xy 363.366111 -330.272529) (xy 363.41642 -330.258381)
			(xy 363.46819 -330.251235) (xy 363.49432 -330.2508) (xy 363.521571 -330.251271) (xy 363.575518 -330.25903)
			(xy 363.627811 -330.274387) (xy 363.677387 -330.29703) (xy 363.723236 -330.326498) (xy 363.764424 -330.36219)
			(xy 363.800114 -330.40338) (xy 363.82958 -330.449231) (xy 363.85222 -330.498808) (xy 363.867574 -330.551102)
			(xy 363.87533 -330.605049) (xy 363.87533 -330.659551) (xy 363.867574 -330.713498) (xy 363.85222 -330.765792)
			(xy 363.829579 -330.815369) (xy 363.800114 -330.86122) (xy 363.764424 -330.90241) (xy 363.723236 -330.938102)
			(xy 363.677387 -330.96757) (xy 363.627811 -330.990213) (xy 363.575518 -331.00557) (xy 363.521571 -331.013329)
			(xy 363.49432 -331.013816) (xy 363.465025 -331.01331) (xy 363.407125 -331.004335) (xy 363.351274 -330.986624)
			(xy 363.298784 -330.960591) (xy 363.250885 -330.926847) (xy 363.2087 -330.886185) (xy 363.190536 -330.863194)
			(xy 363.18317 -330.853542) (xy 363.161326 -330.842874) (xy 363.067092 -330.844652) (xy 363.055192 -330.845503)
			(xy 363.034126 -330.856644) (xy 363.026706 -330.865988) (xy 363.026452 -330.866242) (xy 363.011066 -330.887368)
			(xy 362.975485 -330.925646) (xy 362.935012 -330.958709) (xy 362.890404 -330.985936) (xy 362.842497 -331.006819)
			(xy 362.792187 -331.020966) (xy 362.740416 -331.028113) (xy 362.714286 -331.028548) (xy 362.688332 -331.028123)
			(xy 362.636903 -331.02109) (xy 362.586905 -331.007143) (xy 362.539262 -330.98654) (xy 362.494855 -330.959661)
			(xy 362.454507 -330.927005) (xy 362.418965 -330.889175) (xy 362.388885 -330.846872) (xy 362.376466 -330.824078)
			(xy 362.370116 -330.81214) (xy 362.34751 -330.797662) (xy 362.232702 -330.792074) (xy 362.208826 -330.804266)
			(xy 362.20146 -330.815696) (xy 362.186267 -330.838095) (xy 362.150569 -330.878775) (xy 362.109482 -330.914003)
			(xy 362.06383 -330.943074) (xy 362.014529 -330.965405) (xy 361.962568 -330.980547) (xy 361.908989 -330.988196)
			(xy 361.881928 -330.98867) (xy 361.854671 -330.988285) (xy 361.800712 -330.98053) (xy 361.748405 -330.965175)
			(xy 361.698817 -330.942532) (xy 361.652955 -330.913062) (xy 361.611755 -330.877365) (xy 361.576055 -330.836167)
			(xy 361.546581 -330.790308) (xy 361.523934 -330.740721) (xy 361.508576 -330.688416) (xy 361.500817 -330.634457)
			(xy 361.375953 -330.634457) (xy 361.37596 -330.634848) (xy 361.375451 -330.662734) (xy 361.367331 -330.71791)
			(xy 361.351263 -330.771317) (xy 361.327591 -330.821814) (xy 361.296818 -330.868327) (xy 361.259601 -330.909864)
			(xy 361.216733 -330.945539) (xy 361.169127 -330.974593) (xy 361.117798 -330.996405) (xy 361.063841 -331.010511)
			(xy 361.008404 -331.016611) (xy 360.95267 -331.014574) (xy 360.897827 -331.004444) (xy 360.845043 -330.986437)
			(xy 360.795443 -330.960936) (xy 360.750085 -330.928485) (xy 360.709936 -330.889776) (xy 360.67585 -330.845633)
			(xy 360.648554 -330.796998) (xy 360.628631 -330.744907) (xy 360.616505 -330.69047) (xy 360.612434 -330.634848)
			(xy 360.480023 -330.634848) (xy 360.480102 -330.639166) (xy 360.479593 -330.667052) (xy 360.471473 -330.722228)
			(xy 360.455405 -330.775635) (xy 360.431733 -330.826132) (xy 360.40096 -330.872645) (xy 360.363743 -330.914182)
			(xy 360.320875 -330.949857) (xy 360.273269 -330.978911) (xy 360.22194 -331.000723) (xy 360.167983 -331.014829)
			(xy 360.112546 -331.020929) (xy 360.056812 -331.018892) (xy 360.001969 -331.008762) (xy 359.949185 -330.990755)
			(xy 359.899585 -330.965254) (xy 359.854227 -330.932803) (xy 359.814078 -330.894094) (xy 359.779992 -330.849951)
			(xy 359.752696 -330.801316) (xy 359.732773 -330.749225) (xy 359.720647 -330.694788) (xy 359.716576 -330.639166)
			(xy 352.950595 -330.639166) (xy 352.993883 -330.657561) (xy 353.041489 -330.686615) (xy 353.084357 -330.72229)
			(xy 353.121574 -330.763827) (xy 353.152347 -330.81034) (xy 353.176019 -330.860837) (xy 353.192087 -330.914244)
			(xy 353.200207 -330.96942) (xy 353.200716 -330.997306) (xy 353.200207 -331.025192) (xy 353.192087 -331.080368)
			(xy 353.176019 -331.133775) (xy 353.152347 -331.184272) (xy 353.121574 -331.230785) (xy 353.084357 -331.272322)
			(xy 353.041489 -331.307997) (xy 352.993883 -331.337051) (xy 352.942554 -331.358863) (xy 352.888597 -331.372969)
			(xy 352.83316 -331.379069) (xy 352.777426 -331.377032) (xy 352.722583 -331.366902) (xy 352.669799 -331.348895)
			(xy 352.620199 -331.323394) (xy 352.574841 -331.290943) (xy 352.534692 -331.252234) (xy 352.500606 -331.208091)
			(xy 352.47331 -331.159456) (xy 352.453387 -331.107365) (xy 352.441261 -331.052928) (xy 352.43719 -330.997306)
			(xy 352.184716 -330.997306) (xy 352.184207 -331.025192) (xy 352.176087 -331.080368) (xy 352.160019 -331.133775)
			(xy 352.136347 -331.184272) (xy 352.105574 -331.230785) (xy 352.068357 -331.272322) (xy 352.025489 -331.307997)
			(xy 351.977883 -331.337051) (xy 351.926554 -331.358863) (xy 351.872597 -331.372969) (xy 351.81716 -331.379069)
			(xy 351.761426 -331.377032) (xy 351.706583 -331.366902) (xy 351.653799 -331.348895) (xy 351.604199 -331.323394)
			(xy 351.558841 -331.290943) (xy 351.518692 -331.252234) (xy 351.484606 -331.208091) (xy 351.45731 -331.159456)
			(xy 351.437387 -331.107365) (xy 351.425261 -331.052928) (xy 351.42119 -330.997306) (xy 328.044967 -330.997306)
			(xy 327.471962 -331.575918) (xy 357.9655 -331.575918) (xy 357.969571 -331.520296) (xy 357.981697 -331.465859)
			(xy 358.00162 -331.413768) (xy 358.028916 -331.365133) (xy 358.063002 -331.32099) (xy 358.103151 -331.282281)
			(xy 358.148509 -331.24983) (xy 358.198109 -331.224329) (xy 358.250893 -331.206322) (xy 358.305736 -331.196192)
			(xy 358.36147 -331.194155) (xy 358.416907 -331.200255) (xy 358.470864 -331.214361) (xy 358.522193 -331.236173)
			(xy 358.569799 -331.265227) (xy 358.612667 -331.300902) (xy 358.649884 -331.342439) (xy 358.680657 -331.388952)
			(xy 358.704329 -331.439449) (xy 358.720397 -331.492856) (xy 358.728517 -331.548032) (xy 358.729026 -331.575918)
			(xy 358.728517 -331.603804) (xy 358.720397 -331.65898) (xy 358.704329 -331.712387) (xy 358.680657 -331.762884)
			(xy 358.649884 -331.809397) (xy 358.612667 -331.850934) (xy 358.569799 -331.886609) (xy 358.522193 -331.915663)
			(xy 358.470864 -331.937475) (xy 358.416907 -331.951581) (xy 358.36147 -331.957681) (xy 358.305736 -331.955644)
			(xy 358.250893 -331.945514) (xy 358.198109 -331.927507) (xy 358.148509 -331.902006) (xy 358.103151 -331.869555)
			(xy 358.063002 -331.830846) (xy 358.028916 -331.786703) (xy 358.00162 -331.738068) (xy 357.981697 -331.685977)
			(xy 357.969571 -331.63154) (xy 357.9655 -331.575918) (xy 327.471962 -331.575918) (xy 327.152508 -331.898498)
			(xy 327.120209 -331.930357) (xy 327.05076 -331.98874) (xy 327.013824 -332.015084) (xy 325.675765 -332.947271)
			(xy 365.368753 -332.947271) (xy 365.368753 -332.887329) (xy 365.376578 -332.827899) (xy 365.392093 -332.77)
			(xy 365.415033 -332.71462) (xy 365.445006 -332.66271) (xy 365.481498 -332.615155) (xy 365.523886 -332.572772)
			(xy 365.571443 -332.536283) (xy 365.623356 -332.506315) (xy 365.678737 -332.48338) (xy 365.736639 -332.46787)
			(xy 365.796069 -332.460051) (xy 365.82604 -332.459584) (xy 366.68964 -332.459584) (xy 366.719605 -332.460093)
			(xy 366.779023 -332.46792) (xy 366.836911 -332.483435) (xy 366.892278 -332.506374) (xy 366.944178 -332.536342)
			(xy 366.991723 -332.572828) (xy 367.034098 -332.615207) (xy 367.07058 -332.662755) (xy 367.100544 -332.714658)
			(xy 367.123478 -332.770027) (xy 367.138988 -332.827916) (xy 367.14681 -332.887335) (xy 367.14681 -332.947265)
			(xy 367.138988 -333.006684) (xy 367.123478 -333.064573) (xy 367.100544 -333.119942) (xy 367.07058 -333.171845)
			(xy 367.034098 -333.219393) (xy 366.991723 -333.261772) (xy 366.944178 -333.298258) (xy 366.892278 -333.328226)
			(xy 366.836911 -333.351165) (xy 366.779023 -333.36668) (xy 366.719605 -333.374507) (xy 366.68964 -333.375)
			(xy 365.82604 -333.375) (xy 365.796069 -333.374549) (xy 365.736639 -333.36673) (xy 365.678737 -333.35122)
			(xy 365.623356 -333.328285) (xy 365.571443 -333.298317) (xy 365.523886 -333.261828) (xy 365.481498 -333.219445)
			(xy 365.445006 -333.17189) (xy 365.415033 -333.11998) (xy 365.392093 -333.0646) (xy 365.376578 -333.006701)
			(xy 365.368753 -332.947271) (xy 325.675765 -332.947271) (xy 325.312278 -333.200502) (xy 325.305166 -333.206344)
			(xy 319.206626 -339.304884) (xy 367.1095 -339.304884) (xy 367.113571 -339.249262) (xy 367.125697 -339.194825)
			(xy 367.14562 -339.142734) (xy 367.172916 -339.094099) (xy 367.207002 -339.049956) (xy 367.247151 -339.011247)
			(xy 367.292509 -338.978796) (xy 367.342109 -338.953295) (xy 367.394893 -338.935288) (xy 367.449736 -338.925158)
			(xy 367.50547 -338.923121) (xy 367.560907 -338.929221) (xy 367.614864 -338.943327) (xy 367.666193 -338.965139)
			(xy 367.713799 -338.994193) (xy 367.756667 -339.029868) (xy 367.793884 -339.071405) (xy 367.824657 -339.117918)
			(xy 367.848329 -339.168415) (xy 367.864397 -339.221822) (xy 367.872517 -339.276998) (xy 367.873026 -339.304884)
			(xy 367.872517 -339.33277) (xy 367.864397 -339.387946) (xy 367.848329 -339.441353) (xy 367.824657 -339.49185)
			(xy 367.793884 -339.538363) (xy 367.756667 -339.5799) (xy 367.713799 -339.615575) (xy 367.666193 -339.644629)
			(xy 367.614864 -339.666441) (xy 367.560907 -339.680547) (xy 367.50547 -339.686647) (xy 367.449736 -339.68461)
			(xy 367.394893 -339.67448) (xy 367.342109 -339.656473) (xy 367.292509 -339.630972) (xy 367.247151 -339.598521)
			(xy 367.207002 -339.559812) (xy 367.172916 -339.515669) (xy 367.14562 -339.467034) (xy 367.125697 -339.414943)
			(xy 367.113571 -339.360506) (xy 367.1095 -339.304884) (xy 319.206626 -339.304884) (xy 318.48171 -340.0298)
			(xy 365.682782 -340.0298) (xy 365.686853 -339.974178) (xy 365.698979 -339.919741) (xy 365.718902 -339.86765)
			(xy 365.746198 -339.819015) (xy 365.780284 -339.774872) (xy 365.820433 -339.736163) (xy 365.865791 -339.703712)
			(xy 365.915391 -339.678211) (xy 365.968175 -339.660204) (xy 366.023018 -339.650074) (xy 366.078752 -339.648037)
			(xy 366.134189 -339.654137) (xy 366.188146 -339.668243) (xy 366.239475 -339.690055) (xy 366.287081 -339.719109)
			(xy 366.329949 -339.754784) (xy 366.367166 -339.796321) (xy 366.397939 -339.842834) (xy 366.421611 -339.893331)
			(xy 366.437679 -339.946738) (xy 366.445799 -340.001914) (xy 366.446308 -340.0298) (xy 366.445799 -340.057686)
			(xy 366.437679 -340.112862) (xy 366.421611 -340.166269) (xy 366.397939 -340.216766) (xy 366.367166 -340.263279)
			(xy 366.329949 -340.304816) (xy 366.287081 -340.340491) (xy 366.239475 -340.369545) (xy 366.188146 -340.391357)
			(xy 366.134189 -340.405463) (xy 366.078752 -340.411563) (xy 366.023018 -340.409526) (xy 365.968175 -340.399396)
			(xy 365.915391 -340.381389) (xy 365.865791 -340.355888) (xy 365.820433 -340.323437) (xy 365.780284 -340.284728)
			(xy 365.746198 -340.240585) (xy 365.718902 -340.19195) (xy 365.698979 -340.139859) (xy 365.686853 -340.085422)
			(xy 365.682782 -340.0298) (xy 318.48171 -340.0298) (xy 317.94831 -340.5632) (xy 364.336582 -340.5632)
			(xy 364.340653 -340.507578) (xy 364.352779 -340.453141) (xy 364.372702 -340.40105) (xy 364.399998 -340.352415)
			(xy 364.434084 -340.308272) (xy 364.474233 -340.269563) (xy 364.519591 -340.237112) (xy 364.569191 -340.211611)
			(xy 364.621975 -340.193604) (xy 364.676818 -340.183474) (xy 364.732552 -340.181437) (xy 364.787989 -340.187537)
			(xy 364.841946 -340.201643) (xy 364.893275 -340.223455) (xy 364.940881 -340.252509) (xy 364.983749 -340.288184)
			(xy 365.020966 -340.329721) (xy 365.051739 -340.376234) (xy 365.075411 -340.426731) (xy 365.091479 -340.480138)
			(xy 365.099599 -340.535314) (xy 365.100108 -340.5632) (xy 365.099599 -340.591086) (xy 365.091479 -340.646262)
			(xy 365.075411 -340.699669) (xy 365.051739 -340.750166) (xy 365.020966 -340.796679) (xy 364.983749 -340.838216)
			(xy 364.940881 -340.873891) (xy 364.893275 -340.902945) (xy 364.841946 -340.924757) (xy 364.787989 -340.938863)
			(xy 364.732552 -340.944963) (xy 364.676818 -340.942926) (xy 364.621975 -340.932796) (xy 364.569191 -340.914789)
			(xy 364.519591 -340.889288) (xy 364.474233 -340.856837) (xy 364.434084 -340.818128) (xy 364.399998 -340.773985)
			(xy 364.372702 -340.72535) (xy 364.352779 -340.673259) (xy 364.340653 -340.618822) (xy 364.336582 -340.5632)
			(xy 317.94831 -340.5632) (xy 316.944502 -341.567008) (xy 316.94374 -341.57412) (xy 316.959739 -341.593522)
			(xy 316.986691 -341.635977) (xy 317.007403 -341.681801) (xy 317.021463 -341.730083) (xy 317.028592 -341.779863)
			(xy 317.029084 -341.805006) (xy 317.029084 -341.805514) (xy 317.028617 -341.831433) (xy 317.021102 -341.882725)
			(xy 317.006234 -341.932386) (xy 316.984325 -341.979368) (xy 316.95584 -342.022679) (xy 316.921378 -342.061404)
			(xy 316.881668 -342.094727) (xy 316.837548 -342.121943) (xy 316.813946 -342.132666) (xy 316.80362 -342.137759)
			(xy 316.788458 -342.155043) (xy 316.784736 -342.16594) (xy 316.780418 -342.182196) (xy 316.778132 -342.190324)
			(xy 316.781942 -342.212168) (xy 316.788546 -342.221566) (xy 316.804658 -342.245692) (xy 316.830181 -342.297789)
			(xy 316.84753 -342.353146) (xy 316.856306 -342.410492) (xy 316.856872 -342.439498) (xy 316.856381 -342.46674)
			(xy 316.856376 -342.466772) (xy 318.3394 -342.466772) (xy 318.3394 -342.412228) (xy 318.347162 -342.358239)
			(xy 318.36253 -342.305904) (xy 318.385189 -342.256289) (xy 318.414679 -342.210404) (xy 318.4504 -342.169183)
			(xy 318.491623 -342.133465) (xy 318.53751 -342.103978) (xy 318.587126 -342.081322) (xy 318.639462 -342.065957)
			(xy 318.693452 -342.058198) (xy 318.720724 -342.057736) (xy 319.584324 -342.057736) (xy 319.611592 -342.058228)
			(xy 319.665573 -342.065992) (xy 319.717899 -342.08136) (xy 319.767506 -342.104017) (xy 319.813384 -342.133504)
			(xy 319.854598 -342.169219) (xy 319.890311 -342.210435) (xy 319.919794 -342.256315) (xy 319.942449 -342.305923)
			(xy 319.957813 -342.358251) (xy 319.965574 -342.412232) (xy 319.965574 -342.466768) (xy 319.965574 -342.466769)
			(xy 321.448422 -342.466769) (xy 321.448422 -342.412231) (xy 321.456184 -342.358249) (xy 321.471548 -342.30592)
			(xy 321.494203 -342.256311) (xy 321.523688 -342.21043) (xy 321.559402 -342.169213) (xy 321.600618 -342.133498)
			(xy 321.646497 -342.104011) (xy 321.696105 -342.081354) (xy 321.748433 -342.065987) (xy 321.802415 -342.058224)
			(xy 321.829684 -342.057736) (xy 322.693284 -342.057736) (xy 322.720556 -342.058202) (xy 322.774544 -342.065963)
			(xy 322.826878 -342.081327) (xy 322.876493 -342.103984) (xy 322.922379 -342.133471) (xy 322.9636 -342.169188)
			(xy 322.999319 -342.210409) (xy 323.028808 -342.256293) (xy 323.051467 -342.305907) (xy 323.066834 -342.35824)
			(xy 323.074596 -342.412228) (xy 323.074596 -342.466772) (xy 323.074596 -342.466773) (xy 324.5573 -342.466773)
			(xy 324.5573 -342.412227) (xy 324.565063 -342.358236) (xy 324.580432 -342.305899) (xy 324.603092 -342.256283)
			(xy 324.632584 -342.210397) (xy 324.668307 -342.169176) (xy 324.709532 -342.133458) (xy 324.755422 -342.103971)
			(xy 324.805041 -342.081316) (xy 324.857379 -342.065954) (xy 324.911371 -342.058196) (xy 324.938644 -342.057736)
			(xy 325.802244 -342.057736) (xy 325.829511 -342.058229) (xy 325.88349 -342.065996) (xy 325.935814 -342.081365)
			(xy 325.985418 -342.104024) (xy 326.031293 -342.133511) (xy 326.072505 -342.169226) (xy 326.108216 -342.210442)
			(xy 326.137697 -342.256321) (xy 326.16035 -342.305928) (xy 326.175713 -342.358253) (xy 326.183474 -342.412233)
			(xy 326.183474 -342.466767) (xy 326.183473 -342.466771) (xy 327.6663 -342.466771) (xy 327.6663 -342.412229)
			(xy 327.674062 -342.358241) (xy 327.689428 -342.305908) (xy 327.712086 -342.256294) (xy 327.741574 -342.21041)
			(xy 327.777293 -342.16919) (xy 327.818513 -342.133472) (xy 327.864398 -342.103984) (xy 327.914012 -342.081327)
			(xy 327.966345 -342.065961) (xy 328.020333 -342.058199) (xy 328.047604 -342.057736) (xy 328.911204 -342.057736)
			(xy 328.938473 -342.058227) (xy 328.992456 -342.065989) (xy 329.044785 -342.081354) (xy 329.094394 -342.104011)
			(xy 329.140274 -342.133497) (xy 329.181491 -342.169212) (xy 329.217206 -342.210429) (xy 329.246691 -342.256309)
			(xy 329.269347 -342.305919) (xy 329.284712 -342.358248) (xy 329.292474 -342.412231) (xy 329.292474 -342.466768)
			(xy 330.775322 -342.466768) (xy 330.775322 -342.412232) (xy 330.783083 -342.358251) (xy 330.798447 -342.305924)
			(xy 330.8211 -342.256316) (xy 330.850583 -342.210437) (xy 330.886295 -342.16922) (xy 330.927508 -342.133505)
			(xy 330.973385 -342.104018) (xy 331.022991 -342.081359) (xy 331.075316 -342.065991) (xy 331.129296 -342.058225)
			(xy 331.156564 -342.057736) (xy 332.020164 -342.057736) (xy 332.047437 -342.058201) (xy 332.101427 -342.065959)
			(xy 332.153764 -342.081322) (xy 332.203381 -342.103977) (xy 332.249269 -342.133464) (xy 332.290493 -342.169181)
			(xy 332.326214 -342.210402) (xy 332.355705 -342.256287) (xy 332.378365 -342.305902) (xy 332.393733 -342.358238)
			(xy 332.401496 -342.412228) (xy 332.401496 -342.466772) (xy 333.8842 -342.466772) (xy 333.8842 -342.412228)
			(xy 333.891962 -342.358239) (xy 333.90733 -342.305904) (xy 333.929989 -342.256289) (xy 333.959479 -342.210404)
			(xy 333.9952 -342.169183) (xy 334.036423 -342.133465) (xy 334.08231 -342.103978) (xy 334.131926 -342.081322)
			(xy 334.184262 -342.065957) (xy 334.238252 -342.058198) (xy 334.265524 -342.057736) (xy 335.129124 -342.057736)
			(xy 335.156392 -342.058228) (xy 335.210373 -342.065992) (xy 335.262699 -342.08136) (xy 335.312306 -342.104017)
			(xy 335.358184 -342.133504) (xy 335.399398 -342.169219) (xy 335.435111 -342.210435) (xy 335.464594 -342.256315)
			(xy 335.487249 -342.305923) (xy 335.502613 -342.358251) (xy 335.510374 -342.412232) (xy 335.510374 -342.466768)
			(xy 335.510374 -342.466769) (xy 336.993222 -342.466769) (xy 336.993222 -342.412231) (xy 337.000984 -342.358249)
			(xy 337.016348 -342.30592) (xy 337.039003 -342.256311) (xy 337.068488 -342.21043) (xy 337.104202 -342.169213)
			(xy 337.145418 -342.133498) (xy 337.191297 -342.104011) (xy 337.240905 -342.081354) (xy 337.293233 -342.065987)
			(xy 337.347215 -342.058224) (xy 337.374484 -342.057736) (xy 338.238084 -342.057736) (xy 338.265356 -342.058202)
			(xy 338.319344 -342.065963) (xy 338.371678 -342.081327) (xy 338.421293 -342.103984) (xy 338.467179 -342.133471)
			(xy 338.5084 -342.169188) (xy 338.544119 -342.210409) (xy 338.573608 -342.256293) (xy 338.596267 -342.305907)
			(xy 338.611634 -342.35824) (xy 338.619396 -342.412228) (xy 338.619396 -342.466772) (xy 338.619396 -342.466773)
			(xy 340.1021 -342.466773) (xy 340.1021 -342.412227) (xy 340.109863 -342.358236) (xy 340.125232 -342.305899)
			(xy 340.147892 -342.256283) (xy 340.177384 -342.210397) (xy 340.213107 -342.169176) (xy 340.254332 -342.133458)
			(xy 340.300222 -342.103971) (xy 340.349841 -342.081316) (xy 340.402179 -342.065954) (xy 340.456171 -342.058196)
			(xy 340.483444 -342.057736) (xy 341.347044 -342.057736) (xy 341.374311 -342.058229) (xy 341.42829 -342.065996)
			(xy 341.480614 -342.081365) (xy 341.530218 -342.104024) (xy 341.576093 -342.133511) (xy 341.617305 -342.169226)
			(xy 341.653016 -342.210442) (xy 341.682497 -342.256321) (xy 341.70515 -342.305928) (xy 341.720513 -342.358253)
			(xy 341.728274 -342.412233) (xy 341.728274 -342.466767) (xy 341.728273 -342.466771) (xy 343.2111 -342.466771)
			(xy 343.2111 -342.412229) (xy 343.218862 -342.358241) (xy 343.234228 -342.305908) (xy 343.256886 -342.256294)
			(xy 343.286374 -342.21041) (xy 343.322093 -342.16919) (xy 343.363313 -342.133472) (xy 343.409198 -342.103984)
			(xy 343.458812 -342.081327) (xy 343.511145 -342.065961) (xy 343.565133 -342.058199) (xy 343.592404 -342.057736)
			(xy 344.456004 -342.057736) (xy 344.483273 -342.058227) (xy 344.537256 -342.065989) (xy 344.589585 -342.081354)
			(xy 344.639194 -342.104011) (xy 344.685074 -342.133497) (xy 344.726291 -342.169212) (xy 344.762006 -342.210429)
			(xy 344.791491 -342.256309) (xy 344.814147 -342.305919) (xy 344.829512 -342.358248) (xy 344.837274 -342.412231)
			(xy 344.837274 -342.466769) (xy 370.806722 -342.466769) (xy 370.806722 -342.412231) (xy 370.814484 -342.358249)
			(xy 370.829848 -342.305921) (xy 370.852503 -342.256312) (xy 370.881987 -342.210432) (xy 370.9177 -342.169214)
			(xy 370.958916 -342.133499) (xy 371.004794 -342.104012) (xy 371.054402 -342.081355) (xy 371.10673 -342.065988)
			(xy 371.160711 -342.058224) (xy 371.18798 -342.057736) (xy 372.05158 -342.057736) (xy 372.078852 -342.058202)
			(xy 372.132841 -342.065962) (xy 372.185175 -342.081326) (xy 372.234791 -342.103983) (xy 372.280677 -342.13347)
			(xy 372.321899 -342.169187) (xy 372.357618 -342.210407) (xy 372.387108 -342.256292) (xy 372.409767 -342.305906)
			(xy 372.425134 -342.35824) (xy 372.432896 -342.412228) (xy 372.432896 -342.466772) (xy 372.432896 -342.466773)
			(xy 373.9156 -342.466773) (xy 373.9156 -342.412227) (xy 373.923363 -342.358236) (xy 373.938731 -342.3059)
			(xy 373.961392 -342.256284) (xy 373.990883 -342.210398) (xy 374.026605 -342.169177) (xy 374.06783 -342.133459)
			(xy 374.113719 -342.103973) (xy 374.163338 -342.081317) (xy 374.215676 -342.065954) (xy 374.269667 -342.058197)
			(xy 374.29694 -342.057736) (xy 375.16054 -342.057736) (xy 375.187807 -342.058229) (xy 375.241786 -342.065995)
			(xy 375.294111 -342.081364) (xy 375.343716 -342.104022) (xy 375.389591 -342.133509) (xy 375.430804 -342.169224)
			(xy 375.466515 -342.210441) (xy 375.495997 -342.256319) (xy 375.51865 -342.305927) (xy 375.534013 -342.358253)
			(xy 375.541774 -342.412233) (xy 375.541774 -342.466767) (xy 375.541774 -342.46677) (xy 377.024622 -342.46677)
			(xy 377.024622 -342.41223) (xy 377.032384 -342.358247) (xy 377.04775 -342.305917) (xy 377.070406 -342.256306)
			(xy 377.099892 -342.210425) (xy 377.135607 -342.169207) (xy 377.176825 -342.133492) (xy 377.222706 -342.104006)
			(xy 377.272317 -342.08135) (xy 377.324647 -342.065984) (xy 377.37863 -342.058222) (xy 377.4059 -342.057736)
			(xy 378.2695 -342.057736) (xy 378.296769 -342.058226) (xy 378.350753 -342.065988) (xy 378.403082 -342.081353)
			(xy 378.452692 -342.104009) (xy 378.498572 -342.133495) (xy 378.53979 -342.16921) (xy 378.575505 -342.210428)
			(xy 378.604991 -342.256308) (xy 378.627647 -342.305918) (xy 378.643012 -342.358247) (xy 378.650774 -342.412231)
			(xy 378.650774 -342.466768) (xy 380.133622 -342.466768) (xy 380.133622 -342.412232) (xy 380.141383 -342.358252)
			(xy 380.156746 -342.305925) (xy 380.1794 -342.256318) (xy 380.208882 -342.210438) (xy 380.244593 -342.169222)
			(xy 380.285806 -342.133506) (xy 380.331682 -342.104019) (xy 380.381288 -342.08136) (xy 380.433613 -342.065991)
			(xy 380.487592 -342.058225) (xy 380.51486 -342.057736) (xy 381.37846 -342.057736) (xy 381.405733 -342.058201)
			(xy 381.459724 -342.065958) (xy 381.512061 -342.081321) (xy 381.561679 -342.103976) (xy 381.607567 -342.133463)
			(xy 381.648792 -342.16918) (xy 381.684513 -342.210401) (xy 381.714005 -342.256286) (xy 381.736665 -342.305902)
			(xy 381.752033 -342.358237) (xy 381.759796 -342.412227) (xy 381.759796 -342.466772) (xy 383.2425 -342.466772)
			(xy 383.2425 -342.412228) (xy 383.250262 -342.358239) (xy 383.26563 -342.305904) (xy 383.288289 -342.25629)
			(xy 383.317778 -342.210405) (xy 383.353498 -342.169184) (xy 383.394721 -342.133466) (xy 383.440607 -342.103979)
			(xy 383.490223 -342.081323) (xy 383.542559 -342.065958) (xy 383.596548 -342.058198) (xy 383.62382 -342.057736)
			(xy 384.48742 -342.057736) (xy 384.514688 -342.058228) (xy 384.568669 -342.065992) (xy 384.620996 -342.081359)
			(xy 384.670604 -342.104016) (xy 384.716482 -342.133502) (xy 384.757697 -342.169217) (xy 384.79341 -342.210434)
			(xy 384.822894 -342.256314) (xy 384.845548 -342.305922) (xy 384.860913 -342.35825) (xy 384.868674 -342.412232)
			(xy 384.868674 -342.466768) (xy 384.868674 -342.466769) (xy 386.351522 -342.466769) (xy 386.351522 -342.412231)
			(xy 386.359284 -342.358249) (xy 386.374648 -342.305921) (xy 386.397303 -342.256312) (xy 386.426787 -342.210432)
			(xy 386.4625 -342.169214) (xy 386.503716 -342.133499) (xy 386.549594 -342.104012) (xy 386.599202 -342.081355)
			(xy 386.65153 -342.065988) (xy 386.705511 -342.058224) (xy 386.73278 -342.057736) (xy 387.59638 -342.057736)
			(xy 387.623652 -342.058202) (xy 387.677641 -342.065962) (xy 387.729975 -342.081326) (xy 387.779591 -342.103983)
			(xy 387.825477 -342.13347) (xy 387.866699 -342.169187) (xy 387.902418 -342.210407) (xy 387.931908 -342.256292)
			(xy 387.954567 -342.305906) (xy 387.969934 -342.35824) (xy 387.977696 -342.412228) (xy 387.977696 -342.466772)
			(xy 387.977696 -342.466773) (xy 389.4604 -342.466773) (xy 389.4604 -342.412227) (xy 389.468163 -342.358236)
			(xy 389.483531 -342.3059) (xy 389.506192 -342.256284) (xy 389.535683 -342.210398) (xy 389.571405 -342.169177)
			(xy 389.61263 -342.133459) (xy 389.658519 -342.103973) (xy 389.708138 -342.081317) (xy 389.760476 -342.065954)
			(xy 389.814467 -342.058197) (xy 389.84174 -342.057736) (xy 390.70534 -342.057736) (xy 390.732607 -342.058229)
			(xy 390.786586 -342.065995) (xy 390.838911 -342.081364) (xy 390.888516 -342.104022) (xy 390.934391 -342.133509)
			(xy 390.975604 -342.169224) (xy 391.011315 -342.210441) (xy 391.040797 -342.256319) (xy 391.06345 -342.305927)
			(xy 391.078813 -342.358253) (xy 391.086574 -342.412233) (xy 391.086574 -342.466767) (xy 391.086574 -342.46677)
			(xy 392.569422 -342.46677) (xy 392.569422 -342.41223) (xy 392.577184 -342.358247) (xy 392.59255 -342.305917)
			(xy 392.615206 -342.256306) (xy 392.644692 -342.210425) (xy 392.680407 -342.169207) (xy 392.721625 -342.133492)
			(xy 392.767506 -342.104006) (xy 392.817117 -342.08135) (xy 392.869447 -342.065984) (xy 392.92343 -342.058222)
			(xy 392.9507 -342.057736) (xy 393.8143 -342.057736) (xy 393.841569 -342.058226) (xy 393.895553 -342.065988)
			(xy 393.947882 -342.081353) (xy 393.997492 -342.104009) (xy 394.043372 -342.133495) (xy 394.08459 -342.16921)
			(xy 394.120305 -342.210428) (xy 394.149791 -342.256308) (xy 394.172447 -342.305918) (xy 394.187812 -342.358247)
			(xy 394.195574 -342.412231) (xy 394.195574 -342.466768) (xy 395.678422 -342.466768) (xy 395.678422 -342.412232)
			(xy 395.686183 -342.358252) (xy 395.701546 -342.305925) (xy 395.7242 -342.256318) (xy 395.753682 -342.210438)
			(xy 395.789393 -342.169222) (xy 395.830606 -342.133506) (xy 395.876482 -342.104019) (xy 395.926088 -342.08136)
			(xy 395.978413 -342.065991) (xy 396.032392 -342.058225) (xy 396.05966 -342.057736) (xy 396.92326 -342.057736)
			(xy 396.950533 -342.058201) (xy 397.004524 -342.065958) (xy 397.056861 -342.081321) (xy 397.106479 -342.103976)
			(xy 397.152367 -342.133463) (xy 397.193592 -342.16918) (xy 397.229313 -342.210401) (xy 397.258805 -342.256286)
			(xy 397.281465 -342.305902) (xy 397.296833 -342.358237) (xy 397.304596 -342.412227) (xy 397.304596 -342.466772)
			(xy 398.7873 -342.466772) (xy 398.7873 -342.412228) (xy 398.795062 -342.358239) (xy 398.81043 -342.305904)
			(xy 398.833089 -342.25629) (xy 398.862578 -342.210405) (xy 398.898298 -342.169184) (xy 398.939521 -342.133466)
			(xy 398.985407 -342.103979) (xy 399.035023 -342.081323) (xy 399.087359 -342.065958) (xy 399.141348 -342.058198)
			(xy 399.16862 -342.057736) (xy 400.03222 -342.057736) (xy 400.059488 -342.058228) (xy 400.113469 -342.065992)
			(xy 400.165796 -342.081359) (xy 400.215404 -342.104016) (xy 400.261282 -342.133502) (xy 400.302497 -342.169217)
			(xy 400.33821 -342.210434) (xy 400.367694 -342.256314) (xy 400.390348 -342.305922) (xy 400.405713 -342.35825)
			(xy 400.413474 -342.412232) (xy 400.413474 -342.466768) (xy 400.405713 -342.52075) (xy 400.390348 -342.573078)
			(xy 400.367694 -342.622686) (xy 400.33821 -342.668566) (xy 400.302497 -342.709783) (xy 400.261282 -342.745498)
			(xy 400.215404 -342.774984) (xy 400.165796 -342.797641) (xy 400.113469 -342.813008) (xy 400.059488 -342.820772)
			(xy 400.03222 -342.82126) (xy 399.16862 -342.82126) (xy 399.141348 -342.820802) (xy 399.087359 -342.813042)
			(xy 399.035023 -342.797677) (xy 398.985407 -342.775021) (xy 398.939521 -342.745534) (xy 398.898298 -342.709816)
			(xy 398.862578 -342.668595) (xy 398.833089 -342.62271) (xy 398.81043 -342.573096) (xy 398.795062 -342.520761)
			(xy 398.7873 -342.466772) (xy 397.304596 -342.466772) (xy 397.304596 -342.466773) (xy 397.296833 -342.520763)
			(xy 397.281465 -342.573098) (xy 397.258805 -342.622714) (xy 397.229313 -342.668599) (xy 397.193592 -342.70982)
			(xy 397.152367 -342.745537) (xy 397.106479 -342.775024) (xy 397.056861 -342.797679) (xy 397.004524 -342.813042)
			(xy 396.950533 -342.820799) (xy 396.92326 -342.82126) (xy 396.05966 -342.82126) (xy 396.032392 -342.820775)
			(xy 395.978413 -342.813009) (xy 395.926088 -342.79764) (xy 395.876482 -342.774981) (xy 395.830606 -342.745494)
			(xy 395.789393 -342.709778) (xy 395.753682 -342.668562) (xy 395.7242 -342.622682) (xy 395.701546 -342.573075)
			(xy 395.686183 -342.520748) (xy 395.678422 -342.466768) (xy 394.195574 -342.466768) (xy 394.195574 -342.466769)
			(xy 394.187812 -342.520753) (xy 394.172447 -342.573082) (xy 394.149791 -342.622692) (xy 394.120305 -342.668572)
			(xy 394.08459 -342.70979) (xy 394.043372 -342.745505) (xy 393.997492 -342.774991) (xy 393.947882 -342.797647)
			(xy 393.895553 -342.813012) (xy 393.841569 -342.820774) (xy 393.8143 -342.82126) (xy 392.9507 -342.82126)
			(xy 392.92343 -342.820778) (xy 392.869447 -342.813016) (xy 392.817117 -342.79765) (xy 392.767506 -342.774994)
			(xy 392.721625 -342.745508) (xy 392.680407 -342.709793) (xy 392.644692 -342.668575) (xy 392.615206 -342.622694)
			(xy 392.59255 -342.573083) (xy 392.577184 -342.520753) (xy 392.569422 -342.46677) (xy 391.086574 -342.46677)
			(xy 391.078813 -342.520747) (xy 391.06345 -342.573073) (xy 391.040797 -342.622681) (xy 391.011315 -342.668559)
			(xy 390.975604 -342.709776) (xy 390.934391 -342.745491) (xy 390.888516 -342.774978) (xy 390.838911 -342.797636)
			(xy 390.786586 -342.813005) (xy 390.732607 -342.820771) (xy 390.70534 -342.82126) (xy 389.84174 -342.82126)
			(xy 389.814467 -342.820803) (xy 389.760476 -342.813046) (xy 389.708138 -342.797683) (xy 389.658519 -342.775027)
			(xy 389.61263 -342.745541) (xy 389.571405 -342.709823) (xy 389.535683 -342.668602) (xy 389.506192 -342.622716)
			(xy 389.483531 -342.5731) (xy 389.468163 -342.520764) (xy 389.4604 -342.466773) (xy 387.977696 -342.466773)
			(xy 387.969934 -342.52076) (xy 387.954567 -342.573094) (xy 387.931908 -342.622708) (xy 387.902418 -342.668593)
			(xy 387.866699 -342.709813) (xy 387.825477 -342.74553) (xy 387.779591 -342.775017) (xy 387.729975 -342.797674)
			(xy 387.677641 -342.813038) (xy 387.623652 -342.820798) (xy 387.59638 -342.82126) (xy 386.73278 -342.82126)
			(xy 386.705511 -342.820776) (xy 386.65153 -342.813012) (xy 386.599202 -342.797645) (xy 386.549594 -342.774988)
			(xy 386.503716 -342.745501) (xy 386.4625 -342.709786) (xy 386.426787 -342.668568) (xy 386.397303 -342.622688)
			(xy 386.374648 -342.573079) (xy 386.359284 -342.520751) (xy 386.351522 -342.466769) (xy 384.868674 -342.466769)
			(xy 384.860913 -342.52075) (xy 384.845548 -342.573078) (xy 384.822894 -342.622686) (xy 384.79341 -342.668566)
			(xy 384.757697 -342.709783) (xy 384.716482 -342.745498) (xy 384.670604 -342.774984) (xy 384.620996 -342.797641)
			(xy 384.568669 -342.813008) (xy 384.514688 -342.820772) (xy 384.48742 -342.82126) (xy 383.62382 -342.82126)
			(xy 383.596548 -342.820802) (xy 383.542559 -342.813042) (xy 383.490223 -342.797677) (xy 383.440607 -342.775021)
			(xy 383.394721 -342.745534) (xy 383.353498 -342.709816) (xy 383.317778 -342.668595) (xy 383.288289 -342.62271)
			(xy 383.26563 -342.573096) (xy 383.250262 -342.520761) (xy 383.2425 -342.466772) (xy 381.759796 -342.466772)
			(xy 381.759796 -342.466773) (xy 381.752033 -342.520763) (xy 381.736665 -342.573098) (xy 381.714005 -342.622714)
			(xy 381.684513 -342.668599) (xy 381.648792 -342.70982) (xy 381.607567 -342.745537) (xy 381.561679 -342.775024)
			(xy 381.512061 -342.797679) (xy 381.459724 -342.813042) (xy 381.405733 -342.820799) (xy 381.37846 -342.82126)
			(xy 380.51486 -342.82126) (xy 380.487592 -342.820775) (xy 380.433613 -342.813009) (xy 380.381288 -342.79764)
			(xy 380.331682 -342.774981) (xy 380.285806 -342.745494) (xy 380.244593 -342.709778) (xy 380.208882 -342.668562)
			(xy 380.1794 -342.622682) (xy 380.156746 -342.573075) (xy 380.141383 -342.520748) (xy 380.133622 -342.466768)
			(xy 378.650774 -342.466768) (xy 378.650774 -342.466769) (xy 378.643012 -342.520753) (xy 378.627647 -342.573082)
			(xy 378.604991 -342.622692) (xy 378.575505 -342.668572) (xy 378.53979 -342.70979) (xy 378.498572 -342.745505)
			(xy 378.452692 -342.774991) (xy 378.403082 -342.797647) (xy 378.350753 -342.813012) (xy 378.296769 -342.820774)
			(xy 378.2695 -342.82126) (xy 377.4059 -342.82126) (xy 377.37863 -342.820778) (xy 377.324647 -342.813016)
			(xy 377.272317 -342.79765) (xy 377.222706 -342.774994) (xy 377.176825 -342.745508) (xy 377.135607 -342.709793)
			(xy 377.099892 -342.668575) (xy 377.070406 -342.622694) (xy 377.04775 -342.573083) (xy 377.032384 -342.520753)
			(xy 377.024622 -342.46677) (xy 375.541774 -342.46677) (xy 375.534013 -342.520747) (xy 375.51865 -342.573073)
			(xy 375.495997 -342.622681) (xy 375.466515 -342.668559) (xy 375.430804 -342.709776) (xy 375.389591 -342.745491)
			(xy 375.343716 -342.774978) (xy 375.294111 -342.797636) (xy 375.241786 -342.813005) (xy 375.187807 -342.820771)
			(xy 375.16054 -342.82126) (xy 374.29694 -342.82126) (xy 374.269667 -342.820803) (xy 374.215676 -342.813046)
			(xy 374.163338 -342.797683) (xy 374.113719 -342.775027) (xy 374.06783 -342.745541) (xy 374.026605 -342.709823)
			(xy 373.990883 -342.668602) (xy 373.961392 -342.622716) (xy 373.938731 -342.5731) (xy 373.923363 -342.520764)
			(xy 373.9156 -342.466773) (xy 372.432896 -342.466773) (xy 372.425134 -342.52076) (xy 372.409767 -342.573094)
			(xy 372.387108 -342.622708) (xy 372.357618 -342.668593) (xy 372.321899 -342.709813) (xy 372.280677 -342.74553)
			(xy 372.234791 -342.775017) (xy 372.185175 -342.797674) (xy 372.132841 -342.813038) (xy 372.078852 -342.820798)
			(xy 372.05158 -342.82126) (xy 371.18798 -342.82126) (xy 371.160711 -342.820776) (xy 371.10673 -342.813012)
			(xy 371.054402 -342.797645) (xy 371.004794 -342.774988) (xy 370.958916 -342.745501) (xy 370.9177 -342.709786)
			(xy 370.881987 -342.668568) (xy 370.852503 -342.622688) (xy 370.829848 -342.573079) (xy 370.814484 -342.520751)
			(xy 370.806722 -342.466769) (xy 344.837274 -342.466769) (xy 344.829512 -342.520752) (xy 344.814147 -342.573081)
			(xy 344.791491 -342.622691) (xy 344.762006 -342.668571) (xy 344.726291 -342.709788) (xy 344.685074 -342.745503)
			(xy 344.639194 -342.774989) (xy 344.589585 -342.797646) (xy 344.537256 -342.813011) (xy 344.483273 -342.820773)
			(xy 344.456004 -342.82126) (xy 343.592404 -342.82126) (xy 343.565133 -342.820801) (xy 343.511145 -342.813039)
			(xy 343.458812 -342.797673) (xy 343.409198 -342.775016) (xy 343.363313 -342.745528) (xy 343.322093 -342.70981)
			(xy 343.286374 -342.66859) (xy 343.256886 -342.622706) (xy 343.234228 -342.573092) (xy 343.218862 -342.520759)
			(xy 343.2111 -342.466771) (xy 341.728273 -342.466771) (xy 341.720513 -342.520747) (xy 341.70515 -342.573072)
			(xy 341.682497 -342.622679) (xy 341.653016 -342.668558) (xy 341.617305 -342.709774) (xy 341.576093 -342.745489)
			(xy 341.530218 -342.774976) (xy 341.480614 -342.797635) (xy 341.42829 -342.813004) (xy 341.374311 -342.820771)
			(xy 341.347044 -342.82126) (xy 340.483444 -342.82126) (xy 340.456171 -342.820804) (xy 340.402179 -342.813046)
			(xy 340.349841 -342.797684) (xy 340.300222 -342.775029) (xy 340.254332 -342.745542) (xy 340.213107 -342.709824)
			(xy 340.177384 -342.668603) (xy 340.147892 -342.622717) (xy 340.125232 -342.573101) (xy 340.109863 -342.520764)
			(xy 340.1021 -342.466773) (xy 338.619396 -342.466773) (xy 338.611634 -342.52076) (xy 338.596267 -342.573093)
			(xy 338.573608 -342.622707) (xy 338.544119 -342.668591) (xy 338.5084 -342.709812) (xy 338.467179 -342.745529)
			(xy 338.421293 -342.775016) (xy 338.371678 -342.797673) (xy 338.319344 -342.813037) (xy 338.265356 -342.820798)
			(xy 338.238084 -342.82126) (xy 337.374484 -342.82126) (xy 337.347215 -342.820776) (xy 337.293233 -342.813013)
			(xy 337.240905 -342.797646) (xy 337.191297 -342.774989) (xy 337.145418 -342.745502) (xy 337.104202 -342.709787)
			(xy 337.068488 -342.66857) (xy 337.039003 -342.622689) (xy 337.016348 -342.57308) (xy 337.000984 -342.520751)
			(xy 336.993222 -342.466769) (xy 335.510374 -342.466769) (xy 335.502613 -342.520749) (xy 335.487249 -342.573077)
			(xy 335.464594 -342.622685) (xy 335.435111 -342.668565) (xy 335.399398 -342.709781) (xy 335.358184 -342.745496)
			(xy 335.312306 -342.774983) (xy 335.262699 -342.79764) (xy 335.210373 -342.813008) (xy 335.156392 -342.820772)
			(xy 335.129124 -342.82126) (xy 334.265524 -342.82126) (xy 334.238252 -342.820802) (xy 334.184262 -342.813043)
			(xy 334.131926 -342.797678) (xy 334.08231 -342.775022) (xy 334.036423 -342.745535) (xy 333.9952 -342.709817)
			(xy 333.959479 -342.668596) (xy 333.929989 -342.622711) (xy 333.90733 -342.573096) (xy 333.891962 -342.520761)
			(xy 333.8842 -342.466772) (xy 332.401496 -342.466772) (xy 332.393733 -342.520762) (xy 332.378365 -342.573098)
			(xy 332.355705 -342.622713) (xy 332.326214 -342.668598) (xy 332.290493 -342.709819) (xy 332.249269 -342.745536)
			(xy 332.203381 -342.775023) (xy 332.153764 -342.797678) (xy 332.101427 -342.813041) (xy 332.047437 -342.820799)
			(xy 332.020164 -342.82126) (xy 331.156564 -342.82126) (xy 331.129296 -342.820775) (xy 331.075316 -342.813009)
			(xy 331.022991 -342.797641) (xy 330.973385 -342.774982) (xy 330.927508 -342.745495) (xy 330.886295 -342.70978)
			(xy 330.850583 -342.668563) (xy 330.8211 -342.622684) (xy 330.798447 -342.573076) (xy 330.783083 -342.520749)
			(xy 330.775322 -342.466768) (xy 329.292474 -342.466768) (xy 329.292474 -342.466769) (xy 329.284712 -342.520752)
			(xy 329.269347 -342.573081) (xy 329.246691 -342.622691) (xy 329.217206 -342.668571) (xy 329.181491 -342.709788)
			(xy 329.140274 -342.745503) (xy 329.094394 -342.774989) (xy 329.044785 -342.797646) (xy 328.992456 -342.813011)
			(xy 328.938473 -342.820773) (xy 328.911204 -342.82126) (xy 328.047604 -342.82126) (xy 328.020333 -342.820801)
			(xy 327.966345 -342.813039) (xy 327.914012 -342.797673) (xy 327.864398 -342.775016) (xy 327.818513 -342.745528)
			(xy 327.777293 -342.70981) (xy 327.741574 -342.66859) (xy 327.712086 -342.622706) (xy 327.689428 -342.573092)
			(xy 327.674062 -342.520759) (xy 327.6663 -342.466771) (xy 326.183473 -342.466771) (xy 326.175713 -342.520747)
			(xy 326.16035 -342.573072) (xy 326.137697 -342.622679) (xy 326.108216 -342.668558) (xy 326.072505 -342.709774)
			(xy 326.031293 -342.745489) (xy 325.985418 -342.774976) (xy 325.935814 -342.797635) (xy 325.88349 -342.813004)
			(xy 325.829511 -342.820771) (xy 325.802244 -342.82126) (xy 324.938644 -342.82126) (xy 324.911371 -342.820804)
			(xy 324.857379 -342.813046) (xy 324.805041 -342.797684) (xy 324.755422 -342.775029) (xy 324.709532 -342.745542)
			(xy 324.668307 -342.709824) (xy 324.632584 -342.668603) (xy 324.603092 -342.622717) (xy 324.580432 -342.573101)
			(xy 324.565063 -342.520764) (xy 324.5573 -342.466773) (xy 323.074596 -342.466773) (xy 323.066834 -342.52076)
			(xy 323.051467 -342.573093) (xy 323.028808 -342.622707) (xy 322.999319 -342.668591) (xy 322.9636 -342.709812)
			(xy 322.922379 -342.745529) (xy 322.876493 -342.775016) (xy 322.826878 -342.797673) (xy 322.774544 -342.813037)
			(xy 322.720556 -342.820798) (xy 322.693284 -342.82126) (xy 321.829684 -342.82126) (xy 321.802415 -342.820776)
			(xy 321.748433 -342.813013) (xy 321.696105 -342.797646) (xy 321.646497 -342.774989) (xy 321.600618 -342.745502)
			(xy 321.559402 -342.709787) (xy 321.523688 -342.66857) (xy 321.494203 -342.622689) (xy 321.471548 -342.57308)
			(xy 321.456184 -342.520751) (xy 321.448422 -342.466769) (xy 319.965574 -342.466769) (xy 319.957813 -342.520749)
			(xy 319.942449 -342.573077) (xy 319.919794 -342.622685) (xy 319.890311 -342.668565) (xy 319.854598 -342.709781)
			(xy 319.813384 -342.745496) (xy 319.767506 -342.774983) (xy 319.717899 -342.79764) (xy 319.665573 -342.813008)
			(xy 319.611592 -342.820772) (xy 319.584324 -342.82126) (xy 318.720724 -342.82126) (xy 318.693452 -342.820802)
			(xy 318.639462 -342.813043) (xy 318.587126 -342.797678) (xy 318.53751 -342.775022) (xy 318.491623 -342.745535)
			(xy 318.4504 -342.709817) (xy 318.414679 -342.668596) (xy 318.385189 -342.622711) (xy 318.36253 -342.573096)
			(xy 318.347162 -342.520761) (xy 318.3394 -342.466772) (xy 316.856376 -342.466772) (xy 316.848621 -342.52067)
			(xy 316.833272 -342.572948) (xy 316.810647 -342.622513) (xy 316.781205 -342.668358) (xy 316.745545 -342.709552)
			(xy 316.7253 -342.727788) (xy 316.722252 -342.730582) (xy 316.700583 -342.751837) (xy 316.651766 -342.787901)
			(xy 316.597862 -342.815797) (xy 316.540228 -342.834824) (xy 316.48031 -342.844504) (xy 316.449964 -342.845136)
			(xy 315.828426 -342.845136) (xy 315.816673 -342.845737) (xy 315.795628 -342.856206) (xy 315.78804 -342.865202)
			(xy 315.7601 -342.90254) (xy 315.749178 -342.917018) (xy 315.745368 -342.942164) (xy 315.749686 -342.954102)
			(xy 315.759294 -342.982941) (xy 315.769636 -343.042837) (xy 315.77026 -343.073228) (xy 315.77026 -343.073482)
			(xy 315.769741 -343.101467) (xy 315.760987 -343.156748) (xy 315.743692 -343.209978) (xy 315.718282 -343.259848)
			(xy 315.685383 -343.305127) (xy 315.645805 -343.344702) (xy 315.600522 -343.377598) (xy 315.550651 -343.403004)
			(xy 315.497419 -343.420294) (xy 315.442137 -343.429043) (xy 315.414152 -343.42959) (xy 315.403484 -343.429336)
			(xy 315.399928 -343.429336) (xy 315.388752 -343.42959) (xy 315.388498 -343.42959) (xy 315.36298 -343.429158)
			(xy 315.312466 -343.42188) (xy 315.263511 -343.407459) (xy 315.217118 -343.386191) (xy 315.195458 -343.372694)
			(xy 315.19495 -343.37244) (xy 315.187508 -343.368129) (xy 315.170765 -343.364236) (xy 315.162184 -343.36482)
			(xy 315.154056 -343.365582) (xy 315.138562 -343.372948) (xy 313.893962 -344.617548) (xy 313.888577 -344.623296)
			(xy 313.881326 -344.637266) (xy 313.879738 -344.64498) (xy 313.877198 -344.660728) (xy 313.881008 -344.668602)
			(xy 313.893323 -344.693822) (xy 313.910742 -344.747173) (xy 313.919589 -344.802593) (xy 313.920124 -344.830654)
			(xy 313.920124 -344.831162) (xy 313.919607 -344.85876) (xy 313.91109 -344.913294) (xy 313.894253 -344.965859)
			(xy 313.869502 -345.015194) (xy 313.83743 -345.060116) (xy 313.798806 -345.099546) (xy 313.754557 -345.132538)
			(xy 313.730386 -345.145868) (xy 313.720988 -345.150948) (xy 313.714384 -345.159076) (xy 313.711322 -345.163149)
			(xy 313.706708 -345.172231) (xy 313.70524 -345.17711) (xy 313.69889 -345.200224) (xy 313.68746 -345.242642)
			(xy 313.690254 -345.262962) (xy 313.695334 -345.271598) (xy 313.707832 -345.293689) (xy 313.727517 -345.340472)
			(xy 313.740821 -345.389454) (xy 313.747509 -345.439768) (xy 313.747912 -345.465146) (xy 313.747912 -345.489022)
			(xy 313.747852 -345.492364) (xy 315.23057 -345.492364) (xy 315.23057 -345.437836) (xy 315.23833 -345.383862)
			(xy 315.253692 -345.331541) (xy 315.276343 -345.281939) (xy 315.305821 -345.236066) (xy 315.341529 -345.194854)
			(xy 315.382737 -345.159143) (xy 315.428608 -345.12966) (xy 315.478207 -345.107004) (xy 315.530526 -345.091638)
			(xy 315.5845 -345.083873) (xy 315.611764 -345.083384) (xy 316.475364 -345.083384) (xy 316.50264 -345.083753)
			(xy 316.556637 -345.091512) (xy 316.608981 -345.106877) (xy 316.658604 -345.129535) (xy 316.704498 -345.159026)
			(xy 316.745727 -345.194747) (xy 316.781453 -345.235973) (xy 316.810947 -345.281864) (xy 316.83361 -345.331486)
			(xy 316.84898 -345.383828) (xy 316.856744 -345.437824) (xy 316.856744 -345.492369) (xy 318.339447 -345.492369)
			(xy 318.339447 -345.437831) (xy 318.347209 -345.383849) (xy 318.362575 -345.33152) (xy 318.385231 -345.281912)
			(xy 318.414718 -345.236032) (xy 318.450434 -345.194817) (xy 318.491652 -345.159103) (xy 318.537533 -345.12962)
			(xy 318.587143 -345.106966) (xy 318.639472 -345.091604) (xy 318.693455 -345.083846) (xy 318.720724 -345.083384)
			(xy 319.584324 -345.083384) (xy 319.611596 -345.08378) (xy 319.665583 -345.091546) (xy 319.717916 -345.106915)
			(xy 319.767529 -345.129575) (xy 319.813413 -345.159065) (xy 319.854632 -345.194785) (xy 319.890349 -345.236007)
			(xy 319.919836 -345.281892) (xy 319.942494 -345.331507) (xy 319.95786 -345.38384) (xy 319.965622 -345.437828)
			(xy 319.965622 -345.492365) (xy 321.44847 -345.492365) (xy 321.44847 -345.437835) (xy 321.456231 -345.383859)
			(xy 321.471593 -345.331537) (xy 321.494246 -345.281934) (xy 321.523726 -345.236059) (xy 321.559436 -345.194847)
			(xy 321.600646 -345.159136) (xy 321.64652 -345.129653) (xy 321.696122 -345.106999) (xy 321.748443 -345.091634)
			(xy 321.802419 -345.083871) (xy 321.829684 -345.083384) (xy 322.693284 -345.083384) (xy 322.720559 -345.083755)
			(xy 322.774554 -345.091516) (xy 322.826895 -345.106882) (xy 322.876516 -345.129542) (xy 322.922407 -345.159033)
			(xy 322.963634 -345.194754) (xy 322.999358 -345.23598) (xy 323.02885 -345.28187) (xy 323.051512 -345.33149)
			(xy 323.066881 -345.38383) (xy 323.074644 -345.437825) (xy 323.074644 -345.49237) (xy 324.557348 -345.49237)
			(xy 324.557348 -345.43783) (xy 324.56511 -345.383846) (xy 324.580476 -345.331516) (xy 324.603135 -345.281906)
			(xy 324.632623 -345.236026) (xy 324.668341 -345.194809) (xy 324.709561 -345.159096) (xy 324.755445 -345.129613)
			(xy 324.805057 -345.106961) (xy 324.857389 -345.0916) (xy 324.911374 -345.083844) (xy 324.938644 -345.083384)
			(xy 325.802244 -345.083384) (xy 325.829515 -345.083782) (xy 325.8835 -345.091549) (xy 325.93583 -345.10692)
			(xy 325.985441 -345.129582) (xy 326.031322 -345.159072) (xy 326.072539 -345.194792) (xy 326.108254 -345.236013)
			(xy 326.137739 -345.281898) (xy 326.160395 -345.331511) (xy 326.17576 -345.383843) (xy 326.183522 -345.437829)
			(xy 326.183522 -345.492368) (xy 327.666347 -345.492368) (xy 327.666347 -345.437832) (xy 327.674109 -345.383851)
			(xy 327.689473 -345.331525) (xy 327.712128 -345.281917) (xy 327.741613 -345.236039) (xy 327.777326 -345.194824)
			(xy 327.818542 -345.159111) (xy 327.864421 -345.129627) (xy 327.914028 -345.106972) (xy 327.966355 -345.091608)
			(xy 328.020336 -345.083847) (xy 328.047604 -345.083384) (xy 328.911204 -345.083384) (xy 328.938476 -345.083779)
			(xy 328.992466 -345.091542) (xy 329.044801 -345.106909) (xy 329.094417 -345.129569) (xy 329.140303 -345.159058)
			(xy 329.181525 -345.194778) (xy 329.217244 -345.236) (xy 329.246733 -345.281886) (xy 329.269392 -345.331502)
			(xy 329.284759 -345.383838) (xy 329.292521 -345.437828) (xy 329.292521 -345.492364) (xy 330.77537 -345.492364)
			(xy 330.77537 -345.437836) (xy 330.78313 -345.383862) (xy 330.798492 -345.331541) (xy 330.821143 -345.281939)
			(xy 330.850621 -345.236066) (xy 330.886329 -345.194854) (xy 330.927537 -345.159143) (xy 330.973408 -345.12966)
			(xy 331.023007 -345.107004) (xy 331.075326 -345.091638) (xy 331.1293 -345.083873) (xy 331.156564 -345.083384)
			(xy 332.020164 -345.083384) (xy 332.04744 -345.083753) (xy 332.101437 -345.091512) (xy 332.153781 -345.106877)
			(xy 332.203404 -345.129535) (xy 332.249298 -345.159026) (xy 332.290527 -345.194747) (xy 332.326253 -345.235973)
			(xy 332.355747 -345.281864) (xy 332.37841 -345.331486) (xy 332.39378 -345.383828) (xy 332.401544 -345.437824)
			(xy 332.401544 -345.492369) (xy 333.884247 -345.492369) (xy 333.884247 -345.437831) (xy 333.892009 -345.383849)
			(xy 333.907375 -345.33152) (xy 333.930031 -345.281912) (xy 333.959518 -345.236032) (xy 333.995234 -345.194817)
			(xy 334.036452 -345.159103) (xy 334.082333 -345.12962) (xy 334.131943 -345.106966) (xy 334.184272 -345.091604)
			(xy 334.238255 -345.083846) (xy 334.265524 -345.083384) (xy 335.129124 -345.083384) (xy 335.156396 -345.08378)
			(xy 335.210383 -345.091546) (xy 335.262716 -345.106915) (xy 335.312329 -345.129575) (xy 335.358213 -345.159065)
			(xy 335.399432 -345.194785) (xy 335.435149 -345.236007) (xy 335.464636 -345.281892) (xy 335.487294 -345.331507)
			(xy 335.50266 -345.38384) (xy 335.510422 -345.437828) (xy 335.510422 -345.492365) (xy 336.99327 -345.492365)
			(xy 336.99327 -345.437835) (xy 337.001031 -345.383859) (xy 337.016393 -345.331537) (xy 337.039046 -345.281934)
			(xy 337.068526 -345.236059) (xy 337.104236 -345.194847) (xy 337.145446 -345.159136) (xy 337.19132 -345.129653)
			(xy 337.240922 -345.106999) (xy 337.293243 -345.091634) (xy 337.347219 -345.083871) (xy 337.374484 -345.083384)
			(xy 338.238084 -345.083384) (xy 338.265359 -345.083755) (xy 338.319354 -345.091516) (xy 338.371695 -345.106882)
			(xy 338.421316 -345.129542) (xy 338.467207 -345.159033) (xy 338.508434 -345.194754) (xy 338.544158 -345.23598)
			(xy 338.57365 -345.28187) (xy 338.596312 -345.33149) (xy 338.611681 -345.38383) (xy 338.619444 -345.437825)
			(xy 338.619444 -345.49237) (xy 340.102148 -345.49237) (xy 340.102148 -345.43783) (xy 340.10991 -345.383846)
			(xy 340.125276 -345.331516) (xy 340.147935 -345.281906) (xy 340.177423 -345.236026) (xy 340.213141 -345.194809)
			(xy 340.254361 -345.159096) (xy 340.300245 -345.129613) (xy 340.349857 -345.106961) (xy 340.402189 -345.0916)
			(xy 340.456174 -345.083844) (xy 340.483444 -345.083384) (xy 341.347044 -345.083384) (xy 341.374315 -345.083782)
			(xy 341.4283 -345.091549) (xy 341.48063 -345.10692) (xy 341.530241 -345.129582) (xy 341.576122 -345.159072)
			(xy 341.617339 -345.194792) (xy 341.653054 -345.236013) (xy 341.682539 -345.281898) (xy 341.705195 -345.331511)
			(xy 341.72056 -345.383843) (xy 341.728322 -345.437829) (xy 341.728322 -345.492368) (xy 343.211147 -345.492368)
			(xy 343.211147 -345.437832) (xy 343.218909 -345.383851) (xy 343.234273 -345.331525) (xy 343.256928 -345.281917)
			(xy 343.286413 -345.236039) (xy 343.322126 -345.194824) (xy 343.363342 -345.159111) (xy 343.409221 -345.129627)
			(xy 343.458828 -345.106972) (xy 343.511155 -345.091608) (xy 343.565136 -345.083847) (xy 343.592404 -345.083384)
			(xy 344.456004 -345.083384) (xy 344.483276 -345.083779) (xy 344.537266 -345.091542) (xy 344.589601 -345.106909)
			(xy 344.639217 -345.129569) (xy 344.685103 -345.159058) (xy 344.726325 -345.194778) (xy 344.762044 -345.236)
			(xy 344.791533 -345.281886) (xy 344.814192 -345.331502) (xy 344.829559 -345.383838) (xy 344.837321 -345.437828)
			(xy 344.837321 -345.492365) (xy 370.80677 -345.492365) (xy 370.80677 -345.437835) (xy 370.81453 -345.383859)
			(xy 370.829893 -345.331538) (xy 370.852545 -345.281935) (xy 370.882025 -345.236061) (xy 370.917734 -345.194848)
			(xy 370.958945 -345.159137) (xy 371.004817 -345.129655) (xy 371.054419 -345.107) (xy 371.10674 -345.091635)
			(xy 371.160715 -345.083872) (xy 371.18798 -345.083384) (xy 372.05158 -345.083384) (xy 372.078855 -345.083754)
			(xy 372.132851 -345.091515) (xy 372.185192 -345.106881) (xy 372.234814 -345.129541) (xy 372.280705 -345.159031)
			(xy 372.321933 -345.194753) (xy 372.357657 -345.235978) (xy 372.38715 -345.281869) (xy 372.409812 -345.331489)
			(xy 372.425181 -345.38383) (xy 372.432944 -345.437825) (xy 372.432944 -345.49237) (xy 373.915647 -345.49237)
			(xy 373.915647 -345.43783) (xy 373.92341 -345.383847) (xy 373.938776 -345.331517) (xy 373.961434 -345.281907)
			(xy 373.990922 -345.236027) (xy 374.026639 -345.194811) (xy 374.067859 -345.159098) (xy 374.113742 -345.129615)
			(xy 374.163355 -345.106962) (xy 374.215686 -345.091601) (xy 374.26967 -345.083845) (xy 374.29694 -345.083384)
			(xy 375.16054 -345.083384) (xy 375.187811 -345.083781) (xy 375.241797 -345.091549) (xy 375.294128 -345.106919)
			(xy 375.343739 -345.12958) (xy 375.38962 -345.159071) (xy 375.430838 -345.19479) (xy 375.466553 -345.236012)
			(xy 375.496039 -345.281896) (xy 375.518695 -345.33151) (xy 375.53406 -345.383843) (xy 375.541822 -345.437829)
			(xy 375.541822 -345.492366) (xy 377.02467 -345.492366) (xy 377.02467 -345.437834) (xy 377.032431 -345.383857)
			(xy 377.047795 -345.331534) (xy 377.070448 -345.281929) (xy 377.09993 -345.236054) (xy 377.135641 -345.194841)
			(xy 377.176854 -345.15913) (xy 377.222729 -345.129648) (xy 377.272334 -345.106995) (xy 377.324657 -345.091631)
			(xy 377.378634 -345.08387) (xy 377.4059 -345.083384) (xy 378.2695 -345.083384) (xy 378.296773 -345.083779)
			(xy 378.350763 -345.091541) (xy 378.403099 -345.106908) (xy 378.452715 -345.129567) (xy 378.498601 -345.159057)
			(xy 378.539824 -345.194776) (xy 378.575543 -345.235999) (xy 378.605033 -345.281885) (xy 378.627692 -345.331501)
			(xy 378.643059 -345.383837) (xy 378.650821 -345.437827) (xy 378.650821 -345.492364) (xy 380.13367 -345.492364)
			(xy 380.13367 -345.437836) (xy 380.14143 -345.383862) (xy 380.156791 -345.331542) (xy 380.179442 -345.281941)
			(xy 380.208921 -345.236067) (xy 380.244627 -345.194855) (xy 380.285835 -345.159145) (xy 380.331705 -345.129661)
			(xy 380.381305 -345.107005) (xy 380.433623 -345.091638) (xy 380.487596 -345.083873) (xy 380.51486 -345.083384)
			(xy 381.37846 -345.083384) (xy 381.405736 -345.083753) (xy 381.459734 -345.091511) (xy 381.512078 -345.106876)
			(xy 381.561702 -345.129534) (xy 381.607596 -345.159024) (xy 381.648826 -345.194746) (xy 381.684552 -345.235972)
			(xy 381.714047 -345.281863) (xy 381.73671 -345.331485) (xy 381.75208 -345.383827) (xy 381.759844 -345.437824)
			(xy 381.759844 -345.492369) (xy 383.242547 -345.492369) (xy 383.242547 -345.437831) (xy 383.250309 -345.383849)
			(xy 383.265675 -345.331521) (xy 383.288331 -345.281913) (xy 383.317817 -345.236034) (xy 383.353532 -345.194818)
			(xy 383.39475 -345.159105) (xy 383.44063 -345.129621) (xy 383.49024 -345.106968) (xy 383.542569 -345.091605)
			(xy 383.596551 -345.083846) (xy 383.62382 -345.083384) (xy 384.48742 -345.083384) (xy 384.514692 -345.08378)
			(xy 384.56868 -345.091545) (xy 384.621013 -345.106914) (xy 384.670627 -345.129574) (xy 384.716511 -345.159064)
			(xy 384.757731 -345.194783) (xy 384.793448 -345.236005) (xy 384.822936 -345.281891) (xy 384.845593 -345.331506)
			(xy 384.860959 -345.38384) (xy 384.868722 -345.437828) (xy 384.868722 -345.492365) (xy 386.35157 -345.492365)
			(xy 386.35157 -345.437835) (xy 386.35933 -345.383859) (xy 386.374693 -345.331538) (xy 386.397345 -345.281935)
			(xy 386.426825 -345.236061) (xy 386.462534 -345.194848) (xy 386.503745 -345.159137) (xy 386.549617 -345.129655)
			(xy 386.599219 -345.107) (xy 386.65154 -345.091635) (xy 386.705515 -345.083872) (xy 386.73278 -345.083384)
			(xy 387.59638 -345.083384) (xy 387.623655 -345.083754) (xy 387.677651 -345.091515) (xy 387.729992 -345.106881)
			(xy 387.779614 -345.129541) (xy 387.825505 -345.159031) (xy 387.866733 -345.194753) (xy 387.902457 -345.235978)
			(xy 387.93195 -345.281869) (xy 387.954612 -345.331489) (xy 387.969981 -345.38383) (xy 387.977744 -345.437825)
			(xy 387.977744 -345.49237) (xy 389.460447 -345.49237) (xy 389.460447 -345.43783) (xy 389.46821 -345.383847)
			(xy 389.483576 -345.331517) (xy 389.506234 -345.281907) (xy 389.535722 -345.236027) (xy 389.571439 -345.194811)
			(xy 389.612659 -345.159098) (xy 389.658542 -345.129615) (xy 389.708155 -345.106962) (xy 389.760486 -345.091601)
			(xy 389.81447 -345.083845) (xy 389.84174 -345.083384) (xy 390.70534 -345.083384) (xy 390.732611 -345.083781)
			(xy 390.786597 -345.091549) (xy 390.838928 -345.106919) (xy 390.888539 -345.12958) (xy 390.93442 -345.159071)
			(xy 390.975638 -345.19479) (xy 391.011353 -345.236012) (xy 391.040839 -345.281896) (xy 391.063495 -345.33151)
			(xy 391.07886 -345.383843) (xy 391.086622 -345.437829) (xy 391.086622 -345.492366) (xy 392.56947 -345.492366)
			(xy 392.56947 -345.437834) (xy 392.577231 -345.383857) (xy 392.592595 -345.331534) (xy 392.615248 -345.281929)
			(xy 392.64473 -345.236054) (xy 392.680441 -345.194841) (xy 392.721654 -345.15913) (xy 392.767529 -345.129648)
			(xy 392.817134 -345.106995) (xy 392.869457 -345.091631) (xy 392.923434 -345.08387) (xy 392.9507 -345.083384)
			(xy 393.8143 -345.083384) (xy 393.841573 -345.083779) (xy 393.895563 -345.091541) (xy 393.947899 -345.106908)
			(xy 393.997515 -345.129567) (xy 394.043401 -345.159057) (xy 394.084624 -345.194776) (xy 394.120343 -345.235999)
			(xy 394.149833 -345.281885) (xy 394.172492 -345.331501) (xy 394.187859 -345.383837) (xy 394.195621 -345.437827)
			(xy 394.195621 -345.492364) (xy 395.67847 -345.492364) (xy 395.67847 -345.437836) (xy 395.68623 -345.383862)
			(xy 395.701591 -345.331542) (xy 395.724242 -345.281941) (xy 395.753721 -345.236067) (xy 395.789427 -345.194855)
			(xy 395.830635 -345.159145) (xy 395.876505 -345.129661) (xy 395.926105 -345.107005) (xy 395.978423 -345.091638)
			(xy 396.032396 -345.083873) (xy 396.05966 -345.083384) (xy 396.92326 -345.083384) (xy 396.950536 -345.083753)
			(xy 397.004534 -345.091511) (xy 397.056878 -345.106876) (xy 397.106502 -345.129534) (xy 397.152396 -345.159024)
			(xy 397.193626 -345.194746) (xy 397.229352 -345.235972) (xy 397.258847 -345.281863) (xy 397.28151 -345.331485)
			(xy 397.29688 -345.383827) (xy 397.304644 -345.437824) (xy 397.304644 -345.492369) (xy 398.787347 -345.492369)
			(xy 398.787347 -345.437831) (xy 398.795109 -345.383849) (xy 398.810475 -345.331521) (xy 398.833131 -345.281913)
			(xy 398.862617 -345.236034) (xy 398.898332 -345.194818) (xy 398.93955 -345.159105) (xy 398.98543 -345.129621)
			(xy 399.03504 -345.106968) (xy 399.087369 -345.091605) (xy 399.141351 -345.083846) (xy 399.16862 -345.083384)
			(xy 400.03222 -345.083384) (xy 400.059492 -345.08378) (xy 400.11348 -345.091545) (xy 400.165813 -345.106914)
			(xy 400.215427 -345.129574) (xy 400.261311 -345.159064) (xy 400.302531 -345.194783) (xy 400.338248 -345.236005)
			(xy 400.367736 -345.281891) (xy 400.390393 -345.331506) (xy 400.405759 -345.38384) (xy 400.413522 -345.437828)
			(xy 400.413522 -345.492372) (xy 400.405759 -345.54636) (xy 400.390393 -345.598694) (xy 400.367736 -345.648309)
			(xy 400.338248 -345.694195) (xy 400.302531 -345.735417) (xy 400.261311 -345.771136) (xy 400.215427 -345.800626)
			(xy 400.165813 -345.823286) (xy 400.11348 -345.838655) (xy 400.059492 -345.84642) (xy 400.03222 -345.846908)
			(xy 399.16862 -345.846908) (xy 399.141351 -345.846354) (xy 399.087369 -345.838595) (xy 399.03504 -345.823232)
			(xy 398.98543 -345.800579) (xy 398.93955 -345.771095) (xy 398.898332 -345.735382) (xy 398.862617 -345.694166)
			(xy 398.833131 -345.648287) (xy 398.810475 -345.598679) (xy 398.795109 -345.546351) (xy 398.787347 -345.492369)
			(xy 397.304644 -345.492369) (xy 397.304644 -345.492376) (xy 397.29688 -345.546373) (xy 397.28151 -345.598715)
			(xy 397.258847 -345.648337) (xy 397.229352 -345.694228) (xy 397.193626 -345.735454) (xy 397.152396 -345.771176)
			(xy 397.106502 -345.800666) (xy 397.056878 -345.823324) (xy 397.004534 -345.838689) (xy 396.950536 -345.846447)
			(xy 396.92326 -345.846908) (xy 396.05966 -345.846908) (xy 396.032396 -345.846327) (xy 395.978423 -345.838562)
			(xy 395.926105 -345.823195) (xy 395.876505 -345.800539) (xy 395.830635 -345.771055) (xy 395.789427 -345.735345)
			(xy 395.753721 -345.694133) (xy 395.724242 -345.648259) (xy 395.701591 -345.598658) (xy 395.68623 -345.546338)
			(xy 395.67847 -345.492364) (xy 394.195621 -345.492364) (xy 394.195621 -345.492373) (xy 394.187859 -345.546363)
			(xy 394.172492 -345.598699) (xy 394.149833 -345.648315) (xy 394.120343 -345.694201) (xy 394.084624 -345.735424)
			(xy 394.043401 -345.771143) (xy 393.997515 -345.800633) (xy 393.947899 -345.823292) (xy 393.895563 -345.838659)
			(xy 393.841573 -345.846421) (xy 393.8143 -345.846908) (xy 392.9507 -345.846908) (xy 392.923434 -345.84633)
			(xy 392.869457 -345.838569) (xy 392.817134 -345.823205) (xy 392.767529 -345.800552) (xy 392.721654 -345.77107)
			(xy 392.680441 -345.735359) (xy 392.64473 -345.694146) (xy 392.615248 -345.648271) (xy 392.592595 -345.598666)
			(xy 392.577231 -345.546343) (xy 392.56947 -345.492366) (xy 391.086622 -345.492366) (xy 391.086622 -345.492371)
			(xy 391.07886 -345.546357) (xy 391.063495 -345.59869) (xy 391.040839 -345.648304) (xy 391.011353 -345.694188)
			(xy 390.975638 -345.73541) (xy 390.93442 -345.771129) (xy 390.888539 -345.80062) (xy 390.838928 -345.823281)
			(xy 390.786597 -345.838651) (xy 390.732611 -345.846419) (xy 390.70534 -345.846908) (xy 389.84174 -345.846908)
			(xy 389.81447 -345.846355) (xy 389.760486 -345.838599) (xy 389.708155 -345.823238) (xy 389.658542 -345.800585)
			(xy 389.612659 -345.771102) (xy 389.571439 -345.735389) (xy 389.535722 -345.694173) (xy 389.506234 -345.648293)
			(xy 389.483576 -345.598683) (xy 389.46821 -345.546353) (xy 389.460447 -345.49237) (xy 387.977744 -345.49237)
			(xy 387.977744 -345.492375) (xy 387.969981 -345.54637) (xy 387.954612 -345.598711) (xy 387.93195 -345.648331)
			(xy 387.902457 -345.694221) (xy 387.866733 -345.735447) (xy 387.825505 -345.771169) (xy 387.779614 -345.800659)
			(xy 387.729992 -345.823319) (xy 387.677651 -345.838685) (xy 387.623655 -345.846446) (xy 387.59638 -345.846908)
			(xy 386.73278 -345.846908) (xy 386.705515 -345.846328) (xy 386.65154 -345.838565) (xy 386.599219 -345.8232)
			(xy 386.549617 -345.800545) (xy 386.503745 -345.771063) (xy 386.462534 -345.735352) (xy 386.426825 -345.694139)
			(xy 386.397345 -345.648265) (xy 386.374693 -345.598662) (xy 386.35933 -345.546341) (xy 386.35157 -345.492365)
			(xy 384.868722 -345.492365) (xy 384.868722 -345.492372) (xy 384.860959 -345.54636) (xy 384.845593 -345.598694)
			(xy 384.822936 -345.648309) (xy 384.793448 -345.694195) (xy 384.757731 -345.735417) (xy 384.716511 -345.771136)
			(xy 384.670627 -345.800626) (xy 384.621013 -345.823286) (xy 384.56868 -345.838655) (xy 384.514692 -345.84642)
			(xy 384.48742 -345.846908) (xy 383.62382 -345.846908) (xy 383.596551 -345.846354) (xy 383.542569 -345.838595)
			(xy 383.49024 -345.823232) (xy 383.44063 -345.800579) (xy 383.39475 -345.771095) (xy 383.353532 -345.735382)
			(xy 383.317817 -345.694166) (xy 383.288331 -345.648287) (xy 383.265675 -345.598679) (xy 383.250309 -345.546351)
			(xy 383.242547 -345.492369) (xy 381.759844 -345.492369) (xy 381.759844 -345.492376) (xy 381.75208 -345.546373)
			(xy 381.73671 -345.598715) (xy 381.714047 -345.648337) (xy 381.684552 -345.694228) (xy 381.648826 -345.735454)
			(xy 381.607596 -345.771176) (xy 381.561702 -345.800666) (xy 381.512078 -345.823324) (xy 381.459734 -345.838689)
			(xy 381.405736 -345.846447) (xy 381.37846 -345.846908) (xy 380.51486 -345.846908) (xy 380.487596 -345.846327)
			(xy 380.433623 -345.838562) (xy 380.381305 -345.823195) (xy 380.331705 -345.800539) (xy 380.285835 -345.771055)
			(xy 380.244627 -345.735345) (xy 380.208921 -345.694133) (xy 380.179442 -345.648259) (xy 380.156791 -345.598658)
			(xy 380.14143 -345.546338) (xy 380.13367 -345.492364) (xy 378.650821 -345.492364) (xy 378.650821 -345.492373)
			(xy 378.643059 -345.546363) (xy 378.627692 -345.598699) (xy 378.605033 -345.648315) (xy 378.575543 -345.694201)
			(xy 378.539824 -345.735424) (xy 378.498601 -345.771143) (xy 378.452715 -345.800633) (xy 378.403099 -345.823292)
			(xy 378.350763 -345.838659) (xy 378.296773 -345.846421) (xy 378.2695 -345.846908) (xy 377.4059 -345.846908)
			(xy 377.378634 -345.84633) (xy 377.324657 -345.838569) (xy 377.272334 -345.823205) (xy 377.222729 -345.800552)
			(xy 377.176854 -345.77107) (xy 377.135641 -345.735359) (xy 377.09993 -345.694146) (xy 377.070448 -345.648271)
			(xy 377.047795 -345.598666) (xy 377.032431 -345.546343) (xy 377.02467 -345.492366) (xy 375.541822 -345.492366)
			(xy 375.541822 -345.492371) (xy 375.53406 -345.546357) (xy 375.518695 -345.59869) (xy 375.496039 -345.648304)
			(xy 375.466553 -345.694188) (xy 375.430838 -345.73541) (xy 375.38962 -345.771129) (xy 375.343739 -345.80062)
			(xy 375.294128 -345.823281) (xy 375.241797 -345.838651) (xy 375.187811 -345.846419) (xy 375.16054 -345.846908)
			(xy 374.29694 -345.846908) (xy 374.26967 -345.846355) (xy 374.215686 -345.838599) (xy 374.163355 -345.823238)
			(xy 374.113742 -345.800585) (xy 374.067859 -345.771102) (xy 374.026639 -345.735389) (xy 373.990922 -345.694173)
			(xy 373.961434 -345.648293) (xy 373.938776 -345.598683) (xy 373.92341 -345.546353) (xy 373.915647 -345.49237)
			(xy 372.432944 -345.49237) (xy 372.432944 -345.492375) (xy 372.425181 -345.54637) (xy 372.409812 -345.598711)
			(xy 372.38715 -345.648331) (xy 372.357657 -345.694221) (xy 372.321933 -345.735447) (xy 372.280705 -345.771169)
			(xy 372.234814 -345.800659) (xy 372.185192 -345.823319) (xy 372.132851 -345.838685) (xy 372.078855 -345.846446)
			(xy 372.05158 -345.846908) (xy 371.18798 -345.846908) (xy 371.160715 -345.846328) (xy 371.10674 -345.838565)
			(xy 371.054419 -345.8232) (xy 371.004817 -345.800545) (xy 370.958945 -345.771063) (xy 370.917734 -345.735352)
			(xy 370.882025 -345.694139) (xy 370.852545 -345.648265) (xy 370.829893 -345.598662) (xy 370.81453 -345.546341)
			(xy 370.80677 -345.492365) (xy 344.837321 -345.492365) (xy 344.837321 -345.492372) (xy 344.829559 -345.546362)
			(xy 344.814192 -345.598698) (xy 344.791533 -345.648314) (xy 344.762044 -345.6942) (xy 344.726325 -345.735422)
			(xy 344.685103 -345.771142) (xy 344.639217 -345.800631) (xy 344.589601 -345.823291) (xy 344.537266 -345.838658)
			(xy 344.483276 -345.846421) (xy 344.456004 -345.846908) (xy 343.592404 -345.846908) (xy 343.565136 -345.846353)
			(xy 343.511155 -345.838592) (xy 343.458828 -345.823228) (xy 343.409221 -345.800573) (xy 343.363342 -345.771089)
			(xy 343.322126 -345.735376) (xy 343.286413 -345.694161) (xy 343.256928 -345.648283) (xy 343.234273 -345.598675)
			(xy 343.218909 -345.546349) (xy 343.211147 -345.492368) (xy 341.728322 -345.492368) (xy 341.728322 -345.492371)
			(xy 341.72056 -345.546357) (xy 341.705195 -345.598689) (xy 341.682539 -345.648302) (xy 341.653054 -345.694187)
			(xy 341.617339 -345.735408) (xy 341.576122 -345.771128) (xy 341.530241 -345.800618) (xy 341.48063 -345.82328)
			(xy 341.4283 -345.838651) (xy 341.374315 -345.846418) (xy 341.347044 -345.846908) (xy 340.483444 -345.846908)
			(xy 340.456174 -345.846356) (xy 340.402189 -345.8386) (xy 340.349857 -345.823239) (xy 340.300245 -345.800587)
			(xy 340.254361 -345.771104) (xy 340.213141 -345.735391) (xy 340.177423 -345.694174) (xy 340.147935 -345.648294)
			(xy 340.125276 -345.598684) (xy 340.10991 -345.546354) (xy 340.102148 -345.49237) (xy 338.619444 -345.49237)
			(xy 338.619444 -345.492375) (xy 338.611681 -345.54637) (xy 338.596312 -345.59871) (xy 338.57365 -345.64833)
			(xy 338.544158 -345.69422) (xy 338.508434 -345.735446) (xy 338.467207 -345.771167) (xy 338.421316 -345.800658)
			(xy 338.371695 -345.823318) (xy 338.319354 -345.838684) (xy 338.265359 -345.846445) (xy 338.238084 -345.846908)
			(xy 337.374484 -345.846908) (xy 337.347219 -345.846329) (xy 337.293243 -345.838566) (xy 337.240922 -345.823201)
			(xy 337.19132 -345.800547) (xy 337.145446 -345.771064) (xy 337.104236 -345.735353) (xy 337.068526 -345.694141)
			(xy 337.039046 -345.648266) (xy 337.016393 -345.598663) (xy 337.001031 -345.546341) (xy 336.99327 -345.492365)
			(xy 335.510422 -345.492365) (xy 335.510422 -345.492372) (xy 335.50266 -345.54636) (xy 335.487294 -345.598693)
			(xy 335.464636 -345.648308) (xy 335.435149 -345.694193) (xy 335.399432 -345.735415) (xy 335.358213 -345.771135)
			(xy 335.312329 -345.800625) (xy 335.262716 -345.823285) (xy 335.210383 -345.838654) (xy 335.156396 -345.84642)
			(xy 335.129124 -345.846908) (xy 334.265524 -345.846908) (xy 334.238255 -345.846354) (xy 334.184272 -345.838596)
			(xy 334.131943 -345.823234) (xy 334.082333 -345.80058) (xy 334.036452 -345.771097) (xy 333.995234 -345.735383)
			(xy 333.959518 -345.694168) (xy 333.930031 -345.648288) (xy 333.907375 -345.59868) (xy 333.892009 -345.546351)
			(xy 333.884247 -345.492369) (xy 332.401544 -345.492369) (xy 332.401544 -345.492376) (xy 332.39378 -345.546372)
			(xy 332.37841 -345.598714) (xy 332.355747 -345.648336) (xy 332.326253 -345.694227) (xy 332.290527 -345.735453)
			(xy 332.249298 -345.771174) (xy 332.203404 -345.800665) (xy 332.153781 -345.823323) (xy 332.101437 -345.838688)
			(xy 332.04744 -345.846447) (xy 332.020164 -345.846908) (xy 331.156564 -345.846908) (xy 331.1293 -345.846327)
			(xy 331.075326 -345.838562) (xy 331.023007 -345.823196) (xy 330.973408 -345.80054) (xy 330.927537 -345.771057)
			(xy 330.886329 -345.735346) (xy 330.850622 -345.694134) (xy 330.821143 -345.648261) (xy 330.798492 -345.598659)
			(xy 330.78313 -345.546338) (xy 330.77537 -345.492364) (xy 329.292521 -345.492364) (xy 329.292521 -345.492372)
			(xy 329.284759 -345.546362) (xy 329.269392 -345.598698) (xy 329.246733 -345.648314) (xy 329.217244 -345.6942)
			(xy 329.181525 -345.735422) (xy 329.140303 -345.771142) (xy 329.094417 -345.800631) (xy 329.044801 -345.823291)
			(xy 328.992466 -345.838658) (xy 328.938476 -345.846421) (xy 328.911204 -345.846908) (xy 328.047604 -345.846908)
			(xy 328.020336 -345.846353) (xy 327.966355 -345.838592) (xy 327.914028 -345.823228) (xy 327.864421 -345.800573)
			(xy 327.818542 -345.771089) (xy 327.777326 -345.735376) (xy 327.741613 -345.694161) (xy 327.712128 -345.648283)
			(xy 327.689473 -345.598675) (xy 327.674109 -345.546349) (xy 327.666347 -345.492368) (xy 326.183522 -345.492368)
			(xy 326.183522 -345.492371) (xy 326.17576 -345.546357) (xy 326.160395 -345.598689) (xy 326.137739 -345.648302)
			(xy 326.108254 -345.694187) (xy 326.072539 -345.735408) (xy 326.031322 -345.771128) (xy 325.985441 -345.800618)
			(xy 325.93583 -345.82328) (xy 325.8835 -345.838651) (xy 325.829515 -345.846418) (xy 325.802244 -345.846908)
			(xy 324.938644 -345.846908) (xy 324.911374 -345.846356) (xy 324.857389 -345.8386) (xy 324.805057 -345.823239)
			(xy 324.755445 -345.800587) (xy 324.709561 -345.771104) (xy 324.668341 -345.735391) (xy 324.632623 -345.694174)
			(xy 324.603135 -345.648294) (xy 324.580476 -345.598684) (xy 324.56511 -345.546354) (xy 324.557348 -345.49237)
			(xy 323.074644 -345.49237) (xy 323.074644 -345.492375) (xy 323.066881 -345.54637) (xy 323.051512 -345.59871)
			(xy 323.02885 -345.64833) (xy 322.999358 -345.69422) (xy 322.963634 -345.735446) (xy 322.922407 -345.771167)
			(xy 322.876516 -345.800658) (xy 322.826895 -345.823318) (xy 322.774554 -345.838684) (xy 322.720559 -345.846445)
			(xy 322.693284 -345.846908) (xy 321.829684 -345.846908) (xy 321.802419 -345.846329) (xy 321.748443 -345.838566)
			(xy 321.696122 -345.823201) (xy 321.64652 -345.800547) (xy 321.600646 -345.771064) (xy 321.559436 -345.735353)
			(xy 321.523726 -345.694141) (xy 321.494246 -345.648266) (xy 321.471593 -345.598663) (xy 321.456231 -345.546341)
			(xy 321.44847 -345.492365) (xy 319.965622 -345.492365) (xy 319.965622 -345.492372) (xy 319.95786 -345.54636)
			(xy 319.942494 -345.598693) (xy 319.919836 -345.648308) (xy 319.890349 -345.694193) (xy 319.854632 -345.735415)
			(xy 319.813413 -345.771135) (xy 319.767529 -345.800625) (xy 319.717916 -345.823285) (xy 319.665583 -345.838654)
			(xy 319.611596 -345.84642) (xy 319.584324 -345.846908) (xy 318.720724 -345.846908) (xy 318.693455 -345.846354)
			(xy 318.639472 -345.838596) (xy 318.587143 -345.823234) (xy 318.537533 -345.80058) (xy 318.491652 -345.771097)
			(xy 318.450434 -345.735383) (xy 318.414718 -345.694168) (xy 318.385231 -345.648288) (xy 318.362575 -345.59868)
			(xy 318.347209 -345.546351) (xy 318.339447 -345.492369) (xy 316.856744 -345.492369) (xy 316.856744 -345.492376)
			(xy 316.84898 -345.546372) (xy 316.83361 -345.598714) (xy 316.810947 -345.648336) (xy 316.781453 -345.694227)
			(xy 316.745727 -345.735453) (xy 316.704498 -345.771174) (xy 316.658604 -345.800665) (xy 316.608981 -345.823323)
			(xy 316.556637 -345.838688) (xy 316.50264 -345.846447) (xy 316.475364 -345.846908) (xy 315.611764 -345.846908)
			(xy 315.5845 -345.846327) (xy 315.530526 -345.838562) (xy 315.478207 -345.823196) (xy 315.428608 -345.80054)
			(xy 315.382737 -345.771057) (xy 315.341529 -345.735346) (xy 315.305822 -345.694134) (xy 315.276343 -345.648261)
			(xy 315.253692 -345.598659) (xy 315.23833 -345.546338) (xy 315.23057 -345.492364) (xy 313.747852 -345.492364)
			(xy 313.747425 -345.51628) (xy 313.739668 -345.570242) (xy 313.724314 -345.622551) (xy 313.701675 -345.672145)
			(xy 313.672213 -345.718014) (xy 313.636526 -345.759227) (xy 313.59534 -345.794944) (xy 313.549493 -345.82444)
			(xy 313.499916 -345.847115) (xy 313.447618 -345.862507) (xy 313.393662 -345.870305) (xy 313.366404 -345.870784)
			(xy 312.744866 -345.870784) (xy 312.73311 -345.871378) (xy 312.712059 -345.881843) (xy 312.70448 -345.89085)
			(xy 312.687716 -345.913202) (xy 312.655458 -345.956382) (xy 312.652046 -345.961112) (xy 312.647305 -345.971766)
			(xy 312.64606 -345.977464) (xy 312.644028 -345.98864) (xy 312.64733 -346.000324) (xy 312.653864 -346.024501)
			(xy 312.660873 -346.074089) (xy 312.6613 -346.09913) (xy 312.660771 -346.126835) (xy 312.652186 -346.181577)
			(xy 312.635228 -346.234328) (xy 312.610305 -346.283818) (xy 312.57802 -346.328851) (xy 312.539151 -346.368341)
			(xy 312.494636 -346.401337) (xy 312.445548 -346.427041) (xy 312.393072 -346.444834) (xy 312.338474 -346.454286)
			(xy 312.31078 -346.455238) (xy 312.304684 -346.455238) (xy 312.276911 -346.454682) (xy 312.222044 -346.446011)
			(xy 312.169188 -346.42893) (xy 312.144156 -346.416884) (xy 312.130694 -346.409772) (xy 312.129424 -346.409264)
			(xy 312.113168 -346.412058) (xy 312.105317 -346.413574) (xy 312.091073 -346.420825) (xy 312.085228 -346.426282)
			(xy 311.586372 -346.925138) (xy 311.581761 -346.929992) (xy 311.575062 -346.941578) (xy 311.573164 -346.947998)
			(xy 311.571619 -346.954513) (xy 311.571621 -346.967898) (xy 311.573164 -346.974414) (xy 311.574942 -346.987622)
			(xy 311.574942 -348.613072) (xy 312.121492 -348.613072) (xy 312.121492 -348.558528) (xy 312.129254 -348.504539)
			(xy 312.144621 -348.452205) (xy 312.167279 -348.40259) (xy 312.196768 -348.356705) (xy 312.232487 -348.315484)
			(xy 312.273709 -348.279766) (xy 312.319594 -348.250277) (xy 312.369209 -348.227619) (xy 312.421543 -348.212253)
			(xy 312.475532 -348.204491) (xy 312.502804 -348.204028) (xy 313.366404 -348.204028) (xy 313.393672 -348.204535)
			(xy 313.447654 -348.212297) (xy 313.499982 -348.227662) (xy 313.54959 -348.250318) (xy 313.595469 -348.279803)
			(xy 313.636686 -348.315517) (xy 313.672399 -348.356734) (xy 313.701884 -348.402613) (xy 313.72454 -348.452222)
			(xy 313.739904 -348.50455) (xy 313.747666 -348.558532) (xy 313.747666 -348.613068) (xy 315.230514 -348.613068)
			(xy 315.230514 -348.558532) (xy 315.238275 -348.50455) (xy 315.253639 -348.452222) (xy 315.276293 -348.402613)
			(xy 315.305777 -348.356732) (xy 315.341489 -348.315514) (xy 315.382703 -348.279798) (xy 315.428581 -348.250311)
			(xy 315.478188 -348.227652) (xy 315.530514 -348.212283) (xy 315.584496 -348.204517) (xy 315.611764 -348.204028)
			(xy 316.475364 -348.204028) (xy 316.502636 -348.204509) (xy 316.556625 -348.212267) (xy 316.608961 -348.22763)
			(xy 316.658577 -348.250284) (xy 316.704464 -348.27977) (xy 316.745688 -348.315487) (xy 316.781408 -348.356707)
			(xy 316.810898 -348.402591) (xy 316.833558 -348.452205) (xy 316.848926 -348.504539) (xy 316.856688 -348.558528)
			(xy 316.856688 -348.613072) (xy 316.856688 -348.613073) (xy 318.339392 -348.613073) (xy 318.339392 -348.558527)
			(xy 318.347155 -348.504537) (xy 318.362522 -348.452201) (xy 318.385182 -348.402585) (xy 318.414673 -348.356699)
			(xy 318.450394 -348.315477) (xy 318.491618 -348.279759) (xy 318.537506 -348.250271) (xy 318.587123 -348.227614)
			(xy 318.63946 -348.212249) (xy 318.693451 -348.20449) (xy 318.720724 -348.204028) (xy 319.584324 -348.204028)
			(xy 319.611592 -348.204536) (xy 319.665571 -348.2123) (xy 319.717896 -348.227667) (xy 319.767502 -348.250324)
			(xy 319.813379 -348.27981) (xy 319.854593 -348.315524) (xy 319.890304 -348.35674) (xy 319.919787 -348.402619)
			(xy 319.942441 -348.452226) (xy 319.957805 -348.504552) (xy 319.965566 -348.558532) (xy 319.965566 -348.613068)
			(xy 319.965566 -348.613069) (xy 321.448414 -348.613069) (xy 321.448414 -348.558531) (xy 321.456176 -348.504547)
			(xy 321.471541 -348.452217) (xy 321.494196 -348.402607) (xy 321.523682 -348.356726) (xy 321.559396 -348.315507)
			(xy 321.600613 -348.279791) (xy 321.646493 -348.250304) (xy 321.696102 -348.227646) (xy 321.748431 -348.212279)
			(xy 321.802415 -348.204516) (xy 321.829684 -348.204028) (xy 322.693284 -348.204028) (xy 322.720555 -348.20451)
			(xy 322.774542 -348.21227) (xy 322.826875 -348.227635) (xy 322.876489 -348.250291) (xy 322.922374 -348.279777)
			(xy 322.963595 -348.315494) (xy 322.999313 -348.356713) (xy 323.028801 -348.402597) (xy 323.051459 -348.45221)
			(xy 323.066826 -348.504542) (xy 323.074588 -348.558529) (xy 323.074588 -348.613071) (xy 323.074588 -348.613074)
			(xy 324.557292 -348.613074) (xy 324.557292 -348.558526) (xy 324.565055 -348.504534) (xy 324.580424 -348.452197)
			(xy 324.603085 -348.402579) (xy 324.632578 -348.356692) (xy 324.668301 -348.31547) (xy 324.709527 -348.279751)
			(xy 324.755418 -348.250264) (xy 324.805038 -348.227609) (xy 324.857377 -348.212246) (xy 324.91137 -348.204489)
			(xy 324.938644 -348.204028) (xy 325.802244 -348.204028) (xy 325.829511 -348.204537) (xy 325.883488 -348.212304)
			(xy 325.935811 -348.227673) (xy 325.985414 -348.250331) (xy 326.031288 -348.279817) (xy 326.0725 -348.315531)
			(xy 326.108209 -348.356747) (xy 326.13769 -348.402624) (xy 326.160343 -348.45223) (xy 326.175705 -348.504555)
			(xy 326.183466 -348.558533) (xy 326.183466 -348.613067) (xy 326.183465 -348.613072) (xy 327.666292 -348.613072)
			(xy 327.666292 -348.558528) (xy 327.674054 -348.504539) (xy 327.689421 -348.452205) (xy 327.712079 -348.40259)
			(xy 327.741568 -348.356705) (xy 327.777287 -348.315484) (xy 327.818509 -348.279766) (xy 327.864394 -348.250277)
			(xy 327.914009 -348.227619) (xy 327.966343 -348.212253) (xy 328.020332 -348.204491) (xy 328.047604 -348.204028)
			(xy 328.911204 -348.204028) (xy 328.938472 -348.204535) (xy 328.992454 -348.212297) (xy 329.044782 -348.227662)
			(xy 329.09439 -348.250318) (xy 329.140269 -348.279803) (xy 329.181486 -348.315517) (xy 329.217199 -348.356734)
			(xy 329.246684 -348.402613) (xy 329.26934 -348.452222) (xy 329.284704 -348.50455) (xy 329.292466 -348.558532)
			(xy 329.292466 -348.613068) (xy 330.775314 -348.613068) (xy 330.775314 -348.558532) (xy 330.783075 -348.50455)
			(xy 330.798439 -348.452222) (xy 330.821093 -348.402613) (xy 330.850577 -348.356732) (xy 330.886289 -348.315514)
			(xy 330.927503 -348.279798) (xy 330.973381 -348.250311) (xy 331.022988 -348.227652) (xy 331.075314 -348.212283)
			(xy 331.129296 -348.204517) (xy 331.156564 -348.204028) (xy 332.020164 -348.204028) (xy 332.047436 -348.204509)
			(xy 332.101425 -348.212267) (xy 332.153761 -348.22763) (xy 332.203377 -348.250284) (xy 332.249264 -348.27977)
			(xy 332.290488 -348.315487) (xy 332.326208 -348.356707) (xy 332.355698 -348.402591) (xy 332.378358 -348.452205)
			(xy 332.393726 -348.504539) (xy 332.401488 -348.558528) (xy 332.401488 -348.613072) (xy 332.401488 -348.613073)
			(xy 333.884192 -348.613073) (xy 333.884192 -348.558527) (xy 333.891955 -348.504537) (xy 333.907322 -348.452201)
			(xy 333.929982 -348.402585) (xy 333.959473 -348.356699) (xy 333.995194 -348.315477) (xy 334.036418 -348.279759)
			(xy 334.082306 -348.250271) (xy 334.131923 -348.227614) (xy 334.18426 -348.212249) (xy 334.238251 -348.20449)
			(xy 334.265524 -348.204028) (xy 335.129124 -348.204028) (xy 335.156392 -348.204536) (xy 335.210371 -348.2123)
			(xy 335.262696 -348.227667) (xy 335.312302 -348.250324) (xy 335.358179 -348.27981) (xy 335.399393 -348.315524)
			(xy 335.435104 -348.35674) (xy 335.464587 -348.402619) (xy 335.487241 -348.452226) (xy 335.502605 -348.504552)
			(xy 335.510366 -348.558532) (xy 335.510366 -348.613068) (xy 335.510366 -348.613069) (xy 336.993214 -348.613069)
			(xy 336.993214 -348.558531) (xy 337.000976 -348.504547) (xy 337.016341 -348.452217) (xy 337.038996 -348.402607)
			(xy 337.068482 -348.356726) (xy 337.104196 -348.315507) (xy 337.145413 -348.279791) (xy 337.191293 -348.250304)
			(xy 337.240902 -348.227646) (xy 337.293231 -348.212279) (xy 337.347215 -348.204516) (xy 337.374484 -348.204028)
			(xy 338.238084 -348.204028) (xy 338.265355 -348.20451) (xy 338.319342 -348.21227) (xy 338.371675 -348.227635)
			(xy 338.421289 -348.250291) (xy 338.467174 -348.279777) (xy 338.508395 -348.315494) (xy 338.544113 -348.356713)
			(xy 338.573601 -348.402597) (xy 338.596259 -348.45221) (xy 338.611626 -348.504542) (xy 338.619388 -348.558529)
			(xy 338.619388 -348.613071) (xy 338.619388 -348.613074) (xy 340.102092 -348.613074) (xy 340.102092 -348.558526)
			(xy 340.109855 -348.504534) (xy 340.125224 -348.452197) (xy 340.147885 -348.402579) (xy 340.177378 -348.356692)
			(xy 340.213101 -348.31547) (xy 340.254327 -348.279751) (xy 340.300218 -348.250264) (xy 340.349838 -348.227609)
			(xy 340.402177 -348.212246) (xy 340.45617 -348.204489) (xy 340.483444 -348.204028) (xy 341.347044 -348.204028)
			(xy 341.374311 -348.204537) (xy 341.428288 -348.212304) (xy 341.480611 -348.227673) (xy 341.530214 -348.250331)
			(xy 341.576088 -348.279817) (xy 341.6173 -348.315531) (xy 341.653009 -348.356747) (xy 341.68249 -348.402624)
			(xy 341.705143 -348.45223) (xy 341.720505 -348.504555) (xy 341.728266 -348.558533) (xy 341.728266 -348.613067)
			(xy 341.728265 -348.613072) (xy 343.211092 -348.613072) (xy 343.211092 -348.558528) (xy 343.218854 -348.504539)
			(xy 343.234221 -348.452205) (xy 343.256879 -348.40259) (xy 343.286368 -348.356705) (xy 343.322087 -348.315484)
			(xy 343.363309 -348.279766) (xy 343.409194 -348.250277) (xy 343.458809 -348.227619) (xy 343.511143 -348.212253)
			(xy 343.565132 -348.204491) (xy 343.592404 -348.204028) (xy 344.456004 -348.204028) (xy 344.483272 -348.204535)
			(xy 344.537254 -348.212297) (xy 344.589582 -348.227662) (xy 344.63919 -348.250318) (xy 344.685069 -348.279803)
			(xy 344.726286 -348.315517) (xy 344.761999 -348.356734) (xy 344.791484 -348.402613) (xy 344.81414 -348.452222)
			(xy 344.829504 -348.50455) (xy 344.837266 -348.558532) (xy 344.837266 -348.613068) (xy 344.837266 -348.613069)
			(xy 370.806714 -348.613069) (xy 370.806714 -348.558531) (xy 370.814476 -348.504548) (xy 370.82984 -348.452218)
			(xy 370.852496 -348.402608) (xy 370.881981 -348.356727) (xy 370.917695 -348.315509) (xy 370.958911 -348.279793)
			(xy 371.004791 -348.250305) (xy 371.054399 -348.227647) (xy 371.106728 -348.21228) (xy 371.160711 -348.204516)
			(xy 371.18798 -348.204028) (xy 372.05158 -348.204028) (xy 372.078851 -348.20451) (xy 372.132839 -348.21227)
			(xy 372.185173 -348.227634) (xy 372.234787 -348.25029) (xy 372.280672 -348.279776) (xy 372.321893 -348.315493)
			(xy 372.357612 -348.356712) (xy 372.387101 -348.402595) (xy 372.409759 -348.452209) (xy 372.425126 -348.504542)
			(xy 372.432888 -348.558529) (xy 372.432888 -348.613071) (xy 372.432888 -348.613074) (xy 373.915592 -348.613074)
			(xy 373.915592 -348.558526) (xy 373.923355 -348.504535) (xy 373.938724 -348.452197) (xy 373.961385 -348.40258)
			(xy 373.990877 -348.356694) (xy 374.0266 -348.315471) (xy 374.067826 -348.279753) (xy 374.113715 -348.250266)
			(xy 374.163335 -348.22761) (xy 374.215674 -348.212246) (xy 374.269666 -348.204489) (xy 374.29694 -348.204028)
			(xy 375.16054 -348.204028) (xy 375.187807 -348.204537) (xy 375.241785 -348.212303) (xy 375.294108 -348.227672)
			(xy 375.343712 -348.25033) (xy 375.389587 -348.279816) (xy 375.430798 -348.31553) (xy 375.466508 -348.356746)
			(xy 375.49599 -348.402623) (xy 375.518642 -348.45223) (xy 375.534005 -348.504554) (xy 375.541766 -348.558533)
			(xy 375.541766 -348.613067) (xy 375.541766 -348.61307) (xy 377.024614 -348.61307) (xy 377.024614 -348.55853)
			(xy 377.032376 -348.504545) (xy 377.047742 -348.452214) (xy 377.070399 -348.402603) (xy 377.099886 -348.35672)
			(xy 377.135602 -348.315502) (xy 377.17682 -348.279786) (xy 377.222703 -348.250299) (xy 377.272314 -348.227642)
			(xy 377.324645 -348.212276) (xy 377.37863 -348.204514) (xy 377.4059 -348.204028) (xy 378.2695 -348.204028)
			(xy 378.296769 -348.204534) (xy 378.350751 -348.212296) (xy 378.403079 -348.227661) (xy 378.452688 -348.250316)
			(xy 378.498568 -348.279802) (xy 378.539784 -348.315516) (xy 378.575498 -348.356732) (xy 378.604984 -348.402612)
			(xy 378.627639 -348.452221) (xy 378.643004 -348.504549) (xy 378.650766 -348.558531) (xy 378.650766 -348.613068)
			(xy 380.133614 -348.613068) (xy 380.133614 -348.558532) (xy 380.141375 -348.50455) (xy 380.156739 -348.452223)
			(xy 380.179393 -348.402614) (xy 380.208876 -348.356734) (xy 380.244588 -348.315516) (xy 380.285801 -348.2798)
			(xy 380.331679 -348.250312) (xy 380.381285 -348.227653) (xy 380.433611 -348.212284) (xy 380.487592 -348.204517)
			(xy 380.51486 -348.204028) (xy 381.37846 -348.204028) (xy 381.405732 -348.204509) (xy 381.459722 -348.212266)
			(xy 381.512058 -348.227628) (xy 381.561675 -348.250283) (xy 381.607562 -348.279769) (xy 381.648786 -348.315485)
			(xy 381.684507 -348.356706) (xy 381.713998 -348.40259) (xy 381.736658 -348.452204) (xy 381.752025 -348.504539)
			(xy 381.759788 -348.558528) (xy 381.759788 -348.613072) (xy 381.759788 -348.613073) (xy 383.242492 -348.613073)
			(xy 383.242492 -348.558527) (xy 383.250254 -348.504537) (xy 383.265622 -348.452202) (xy 383.288282 -348.402586)
			(xy 383.317772 -348.3567) (xy 383.353493 -348.315478) (xy 383.394716 -348.27976) (xy 383.440603 -348.250272)
			(xy 383.49022 -348.227615) (xy 383.542557 -348.21225) (xy 383.596547 -348.20449) (xy 383.62382 -348.204028)
			(xy 384.48742 -348.204028) (xy 384.514688 -348.204536) (xy 384.568668 -348.2123) (xy 384.620994 -348.227666)
			(xy 384.6706 -348.250323) (xy 384.716477 -348.279809) (xy 384.757691 -348.315523) (xy 384.793403 -348.356739)
			(xy 384.822887 -348.402618) (xy 384.845541 -348.452225) (xy 384.860905 -348.504552) (xy 384.868666 -348.558532)
			(xy 384.868666 -348.613068) (xy 384.868666 -348.613069) (xy 386.351514 -348.613069) (xy 386.351514 -348.558531)
			(xy 386.359276 -348.504548) (xy 386.37464 -348.452218) (xy 386.397296 -348.402608) (xy 386.426781 -348.356727)
			(xy 386.462495 -348.315509) (xy 386.503711 -348.279793) (xy 386.549591 -348.250305) (xy 386.599199 -348.227647)
			(xy 386.651528 -348.21228) (xy 386.705511 -348.204516) (xy 386.73278 -348.204028) (xy 387.59638 -348.204028)
			(xy 387.623651 -348.20451) (xy 387.677639 -348.21227) (xy 387.729973 -348.227634) (xy 387.779587 -348.25029)
			(xy 387.825472 -348.279776) (xy 387.866693 -348.315493) (xy 387.902412 -348.356712) (xy 387.931901 -348.402595)
			(xy 387.954559 -348.452209) (xy 387.969926 -348.504542) (xy 387.977688 -348.558529) (xy 387.977688 -348.613071)
			(xy 387.977688 -348.613074) (xy 389.460392 -348.613074) (xy 389.460392 -348.558526) (xy 389.468155 -348.504535)
			(xy 389.483524 -348.452197) (xy 389.506185 -348.40258) (xy 389.535677 -348.356694) (xy 389.5714 -348.315471)
			(xy 389.612626 -348.279753) (xy 389.658515 -348.250266) (xy 389.708135 -348.22761) (xy 389.760474 -348.212246)
			(xy 389.814466 -348.204489) (xy 389.84174 -348.204028) (xy 390.70534 -348.204028) (xy 390.732607 -348.204537)
			(xy 390.786585 -348.212303) (xy 390.838908 -348.227672) (xy 390.888512 -348.25033) (xy 390.934387 -348.279816)
			(xy 390.975598 -348.31553) (xy 391.011308 -348.356746) (xy 391.04079 -348.402623) (xy 391.063442 -348.45223)
			(xy 391.078805 -348.504554) (xy 391.086566 -348.558533) (xy 391.086566 -348.613067) (xy 391.086566 -348.61307)
			(xy 392.569414 -348.61307) (xy 392.569414 -348.55853) (xy 392.577176 -348.504545) (xy 392.592542 -348.452214)
			(xy 392.615199 -348.402603) (xy 392.644686 -348.35672) (xy 392.680402 -348.315502) (xy 392.72162 -348.279786)
			(xy 392.767503 -348.250299) (xy 392.817114 -348.227642) (xy 392.869445 -348.212276) (xy 392.92343 -348.204514)
			(xy 392.9507 -348.204028) (xy 393.8143 -348.204028) (xy 393.841569 -348.204534) (xy 393.895551 -348.212296)
			(xy 393.947879 -348.227661) (xy 393.997488 -348.250316) (xy 394.043368 -348.279802) (xy 394.084584 -348.315516)
			(xy 394.120298 -348.356732) (xy 394.149784 -348.402612) (xy 394.172439 -348.452221) (xy 394.187804 -348.504549)
			(xy 394.195566 -348.558531) (xy 394.195566 -348.613068) (xy 395.678414 -348.613068) (xy 395.678414 -348.558532)
			(xy 395.686175 -348.50455) (xy 395.701539 -348.452223) (xy 395.724193 -348.402614) (xy 395.753676 -348.356734)
			(xy 395.789388 -348.315516) (xy 395.830601 -348.2798) (xy 395.876479 -348.250312) (xy 395.926085 -348.227653)
			(xy 395.978411 -348.212284) (xy 396.032392 -348.204517) (xy 396.05966 -348.204028) (xy 396.92326 -348.204028)
			(xy 396.950532 -348.204509) (xy 397.004522 -348.212266) (xy 397.056858 -348.227628) (xy 397.106475 -348.250283)
			(xy 397.152362 -348.279769) (xy 397.193586 -348.315485) (xy 397.229307 -348.356706) (xy 397.258798 -348.40259)
			(xy 397.281458 -348.452204) (xy 397.296825 -348.504539) (xy 397.304588 -348.558528) (xy 397.304588 -348.613072)
			(xy 397.304588 -348.613073) (xy 398.787292 -348.613073) (xy 398.787292 -348.558527) (xy 398.795054 -348.504537)
			(xy 398.810422 -348.452202) (xy 398.833082 -348.402586) (xy 398.862572 -348.3567) (xy 398.898293 -348.315478)
			(xy 398.939516 -348.27976) (xy 398.985403 -348.250272) (xy 399.03502 -348.227615) (xy 399.087357 -348.21225)
			(xy 399.141347 -348.20449) (xy 399.16862 -348.204028) (xy 400.03222 -348.204028) (xy 400.059488 -348.204536)
			(xy 400.113468 -348.2123) (xy 400.165794 -348.227666) (xy 400.2154 -348.250323) (xy 400.261277 -348.279809)
			(xy 400.302491 -348.315523) (xy 400.338203 -348.356739) (xy 400.367687 -348.402618) (xy 400.390341 -348.452225)
			(xy 400.405705 -348.504552) (xy 400.413466 -348.558532) (xy 400.413466 -348.613068) (xy 400.405705 -348.667048)
			(xy 400.390341 -348.719375) (xy 400.367687 -348.768982) (xy 400.338203 -348.814861) (xy 400.302491 -348.856077)
			(xy 400.261277 -348.891791) (xy 400.2154 -348.921277) (xy 400.165794 -348.943934) (xy 400.113468 -348.9593)
			(xy 400.059488 -348.967064) (xy 400.03222 -348.967552) (xy 399.16862 -348.967552) (xy 399.141347 -348.96711)
			(xy 399.087357 -348.95935) (xy 399.03502 -348.943985) (xy 398.985403 -348.921328) (xy 398.939516 -348.89184)
			(xy 398.898293 -348.856122) (xy 398.862572 -348.8149) (xy 398.833082 -348.769014) (xy 398.810422 -348.719398)
			(xy 398.795054 -348.667063) (xy 398.787292 -348.613073) (xy 397.304588 -348.613073) (xy 397.296825 -348.667061)
			(xy 397.281458 -348.719396) (xy 397.258798 -348.76901) (xy 397.229307 -348.814894) (xy 397.193586 -348.856115)
			(xy 397.152362 -348.891831) (xy 397.106475 -348.921317) (xy 397.056858 -348.943972) (xy 397.004522 -348.959334)
			(xy 396.950532 -348.967091) (xy 396.92326 -348.967552) (xy 396.05966 -348.967552) (xy 396.032392 -348.967083)
			(xy 395.978411 -348.959316) (xy 395.926085 -348.943947) (xy 395.876479 -348.921288) (xy 395.830601 -348.8918)
			(xy 395.789388 -348.856084) (xy 395.753676 -348.814866) (xy 395.724193 -348.768986) (xy 395.701539 -348.719377)
			(xy 395.686175 -348.66705) (xy 395.678414 -348.613068) (xy 394.195566 -348.613068) (xy 394.195566 -348.613069)
			(xy 394.187804 -348.667051) (xy 394.172439 -348.719379) (xy 394.149784 -348.768988) (xy 394.120298 -348.814868)
			(xy 394.084584 -348.856084) (xy 394.043368 -348.891798) (xy 393.997488 -348.921284) (xy 393.947879 -348.943939)
			(xy 393.895551 -348.959304) (xy 393.841569 -348.967066) (xy 393.8143 -348.967552) (xy 392.9507 -348.967552)
			(xy 392.92343 -348.967086) (xy 392.869445 -348.959324) (xy 392.817114 -348.943958) (xy 392.767503 -348.921301)
			(xy 392.72162 -348.891814) (xy 392.680402 -348.856098) (xy 392.644686 -348.81488) (xy 392.615199 -348.768997)
			(xy 392.592542 -348.719386) (xy 392.577176 -348.667055) (xy 392.569414 -348.61307) (xy 391.086566 -348.61307)
			(xy 391.078805 -348.667046) (xy 391.063442 -348.71937) (xy 391.04079 -348.768977) (xy 391.011308 -348.814854)
			(xy 390.975598 -348.85607) (xy 390.934387 -348.891784) (xy 390.888512 -348.92127) (xy 390.838908 -348.943928)
			(xy 390.786585 -348.959297) (xy 390.732607 -348.967063) (xy 390.70534 -348.967552) (xy 389.84174 -348.967552)
			(xy 389.814466 -348.967111) (xy 389.760474 -348.959354) (xy 389.708135 -348.94399) (xy 389.658515 -348.921334)
			(xy 389.612626 -348.891847) (xy 389.5714 -348.856129) (xy 389.535677 -348.814906) (xy 389.506185 -348.76902)
			(xy 389.483524 -348.719403) (xy 389.468155 -348.667065) (xy 389.460392 -348.613074) (xy 387.977688 -348.613074)
			(xy 387.969926 -348.667058) (xy 387.954559 -348.719391) (xy 387.931901 -348.769005) (xy 387.902412 -348.814888)
			(xy 387.866693 -348.856107) (xy 387.825472 -348.891824) (xy 387.779587 -348.92131) (xy 387.729973 -348.943966)
			(xy 387.677639 -348.95933) (xy 387.623651 -348.96709) (xy 387.59638 -348.967552) (xy 386.73278 -348.967552)
			(xy 386.705511 -348.967084) (xy 386.651528 -348.95932) (xy 386.599199 -348.943953) (xy 386.549591 -348.921295)
			(xy 386.503711 -348.891807) (xy 386.462495 -348.856091) (xy 386.426781 -348.814873) (xy 386.397296 -348.768992)
			(xy 386.37464 -348.719382) (xy 386.359276 -348.667052) (xy 386.351514 -348.613069) (xy 384.868666 -348.613069)
			(xy 384.860905 -348.667048) (xy 384.845541 -348.719375) (xy 384.822887 -348.768982) (xy 384.793403 -348.814861)
			(xy 384.757691 -348.856077) (xy 384.716477 -348.891791) (xy 384.6706 -348.921277) (xy 384.620994 -348.943934)
			(xy 384.568668 -348.9593) (xy 384.514688 -348.967064) (xy 384.48742 -348.967552) (xy 383.62382 -348.967552)
			(xy 383.596547 -348.96711) (xy 383.542557 -348.95935) (xy 383.49022 -348.943985) (xy 383.440603 -348.921328)
			(xy 383.394716 -348.89184) (xy 383.353493 -348.856122) (xy 383.317772 -348.8149) (xy 383.288282 -348.769014)
			(xy 383.265622 -348.719398) (xy 383.250254 -348.667063) (xy 383.242492 -348.613073) (xy 381.759788 -348.613073)
			(xy 381.752025 -348.667061) (xy 381.736658 -348.719396) (xy 381.713998 -348.76901) (xy 381.684507 -348.814894)
			(xy 381.648786 -348.856115) (xy 381.607562 -348.891831) (xy 381.561675 -348.921317) (xy 381.512058 -348.943972)
			(xy 381.459722 -348.959334) (xy 381.405732 -348.967091) (xy 381.37846 -348.967552) (xy 380.51486 -348.967552)
			(xy 380.487592 -348.967083) (xy 380.433611 -348.959316) (xy 380.381285 -348.943947) (xy 380.331679 -348.921288)
			(xy 380.285801 -348.8918) (xy 380.244588 -348.856084) (xy 380.208876 -348.814866) (xy 380.179393 -348.768986)
			(xy 380.156739 -348.719377) (xy 380.141375 -348.66705) (xy 380.133614 -348.613068) (xy 378.650766 -348.613068)
			(xy 378.650766 -348.613069) (xy 378.643004 -348.667051) (xy 378.627639 -348.719379) (xy 378.604984 -348.768988)
			(xy 378.575498 -348.814868) (xy 378.539784 -348.856084) (xy 378.498568 -348.891798) (xy 378.452688 -348.921284)
			(xy 378.403079 -348.943939) (xy 378.350751 -348.959304) (xy 378.296769 -348.967066) (xy 378.2695 -348.967552)
			(xy 377.4059 -348.967552) (xy 377.37863 -348.967086) (xy 377.324645 -348.959324) (xy 377.272314 -348.943958)
			(xy 377.222703 -348.921301) (xy 377.17682 -348.891814) (xy 377.135602 -348.856098) (xy 377.099886 -348.81488)
			(xy 377.070399 -348.768997) (xy 377.047742 -348.719386) (xy 377.032376 -348.667055) (xy 377.024614 -348.61307)
			(xy 375.541766 -348.61307) (xy 375.534005 -348.667046) (xy 375.518642 -348.71937) (xy 375.49599 -348.768977)
			(xy 375.466508 -348.814854) (xy 375.430798 -348.85607) (xy 375.389587 -348.891784) (xy 375.343712 -348.92127)
			(xy 375.294108 -348.943928) (xy 375.241785 -348.959297) (xy 375.187807 -348.967063) (xy 375.16054 -348.967552)
			(xy 374.29694 -348.967552) (xy 374.269666 -348.967111) (xy 374.215674 -348.959354) (xy 374.163335 -348.94399)
			(xy 374.113715 -348.921334) (xy 374.067826 -348.891847) (xy 374.0266 -348.856129) (xy 373.990877 -348.814906)
			(xy 373.961385 -348.76902) (xy 373.938724 -348.719403) (xy 373.923355 -348.667065) (xy 373.915592 -348.613074)
			(xy 372.432888 -348.613074) (xy 372.425126 -348.667058) (xy 372.409759 -348.719391) (xy 372.387101 -348.769005)
			(xy 372.357612 -348.814888) (xy 372.321893 -348.856107) (xy 372.280672 -348.891824) (xy 372.234787 -348.92131)
			(xy 372.185173 -348.943966) (xy 372.132839 -348.95933) (xy 372.078851 -348.96709) (xy 372.05158 -348.967552)
			(xy 371.18798 -348.967552) (xy 371.160711 -348.967084) (xy 371.106728 -348.95932) (xy 371.054399 -348.943953)
			(xy 371.004791 -348.921295) (xy 370.958911 -348.891807) (xy 370.917695 -348.856091) (xy 370.881981 -348.814873)
			(xy 370.852496 -348.768992) (xy 370.82984 -348.719382) (xy 370.814476 -348.667052) (xy 370.806714 -348.613069)
			(xy 344.837266 -348.613069) (xy 344.829504 -348.66705) (xy 344.81414 -348.719378) (xy 344.791484 -348.768987)
			(xy 344.761999 -348.814866) (xy 344.726286 -348.856083) (xy 344.685069 -348.891797) (xy 344.63919 -348.921282)
			(xy 344.589582 -348.943938) (xy 344.537254 -348.959303) (xy 344.483272 -348.967065) (xy 344.456004 -348.967552)
			(xy 343.592404 -348.967552) (xy 343.565132 -348.967109) (xy 343.511143 -348.959347) (xy 343.458809 -348.943981)
			(xy 343.409194 -348.921323) (xy 343.363309 -348.891834) (xy 343.322087 -348.856116) (xy 343.286368 -348.814895)
			(xy 343.256879 -348.76901) (xy 343.234221 -348.719395) (xy 343.218854 -348.667061) (xy 343.211092 -348.613072)
			(xy 341.728265 -348.613072) (xy 341.720505 -348.667045) (xy 341.705143 -348.71937) (xy 341.68249 -348.768976)
			(xy 341.653009 -348.814853) (xy 341.6173 -348.856069) (xy 341.576088 -348.891783) (xy 341.530214 -348.921269)
			(xy 341.480611 -348.943927) (xy 341.428288 -348.959296) (xy 341.374311 -348.967063) (xy 341.347044 -348.967552)
			(xy 340.483444 -348.967552) (xy 340.45617 -348.967111) (xy 340.402177 -348.959354) (xy 340.349838 -348.943991)
			(xy 340.300218 -348.921336) (xy 340.254327 -348.891849) (xy 340.213101 -348.85613) (xy 340.177378 -348.814908)
			(xy 340.147885 -348.769021) (xy 340.125224 -348.719403) (xy 340.109855 -348.667066) (xy 340.102092 -348.613074)
			(xy 338.619388 -348.613074) (xy 338.611626 -348.667058) (xy 338.596259 -348.71939) (xy 338.573601 -348.769003)
			(xy 338.544113 -348.814887) (xy 338.508395 -348.856106) (xy 338.467174 -348.891823) (xy 338.421289 -348.921309)
			(xy 338.371675 -348.943965) (xy 338.319342 -348.95933) (xy 338.265355 -348.96709) (xy 338.238084 -348.967552)
			(xy 337.374484 -348.967552) (xy 337.347215 -348.967084) (xy 337.293231 -348.959321) (xy 337.240902 -348.943954)
			(xy 337.191293 -348.921296) (xy 337.145413 -348.891809) (xy 337.104196 -348.856093) (xy 337.068482 -348.814874)
			(xy 337.038996 -348.768993) (xy 337.016341 -348.719383) (xy 337.000976 -348.667053) (xy 336.993214 -348.613069)
			(xy 335.510366 -348.613069) (xy 335.502605 -348.667048) (xy 335.487241 -348.719374) (xy 335.464587 -348.768981)
			(xy 335.435104 -348.81486) (xy 335.399393 -348.856076) (xy 335.358179 -348.89179) (xy 335.312302 -348.921276)
			(xy 335.262696 -348.943933) (xy 335.210371 -348.9593) (xy 335.156392 -348.967064) (xy 335.129124 -348.967552)
			(xy 334.265524 -348.967552) (xy 334.238251 -348.96711) (xy 334.18426 -348.959351) (xy 334.131923 -348.943986)
			(xy 334.082306 -348.921329) (xy 334.036418 -348.891841) (xy 333.995194 -348.856123) (xy 333.959473 -348.814901)
			(xy 333.929982 -348.769015) (xy 333.907322 -348.719399) (xy 333.891955 -348.667063) (xy 333.884192 -348.613073)
			(xy 332.401488 -348.613073) (xy 332.393726 -348.667061) (xy 332.378358 -348.719395) (xy 332.355698 -348.769009)
			(xy 332.326208 -348.814893) (xy 332.290488 -348.856113) (xy 332.249264 -348.89183) (xy 332.203377 -348.921316)
			(xy 332.153761 -348.94397) (xy 332.101425 -348.959333) (xy 332.047436 -348.967091) (xy 332.020164 -348.967552)
			(xy 331.156564 -348.967552) (xy 331.129296 -348.967083) (xy 331.075314 -348.959317) (xy 331.022988 -348.943948)
			(xy 330.973381 -348.921289) (xy 330.927503 -348.891802) (xy 330.886289 -348.856086) (xy 330.850577 -348.814868)
			(xy 330.821093 -348.768987) (xy 330.798439 -348.719378) (xy 330.783075 -348.66705) (xy 330.775314 -348.613068)
			(xy 329.292466 -348.613068) (xy 329.284704 -348.66705) (xy 329.26934 -348.719378) (xy 329.246684 -348.768987)
			(xy 329.217199 -348.814866) (xy 329.181486 -348.856083) (xy 329.140269 -348.891797) (xy 329.09439 -348.921282)
			(xy 329.044782 -348.943938) (xy 328.992454 -348.959303) (xy 328.938472 -348.967065) (xy 328.911204 -348.967552)
			(xy 328.047604 -348.967552) (xy 328.020332 -348.967109) (xy 327.966343 -348.959347) (xy 327.914009 -348.943981)
			(xy 327.864394 -348.921323) (xy 327.818509 -348.891834) (xy 327.777287 -348.856116) (xy 327.741568 -348.814895)
			(xy 327.712079 -348.76901) (xy 327.689421 -348.719395) (xy 327.674054 -348.667061) (xy 327.666292 -348.613072)
			(xy 326.183465 -348.613072) (xy 326.175705 -348.667045) (xy 326.160343 -348.71937) (xy 326.13769 -348.768976)
			(xy 326.108209 -348.814853) (xy 326.0725 -348.856069) (xy 326.031288 -348.891783) (xy 325.985414 -348.921269)
			(xy 325.935811 -348.943927) (xy 325.883488 -348.959296) (xy 325.829511 -348.967063) (xy 325.802244 -348.967552)
			(xy 324.938644 -348.967552) (xy 324.91137 -348.967111) (xy 324.857377 -348.959354) (xy 324.805038 -348.943991)
			(xy 324.755418 -348.921336) (xy 324.709527 -348.891849) (xy 324.668301 -348.85613) (xy 324.632578 -348.814908)
			(xy 324.603085 -348.769021) (xy 324.580424 -348.719403) (xy 324.565055 -348.667066) (xy 324.557292 -348.613074)
			(xy 323.074588 -348.613074) (xy 323.066826 -348.667058) (xy 323.051459 -348.71939) (xy 323.028801 -348.769003)
			(xy 322.999313 -348.814887) (xy 322.963595 -348.856106) (xy 322.922374 -348.891823) (xy 322.876489 -348.921309)
			(xy 322.826875 -348.943965) (xy 322.774542 -348.95933) (xy 322.720555 -348.96709) (xy 322.693284 -348.967552)
			(xy 321.829684 -348.967552) (xy 321.802415 -348.967084) (xy 321.748431 -348.959321) (xy 321.696102 -348.943954)
			(xy 321.646493 -348.921296) (xy 321.600613 -348.891809) (xy 321.559396 -348.856093) (xy 321.523682 -348.814874)
			(xy 321.494196 -348.768993) (xy 321.471541 -348.719383) (xy 321.456176 -348.667053) (xy 321.448414 -348.613069)
			(xy 319.965566 -348.613069) (xy 319.957805 -348.667048) (xy 319.942441 -348.719374) (xy 319.919787 -348.768981)
			(xy 319.890304 -348.81486) (xy 319.854593 -348.856076) (xy 319.813379 -348.89179) (xy 319.767502 -348.921276)
			(xy 319.717896 -348.943933) (xy 319.665571 -348.9593) (xy 319.611592 -348.967064) (xy 319.584324 -348.967552)
			(xy 318.720724 -348.967552) (xy 318.693451 -348.96711) (xy 318.63946 -348.959351) (xy 318.587123 -348.943986)
			(xy 318.537506 -348.921329) (xy 318.491618 -348.891841) (xy 318.450394 -348.856123) (xy 318.414673 -348.814901)
			(xy 318.385182 -348.769015) (xy 318.362522 -348.719399) (xy 318.347155 -348.667063) (xy 318.339392 -348.613073)
			(xy 316.856688 -348.613073) (xy 316.848926 -348.667061) (xy 316.833558 -348.719395) (xy 316.810898 -348.769009)
			(xy 316.781408 -348.814893) (xy 316.745688 -348.856113) (xy 316.704464 -348.89183) (xy 316.658577 -348.921316)
			(xy 316.608961 -348.94397) (xy 316.556625 -348.959333) (xy 316.502636 -348.967091) (xy 316.475364 -348.967552)
			(xy 315.611764 -348.967552) (xy 315.584496 -348.967083) (xy 315.530514 -348.959317) (xy 315.478188 -348.943948)
			(xy 315.428581 -348.921289) (xy 315.382703 -348.891802) (xy 315.341489 -348.856086) (xy 315.305777 -348.814868)
			(xy 315.276293 -348.768987) (xy 315.253639 -348.719378) (xy 315.238275 -348.66705) (xy 315.230514 -348.613068)
			(xy 313.747666 -348.613068) (xy 313.739904 -348.66705) (xy 313.72454 -348.719378) (xy 313.701884 -348.768987)
			(xy 313.672399 -348.814866) (xy 313.636686 -348.856083) (xy 313.595469 -348.891797) (xy 313.54959 -348.921282)
			(xy 313.499982 -348.943938) (xy 313.447654 -348.959303) (xy 313.393672 -348.967065) (xy 313.366404 -348.967552)
			(xy 312.502804 -348.967552) (xy 312.475532 -348.967109) (xy 312.421543 -348.959347) (xy 312.369209 -348.943981)
			(xy 312.319594 -348.921323) (xy 312.273709 -348.891834) (xy 312.232487 -348.856116) (xy 312.196768 -348.814895)
			(xy 312.167279 -348.76901) (xy 312.144621 -348.719395) (xy 312.129254 -348.667061) (xy 312.121492 -348.613072)
			(xy 311.574942 -348.613072) (xy 311.574942 -351.638668) (xy 312.121539 -351.638668) (xy 312.121539 -351.584132)
			(xy 312.129301 -351.53015) (xy 312.144666 -351.477822) (xy 312.167321 -351.428213) (xy 312.196807 -351.382334)
			(xy 312.232521 -351.341118) (xy 312.273737 -351.305404) (xy 312.319617 -351.27592) (xy 312.369226 -351.253264)
			(xy 312.421554 -351.2379) (xy 312.475536 -351.230139) (xy 312.502804 -351.229676) (xy 313.366404 -351.229676)
			(xy 313.393676 -351.230087) (xy 313.447664 -351.23785) (xy 313.499999 -351.253217) (xy 313.549613 -351.275876)
			(xy 313.595498 -351.305365) (xy 313.63672 -351.341083) (xy 313.672438 -351.382305) (xy 313.701926 -351.42819)
			(xy 313.724584 -351.477805) (xy 313.739951 -351.530139) (xy 313.747713 -351.584128) (xy 313.747713 -351.638665)
			(xy 315.230562 -351.638665) (xy 315.230562 -351.584135) (xy 315.238322 -351.53016) (xy 315.253684 -351.477838)
			(xy 315.276335 -351.428236) (xy 315.305815 -351.382361) (xy 315.341523 -351.341148) (xy 315.382732 -351.305437)
			(xy 315.428604 -351.275953) (xy 315.478205 -351.253297) (xy 315.530525 -351.23793) (xy 315.584499 -351.230165)
			(xy 315.611764 -351.229676) (xy 316.475364 -351.229676) (xy 316.502639 -351.230061) (xy 316.556636 -351.23782)
			(xy 316.608978 -351.253185) (xy 316.6586 -351.275842) (xy 316.704493 -351.305332) (xy 316.745722 -351.341053)
			(xy 316.781446 -351.382278) (xy 316.81094 -351.428168) (xy 316.833603 -351.477788) (xy 316.848972 -351.530129)
			(xy 316.856736 -351.584125) (xy 316.856736 -351.638669) (xy 318.339439 -351.638669) (xy 318.339439 -351.584131)
			(xy 318.347201 -351.530147) (xy 318.362567 -351.477818) (xy 318.385224 -351.428208) (xy 318.414711 -351.382328)
			(xy 318.450428 -351.341111) (xy 318.491647 -351.305397) (xy 318.537529 -351.275913) (xy 318.58714 -351.253259)
			(xy 318.63947 -351.237896) (xy 318.693455 -351.230138) (xy 318.720724 -351.229676) (xy 319.584324 -351.229676)
			(xy 319.611595 -351.230088) (xy 319.665581 -351.237853) (xy 319.717913 -351.253222) (xy 319.767525 -351.275882)
			(xy 319.813408 -351.305372) (xy 319.854627 -351.34109) (xy 319.890343 -351.382312) (xy 319.919829 -351.428196)
			(xy 319.942486 -351.477809) (xy 319.957852 -351.530142) (xy 319.965614 -351.584129) (xy 319.965614 -351.638666)
			(xy 321.448462 -351.638666) (xy 321.448462 -351.584134) (xy 321.456223 -351.530157) (xy 321.471586 -351.477834)
			(xy 321.494239 -351.42823) (xy 321.52372 -351.382354) (xy 321.55943 -351.341141) (xy 321.600642 -351.30543)
			(xy 321.646516 -351.275946) (xy 321.696119 -351.253291) (xy 321.748442 -351.237926) (xy 321.802418 -351.230163)
			(xy 321.829684 -351.229676) (xy 322.693284 -351.229676) (xy 322.720558 -351.230062) (xy 322.774552 -351.237824)
			(xy 322.826892 -351.25319) (xy 322.876512 -351.275849) (xy 322.922403 -351.305339) (xy 322.963629 -351.34106)
			(xy 322.999351 -351.382285) (xy 323.028843 -351.428174) (xy 323.051504 -351.477793) (xy 323.066873 -351.530132)
			(xy 323.074636 -351.584126) (xy 323.074636 -351.63867) (xy 324.55734 -351.63867) (xy 324.55734 -351.58413)
			(xy 324.565102 -351.530144) (xy 324.580469 -351.477813) (xy 324.603128 -351.428202) (xy 324.632616 -351.382321)
			(xy 324.668335 -351.341104) (xy 324.709556 -351.30539) (xy 324.755441 -351.275906) (xy 324.805055 -351.253254)
			(xy 324.857387 -351.237893) (xy 324.911374 -351.230136) (xy 324.938644 -351.229676) (xy 325.802244 -351.229676)
			(xy 325.829514 -351.23009) (xy 325.883498 -351.237857) (xy 325.935828 -351.253228) (xy 325.985437 -351.275889)
			(xy 326.031317 -351.305379) (xy 326.072534 -351.341097) (xy 326.108248 -351.382318) (xy 326.137732 -351.428201)
			(xy 326.160388 -351.477814) (xy 326.175752 -351.530145) (xy 326.183514 -351.58413) (xy 326.183514 -351.638668)
			(xy 327.666339 -351.638668) (xy 327.666339 -351.584132) (xy 327.674101 -351.53015) (xy 327.689466 -351.477822)
			(xy 327.712121 -351.428213) (xy 327.741607 -351.382334) (xy 327.777321 -351.341118) (xy 327.818537 -351.305404)
			(xy 327.864417 -351.27592) (xy 327.914026 -351.253264) (xy 327.966354 -351.2379) (xy 328.020336 -351.230139)
			(xy 328.047604 -351.229676) (xy 328.911204 -351.229676) (xy 328.938476 -351.230087) (xy 328.992464 -351.23785)
			(xy 329.044799 -351.253217) (xy 329.094413 -351.275876) (xy 329.140298 -351.305365) (xy 329.18152 -351.341083)
			(xy 329.217238 -351.382305) (xy 329.246726 -351.42819) (xy 329.269384 -351.477805) (xy 329.284751 -351.530139)
			(xy 329.292513 -351.584128) (xy 329.292513 -351.638665) (xy 330.775362 -351.638665) (xy 330.775362 -351.584135)
			(xy 330.783122 -351.53016) (xy 330.798484 -351.477838) (xy 330.821135 -351.428236) (xy 330.850615 -351.382361)
			(xy 330.886323 -351.341148) (xy 330.927532 -351.305437) (xy 330.973404 -351.275953) (xy 331.023005 -351.253297)
			(xy 331.075325 -351.23793) (xy 331.129299 -351.230165) (xy 331.156564 -351.229676) (xy 332.020164 -351.229676)
			(xy 332.047439 -351.230061) (xy 332.101436 -351.23782) (xy 332.153778 -351.253185) (xy 332.2034 -351.275842)
			(xy 332.249293 -351.305332) (xy 332.290522 -351.341053) (xy 332.326246 -351.382278) (xy 332.35574 -351.428168)
			(xy 332.378403 -351.477788) (xy 332.393772 -351.530129) (xy 332.401536 -351.584125) (xy 332.401536 -351.638669)
			(xy 333.884239 -351.638669) (xy 333.884239 -351.584131) (xy 333.892001 -351.530147) (xy 333.907367 -351.477818)
			(xy 333.930024 -351.428208) (xy 333.959511 -351.382328) (xy 333.995228 -351.341111) (xy 334.036447 -351.305397)
			(xy 334.082329 -351.275913) (xy 334.13194 -351.253259) (xy 334.18427 -351.237896) (xy 334.238255 -351.230138)
			(xy 334.265524 -351.229676) (xy 335.129124 -351.229676) (xy 335.156395 -351.230088) (xy 335.210381 -351.237853)
			(xy 335.262713 -351.253222) (xy 335.312325 -351.275882) (xy 335.358208 -351.305372) (xy 335.399427 -351.34109)
			(xy 335.435143 -351.382312) (xy 335.464629 -351.428196) (xy 335.487286 -351.477809) (xy 335.502652 -351.530142)
			(xy 335.510414 -351.584129) (xy 335.510414 -351.638666) (xy 336.993262 -351.638666) (xy 336.993262 -351.584134)
			(xy 337.001023 -351.530157) (xy 337.016386 -351.477834) (xy 337.039039 -351.42823) (xy 337.06852 -351.382354)
			(xy 337.10423 -351.341141) (xy 337.145442 -351.30543) (xy 337.191316 -351.275946) (xy 337.240919 -351.253291)
			(xy 337.293242 -351.237926) (xy 337.347218 -351.230163) (xy 337.374484 -351.229676) (xy 338.238084 -351.229676)
			(xy 338.265358 -351.230062) (xy 338.319352 -351.237824) (xy 338.371692 -351.25319) (xy 338.421312 -351.275849)
			(xy 338.467203 -351.305339) (xy 338.508429 -351.34106) (xy 338.544151 -351.382285) (xy 338.573643 -351.428174)
			(xy 338.596304 -351.477793) (xy 338.611673 -351.530132) (xy 338.619436 -351.584126) (xy 338.619436 -351.63867)
			(xy 340.10214 -351.63867) (xy 340.10214 -351.58413) (xy 340.109902 -351.530144) (xy 340.125269 -351.477813)
			(xy 340.147928 -351.428202) (xy 340.177416 -351.382321) (xy 340.213135 -351.341104) (xy 340.254356 -351.30539)
			(xy 340.300241 -351.275906) (xy 340.349855 -351.253254) (xy 340.402187 -351.237893) (xy 340.456174 -351.230136)
			(xy 340.483444 -351.229676) (xy 341.347044 -351.229676) (xy 341.374314 -351.23009) (xy 341.428298 -351.237857)
			(xy 341.480628 -351.253228) (xy 341.530237 -351.275889) (xy 341.576117 -351.305379) (xy 341.617334 -351.341097)
			(xy 341.653048 -351.382318) (xy 341.682532 -351.428201) (xy 341.705188 -351.477814) (xy 341.720552 -351.530145)
			(xy 341.728314 -351.58413) (xy 341.728314 -351.638668) (xy 343.211139 -351.638668) (xy 343.211139 -351.584132)
			(xy 343.218901 -351.53015) (xy 343.234266 -351.477822) (xy 343.256921 -351.428213) (xy 343.286407 -351.382334)
			(xy 343.322121 -351.341118) (xy 343.363337 -351.305404) (xy 343.409217 -351.27592) (xy 343.458826 -351.253264)
			(xy 343.511154 -351.2379) (xy 343.565136 -351.230139) (xy 343.592404 -351.229676) (xy 344.456004 -351.229676)
			(xy 344.483276 -351.230087) (xy 344.537264 -351.23785) (xy 344.589599 -351.253217) (xy 344.639213 -351.275876)
			(xy 344.685098 -351.305365) (xy 344.72632 -351.341083) (xy 344.762038 -351.382305) (xy 344.791526 -351.42819)
			(xy 344.814184 -351.477805) (xy 344.829551 -351.530139) (xy 344.837313 -351.584128) (xy 344.837313 -351.638666)
			(xy 370.806762 -351.638666) (xy 370.806762 -351.584134) (xy 370.814523 -351.530158) (xy 370.829885 -351.477835)
			(xy 370.852538 -351.428231) (xy 370.882019 -351.382356) (xy 370.917729 -351.341143) (xy 370.95894 -351.305431)
			(xy 371.004814 -351.275948) (xy 371.054416 -351.253292) (xy 371.106738 -351.237927) (xy 371.160714 -351.230164)
			(xy 371.18798 -351.229676) (xy 372.05158 -351.229676) (xy 372.078855 -351.230062) (xy 372.132849 -351.237823)
			(xy 372.185189 -351.253189) (xy 372.23481 -351.275848) (xy 372.280701 -351.305338) (xy 372.321927 -351.341059)
			(xy 372.35765 -351.382283) (xy 372.387143 -351.428172) (xy 372.409804 -351.477792) (xy 372.425173 -351.530131)
			(xy 372.432936 -351.584125) (xy 372.432936 -351.63867) (xy 373.91564 -351.63867) (xy 373.91564 -351.58413)
			(xy 373.923402 -351.530145) (xy 373.938769 -351.477814) (xy 373.961427 -351.428203) (xy 373.990915 -351.382322)
			(xy 374.026634 -351.341105) (xy 374.067854 -351.305391) (xy 374.113738 -351.275908) (xy 374.163352 -351.253255)
			(xy 374.215684 -351.237893) (xy 374.26967 -351.230137) (xy 374.29694 -351.229676) (xy 375.16054 -351.229676)
			(xy 375.18781 -351.230089) (xy 375.241795 -351.237856) (xy 375.294125 -351.253227) (xy 375.343735 -351.275887)
			(xy 375.389615 -351.305377) (xy 375.430832 -351.341096) (xy 375.466547 -351.382317) (xy 375.496032 -351.4282)
			(xy 375.518687 -351.477813) (xy 375.534052 -351.530144) (xy 375.541814 -351.58413) (xy 375.541814 -351.638667)
			(xy 377.024662 -351.638667) (xy 377.024662 -351.584133) (xy 377.032423 -351.530155) (xy 377.047787 -351.477831)
			(xy 377.070441 -351.428226) (xy 377.099924 -351.382349) (xy 377.135636 -351.341136) (xy 377.176849 -351.305424)
			(xy 377.222726 -351.275941) (xy 377.272331 -351.253287) (xy 377.324655 -351.237923) (xy 377.378633 -351.230162)
			(xy 377.4059 -351.229676) (xy 378.2695 -351.229676) (xy 378.296772 -351.230087) (xy 378.350761 -351.237849)
			(xy 378.403096 -351.253216) (xy 378.452711 -351.275874) (xy 378.498596 -351.305363) (xy 378.539818 -351.341082)
			(xy 378.575537 -351.382304) (xy 378.605026 -351.428189) (xy 378.627684 -351.477804) (xy 378.643051 -351.530139)
			(xy 378.650813 -351.584128) (xy 378.650813 -351.638665) (xy 380.133662 -351.638665) (xy 380.133662 -351.584135)
			(xy 380.141422 -351.53016) (xy 380.156784 -351.477839) (xy 380.179435 -351.428237) (xy 380.208914 -351.382362)
			(xy 380.244621 -351.34115) (xy 380.28583 -351.305438) (xy 380.331702 -351.275954) (xy 380.381302 -351.253298)
			(xy 380.433621 -351.237931) (xy 380.487595 -351.230165) (xy 380.51486 -351.229676) (xy 381.37846 -351.229676)
			(xy 381.405736 -351.230061) (xy 381.459732 -351.237819) (xy 381.512075 -351.253183) (xy 381.561698 -351.275841)
			(xy 381.607591 -351.30533) (xy 381.64882 -351.341051) (xy 381.684546 -351.382277) (xy 381.71404 -351.428167)
			(xy 381.736703 -351.477788) (xy 381.752072 -351.530129) (xy 381.759836 -351.584124) (xy 381.759836 -351.638669)
			(xy 383.242539 -351.638669) (xy 383.242539 -351.584131) (xy 383.250301 -351.530148) (xy 383.265667 -351.477818)
			(xy 383.288324 -351.428209) (xy 383.31781 -351.382329) (xy 383.353526 -351.341112) (xy 383.394745 -351.305398)
			(xy 383.440626 -351.275914) (xy 383.490237 -351.25326) (xy 383.542567 -351.237897) (xy 383.596551 -351.230138)
			(xy 383.62382 -351.229676) (xy 384.48742 -351.229676) (xy 384.514691 -351.230088) (xy 384.568678 -351.237853)
			(xy 384.62101 -351.253221) (xy 384.670623 -351.275881) (xy 384.716506 -351.30537) (xy 384.757725 -351.341089)
			(xy 384.793442 -351.38231) (xy 384.822929 -351.428195) (xy 384.845586 -351.477808) (xy 384.860952 -351.530142)
			(xy 384.868714 -351.584129) (xy 384.868714 -351.638666) (xy 386.351562 -351.638666) (xy 386.351562 -351.584134)
			(xy 386.359323 -351.530158) (xy 386.374685 -351.477835) (xy 386.397338 -351.428231) (xy 386.426819 -351.382356)
			(xy 386.462529 -351.341143) (xy 386.50374 -351.305431) (xy 386.549614 -351.275948) (xy 386.599216 -351.253292)
			(xy 386.651538 -351.237927) (xy 386.705514 -351.230164) (xy 386.73278 -351.229676) (xy 387.59638 -351.229676)
			(xy 387.623655 -351.230062) (xy 387.677649 -351.237823) (xy 387.729989 -351.253189) (xy 387.77961 -351.275848)
			(xy 387.825501 -351.305338) (xy 387.866727 -351.341059) (xy 387.90245 -351.382283) (xy 387.931943 -351.428172)
			(xy 387.954604 -351.477792) (xy 387.969973 -351.530131) (xy 387.977736 -351.584125) (xy 387.977736 -351.63867)
			(xy 389.46044 -351.63867) (xy 389.46044 -351.58413) (xy 389.468202 -351.530145) (xy 389.483569 -351.477814)
			(xy 389.506227 -351.428203) (xy 389.535715 -351.382322) (xy 389.571434 -351.341105) (xy 389.612654 -351.305391)
			(xy 389.658538 -351.275908) (xy 389.708152 -351.253255) (xy 389.760484 -351.237893) (xy 389.81447 -351.230137)
			(xy 389.84174 -351.229676) (xy 390.70534 -351.229676) (xy 390.73261 -351.230089) (xy 390.786595 -351.237856)
			(xy 390.838925 -351.253227) (xy 390.888535 -351.275887) (xy 390.934415 -351.305377) (xy 390.975632 -351.341096)
			(xy 391.011347 -351.382317) (xy 391.040832 -351.4282) (xy 391.063487 -351.477813) (xy 391.078852 -351.530144)
			(xy 391.086614 -351.58413) (xy 391.086614 -351.638667) (xy 392.569462 -351.638667) (xy 392.569462 -351.584133)
			(xy 392.577223 -351.530155) (xy 392.592587 -351.477831) (xy 392.615241 -351.428226) (xy 392.644724 -351.382349)
			(xy 392.680436 -351.341136) (xy 392.721649 -351.305424) (xy 392.767526 -351.275941) (xy 392.817131 -351.253287)
			(xy 392.869455 -351.237923) (xy 392.923433 -351.230162) (xy 392.9507 -351.229676) (xy 393.8143 -351.229676)
			(xy 393.841572 -351.230087) (xy 393.895561 -351.237849) (xy 393.947896 -351.253216) (xy 393.997511 -351.275874)
			(xy 394.043396 -351.305363) (xy 394.084618 -351.341082) (xy 394.120337 -351.382304) (xy 394.149826 -351.428189)
			(xy 394.172484 -351.477804) (xy 394.187851 -351.530139) (xy 394.195613 -351.584128) (xy 394.195613 -351.638665)
			(xy 395.678462 -351.638665) (xy 395.678462 -351.584135) (xy 395.686222 -351.53016) (xy 395.701584 -351.477839)
			(xy 395.724235 -351.428237) (xy 395.753714 -351.382362) (xy 395.789421 -351.34115) (xy 395.83063 -351.305438)
			(xy 395.876502 -351.275954) (xy 395.926102 -351.253298) (xy 395.978421 -351.237931) (xy 396.032395 -351.230165)
			(xy 396.05966 -351.229676) (xy 396.92326 -351.229676) (xy 396.950536 -351.230061) (xy 397.004532 -351.237819)
			(xy 397.056875 -351.253183) (xy 397.106498 -351.275841) (xy 397.152391 -351.30533) (xy 397.19362 -351.341051)
			(xy 397.229346 -351.382277) (xy 397.25884 -351.428167) (xy 397.281503 -351.477788) (xy 397.296872 -351.530129)
			(xy 397.304636 -351.584124) (xy 397.304636 -351.638669) (xy 398.787339 -351.638669) (xy 398.787339 -351.584131)
			(xy 398.795101 -351.530148) (xy 398.810467 -351.477818) (xy 398.833124 -351.428209) (xy 398.86261 -351.382329)
			(xy 398.898326 -351.341112) (xy 398.939545 -351.305398) (xy 398.985426 -351.275914) (xy 399.035037 -351.25326)
			(xy 399.087367 -351.237897) (xy 399.141351 -351.230138) (xy 399.16862 -351.229676) (xy 400.03222 -351.229676)
			(xy 400.059491 -351.230088) (xy 400.113478 -351.237853) (xy 400.16581 -351.253221) (xy 400.215423 -351.275881)
			(xy 400.261306 -351.30537) (xy 400.302525 -351.341089) (xy 400.338242 -351.38231) (xy 400.367729 -351.428195)
			(xy 400.390386 -351.477808) (xy 400.405752 -351.530142) (xy 400.413514 -351.584129) (xy 400.413514 -351.638671)
			(xy 400.405752 -351.692658) (xy 400.390386 -351.744992) (xy 400.367729 -351.794605) (xy 400.338242 -351.84049)
			(xy 400.302525 -351.881711) (xy 400.261306 -351.91743) (xy 400.215423 -351.946919) (xy 400.16581 -351.969579)
			(xy 400.113478 -351.984947) (xy 400.059491 -351.992712) (xy 400.03222 -351.9932) (xy 399.16862 -351.9932)
			(xy 399.141351 -351.992662) (xy 399.087367 -351.984903) (xy 399.035037 -351.96954) (xy 398.985426 -351.946886)
			(xy 398.939545 -351.917402) (xy 398.898326 -351.881688) (xy 398.86261 -351.840471) (xy 398.833124 -351.794591)
			(xy 398.810467 -351.744982) (xy 398.795101 -351.692652) (xy 398.787339 -351.638669) (xy 397.304636 -351.638669)
			(xy 397.304636 -351.638676) (xy 397.296872 -351.692671) (xy 397.281503 -351.745012) (xy 397.25884 -351.794633)
			(xy 397.229346 -351.840523) (xy 397.19362 -351.881749) (xy 397.152391 -351.91747) (xy 397.106498 -351.946959)
			(xy 397.056875 -351.969617) (xy 397.004532 -351.984981) (xy 396.950536 -351.992739) (xy 396.92326 -351.9932)
			(xy 396.05966 -351.9932) (xy 396.032395 -351.992635) (xy 395.978421 -351.984869) (xy 395.926102 -351.969502)
			(xy 395.876502 -351.946846) (xy 395.83063 -351.917362) (xy 395.789421 -351.88165) (xy 395.753714 -351.840438)
			(xy 395.724235 -351.794563) (xy 395.701584 -351.744961) (xy 395.686222 -351.69264) (xy 395.678462 -351.638665)
			(xy 394.195613 -351.638665) (xy 394.195613 -351.638672) (xy 394.187851 -351.692661) (xy 394.172484 -351.744996)
			(xy 394.149826 -351.794611) (xy 394.120337 -351.840496) (xy 394.084618 -351.881718) (xy 394.043396 -351.917437)
			(xy 393.997511 -351.946926) (xy 393.947896 -351.969584) (xy 393.895561 -351.984951) (xy 393.841572 -351.992713)
			(xy 393.8143 -351.9932) (xy 392.9507 -351.9932) (xy 392.923433 -351.992638) (xy 392.869455 -351.984877)
			(xy 392.817131 -351.969513) (xy 392.767526 -351.946859) (xy 392.721649 -351.917376) (xy 392.680436 -351.881664)
			(xy 392.644724 -351.840451) (xy 392.615241 -351.794574) (xy 392.592587 -351.744969) (xy 392.577223 -351.692645)
			(xy 392.569462 -351.638667) (xy 391.086614 -351.638667) (xy 391.086614 -351.63867) (xy 391.078852 -351.692656)
			(xy 391.063487 -351.744987) (xy 391.040832 -351.7946) (xy 391.011347 -351.840483) (xy 390.975632 -351.881704)
			(xy 390.934415 -351.917423) (xy 390.888535 -351.946913) (xy 390.838925 -351.969573) (xy 390.786595 -351.984944)
			(xy 390.73261 -351.992711) (xy 390.70534 -351.9932) (xy 389.84174 -351.9932) (xy 389.81447 -351.992663)
			(xy 389.760484 -351.984907) (xy 389.708152 -351.969545) (xy 389.658538 -351.946892) (xy 389.612654 -351.917409)
			(xy 389.571434 -351.881695) (xy 389.535715 -351.840478) (xy 389.506227 -351.794597) (xy 389.483569 -351.744986)
			(xy 389.468202 -351.692655) (xy 389.46044 -351.63867) (xy 387.977736 -351.63867) (xy 387.977736 -351.638675)
			(xy 387.969973 -351.692669) (xy 387.954604 -351.745008) (xy 387.931943 -351.794628) (xy 387.90245 -351.840517)
			(xy 387.866727 -351.881741) (xy 387.825501 -351.917462) (xy 387.77961 -351.946952) (xy 387.729989 -351.969611)
			(xy 387.677649 -351.984977) (xy 387.623655 -351.992738) (xy 387.59638 -351.9932) (xy 386.73278 -351.9932)
			(xy 386.705514 -351.992636) (xy 386.651538 -351.984873) (xy 386.599216 -351.969508) (xy 386.549614 -351.946852)
			(xy 386.50374 -351.917369) (xy 386.462529 -351.881657) (xy 386.426819 -351.840444) (xy 386.397338 -351.794569)
			(xy 386.374685 -351.744965) (xy 386.359323 -351.692642) (xy 386.351562 -351.638666) (xy 384.868714 -351.638666)
			(xy 384.868714 -351.638671) (xy 384.860952 -351.692658) (xy 384.845586 -351.744992) (xy 384.822929 -351.794605)
			(xy 384.793442 -351.84049) (xy 384.757725 -351.881711) (xy 384.716506 -351.91743) (xy 384.670623 -351.946919)
			(xy 384.62101 -351.969579) (xy 384.568678 -351.984947) (xy 384.514691 -351.992712) (xy 384.48742 -351.9932)
			(xy 383.62382 -351.9932) (xy 383.596551 -351.992662) (xy 383.542567 -351.984903) (xy 383.490237 -351.96954)
			(xy 383.440626 -351.946886) (xy 383.394745 -351.917402) (xy 383.353526 -351.881688) (xy 383.31781 -351.840471)
			(xy 383.288324 -351.794591) (xy 383.265667 -351.744982) (xy 383.250301 -351.692652) (xy 383.242539 -351.638669)
			(xy 381.759836 -351.638669) (xy 381.759836 -351.638676) (xy 381.752072 -351.692671) (xy 381.736703 -351.745012)
			(xy 381.71404 -351.794633) (xy 381.684546 -351.840523) (xy 381.64882 -351.881749) (xy 381.607591 -351.91747)
			(xy 381.561698 -351.946959) (xy 381.512075 -351.969617) (xy 381.459732 -351.984981) (xy 381.405736 -351.992739)
			(xy 381.37846 -351.9932) (xy 380.51486 -351.9932) (xy 380.487595 -351.992635) (xy 380.433621 -351.984869)
			(xy 380.381302 -351.969502) (xy 380.331702 -351.946846) (xy 380.28583 -351.917362) (xy 380.244621 -351.88165)
			(xy 380.208914 -351.840438) (xy 380.179435 -351.794563) (xy 380.156784 -351.744961) (xy 380.141422 -351.69264)
			(xy 380.133662 -351.638665) (xy 378.650813 -351.638665) (xy 378.650813 -351.638672) (xy 378.643051 -351.692661)
			(xy 378.627684 -351.744996) (xy 378.605026 -351.794611) (xy 378.575537 -351.840496) (xy 378.539818 -351.881718)
			(xy 378.498596 -351.917437) (xy 378.452711 -351.946926) (xy 378.403096 -351.969584) (xy 378.350761 -351.984951)
			(xy 378.296772 -351.992713) (xy 378.2695 -351.9932) (xy 377.4059 -351.9932) (xy 377.378633 -351.992638)
			(xy 377.324655 -351.984877) (xy 377.272331 -351.969513) (xy 377.222726 -351.946859) (xy 377.176849 -351.917376)
			(xy 377.135636 -351.881664) (xy 377.099924 -351.840451) (xy 377.070441 -351.794574) (xy 377.047787 -351.744969)
			(xy 377.032423 -351.692645) (xy 377.024662 -351.638667) (xy 375.541814 -351.638667) (xy 375.541814 -351.63867)
			(xy 375.534052 -351.692656) (xy 375.518687 -351.744987) (xy 375.496032 -351.7946) (xy 375.466547 -351.840483)
			(xy 375.430832 -351.881704) (xy 375.389615 -351.917423) (xy 375.343735 -351.946913) (xy 375.294125 -351.969573)
			(xy 375.241795 -351.984944) (xy 375.18781 -351.992711) (xy 375.16054 -351.9932) (xy 374.29694 -351.9932)
			(xy 374.26967 -351.992663) (xy 374.215684 -351.984907) (xy 374.163352 -351.969545) (xy 374.113738 -351.946892)
			(xy 374.067854 -351.917409) (xy 374.026634 -351.881695) (xy 373.990915 -351.840478) (xy 373.961427 -351.794597)
			(xy 373.938769 -351.744986) (xy 373.923402 -351.692655) (xy 373.91564 -351.63867) (xy 372.432936 -351.63867)
			(xy 372.432936 -351.638675) (xy 372.425173 -351.692669) (xy 372.409804 -351.745008) (xy 372.387143 -351.794628)
			(xy 372.35765 -351.840517) (xy 372.321927 -351.881741) (xy 372.280701 -351.917462) (xy 372.23481 -351.946952)
			(xy 372.185189 -351.969611) (xy 372.132849 -351.984977) (xy 372.078855 -351.992738) (xy 372.05158 -351.9932)
			(xy 371.18798 -351.9932) (xy 371.160714 -351.992636) (xy 371.106738 -351.984873) (xy 371.054416 -351.969508)
			(xy 371.004814 -351.946852) (xy 370.95894 -351.917369) (xy 370.917729 -351.881657) (xy 370.882019 -351.840444)
			(xy 370.852538 -351.794569) (xy 370.829885 -351.744965) (xy 370.814523 -351.692642) (xy 370.806762 -351.638666)
			(xy 344.837313 -351.638666) (xy 344.837313 -351.638672) (xy 344.829551 -351.692661) (xy 344.814184 -351.744995)
			(xy 344.791526 -351.79461) (xy 344.762038 -351.840495) (xy 344.726319 -351.881717) (xy 344.685098 -351.917435)
			(xy 344.639213 -351.946924) (xy 344.589599 -351.969583) (xy 344.537264 -351.98495) (xy 344.483276 -351.992713)
			(xy 344.456004 -351.9932) (xy 343.592404 -351.9932) (xy 343.565136 -351.992661) (xy 343.511154 -351.9849)
			(xy 343.458826 -351.969536) (xy 343.409217 -351.94688) (xy 343.363337 -351.917396) (xy 343.322121 -351.881682)
			(xy 343.286407 -351.840466) (xy 343.256921 -351.794587) (xy 343.234266 -351.744978) (xy 343.218901 -351.69265)
			(xy 343.211139 -351.638668) (xy 341.728314 -351.638668) (xy 341.728314 -351.63867) (xy 341.720552 -351.692655)
			(xy 341.705188 -351.744986) (xy 341.682532 -351.794599) (xy 341.653048 -351.840482) (xy 341.617334 -351.881703)
			(xy 341.576117 -351.917421) (xy 341.530237 -351.946911) (xy 341.480628 -351.969572) (xy 341.428298 -351.984943)
			(xy 341.374314 -351.99271) (xy 341.347044 -351.9932) (xy 340.483444 -351.9932) (xy 340.456174 -351.992664)
			(xy 340.402187 -351.984907) (xy 340.349855 -351.969546) (xy 340.300241 -351.946894) (xy 340.254356 -351.91741)
			(xy 340.213135 -351.881696) (xy 340.177416 -351.840479) (xy 340.147928 -351.794598) (xy 340.125269 -351.744987)
			(xy 340.109902 -351.692656) (xy 340.10214 -351.63867) (xy 338.619436 -351.63867) (xy 338.619436 -351.638674)
			(xy 338.611673 -351.692668) (xy 338.596304 -351.745007) (xy 338.573643 -351.794626) (xy 338.544151 -351.840515)
			(xy 338.508429 -351.88174) (xy 338.467203 -351.917461) (xy 338.421312 -351.946951) (xy 338.371692 -351.96961)
			(xy 338.319352 -351.984976) (xy 338.265358 -351.992738) (xy 338.238084 -351.9932) (xy 337.374484 -351.9932)
			(xy 337.347218 -351.992637) (xy 337.293242 -351.984874) (xy 337.240919 -351.969509) (xy 337.191316 -351.946854)
			(xy 337.145442 -351.91737) (xy 337.10423 -351.881659) (xy 337.06852 -351.840446) (xy 337.039039 -351.79457)
			(xy 337.016386 -351.744966) (xy 337.001023 -351.692643) (xy 336.993262 -351.638666) (xy 335.510414 -351.638666)
			(xy 335.510414 -351.638671) (xy 335.502652 -351.692658) (xy 335.487286 -351.744991) (xy 335.464629 -351.794604)
			(xy 335.435143 -351.840488) (xy 335.399427 -351.88171) (xy 335.358208 -351.917428) (xy 335.312325 -351.946918)
			(xy 335.262713 -351.969578) (xy 335.210381 -351.984947) (xy 335.156395 -351.992712) (xy 335.129124 -351.9932)
			(xy 334.265524 -351.9932) (xy 334.238255 -351.992662) (xy 334.18427 -351.984904) (xy 334.13194 -351.969541)
			(xy 334.082329 -351.946887) (xy 334.036447 -351.917403) (xy 333.995228 -351.881689) (xy 333.959511 -351.840472)
			(xy 333.930024 -351.794592) (xy 333.907367 -351.744982) (xy 333.892001 -351.692653) (xy 333.884239 -351.638669)
			(xy 332.401536 -351.638669) (xy 332.401536 -351.638675) (xy 332.393772 -351.692671) (xy 332.378403 -351.745011)
			(xy 332.35574 -351.794632) (xy 332.326246 -351.840522) (xy 332.290522 -351.881747) (xy 332.249293 -351.917468)
			(xy 332.2034 -351.946958) (xy 332.153778 -351.969615) (xy 332.101436 -351.98498) (xy 332.047439 -351.992739)
			(xy 332.020164 -351.9932) (xy 331.156564 -351.9932) (xy 331.129299 -351.992635) (xy 331.075325 -351.98487)
			(xy 331.023005 -351.969503) (xy 330.973404 -351.946847) (xy 330.927532 -351.917363) (xy 330.886323 -351.881652)
			(xy 330.850615 -351.840439) (xy 330.821136 -351.794564) (xy 330.798484 -351.744962) (xy 330.783122 -351.69264)
			(xy 330.775362 -351.638665) (xy 329.292513 -351.638665) (xy 329.292513 -351.638672) (xy 329.284751 -351.692661)
			(xy 329.269384 -351.744995) (xy 329.246726 -351.79461) (xy 329.217238 -351.840495) (xy 329.181519 -351.881717)
			(xy 329.140298 -351.917435) (xy 329.094413 -351.946924) (xy 329.044799 -351.969583) (xy 328.992464 -351.98495)
			(xy 328.938476 -351.992713) (xy 328.911204 -351.9932) (xy 328.047604 -351.9932) (xy 328.020336 -351.992661)
			(xy 327.966354 -351.9849) (xy 327.914026 -351.969536) (xy 327.864417 -351.94688) (xy 327.818537 -351.917396)
			(xy 327.777321 -351.881682) (xy 327.741607 -351.840466) (xy 327.712121 -351.794587) (xy 327.689466 -351.744978)
			(xy 327.674101 -351.69265) (xy 327.666339 -351.638668) (xy 326.183514 -351.638668) (xy 326.183514 -351.63867)
			(xy 326.175752 -351.692655) (xy 326.160388 -351.744986) (xy 326.137732 -351.794599) (xy 326.108248 -351.840482)
			(xy 326.072534 -351.881703) (xy 326.031317 -351.917421) (xy 325.985437 -351.946911) (xy 325.935828 -351.969572)
			(xy 325.883498 -351.984943) (xy 325.829514 -351.99271) (xy 325.802244 -351.9932) (xy 324.938644 -351.9932)
			(xy 324.911374 -351.992664) (xy 324.857387 -351.984907) (xy 324.805055 -351.969546) (xy 324.755441 -351.946894)
			(xy 324.709556 -351.91741) (xy 324.668335 -351.881696) (xy 324.632616 -351.840479) (xy 324.603128 -351.794598)
			(xy 324.580469 -351.744987) (xy 324.565102 -351.692656) (xy 324.55734 -351.63867) (xy 323.074636 -351.63867)
			(xy 323.074636 -351.638674) (xy 323.066873 -351.692668) (xy 323.051504 -351.745007) (xy 323.028843 -351.794626)
			(xy 322.999351 -351.840515) (xy 322.963629 -351.88174) (xy 322.922403 -351.917461) (xy 322.876512 -351.946951)
			(xy 322.826892 -351.96961) (xy 322.774552 -351.984976) (xy 322.720558 -351.992738) (xy 322.693284 -351.9932)
			(xy 321.829684 -351.9932) (xy 321.802418 -351.992637) (xy 321.748442 -351.984874) (xy 321.696119 -351.969509)
			(xy 321.646516 -351.946854) (xy 321.600642 -351.91737) (xy 321.55943 -351.881659) (xy 321.52372 -351.840446)
			(xy 321.494239 -351.79457) (xy 321.471586 -351.744966) (xy 321.456223 -351.692643) (xy 321.448462 -351.638666)
			(xy 319.965614 -351.638666) (xy 319.965614 -351.638671) (xy 319.957852 -351.692658) (xy 319.942486 -351.744991)
			(xy 319.919829 -351.794604) (xy 319.890343 -351.840488) (xy 319.854627 -351.88171) (xy 319.813408 -351.917428)
			(xy 319.767525 -351.946918) (xy 319.717913 -351.969578) (xy 319.665581 -351.984947) (xy 319.611595 -351.992712)
			(xy 319.584324 -351.9932) (xy 318.720724 -351.9932) (xy 318.693455 -351.992662) (xy 318.63947 -351.984904)
			(xy 318.58714 -351.969541) (xy 318.537529 -351.946887) (xy 318.491647 -351.917403) (xy 318.450428 -351.881689)
			(xy 318.414711 -351.840472) (xy 318.385224 -351.794592) (xy 318.362567 -351.744982) (xy 318.347201 -351.692653)
			(xy 318.339439 -351.638669) (xy 316.856736 -351.638669) (xy 316.856736 -351.638675) (xy 316.848972 -351.692671)
			(xy 316.833603 -351.745011) (xy 316.81094 -351.794632) (xy 316.781446 -351.840522) (xy 316.745722 -351.881747)
			(xy 316.704493 -351.917468) (xy 316.6586 -351.946958) (xy 316.608978 -351.969615) (xy 316.556636 -351.98498)
			(xy 316.502639 -351.992739) (xy 316.475364 -351.9932) (xy 315.611764 -351.9932) (xy 315.584499 -351.992635)
			(xy 315.530525 -351.98487) (xy 315.478205 -351.969503) (xy 315.428604 -351.946847) (xy 315.382732 -351.917363)
			(xy 315.341523 -351.881652) (xy 315.305815 -351.840439) (xy 315.276336 -351.794564) (xy 315.253684 -351.744962)
			(xy 315.238322 -351.69264) (xy 315.230562 -351.638665) (xy 313.747713 -351.638665) (xy 313.747713 -351.638672)
			(xy 313.739951 -351.692661) (xy 313.724584 -351.744995) (xy 313.701926 -351.79461) (xy 313.672438 -351.840495)
			(xy 313.636719 -351.881717) (xy 313.595498 -351.917435) (xy 313.549613 -351.946924) (xy 313.499999 -351.969583)
			(xy 313.447664 -351.98495) (xy 313.393676 -351.992713) (xy 313.366404 -351.9932) (xy 312.502804 -351.9932)
			(xy 312.475536 -351.992661) (xy 312.421554 -351.9849) (xy 312.369226 -351.969536) (xy 312.319617 -351.94688)
			(xy 312.273737 -351.917396) (xy 312.232521 -351.881682) (xy 312.196807 -351.840466) (xy 312.167321 -351.794587)
			(xy 312.144666 -351.744978) (xy 312.129301 -351.69265) (xy 312.121539 -351.638668) (xy 311.574942 -351.638668)
			(xy 311.574942 -352.723704) (xy 311.574517 -352.733773) (xy 311.566795 -352.752371) (xy 311.559956 -352.759772)
			(xy 309.732426 -354.587302) (xy 309.728901 -354.59103) (xy 309.723266 -354.599602) (xy 309.72125 -354.60432)
			(xy 309.717694 -354.612956) (xy 309.717694 -354.759369) (xy 315.230506 -354.759369) (xy 315.230506 -354.704831)
			(xy 315.238267 -354.650848) (xy 315.253632 -354.598519) (xy 315.276286 -354.548909) (xy 315.30577 -354.503027)
			(xy 315.341483 -354.461809) (xy 315.382699 -354.426092) (xy 315.428577 -354.396604) (xy 315.478185 -354.373944)
			(xy 315.530513 -354.358575) (xy 315.584495 -354.350809) (xy 315.611764 -354.35032) (xy 316.475364 -354.35032)
			(xy 316.502635 -354.350817) (xy 316.556624 -354.358575) (xy 316.608958 -354.373937) (xy 316.658574 -354.396591)
			(xy 316.70446 -354.426077) (xy 316.745682 -354.461793) (xy 316.781402 -354.503012) (xy 316.810891 -354.548895)
			(xy 316.83355 -354.598508) (xy 316.848918 -354.650841) (xy 316.85668 -354.704829) (xy 316.85668 -354.759371)
			(xy 316.85668 -354.759373) (xy 318.339384 -354.759373) (xy 318.339384 -354.704827) (xy 318.347147 -354.650835)
			(xy 318.362515 -354.598498) (xy 318.385175 -354.548881) (xy 318.414667 -354.502994) (xy 318.450388 -354.461771)
			(xy 318.491613 -354.426052) (xy 318.537502 -354.396564) (xy 318.587121 -354.373907) (xy 318.639459 -354.358542)
			(xy 318.693451 -354.350782) (xy 318.720724 -354.35032) (xy 319.584324 -354.35032) (xy 319.611591 -354.350844)
			(xy 319.665569 -354.358608) (xy 319.717894 -354.373975) (xy 319.767498 -354.396631) (xy 319.813374 -354.426116)
			(xy 319.854587 -354.46183) (xy 319.890298 -354.503045) (xy 319.91978 -354.548923) (xy 319.942434 -354.598529)
			(xy 319.957797 -354.650854) (xy 319.965558 -354.704833) (xy 319.965558 -354.759367) (xy 319.965558 -354.75937)
			(xy 321.448406 -354.75937) (xy 321.448406 -354.70483) (xy 321.456168 -354.650845) (xy 321.471533 -354.598515)
			(xy 321.494189 -354.548903) (xy 321.523675 -354.503021) (xy 321.55939 -354.461802) (xy 321.600608 -354.426085)
			(xy 321.646489 -354.396597) (xy 321.6961 -354.373939) (xy 321.74843 -354.358571) (xy 321.802414 -354.350808)
			(xy 321.829684 -354.35032) (xy 322.693284 -354.35032) (xy 322.720554 -354.350818) (xy 322.774541 -354.358578)
			(xy 322.826873 -354.373942) (xy 322.876485 -354.396598) (xy 322.922369 -354.426084) (xy 322.963589 -354.4618)
			(xy 322.999307 -354.503018) (xy 323.028794 -354.5489) (xy 323.051452 -354.598512) (xy 323.066818 -354.650844)
			(xy 323.074581 -354.70483) (xy 323.074581 -354.75937) (xy 323.07458 -354.759374) (xy 324.557284 -354.759374)
			(xy 324.557284 -354.704826) (xy 324.565047 -354.650832) (xy 324.580417 -354.598494) (xy 324.603078 -354.548875)
			(xy 324.632571 -354.502987) (xy 324.668295 -354.461764) (xy 324.709523 -354.426045) (xy 324.755414 -354.396557)
			(xy 324.805035 -354.373901) (xy 324.857375 -354.358538) (xy 324.91137 -354.350781) (xy 324.938644 -354.35032)
			(xy 325.802244 -354.35032) (xy 325.82951 -354.350845) (xy 325.883486 -354.358612) (xy 325.935808 -354.37398)
			(xy 325.98541 -354.396638) (xy 326.031284 -354.426124) (xy 326.072494 -354.461837) (xy 326.108203 -354.503052)
			(xy 326.137683 -354.548928) (xy 326.160335 -354.598533) (xy 326.175698 -354.650857) (xy 326.183458 -354.704834)
			(xy 326.183458 -354.759366) (xy 326.183457 -354.759372) (xy 327.666284 -354.759372) (xy 327.666284 -354.704828)
			(xy 327.674046 -354.650838) (xy 327.689413 -354.598502) (xy 327.712072 -354.548887) (xy 327.741562 -354.503001)
			(xy 327.777281 -354.461778) (xy 327.818504 -354.426059) (xy 327.86439 -354.39657) (xy 327.914006 -354.373912)
			(xy 327.966342 -354.358545) (xy 328.020332 -354.350783) (xy 328.047604 -354.35032) (xy 328.911204 -354.35032)
			(xy 328.938472 -354.350843) (xy 328.992453 -354.358604) (xy 329.044779 -354.373969) (xy 329.094386 -354.396625)
			(xy 329.140265 -354.426109) (xy 329.18148 -354.461823) (xy 329.217193 -354.503039) (xy 329.246677 -354.548917)
			(xy 329.269332 -354.598525) (xy 329.284696 -354.650851) (xy 329.292458 -354.704832) (xy 329.292458 -354.759368)
			(xy 329.292458 -354.759369) (xy 330.775306 -354.759369) (xy 330.775306 -354.704831) (xy 330.783067 -354.650848)
			(xy 330.798432 -354.598519) (xy 330.821086 -354.548909) (xy 330.85057 -354.503027) (xy 330.886283 -354.461809)
			(xy 330.927499 -354.426092) (xy 330.973377 -354.396604) (xy 331.022985 -354.373944) (xy 331.075313 -354.358575)
			(xy 331.129295 -354.350809) (xy 331.156564 -354.35032) (xy 332.020164 -354.35032) (xy 332.047435 -354.350817)
			(xy 332.101424 -354.358575) (xy 332.153758 -354.373937) (xy 332.203374 -354.396591) (xy 332.24926 -354.426077)
			(xy 332.290482 -354.461793) (xy 332.326202 -354.503012) (xy 332.355691 -354.548895) (xy 332.37835 -354.598508)
			(xy 332.393718 -354.650841) (xy 332.40148 -354.704829) (xy 332.40148 -354.759371) (xy 332.40148 -354.759373)
			(xy 333.884184 -354.759373) (xy 333.884184 -354.704827) (xy 333.891947 -354.650835) (xy 333.907315 -354.598498)
			(xy 333.929975 -354.548881) (xy 333.959467 -354.502994) (xy 333.995188 -354.461771) (xy 334.036413 -354.426052)
			(xy 334.082302 -354.396564) (xy 334.131921 -354.373907) (xy 334.184259 -354.358542) (xy 334.238251 -354.350782)
			(xy 334.265524 -354.35032) (xy 335.129124 -354.35032) (xy 335.156391 -354.350844) (xy 335.210369 -354.358608)
			(xy 335.262694 -354.373975) (xy 335.312298 -354.396631) (xy 335.358174 -354.426116) (xy 335.399387 -354.46183)
			(xy 335.435098 -354.503045) (xy 335.46458 -354.548923) (xy 335.487234 -354.598529) (xy 335.502597 -354.650854)
			(xy 335.510358 -354.704833) (xy 335.510358 -354.759367) (xy 335.510358 -354.75937) (xy 336.993206 -354.75937)
			(xy 336.993206 -354.70483) (xy 337.000968 -354.650845) (xy 337.016333 -354.598515) (xy 337.038989 -354.548903)
			(xy 337.068475 -354.503021) (xy 337.10419 -354.461802) (xy 337.145408 -354.426085) (xy 337.191289 -354.396597)
			(xy 337.2409 -354.373939) (xy 337.29323 -354.358571) (xy 337.347214 -354.350808) (xy 337.374484 -354.35032)
			(xy 338.238084 -354.35032) (xy 338.265354 -354.350818) (xy 338.319341 -354.358578) (xy 338.371673 -354.373942)
			(xy 338.421285 -354.396598) (xy 338.467169 -354.426084) (xy 338.508389 -354.4618) (xy 338.544107 -354.503018)
			(xy 338.573594 -354.5489) (xy 338.596252 -354.598512) (xy 338.611618 -354.650844) (xy 338.619381 -354.70483)
			(xy 338.619381 -354.75937) (xy 338.61938 -354.759374) (xy 340.102084 -354.759374) (xy 340.102084 -354.704826)
			(xy 340.109847 -354.650832) (xy 340.125217 -354.598494) (xy 340.147878 -354.548875) (xy 340.177371 -354.502987)
			(xy 340.213095 -354.461764) (xy 340.254323 -354.426045) (xy 340.300214 -354.396557) (xy 340.349835 -354.373901)
			(xy 340.402175 -354.358538) (xy 340.45617 -354.350781) (xy 340.483444 -354.35032) (xy 341.347044 -354.35032)
			(xy 341.37431 -354.350845) (xy 341.428286 -354.358612) (xy 341.480608 -354.37398) (xy 341.53021 -354.396638)
			(xy 341.576084 -354.426124) (xy 341.617294 -354.461837) (xy 341.653003 -354.503052) (xy 341.682483 -354.548928)
			(xy 341.705135 -354.598533) (xy 341.720498 -354.650857) (xy 341.728258 -354.704834) (xy 341.728258 -354.759366)
			(xy 341.728257 -354.759372) (xy 343.211084 -354.759372) (xy 343.211084 -354.704828) (xy 343.218846 -354.650838)
			(xy 343.234213 -354.598502) (xy 343.256872 -354.548887) (xy 343.286362 -354.503001) (xy 343.322081 -354.461778)
			(xy 343.363304 -354.426059) (xy 343.40919 -354.39657) (xy 343.458806 -354.373912) (xy 343.511142 -354.358545)
			(xy 343.565132 -354.350783) (xy 343.592404 -354.35032) (xy 344.456004 -354.35032) (xy 344.483272 -354.350843)
			(xy 344.537253 -354.358604) (xy 344.589579 -354.373969) (xy 344.639186 -354.396625) (xy 344.685065 -354.426109)
			(xy 344.72628 -354.461823) (xy 344.761993 -354.503039) (xy 344.791477 -354.548917) (xy 344.814132 -354.598525)
			(xy 344.829496 -354.650851) (xy 344.837258 -354.704832) (xy 344.837258 -354.759368) (xy 344.837257 -354.759374)
			(xy 373.915584 -354.759374) (xy 373.915584 -354.704826) (xy 373.923347 -354.650833) (xy 373.938716 -354.598495)
			(xy 373.961378 -354.548876) (xy 373.990871 -354.502989) (xy 374.026594 -354.461766) (xy 374.067821 -354.426047)
			(xy 374.113712 -354.396559) (xy 374.163332 -354.373902) (xy 374.215672 -354.358539) (xy 374.269666 -354.350781)
			(xy 374.29694 -354.35032) (xy 375.16054 -354.35032) (xy 375.187806 -354.350845) (xy 375.241783 -354.358611)
			(xy 375.294105 -354.373979) (xy 375.343708 -354.396637) (xy 375.389582 -354.426122) (xy 375.430793 -354.461836)
			(xy 375.466502 -354.50305) (xy 375.495983 -354.548927) (xy 375.518635 -354.598532) (xy 375.533997 -354.650856)
			(xy 375.541758 -354.704834) (xy 375.541758 -354.759366) (xy 375.541757 -354.759371) (xy 377.024606 -354.759371)
			(xy 377.024606 -354.704829) (xy 377.032369 -354.650843) (xy 377.047735 -354.598511) (xy 377.070392 -354.548899)
			(xy 377.099879 -354.503016) (xy 377.135596 -354.461796) (xy 377.176816 -354.426079) (xy 377.222699 -354.396592)
			(xy 377.272311 -354.373935) (xy 377.324643 -354.358569) (xy 377.378629 -354.350806) (xy 377.4059 -354.35032)
			(xy 378.2695 -354.35032) (xy 378.296768 -354.350842) (xy 378.350749 -354.358604) (xy 378.403076 -354.373968)
			(xy 378.452684 -354.396623) (xy 378.498563 -354.426108) (xy 378.539778 -354.461822) (xy 378.575492 -354.503037)
			(xy 378.604977 -354.548916) (xy 378.627632 -354.598524) (xy 378.642996 -354.650851) (xy 378.650758 -354.704832)
			(xy 378.650758 -354.759368) (xy 378.650758 -354.759369) (xy 380.133606 -354.759369) (xy 380.133606 -354.704831)
			(xy 380.141367 -354.650849) (xy 380.156731 -354.59852) (xy 380.179386 -354.54891) (xy 380.208869 -354.503029)
			(xy 380.244582 -354.46181) (xy 380.285797 -354.426093) (xy 380.331675 -354.396605) (xy 380.381282 -354.373945)
			(xy 380.433609 -354.358576) (xy 380.487591 -354.350809) (xy 380.51486 -354.35032) (xy 381.37846 -354.35032)
			(xy 381.405732 -354.350817) (xy 381.45972 -354.358574) (xy 381.512055 -354.373936) (xy 381.561671 -354.39659)
			(xy 381.607558 -354.426075) (xy 381.648781 -354.461791) (xy 381.684501 -354.50301) (xy 381.713991 -354.548894)
			(xy 381.73665 -354.598507) (xy 381.752018 -354.650841) (xy 381.75978 -354.704828) (xy 381.75978 -354.759372)
			(xy 381.75978 -354.759373) (xy 383.242484 -354.759373) (xy 383.242484 -354.704827) (xy 383.250247 -354.650836)
			(xy 383.265615 -354.598499) (xy 383.288275 -354.548882) (xy 383.317766 -354.502995) (xy 383.353487 -354.461773)
			(xy 383.394711 -354.426054) (xy 383.4406 -354.396565) (xy 383.490218 -354.373908) (xy 383.542555 -354.358542)
			(xy 383.596547 -354.350782) (xy 383.62382 -354.35032) (xy 384.48742 -354.35032) (xy 384.514687 -354.350844)
			(xy 384.568666 -354.358607) (xy 384.620991 -354.373974) (xy 384.670596 -354.39663) (xy 384.716472 -354.426115)
			(xy 384.757686 -354.461829) (xy 384.793397 -354.503044) (xy 384.82288 -354.548922) (xy 384.845533 -354.598528)
			(xy 384.860897 -354.650854) (xy 384.868658 -354.704833) (xy 384.868658 -354.759367) (xy 384.868658 -354.75937)
			(xy 386.351506 -354.75937) (xy 386.351506 -354.70483) (xy 386.359268 -354.650846) (xy 386.374633 -354.598515)
			(xy 386.397289 -354.548904) (xy 386.426774 -354.503022) (xy 386.462489 -354.461803) (xy 386.503706 -354.426086)
			(xy 386.549587 -354.396598) (xy 386.599197 -354.37394) (xy 386.651526 -354.358572) (xy 386.70551 -354.350808)
			(xy 386.73278 -354.35032) (xy 387.59638 -354.35032) (xy 387.623651 -354.350818) (xy 387.677637 -354.358578)
			(xy 387.72997 -354.373941) (xy 387.779583 -354.396597) (xy 387.825467 -354.426082) (xy 387.866688 -354.461798)
			(xy 387.902406 -354.503017) (xy 387.931894 -354.548899) (xy 387.954552 -354.598511) (xy 387.969918 -354.650843)
			(xy 387.97768 -354.704829) (xy 387.97768 -354.759371) (xy 387.97768 -354.759374) (xy 389.460384 -354.759374)
			(xy 389.460384 -354.704826) (xy 389.468147 -354.650833) (xy 389.483516 -354.598495) (xy 389.506178 -354.548876)
			(xy 389.535671 -354.502989) (xy 389.571394 -354.461766) (xy 389.612621 -354.426047) (xy 389.658512 -354.396559)
			(xy 389.708132 -354.373902) (xy 389.760472 -354.358539) (xy 389.814466 -354.350781) (xy 389.84174 -354.35032)
			(xy 390.70534 -354.35032) (xy 390.732606 -354.350845) (xy 390.786583 -354.358611) (xy 390.838905 -354.373979)
			(xy 390.888508 -354.396637) (xy 390.934382 -354.426122) (xy 390.975593 -354.461836) (xy 391.011302 -354.50305)
			(xy 391.040783 -354.548927) (xy 391.063435 -354.598532) (xy 391.078797 -354.650856) (xy 391.086558 -354.704834)
			(xy 391.086558 -354.759366) (xy 391.086557 -354.759371) (xy 392.569406 -354.759371) (xy 392.569406 -354.704829)
			(xy 392.577169 -354.650843) (xy 392.592535 -354.598511) (xy 392.615192 -354.548899) (xy 392.644679 -354.503016)
			(xy 392.680396 -354.461796) (xy 392.721616 -354.426079) (xy 392.767499 -354.396592) (xy 392.817111 -354.373935)
			(xy 392.869443 -354.358569) (xy 392.923429 -354.350806) (xy 392.9507 -354.35032) (xy 393.8143 -354.35032)
			(xy 393.841568 -354.350842) (xy 393.895549 -354.358604) (xy 393.947876 -354.373968) (xy 393.997484 -354.396623)
			(xy 394.043363 -354.426108) (xy 394.084578 -354.461822) (xy 394.120292 -354.503037) (xy 394.149777 -354.548916)
			(xy 394.172432 -354.598524) (xy 394.187796 -354.650851) (xy 394.195558 -354.704832) (xy 394.195558 -354.759368)
			(xy 394.195558 -354.759369) (xy 395.678406 -354.759369) (xy 395.678406 -354.704831) (xy 395.686167 -354.650849)
			(xy 395.701531 -354.59852) (xy 395.724186 -354.54891) (xy 395.753669 -354.503029) (xy 395.789382 -354.46181)
			(xy 395.830597 -354.426093) (xy 395.876475 -354.396605) (xy 395.926082 -354.373945) (xy 395.978409 -354.358576)
			(xy 396.032391 -354.350809) (xy 396.05966 -354.35032) (xy 396.92326 -354.35032) (xy 396.950532 -354.350817)
			(xy 397.00452 -354.358574) (xy 397.056855 -354.373936) (xy 397.106471 -354.39659) (xy 397.152358 -354.426075)
			(xy 397.193581 -354.461791) (xy 397.229301 -354.50301) (xy 397.258791 -354.548894) (xy 397.28145 -354.598507)
			(xy 397.296818 -354.650841) (xy 397.30458 -354.704828) (xy 397.30458 -354.759372) (xy 397.30458 -354.759373)
			(xy 398.787284 -354.759373) (xy 398.787284 -354.704827) (xy 398.795047 -354.650836) (xy 398.810415 -354.598499)
			(xy 398.833075 -354.548882) (xy 398.862566 -354.502995) (xy 398.898287 -354.461773) (xy 398.939511 -354.426054)
			(xy 398.9854 -354.396565) (xy 399.035018 -354.373908) (xy 399.087355 -354.358542) (xy 399.141347 -354.350782)
			(xy 399.16862 -354.35032) (xy 400.03222 -354.35032) (xy 400.059487 -354.350844) (xy 400.113466 -354.358607)
			(xy 400.165791 -354.373974) (xy 400.215396 -354.39663) (xy 400.261272 -354.426115) (xy 400.302486 -354.461829)
			(xy 400.338197 -354.503044) (xy 400.36768 -354.548922) (xy 400.390333 -354.598528) (xy 400.405697 -354.650854)
			(xy 400.413458 -354.704833) (xy 400.413458 -354.759367) (xy 400.405697 -354.813346) (xy 400.390333 -354.865672)
			(xy 400.36768 -354.915278) (xy 400.338197 -354.961156) (xy 400.302486 -355.002371) (xy 400.261272 -355.038085)
			(xy 400.215396 -355.06757) (xy 400.165791 -355.090226) (xy 400.113466 -355.105593) (xy 400.059487 -355.113356)
			(xy 400.03222 -355.113844) (xy 399.16862 -355.113844) (xy 399.141347 -355.113418) (xy 399.087355 -355.105658)
			(xy 399.035018 -355.090292) (xy 398.9854 -355.067635) (xy 398.939511 -355.038146) (xy 398.898287 -355.002427)
			(xy 398.862566 -354.961205) (xy 398.833075 -354.915318) (xy 398.810415 -354.865701) (xy 398.795047 -354.813364)
			(xy 398.787284 -354.759373) (xy 397.30458 -354.759373) (xy 397.296818 -354.813359) (xy 397.28145 -354.865693)
			(xy 397.258791 -354.915306) (xy 397.229301 -354.96119) (xy 397.193581 -355.002409) (xy 397.152358 -355.038125)
			(xy 397.106471 -355.06761) (xy 397.056855 -355.090264) (xy 397.00452 -355.105626) (xy 396.950532 -355.113383)
			(xy 396.92326 -355.113844) (xy 396.05966 -355.113844) (xy 396.032391 -355.113391) (xy 395.978409 -355.105624)
			(xy 395.926082 -355.090255) (xy 395.876475 -355.067595) (xy 395.830597 -355.038107) (xy 395.789382 -355.00239)
			(xy 395.753669 -354.961171) (xy 395.724186 -354.91529) (xy 395.701531 -354.86568) (xy 395.686167 -354.813351)
			(xy 395.678406 -354.759369) (xy 394.195558 -354.759369) (xy 394.187796 -354.813349) (xy 394.172432 -354.865676)
			(xy 394.149777 -354.915284) (xy 394.120292 -354.961163) (xy 394.084578 -355.002378) (xy 394.043363 -355.038092)
			(xy 393.997484 -355.067577) (xy 393.947876 -355.090232) (xy 393.895549 -355.105596) (xy 393.841568 -355.113358)
			(xy 393.8143 -355.113844) (xy 392.9507 -355.113844) (xy 392.923429 -355.113394) (xy 392.869443 -355.105631)
			(xy 392.817111 -355.090265) (xy 392.767499 -355.067608) (xy 392.721616 -355.038121) (xy 392.680396 -355.002404)
			(xy 392.644679 -354.961184) (xy 392.615192 -354.915301) (xy 392.592535 -354.865689) (xy 392.577169 -354.813357)
			(xy 392.569406 -354.759371) (xy 391.086557 -354.759371) (xy 391.078797 -354.813344) (xy 391.063435 -354.865668)
			(xy 391.040783 -354.915273) (xy 391.011302 -354.96115) (xy 390.975593 -355.002364) (xy 390.934382 -355.038078)
			(xy 390.888508 -355.067563) (xy 390.838905 -355.090221) (xy 390.786583 -355.105589) (xy 390.732606 -355.113355)
			(xy 390.70534 -355.113844) (xy 389.84174 -355.113844) (xy 389.814466 -355.113419) (xy 389.760472 -355.105661)
			(xy 389.708132 -355.090298) (xy 389.658512 -355.067641) (xy 389.612621 -355.038153) (xy 389.571394 -355.002434)
			(xy 389.535671 -354.961211) (xy 389.506178 -354.915324) (xy 389.483516 -354.865705) (xy 389.468147 -354.813367)
			(xy 389.460384 -354.759374) (xy 387.97768 -354.759374) (xy 387.969918 -354.813357) (xy 387.954552 -354.865689)
			(xy 387.931894 -354.915301) (xy 387.902406 -354.961183) (xy 387.866688 -355.002402) (xy 387.825467 -355.038118)
			(xy 387.779583 -355.067603) (xy 387.72997 -355.090259) (xy 387.677637 -355.105622) (xy 387.623651 -355.113382)
			(xy 387.59638 -355.113844) (xy 386.73278 -355.113844) (xy 386.70551 -355.113392) (xy 386.651526 -355.105628)
			(xy 386.599197 -355.09026) (xy 386.549587 -355.067602) (xy 386.503706 -355.038114) (xy 386.462489 -355.002397)
			(xy 386.426774 -354.961178) (xy 386.397289 -354.915296) (xy 386.374633 -354.865685) (xy 386.359268 -354.813354)
			(xy 386.351506 -354.75937) (xy 384.868658 -354.75937) (xy 384.860897 -354.813346) (xy 384.845533 -354.865672)
			(xy 384.82288 -354.915278) (xy 384.793397 -354.961156) (xy 384.757686 -355.002371) (xy 384.716472 -355.038085)
			(xy 384.670596 -355.06757) (xy 384.620991 -355.090226) (xy 384.568666 -355.105593) (xy 384.514687 -355.113356)
			(xy 384.48742 -355.113844) (xy 383.62382 -355.113844) (xy 383.596547 -355.113418) (xy 383.542555 -355.105658)
			(xy 383.490218 -355.090292) (xy 383.4406 -355.067635) (xy 383.394711 -355.038146) (xy 383.353487 -355.002427)
			(xy 383.317766 -354.961205) (xy 383.288275 -354.915318) (xy 383.265615 -354.865701) (xy 383.250247 -354.813364)
			(xy 383.242484 -354.759373) (xy 381.75978 -354.759373) (xy 381.752018 -354.813359) (xy 381.73665 -354.865693)
			(xy 381.713991 -354.915306) (xy 381.684501 -354.96119) (xy 381.648781 -355.002409) (xy 381.607558 -355.038125)
			(xy 381.561671 -355.06761) (xy 381.512055 -355.090264) (xy 381.45972 -355.105626) (xy 381.405732 -355.113383)
			(xy 381.37846 -355.113844) (xy 380.51486 -355.113844) (xy 380.487591 -355.113391) (xy 380.433609 -355.105624)
			(xy 380.381282 -355.090255) (xy 380.331675 -355.067595) (xy 380.285797 -355.038107) (xy 380.244582 -355.00239)
			(xy 380.208869 -354.961171) (xy 380.179386 -354.91529) (xy 380.156731 -354.86568) (xy 380.141367 -354.813351)
			(xy 380.133606 -354.759369) (xy 378.650758 -354.759369) (xy 378.642996 -354.813349) (xy 378.627632 -354.865676)
			(xy 378.604977 -354.915284) (xy 378.575492 -354.961163) (xy 378.539778 -355.002378) (xy 378.498563 -355.038092)
			(xy 378.452684 -355.067577) (xy 378.403076 -355.090232) (xy 378.350749 -355.105596) (xy 378.296768 -355.113358)
			(xy 378.2695 -355.113844) (xy 377.4059 -355.113844) (xy 377.378629 -355.113394) (xy 377.324643 -355.105631)
			(xy 377.272311 -355.090265) (xy 377.222699 -355.067608) (xy 377.176816 -355.038121) (xy 377.135596 -355.002404)
			(xy 377.099879 -354.961184) (xy 377.070392 -354.915301) (xy 377.047735 -354.865689) (xy 377.032369 -354.813357)
			(xy 377.024606 -354.759371) (xy 375.541757 -354.759371) (xy 375.533997 -354.813344) (xy 375.518635 -354.865668)
			(xy 375.495983 -354.915273) (xy 375.466502 -354.96115) (xy 375.430793 -355.002364) (xy 375.389582 -355.038078)
			(xy 375.343708 -355.067563) (xy 375.294105 -355.090221) (xy 375.241783 -355.105589) (xy 375.187806 -355.113355)
			(xy 375.16054 -355.113844) (xy 374.29694 -355.113844) (xy 374.269666 -355.113419) (xy 374.215672 -355.105661)
			(xy 374.163332 -355.090298) (xy 374.113712 -355.067641) (xy 374.067821 -355.038153) (xy 374.026594 -355.002434)
			(xy 373.990871 -354.961211) (xy 373.961378 -354.915324) (xy 373.938716 -354.865705) (xy 373.923347 -354.813367)
			(xy 373.915584 -354.759374) (xy 344.837257 -354.759374) (xy 344.829496 -354.813349) (xy 344.814132 -354.865675)
			(xy 344.791477 -354.915283) (xy 344.761993 -354.961161) (xy 344.72628 -355.002377) (xy 344.685065 -355.038091)
			(xy 344.639186 -355.067575) (xy 344.589579 -355.090231) (xy 344.537253 -355.105596) (xy 344.483272 -355.113357)
			(xy 344.456004 -355.113844) (xy 343.592404 -355.113844) (xy 343.565132 -355.113417) (xy 343.511142 -355.105655)
			(xy 343.458806 -355.090288) (xy 343.40919 -355.06763) (xy 343.363304 -355.038141) (xy 343.322081 -355.002422)
			(xy 343.286362 -354.961199) (xy 343.256872 -354.915313) (xy 343.234213 -354.865698) (xy 343.218846 -354.813362)
			(xy 343.211084 -354.759372) (xy 341.728257 -354.759372) (xy 341.720498 -354.813343) (xy 341.705135 -354.865667)
			(xy 341.682483 -354.915272) (xy 341.653003 -354.961148) (xy 341.617294 -355.002363) (xy 341.576084 -355.038076)
			(xy 341.53021 -355.067562) (xy 341.480608 -355.09022) (xy 341.428286 -355.105588) (xy 341.37431 -355.113355)
			(xy 341.347044 -355.113844) (xy 340.483444 -355.113844) (xy 340.45617 -355.113419) (xy 340.402175 -355.105662)
			(xy 340.349835 -355.090299) (xy 340.300214 -355.067643) (xy 340.254323 -355.038155) (xy 340.213095 -355.002436)
			(xy 340.177371 -354.961213) (xy 340.147878 -354.915325) (xy 340.125217 -354.865706) (xy 340.109847 -354.813368)
			(xy 340.102084 -354.759374) (xy 338.61938 -354.759374) (xy 338.611618 -354.813356) (xy 338.596252 -354.865688)
			(xy 338.573594 -354.9153) (xy 338.544107 -354.961182) (xy 338.508389 -355.0024) (xy 338.467169 -355.038116)
			(xy 338.421285 -355.067602) (xy 338.371673 -355.090258) (xy 338.319341 -355.105622) (xy 338.265354 -355.113382)
			(xy 338.238084 -355.113844) (xy 337.374484 -355.113844) (xy 337.347214 -355.113392) (xy 337.29323 -355.105629)
			(xy 337.2409 -355.090261) (xy 337.191289 -355.067603) (xy 337.145408 -355.038115) (xy 337.10419 -355.002398)
			(xy 337.068475 -354.961179) (xy 337.038989 -354.915297) (xy 337.016333 -354.865685) (xy 337.000968 -354.813355)
			(xy 336.993206 -354.75937) (xy 335.510358 -354.75937) (xy 335.502597 -354.813346) (xy 335.487234 -354.865671)
			(xy 335.46458 -354.915277) (xy 335.435098 -354.961155) (xy 335.399387 -355.00237) (xy 335.358174 -355.038084)
			(xy 335.312298 -355.067569) (xy 335.262694 -355.090225) (xy 335.210369 -355.105592) (xy 335.156391 -355.113356)
			(xy 335.129124 -355.113844) (xy 334.265524 -355.113844) (xy 334.238251 -355.113418) (xy 334.184259 -355.105658)
			(xy 334.131921 -355.090293) (xy 334.082302 -355.067636) (xy 334.036413 -355.038148) (xy 333.995188 -355.002429)
			(xy 333.959467 -354.961206) (xy 333.929975 -354.915319) (xy 333.907315 -354.865702) (xy 333.891947 -354.813365)
			(xy 333.884184 -354.759373) (xy 332.40148 -354.759373) (xy 332.393718 -354.813359) (xy 332.37835 -354.865692)
			(xy 332.355691 -354.915305) (xy 332.326202 -354.961188) (xy 332.290482 -355.002407) (xy 332.24926 -355.038123)
			(xy 332.203374 -355.067609) (xy 332.153758 -355.090263) (xy 332.101424 -355.105625) (xy 332.047435 -355.113383)
			(xy 332.020164 -355.113844) (xy 331.156564 -355.113844) (xy 331.129295 -355.113391) (xy 331.075313 -355.105625)
			(xy 331.022985 -355.090256) (xy 330.973377 -355.067596) (xy 330.927499 -355.038108) (xy 330.886283 -355.002391)
			(xy 330.85057 -354.961173) (xy 330.821086 -354.915291) (xy 330.798432 -354.865681) (xy 330.783067 -354.813352)
			(xy 330.775306 -354.759369) (xy 329.292458 -354.759369) (xy 329.284696 -354.813349) (xy 329.269332 -354.865675)
			(xy 329.246677 -354.915283) (xy 329.217193 -354.961161) (xy 329.18148 -355.002377) (xy 329.140265 -355.038091)
			(xy 329.094386 -355.067575) (xy 329.044779 -355.090231) (xy 328.992453 -355.105596) (xy 328.938472 -355.113357)
			(xy 328.911204 -355.113844) (xy 328.047604 -355.113844) (xy 328.020332 -355.113417) (xy 327.966342 -355.105655)
			(xy 327.914006 -355.090288) (xy 327.86439 -355.06763) (xy 327.818504 -355.038141) (xy 327.777281 -355.002422)
			(xy 327.741562 -354.961199) (xy 327.712072 -354.915313) (xy 327.689413 -354.865698) (xy 327.674046 -354.813362)
			(xy 327.666284 -354.759372) (xy 326.183457 -354.759372) (xy 326.175698 -354.813343) (xy 326.160335 -354.865667)
			(xy 326.137683 -354.915272) (xy 326.108203 -354.961148) (xy 326.072494 -355.002363) (xy 326.031284 -355.038076)
			(xy 325.98541 -355.067562) (xy 325.935808 -355.09022) (xy 325.883486 -355.105588) (xy 325.82951 -355.113355)
			(xy 325.802244 -355.113844) (xy 324.938644 -355.113844) (xy 324.91137 -355.113419) (xy 324.857375 -355.105662)
			(xy 324.805035 -355.090299) (xy 324.755414 -355.067643) (xy 324.709523 -355.038155) (xy 324.668295 -355.002436)
			(xy 324.632571 -354.961213) (xy 324.603078 -354.915325) (xy 324.580417 -354.865706) (xy 324.565047 -354.813368)
			(xy 324.557284 -354.759374) (xy 323.07458 -354.759374) (xy 323.066818 -354.813356) (xy 323.051452 -354.865688)
			(xy 323.028794 -354.9153) (xy 322.999307 -354.961182) (xy 322.963589 -355.0024) (xy 322.922369 -355.038116)
			(xy 322.876485 -355.067602) (xy 322.826873 -355.090258) (xy 322.774541 -355.105622) (xy 322.720554 -355.113382)
			(xy 322.693284 -355.113844) (xy 321.829684 -355.113844) (xy 321.802414 -355.113392) (xy 321.74843 -355.105629)
			(xy 321.6961 -355.090261) (xy 321.646489 -355.067603) (xy 321.600608 -355.038115) (xy 321.55939 -355.002398)
			(xy 321.523675 -354.961179) (xy 321.494189 -354.915297) (xy 321.471533 -354.865685) (xy 321.456168 -354.813355)
			(xy 321.448406 -354.75937) (xy 319.965558 -354.75937) (xy 319.957797 -354.813346) (xy 319.942434 -354.865671)
			(xy 319.91978 -354.915277) (xy 319.890298 -354.961155) (xy 319.854587 -355.00237) (xy 319.813374 -355.038084)
			(xy 319.767498 -355.067569) (xy 319.717894 -355.090225) (xy 319.665569 -355.105592) (xy 319.611591 -355.113356)
			(xy 319.584324 -355.113844) (xy 318.720724 -355.113844) (xy 318.693451 -355.113418) (xy 318.639459 -355.105658)
			(xy 318.587121 -355.090293) (xy 318.537502 -355.067636) (xy 318.491613 -355.038148) (xy 318.450388 -355.002429)
			(xy 318.414667 -354.961206) (xy 318.385175 -354.915319) (xy 318.362515 -354.865702) (xy 318.347147 -354.813365)
			(xy 318.339384 -354.759373) (xy 316.85668 -354.759373) (xy 316.848918 -354.813359) (xy 316.83355 -354.865692)
			(xy 316.810891 -354.915305) (xy 316.781402 -354.961188) (xy 316.745682 -355.002407) (xy 316.70446 -355.038123)
			(xy 316.658574 -355.067609) (xy 316.608958 -355.090263) (xy 316.556624 -355.105625) (xy 316.502635 -355.113383)
			(xy 316.475364 -355.113844) (xy 315.611764 -355.113844) (xy 315.584495 -355.113391) (xy 315.530513 -355.105625)
			(xy 315.478185 -355.090256) (xy 315.428577 -355.067596) (xy 315.382699 -355.038108) (xy 315.341483 -355.002391)
			(xy 315.30577 -354.961173) (xy 315.276286 -354.915291) (xy 315.253632 -354.865681) (xy 315.238267 -354.813352)
			(xy 315.230506 -354.759369) (xy 309.717694 -354.759369) (xy 309.717694 -357.784966) (xy 315.230554 -357.784966)
			(xy 315.230554 -357.730434) (xy 315.238314 -357.676458) (xy 315.253677 -357.624136) (xy 315.276328 -357.574532)
			(xy 315.305809 -357.528656) (xy 315.341517 -357.487443) (xy 315.382727 -357.45173) (xy 315.4286 -357.422246)
			(xy 315.478202 -357.399589) (xy 315.530523 -357.384222) (xy 315.584498 -357.376457) (xy 315.611764 -357.375968)
			(xy 316.475364 -357.375968) (xy 316.502639 -357.376369) (xy 316.556634 -357.384128) (xy 316.608975 -357.399492)
			(xy 316.658597 -357.422149) (xy 316.704488 -357.451638) (xy 316.745716 -357.487359) (xy 316.78144 -357.528583)
			(xy 316.810933 -357.574472) (xy 316.833595 -357.624091) (xy 316.848965 -357.676431) (xy 316.856728 -357.730425)
			(xy 316.856728 -357.78497) (xy 318.339431 -357.78497) (xy 318.339431 -357.73043) (xy 318.347194 -357.676445)
			(xy 318.36256 -357.624115) (xy 318.385217 -357.574504) (xy 318.414705 -357.528623) (xy 318.450422 -357.487405)
			(xy 318.491642 -357.451691) (xy 318.537525 -357.422206) (xy 318.587137 -357.399552) (xy 318.639469 -357.384189)
			(xy 318.693454 -357.37643) (xy 318.720724 -357.375968) (xy 319.584324 -357.375968) (xy 319.611594 -357.376396)
			(xy 319.66558 -357.384161) (xy 319.71791 -357.39953) (xy 319.767521 -357.422189) (xy 319.813403 -357.451678)
			(xy 319.854621 -357.487396) (xy 319.890336 -357.528616) (xy 319.919822 -357.5745) (xy 319.942479 -357.624112)
			(xy 319.957844 -357.676444) (xy 319.965606 -357.73043) (xy 319.965606 -357.784967) (xy 321.448454 -357.784967)
			(xy 321.448454 -357.730434) (xy 321.456215 -357.676456) (xy 321.471578 -357.624131) (xy 321.494232 -357.574526)
			(xy 321.523714 -357.52865) (xy 321.559424 -357.487436) (xy 321.600637 -357.451723) (xy 321.646512 -357.422239)
			(xy 321.696116 -357.399584) (xy 321.74844 -357.384218) (xy 321.802418 -357.376455) (xy 321.829684 -357.375968)
			(xy 322.693284 -357.375968) (xy 322.720558 -357.37637) (xy 322.774551 -357.384131) (xy 322.826889 -357.399497)
			(xy 322.876508 -357.422156) (xy 322.922398 -357.451645) (xy 322.963623 -357.487366) (xy 322.999345 -357.528589)
			(xy 323.028836 -357.574477) (xy 323.051497 -357.624096) (xy 323.066865 -357.676434) (xy 323.074628 -357.730426)
			(xy 323.074628 -357.784971) (xy 324.557332 -357.784971) (xy 324.557332 -357.730429) (xy 324.565094 -357.676443)
			(xy 324.580461 -357.624111) (xy 324.603121 -357.574498) (xy 324.63261 -357.528616) (xy 324.668329 -357.487398)
			(xy 324.709551 -357.451684) (xy 324.755437 -357.422199) (xy 324.805052 -357.399546) (xy 324.857386 -357.384185)
			(xy 324.911373 -357.376428) (xy 324.938644 -357.375968) (xy 325.802244 -357.375968) (xy 325.829513 -357.376398)
			(xy 325.883497 -357.384165) (xy 325.935825 -357.399535) (xy 325.985433 -357.422196) (xy 326.031312 -357.451685)
			(xy 326.072528 -357.487403) (xy 326.108241 -357.528623) (xy 326.137725 -357.574505) (xy 326.16038 -357.624116)
			(xy 326.175744 -357.676447) (xy 326.183506 -357.73043) (xy 326.183506 -357.784969) (xy 327.666331 -357.784969)
			(xy 327.666331 -357.730431) (xy 327.674093 -357.676448) (xy 327.689458 -357.624119) (xy 327.712114 -357.57451)
			(xy 327.7416 -357.528629) (xy 327.777315 -357.487412) (xy 327.818533 -357.451698) (xy 327.864413 -357.422212)
			(xy 327.914023 -357.399557) (xy 327.966352 -357.384192) (xy 328.020335 -357.376431) (xy 328.047604 -357.375968)
			(xy 328.911204 -357.375968) (xy 328.938475 -357.376395) (xy 328.992463 -357.384158) (xy 329.044796 -357.399524)
			(xy 329.094409 -357.422183) (xy 329.140293 -357.451671) (xy 329.181514 -357.487389) (xy 329.217231 -357.52861)
			(xy 329.246719 -357.574494) (xy 329.269377 -357.624108) (xy 329.284743 -357.676441) (xy 329.292506 -357.730429)
			(xy 329.292506 -357.784966) (xy 330.775354 -357.784966) (xy 330.775354 -357.730434) (xy 330.783114 -357.676458)
			(xy 330.798477 -357.624136) (xy 330.821128 -357.574532) (xy 330.850609 -357.528656) (xy 330.886317 -357.487443)
			(xy 330.927527 -357.45173) (xy 330.9734 -357.422246) (xy 331.023002 -357.399589) (xy 331.075323 -357.384222)
			(xy 331.129298 -357.376457) (xy 331.156564 -357.375968) (xy 332.020164 -357.375968) (xy 332.047439 -357.376369)
			(xy 332.101434 -357.384128) (xy 332.153775 -357.399492) (xy 332.203397 -357.422149) (xy 332.249288 -357.451638)
			(xy 332.290516 -357.487359) (xy 332.32624 -357.528583) (xy 332.355733 -357.574472) (xy 332.378395 -357.624091)
			(xy 332.393765 -357.676431) (xy 332.401528 -357.730425) (xy 332.401528 -357.78497) (xy 333.884231 -357.78497)
			(xy 333.884231 -357.73043) (xy 333.891994 -357.676445) (xy 333.90736 -357.624115) (xy 333.930017 -357.574504)
			(xy 333.959505 -357.528623) (xy 333.995222 -357.487405) (xy 334.036442 -357.451691) (xy 334.082325 -357.422206)
			(xy 334.131937 -357.399552) (xy 334.184269 -357.384189) (xy 334.238254 -357.37643) (xy 334.265524 -357.375968)
			(xy 335.129124 -357.375968) (xy 335.156394 -357.376396) (xy 335.21038 -357.384161) (xy 335.26271 -357.39953)
			(xy 335.312321 -357.422189) (xy 335.358203 -357.451678) (xy 335.399421 -357.487396) (xy 335.435136 -357.528616)
			(xy 335.464622 -357.5745) (xy 335.487279 -357.624112) (xy 335.502644 -357.676444) (xy 335.510406 -357.73043)
			(xy 335.510406 -357.784967) (xy 336.993254 -357.784967) (xy 336.993254 -357.730434) (xy 337.001015 -357.676456)
			(xy 337.016378 -357.624131) (xy 337.039032 -357.574526) (xy 337.068514 -357.52865) (xy 337.104224 -357.487436)
			(xy 337.145437 -357.451723) (xy 337.191312 -357.422239) (xy 337.240916 -357.399584) (xy 337.29324 -357.384218)
			(xy 337.347218 -357.376455) (xy 337.374484 -357.375968) (xy 338.238084 -357.375968) (xy 338.265358 -357.37637)
			(xy 338.319351 -357.384131) (xy 338.371689 -357.399497) (xy 338.421308 -357.422156) (xy 338.467198 -357.451645)
			(xy 338.508423 -357.487366) (xy 338.544145 -357.528589) (xy 338.573636 -357.574477) (xy 338.596297 -357.624096)
			(xy 338.611665 -357.676434) (xy 338.619428 -357.730426) (xy 338.619428 -357.784971) (xy 340.102132 -357.784971)
			(xy 340.102132 -357.730429) (xy 340.109894 -357.676443) (xy 340.125261 -357.624111) (xy 340.147921 -357.574498)
			(xy 340.17741 -357.528616) (xy 340.213129 -357.487398) (xy 340.254351 -357.451684) (xy 340.300237 -357.422199)
			(xy 340.349852 -357.399546) (xy 340.402186 -357.384185) (xy 340.456173 -357.376428) (xy 340.483444 -357.375968)
			(xy 341.347044 -357.375968) (xy 341.374313 -357.376398) (xy 341.428297 -357.384165) (xy 341.480625 -357.399535)
			(xy 341.530233 -357.422196) (xy 341.576112 -357.451685) (xy 341.617328 -357.487403) (xy 341.653041 -357.528623)
			(xy 341.682525 -357.574505) (xy 341.70518 -357.624116) (xy 341.720544 -357.676447) (xy 341.728306 -357.73043)
			(xy 341.728306 -357.784969) (xy 343.211131 -357.784969) (xy 343.211131 -357.730431) (xy 343.218893 -357.676448)
			(xy 343.234258 -357.624119) (xy 343.256914 -357.57451) (xy 343.2864 -357.528629) (xy 343.322115 -357.487412)
			(xy 343.363333 -357.451698) (xy 343.409213 -357.422212) (xy 343.458823 -357.399557) (xy 343.511152 -357.384192)
			(xy 343.565135 -357.376431) (xy 343.592404 -357.375968) (xy 344.456004 -357.375968) (xy 344.483275 -357.376395)
			(xy 344.537263 -357.384158) (xy 344.589596 -357.399524) (xy 344.639209 -357.422183) (xy 344.685093 -357.451671)
			(xy 344.726314 -357.487389) (xy 344.762031 -357.52861) (xy 344.791519 -357.574494) (xy 344.814177 -357.624108)
			(xy 344.829543 -357.676441) (xy 344.837306 -357.730429) (xy 344.837306 -357.784971) (xy 373.915632 -357.784971)
			(xy 373.915632 -357.730429) (xy 373.923394 -357.676443) (xy 373.938761 -357.624111) (xy 373.96142 -357.574499)
			(xy 373.990909 -357.528617) (xy 374.026628 -357.4874) (xy 374.06785 -357.451685) (xy 374.113735 -357.422201)
			(xy 374.163349 -357.399547) (xy 374.215682 -357.384186) (xy 374.269669 -357.376429) (xy 374.29694 -357.375968)
			(xy 375.16054 -357.375968) (xy 375.18781 -357.376397) (xy 375.241793 -357.384164) (xy 375.294122 -357.399534)
			(xy 375.343731 -357.422194) (xy 375.389611 -357.451684) (xy 375.430827 -357.487402) (xy 375.46654 -357.528622)
			(xy 375.496025 -357.574504) (xy 375.51868 -357.624116) (xy 375.534044 -357.676446) (xy 375.541806 -357.73043)
			(xy 375.541806 -357.784967) (xy 377.024654 -357.784967) (xy 377.024654 -357.730433) (xy 377.032415 -357.676453)
			(xy 377.04778 -357.624128) (xy 377.070434 -357.574522) (xy 377.099918 -357.528644) (xy 377.13563 -357.48743)
			(xy 377.176844 -357.451718) (xy 377.222722 -357.422234) (xy 377.272328 -357.39958) (xy 377.324653 -357.384215)
			(xy 377.378633 -357.376454) (xy 377.4059 -357.375968) (xy 378.2695 -357.375968) (xy 378.296772 -357.376395)
			(xy 378.350759 -357.384157) (xy 378.403093 -357.399523) (xy 378.452707 -357.422181) (xy 378.498592 -357.451669)
			(xy 378.539812 -357.487388) (xy 378.575531 -357.528608) (xy 378.605019 -357.574493) (xy 378.627677 -357.624107)
			(xy 378.643043 -357.676441) (xy 378.650805 -357.730428) (xy 378.650805 -357.784965) (xy 380.133654 -357.784965)
			(xy 380.133654 -357.730435) (xy 380.141414 -357.676459) (xy 380.156776 -357.624137) (xy 380.179428 -357.574533)
			(xy 380.208908 -357.528658) (xy 380.244616 -357.487444) (xy 380.285825 -357.451732) (xy 380.331698 -357.422247)
			(xy 380.381299 -357.39959) (xy 380.43362 -357.384223) (xy 380.487595 -357.376457) (xy 380.51486 -357.375968)
			(xy 381.37846 -357.375968) (xy 381.405735 -357.376369) (xy 381.45973 -357.384127) (xy 381.512072 -357.399491)
			(xy 381.561694 -357.422148) (xy 381.607586 -357.451637) (xy 381.648815 -357.487357) (xy 381.684539 -357.528582)
			(xy 381.714033 -357.574471) (xy 381.736695 -357.62409) (xy 381.752065 -357.67643) (xy 381.759828 -357.730425)
			(xy 381.759828 -357.78497) (xy 383.242531 -357.78497) (xy 383.242531 -357.73043) (xy 383.250294 -357.676446)
			(xy 383.26566 -357.624116) (xy 383.288317 -357.574505) (xy 383.317804 -357.528624) (xy 383.353521 -357.487407)
			(xy 383.39474 -357.451692) (xy 383.440623 -357.422207) (xy 383.490234 -357.399553) (xy 383.542565 -357.384189)
			(xy 383.59655 -357.37643) (xy 383.62382 -357.375968) (xy 384.48742 -357.375968) (xy 384.514691 -357.376396)
			(xy 384.568676 -357.38416) (xy 384.621007 -357.399529) (xy 384.670619 -357.422188) (xy 384.716501 -357.451677)
			(xy 384.75772 -357.487395) (xy 384.793435 -357.528615) (xy 384.822922 -357.574499) (xy 384.845578 -357.624111)
			(xy 384.860944 -357.676443) (xy 384.868706 -357.730429) (xy 384.868706 -357.784966) (xy 386.351554 -357.784966)
			(xy 386.351554 -357.730434) (xy 386.359315 -357.676456) (xy 386.374678 -357.624132) (xy 386.397331 -357.574527)
			(xy 386.426813 -357.528651) (xy 386.462523 -357.487437) (xy 386.503735 -357.451725) (xy 386.54961 -357.422241)
			(xy 386.599213 -357.399585) (xy 386.651537 -357.384219) (xy 386.705514 -357.376456) (xy 386.73278 -357.375968)
			(xy 387.59638 -357.375968) (xy 387.623654 -357.37637) (xy 387.677647 -357.384131) (xy 387.729987 -357.399496)
			(xy 387.779606 -357.422155) (xy 387.825496 -357.451644) (xy 387.866722 -357.487364) (xy 387.902444 -357.528588)
			(xy 387.931936 -357.574476) (xy 387.954597 -357.624095) (xy 387.969965 -357.676433) (xy 387.977728 -357.730426)
			(xy 387.977728 -357.784971) (xy 389.460432 -357.784971) (xy 389.460432 -357.730429) (xy 389.468194 -357.676443)
			(xy 389.483561 -357.624111) (xy 389.50622 -357.574499) (xy 389.535709 -357.528617) (xy 389.571428 -357.4874)
			(xy 389.61265 -357.451685) (xy 389.658535 -357.422201) (xy 389.708149 -357.399547) (xy 389.760482 -357.384186)
			(xy 389.814469 -357.376429) (xy 389.84174 -357.375968) (xy 390.70534 -357.375968) (xy 390.73261 -357.376397)
			(xy 390.786593 -357.384164) (xy 390.838922 -357.399534) (xy 390.888531 -357.422194) (xy 390.934411 -357.451684)
			(xy 390.975627 -357.487402) (xy 391.01134 -357.528622) (xy 391.040825 -357.574504) (xy 391.06348 -357.624116)
			(xy 391.078844 -357.676446) (xy 391.086606 -357.73043) (xy 391.086606 -357.784967) (xy 392.569454 -357.784967)
			(xy 392.569454 -357.730433) (xy 392.577215 -357.676453) (xy 392.59258 -357.624128) (xy 392.615234 -357.574522)
			(xy 392.644718 -357.528644) (xy 392.68043 -357.48743) (xy 392.721644 -357.451718) (xy 392.767522 -357.422234)
			(xy 392.817128 -357.39958) (xy 392.869453 -357.384215) (xy 392.923433 -357.376454) (xy 392.9507 -357.375968)
			(xy 393.8143 -357.375968) (xy 393.841572 -357.376395) (xy 393.895559 -357.384157) (xy 393.947893 -357.399523)
			(xy 393.997507 -357.422181) (xy 394.043392 -357.451669) (xy 394.084612 -357.487388) (xy 394.120331 -357.528608)
			(xy 394.149819 -357.574493) (xy 394.172477 -357.624107) (xy 394.187843 -357.676441) (xy 394.195605 -357.730428)
			(xy 394.195605 -357.784965) (xy 395.678454 -357.784965) (xy 395.678454 -357.730435) (xy 395.686214 -357.676459)
			(xy 395.701576 -357.624137) (xy 395.724228 -357.574533) (xy 395.753708 -357.528658) (xy 395.789416 -357.487444)
			(xy 395.830625 -357.451732) (xy 395.876498 -357.422247) (xy 395.926099 -357.39959) (xy 395.97842 -357.384223)
			(xy 396.032395 -357.376457) (xy 396.05966 -357.375968) (xy 396.92326 -357.375968) (xy 396.950535 -357.376369)
			(xy 397.00453 -357.384127) (xy 397.056872 -357.399491) (xy 397.106494 -357.422148) (xy 397.152386 -357.451637)
			(xy 397.193615 -357.487357) (xy 397.229339 -357.528582) (xy 397.258833 -357.574471) (xy 397.281495 -357.62409)
			(xy 397.296865 -357.67643) (xy 397.304628 -357.730425) (xy 397.304628 -357.78497) (xy 398.787331 -357.78497)
			(xy 398.787331 -357.73043) (xy 398.795094 -357.676446) (xy 398.81046 -357.624116) (xy 398.833117 -357.574505)
			(xy 398.862604 -357.528624) (xy 398.898321 -357.487407) (xy 398.93954 -357.451692) (xy 398.985423 -357.422207)
			(xy 399.035034 -357.399553) (xy 399.087365 -357.384189) (xy 399.14135 -357.37643) (xy 399.16862 -357.375968)
			(xy 400.03222 -357.375968) (xy 400.059491 -357.376396) (xy 400.113476 -357.38416) (xy 400.165807 -357.399529)
			(xy 400.215419 -357.422188) (xy 400.261301 -357.451677) (xy 400.30252 -357.487395) (xy 400.338235 -357.528615)
			(xy 400.367722 -357.574499) (xy 400.390378 -357.624111) (xy 400.405744 -357.676443) (xy 400.413506 -357.730429)
			(xy 400.413506 -357.784966) (xy 401.896354 -357.784966) (xy 401.896354 -357.730434) (xy 401.904115 -357.676456)
			(xy 401.919478 -357.624132) (xy 401.942131 -357.574527) (xy 401.971613 -357.528651) (xy 402.007323 -357.487437)
			(xy 402.048535 -357.451725) (xy 402.09441 -357.422241) (xy 402.144013 -357.399585) (xy 402.196337 -357.384219)
			(xy 402.250314 -357.376456) (xy 402.27758 -357.375968) (xy 403.14118 -357.375968) (xy 403.168454 -357.37637)
			(xy 403.222447 -357.384131) (xy 403.274787 -357.399496) (xy 403.324406 -357.422155) (xy 403.370296 -357.451644)
			(xy 403.411522 -357.487364) (xy 403.447244 -357.528588) (xy 403.476736 -357.574476) (xy 403.499397 -357.624095)
			(xy 403.514765 -357.676433) (xy 403.522528 -357.730426) (xy 403.522528 -357.784974) (xy 403.514765 -357.838967)
			(xy 403.499397 -357.891305) (xy 403.476736 -357.940924) (xy 403.447244 -357.986812) (xy 403.411522 -358.028036)
			(xy 403.370296 -358.063756) (xy 403.324406 -358.093245) (xy 403.274787 -358.115904) (xy 403.222447 -358.131269)
			(xy 403.168454 -358.13903) (xy 403.14118 -358.139492) (xy 402.27758 -358.139492) (xy 402.250314 -358.138944)
			(xy 402.196337 -358.131181) (xy 402.144013 -358.115815) (xy 402.09441 -358.093159) (xy 402.048535 -358.063675)
			(xy 402.007323 -358.027963) (xy 401.971613 -357.986749) (xy 401.942131 -357.940873) (xy 401.919478 -357.891268)
			(xy 401.904115 -357.838944) (xy 401.896354 -357.784966) (xy 400.413506 -357.784966) (xy 400.413506 -357.784971)
			(xy 400.405744 -357.838957) (xy 400.390378 -357.891289) (xy 400.367722 -357.940901) (xy 400.338235 -357.986785)
			(xy 400.30252 -358.028005) (xy 400.261301 -358.063723) (xy 400.215419 -358.093212) (xy 400.165807 -358.115871)
			(xy 400.113476 -358.13124) (xy 400.059491 -358.139004) (xy 400.03222 -358.139492) (xy 399.16862 -358.139492)
			(xy 399.14135 -358.13897) (xy 399.087365 -358.131211) (xy 399.035034 -358.115847) (xy 398.985423 -358.093193)
			(xy 398.93954 -358.063708) (xy 398.898321 -358.027993) (xy 398.862604 -357.986776) (xy 398.833117 -357.940895)
			(xy 398.81046 -357.891284) (xy 398.795094 -357.838954) (xy 398.787331 -357.78497) (xy 397.304628 -357.78497)
			(xy 397.304628 -357.784975) (xy 397.296865 -357.83897) (xy 397.281495 -357.89131) (xy 397.258833 -357.940929)
			(xy 397.229339 -357.986818) (xy 397.193615 -358.028043) (xy 397.152386 -358.063763) (xy 397.106494 -358.093252)
			(xy 397.056872 -358.115909) (xy 397.00453 -358.131273) (xy 396.950535 -358.139031) (xy 396.92326 -358.139492)
			(xy 396.05966 -358.139492) (xy 396.032395 -358.138943) (xy 395.97842 -358.131177) (xy 395.926099 -358.11581)
			(xy 395.876498 -358.093153) (xy 395.830625 -358.063668) (xy 395.789416 -358.027956) (xy 395.753708 -357.986742)
			(xy 395.724228 -357.940867) (xy 395.701576 -357.891263) (xy 395.686214 -357.838941) (xy 395.678454 -357.784965)
			(xy 394.195605 -357.784965) (xy 394.195605 -357.784972) (xy 394.187843 -357.838959) (xy 394.172477 -357.891293)
			(xy 394.149819 -357.940907) (xy 394.120331 -357.986792) (xy 394.084612 -358.028012) (xy 394.043392 -358.063731)
			(xy 393.997507 -358.093219) (xy 393.947893 -358.115877) (xy 393.895559 -358.131243) (xy 393.841572 -358.139005)
			(xy 393.8143 -358.139492) (xy 392.9507 -358.139492) (xy 392.923433 -358.138946) (xy 392.869453 -358.131185)
			(xy 392.817128 -358.11582) (xy 392.767522 -358.093166) (xy 392.721644 -358.063682) (xy 392.68043 -358.02797)
			(xy 392.644718 -357.986756) (xy 392.615234 -357.940878) (xy 392.59258 -357.891272) (xy 392.577215 -357.838947)
			(xy 392.569454 -357.784967) (xy 391.086606 -357.784967) (xy 391.086606 -357.78497) (xy 391.078844 -357.838954)
			(xy 391.06348 -357.891284) (xy 391.040825 -357.940896) (xy 391.01134 -357.986778) (xy 390.975627 -358.027998)
			(xy 390.934411 -358.063716) (xy 390.888531 -358.093206) (xy 390.838922 -358.115866) (xy 390.786593 -358.131236)
			(xy 390.73261 -358.139003) (xy 390.70534 -358.139492) (xy 389.84174 -358.139492) (xy 389.814469 -358.138971)
			(xy 389.760482 -358.131214) (xy 389.708149 -358.115853) (xy 389.658535 -358.093199) (xy 389.61265 -358.063715)
			(xy 389.571428 -358.028) (xy 389.535709 -357.986783) (xy 389.50622 -357.940901) (xy 389.483561 -357.891289)
			(xy 389.468194 -357.838957) (xy 389.460432 -357.784971) (xy 387.977728 -357.784971) (xy 387.977728 -357.784974)
			(xy 387.969965 -357.838967) (xy 387.954597 -357.891305) (xy 387.931936 -357.940924) (xy 387.902444 -357.986812)
			(xy 387.866722 -358.028036) (xy 387.825496 -358.063756) (xy 387.779606 -358.093245) (xy 387.729987 -358.115904)
			(xy 387.677647 -358.131269) (xy 387.623654 -358.13903) (xy 387.59638 -358.139492) (xy 386.73278 -358.139492)
			(xy 386.705514 -358.138944) (xy 386.651537 -358.131181) (xy 386.599213 -358.115815) (xy 386.54961 -358.093159)
			(xy 386.503735 -358.063675) (xy 386.462523 -358.027963) (xy 386.426813 -357.986749) (xy 386.397331 -357.940873)
			(xy 386.374678 -357.891268) (xy 386.359315 -357.838944) (xy 386.351554 -357.784966) (xy 384.868706 -357.784966)
			(xy 384.868706 -357.784971) (xy 384.860944 -357.838957) (xy 384.845578 -357.891289) (xy 384.822922 -357.940901)
			(xy 384.793435 -357.986785) (xy 384.75772 -358.028005) (xy 384.716501 -358.063723) (xy 384.670619 -358.093212)
			(xy 384.621007 -358.115871) (xy 384.568676 -358.13124) (xy 384.514691 -358.139004) (xy 384.48742 -358.139492)
			(xy 383.62382 -358.139492) (xy 383.59655 -358.13897) (xy 383.542565 -358.131211) (xy 383.490234 -358.115847)
			(xy 383.440623 -358.093193) (xy 383.39474 -358.063708) (xy 383.353521 -358.027993) (xy 383.317804 -357.986776)
			(xy 383.288317 -357.940895) (xy 383.26566 -357.891284) (xy 383.250294 -357.838954) (xy 383.242531 -357.78497)
			(xy 381.759828 -357.78497) (xy 381.759828 -357.784975) (xy 381.752065 -357.83897) (xy 381.736695 -357.89131)
			(xy 381.714033 -357.940929) (xy 381.684539 -357.986818) (xy 381.648815 -358.028043) (xy 381.607586 -358.063763)
			(xy 381.561694 -358.093252) (xy 381.512072 -358.115909) (xy 381.45973 -358.131273) (xy 381.405735 -358.139031)
			(xy 381.37846 -358.139492) (xy 380.51486 -358.139492) (xy 380.487595 -358.138943) (xy 380.43362 -358.131177)
			(xy 380.381299 -358.11581) (xy 380.331698 -358.093153) (xy 380.285825 -358.063668) (xy 380.244616 -358.027956)
			(xy 380.208908 -357.986742) (xy 380.179428 -357.940867) (xy 380.156776 -357.891263) (xy 380.141414 -357.838941)
			(xy 380.133654 -357.784965) (xy 378.650805 -357.784965) (xy 378.650805 -357.784972) (xy 378.643043 -357.838959)
			(xy 378.627677 -357.891293) (xy 378.605019 -357.940907) (xy 378.575531 -357.986792) (xy 378.539812 -358.028012)
			(xy 378.498592 -358.063731) (xy 378.452707 -358.093219) (xy 378.403093 -358.115877) (xy 378.350759 -358.131243)
			(xy 378.296772 -358.139005) (xy 378.2695 -358.139492) (xy 377.4059 -358.139492) (xy 377.378633 -358.138946)
			(xy 377.324653 -358.131185) (xy 377.272328 -358.11582) (xy 377.222722 -358.093166) (xy 377.176844 -358.063682)
			(xy 377.13563 -358.02797) (xy 377.099918 -357.986756) (xy 377.070434 -357.940878) (xy 377.04778 -357.891272)
			(xy 377.032415 -357.838947) (xy 377.024654 -357.784967) (xy 375.541806 -357.784967) (xy 375.541806 -357.78497)
			(xy 375.534044 -357.838954) (xy 375.51868 -357.891284) (xy 375.496025 -357.940896) (xy 375.46654 -357.986778)
			(xy 375.430827 -358.027998) (xy 375.389611 -358.063716) (xy 375.343731 -358.093206) (xy 375.294122 -358.115866)
			(xy 375.241793 -358.131236) (xy 375.18781 -358.139003) (xy 375.16054 -358.139492) (xy 374.29694 -358.139492)
			(xy 374.269669 -358.138971) (xy 374.215682 -358.131214) (xy 374.163349 -358.115853) (xy 374.113735 -358.093199)
			(xy 374.06785 -358.063715) (xy 374.026628 -358.028) (xy 373.990909 -357.986783) (xy 373.96142 -357.940901)
			(xy 373.938761 -357.891289) (xy 373.923394 -357.838957) (xy 373.915632 -357.784971) (xy 344.837306 -357.784971)
			(xy 344.829543 -357.838959) (xy 344.814177 -357.891292) (xy 344.791519 -357.940906) (xy 344.762031 -357.98679)
			(xy 344.726314 -358.028011) (xy 344.685093 -358.063729) (xy 344.639209 -358.093217) (xy 344.589596 -358.115876)
			(xy 344.537263 -358.131242) (xy 344.483275 -358.139005) (xy 344.456004 -358.139492) (xy 343.592404 -358.139492)
			(xy 343.565135 -358.138969) (xy 343.511152 -358.131208) (xy 343.458823 -358.115843) (xy 343.409213 -358.093188)
			(xy 343.363333 -358.063702) (xy 343.322115 -358.027988) (xy 343.2864 -357.986771) (xy 343.256914 -357.94089)
			(xy 343.234258 -357.891281) (xy 343.218893 -357.838952) (xy 343.211131 -357.784969) (xy 341.728306 -357.784969)
			(xy 341.728306 -357.78497) (xy 341.720544 -357.838953) (xy 341.70518 -357.891284) (xy 341.682525 -357.940895)
			(xy 341.653041 -357.986777) (xy 341.617328 -358.027997) (xy 341.576112 -358.063715) (xy 341.530233 -358.093204)
			(xy 341.480625 -358.115865) (xy 341.428297 -358.131235) (xy 341.374313 -358.139002) (xy 341.347044 -358.139492)
			(xy 340.483444 -358.139492) (xy 340.456173 -358.138972) (xy 340.402186 -358.131215) (xy 340.349852 -358.115854)
			(xy 340.300237 -358.093201) (xy 340.254351 -358.063716) (xy 340.213129 -358.028002) (xy 340.17741 -357.986784)
			(xy 340.147921 -357.940902) (xy 340.125261 -357.891289) (xy 340.109894 -357.838957) (xy 340.102132 -357.784971)
			(xy 338.619428 -357.784971) (xy 338.619428 -357.784974) (xy 338.611665 -357.838966) (xy 338.596297 -357.891304)
			(xy 338.573636 -357.940923) (xy 338.544145 -357.986811) (xy 338.508423 -358.028034) (xy 338.467198 -358.063755)
			(xy 338.421308 -358.093244) (xy 338.371689 -358.115903) (xy 338.319351 -358.131269) (xy 338.265358 -358.13903)
			(xy 338.238084 -358.139492) (xy 337.374484 -358.139492) (xy 337.347218 -358.138945) (xy 337.29324 -358.131182)
			(xy 337.240916 -358.115816) (xy 337.191312 -358.093161) (xy 337.145437 -358.063677) (xy 337.104224 -358.027964)
			(xy 337.068514 -357.98675) (xy 337.039032 -357.940874) (xy 337.016378 -357.891269) (xy 337.001015 -357.838944)
			(xy 336.993254 -357.784967) (xy 335.510406 -357.784967) (xy 335.510406 -357.78497) (xy 335.502644 -357.838956)
			(xy 335.487279 -357.891288) (xy 335.464622 -357.9409) (xy 335.435136 -357.986784) (xy 335.399421 -358.028004)
			(xy 335.358203 -358.063722) (xy 335.312321 -358.093211) (xy 335.26271 -358.11587) (xy 335.21038 -358.131239)
			(xy 335.156394 -358.139004) (xy 335.129124 -358.139492) (xy 334.265524 -358.139492) (xy 334.238254 -358.13897)
			(xy 334.184269 -358.131211) (xy 334.131937 -358.115848) (xy 334.082325 -358.093194) (xy 334.036442 -358.063709)
			(xy 333.995222 -358.027995) (xy 333.959505 -357.986777) (xy 333.930017 -357.940896) (xy 333.90736 -357.891285)
			(xy 333.891994 -357.838955) (xy 333.884231 -357.78497) (xy 332.401528 -357.78497) (xy 332.401528 -357.784975)
			(xy 332.393765 -357.838969) (xy 332.378395 -357.891309) (xy 332.355733 -357.940928) (xy 332.32624 -357.986817)
			(xy 332.290516 -358.028041) (xy 332.249288 -358.063762) (xy 332.203397 -358.093251) (xy 332.153775 -358.115908)
			(xy 332.101434 -358.131272) (xy 332.047439 -358.139031) (xy 332.020164 -358.139492) (xy 331.156564 -358.139492)
			(xy 331.129298 -358.138943) (xy 331.075323 -358.131178) (xy 331.023002 -358.115811) (xy 330.9734 -358.093154)
			(xy 330.927527 -358.06367) (xy 330.886317 -358.027957) (xy 330.850609 -357.986744) (xy 330.821128 -357.940868)
			(xy 330.798477 -357.891264) (xy 330.783114 -357.838942) (xy 330.775354 -357.784966) (xy 329.292506 -357.784966)
			(xy 329.292506 -357.784971) (xy 329.284743 -357.838959) (xy 329.269377 -357.891292) (xy 329.246719 -357.940906)
			(xy 329.217231 -357.98679) (xy 329.181514 -358.028011) (xy 329.140293 -358.063729) (xy 329.094409 -358.093217)
			(xy 329.044796 -358.115876) (xy 328.992463 -358.131242) (xy 328.938475 -358.139005) (xy 328.911204 -358.139492)
			(xy 328.047604 -358.139492) (xy 328.020335 -358.138969) (xy 327.966352 -358.131208) (xy 327.914023 -358.115843)
			(xy 327.864413 -358.093188) (xy 327.818533 -358.063702) (xy 327.777315 -358.027988) (xy 327.7416 -357.986771)
			(xy 327.712114 -357.94089) (xy 327.689458 -357.891281) (xy 327.674093 -357.838952) (xy 327.666331 -357.784969)
			(xy 326.183506 -357.784969) (xy 326.183506 -357.78497) (xy 326.175744 -357.838953) (xy 326.16038 -357.891284)
			(xy 326.137725 -357.940895) (xy 326.108241 -357.986777) (xy 326.072528 -358.027997) (xy 326.031312 -358.063715)
			(xy 325.985433 -358.093204) (xy 325.935825 -358.115865) (xy 325.883497 -358.131235) (xy 325.829513 -358.139002)
			(xy 325.802244 -358.139492) (xy 324.938644 -358.139492) (xy 324.911373 -358.138972) (xy 324.857386 -358.131215)
			(xy 324.805052 -358.115854) (xy 324.755437 -358.093201) (xy 324.709551 -358.063716) (xy 324.668329 -358.028002)
			(xy 324.63261 -357.986784) (xy 324.603121 -357.940902) (xy 324.580461 -357.891289) (xy 324.565094 -357.838957)
			(xy 324.557332 -357.784971) (xy 323.074628 -357.784971) (xy 323.074628 -357.784974) (xy 323.066865 -357.838966)
			(xy 323.051497 -357.891304) (xy 323.028836 -357.940923) (xy 322.999345 -357.986811) (xy 322.963623 -358.028034)
			(xy 322.922398 -358.063755) (xy 322.876508 -358.093244) (xy 322.826889 -358.115903) (xy 322.774551 -358.131269)
			(xy 322.720558 -358.13903) (xy 322.693284 -358.139492) (xy 321.829684 -358.139492) (xy 321.802418 -358.138945)
			(xy 321.74844 -358.131182) (xy 321.696116 -358.115816) (xy 321.646512 -358.093161) (xy 321.600637 -358.063677)
			(xy 321.559424 -358.027964) (xy 321.523714 -357.98675) (xy 321.494232 -357.940874) (xy 321.471578 -357.891269)
			(xy 321.456215 -357.838944) (xy 321.448454 -357.784967) (xy 319.965606 -357.784967) (xy 319.965606 -357.78497)
			(xy 319.957844 -357.838956) (xy 319.942479 -357.891288) (xy 319.919822 -357.9409) (xy 319.890336 -357.986784)
			(xy 319.854621 -358.028004) (xy 319.813403 -358.063722) (xy 319.767521 -358.093211) (xy 319.71791 -358.11587)
			(xy 319.66558 -358.131239) (xy 319.611594 -358.139004) (xy 319.584324 -358.139492) (xy 318.720724 -358.139492)
			(xy 318.693454 -358.13897) (xy 318.639469 -358.131211) (xy 318.587137 -358.115848) (xy 318.537525 -358.093194)
			(xy 318.491642 -358.063709) (xy 318.450422 -358.027995) (xy 318.414705 -357.986777) (xy 318.385217 -357.940896)
			(xy 318.36256 -357.891285) (xy 318.347194 -357.838955) (xy 318.339431 -357.78497) (xy 316.856728 -357.78497)
			(xy 316.856728 -357.784975) (xy 316.848965 -357.838969) (xy 316.833595 -357.891309) (xy 316.810933 -357.940928)
			(xy 316.78144 -357.986817) (xy 316.745716 -358.028041) (xy 316.704488 -358.063762) (xy 316.658597 -358.093251)
			(xy 316.608975 -358.115908) (xy 316.556634 -358.131272) (xy 316.502639 -358.139031) (xy 316.475364 -358.139492)
			(xy 315.611764 -358.139492) (xy 315.584498 -358.138943) (xy 315.530523 -358.131178) (xy 315.478202 -358.115811)
			(xy 315.4286 -358.093154) (xy 315.382727 -358.06367) (xy 315.341517 -358.027957) (xy 315.305809 -357.986744)
			(xy 315.276328 -357.940868) (xy 315.253677 -357.891264) (xy 315.238314 -357.838942) (xy 315.230554 -357.784966)
			(xy 309.717694 -357.784966) (xy 309.717694 -359.3084) (xy 363.411514 -359.3084) (xy 363.415585 -359.252778)
			(xy 363.427711 -359.198341) (xy 363.447634 -359.14625) (xy 363.47493 -359.097615) (xy 363.509016 -359.053472)
			(xy 363.549165 -359.014763) (xy 363.594523 -358.982312) (xy 363.644123 -358.956811) (xy 363.696907 -358.938804)
			(xy 363.75175 -358.928674) (xy 363.807484 -358.926637) (xy 363.862921 -358.932737) (xy 363.916878 -358.946843)
			(xy 363.968207 -358.968655) (xy 364.015813 -358.997709) (xy 364.058681 -359.033384) (xy 364.095898 -359.074921)
			(xy 364.126671 -359.121434) (xy 364.150343 -359.171931) (xy 364.166411 -359.225338) (xy 364.174531 -359.280514)
			(xy 364.17504 -359.3084) (xy 365.189514 -359.3084) (xy 365.193585 -359.252778) (xy 365.205711 -359.198341)
			(xy 365.225634 -359.14625) (xy 365.25293 -359.097615) (xy 365.287016 -359.053472) (xy 365.327165 -359.014763)
			(xy 365.372523 -358.982312) (xy 365.422123 -358.956811) (xy 365.474907 -358.938804) (xy 365.52975 -358.928674)
			(xy 365.585484 -358.926637) (xy 365.640921 -358.932737) (xy 365.694878 -358.946843) (xy 365.746207 -358.968655)
			(xy 365.793813 -358.997709) (xy 365.836681 -359.033384) (xy 365.873898 -359.074921) (xy 365.904671 -359.121434)
			(xy 365.928343 -359.171931) (xy 365.944411 -359.225338) (xy 365.952531 -359.280514) (xy 365.95304 -359.3084)
			(xy 365.952531 -359.336286) (xy 365.944411 -359.391462) (xy 365.928343 -359.444869) (xy 365.904671 -359.495366)
			(xy 365.873898 -359.541879) (xy 365.836681 -359.583416) (xy 365.793813 -359.619091) (xy 365.746207 -359.648145)
			(xy 365.694878 -359.669957) (xy 365.640921 -359.684063) (xy 365.585484 -359.690163) (xy 365.52975 -359.688126)
			(xy 365.474907 -359.677996) (xy 365.422123 -359.659989) (xy 365.372523 -359.634488) (xy 365.327165 -359.602037)
			(xy 365.287016 -359.563328) (xy 365.25293 -359.519185) (xy 365.225634 -359.47055) (xy 365.205711 -359.418459)
			(xy 365.193585 -359.364022) (xy 365.189514 -359.3084) (xy 364.17504 -359.3084) (xy 364.174531 -359.336286)
			(xy 364.166411 -359.391462) (xy 364.150343 -359.444869) (xy 364.126671 -359.495366) (xy 364.095898 -359.541879)
			(xy 364.058681 -359.583416) (xy 364.015813 -359.619091) (xy 363.968207 -359.648145) (xy 363.916878 -359.669957)
			(xy 363.862921 -359.684063) (xy 363.807484 -359.690163) (xy 363.75175 -359.688126) (xy 363.696907 -359.677996)
			(xy 363.644123 -359.659989) (xy 363.594523 -359.634488) (xy 363.549165 -359.602037) (xy 363.509016 -359.563328)
			(xy 363.47493 -359.519185) (xy 363.447634 -359.47055) (xy 363.427711 -359.418459) (xy 363.415585 -359.364022)
			(xy 363.411514 -359.3084) (xy 309.717694 -359.3084) (xy 309.717694 -362.45165) (xy 357.205532 -362.45165)
			(xy 357.209603 -362.396028) (xy 357.221729 -362.341591) (xy 357.241652 -362.2895) (xy 357.268948 -362.240865)
			(xy 357.303034 -362.196722) (xy 357.343183 -362.158013) (xy 357.388541 -362.125562) (xy 357.438141 -362.100061)
			(xy 357.490925 -362.082054) (xy 357.545768 -362.071924) (xy 357.601502 -362.069887) (xy 357.656939 -362.075987)
			(xy 357.710896 -362.090093) (xy 357.762225 -362.111905) (xy 357.809831 -362.140959) (xy 357.852699 -362.176634)
			(xy 357.889916 -362.218171) (xy 357.920689 -362.264684) (xy 357.944361 -362.315181) (xy 357.960429 -362.368588)
			(xy 357.968549 -362.423764) (xy 357.969058 -362.45165) (xy 357.968549 -362.479536) (xy 357.960429 -362.534712)
			(xy 357.944361 -362.588119) (xy 357.920689 -362.638616) (xy 357.889916 -362.685129) (xy 357.852699 -362.726666)
			(xy 357.809831 -362.762341) (xy 357.762225 -362.791395) (xy 357.710896 -362.813207) (xy 357.656939 -362.827313)
			(xy 357.601502 -362.833413) (xy 357.545768 -362.831376) (xy 357.490925 -362.821246) (xy 357.438141 -362.803239)
			(xy 357.388541 -362.777738) (xy 357.343183 -362.745287) (xy 357.303034 -362.706578) (xy 357.268948 -362.662435)
			(xy 357.241652 -362.6138) (xy 357.221729 -362.561709) (xy 357.209603 -362.507272) (xy 357.205532 -362.45165)
			(xy 309.717694 -362.45165) (xy 309.717694 -367.407952) (xy 405.214326 -367.407952) (xy 405.218397 -367.35233)
			(xy 405.230523 -367.297893) (xy 405.250446 -367.245802) (xy 405.277742 -367.197167) (xy 405.311828 -367.153024)
			(xy 405.351977 -367.114315) (xy 405.397335 -367.081864) (xy 405.446935 -367.056363) (xy 405.499719 -367.038356)
			(xy 405.554562 -367.028226) (xy 405.610296 -367.026189) (xy 405.665733 -367.032289) (xy 405.71969 -367.046395)
			(xy 405.771019 -367.068207) (xy 405.818625 -367.097261) (xy 405.861493 -367.132936) (xy 405.89871 -367.174473)
			(xy 405.929483 -367.220986) (xy 405.953155 -367.271483) (xy 405.969223 -367.32489) (xy 405.977343 -367.380066)
			(xy 405.977852 -367.407952) (xy 405.977343 -367.435838) (xy 405.969223 -367.491014) (xy 405.953155 -367.544421)
			(xy 405.929483 -367.594918) (xy 405.89871 -367.641431) (xy 405.861493 -367.682968) (xy 405.818625 -367.718643)
			(xy 405.771019 -367.747697) (xy 405.71969 -367.769509) (xy 405.665733 -367.783615) (xy 405.610296 -367.789715)
			(xy 405.554562 -367.787678) (xy 405.499719 -367.777548) (xy 405.446935 -367.759541) (xy 405.397335 -367.73404)
			(xy 405.351977 -367.701589) (xy 405.311828 -367.66288) (xy 405.277742 -367.618737) (xy 405.250446 -367.570102)
			(xy 405.230523 -367.518011) (xy 405.218397 -367.463574) (xy 405.214326 -367.407952) (xy 309.717694 -367.407952)
			(xy 309.717694 -368.990118) (xy 333.203812 -368.990118) (xy 333.207803 -368.927951) (xy 333.219712 -368.866804)
			(xy 333.239341 -368.807683) (xy 333.26637 -368.751557) (xy 333.300354 -368.699348) (xy 333.340736 -368.651913)
			(xy 333.386852 -368.610032) (xy 333.437944 -368.574392) (xy 333.493175 -368.545578) (xy 333.551637 -368.524064)
			(xy 333.612371 -368.510202) (xy 333.674378 -368.50422) (xy 333.736641 -368.506216) (xy 333.798138 -368.516159)
			(xy 333.857859 -368.533883) (xy 333.914822 -368.5591) (xy 333.968093 -368.591393) (xy 334.016798 -368.630233)
			(xy 334.060135 -368.674983) (xy 334.097395 -368.724907) (xy 334.127964 -368.779186) (xy 334.151342 -368.836929)
			(xy 334.167143 -368.897187) (xy 334.175109 -368.95897) (xy 334.175608 -368.990118) (xy 337.603854 -368.990118)
			(xy 337.607845 -368.927951) (xy 337.619754 -368.866804) (xy 337.639383 -368.807683) (xy 337.666412 -368.751557)
			(xy 337.700396 -368.699348) (xy 337.740778 -368.651913) (xy 337.786894 -368.610032) (xy 337.837986 -368.574392)
			(xy 337.893217 -368.545578) (xy 337.951679 -368.524064) (xy 338.012413 -368.510202) (xy 338.07442 -368.50422)
			(xy 338.136683 -368.506216) (xy 338.19818 -368.516159) (xy 338.257901 -368.533883) (xy 338.314864 -368.5591)
			(xy 338.368135 -368.591393) (xy 338.41684 -368.630233) (xy 338.460177 -368.674983) (xy 338.497437 -368.724907)
			(xy 338.528006 -368.779186) (xy 338.551384 -368.836929) (xy 338.567185 -368.897187) (xy 338.575151 -368.95897)
			(xy 338.57565 -368.990118) (xy 342.003896 -368.990118) (xy 342.007887 -368.927951) (xy 342.019796 -368.866804)
			(xy 342.039425 -368.807683) (xy 342.066454 -368.751557) (xy 342.100438 -368.699348) (xy 342.14082 -368.651913)
			(xy 342.186936 -368.610032) (xy 342.238028 -368.574392) (xy 342.293259 -368.545578) (xy 342.351721 -368.524064)
			(xy 342.412455 -368.510202) (xy 342.474462 -368.50422) (xy 342.536725 -368.506216) (xy 342.598222 -368.516159)
			(xy 342.657943 -368.533883) (xy 342.714906 -368.5591) (xy 342.768177 -368.591393) (xy 342.816882 -368.630233)
			(xy 342.860219 -368.674983) (xy 342.897479 -368.724907) (xy 342.928048 -368.779186) (xy 342.951426 -368.836929)
			(xy 342.967227 -368.897187) (xy 342.975193 -368.95897) (xy 342.975692 -368.990118) (xy 346.403938 -368.990118)
			(xy 346.407929 -368.927951) (xy 346.419838 -368.866804) (xy 346.439467 -368.807683) (xy 346.466496 -368.751557)
			(xy 346.50048 -368.699348) (xy 346.540862 -368.651913) (xy 346.586978 -368.610032) (xy 346.63807 -368.574392)
			(xy 346.693301 -368.545578) (xy 346.751763 -368.524064) (xy 346.812497 -368.510202) (xy 346.874504 -368.50422)
			(xy 346.936767 -368.506216) (xy 346.998264 -368.516159) (xy 347.057985 -368.533883) (xy 347.114948 -368.5591)
			(xy 347.168219 -368.591393) (xy 347.216924 -368.630233) (xy 347.260261 -368.674983) (xy 347.297521 -368.724907)
			(xy 347.32809 -368.779186) (xy 347.351468 -368.836929) (xy 347.367269 -368.897187) (xy 347.375235 -368.95897)
			(xy 347.375734 -368.990118) (xy 350.80398 -368.990118) (xy 350.807971 -368.927951) (xy 350.81988 -368.866804)
			(xy 350.839509 -368.807683) (xy 350.866538 -368.751557) (xy 350.900522 -368.699348) (xy 350.940904 -368.651913)
			(xy 350.98702 -368.610032) (xy 351.038112 -368.574392) (xy 351.093343 -368.545578) (xy 351.151805 -368.524064)
			(xy 351.212539 -368.510202) (xy 351.274546 -368.50422) (xy 351.336809 -368.506216) (xy 351.398306 -368.516159)
			(xy 351.458027 -368.533883) (xy 351.51499 -368.5591) (xy 351.568261 -368.591393) (xy 351.616966 -368.630233)
			(xy 351.660303 -368.674983) (xy 351.697563 -368.724907) (xy 351.728132 -368.779186) (xy 351.75151 -368.836929)
			(xy 351.767311 -368.897187) (xy 351.775277 -368.95897) (xy 351.775776 -368.990118) (xy 377.203724 -368.990118)
			(xy 377.207715 -368.927951) (xy 377.219624 -368.866804) (xy 377.239253 -368.807683) (xy 377.266282 -368.751557)
			(xy 377.300266 -368.699348) (xy 377.340648 -368.651913) (xy 377.386764 -368.610032) (xy 377.437856 -368.574392)
			(xy 377.493087 -368.545578) (xy 377.551549 -368.524064) (xy 377.612283 -368.510202) (xy 377.67429 -368.50422)
			(xy 377.736553 -368.506216) (xy 377.79805 -368.516159) (xy 377.857771 -368.533883) (xy 377.914734 -368.5591)
			(xy 377.968005 -368.591393) (xy 378.01671 -368.630233) (xy 378.060047 -368.674983) (xy 378.097307 -368.724907)
			(xy 378.127876 -368.779186) (xy 378.151254 -368.836929) (xy 378.167055 -368.897187) (xy 378.175021 -368.95897)
			(xy 378.17552 -368.990118) (xy 381.603766 -368.990118) (xy 381.607757 -368.927951) (xy 381.619666 -368.866804)
			(xy 381.639295 -368.807683) (xy 381.666324 -368.751557) (xy 381.700308 -368.699348) (xy 381.74069 -368.651913)
			(xy 381.786806 -368.610032) (xy 381.837898 -368.574392) (xy 381.893129 -368.545578) (xy 381.951591 -368.524064)
			(xy 382.012325 -368.510202) (xy 382.074332 -368.50422) (xy 382.136595 -368.506216) (xy 382.198092 -368.516159)
			(xy 382.257813 -368.533883) (xy 382.314776 -368.5591) (xy 382.368047 -368.591393) (xy 382.416752 -368.630233)
			(xy 382.460089 -368.674983) (xy 382.497349 -368.724907) (xy 382.527918 -368.779186) (xy 382.551296 -368.836929)
			(xy 382.567097 -368.897187) (xy 382.575063 -368.95897) (xy 382.575562 -368.990118) (xy 386.003808 -368.990118)
			(xy 386.007799 -368.927951) (xy 386.019708 -368.866804) (xy 386.039337 -368.807683) (xy 386.066366 -368.751557)
			(xy 386.10035 -368.699348) (xy 386.140732 -368.651913) (xy 386.186848 -368.610032) (xy 386.23794 -368.574392)
			(xy 386.293171 -368.545578) (xy 386.351633 -368.524064) (xy 386.412367 -368.510202) (xy 386.474374 -368.50422)
			(xy 386.536637 -368.506216) (xy 386.598134 -368.516159) (xy 386.657855 -368.533883) (xy 386.714818 -368.5591)
			(xy 386.768089 -368.591393) (xy 386.816794 -368.630233) (xy 386.860131 -368.674983) (xy 386.897391 -368.724907)
			(xy 386.92796 -368.779186) (xy 386.951338 -368.836929) (xy 386.967139 -368.897187) (xy 386.975105 -368.95897)
			(xy 386.975604 -368.990118) (xy 390.40385 -368.990118) (xy 390.407841 -368.927951) (xy 390.41975 -368.866804)
			(xy 390.439379 -368.807683) (xy 390.466408 -368.751557) (xy 390.500392 -368.699348) (xy 390.540774 -368.651913)
			(xy 390.58689 -368.610032) (xy 390.637982 -368.574392) (xy 390.693213 -368.545578) (xy 390.751675 -368.524064)
			(xy 390.812409 -368.510202) (xy 390.874416 -368.50422) (xy 390.936679 -368.506216) (xy 390.998176 -368.516159)
			(xy 391.057897 -368.533883) (xy 391.11486 -368.5591) (xy 391.168131 -368.591393) (xy 391.216836 -368.630233)
			(xy 391.260173 -368.674983) (xy 391.297433 -368.724907) (xy 391.328002 -368.779186) (xy 391.35138 -368.836929)
			(xy 391.367181 -368.897187) (xy 391.375147 -368.95897) (xy 391.375646 -368.990118) (xy 394.803892 -368.990118)
			(xy 394.807883 -368.927951) (xy 394.819792 -368.866804) (xy 394.839421 -368.807683) (xy 394.86645 -368.751557)
			(xy 394.900434 -368.699348) (xy 394.940816 -368.651913) (xy 394.986932 -368.610032) (xy 395.038024 -368.574392)
			(xy 395.093255 -368.545578) (xy 395.151717 -368.524064) (xy 395.212451 -368.510202) (xy 395.274458 -368.50422)
			(xy 395.336721 -368.506216) (xy 395.398218 -368.516159) (xy 395.457939 -368.533883) (xy 395.514902 -368.5591)
			(xy 395.568173 -368.591393) (xy 395.616878 -368.630233) (xy 395.660215 -368.674983) (xy 395.697475 -368.724907)
			(xy 395.728044 -368.779186) (xy 395.751422 -368.836929) (xy 395.767223 -368.897187) (xy 395.775189 -368.95897)
			(xy 395.775688 -368.990118) (xy 395.775189 -369.021266) (xy 395.767223 -369.083049) (xy 395.751422 -369.143307)
			(xy 395.728044 -369.20105) (xy 395.697475 -369.255329) (xy 395.660215 -369.305253) (xy 395.616878 -369.350003)
			(xy 395.568173 -369.388843) (xy 395.514902 -369.421136) (xy 395.457939 -369.446353) (xy 395.398218 -369.464077)
			(xy 395.336721 -369.47402) (xy 395.274458 -369.476016) (xy 395.212451 -369.470034) (xy 395.151717 -369.456172)
			(xy 395.093255 -369.434658) (xy 395.038024 -369.405844) (xy 394.986932 -369.370204) (xy 394.940816 -369.328323)
			(xy 394.900434 -369.280888) (xy 394.86645 -369.228679) (xy 394.839421 -369.172553) (xy 394.819792 -369.113432)
			(xy 394.807883 -369.052285) (xy 394.803892 -368.990118) (xy 391.375646 -368.990118) (xy 391.375147 -369.021266)
			(xy 391.367181 -369.083049) (xy 391.35138 -369.143307) (xy 391.328002 -369.20105) (xy 391.297433 -369.255329)
			(xy 391.260173 -369.305253) (xy 391.216836 -369.350003) (xy 391.168131 -369.388843) (xy 391.11486 -369.421136)
			(xy 391.057897 -369.446353) (xy 390.998176 -369.464077) (xy 390.936679 -369.47402) (xy 390.874416 -369.476016)
			(xy 390.812409 -369.470034) (xy 390.751675 -369.456172) (xy 390.693213 -369.434658) (xy 390.637982 -369.405844)
			(xy 390.58689 -369.370204) (xy 390.540774 -369.328323) (xy 390.500392 -369.280888) (xy 390.466408 -369.228679)
			(xy 390.439379 -369.172553) (xy 390.41975 -369.113432) (xy 390.407841 -369.052285) (xy 390.40385 -368.990118)
			(xy 386.975604 -368.990118) (xy 386.975105 -369.021266) (xy 386.967139 -369.083049) (xy 386.951338 -369.143307)
			(xy 386.92796 -369.20105) (xy 386.897391 -369.255329) (xy 386.860131 -369.305253) (xy 386.816794 -369.350003)
			(xy 386.768089 -369.388843) (xy 386.714818 -369.421136) (xy 386.657855 -369.446353) (xy 386.598134 -369.464077)
			(xy 386.536637 -369.47402) (xy 386.474374 -369.476016) (xy 386.412367 -369.470034) (xy 386.351633 -369.456172)
			(xy 386.293171 -369.434658) (xy 386.23794 -369.405844) (xy 386.186848 -369.370204) (xy 386.140732 -369.328323)
			(xy 386.10035 -369.280888) (xy 386.066366 -369.228679) (xy 386.039337 -369.172553) (xy 386.019708 -369.113432)
			(xy 386.007799 -369.052285) (xy 386.003808 -368.990118) (xy 382.575562 -368.990118) (xy 382.575063 -369.021266)
			(xy 382.567097 -369.083049) (xy 382.551296 -369.143307) (xy 382.527918 -369.20105) (xy 382.497349 -369.255329)
			(xy 382.460089 -369.305253) (xy 382.416752 -369.350003) (xy 382.368047 -369.388843) (xy 382.314776 -369.421136)
			(xy 382.257813 -369.446353) (xy 382.198092 -369.464077) (xy 382.136595 -369.47402) (xy 382.074332 -369.476016)
			(xy 382.012325 -369.470034) (xy 381.951591 -369.456172) (xy 381.893129 -369.434658) (xy 381.837898 -369.405844)
			(xy 381.786806 -369.370204) (xy 381.74069 -369.328323) (xy 381.700308 -369.280888) (xy 381.666324 -369.228679)
			(xy 381.639295 -369.172553) (xy 381.619666 -369.113432) (xy 381.607757 -369.052285) (xy 381.603766 -368.990118)
			(xy 378.17552 -368.990118) (xy 378.175021 -369.021266) (xy 378.167055 -369.083049) (xy 378.151254 -369.143307)
			(xy 378.127876 -369.20105) (xy 378.097307 -369.255329) (xy 378.060047 -369.305253) (xy 378.01671 -369.350003)
			(xy 377.968005 -369.388843) (xy 377.914734 -369.421136) (xy 377.857771 -369.446353) (xy 377.79805 -369.464077)
			(xy 377.736553 -369.47402) (xy 377.67429 -369.476016) (xy 377.612283 -369.470034) (xy 377.551549 -369.456172)
			(xy 377.493087 -369.434658) (xy 377.437856 -369.405844) (xy 377.386764 -369.370204) (xy 377.340648 -369.328323)
			(xy 377.300266 -369.280888) (xy 377.266282 -369.228679) (xy 377.239253 -369.172553) (xy 377.219624 -369.113432)
			(xy 377.207715 -369.052285) (xy 377.203724 -368.990118) (xy 351.775776 -368.990118) (xy 351.775277 -369.021266)
			(xy 351.767311 -369.083049) (xy 351.75151 -369.143307) (xy 351.728132 -369.20105) (xy 351.697563 -369.255329)
			(xy 351.660303 -369.305253) (xy 351.616966 -369.350003) (xy 351.568261 -369.388843) (xy 351.51499 -369.421136)
			(xy 351.458027 -369.446353) (xy 351.398306 -369.464077) (xy 351.336809 -369.47402) (xy 351.274546 -369.476016)
			(xy 351.212539 -369.470034) (xy 351.151805 -369.456172) (xy 351.093343 -369.434658) (xy 351.038112 -369.405844)
			(xy 350.98702 -369.370204) (xy 350.940904 -369.328323) (xy 350.900522 -369.280888) (xy 350.866538 -369.228679)
			(xy 350.839509 -369.172553) (xy 350.81988 -369.113432) (xy 350.807971 -369.052285) (xy 350.80398 -368.990118)
			(xy 347.375734 -368.990118) (xy 347.375235 -369.021266) (xy 347.367269 -369.083049) (xy 347.351468 -369.143307)
			(xy 347.32809 -369.20105) (xy 347.297521 -369.255329) (xy 347.260261 -369.305253) (xy 347.216924 -369.350003)
			(xy 347.168219 -369.388843) (xy 347.114948 -369.421136) (xy 347.057985 -369.446353) (xy 346.998264 -369.464077)
			(xy 346.936767 -369.47402) (xy 346.874504 -369.476016) (xy 346.812497 -369.470034) (xy 346.751763 -369.456172)
			(xy 346.693301 -369.434658) (xy 346.63807 -369.405844) (xy 346.586978 -369.370204) (xy 346.540862 -369.328323)
			(xy 346.50048 -369.280888) (xy 346.466496 -369.228679) (xy 346.439467 -369.172553) (xy 346.419838 -369.113432)
			(xy 346.407929 -369.052285) (xy 346.403938 -368.990118) (xy 342.975692 -368.990118) (xy 342.975193 -369.021266)
			(xy 342.967227 -369.083049) (xy 342.951426 -369.143307) (xy 342.928048 -369.20105) (xy 342.897479 -369.255329)
			(xy 342.860219 -369.305253) (xy 342.816882 -369.350003) (xy 342.768177 -369.388843) (xy 342.714906 -369.421136)
			(xy 342.657943 -369.446353) (xy 342.598222 -369.464077) (xy 342.536725 -369.47402) (xy 342.474462 -369.476016)
			(xy 342.412455 -369.470034) (xy 342.351721 -369.456172) (xy 342.293259 -369.434658) (xy 342.238028 -369.405844)
			(xy 342.186936 -369.370204) (xy 342.14082 -369.328323) (xy 342.100438 -369.280888) (xy 342.066454 -369.228679)
			(xy 342.039425 -369.172553) (xy 342.019796 -369.113432) (xy 342.007887 -369.052285) (xy 342.003896 -368.990118)
			(xy 338.57565 -368.990118) (xy 338.575151 -369.021266) (xy 338.567185 -369.083049) (xy 338.551384 -369.143307)
			(xy 338.528006 -369.20105) (xy 338.497437 -369.255329) (xy 338.460177 -369.305253) (xy 338.41684 -369.350003)
			(xy 338.368135 -369.388843) (xy 338.314864 -369.421136) (xy 338.257901 -369.446353) (xy 338.19818 -369.464077)
			(xy 338.136683 -369.47402) (xy 338.07442 -369.476016) (xy 338.012413 -369.470034) (xy 337.951679 -369.456172)
			(xy 337.893217 -369.434658) (xy 337.837986 -369.405844) (xy 337.786894 -369.370204) (xy 337.740778 -369.328323)
			(xy 337.700396 -369.280888) (xy 337.666412 -369.228679) (xy 337.639383 -369.172553) (xy 337.619754 -369.113432)
			(xy 337.607845 -369.052285) (xy 337.603854 -368.990118) (xy 334.175608 -368.990118) (xy 334.175109 -369.021266)
			(xy 334.167143 -369.083049) (xy 334.151342 -369.143307) (xy 334.127964 -369.20105) (xy 334.097395 -369.255329)
			(xy 334.060135 -369.305253) (xy 334.016798 -369.350003) (xy 333.968093 -369.388843) (xy 333.914822 -369.421136)
			(xy 333.857859 -369.446353) (xy 333.798138 -369.464077) (xy 333.736641 -369.47402) (xy 333.674378 -369.476016)
			(xy 333.612371 -369.470034) (xy 333.551637 -369.456172) (xy 333.493175 -369.434658) (xy 333.437944 -369.405844)
			(xy 333.386852 -369.370204) (xy 333.340736 -369.328323) (xy 333.300354 -369.280888) (xy 333.26637 -369.228679)
			(xy 333.239341 -369.172553) (xy 333.219712 -369.113432) (xy 333.207803 -369.052285) (xy 333.203812 -368.990118)
			(xy 309.717694 -368.990118) (xy 309.717694 -370.522709) (xy 331.005012 -370.522709) (xy 331.005013 -370.457271)
			(xy 331.013799 -370.392426) (xy 331.031209 -370.329346) (xy 331.056929 -370.269175) (xy 331.073252 -370.240814)
			(xy 331.076558 -370.234785) (xy 331.08017 -370.221525) (xy 331.080364 -370.214652) (xy 331.080364 -369.928902)
			(xy 331.080766 -369.918727) (xy 331.088555 -369.899928) (xy 331.102948 -369.885542) (xy 331.121751 -369.877761)
			(xy 331.131926 -369.87734) (xy 331.848206 -369.87734) (xy 331.858364 -369.877829) (xy 331.877134 -369.885605)
			(xy 331.891499 -369.899973) (xy 331.899273 -369.918744) (xy 331.899768 -369.928902) (xy 331.899768 -370.214652)
			(xy 331.899982 -370.221524) (xy 331.903576 -370.234786) (xy 331.90688 -370.240814) (xy 331.923191 -370.269181)
			(xy 331.948909 -370.329351) (xy 331.966318 -370.392429) (xy 331.975102 -370.457272) (xy 331.975103 -370.522708)
			(xy 331.966322 -370.587551) (xy 331.948916 -370.650629) (xy 331.923201 -370.710801) (xy 331.90688 -370.739162)
			(xy 331.903577 -370.745193) (xy 331.899964 -370.758452) (xy 331.899768 -370.765324) (xy 331.899768 -371.514878)
			(xy 331.899972 -371.52175) (xy 331.903573 -371.535013) (xy 331.90688 -371.54104) (xy 331.923214 -371.569395)
			(xy 331.948929 -371.629568) (xy 331.966335 -371.692648) (xy 331.975117 -371.757493) (xy 331.975115 -371.822931)
			(xy 331.96633 -371.887776) (xy 331.948921 -371.950855) (xy 331.923203 -372.011027) (xy 331.90688 -372.039388)
			(xy 331.903568 -372.045414) (xy 331.899961 -372.058677) (xy 331.899768 -372.06555) (xy 331.899768 -372.351554)
			(xy 331.899299 -372.361722) (xy 331.89153 -372.380514) (xy 331.877158 -372.394901) (xy 331.858373 -372.402688)
			(xy 331.848206 -372.403116) (xy 331.131926 -372.403116) (xy 331.12175 -372.402714) (xy 331.102948 -372.394929)
			(xy 331.08856 -372.380536) (xy 331.080783 -372.36173) (xy 331.080364 -372.351554) (xy 331.080364 -372.06555)
			(xy 331.080157 -372.058678) (xy 331.07656 -372.045415) (xy 331.073252 -372.039388) (xy 331.056941 -372.01102)
			(xy 331.031222 -371.950851) (xy 331.013812 -371.887773) (xy 331.005027 -371.82293) (xy 331.005025 -371.757494)
			(xy 331.013807 -371.69265) (xy 331.031214 -371.629572) (xy 331.05693 -371.569401) (xy 331.073252 -371.54104)
			(xy 331.076549 -371.535006) (xy 331.080166 -371.52175) (xy 331.080364 -371.514878) (xy 331.080364 -370.765324)
			(xy 331.080167 -370.758451) (xy 331.076563 -370.745188) (xy 331.073252 -370.739162) (xy 331.056919 -370.710806)
			(xy 331.031202 -370.650634) (xy 331.013794 -370.587554) (xy 331.005012 -370.522709) (xy 309.717694 -370.522709)
			(xy 309.717694 -372.890034) (xy 333.204312 -372.890034) (xy 333.204869 -372.857304) (xy 333.213727 -372.792446)
			(xy 333.23122 -372.729365) (xy 333.25703 -372.669208) (xy 333.2734 -372.64086) (xy 333.276729 -372.634842)
			(xy 333.280326 -372.621573) (xy 333.280512 -372.614698) (xy 333.280512 -371.865398) (xy 333.280319 -371.858525)
			(xy 333.276712 -371.845262) (xy 333.2734 -371.839236) (xy 333.257049 -371.810879) (xy 333.231243 -371.750722)
			(xy 333.21375 -371.687645) (xy 333.204885 -371.62279) (xy 333.204312 -371.590062) (xy 333.204882 -371.557333)
			(xy 333.213736 -371.492474) (xy 333.231225 -371.429394) (xy 333.257032 -371.369236) (xy 333.2734 -371.340888)
			(xy 333.276719 -371.334865) (xy 333.280322 -371.3216) (xy 333.280512 -371.314726) (xy 333.280512 -371.028722)
			(xy 333.281044 -371.0186) (xy 333.288759 -370.999885) (xy 333.303031 -370.985529) (xy 333.321701 -370.977704)
			(xy 333.33182 -370.97716) (xy 334.0481 -370.97716) (xy 334.058249 -370.977621) (xy 334.076994 -370.985409)
			(xy 334.091316 -370.999793) (xy 334.099023 -371.018571) (xy 334.099408 -371.028722) (xy 334.099408 -371.314726)
			(xy 334.099589 -371.3216) (xy 334.103204 -371.334863) (xy 334.10652 -371.340888) (xy 334.122883 -371.369239)
			(xy 334.148685 -371.429398) (xy 334.166175 -371.492477) (xy 334.175037 -371.557333) (xy 334.175608 -371.590062)
			(xy 334.175046 -371.622792) (xy 334.166189 -371.68765) (xy 334.148698 -371.75073) (xy 334.131759 -371.790214)
			(xy 335.40446 -371.790214) (xy 335.405015 -371.757484) (xy 335.413875 -371.692626) (xy 335.431368 -371.629546)
			(xy 335.457178 -371.569388) (xy 335.473548 -371.54104) (xy 335.476844 -371.535006) (xy 335.480462 -371.52175)
			(xy 335.48066 -371.514878) (xy 335.48066 -370.765324) (xy 335.480464 -370.758451) (xy 335.476859 -370.745188)
			(xy 335.473548 -370.739162) (xy 335.457172 -370.710818) (xy 335.431372 -370.650657) (xy 335.413885 -370.587576)
			(xy 335.405028 -370.522718) (xy 335.40446 -370.489988) (xy 335.405048 -370.457259) (xy 335.413898 -370.392402)
			(xy 335.431382 -370.329322) (xy 335.457183 -370.269163) (xy 335.473548 -370.240814) (xy 335.476854 -370.234785)
			(xy 335.480466 -370.221525) (xy 335.48066 -370.214652) (xy 335.48066 -369.928902) (xy 335.481129 -369.918773)
			(xy 335.48886 -369.900048) (xy 335.503152 -369.885691) (xy 335.521841 -369.877875) (xy 335.531968 -369.87734)
			(xy 336.248248 -369.87734) (xy 336.25841 -369.877683) (xy 336.277171 -369.885502) (xy 336.291494 -369.899923)
			(xy 336.299185 -369.918737) (xy 336.299556 -369.928902) (xy 336.299556 -370.214652) (xy 336.299759 -370.221525)
			(xy 336.303359 -370.234788) (xy 336.306668 -370.240814) (xy 336.323036 -370.269162) (xy 336.348838 -370.329322)
			(xy 336.366327 -370.392402) (xy 336.375186 -370.457259) (xy 336.375756 -370.489988) (xy 336.3752 -370.522708)
			(xy 339.805098 -370.522708) (xy 339.805099 -370.457271) (xy 339.813884 -370.392426) (xy 339.831294 -370.329347)
			(xy 339.857013 -370.269175) (xy 339.873336 -370.240814) (xy 339.876641 -370.234784) (xy 339.880254 -370.221525)
			(xy 339.880448 -370.214652) (xy 339.880448 -369.928902) (xy 339.880866 -369.918729) (xy 339.888652 -369.899933)
			(xy 339.903039 -369.885547) (xy 339.921837 -369.877764) (xy 339.93201 -369.87734) (xy 340.64829 -369.87734)
			(xy 340.658461 -369.877772) (xy 340.677256 -369.885554) (xy 340.691641 -369.899937) (xy 340.699426 -369.918731)
			(xy 340.699852 -369.928902) (xy 340.699852 -370.214652) (xy 340.700056 -370.221524) (xy 340.703655 -370.234788)
			(xy 340.706964 -370.240814) (xy 340.723276 -370.269181) (xy 340.748994 -370.329351) (xy 340.766403 -370.392428)
			(xy 340.775188 -370.457272) (xy 340.77519 -370.522708) (xy 344.204888 -370.522708) (xy 344.204889 -370.457271)
			(xy 344.213674 -370.392426) (xy 344.231083 -370.329347) (xy 344.256801 -370.269175) (xy 344.273124 -370.240814)
			(xy 344.276435 -370.234788) (xy 344.280043 -370.221525) (xy 344.280236 -370.214652) (xy 344.280236 -369.928902)
			(xy 344.280735 -369.918745) (xy 344.288508 -369.899976) (xy 344.302873 -369.885611) (xy 344.321641 -369.877836)
			(xy 344.331798 -369.87734) (xy 345.048078 -369.87734) (xy 345.058248 -369.877782) (xy 345.077043 -369.88556)
			(xy 345.091429 -369.89994) (xy 345.099214 -369.918732) (xy 345.09964 -369.928902) (xy 345.09964 -370.214652)
			(xy 345.099845 -370.221524) (xy 345.103444 -370.234787) (xy 345.106752 -370.240814) (xy 345.123064 -370.269181)
			(xy 345.148783 -370.329351) (xy 345.166193 -370.392428) (xy 345.174978 -370.457272) (xy 345.174978 -370.489988)
			(xy 348.603832 -370.489988) (xy 348.607823 -370.427821) (xy 348.619732 -370.366674) (xy 348.639361 -370.307553)
			(xy 348.66639 -370.251427) (xy 348.700374 -370.199218) (xy 348.740756 -370.151783) (xy 348.786872 -370.109902)
			(xy 348.837964 -370.074262) (xy 348.893195 -370.045448) (xy 348.951657 -370.023934) (xy 349.012391 -370.010072)
			(xy 349.074398 -370.00409) (xy 349.136661 -370.006086) (xy 349.198158 -370.016029) (xy 349.257879 -370.033753)
			(xy 349.314842 -370.05897) (xy 349.368113 -370.091263) (xy 349.416818 -370.130103) (xy 349.460155 -370.174853)
			(xy 349.497415 -370.224777) (xy 349.527984 -370.279056) (xy 349.551362 -370.336799) (xy 349.567163 -370.397057)
			(xy 349.575129 -370.45884) (xy 349.575628 -370.489988) (xy 349.575129 -370.521136) (xy 349.574926 -370.522709)
			(xy 375.004922 -370.522709) (xy 375.004924 -370.457271) (xy 375.013709 -370.392425) (xy 375.03112 -370.329346)
			(xy 375.05684 -370.269175) (xy 375.073164 -370.240814) (xy 375.076471 -370.234785) (xy 375.080082 -370.221525)
			(xy 375.080276 -370.214652) (xy 375.080276 -369.928902) (xy 375.080666 -369.918726) (xy 375.088458 -369.899924)
			(xy 375.102854 -369.885538) (xy 375.121661 -369.877759) (xy 375.131838 -369.87734) (xy 375.848118 -369.87734)
			(xy 375.858277 -369.877818) (xy 375.877047 -369.885599) (xy 375.891412 -369.89997) (xy 375.899185 -369.918743)
			(xy 375.89968 -369.928902) (xy 375.89968 -370.214652) (xy 375.899893 -370.221524) (xy 375.903487 -370.234786)
			(xy 375.906792 -370.240814) (xy 375.923103 -370.269181) (xy 375.94882 -370.329351) (xy 375.966228 -370.392429)
			(xy 375.975012 -370.457272) (xy 375.975014 -370.522707) (xy 375.966232 -370.587551) (xy 375.948827 -370.650629)
			(xy 375.923112 -370.7108) (xy 375.906792 -370.739162) (xy 375.90349 -370.745193) (xy 375.899877 -370.758452)
			(xy 375.89968 -370.765324) (xy 375.89968 -371.514878) (xy 375.899883 -371.52175) (xy 375.903484 -371.535013)
			(xy 375.906792 -371.54104) (xy 375.923125 -371.569395) (xy 375.94884 -371.629568) (xy 375.966246 -371.692648)
			(xy 375.975027 -371.757493) (xy 375.975026 -371.822931) (xy 375.966241 -371.887776) (xy 375.948832 -371.950855)
			(xy 375.923114 -372.011026) (xy 375.906792 -372.039388) (xy 375.903481 -372.045414) (xy 375.899873 -372.058677)
			(xy 375.89968 -372.06555) (xy 375.89968 -372.351554) (xy 375.899199 -372.36172) (xy 375.891432 -372.380511)
			(xy 375.877064 -372.394896) (xy 375.858284 -372.402686) (xy 375.848118 -372.403116) (xy 375.131838 -372.403116)
			(xy 375.121663 -372.402704) (xy 375.102861 -372.394923) (xy 375.088473 -372.380533) (xy 375.080695 -372.361729)
			(xy 375.080276 -372.351554) (xy 375.080276 -372.06555) (xy 375.080068 -372.058678) (xy 375.076471 -372.045415)
			(xy 375.073164 -372.039388) (xy 375.056853 -372.01102) (xy 375.031133 -371.950851) (xy 375.013722 -371.887774)
			(xy 375.004937 -371.82293) (xy 375.004935 -371.757494) (xy 375.013718 -371.69265) (xy 375.031125 -371.629572)
			(xy 375.056842 -371.569401) (xy 375.073164 -371.54104) (xy 375.076462 -371.535007) (xy 375.080078 -371.52175)
			(xy 375.080276 -371.514878) (xy 375.080276 -370.765324) (xy 375.080078 -370.758451) (xy 375.076474 -370.745188)
			(xy 375.073164 -370.739162) (xy 375.056831 -370.710807) (xy 375.031113 -370.650634) (xy 375.013705 -370.587554)
			(xy 375.004922 -370.522709) (xy 349.574926 -370.522709) (xy 349.567163 -370.582919) (xy 349.551362 -370.643177)
			(xy 349.527984 -370.70092) (xy 349.497415 -370.755199) (xy 349.460155 -370.805123) (xy 349.416818 -370.849873)
			(xy 349.368113 -370.888713) (xy 349.314842 -370.921006) (xy 349.257879 -370.946223) (xy 349.198158 -370.963947)
			(xy 349.136661 -370.97389) (xy 349.074398 -370.975886) (xy 349.012391 -370.969904) (xy 348.951657 -370.956042)
			(xy 348.893195 -370.934528) (xy 348.837964 -370.905714) (xy 348.786872 -370.870074) (xy 348.740756 -370.828193)
			(xy 348.700374 -370.780758) (xy 348.66639 -370.728549) (xy 348.639361 -370.672423) (xy 348.619732 -370.613302)
			(xy 348.607823 -370.552155) (xy 348.603832 -370.489988) (xy 345.174978 -370.489988) (xy 345.174979 -370.522708)
			(xy 345.166197 -370.587552) (xy 345.14879 -370.65063) (xy 345.123074 -370.710801) (xy 345.106752 -370.739162)
			(xy 345.103455 -370.745195) (xy 345.099837 -370.758452) (xy 345.09964 -370.765324) (xy 345.09964 -371.514878)
			(xy 345.099835 -371.521751) (xy 345.103441 -371.535014) (xy 345.106752 -371.54104) (xy 345.123086 -371.569395)
			(xy 345.145905 -371.622787) (xy 346.405014 -371.622787) (xy 346.405019 -371.557348) (xy 346.413808 -371.492501)
			(xy 346.431222 -371.429421) (xy 346.456946 -371.369249) (xy 346.473272 -371.340888) (xy 346.476589 -371.334864)
			(xy 346.480194 -371.3216) (xy 346.480384 -371.314726) (xy 346.480384 -371.028722) (xy 346.480783 -371.018546)
			(xy 346.488569 -370.999743) (xy 346.502963 -370.985356) (xy 346.52177 -370.977578) (xy 346.531946 -370.97716)
			(xy 347.248226 -370.97716) (xy 347.258388 -370.977612) (xy 347.277162 -370.9854) (xy 347.291527 -370.999778)
			(xy 347.299297 -371.018559) (xy 347.299788 -371.028722) (xy 347.299788 -371.314726) (xy 347.299971 -371.3216)
			(xy 347.303586 -371.334863) (xy 347.3069 -371.340888) (xy 347.323189 -371.369267) (xy 347.348907 -371.429435)
			(xy 347.366318 -371.49251) (xy 347.375104 -371.557351) (xy 347.375109 -371.622784) (xy 347.366331 -371.687626)
			(xy 347.348929 -371.750704) (xy 347.332046 -371.790214) (xy 348.603832 -371.790214) (xy 348.607823 -371.728047)
			(xy 348.619732 -371.6669) (xy 348.639361 -371.607779) (xy 348.66639 -371.551653) (xy 348.700374 -371.499444)
			(xy 348.740756 -371.452009) (xy 348.786872 -371.410128) (xy 348.837964 -371.374488) (xy 348.893195 -371.345674)
			(xy 348.951657 -371.32416) (xy 349.012391 -371.310298) (xy 349.074398 -371.304316) (xy 349.136661 -371.306312)
			(xy 349.198158 -371.316255) (xy 349.257879 -371.333979) (xy 349.314842 -371.359196) (xy 349.368113 -371.391489)
			(xy 349.416818 -371.430329) (xy 349.460155 -371.475079) (xy 349.497415 -371.525003) (xy 349.527984 -371.579282)
			(xy 349.532348 -371.590062) (xy 350.80398 -371.590062) (xy 350.807971 -371.527895) (xy 350.81988 -371.466748)
			(xy 350.839509 -371.407627) (xy 350.866538 -371.351501) (xy 350.900522 -371.299292) (xy 350.940904 -371.251857)
			(xy 350.98702 -371.209976) (xy 351.038112 -371.174336) (xy 351.093343 -371.145522) (xy 351.151805 -371.124008)
			(xy 351.212539 -371.110146) (xy 351.274546 -371.104164) (xy 351.336809 -371.10616) (xy 351.398306 -371.116103)
			(xy 351.458027 -371.133827) (xy 351.51499 -371.159044) (xy 351.568261 -371.191337) (xy 351.616966 -371.230177)
			(xy 351.660303 -371.274927) (xy 351.697563 -371.324851) (xy 351.728132 -371.37913) (xy 351.75151 -371.436873)
			(xy 351.767311 -371.497131) (xy 351.775277 -371.558914) (xy 351.775776 -371.590062) (xy 351.775277 -371.62121)
			(xy 351.767311 -371.682993) (xy 351.75151 -371.743251) (xy 351.728132 -371.800994) (xy 351.697563 -371.855273)
			(xy 351.660303 -371.905197) (xy 351.616966 -371.949947) (xy 351.568261 -371.988787) (xy 351.51499 -372.02108)
			(xy 351.458027 -372.046297) (xy 351.398306 -372.064021) (xy 351.336809 -372.073964) (xy 351.274546 -372.07596)
			(xy 351.212539 -372.069978) (xy 351.151805 -372.056116) (xy 351.093343 -372.034602) (xy 351.038112 -372.005788)
			(xy 350.98702 -371.970148) (xy 350.940904 -371.928267) (xy 350.900522 -371.880832) (xy 350.866538 -371.828623)
			(xy 350.839509 -371.772497) (xy 350.81988 -371.713376) (xy 350.807971 -371.652229) (xy 350.80398 -371.590062)
			(xy 349.532348 -371.590062) (xy 349.551362 -371.637025) (xy 349.567163 -371.697283) (xy 349.575129 -371.759066)
			(xy 349.575628 -371.790214) (xy 349.575129 -371.821362) (xy 349.567163 -371.883145) (xy 349.551362 -371.943403)
			(xy 349.527984 -372.001146) (xy 349.497415 -372.055425) (xy 349.460155 -372.105349) (xy 349.416818 -372.150099)
			(xy 349.368113 -372.188939) (xy 349.314842 -372.221232) (xy 349.257879 -372.246449) (xy 349.198158 -372.264173)
			(xy 349.136661 -372.274116) (xy 349.074398 -372.276112) (xy 349.012391 -372.27013) (xy 348.951657 -372.256268)
			(xy 348.893195 -372.234754) (xy 348.837964 -372.20594) (xy 348.786872 -372.1703) (xy 348.740756 -372.128419)
			(xy 348.700374 -372.080984) (xy 348.66639 -372.028775) (xy 348.639361 -371.972649) (xy 348.619732 -371.913528)
			(xy 348.607823 -371.852381) (xy 348.603832 -371.790214) (xy 347.332046 -371.790214) (xy 347.323218 -371.810874)
			(xy 347.3069 -371.839236) (xy 347.303572 -371.845254) (xy 347.299975 -371.858523) (xy 347.299788 -371.865398)
			(xy 347.299788 -372.614698) (xy 347.299982 -372.621571) (xy 347.303589 -372.634834) (xy 347.3069 -372.64086)
			(xy 347.32325 -372.669206) (xy 347.348963 -372.729381) (xy 347.366366 -372.792463) (xy 347.375145 -372.85731)
			(xy 347.375143 -372.890034) (xy 350.80398 -372.890034) (xy 350.807971 -372.827867) (xy 350.81988 -372.76672)
			(xy 350.839509 -372.707599) (xy 350.866538 -372.651473) (xy 350.900522 -372.599264) (xy 350.940904 -372.551829)
			(xy 350.98702 -372.509948) (xy 351.038112 -372.474308) (xy 351.093343 -372.445494) (xy 351.151805 -372.42398)
			(xy 351.212539 -372.410118) (xy 351.274546 -372.404136) (xy 351.336809 -372.406132) (xy 351.398306 -372.416075)
			(xy 351.458027 -372.433799) (xy 351.51499 -372.459016) (xy 351.568261 -372.491309) (xy 351.616966 -372.530149)
			(xy 351.660303 -372.574899) (xy 351.697563 -372.624823) (xy 351.728132 -372.679102) (xy 351.75151 -372.736845)
			(xy 351.767311 -372.797103) (xy 351.775277 -372.858886) (xy 351.775776 -372.890034) (xy 377.204224 -372.890034)
			(xy 377.204779 -372.857304) (xy 377.213638 -372.792445) (xy 377.231131 -372.729365) (xy 377.256942 -372.669208)
			(xy 377.273312 -372.64086) (xy 377.276642 -372.634843) (xy 377.280238 -372.621573) (xy 377.280424 -372.614698)
			(xy 377.280424 -371.865398) (xy 377.28023 -371.858525) (xy 377.276623 -371.845262) (xy 377.273312 -371.839236)
			(xy 377.256962 -371.810878) (xy 377.231156 -371.750722) (xy 377.213662 -371.687645) (xy 377.204797 -371.62279)
			(xy 377.204224 -371.590062) (xy 377.204792 -371.557333) (xy 377.213647 -371.492474) (xy 377.231136 -371.429394)
			(xy 377.256943 -371.369236) (xy 377.273312 -371.340888) (xy 377.276632 -371.334866) (xy 377.280234 -371.3216)
			(xy 377.280424 -371.314726) (xy 377.280424 -371.028722) (xy 377.280944 -371.018599) (xy 377.288662 -370.999881)
			(xy 377.302938 -370.985524) (xy 377.321612 -370.977702) (xy 377.331732 -370.97716) (xy 378.048012 -370.97716)
			(xy 378.058162 -370.977611) (xy 378.076907 -370.985403) (xy 378.091229 -370.99979) (xy 378.098935 -371.01857)
			(xy 378.09932 -371.028722) (xy 378.09932 -371.314726) (xy 378.099499 -371.3216) (xy 378.103116 -371.334863)
			(xy 378.106432 -371.340888) (xy 378.122786 -371.369244) (xy 378.148592 -371.4294) (xy 378.166086 -371.492478)
			(xy 378.174949 -371.557333) (xy 378.17552 -371.590062) (xy 378.174957 -371.622792) (xy 378.1661 -371.68765)
			(xy 378.148609 -371.75073) (xy 378.13167 -371.790214) (xy 379.404372 -371.790214) (xy 379.404925 -371.757484)
			(xy 379.413785 -371.692625) (xy 379.431279 -371.629545) (xy 379.45709 -371.569388) (xy 379.47346 -371.54104)
			(xy 379.476757 -371.535007) (xy 379.480374 -371.52175) (xy 379.480572 -371.514878) (xy 379.480572 -370.765324)
			(xy 379.480374 -370.758451) (xy 379.47677 -370.745188) (xy 379.47346 -370.739162) (xy 379.457085 -370.710818)
			(xy 379.431284 -370.650657) (xy 379.413797 -370.587576) (xy 379.40494 -370.522718) (xy 379.404372 -370.489988)
			(xy 379.404959 -370.457259) (xy 379.413809 -370.392402) (xy 379.431293 -370.329322) (xy 379.457095 -370.269163)
			(xy 379.47346 -370.240814) (xy 379.476766 -370.234785) (xy 379.480378 -370.221525) (xy 379.480572 -370.214652)
			(xy 379.480572 -369.928902) (xy 379.481029 -369.918772) (xy 379.488762 -369.900044) (xy 379.503058 -369.885687)
			(xy 379.521752 -369.877873) (xy 379.53188 -369.87734) (xy 380.24816 -369.87734) (xy 380.258316 -369.877755)
			(xy 380.277076 -369.885545) (xy 380.291402 -369.899945) (xy 380.299096 -369.918743) (xy 380.299468 -369.928902)
			(xy 380.299468 -370.214652) (xy 380.299682 -370.221524) (xy 380.303276 -370.234786) (xy 380.30658 -370.240814)
			(xy 380.322949 -370.269161) (xy 380.348751 -370.329321) (xy 380.366239 -370.392401) (xy 380.375098 -370.457259)
			(xy 380.375668 -370.489988) (xy 380.37511 -370.522709) (xy 383.805008 -370.522709) (xy 383.80501 -370.457271)
			(xy 383.813795 -370.392426) (xy 383.831205 -370.329346) (xy 383.856925 -370.269175) (xy 383.873248 -370.240814)
			(xy 383.876554 -370.234785) (xy 383.880166 -370.221525) (xy 383.88036 -370.214652) (xy 383.88036 -369.928902)
			(xy 383.880766 -369.918728) (xy 383.888554 -369.899929) (xy 383.902946 -369.885543) (xy 383.921748 -369.877762)
			(xy 383.931922 -369.87734) (xy 384.648202 -369.87734) (xy 384.65836 -369.877832) (xy 384.67713 -369.885607)
			(xy 384.691495 -369.899974) (xy 384.699269 -369.918744) (xy 384.699764 -369.928902) (xy 384.699764 -370.214652)
			(xy 384.699979 -370.221524) (xy 384.703572 -370.234786) (xy 384.706876 -370.240814) (xy 384.723188 -370.269181)
			(xy 384.748905 -370.329351) (xy 384.766314 -370.392428) (xy 384.775099 -370.457272) (xy 384.7751 -370.522708)
			(xy 388.204798 -370.522708) (xy 388.204799 -370.457271) (xy 388.213584 -370.392426) (xy 388.230994 -370.329347)
			(xy 388.256713 -370.269175) (xy 388.273036 -370.240814) (xy 388.276341 -370.234784) (xy 388.279954 -370.221525)
			(xy 388.280148 -370.214652) (xy 388.280148 -369.928902) (xy 388.280566 -369.918729) (xy 388.288352 -369.899933)
			(xy 388.302739 -369.885547) (xy 388.321537 -369.877764) (xy 388.33171 -369.87734) (xy 389.04799 -369.87734)
			(xy 389.058161 -369.877772) (xy 389.076956 -369.885554) (xy 389.091341 -369.899937) (xy 389.099126 -369.918731)
			(xy 389.099552 -369.928902) (xy 389.099552 -370.214652) (xy 389.099756 -370.221524) (xy 389.103355 -370.234788)
			(xy 389.106664 -370.240814) (xy 389.122976 -370.269181) (xy 389.148694 -370.329351) (xy 389.166103 -370.392428)
			(xy 389.174888 -370.457272) (xy 389.174889 -370.489988) (xy 392.603744 -370.489988) (xy 392.607735 -370.427821)
			(xy 392.619644 -370.366674) (xy 392.639273 -370.307553) (xy 392.666302 -370.251427) (xy 392.700286 -370.199218)
			(xy 392.740668 -370.151783) (xy 392.786784 -370.109902) (xy 392.837876 -370.074262) (xy 392.893107 -370.045448)
			(xy 392.951569 -370.023934) (xy 393.012303 -370.010072) (xy 393.07431 -370.00409) (xy 393.136573 -370.006086)
			(xy 393.19807 -370.016029) (xy 393.257791 -370.033753) (xy 393.314754 -370.05897) (xy 393.368025 -370.091263)
			(xy 393.41673 -370.130103) (xy 393.460067 -370.174853) (xy 393.497327 -370.224777) (xy 393.527896 -370.279056)
			(xy 393.551274 -370.336799) (xy 393.567075 -370.397057) (xy 393.575041 -370.45884) (xy 393.57554 -370.489988)
			(xy 393.575041 -370.521136) (xy 393.567075 -370.582919) (xy 393.551274 -370.643177) (xy 393.527896 -370.70092)
			(xy 393.497327 -370.755199) (xy 393.460067 -370.805123) (xy 393.41673 -370.849873) (xy 393.368025 -370.888713)
			(xy 393.314754 -370.921006) (xy 393.257791 -370.946223) (xy 393.19807 -370.963947) (xy 393.136573 -370.97389)
			(xy 393.07431 -370.975886) (xy 393.012303 -370.969904) (xy 392.951569 -370.956042) (xy 392.893107 -370.934528)
			(xy 392.837876 -370.905714) (xy 392.786784 -370.870074) (xy 392.740668 -370.828193) (xy 392.700286 -370.780758)
			(xy 392.666302 -370.728549) (xy 392.639273 -370.672423) (xy 392.619644 -370.613302) (xy 392.607735 -370.552155)
			(xy 392.603744 -370.489988) (xy 389.174889 -370.489988) (xy 389.17489 -370.522708) (xy 389.166108 -370.587552)
			(xy 389.148701 -370.65063) (xy 389.122985 -370.710801) (xy 389.106664 -370.739162) (xy 389.103368 -370.745196)
			(xy 389.09975 -370.758452) (xy 389.099552 -370.765324) (xy 389.099552 -371.514878) (xy 389.099746 -371.521751)
			(xy 389.103352 -371.535014) (xy 389.106664 -371.54104) (xy 389.122998 -371.569395) (xy 389.145816 -371.622787)
			(xy 390.404925 -371.622787) (xy 390.404929 -371.557347) (xy 390.413718 -371.4925) (xy 390.431133 -371.42942)
			(xy 390.456858 -371.369249) (xy 390.473184 -371.340888) (xy 390.476502 -371.334865) (xy 390.480106 -371.3216)
			(xy 390.480296 -371.314726) (xy 390.480296 -371.028722) (xy 390.48085 -371.018571) (xy 390.48861 -370.99981)
			(xy 390.502956 -370.985446) (xy 390.521707 -370.977663) (xy 390.531858 -370.97716) (xy 391.248138 -370.97716)
			(xy 391.258301 -370.977603) (xy 391.277075 -370.985394) (xy 391.29144 -370.999775) (xy 391.299209 -371.018558)
			(xy 391.299258 -371.019578) (xy 404.149814 -371.019578) (xy 404.150207 -370.99322) (xy 404.157455 -370.941005)
			(xy 404.171825 -370.890286) (xy 404.193043 -370.842029) (xy 404.220703 -370.797153) (xy 404.25428 -370.756514)
			(xy 404.293133 -370.720885) (xy 404.336523 -370.690947) (xy 404.359872 -370.67871) (xy 404.372456 -370.671818)
			(xy 404.393539 -370.652384) (xy 404.408375 -370.627847) (xy 404.41579 -370.600149) (xy 404.415198 -370.571482)
			(xy 404.406645 -370.544113) (xy 404.390808 -370.52021) (xy 404.380192 -370.510562) (xy 404.359429 -370.492363)
			(xy 404.322896 -370.450966) (xy 404.292711 -370.404736) (xy 404.269504 -370.354639) (xy 404.253758 -370.30172)
			(xy 404.245804 -370.247084) (xy 404.245318 -370.219478) (xy 404.245804 -370.192227) (xy 404.25356 -370.138279)
			(xy 404.268915 -370.085984) (xy 404.291557 -370.036407) (xy 404.321023 -369.990557) (xy 404.356714 -369.949366)
			(xy 404.397905 -369.913675) (xy 404.443755 -369.884209) (xy 404.493332 -369.861567) (xy 404.545627 -369.846212)
			(xy 404.599575 -369.838456) (xy 404.654077 -369.838456) (xy 404.708025 -369.846212) (xy 404.76032 -369.861567)
			(xy 404.809897 -369.884209) (xy 404.855747 -369.913675) (xy 404.896938 -369.949366) (xy 404.932629 -369.990557)
			(xy 404.962095 -370.036407) (xy 404.984737 -370.085984) (xy 405.000092 -370.138279) (xy 405.007848 -370.192227)
			(xy 405.008334 -370.219478) (xy 405.007879 -370.245834) (xy 405.000637 -370.298045) (xy 404.986275 -370.348761)
			(xy 404.965066 -370.397017) (xy 404.937414 -370.441893) (xy 404.903846 -370.482533) (xy 404.865002 -370.518164)
			(xy 404.821621 -370.548106) (xy 404.798276 -370.560346) (xy 404.785647 -370.567166) (xy 404.764551 -370.58661)
			(xy 404.749709 -370.611162) (xy 404.742295 -370.638877) (xy 404.742897 -370.66756) (xy 404.751468 -370.69494)
			(xy 404.767328 -370.718847) (xy 404.777956 -370.728494) (xy 404.798687 -370.746728) (xy 404.835224 -370.788116)
			(xy 404.865415 -370.834338) (xy 404.888629 -370.884429) (xy 404.90438 -370.937342) (xy 404.91234 -370.991974)
			(xy 404.912627 -371.008148) (xy 405.37206 -371.008148) (xy 405.376131 -370.952526) (xy 405.388257 -370.898089)
			(xy 405.40818 -370.845998) (xy 405.435476 -370.797363) (xy 405.469562 -370.75322) (xy 405.509711 -370.714511)
			(xy 405.555069 -370.68206) (xy 405.604669 -370.656559) (xy 405.657453 -370.638552) (xy 405.712296 -370.628422)
			(xy 405.76803 -370.626385) (xy 405.823467 -370.632485) (xy 405.877424 -370.646591) (xy 405.928753 -370.668403)
			(xy 405.976359 -370.697457) (xy 406.019227 -370.733132) (xy 406.056444 -370.774669) (xy 406.087217 -370.821182)
			(xy 406.110889 -370.871679) (xy 406.126957 -370.925086) (xy 406.135077 -370.980262) (xy 406.135586 -371.008148)
			(xy 406.135077 -371.036034) (xy 406.126957 -371.09121) (xy 406.110889 -371.144617) (xy 406.087217 -371.195114)
			(xy 406.056444 -371.241627) (xy 406.019227 -371.283164) (xy 405.976359 -371.318839) (xy 405.928753 -371.347893)
			(xy 405.877424 -371.369705) (xy 405.823467 -371.383811) (xy 405.76803 -371.389911) (xy 405.712296 -371.387874)
			(xy 405.657453 -371.377744) (xy 405.604669 -371.359737) (xy 405.555069 -371.334236) (xy 405.509711 -371.301785)
			(xy 405.469562 -371.263076) (xy 405.435476 -371.218933) (xy 405.40818 -371.170298) (xy 405.388257 -371.118207)
			(xy 405.376131 -371.06377) (xy 405.37206 -371.008148) (xy 404.912627 -371.008148) (xy 404.91283 -371.019578)
			(xy 404.912344 -371.046829) (xy 404.904588 -371.100777) (xy 404.889233 -371.153072) (xy 404.866591 -371.202649)
			(xy 404.837125 -371.248499) (xy 404.801434 -371.28969) (xy 404.760243 -371.325381) (xy 404.714393 -371.354847)
			(xy 404.664816 -371.377489) (xy 404.612521 -371.392844) (xy 404.558573 -371.4006) (xy 404.504071 -371.4006)
			(xy 404.450123 -371.392844) (xy 404.397828 -371.377489) (xy 404.348251 -371.354847) (xy 404.302401 -371.325381)
			(xy 404.26121 -371.28969) (xy 404.225519 -371.248499) (xy 404.196053 -371.202649) (xy 404.173411 -371.153072)
			(xy 404.158056 -371.100777) (xy 404.1503 -371.046829) (xy 404.149814 -371.019578) (xy 391.299258 -371.019578)
			(xy 391.2997 -371.028722) (xy 391.2997 -371.314726) (xy 391.299882 -371.3216) (xy 391.303497 -371.334863)
			(xy 391.306812 -371.340888) (xy 391.3231 -371.369268) (xy 391.348818 -371.429435) (xy 391.366228 -371.49251)
			(xy 391.375015 -371.557351) (xy 391.375019 -371.622784) (xy 391.366241 -371.687626) (xy 391.34884 -371.750703)
			(xy 391.331958 -371.790214) (xy 392.603744 -371.790214) (xy 392.607735 -371.728047) (xy 392.619644 -371.6669)
			(xy 392.639273 -371.607779) (xy 392.666302 -371.551653) (xy 392.700286 -371.499444) (xy 392.740668 -371.452009)
			(xy 392.786784 -371.410128) (xy 392.837876 -371.374488) (xy 392.893107 -371.345674) (xy 392.951569 -371.32416)
			(xy 393.012303 -371.310298) (xy 393.07431 -371.304316) (xy 393.136573 -371.306312) (xy 393.19807 -371.316255)
			(xy 393.257791 -371.333979) (xy 393.314754 -371.359196) (xy 393.368025 -371.391489) (xy 393.41673 -371.430329)
			(xy 393.460067 -371.475079) (xy 393.497327 -371.525003) (xy 393.527896 -371.579282) (xy 393.53226 -371.590062)
			(xy 394.803892 -371.590062) (xy 394.807883 -371.527895) (xy 394.819792 -371.466748) (xy 394.839421 -371.407627)
			(xy 394.86645 -371.351501) (xy 394.900434 -371.299292) (xy 394.940816 -371.251857) (xy 394.986932 -371.209976)
			(xy 395.038024 -371.174336) (xy 395.093255 -371.145522) (xy 395.151717 -371.124008) (xy 395.212451 -371.110146)
			(xy 395.274458 -371.104164) (xy 395.336721 -371.10616) (xy 395.398218 -371.116103) (xy 395.457939 -371.133827)
			(xy 395.514902 -371.159044) (xy 395.568173 -371.191337) (xy 395.616878 -371.230177) (xy 395.660215 -371.274927)
			(xy 395.697475 -371.324851) (xy 395.728044 -371.37913) (xy 395.751422 -371.436873) (xy 395.767223 -371.497131)
			(xy 395.775189 -371.558914) (xy 395.775688 -371.590062) (xy 395.775189 -371.62121) (xy 395.767223 -371.682993)
			(xy 395.751422 -371.743251) (xy 395.728044 -371.800994) (xy 395.697475 -371.855273) (xy 395.660215 -371.905197)
			(xy 395.616878 -371.949947) (xy 395.568173 -371.988787) (xy 395.514902 -372.02108) (xy 395.457939 -372.046297)
			(xy 395.398218 -372.064021) (xy 395.336721 -372.073964) (xy 395.274458 -372.07596) (xy 395.212451 -372.069978)
			(xy 395.151717 -372.056116) (xy 395.093255 -372.034602) (xy 395.038024 -372.005788) (xy 394.986932 -371.970148)
			(xy 394.940816 -371.928267) (xy 394.900434 -371.880832) (xy 394.86645 -371.828623) (xy 394.839421 -371.772497)
			(xy 394.819792 -371.713376) (xy 394.807883 -371.652229) (xy 394.803892 -371.590062) (xy 393.53226 -371.590062)
			(xy 393.551274 -371.637025) (xy 393.567075 -371.697283) (xy 393.575041 -371.759066) (xy 393.57554 -371.790214)
			(xy 393.575041 -371.821362) (xy 393.567075 -371.883145) (xy 393.551274 -371.943403) (xy 393.527896 -372.001146)
			(xy 393.497327 -372.055425) (xy 393.460067 -372.105349) (xy 393.41673 -372.150099) (xy 393.368025 -372.188939)
			(xy 393.314754 -372.221232) (xy 393.257791 -372.246449) (xy 393.19807 -372.264173) (xy 393.136573 -372.274116)
			(xy 393.07431 -372.276112) (xy 393.012303 -372.27013) (xy 392.951569 -372.256268) (xy 392.893107 -372.234754)
			(xy 392.837876 -372.20594) (xy 392.786784 -372.1703) (xy 392.740668 -372.128419) (xy 392.700286 -372.080984)
			(xy 392.666302 -372.028775) (xy 392.639273 -371.972649) (xy 392.619644 -371.913528) (xy 392.607735 -371.852381)
			(xy 392.603744 -371.790214) (xy 391.331958 -371.790214) (xy 391.32313 -371.810874) (xy 391.306812 -371.839236)
			(xy 391.303485 -371.845255) (xy 391.299887 -371.858523) (xy 391.2997 -371.865398) (xy 391.2997 -372.614698)
			(xy 391.299893 -372.621571) (xy 391.3035 -372.634834) (xy 391.306812 -372.64086) (xy 391.323161 -372.669206)
			(xy 391.348874 -372.729381) (xy 391.366277 -372.792463) (xy 391.375056 -372.85731) (xy 391.375054 -372.890034)
			(xy 394.803892 -372.890034) (xy 394.807883 -372.827867) (xy 394.819792 -372.76672) (xy 394.839421 -372.707599)
			(xy 394.86645 -372.651473) (xy 394.900434 -372.599264) (xy 394.940816 -372.551829) (xy 394.986932 -372.509948)
			(xy 395.038024 -372.474308) (xy 395.093255 -372.445494) (xy 395.151717 -372.42398) (xy 395.212451 -372.410118)
			(xy 395.274458 -372.404136) (xy 395.336721 -372.406132) (xy 395.398218 -372.416075) (xy 395.457939 -372.433799)
			(xy 395.514902 -372.459016) (xy 395.568173 -372.491309) (xy 395.616878 -372.530149) (xy 395.660215 -372.574899)
			(xy 395.697475 -372.624823) (xy 395.728044 -372.679102) (xy 395.751422 -372.736845) (xy 395.767223 -372.797103)
			(xy 395.775189 -372.858886) (xy 395.775688 -372.890034) (xy 395.775189 -372.921182) (xy 395.767223 -372.982965)
			(xy 395.751422 -373.043223) (xy 395.728044 -373.100966) (xy 395.697475 -373.155245) (xy 395.660215 -373.205169)
			(xy 395.616878 -373.249919) (xy 395.568173 -373.288759) (xy 395.514902 -373.321052) (xy 395.457939 -373.346269)
			(xy 395.398218 -373.363993) (xy 395.336721 -373.373936) (xy 395.274458 -373.375932) (xy 395.212451 -373.36995)
			(xy 395.151717 -373.356088) (xy 395.093255 -373.334574) (xy 395.038024 -373.30576) (xy 394.986932 -373.27012)
			(xy 394.940816 -373.228239) (xy 394.900434 -373.180804) (xy 394.86645 -373.128595) (xy 394.839421 -373.072469)
			(xy 394.819792 -373.013348) (xy 394.807883 -372.952201) (xy 394.803892 -372.890034) (xy 391.375054 -372.890034)
			(xy 391.375052 -372.922748) (xy 391.366265 -372.987594) (xy 391.348854 -373.050674) (xy 391.323135 -373.110846)
			(xy 391.306812 -373.139208) (xy 391.303495 -373.145232) (xy 391.299891 -373.158496) (xy 391.2997 -373.16537)
			(xy 391.2997 -373.451374) (xy 391.299146 -373.461525) (xy 391.291388 -373.480287) (xy 391.277041 -373.494652)
			(xy 391.258289 -373.502434) (xy 391.248138 -373.502936) (xy 390.531858 -373.502936) (xy 390.521694 -373.5025)
			(xy 390.502919 -373.494707) (xy 390.488555 -373.480324) (xy 390.480786 -373.461538) (xy 390.480296 -373.451374)
			(xy 390.480296 -373.16537) (xy 390.480116 -373.158496) (xy 390.4765 -373.145233) (xy 390.473184 -373.139208)
			(xy 390.456889 -373.110831) (xy 390.431167 -373.050664) (xy 390.413754 -372.987589) (xy 390.404966 -372.922747)
			(xy 390.404962 -372.857312) (xy 390.413742 -372.792468) (xy 390.431147 -372.729391) (xy 390.456863 -372.669221)
			(xy 390.473184 -372.64086) (xy 390.476512 -372.634842) (xy 390.480109 -372.621573) (xy 390.480296 -372.614698)
			(xy 390.480296 -371.865398) (xy 390.480105 -371.858525) (xy 390.476496 -371.845262) (xy 390.473184 -371.839236)
			(xy 390.456828 -371.810893) (xy 390.431111 -371.750718) (xy 390.413705 -371.687636) (xy 390.404925 -371.622787)
			(xy 389.145816 -371.622787) (xy 389.148714 -371.629567) (xy 389.166121 -371.692648) (xy 389.174903 -371.757493)
			(xy 389.174901 -371.822931) (xy 389.166116 -371.887776) (xy 389.148706 -371.950855) (xy 389.122987 -372.011027)
			(xy 389.106664 -372.039388) (xy 389.103359 -372.045417) (xy 389.099746 -372.058677) (xy 389.099552 -372.06555)
			(xy 389.099552 -372.351554) (xy 389.099098 -372.361724) (xy 389.091327 -372.380519) (xy 389.07695 -372.394906)
			(xy 389.05816 -372.402691) (xy 389.04799 -372.403116) (xy 388.33171 -372.403116) (xy 388.321533 -372.402727)
			(xy 388.30273 -372.394937) (xy 388.288343 -372.38054) (xy 388.280566 -372.361731) (xy 388.280148 -372.351554)
			(xy 388.280148 -372.06555) (xy 388.279944 -372.058678) (xy 388.276345 -372.045415) (xy 388.273036 -372.039388)
			(xy 388.256726 -372.01102) (xy 388.231007 -371.950851) (xy 388.213598 -371.887773) (xy 388.204813 -371.82293)
			(xy 388.204811 -371.757494) (xy 388.213593 -371.69265) (xy 388.230999 -371.629572) (xy 388.256715 -371.569401)
			(xy 388.273036 -371.54104) (xy 388.276332 -371.535006) (xy 388.27995 -371.52175) (xy 388.280148 -371.514878)
			(xy 388.280148 -370.765324) (xy 388.279953 -370.758451) (xy 388.276348 -370.745188) (xy 388.273036 -370.739162)
			(xy 388.256704 -370.710806) (xy 388.230987 -370.650634) (xy 388.21358 -370.587554) (xy 388.204798 -370.522708)
			(xy 384.7751 -370.522708) (xy 384.766318 -370.587551) (xy 384.748912 -370.65063) (xy 384.723197 -370.710801)
			(xy 384.706876 -370.739162) (xy 384.703573 -370.745192) (xy 384.69996 -370.758452) (xy 384.699764 -370.765324)
			(xy 384.699764 -371.514878) (xy 384.699969 -371.52175) (xy 384.703569 -371.535013) (xy 384.706876 -371.54104)
			(xy 384.72321 -371.569395) (xy 384.748925 -371.629568) (xy 384.766332 -371.692648) (xy 384.775113 -371.757493)
			(xy 384.775112 -371.822931) (xy 384.766327 -371.887776) (xy 384.748917 -371.950855) (xy 384.723199 -372.011027)
			(xy 384.706876 -372.039388) (xy 384.703564 -372.045414) (xy 384.699957 -372.058677) (xy 384.699764 -372.06555)
			(xy 384.699764 -372.351554) (xy 384.699299 -372.361722) (xy 384.691529 -372.380516) (xy 384.677156 -372.394902)
			(xy 384.65837 -372.402689) (xy 384.648202 -372.403116) (xy 383.931922 -372.403116) (xy 383.921746 -372.402717)
			(xy 383.902943 -372.394931) (xy 383.888556 -372.380537) (xy 383.880778 -372.36173) (xy 383.88036 -372.351554)
			(xy 383.88036 -372.06555) (xy 383.880154 -372.058678) (xy 383.876556 -372.045415) (xy 383.873248 -372.039388)
			(xy 383.856937 -372.01102) (xy 383.831218 -371.950851) (xy 383.813808 -371.887773) (xy 383.805023 -371.82293)
			(xy 383.805022 -371.757494) (xy 383.813804 -371.69265) (xy 383.83121 -371.629572) (xy 383.856926 -371.569401)
			(xy 383.873248 -371.54104) (xy 383.876544 -371.535006) (xy 383.880162 -371.52175) (xy 383.88036 -371.514878)
			(xy 383.88036 -370.765324) (xy 383.880164 -370.758451) (xy 383.876559 -370.745188) (xy 383.873248 -370.739162)
			(xy 383.856915 -370.710806) (xy 383.831198 -370.650634) (xy 383.813791 -370.587554) (xy 383.805008 -370.522709)
			(xy 380.37511 -370.522709) (xy 380.37511 -370.522718) (xy 380.36625 -370.587576) (xy 380.348758 -370.650656)
			(xy 380.322949 -370.710814) (xy 380.30658 -370.739162) (xy 380.303277 -370.745193) (xy 380.299664 -370.758452)
			(xy 380.299468 -370.765324) (xy 380.299468 -371.514878) (xy 380.299672 -371.52175) (xy 380.303273 -371.535013)
			(xy 380.30658 -371.54104) (xy 380.32296 -371.569382) (xy 380.345861 -371.622787) (xy 381.604852 -371.622787)
			(xy 381.604857 -371.557348) (xy 381.613644 -371.492502) (xy 381.631056 -371.429422) (xy 381.656776 -371.36925)
			(xy 381.6731 -371.340888) (xy 381.676419 -371.334865) (xy 381.680022 -371.3216) (xy 381.680212 -371.314726)
			(xy 381.680212 -371.028722) (xy 381.680751 -371.018569) (xy 381.688513 -370.999805) (xy 381.702865 -370.98544)
			(xy 381.721621 -370.97766) (xy 381.731774 -370.97716) (xy 382.448054 -370.97716) (xy 382.458225 -370.977602)
			(xy 382.477023 -370.985376) (xy 382.491411 -370.999757) (xy 382.499193 -371.018551) (xy 382.499616 -371.028722)
			(xy 382.499616 -371.314726) (xy 382.499796 -371.3216) (xy 382.503412 -371.334863) (xy 382.506728 -371.340888)
			(xy 382.523019 -371.369267) (xy 382.548741 -371.429433) (xy 382.566154 -371.492508) (xy 382.574942 -371.55735)
			(xy 382.574947 -371.622785) (xy 382.566167 -371.687628) (xy 382.548763 -371.750705) (xy 382.523049 -371.810875)
			(xy 382.506728 -371.839236) (xy 382.503402 -371.845255) (xy 382.499803 -371.858523) (xy 382.499616 -371.865398)
			(xy 382.499616 -372.614698) (xy 382.499807 -372.621571) (xy 382.503416 -372.634834) (xy 382.506728 -372.64086)
			(xy 382.52308 -372.669205) (xy 382.548797 -372.72938) (xy 382.566203 -372.792462) (xy 382.574983 -372.857309)
			(xy 382.574981 -372.890034) (xy 386.004308 -372.890034) (xy 386.004866 -372.857304) (xy 386.013724 -372.792446)
			(xy 386.031216 -372.729365) (xy 386.057026 -372.669208) (xy 386.073396 -372.64086) (xy 386.076725 -372.634842)
			(xy 386.080322 -372.621573) (xy 386.080508 -372.614698) (xy 386.080508 -371.865398) (xy 386.080316 -371.858525)
			(xy 386.076708 -371.845262) (xy 386.073396 -371.839236) (xy 386.057044 -371.810879) (xy 386.031239 -371.750722)
			(xy 386.013746 -371.687645) (xy 386.004881 -371.62279) (xy 386.004308 -371.590062) (xy 386.004878 -371.557333)
			(xy 386.013732 -371.492475) (xy 386.031221 -371.429394) (xy 386.057028 -371.369236) (xy 386.073396 -371.340888)
			(xy 386.076715 -371.334865) (xy 386.080318 -371.3216) (xy 386.080508 -371.314726) (xy 386.080508 -371.028722)
			(xy 386.081044 -371.018601) (xy 386.088758 -370.999886) (xy 386.103029 -370.98553) (xy 386.121698 -370.977704)
			(xy 386.131816 -370.97716) (xy 386.848096 -370.97716) (xy 386.858245 -370.977624) (xy 386.876989 -370.985411)
			(xy 386.891311 -370.999794) (xy 386.899019 -371.018571) (xy 386.899404 -371.028722) (xy 386.899404 -371.314726)
			(xy 386.899585 -371.3216) (xy 386.903201 -371.334863) (xy 386.906516 -371.340888) (xy 386.922878 -371.369239)
			(xy 386.948681 -371.429398) (xy 386.966171 -371.492477) (xy 386.975033 -371.557333) (xy 386.975604 -371.590062)
			(xy 386.975043 -371.622792) (xy 386.966186 -371.68765) (xy 386.948694 -371.75073) (xy 386.922885 -371.810888)
			(xy 386.906516 -371.839236) (xy 386.90319 -371.845255) (xy 386.899591 -371.858523) (xy 386.899404 -371.865398)
			(xy 386.899404 -372.614698) (xy 386.899596 -372.621571) (xy 386.903204 -372.634834) (xy 386.906516 -372.64086)
			(xy 386.922867 -372.669217) (xy 386.948672 -372.729374) (xy 386.966166 -372.792451) (xy 386.975031 -372.857306)
			(xy 386.975604 -372.890034) (xy 386.97503 -372.922763) (xy 386.966177 -372.987621) (xy 386.948689 -373.050701)
			(xy 386.922883 -373.11086) (xy 386.906516 -373.139208) (xy 386.9032 -373.145232) (xy 386.899595 -373.158496)
			(xy 386.899404 -373.16537) (xy 386.899404 -373.451374) (xy 386.898854 -373.461494) (xy 386.891142 -373.480206)
			(xy 386.876876 -373.494562) (xy 386.858212 -373.50239) (xy 386.848096 -373.502936) (xy 386.131816 -373.502936)
			(xy 386.121667 -373.502466) (xy 386.102922 -373.494683) (xy 386.0886 -373.480301) (xy 386.080893 -373.461524)
			(xy 386.080508 -373.451374) (xy 386.080508 -373.16537) (xy 386.080327 -373.158496) (xy 386.076711 -373.145233)
			(xy 386.073396 -373.139208) (xy 386.057033 -373.110857) (xy 386.031231 -373.050698) (xy 386.01374 -372.987619)
			(xy 386.004879 -372.922763) (xy 386.004308 -372.890034) (xy 382.574981 -372.890034) (xy 382.57498 -372.922749)
			(xy 382.566191 -372.987596) (xy 382.548777 -373.050676) (xy 382.523054 -373.110847) (xy 382.506728 -373.139208)
			(xy 382.503412 -373.145232) (xy 382.499807 -373.158496) (xy 382.499616 -373.16537) (xy 382.499616 -373.451374)
			(xy 382.499214 -373.46155) (xy 382.491429 -373.480352) (xy 382.477036 -373.49474) (xy 382.45823 -373.502517)
			(xy 382.448054 -373.502936) (xy 381.731774 -373.502936) (xy 381.721611 -373.502487) (xy 381.702837 -373.4947)
			(xy 381.688471 -373.48032) (xy 381.680702 -373.461537) (xy 381.680212 -373.451374) (xy 381.680212 -373.16537)
			(xy 381.68003 -373.158496) (xy 381.676415 -373.145233) (xy 381.6731 -373.139208) (xy 381.656808 -373.11083)
			(xy 381.63109 -373.050663) (xy 381.61368 -372.987587) (xy 381.604893 -372.922746) (xy 381.604889 -372.857312)
			(xy 381.613668 -372.79247) (xy 381.63107 -372.729393) (xy 381.656781 -372.669222) (xy 381.6731 -372.64086)
			(xy 381.676429 -372.634842) (xy 381.680026 -372.621573) (xy 381.680212 -372.614698) (xy 381.680212 -371.865398)
			(xy 381.680019 -371.858525) (xy 381.676412 -371.845262) (xy 381.6731 -371.839236) (xy 381.656747 -371.810892)
			(xy 381.631034 -371.750716) (xy 381.613631 -371.687634) (xy 381.604852 -371.622787) (xy 380.345861 -371.622787)
			(xy 380.348758 -371.629544) (xy 380.366244 -371.692626) (xy 380.3751 -371.757484) (xy 380.375668 -371.790214)
			(xy 380.375077 -371.822943) (xy 380.366227 -371.8878) (xy 380.348744 -371.95088) (xy 380.322945 -372.011039)
			(xy 380.30658 -372.039388) (xy 380.303268 -372.045414) (xy 380.299661 -372.058677) (xy 380.299468 -372.06555)
			(xy 380.299468 -372.351554) (xy 380.298936 -372.361677) (xy 380.291225 -372.380395) (xy 380.276952 -372.394753)
			(xy 380.25828 -372.402575) (xy 380.24816 -372.403116) (xy 379.53188 -372.403116) (xy 379.521727 -372.402695)
			(xy 379.502977 -372.394896) (xy 379.488655 -372.3805) (xy 379.480953 -372.36171) (xy 379.480572 -372.351554)
			(xy 379.480572 -372.06555) (xy 379.480364 -372.058678) (xy 379.476767 -372.045415) (xy 379.47346 -372.039388)
			(xy 379.457095 -372.011038) (xy 379.431292 -371.950879) (xy 379.413802 -371.8878) (xy 379.404942 -371.822943)
			(xy 379.404372 -371.790214) (xy 378.13167 -371.790214) (xy 378.122801 -371.810888) (xy 378.106432 -371.839236)
			(xy 378.103107 -371.845256) (xy 378.099508 -371.858523) (xy 378.09932 -371.865398) (xy 378.09932 -372.614698)
			(xy 378.09951 -372.621571) (xy 378.10312 -372.634834) (xy 378.106432 -372.64086) (xy 378.122775 -372.669222)
			(xy 378.148584 -372.729376) (xy 378.16608 -372.792452) (xy 378.174947 -372.857306) (xy 378.17552 -372.890034)
			(xy 378.174944 -372.922763) (xy 378.166091 -372.987621) (xy 378.148603 -373.050701) (xy 378.122799 -373.110859)
			(xy 378.106432 -373.139208) (xy 378.103117 -373.145233) (xy 378.099511 -373.158496) (xy 378.09932 -373.16537)
			(xy 378.09932 -373.451374) (xy 378.098851 -373.461504) (xy 378.091125 -373.480232) (xy 378.076832 -373.494591)
			(xy 378.05814 -373.502404) (xy 378.048012 -373.502936) (xy 377.331732 -373.502936) (xy 377.321584 -373.502453)
			(xy 377.30284 -373.494675) (xy 377.288516 -373.480297) (xy 377.280809 -373.461523) (xy 377.280424 -373.451374)
			(xy 377.280424 -373.16537) (xy 377.28024 -373.158496) (xy 377.276626 -373.145234) (xy 377.273312 -373.139208)
			(xy 377.256951 -373.110856) (xy 377.231148 -373.050698) (xy 377.213657 -372.987619) (xy 377.204795 -372.922763)
			(xy 377.204224 -372.890034) (xy 351.775776 -372.890034) (xy 351.775277 -372.921182) (xy 351.767311 -372.982965)
			(xy 351.75151 -373.043223) (xy 351.728132 -373.100966) (xy 351.697563 -373.155245) (xy 351.660303 -373.205169)
			(xy 351.616966 -373.249919) (xy 351.568261 -373.288759) (xy 351.51499 -373.321052) (xy 351.458027 -373.346269)
			(xy 351.398306 -373.363993) (xy 351.336809 -373.373936) (xy 351.274546 -373.375932) (xy 351.212539 -373.36995)
			(xy 351.151805 -373.356088) (xy 351.093343 -373.334574) (xy 351.038112 -373.30576) (xy 350.98702 -373.27012)
			(xy 350.940904 -373.228239) (xy 350.900522 -373.180804) (xy 350.866538 -373.128595) (xy 350.839509 -373.072469)
			(xy 350.81988 -373.013348) (xy 350.807971 -372.952201) (xy 350.80398 -372.890034) (xy 347.375143 -372.890034)
			(xy 347.375141 -372.922748) (xy 347.366354 -372.987594) (xy 347.348943 -373.050674) (xy 347.323223 -373.110846)
			(xy 347.3069 -373.139208) (xy 347.303582 -373.145231) (xy 347.299979 -373.158496) (xy 347.299788 -373.16537)
			(xy 347.299788 -373.451374) (xy 347.299246 -373.461527) (xy 347.291485 -373.480291) (xy 347.277134 -373.494656)
			(xy 347.258378 -373.502436) (xy 347.248226 -373.502936) (xy 346.531946 -373.502936) (xy 346.521774 -373.502498)
			(xy 346.502975 -373.494723) (xy 346.488588 -373.480341) (xy 346.480806 -373.461546) (xy 346.480384 -373.451374)
			(xy 346.480384 -373.16537) (xy 346.480206 -373.158496) (xy 346.476588 -373.145233) (xy 346.473272 -373.139208)
			(xy 346.456978 -373.110831) (xy 346.431256 -373.050664) (xy 346.413843 -372.987589) (xy 346.405055 -372.922747)
			(xy 346.405051 -372.857312) (xy 346.413831 -372.792469) (xy 346.431236 -372.729391) (xy 346.456951 -372.669221)
			(xy 346.473272 -372.64086) (xy 346.476599 -372.634841) (xy 346.480197 -372.621573) (xy 346.480384 -372.614698)
			(xy 346.480384 -371.865398) (xy 346.480195 -371.858525) (xy 346.476585 -371.845262) (xy 346.473272 -371.839236)
			(xy 346.456917 -371.810893) (xy 346.4312 -371.750718) (xy 346.413794 -371.687635) (xy 346.405014 -371.622787)
			(xy 345.145905 -371.622787) (xy 345.148803 -371.629567) (xy 345.16621 -371.692647) (xy 345.174993 -371.757493)
			(xy 345.174991 -371.822931) (xy 345.166206 -371.887776) (xy 345.148795 -371.950855) (xy 345.123075 -372.011027)
			(xy 345.106752 -372.039388) (xy 345.103446 -372.045417) (xy 345.099834 -372.058677) (xy 345.09964 -372.06555)
			(xy 345.09964 -372.351554) (xy 345.099198 -372.361725) (xy 345.091424 -372.380523) (xy 345.077043 -372.394911)
			(xy 345.058249 -372.402693) (xy 345.048078 -372.403116) (xy 344.331798 -372.403116) (xy 344.321621 -372.402737)
			(xy 344.302817 -372.394942) (xy 344.288431 -372.380543) (xy 344.280654 -372.361732) (xy 344.280236 -372.351554)
			(xy 344.280236 -372.06555) (xy 344.280021 -372.058679) (xy 344.276428 -372.045416) (xy 344.273124 -372.039388)
			(xy 344.256814 -372.01102) (xy 344.231096 -371.95085) (xy 344.213687 -371.887773) (xy 344.204903 -371.82293)
			(xy 344.204901 -371.757494) (xy 344.213682 -371.692651) (xy 344.231088 -371.629572) (xy 344.256803 -371.569401)
			(xy 344.273124 -371.54104) (xy 344.276426 -371.535009) (xy 344.280039 -371.52175) (xy 344.280236 -371.514878)
			(xy 344.280236 -370.765324) (xy 344.28003 -370.758452) (xy 344.276431 -370.745189) (xy 344.273124 -370.739162)
			(xy 344.256792 -370.710806) (xy 344.231076 -370.650634) (xy 344.21367 -370.587554) (xy 344.204888 -370.522708)
			(xy 340.77519 -370.522708) (xy 340.766408 -370.587552) (xy 340.749001 -370.65063) (xy 340.723285 -370.710801)
			(xy 340.706964 -370.739162) (xy 340.703668 -370.745196) (xy 340.70005 -370.758452) (xy 340.699852 -370.765324)
			(xy 340.699852 -371.514878) (xy 340.700046 -371.521751) (xy 340.703652 -371.535014) (xy 340.706964 -371.54104)
			(xy 340.723298 -371.569395) (xy 340.749014 -371.629567) (xy 340.766421 -371.692648) (xy 340.775203 -371.757493)
			(xy 340.775201 -371.822931) (xy 340.766416 -371.887776) (xy 340.749006 -371.950855) (xy 340.723287 -372.011027)
			(xy 340.706964 -372.039388) (xy 340.703659 -372.045417) (xy 340.700046 -372.058677) (xy 340.699852 -372.06555)
			(xy 340.699852 -372.351554) (xy 340.699398 -372.361724) (xy 340.691627 -372.380519) (xy 340.67725 -372.394906)
			(xy 340.65846 -372.402691) (xy 340.64829 -372.403116) (xy 339.93201 -372.403116) (xy 339.921833 -372.402727)
			(xy 339.90303 -372.394937) (xy 339.888643 -372.38054) (xy 339.880866 -372.361731) (xy 339.880448 -372.351554)
			(xy 339.880448 -372.06555) (xy 339.880244 -372.058678) (xy 339.876645 -372.045415) (xy 339.873336 -372.039388)
			(xy 339.857026 -372.01102) (xy 339.831307 -371.950851) (xy 339.813898 -371.887773) (xy 339.805113 -371.82293)
			(xy 339.805111 -371.757494) (xy 339.813893 -371.69265) (xy 339.831299 -371.629572) (xy 339.857015 -371.569401)
			(xy 339.873336 -371.54104) (xy 339.876632 -371.535006) (xy 339.88025 -371.52175) (xy 339.880448 -371.514878)
			(xy 339.880448 -370.765324) (xy 339.880253 -370.758451) (xy 339.876648 -370.745188) (xy 339.873336 -370.739162)
			(xy 339.857004 -370.710806) (xy 339.831287 -370.650634) (xy 339.81388 -370.587554) (xy 339.805098 -370.522708)
			(xy 336.3752 -370.522708) (xy 336.3752 -370.522718) (xy 336.36634 -370.587576) (xy 336.348847 -370.650656)
			(xy 336.323037 -370.710814) (xy 336.306668 -370.739162) (xy 336.303365 -370.745192) (xy 336.299752 -370.758452)
			(xy 336.299556 -370.765324) (xy 336.299556 -371.514878) (xy 336.299749 -371.521751) (xy 336.303356 -371.535014)
			(xy 336.306668 -371.54104) (xy 336.323046 -371.569382) (xy 336.345948 -371.622787) (xy 337.604942 -371.622787)
			(xy 337.604946 -371.557348) (xy 337.613734 -371.492502) (xy 337.631145 -371.429422) (xy 337.656865 -371.36925)
			(xy 337.673188 -371.340888) (xy 337.676506 -371.334865) (xy 337.68011 -371.3216) (xy 337.6803 -371.314726)
			(xy 337.6803 -371.028722) (xy 337.68085 -371.01857) (xy 337.68861 -370.999809) (xy 337.702958 -370.985444)
			(xy 337.721711 -370.977662) (xy 337.731862 -370.97716) (xy 338.448142 -370.97716) (xy 338.458305 -370.9776)
			(xy 338.477079 -370.985392) (xy 338.491444 -370.999774) (xy 338.499213 -371.018558) (xy 338.499704 -371.028722)
			(xy 338.499704 -371.314726) (xy 338.499885 -371.3216) (xy 338.503501 -371.334863) (xy 338.506816 -371.340888)
			(xy 338.523107 -371.369267) (xy 338.54883 -371.429433) (xy 338.566244 -371.492508) (xy 338.575032 -371.55735)
			(xy 338.575037 -371.622785) (xy 338.566257 -371.687628) (xy 338.548852 -371.750705) (xy 338.523137 -371.810875)
			(xy 338.506816 -371.839236) (xy 338.50349 -371.845255) (xy 338.499891 -371.858523) (xy 338.499704 -371.865398)
			(xy 338.499704 -372.614698) (xy 338.499896 -372.621571) (xy 338.503504 -372.634834) (xy 338.506816 -372.64086)
			(xy 338.523168 -372.669205) (xy 338.548886 -372.729379) (xy 338.566292 -372.792462) (xy 338.575073 -372.857309)
			(xy 338.575071 -372.890034) (xy 342.004396 -372.890034) (xy 342.004955 -372.857304) (xy 342.013813 -372.792446)
			(xy 342.031305 -372.729366) (xy 342.057115 -372.669208) (xy 342.073484 -372.64086) (xy 342.076812 -372.634842)
			(xy 342.080409 -372.621573) (xy 342.080596 -372.614698) (xy 342.080596 -371.865398) (xy 342.080405 -371.858525)
			(xy 342.076796 -371.845262) (xy 342.073484 -371.839236) (xy 342.057131 -371.81088) (xy 342.031327 -371.750723)
			(xy 342.013834 -371.687645) (xy 342.004969 -371.62279) (xy 342.004396 -371.590062) (xy 342.004968 -371.557333)
			(xy 342.013822 -371.492475) (xy 342.03131 -371.429395) (xy 342.057116 -371.369236) (xy 342.073484 -371.340888)
			(xy 342.076802 -371.334865) (xy 342.080406 -371.3216) (xy 342.080596 -371.314726) (xy 342.080596 -371.028722)
			(xy 342.081143 -371.018602) (xy 342.088856 -370.99989) (xy 342.103123 -370.985534) (xy 342.121787 -370.977706)
			(xy 342.131904 -370.97716) (xy 342.848184 -370.97716) (xy 342.858332 -370.977634) (xy 342.877076 -370.985417)
			(xy 342.891399 -370.999797) (xy 342.899106 -371.018572) (xy 342.899492 -371.028722) (xy 342.899492 -371.314726)
			(xy 342.899675 -371.3216) (xy 342.903289 -371.334863) (xy 342.906604 -371.340888) (xy 342.922965 -371.36924)
			(xy 342.948768 -371.429398) (xy 342.966259 -371.492477) (xy 342.975121 -371.557333) (xy 342.975692 -371.590062)
			(xy 342.975133 -371.622792) (xy 342.966275 -371.68765) (xy 342.948783 -371.75073) (xy 342.922973 -371.810888)
			(xy 342.906604 -371.839236) (xy 342.903277 -371.845255) (xy 342.899679 -371.858523) (xy 342.899492 -371.865398)
			(xy 342.899492 -372.614698) (xy 342.899686 -372.621571) (xy 342.903293 -372.634834) (xy 342.906604 -372.64086)
			(xy 342.922954 -372.669218) (xy 342.94876 -372.729374) (xy 342.966254 -372.792451) (xy 342.975119 -372.857306)
			(xy 342.975692 -372.890034) (xy 342.97512 -372.922763) (xy 342.966266 -372.987621) (xy 342.948778 -373.050702)
			(xy 342.922972 -373.11086) (xy 342.906604 -373.139208) (xy 342.903287 -373.145231) (xy 342.899683 -373.158496)
			(xy 342.899492 -373.16537) (xy 342.899492 -373.451374) (xy 342.898953 -373.461495) (xy 342.89124 -373.48021)
			(xy 342.87697 -373.494566) (xy 342.858302 -373.502392) (xy 342.848184 -373.502936) (xy 342.131904 -373.502936)
			(xy 342.121755 -373.502476) (xy 342.103009 -373.494688) (xy 342.088687 -373.480304) (xy 342.080981 -373.461525)
			(xy 342.080596 -373.451374) (xy 342.080596 -373.16537) (xy 342.080416 -373.158496) (xy 342.0768 -373.145233)
			(xy 342.073484 -373.139208) (xy 342.05712 -373.110858) (xy 342.031318 -373.050699) (xy 342.013828 -372.987619)
			(xy 342.004967 -372.922763) (xy 342.004396 -372.890034) (xy 338.575071 -372.890034) (xy 338.575069 -372.922749)
			(xy 338.566281 -372.987596) (xy 338.548866 -373.050676) (xy 338.523142 -373.110847) (xy 338.506816 -373.139208)
			(xy 338.5035 -373.145232) (xy 338.499895 -373.158496) (xy 338.499704 -373.16537) (xy 338.499704 -373.451374)
			(xy 338.499147 -373.461525) (xy 338.491388 -373.480286) (xy 338.477043 -373.49465) (xy 338.458292 -373.502433)
			(xy 338.448142 -373.502936) (xy 337.731862 -373.502936) (xy 337.721699 -373.502497) (xy 337.702924 -373.494705)
			(xy 337.688559 -373.480323) (xy 337.68079 -373.461538) (xy 337.6803 -373.451374) (xy 337.6803 -373.16537)
			(xy 337.68012 -373.158496) (xy 337.676504 -373.145233) (xy 337.673188 -373.139208) (xy 337.656896 -373.11083)
			(xy 337.631179 -373.050662) (xy 337.613769 -372.987587) (xy 337.604983 -372.922746) (xy 337.604979 -372.857312)
			(xy 337.613757 -372.79247) (xy 337.631159 -372.729393) (xy 337.65687 -372.669222) (xy 337.673188 -372.64086)
			(xy 337.676516 -372.634842) (xy 337.680114 -372.621573) (xy 337.6803 -372.614698) (xy 337.6803 -371.865398)
			(xy 337.680109 -371.858525) (xy 337.6765 -371.845262) (xy 337.673188 -371.839236) (xy 337.656835 -371.810892)
			(xy 337.631123 -371.750716) (xy 337.613721 -371.687634) (xy 337.604942 -371.622787) (xy 336.345948 -371.622787)
			(xy 336.348846 -371.629544) (xy 336.366332 -371.692626) (xy 336.375188 -371.757484) (xy 336.375756 -371.790214)
			(xy 336.375167 -371.822943) (xy 336.366317 -371.8878) (xy 336.348833 -371.95088) (xy 336.323033 -372.011039)
			(xy 336.306668 -372.039388) (xy 336.303355 -372.045414) (xy 336.299749 -372.058677) (xy 336.299556 -372.06555)
			(xy 336.299556 -372.351554) (xy 336.299036 -372.361678) (xy 336.291322 -372.380399) (xy 336.277046 -372.394757)
			(xy 336.258369 -372.402577) (xy 336.248248 -372.403116) (xy 335.531968 -372.403116) (xy 335.521814 -372.402705)
			(xy 335.503064 -372.394902) (xy 335.488742 -372.380502) (xy 335.481041 -372.36171) (xy 335.48066 -372.351554)
			(xy 335.48066 -372.06555) (xy 335.480454 -372.058678) (xy 335.476856 -372.045415) (xy 335.473548 -372.039388)
			(xy 335.457182 -372.011039) (xy 335.431379 -371.95088) (xy 335.41389 -371.8878) (xy 335.40503 -371.822943)
			(xy 335.40446 -371.790214) (xy 334.131759 -371.790214) (xy 334.122889 -371.810888) (xy 334.10652 -371.839236)
			(xy 334.103194 -371.845255) (xy 334.099595 -371.858523) (xy 334.099408 -371.865398) (xy 334.099408 -372.614698)
			(xy 334.099599 -372.621571) (xy 334.103208 -372.634834) (xy 334.10652 -372.64086) (xy 334.122872 -372.669217)
			(xy 334.148676 -372.729374) (xy 334.16617 -372.792451) (xy 334.175035 -372.857306) (xy 334.175608 -372.890034)
			(xy 334.175034 -372.922763) (xy 334.16618 -372.987621) (xy 334.148692 -373.050701) (xy 334.122887 -373.11086)
			(xy 334.10652 -373.139208) (xy 334.103204 -373.145232) (xy 334.099599 -373.158496) (xy 334.099408 -373.16537)
			(xy 334.099408 -373.451374) (xy 334.098854 -373.461493) (xy 334.091143 -373.480205) (xy 334.076878 -373.49456)
			(xy 334.058216 -373.502389) (xy 334.0481 -373.502936) (xy 333.33182 -373.502936) (xy 333.321672 -373.502463)
			(xy 333.302927 -373.494681) (xy 333.288604 -373.4803) (xy 333.280897 -373.461524) (xy 333.280512 -373.451374)
			(xy 333.280512 -373.16537) (xy 333.28033 -373.158496) (xy 333.276715 -373.145233) (xy 333.2734 -373.139208)
			(xy 333.257038 -373.110857) (xy 333.231235 -373.050698) (xy 333.213744 -372.987619) (xy 333.204883 -372.922763)
			(xy 333.204312 -372.890034) (xy 309.717694 -372.890034) (xy 309.717694 -374.422884) (xy 331.004995 -374.422884)
			(xy 331.005 -374.357444) (xy 331.013789 -374.292597) (xy 331.031203 -374.229517) (xy 331.056927 -374.169345)
			(xy 331.073252 -374.140984) (xy 331.076569 -374.13496) (xy 331.080174 -374.121696) (xy 331.080364 -374.114822)
			(xy 331.080364 -373.828818) (xy 331.080779 -373.818644) (xy 331.088563 -373.799845) (xy 331.102952 -373.785458)
			(xy 331.121752 -373.777677) (xy 331.131926 -373.777256) (xy 331.848206 -373.777256) (xy 331.85838 -373.777659)
			(xy 331.877178 -373.78545) (xy 331.891564 -373.799842) (xy 331.899345 -373.818644) (xy 331.899768 -373.828818)
			(xy 331.899768 -374.114822) (xy 331.899956 -374.121695) (xy 331.903567 -374.134958) (xy 331.90688 -374.140984)
			(xy 331.923166 -374.169365) (xy 331.948886 -374.229532) (xy 331.966297 -374.292606) (xy 331.975085 -374.357447)
			(xy 331.97509 -374.422881) (xy 331.966312 -374.487723) (xy 331.94891 -374.5508) (xy 331.923199 -374.610971)
			(xy 331.90688 -374.639332) (xy 331.903552 -374.64535) (xy 331.899955 -374.658619) (xy 331.899768 -374.665494)
			(xy 331.899768 -375.414794) (xy 331.899966 -375.421667) (xy 331.903571 -375.434929) (xy 331.90688 -375.440956)
			(xy 331.923227 -375.469303) (xy 331.948941 -375.529478) (xy 331.966346 -375.59256) (xy 331.975126 -375.657406)
			(xy 331.975122 -375.722845) (xy 331.966336 -375.787691) (xy 331.948924 -375.850771) (xy 331.923204 -375.910942)
			(xy 331.90688 -375.939304) (xy 331.903562 -375.945327) (xy 331.899959 -375.958592) (xy 331.899768 -375.965466)
			(xy 331.899768 -376.25147) (xy 331.899312 -376.261639) (xy 331.891538 -376.280432) (xy 331.877162 -376.294817)
			(xy 331.858375 -376.302604) (xy 331.848206 -376.303032) (xy 331.131926 -376.303032) (xy 331.121752 -376.302614)
			(xy 331.102953 -376.294832) (xy 331.088566 -376.280444) (xy 331.080785 -376.261644) (xy 331.080364 -376.25147)
			(xy 331.080364 -375.965466) (xy 331.080189 -375.958591) (xy 331.07657 -375.945329) (xy 331.073252 -375.939304)
			(xy 331.056955 -375.910929) (xy 331.031234 -375.850761) (xy 331.013823 -375.787685) (xy 331.005036 -375.722843)
			(xy 331.005032 -375.657408) (xy 331.013812 -375.592565) (xy 331.031217 -375.529488) (xy 331.056931 -375.469317)
			(xy 331.073252 -375.440956) (xy 331.076579 -375.434937) (xy 331.080177 -375.421669) (xy 331.080364 -375.414794)
			(xy 331.080364 -374.665494) (xy 331.080179 -374.65862) (xy 331.076566 -374.645357) (xy 331.073252 -374.639332)
			(xy 331.056894 -374.61099) (xy 331.031179 -374.550815) (xy 331.013774 -374.487732) (xy 331.004995 -374.422884)
			(xy 309.717694 -374.422884) (xy 309.717694 -376.790204) (xy 333.204312 -376.790204) (xy 333.204856 -376.757474)
			(xy 333.213718 -376.692615) (xy 333.231215 -376.629534) (xy 333.257028 -376.569377) (xy 333.2734 -376.54103)
			(xy 333.276704 -376.535) (xy 333.280316 -376.52174) (xy 333.280512 -376.514868) (xy 333.280512 -375.765568)
			(xy 333.280331 -375.758694) (xy 333.276715 -375.745431) (xy 333.2734 -375.739406) (xy 333.257037 -375.711055)
			(xy 333.231234 -375.650896) (xy 333.213744 -375.587817) (xy 333.204883 -375.522961) (xy 333.204312 -375.490232)
			(xy 333.204868 -375.457502) (xy 333.213727 -375.392643) (xy 333.23122 -375.329563) (xy 333.25703 -375.269406)
			(xy 333.2734 -375.241058) (xy 333.27673 -375.235041) (xy 333.280326 -375.221771) (xy 333.280512 -375.214896)
			(xy 333.280512 -374.928638) (xy 333.281057 -374.918517) (xy 333.288767 -374.899802) (xy 333.303035 -374.885446)
			(xy 333.321702 -374.87762) (xy 333.33182 -374.877076) (xy 334.0481 -374.877076) (xy 334.058251 -374.877521)
			(xy 334.076999 -374.885312) (xy 334.091321 -374.899701) (xy 334.099025 -374.918485) (xy 334.099408 -374.928638)
			(xy 334.099408 -375.214896) (xy 334.0996 -375.221769) (xy 334.103208 -375.235032) (xy 334.10652 -375.241058)
			(xy 334.122871 -375.269415) (xy 334.148676 -375.329572) (xy 334.166169 -375.392649) (xy 334.175035 -375.457504)
			(xy 334.175608 -375.490232) (xy 334.175033 -375.522961) (xy 334.16618 -375.587819) (xy 334.148692 -375.650899)
			(xy 334.131864 -375.69013) (xy 335.40446 -375.69013) (xy 335.405022 -375.6574) (xy 335.41388 -375.592542)
			(xy 335.431371 -375.529462) (xy 335.457179 -375.469304) (xy 335.473548 -375.440956) (xy 335.476874 -375.434937)
			(xy 335.480473 -375.421669) (xy 335.48066 -375.414794) (xy 335.48066 -374.665494) (xy 335.480475 -374.65862)
			(xy 335.476863 -374.645357) (xy 335.473548 -374.639332) (xy 335.4572 -374.610973) (xy 335.431393 -374.550817)
			(xy 335.413898 -374.487741) (xy 335.405033 -374.422886) (xy 335.40446 -374.390158) (xy 335.405035 -374.357429)
			(xy 335.413889 -374.292571) (xy 335.431376 -374.229491) (xy 335.457181 -374.169332) (xy 335.473548 -374.140984)
			(xy 335.476864 -374.13496) (xy 335.48047 -374.121696) (xy 335.48066 -374.114822) (xy 335.48066 -373.828818)
			(xy 335.481142 -373.81869) (xy 335.488867 -373.799965) (xy 335.503156 -373.785608) (xy 335.521842 -373.777791)
			(xy 335.531968 -373.777256) (xy 336.248248 -373.777256) (xy 336.2584 -373.777682) (xy 336.277145 -373.785485)
			(xy 336.291465 -373.799879) (xy 336.299171 -373.818664) (xy 336.299556 -373.828818) (xy 336.299556 -374.114822)
			(xy 336.299733 -374.121696) (xy 336.303351 -374.134959) (xy 336.306668 -374.140984) (xy 336.323024 -374.169338)
			(xy 336.348829 -374.229496) (xy 336.366321 -374.292574) (xy 336.375184 -374.357429) (xy 336.375756 -374.390158)
			(xy 336.375186 -374.422884) (xy 339.805081 -374.422884) (xy 339.805086 -374.357444) (xy 339.813875 -374.292597)
			(xy 339.831288 -374.229517) (xy 339.857011 -374.169345) (xy 339.873336 -374.140984) (xy 339.876651 -374.13496)
			(xy 339.880257 -374.121696) (xy 339.880448 -374.114822) (xy 339.880448 -373.828818) (xy 339.880879 -373.818646)
			(xy 339.88866 -373.79985) (xy 339.903043 -373.785464) (xy 339.921838 -373.77768) (xy 339.93201 -373.777256)
			(xy 340.64829 -373.777256) (xy 340.658463 -373.777672) (xy 340.677261 -373.785457) (xy 340.691647 -373.799846)
			(xy 340.699429 -373.818645) (xy 340.699852 -373.828818) (xy 340.699852 -374.114822) (xy 340.700029 -374.121696)
			(xy 340.703647 -374.134959) (xy 340.706964 -374.140984) (xy 340.723251 -374.169365) (xy 340.748971 -374.229532)
			(xy 340.766383 -374.292606) (xy 340.775171 -374.357447) (xy 340.775176 -374.422881) (xy 340.775176 -374.422884)
			(xy 344.204871 -374.422884) (xy 344.204876 -374.357444) (xy 344.213664 -374.292598) (xy 344.231077 -374.229518)
			(xy 344.256799 -374.169345) (xy 344.273124 -374.140984) (xy 344.276446 -374.134963) (xy 344.280047 -374.121696)
			(xy 344.280236 -374.114822) (xy 344.280236 -373.828818) (xy 344.280678 -373.818648) (xy 344.288457 -373.799854)
			(xy 344.302837 -373.785468) (xy 344.321628 -373.777682) (xy 344.331798 -373.777256) (xy 345.048078 -373.777256)
			(xy 345.05825 -373.777683) (xy 345.077048 -373.785464) (xy 345.091434 -373.799849) (xy 345.099217 -373.818646)
			(xy 345.09964 -373.828818) (xy 345.09964 -374.114822) (xy 345.099819 -374.121696) (xy 345.103436 -374.134959)
			(xy 345.106752 -374.140984) (xy 345.123039 -374.169365) (xy 345.14876 -374.229531) (xy 345.166173 -374.292606)
			(xy 345.174961 -374.357447) (xy 345.174963 -374.390158) (xy 348.603832 -374.390158) (xy 348.607823 -374.327991)
			(xy 348.619732 -374.266844) (xy 348.639361 -374.207723) (xy 348.66639 -374.151597) (xy 348.700374 -374.099388)
			(xy 348.740756 -374.051953) (xy 348.786872 -374.010072) (xy 348.837964 -373.974432) (xy 348.893195 -373.945618)
			(xy 348.951657 -373.924104) (xy 349.012391 -373.910242) (xy 349.074398 -373.90426) (xy 349.136661 -373.906256)
			(xy 349.198158 -373.916199) (xy 349.257879 -373.933923) (xy 349.314842 -373.95914) (xy 349.368113 -373.991433)
			(xy 349.416818 -374.030273) (xy 349.460155 -374.075023) (xy 349.497415 -374.124947) (xy 349.527984 -374.179226)
			(xy 349.551362 -374.236969) (xy 349.567163 -374.297227) (xy 349.575129 -374.35901) (xy 349.575628 -374.390158)
			(xy 349.575129 -374.421306) (xy 349.574926 -374.422884) (xy 375.004905 -374.422884) (xy 375.00491 -374.357444)
			(xy 375.013699 -374.292597) (xy 375.031114 -374.229517) (xy 375.056838 -374.169345) (xy 375.073164 -374.140984)
			(xy 375.076481 -374.134961) (xy 375.080086 -374.121696) (xy 375.080276 -374.114822) (xy 375.080276 -373.828818)
			(xy 375.080679 -373.818643) (xy 375.088465 -373.799841) (xy 375.102858 -373.785454) (xy 375.121663 -373.777675)
			(xy 375.131838 -373.777256) (xy 375.848118 -373.777256) (xy 375.858279 -373.777719) (xy 375.877052 -373.785503)
			(xy 375.891418 -373.799878) (xy 375.899188 -373.818656) (xy 375.89968 -373.828818) (xy 375.89968 -374.114822)
			(xy 375.899866 -374.121696) (xy 375.903479 -374.134958) (xy 375.906792 -374.140984) (xy 375.923078 -374.169365)
			(xy 375.948797 -374.229532) (xy 375.966208 -374.292607) (xy 375.974995 -374.357447) (xy 375.975 -374.422881)
			(xy 375.966222 -374.487723) (xy 375.948821 -374.5508) (xy 375.92311 -374.61097) (xy 375.906792 -374.639332)
			(xy 375.903465 -374.645351) (xy 375.899867 -374.658619) (xy 375.89968 -374.665494) (xy 375.89968 -375.414794)
			(xy 375.899877 -375.421667) (xy 375.903482 -375.43493) (xy 375.906792 -375.440956) (xy 375.923139 -375.469304)
			(xy 375.948852 -375.529478) (xy 375.966256 -375.59256) (xy 375.975036 -375.657407) (xy 375.975033 -375.722845)
			(xy 375.966246 -375.787691) (xy 375.948835 -375.85077) (xy 375.923115 -375.910942) (xy 375.906792 -375.939304)
			(xy 375.903475 -375.945328) (xy 375.899871 -375.958592) (xy 375.89968 -375.965466) (xy 375.89968 -376.25147)
			(xy 375.899212 -376.261637) (xy 375.89144 -376.280428) (xy 375.877068 -376.294813) (xy 375.858285 -376.302602)
			(xy 375.848118 -376.303032) (xy 375.131838 -376.303032) (xy 375.121665 -376.302604) (xy 375.102866 -376.294826)
			(xy 375.088478 -376.280441) (xy 375.080697 -376.261643) (xy 375.080276 -376.25147) (xy 375.080276 -375.965466)
			(xy 375.0801 -375.958592) (xy 375.076481 -375.945329) (xy 375.073164 -375.939304) (xy 375.056866 -375.910929)
			(xy 375.031145 -375.850761) (xy 375.013733 -375.787685) (xy 375.004946 -375.722843) (xy 375.004943 -375.657408)
			(xy 375.013723 -375.592565) (xy 375.031128 -375.529487) (xy 375.056843 -375.469317) (xy 375.073164 -375.440956)
			(xy 375.076491 -375.434938) (xy 375.080089 -375.421669) (xy 375.080276 -375.414794) (xy 375.080276 -374.665494)
			(xy 375.080089 -374.65862) (xy 375.076478 -374.645358) (xy 375.073164 -374.639332) (xy 375.056805 -374.610991)
			(xy 375.03109 -374.550815) (xy 375.013685 -374.487732) (xy 375.004905 -374.422884) (xy 349.574926 -374.422884)
			(xy 349.567163 -374.483089) (xy 349.551362 -374.543347) (xy 349.527984 -374.60109) (xy 349.497415 -374.655369)
			(xy 349.460155 -374.705293) (xy 349.416818 -374.750043) (xy 349.368113 -374.788883) (xy 349.314842 -374.821176)
			(xy 349.257879 -374.846393) (xy 349.198158 -374.864117) (xy 349.136661 -374.87406) (xy 349.074398 -374.876056)
			(xy 349.012391 -374.870074) (xy 348.951657 -374.856212) (xy 348.893195 -374.834698) (xy 348.837964 -374.805884)
			(xy 348.786872 -374.770244) (xy 348.740756 -374.728363) (xy 348.700374 -374.680928) (xy 348.66639 -374.628719)
			(xy 348.639361 -374.572593) (xy 348.619732 -374.513472) (xy 348.607823 -374.452325) (xy 348.603832 -374.390158)
			(xy 345.174963 -374.390158) (xy 345.174966 -374.422881) (xy 345.166187 -374.487723) (xy 345.148784 -374.550801)
			(xy 345.123072 -374.610971) (xy 345.106752 -374.639332) (xy 345.10343 -374.645353) (xy 345.099828 -374.65862)
			(xy 345.09964 -374.665494) (xy 345.09964 -375.414794) (xy 345.099829 -375.421667) (xy 345.103439 -375.43493)
			(xy 345.106752 -375.440956) (xy 345.1231 -375.469303) (xy 345.148816 -375.529478) (xy 345.166221 -375.592559)
			(xy 345.175002 -375.657406) (xy 345.174998 -375.722845) (xy 345.166211 -375.787691) (xy 345.148799 -375.850771)
			(xy 345.123077 -375.910943) (xy 345.106752 -375.939304) (xy 345.10344 -375.94533) (xy 345.099832 -375.958593)
			(xy 345.09964 -375.965466) (xy 345.09964 -376.25147) (xy 345.099211 -376.261642) (xy 345.091432 -376.280441)
			(xy 345.077047 -376.294827) (xy 345.05825 -376.302609) (xy 345.048078 -376.303032) (xy 344.331798 -376.303032)
			(xy 344.321623 -376.302637) (xy 344.302822 -376.294846) (xy 344.288436 -376.280451) (xy 344.280657 -376.261646)
			(xy 344.280236 -376.25147) (xy 344.280236 -375.965466) (xy 344.280052 -375.958592) (xy 344.276438 -375.94533)
			(xy 344.273124 -375.939304) (xy 344.256828 -375.910929) (xy 344.231108 -375.850761) (xy 344.213698 -375.787685)
			(xy 344.204912 -375.722843) (xy 344.204908 -375.657408) (xy 344.213688 -375.592566) (xy 344.231091 -375.529488)
			(xy 344.256804 -375.469317) (xy 344.273124 -375.440956) (xy 344.276456 -375.43494) (xy 344.28005 -375.42167)
			(xy 344.280236 -375.414794) (xy 344.280236 -374.665494) (xy 344.280042 -374.658621) (xy 344.276435 -374.645358)
			(xy 344.273124 -374.639332) (xy 344.256767 -374.61099) (xy 344.231053 -374.550814) (xy 344.21365 -374.487732)
			(xy 344.204871 -374.422884) (xy 340.775176 -374.422884) (xy 340.766398 -374.487723) (xy 340.748995 -374.5508)
			(xy 340.723283 -374.610971) (xy 340.706964 -374.639332) (xy 340.703643 -374.645354) (xy 340.70004 -374.65862)
			(xy 340.699852 -374.665494) (xy 340.699852 -375.414794) (xy 340.70004 -375.421668) (xy 340.70365 -375.434931)
			(xy 340.706964 -375.440956) (xy 340.723312 -375.469303) (xy 340.749027 -375.529478) (xy 340.766432 -375.592559)
			(xy 340.775212 -375.657406) (xy 340.775209 -375.722845) (xy 340.766421 -375.787691) (xy 340.74901 -375.850771)
			(xy 340.723288 -375.910943) (xy 340.706964 -375.939304) (xy 340.703653 -375.94533) (xy 340.700044 -375.958593)
			(xy 340.699852 -375.965466) (xy 340.699852 -376.25147) (xy 340.699411 -376.261641) (xy 340.691634 -376.280437)
			(xy 340.677254 -376.294823) (xy 340.658461 -376.302607) (xy 340.64829 -376.303032) (xy 339.93201 -376.303032)
			(xy 339.921835 -376.302627) (xy 339.903035 -376.29484) (xy 339.888649 -376.280448) (xy 339.880869 -376.261645)
			(xy 339.880448 -376.25147) (xy 339.880448 -375.965466) (xy 339.880275 -375.958591) (xy 339.876655 -375.945328)
			(xy 339.873336 -375.939304) (xy 339.857039 -375.910929) (xy 339.831319 -375.850761) (xy 339.813909 -375.787685)
			(xy 339.805122 -375.722843) (xy 339.805119 -375.657408) (xy 339.813898 -375.592566) (xy 339.831302 -375.529488)
			(xy 339.857016 -375.469317) (xy 339.873336 -375.440956) (xy 339.876661 -375.434936) (xy 339.880261 -375.421669)
			(xy 339.880448 -375.414794) (xy 339.880448 -374.665494) (xy 339.880265 -374.65862) (xy 339.876651 -374.645357)
			(xy 339.873336 -374.639332) (xy 339.856978 -374.61099) (xy 339.831264 -374.550815) (xy 339.81386 -374.487732)
			(xy 339.805081 -374.422884) (xy 336.375186 -374.422884) (xy 336.375186 -374.422887) (xy 336.366331 -374.487745)
			(xy 336.348841 -374.550825) (xy 336.323036 -374.610984) (xy 336.306668 -374.639332) (xy 336.30334 -374.64535)
			(xy 336.299743 -374.658619) (xy 336.299556 -374.665494) (xy 336.299556 -375.414794) (xy 336.299743 -375.421668)
			(xy 336.303354 -375.434931) (xy 336.306668 -375.440956) (xy 336.323013 -375.469317) (xy 336.348821 -375.529472)
			(xy 336.366316 -375.592548) (xy 336.375183 -375.657402) (xy 336.375756 -375.69013) (xy 336.375174 -375.722859)
			(xy 336.366322 -375.787716) (xy 336.348836 -375.850796) (xy 336.323034 -375.910955) (xy 336.306668 -375.939304)
			(xy 336.30335 -375.945327) (xy 336.299747 -375.958592) (xy 336.299556 -375.965466) (xy 336.299556 -376.25147)
			(xy 336.299049 -376.261595) (xy 336.29133 -376.280317) (xy 336.27705 -376.294674) (xy 336.258371 -376.302494)
			(xy 336.248248 -376.303032) (xy 335.531968 -376.303032) (xy 335.521816 -376.302605) (xy 335.503069 -376.294805)
			(xy 335.488748 -376.280411) (xy 335.481043 -376.261624) (xy 335.48066 -376.25147) (xy 335.48066 -375.965466)
			(xy 335.480486 -375.958591) (xy 335.476866 -375.945328) (xy 335.473548 -375.939304) (xy 335.457189 -375.910951)
			(xy 335.431384 -375.850793) (xy 335.413893 -375.787715) (xy 335.405031 -375.722859) (xy 335.40446 -375.69013)
			(xy 334.131864 -375.69013) (xy 334.122887 -375.711058) (xy 334.10652 -375.739406) (xy 334.103205 -375.74543)
			(xy 334.099599 -375.758694) (xy 334.099408 -375.765568) (xy 334.099408 -376.514868) (xy 334.099611 -376.52174)
			(xy 334.103212 -376.535003) (xy 334.10652 -376.54103) (xy 334.122899 -376.569372) (xy 334.148697 -376.629534)
			(xy 334.166183 -376.692616) (xy 334.17504 -376.757474) (xy 334.17504 -376.757486) (xy 337.604965 -376.757486)
			(xy 337.613748 -376.692642) (xy 337.631153 -376.629563) (xy 337.656868 -376.569392) (xy 337.673188 -376.54103)
			(xy 337.676491 -376.535) (xy 337.680104 -376.52174) (xy 337.6803 -376.514868) (xy 337.6803 -375.765568)
			(xy 337.68012 -375.758694) (xy 337.676504 -375.745431) (xy 337.673188 -375.739406) (xy 337.656894 -375.711029)
			(xy 337.631177 -375.650861) (xy 337.613768 -375.587786) (xy 337.604982 -375.522944) (xy 337.604978 -375.457511)
			(xy 337.613757 -375.392668) (xy 337.631159 -375.329591) (xy 337.656869 -375.26942) (xy 337.673188 -375.241058)
			(xy 337.676517 -375.23504) (xy 337.680114 -375.221771) (xy 337.6803 -375.214896) (xy 337.6803 -374.928638)
			(xy 337.680864 -374.918487) (xy 337.688619 -374.899726) (xy 337.702963 -374.885361) (xy 337.721712 -374.877579)
			(xy 337.731862 -374.877076) (xy 338.448142 -374.877076) (xy 338.458307 -374.8775) (xy 338.477085 -374.885295)
			(xy 338.49145 -374.899683) (xy 338.499216 -374.918472) (xy 338.499704 -374.928638) (xy 338.499704 -375.214896)
			(xy 338.499897 -375.221769) (xy 338.503504 -375.235032) (xy 338.506816 -375.241058) (xy 338.523167 -375.269404)
			(xy 338.548884 -375.329578) (xy 338.566291 -375.39266) (xy 338.575072 -375.457508) (xy 338.575068 -375.522947)
			(xy 338.56628 -375.587794) (xy 338.548866 -375.650874) (xy 338.523142 -375.711045) (xy 338.506816 -375.739406)
			(xy 338.5035 -375.74543) (xy 338.499895 -375.758694) (xy 338.499704 -375.765568) (xy 338.499704 -376.514868)
			(xy 338.499908 -376.52174) (xy 338.503508 -376.535003) (xy 338.506816 -376.54103) (xy 338.523143 -376.569389)
			(xy 338.548863 -376.62956) (xy 338.566272 -376.692639) (xy 338.575056 -376.757485) (xy 338.575056 -376.790204)
			(xy 342.004396 -376.790204) (xy 342.004941 -376.757474) (xy 342.013803 -376.692615) (xy 342.031299 -376.629535)
			(xy 342.057112 -376.569377) (xy 342.073484 -376.54103) (xy 342.076787 -376.535) (xy 342.0804 -376.52174)
			(xy 342.080596 -376.514868) (xy 342.080596 -375.765568) (xy 342.080417 -375.758694) (xy 342.0768 -375.745431)
			(xy 342.073484 -375.739406) (xy 342.057119 -375.711056) (xy 342.031318 -375.650897) (xy 342.013828 -375.587818)
			(xy 342.004967 -375.522961) (xy 342.004396 -375.490232) (xy 342.004954 -375.457502) (xy 342.013813 -375.392644)
			(xy 342.031305 -375.329564) (xy 342.057115 -375.269406) (xy 342.073484 -375.241058) (xy 342.076813 -375.23504)
			(xy 342.08041 -375.221771) (xy 342.080596 -375.214896) (xy 342.080596 -374.928638) (xy 342.081157 -374.918519)
			(xy 342.088864 -374.899807) (xy 342.103127 -374.885451) (xy 342.121789 -374.877623) (xy 342.131904 -374.877076)
			(xy 342.848184 -374.877076) (xy 342.858334 -374.877534) (xy 342.877082 -374.88532) (xy 342.891405 -374.899705)
			(xy 342.899109 -374.918486) (xy 342.899492 -374.928638) (xy 342.899492 -375.214896) (xy 342.899686 -375.221769)
			(xy 342.903293 -375.235032) (xy 342.906604 -375.241058) (xy 342.922953 -375.269416) (xy 342.948759 -375.329573)
			(xy 342.966253 -375.392649) (xy 342.975119 -375.457504) (xy 342.975692 -375.490232) (xy 342.975119 -375.522961)
			(xy 342.966266 -375.587819) (xy 342.948777 -375.6509) (xy 342.922972 -375.711058) (xy 342.906604 -375.739406)
			(xy 342.903287 -375.74543) (xy 342.899683 -375.758694) (xy 342.899492 -375.765568) (xy 342.899492 -376.514868)
			(xy 342.899697 -376.52174) (xy 342.903296 -376.535003) (xy 342.906604 -376.54103) (xy 342.922982 -376.569372)
			(xy 342.948781 -376.629534) (xy 342.966267 -376.692616) (xy 342.975124 -376.757474) (xy 342.975692 -376.790204)
			(xy 342.975152 -376.822922) (xy 346.405038 -376.822922) (xy 346.405038 -376.757485) (xy 346.413821 -376.69264)
			(xy 346.43123 -376.629562) (xy 346.456949 -376.569391) (xy 346.473272 -376.54103) (xy 346.476574 -376.534999)
			(xy 346.480188 -376.52174) (xy 346.480384 -376.514868) (xy 346.480384 -375.765568) (xy 346.480206 -375.758694)
			(xy 346.476589 -375.745431) (xy 346.473272 -375.739406) (xy 346.456976 -375.71103) (xy 346.431254 -375.650863)
			(xy 346.413842 -375.587787) (xy 346.405054 -375.522945) (xy 346.40505 -375.45751) (xy 346.413831 -375.392667)
			(xy 346.431236 -375.329589) (xy 346.456951 -375.269419) (xy 346.473272 -375.241058) (xy 346.4766 -375.23504)
			(xy 346.480198 -375.221771) (xy 346.480384 -375.214896) (xy 346.480384 -374.928638) (xy 346.480796 -374.918463)
			(xy 346.488577 -374.899661) (xy 346.502967 -374.885273) (xy 346.521771 -374.877495) (xy 346.531946 -374.877076)
			(xy 347.248226 -374.877076) (xy 347.258404 -374.877443) (xy 347.277207 -374.885244) (xy 347.291592 -374.899647)
			(xy 347.299369 -374.918459) (xy 347.299788 -374.928638) (xy 347.299788 -375.214896) (xy 347.299983 -375.221769)
			(xy 347.303589 -375.235032) (xy 347.3069 -375.241058) (xy 347.323248 -375.269405) (xy 347.348961 -375.32958)
			(xy 347.366365 -375.392661) (xy 347.375144 -375.457508) (xy 347.375141 -375.522947) (xy 347.366354 -375.587792)
			(xy 347.348943 -375.650872) (xy 347.332163 -375.69013) (xy 348.603832 -375.69013) (xy 348.607823 -375.627963)
			(xy 348.619732 -375.566816) (xy 348.639361 -375.507695) (xy 348.66639 -375.451569) (xy 348.700374 -375.39936)
			(xy 348.740756 -375.351925) (xy 348.786872 -375.310044) (xy 348.837964 -375.274404) (xy 348.893195 -375.24559)
			(xy 348.951657 -375.224076) (xy 349.012391 -375.210214) (xy 349.074398 -375.204232) (xy 349.136661 -375.206228)
			(xy 349.198158 -375.216171) (xy 349.257879 -375.233895) (xy 349.314842 -375.259112) (xy 349.368113 -375.291405)
			(xy 349.416818 -375.330245) (xy 349.460155 -375.374995) (xy 349.497415 -375.424919) (xy 349.527984 -375.479198)
			(xy 349.532451 -375.490232) (xy 350.80398 -375.490232) (xy 350.807971 -375.428065) (xy 350.81988 -375.366918)
			(xy 350.839509 -375.307797) (xy 350.866538 -375.251671) (xy 350.900522 -375.199462) (xy 350.940904 -375.152027)
			(xy 350.98702 -375.110146) (xy 351.038112 -375.074506) (xy 351.093343 -375.045692) (xy 351.151805 -375.024178)
			(xy 351.212539 -375.010316) (xy 351.274546 -375.004334) (xy 351.336809 -375.00633) (xy 351.398306 -375.016273)
			(xy 351.458027 -375.033997) (xy 351.51499 -375.059214) (xy 351.568261 -375.091507) (xy 351.616966 -375.130347)
			(xy 351.660303 -375.175097) (xy 351.697563 -375.225021) (xy 351.728132 -375.2793) (xy 351.75151 -375.337043)
			(xy 351.767311 -375.397301) (xy 351.775277 -375.459084) (xy 351.775776 -375.490232) (xy 351.775277 -375.52138)
			(xy 351.767311 -375.583163) (xy 351.75151 -375.643421) (xy 351.728132 -375.701164) (xy 351.697563 -375.755443)
			(xy 351.660303 -375.805367) (xy 351.616966 -375.850117) (xy 351.568261 -375.888957) (xy 351.51499 -375.92125)
			(xy 351.458027 -375.946467) (xy 351.398306 -375.964191) (xy 351.336809 -375.974134) (xy 351.274546 -375.97613)
			(xy 351.212539 -375.970148) (xy 351.151805 -375.956286) (xy 351.093343 -375.934772) (xy 351.038112 -375.905958)
			(xy 350.98702 -375.870318) (xy 350.940904 -375.828437) (xy 350.900522 -375.781002) (xy 350.866538 -375.728793)
			(xy 350.839509 -375.672667) (xy 350.81988 -375.613546) (xy 350.807971 -375.552399) (xy 350.80398 -375.490232)
			(xy 349.532451 -375.490232) (xy 349.551362 -375.536941) (xy 349.567163 -375.597199) (xy 349.575129 -375.658982)
			(xy 349.575628 -375.69013) (xy 349.575129 -375.721278) (xy 349.567163 -375.783061) (xy 349.551362 -375.843319)
			(xy 349.527984 -375.901062) (xy 349.497415 -375.955341) (xy 349.460155 -376.005265) (xy 349.416818 -376.050015)
			(xy 349.368113 -376.088855) (xy 349.314842 -376.121148) (xy 349.257879 -376.146365) (xy 349.198158 -376.164089)
			(xy 349.136661 -376.174032) (xy 349.074398 -376.176028) (xy 349.012391 -376.170046) (xy 348.951657 -376.156184)
			(xy 348.893195 -376.13467) (xy 348.837964 -376.105856) (xy 348.786872 -376.070216) (xy 348.740756 -376.028335)
			(xy 348.700374 -375.9809) (xy 348.66639 -375.928691) (xy 348.639361 -375.872565) (xy 348.619732 -375.813444)
			(xy 348.607823 -375.752297) (xy 348.603832 -375.69013) (xy 347.332163 -375.69013) (xy 347.323223 -375.711044)
			(xy 347.3069 -375.739406) (xy 347.303583 -375.74543) (xy 347.299979 -375.758694) (xy 347.299788 -375.765568)
			(xy 347.299788 -376.514868) (xy 347.299993 -376.52174) (xy 347.303593 -376.535003) (xy 347.3069 -376.54103)
			(xy 347.323224 -376.56939) (xy 347.34894 -376.629562) (xy 347.366346 -376.692641) (xy 347.375128 -376.757485)
			(xy 347.375128 -376.790204) (xy 350.80398 -376.790204) (xy 350.807971 -376.728037) (xy 350.81988 -376.66689)
			(xy 350.839509 -376.607769) (xy 350.866538 -376.551643) (xy 350.900522 -376.499434) (xy 350.940904 -376.451999)
			(xy 350.98702 -376.410118) (xy 351.038112 -376.374478) (xy 351.093343 -376.345664) (xy 351.151805 -376.32415)
			(xy 351.212539 -376.310288) (xy 351.274546 -376.304306) (xy 351.336809 -376.306302) (xy 351.398306 -376.316245)
			(xy 351.458027 -376.333969) (xy 351.51499 -376.359186) (xy 351.568261 -376.391479) (xy 351.616966 -376.430319)
			(xy 351.660303 -376.475069) (xy 351.697563 -376.524993) (xy 351.728132 -376.579272) (xy 351.75151 -376.637015)
			(xy 351.767311 -376.697273) (xy 351.775277 -376.759056) (xy 351.775776 -376.790204) (xy 377.204224 -376.790204)
			(xy 377.204766 -376.757474) (xy 377.213628 -376.692614) (xy 377.231126 -376.629534) (xy 377.25694 -376.569377)
			(xy 377.273312 -376.54103) (xy 377.276617 -376.535001) (xy 377.280229 -376.521741) (xy 377.280424 -376.514868)
			(xy 377.280424 -375.765568) (xy 377.280241 -375.758694) (xy 377.276626 -375.745431) (xy 377.273312 -375.739406)
			(xy 377.25695 -375.711055) (xy 377.231147 -375.650896) (xy 377.213656 -375.587817) (xy 377.204795 -375.522961)
			(xy 377.204224 -375.490232) (xy 377.204779 -375.457502) (xy 377.213637 -375.392643) (xy 377.231131 -375.329563)
			(xy 377.256942 -375.269406) (xy 377.273312 -375.241058) (xy 377.276643 -375.235041) (xy 377.280238 -375.221771)
			(xy 377.280424 -375.214896) (xy 377.280424 -374.928638) (xy 377.280957 -374.918516) (xy 377.28867 -374.899799)
			(xy 377.302942 -374.885442) (xy 377.321613 -374.877618) (xy 377.331732 -374.877076) (xy 378.048012 -374.877076)
			(xy 378.058164 -374.877511) (xy 378.076912 -374.885306) (xy 378.091234 -374.899698) (xy 378.098938 -374.918484)
			(xy 378.09932 -374.928638) (xy 378.09932 -375.214896) (xy 378.099511 -375.221769) (xy 378.10312 -375.235032)
			(xy 378.106432 -375.241058) (xy 378.122774 -375.26942) (xy 378.148583 -375.329574) (xy 378.16608 -375.39265)
			(xy 378.174947 -375.457504) (xy 378.17552 -375.490232) (xy 378.174943 -375.522961) (xy 378.16609 -375.587819)
			(xy 378.148603 -375.650899) (xy 378.131775 -375.69013) (xy 379.404372 -375.69013) (xy 379.404932 -375.6574)
			(xy 379.41379 -375.592542) (xy 379.431282 -375.529462) (xy 379.457091 -375.469304) (xy 379.47346 -375.440956)
			(xy 379.476787 -375.434937) (xy 379.480385 -375.421669) (xy 379.480572 -375.414794) (xy 379.480572 -374.665494)
			(xy 379.480386 -374.65862) (xy 379.476774 -374.645357) (xy 379.47346 -374.639332) (xy 379.457113 -374.610973)
			(xy 379.431305 -374.550817) (xy 379.41381 -374.487741) (xy 379.404945 -374.422886) (xy 379.404372 -374.390158)
			(xy 379.404945 -374.357429) (xy 379.413799 -374.292571) (xy 379.431287 -374.229491) (xy 379.457092 -374.169332)
			(xy 379.47346 -374.140984) (xy 379.476777 -374.13496) (xy 379.480382 -374.121696) (xy 379.480572 -374.114822)
			(xy 379.480572 -373.828818) (xy 379.481042 -373.818688) (xy 379.48877 -373.799962) (xy 379.503062 -373.785604)
			(xy 379.521753 -373.777789) (xy 379.53188 -373.777256) (xy 380.24816 -373.777256) (xy 380.258306 -373.777754)
			(xy 380.277049 -373.785528) (xy 380.291372 -373.799901) (xy 380.299081 -373.818671) (xy 380.299468 -373.828818)
			(xy 380.299468 -374.114822) (xy 380.299656 -374.121695) (xy 380.303267 -374.134958) (xy 380.30658 -374.140984)
			(xy 380.322937 -374.169338) (xy 380.348742 -374.229496) (xy 380.366234 -374.292574) (xy 380.375096 -374.357429)
			(xy 380.375668 -374.390158) (xy 380.375097 -374.422884) (xy 383.804991 -374.422884) (xy 383.804996 -374.357444)
			(xy 383.813785 -374.292597) (xy 383.831199 -374.229517) (xy 383.856923 -374.169345) (xy 383.873248 -374.140984)
			(xy 383.876564 -374.13496) (xy 383.88017 -374.121696) (xy 383.88036 -374.114822) (xy 383.88036 -373.828818)
			(xy 383.880779 -373.818645) (xy 383.888562 -373.799846) (xy 383.90295 -373.78546) (xy 383.921749 -373.777678)
			(xy 383.931922 -373.777256) (xy 384.648202 -373.777256) (xy 384.658376 -373.777663) (xy 384.677174 -373.785452)
			(xy 384.69156 -373.799843) (xy 384.699341 -373.818644) (xy 384.699764 -373.828818) (xy 384.699764 -374.114822)
			(xy 384.699952 -374.121695) (xy 384.703564 -374.134958) (xy 384.706876 -374.140984) (xy 384.723162 -374.169365)
			(xy 384.748882 -374.229532) (xy 384.766294 -374.292606) (xy 384.775081 -374.357447) (xy 384.775086 -374.422881)
			(xy 384.775086 -374.422884) (xy 388.204781 -374.422884) (xy 388.204786 -374.357444) (xy 388.213575 -374.292597)
			(xy 388.230988 -374.229517) (xy 388.256711 -374.169345) (xy 388.273036 -374.140984) (xy 388.276351 -374.13496)
			(xy 388.279957 -374.121696) (xy 388.280148 -374.114822) (xy 388.280148 -373.828818) (xy 388.280579 -373.818646)
			(xy 388.28836 -373.79985) (xy 388.302743 -373.785464) (xy 388.321538 -373.77768) (xy 388.33171 -373.777256)
			(xy 389.04799 -373.777256) (xy 389.058163 -373.777672) (xy 389.076961 -373.785457) (xy 389.091347 -373.799846)
			(xy 389.099129 -373.818645) (xy 389.099552 -373.828818) (xy 389.099552 -374.114822) (xy 389.099729 -374.121696)
			(xy 389.103347 -374.134959) (xy 389.106664 -374.140984) (xy 389.122951 -374.169365) (xy 389.148671 -374.229532)
			(xy 389.166083 -374.292606) (xy 389.174871 -374.357447) (xy 389.174873 -374.390158) (xy 392.603744 -374.390158)
			(xy 392.607735 -374.327991) (xy 392.619644 -374.266844) (xy 392.639273 -374.207723) (xy 392.666302 -374.151597)
			(xy 392.700286 -374.099388) (xy 392.740668 -374.051953) (xy 392.786784 -374.010072) (xy 392.837876 -373.974432)
			(xy 392.893107 -373.945618) (xy 392.951569 -373.924104) (xy 393.012303 -373.910242) (xy 393.07431 -373.90426)
			(xy 393.136573 -373.906256) (xy 393.19807 -373.916199) (xy 393.257791 -373.933923) (xy 393.314754 -373.95914)
			(xy 393.368025 -373.991433) (xy 393.41673 -374.030273) (xy 393.460067 -374.075023) (xy 393.497327 -374.124947)
			(xy 393.519805 -374.16486) (xy 403.928832 -374.16486) (xy 403.932903 -374.109238) (xy 403.945029 -374.054801)
			(xy 403.964952 -374.00271) (xy 403.992248 -373.954075) (xy 404.026334 -373.909932) (xy 404.066483 -373.871223)
			(xy 404.111841 -373.838772) (xy 404.161441 -373.813271) (xy 404.214225 -373.795264) (xy 404.269068 -373.785134)
			(xy 404.324802 -373.783097) (xy 404.380239 -373.789197) (xy 404.434196 -373.803303) (xy 404.485525 -373.825115)
			(xy 404.533131 -373.854169) (xy 404.575999 -373.889844) (xy 404.613216 -373.931381) (xy 404.643989 -373.977894)
			(xy 404.667661 -374.028391) (xy 404.683729 -374.081798) (xy 404.691849 -374.136974) (xy 404.692358 -374.16486)
			(xy 404.691849 -374.192746) (xy 404.683729 -374.247922) (xy 404.667661 -374.301329) (xy 404.643989 -374.351826)
			(xy 404.613216 -374.398339) (xy 404.575999 -374.439876) (xy 404.533131 -374.475551) (xy 404.485525 -374.504605)
			(xy 404.434196 -374.526417) (xy 404.380239 -374.540523) (xy 404.324802 -374.546623) (xy 404.269068 -374.544586)
			(xy 404.214225 -374.534456) (xy 404.161441 -374.516449) (xy 404.111841 -374.490948) (xy 404.066483 -374.458497)
			(xy 404.026334 -374.419788) (xy 403.992248 -374.375645) (xy 403.964952 -374.32701) (xy 403.945029 -374.274919)
			(xy 403.932903 -374.220482) (xy 403.928832 -374.16486) (xy 393.519805 -374.16486) (xy 393.527896 -374.179226)
			(xy 393.551274 -374.236969) (xy 393.567075 -374.297227) (xy 393.575041 -374.35901) (xy 393.57554 -374.390158)
			(xy 393.575041 -374.421306) (xy 393.567075 -374.483089) (xy 393.551274 -374.543347) (xy 393.527896 -374.60109)
			(xy 393.497327 -374.655369) (xy 393.462037 -374.702653) (xy 405.266855 -374.702653) (xy 405.266855 -374.648147)
			(xy 405.274612 -374.594195) (xy 405.289969 -374.541897) (xy 405.312612 -374.492317) (xy 405.34208 -374.446463)
			(xy 405.377775 -374.40527) (xy 405.418968 -374.369577) (xy 405.464822 -374.340109) (xy 405.514403 -374.317467)
			(xy 405.566701 -374.302111) (xy 405.620653 -374.294355) (xy 405.647906 -374.293892) (xy 405.64816 -374.293892)
			(xy 405.676552 -374.294419) (xy 405.732706 -374.302865) (xy 405.78699 -374.319533) (xy 405.838208 -374.344055)
			(xy 405.885231 -374.375889) (xy 405.906478 -374.39473) (xy 405.913844 -374.401588) (xy 405.93264 -374.408446)
			(xy 406.014682 -374.405144) (xy 406.02457 -374.404284) (xy 406.042608 -374.396051) (xy 406.049734 -374.389142)
			(xy 406.049988 -374.388888) (xy 406.068094 -374.369853) (xy 406.108661 -374.336473) (xy 406.153427 -374.308978)
			(xy 406.201543 -374.287887) (xy 406.252098 -374.273602) (xy 406.304136 -374.266391) (xy 406.330404 -374.265952)
			(xy 406.357652 -374.266518) (xy 406.411594 -374.274275) (xy 406.463882 -374.289628) (xy 406.513454 -374.312267)
			(xy 406.559299 -374.341731) (xy 406.600484 -374.377418) (xy 406.636172 -374.418604) (xy 406.665634 -374.46445)
			(xy 406.688273 -374.514021) (xy 406.703626 -374.56631) (xy 406.711382 -374.620252) (xy 406.711382 -374.674748)
			(xy 406.703626 -374.72869) (xy 406.688273 -374.780979) (xy 406.665634 -374.83055) (xy 406.636172 -374.876396)
			(xy 406.600484 -374.917582) (xy 406.559299 -374.953269) (xy 406.513454 -374.982733) (xy 406.463882 -375.005372)
			(xy 406.411594 -375.020725) (xy 406.357652 -375.028482) (xy 406.330404 -375.028968) (xy 406.33015 -375.028968)
			(xy 406.301757 -375.028445) (xy 406.245603 -375.019999) (xy 406.191318 -375.003331) (xy 406.1401 -374.978809)
			(xy 406.093079 -374.946972) (xy 406.071832 -374.92813) (xy 406.064466 -374.921272) (xy 406.04567 -374.914414)
			(xy 405.963628 -374.917716) (xy 405.953738 -374.918564) (xy 405.935699 -374.926804) (xy 405.928576 -374.933718)
			(xy 405.928322 -374.933972) (xy 405.910204 -374.952995) (xy 405.86964 -374.986377) (xy 405.824877 -375.013875)
			(xy 405.776763 -375.034968) (xy 405.72621 -375.049256) (xy 405.674173 -375.056468) (xy 405.647906 -375.056908)
			(xy 405.620653 -375.056445) (xy 405.566701 -375.048689) (xy 405.514403 -375.033333) (xy 405.464822 -375.010691)
			(xy 405.418968 -374.981223) (xy 405.377775 -374.94553) (xy 405.34208 -374.904337) (xy 405.312612 -374.858483)
			(xy 405.289969 -374.808903) (xy 405.274612 -374.756605) (xy 405.266855 -374.702653) (xy 393.462037 -374.702653)
			(xy 393.460067 -374.705293) (xy 393.41673 -374.750043) (xy 393.368025 -374.788883) (xy 393.314754 -374.821176)
			(xy 393.257791 -374.846393) (xy 393.19807 -374.864117) (xy 393.136573 -374.87406) (xy 393.07431 -374.876056)
			(xy 393.012303 -374.870074) (xy 392.951569 -374.856212) (xy 392.893107 -374.834698) (xy 392.837876 -374.805884)
			(xy 392.786784 -374.770244) (xy 392.740668 -374.728363) (xy 392.700286 -374.680928) (xy 392.666302 -374.628719)
			(xy 392.639273 -374.572593) (xy 392.619644 -374.513472) (xy 392.607735 -374.452325) (xy 392.603744 -374.390158)
			(xy 389.174873 -374.390158) (xy 389.174876 -374.422881) (xy 389.166098 -374.487723) (xy 389.148695 -374.5508)
			(xy 389.122983 -374.610971) (xy 389.106664 -374.639332) (xy 389.103343 -374.645354) (xy 389.09974 -374.65862)
			(xy 389.099552 -374.665494) (xy 389.099552 -375.414794) (xy 389.09974 -375.421668) (xy 389.10335 -375.434931)
			(xy 389.106664 -375.440956) (xy 389.123012 -375.469303) (xy 389.148727 -375.529478) (xy 389.166132 -375.592559)
			(xy 389.174912 -375.657406) (xy 389.174909 -375.722845) (xy 389.166121 -375.787691) (xy 389.14871 -375.850771)
			(xy 389.122988 -375.910943) (xy 389.106664 -375.939304) (xy 389.103353 -375.94533) (xy 389.099744 -375.958593)
			(xy 389.099552 -375.965466) (xy 389.099552 -376.25147) (xy 389.099111 -376.261641) (xy 389.091334 -376.280437)
			(xy 389.076954 -376.294823) (xy 389.058161 -376.302607) (xy 389.04799 -376.303032) (xy 388.33171 -376.303032)
			(xy 388.321535 -376.302627) (xy 388.302735 -376.29484) (xy 388.288349 -376.280448) (xy 388.280569 -376.261645)
			(xy 388.280148 -376.25147) (xy 388.280148 -375.965466) (xy 388.279975 -375.958591) (xy 388.276355 -375.945328)
			(xy 388.273036 -375.939304) (xy 388.256739 -375.910929) (xy 388.231019 -375.850761) (xy 388.213609 -375.787685)
			(xy 388.204822 -375.722843) (xy 388.204819 -375.657408) (xy 388.213598 -375.592566) (xy 388.231002 -375.529488)
			(xy 388.256716 -375.469317) (xy 388.273036 -375.440956) (xy 388.276361 -375.434936) (xy 388.279961 -375.421669)
			(xy 388.280148 -375.414794) (xy 388.280148 -374.665494) (xy 388.279965 -374.65862) (xy 388.276351 -374.645357)
			(xy 388.273036 -374.639332) (xy 388.256678 -374.61099) (xy 388.230964 -374.550815) (xy 388.21356 -374.487732)
			(xy 388.204781 -374.422884) (xy 384.775086 -374.422884) (xy 384.766308 -374.487723) (xy 384.748906 -374.5508)
			(xy 384.723195 -374.610971) (xy 384.706876 -374.639332) (xy 384.703548 -374.64535) (xy 384.699951 -374.658619)
			(xy 384.699764 -374.665494) (xy 384.699764 -375.414794) (xy 384.699963 -375.421667) (xy 384.703567 -375.434929)
			(xy 384.706876 -375.440956) (xy 384.723223 -375.469303) (xy 384.748938 -375.529478) (xy 384.766342 -375.59256)
			(xy 384.775122 -375.657406) (xy 384.775119 -375.722845) (xy 384.766332 -375.787691) (xy 384.748921 -375.850771)
			(xy 384.7232 -375.910943) (xy 384.706876 -375.939304) (xy 384.703558 -375.945327) (xy 384.699955 -375.958592)
			(xy 384.699764 -375.965466) (xy 384.699764 -376.25147) (xy 384.699311 -376.261639) (xy 384.691537 -376.280433)
			(xy 384.67716 -376.294819) (xy 384.658371 -376.302605) (xy 384.648202 -376.303032) (xy 383.931922 -376.303032)
			(xy 383.921748 -376.302617) (xy 383.902948 -376.294834) (xy 383.888562 -376.280445) (xy 383.880781 -376.261644)
			(xy 383.88036 -376.25147) (xy 383.88036 -375.965466) (xy 383.880186 -375.958591) (xy 383.876566 -375.945328)
			(xy 383.873248 -375.939304) (xy 383.856951 -375.910929) (xy 383.83123 -375.850761) (xy 383.813819 -375.787685)
			(xy 383.805032 -375.722843) (xy 383.805029 -375.657408) (xy 383.813809 -375.592565) (xy 383.831213 -375.529488)
			(xy 383.856927 -375.469317) (xy 383.873248 -375.440956) (xy 383.876574 -375.434937) (xy 383.880173 -375.421669)
			(xy 383.88036 -375.414794) (xy 383.88036 -374.665494) (xy 383.880175 -374.65862) (xy 383.876563 -374.645357)
			(xy 383.873248 -374.639332) (xy 383.85689 -374.61099) (xy 383.831175 -374.550815) (xy 383.813771 -374.487732)
			(xy 383.804991 -374.422884) (xy 380.375097 -374.422884) (xy 380.375097 -374.422887) (xy 380.366241 -374.487745)
			(xy 380.348752 -374.550825) (xy 380.322947 -374.610984) (xy 380.30658 -374.639332) (xy 380.303252 -374.64535)
			(xy 380.299655 -374.658619) (xy 380.299468 -374.665494) (xy 380.299468 -375.414794) (xy 380.299666 -375.421667)
			(xy 380.303271 -375.434929) (xy 380.30658 -375.440956) (xy 380.322926 -375.469316) (xy 380.348733 -375.529471)
			(xy 380.366228 -375.592548) (xy 380.375095 -375.657402) (xy 380.375668 -375.69013) (xy 380.375084 -375.722859)
			(xy 380.366232 -375.787716) (xy 380.348747 -375.850796) (xy 380.322946 -375.910955) (xy 380.30658 -375.939304)
			(xy 380.303262 -375.945327) (xy 380.299659 -375.958592) (xy 380.299468 -375.965466) (xy 380.299468 -376.25147)
			(xy 380.298949 -376.261594) (xy 380.291233 -376.280313) (xy 380.276956 -376.29467) (xy 380.258281 -376.302492)
			(xy 380.24816 -376.303032) (xy 379.53188 -376.303032) (xy 379.521729 -376.302596) (xy 379.502982 -376.294799)
			(xy 379.48866 -376.280408) (xy 379.480955 -376.261623) (xy 379.480572 -376.25147) (xy 379.480572 -375.965466)
			(xy 379.480397 -375.958591) (xy 379.476778 -375.945328) (xy 379.47346 -375.939304) (xy 379.457102 -375.910951)
			(xy 379.431297 -375.850793) (xy 379.413805 -375.787715) (xy 379.404943 -375.722859) (xy 379.404372 -375.69013)
			(xy 378.131775 -375.69013) (xy 378.122799 -375.711057) (xy 378.106432 -375.739406) (xy 378.103118 -375.745431)
			(xy 378.099512 -375.758694) (xy 378.09932 -375.765568) (xy 378.09932 -376.514868) (xy 378.099522 -376.521741)
			(xy 378.103123 -376.535003) (xy 378.106432 -376.54103) (xy 378.122803 -376.569376) (xy 378.148605 -376.629536)
			(xy 378.166093 -376.692617) (xy 378.174951 -376.757475) (xy 378.17552 -376.790204) (xy 378.174976 -376.822921)
			(xy 381.604876 -376.822921) (xy 381.604876 -376.757485) (xy 381.613658 -376.692642) (xy 381.631064 -376.629563)
			(xy 381.656779 -376.569392) (xy 381.6731 -376.54103) (xy 381.676404 -376.535) (xy 381.680016 -376.52174)
			(xy 381.680212 -376.514868) (xy 381.680212 -375.765568) (xy 381.680031 -375.758694) (xy 381.676415 -375.745431)
			(xy 381.6731 -375.739406) (xy 381.656806 -375.711029) (xy 381.631088 -375.650861) (xy 381.613678 -375.587786)
			(xy 381.604892 -375.522944) (xy 381.604888 -375.45751) (xy 381.613667 -375.392668) (xy 381.63107 -375.329591)
			(xy 381.656781 -375.26942) (xy 381.6731 -375.241058) (xy 381.67643 -375.235041) (xy 381.680026 -375.221771)
			(xy 381.680212 -375.214896) (xy 381.680212 -374.928638) (xy 381.680694 -374.918472) (xy 381.688462 -374.899683)
			(xy 381.702829 -374.885298) (xy 381.721609 -374.877507) (xy 381.731774 -374.877076) (xy 382.448054 -374.877076)
			(xy 382.458227 -374.877502) (xy 382.477028 -374.885279) (xy 382.491416 -374.899665) (xy 382.499196 -374.918465)
			(xy 382.499616 -374.928638) (xy 382.499616 -375.214896) (xy 382.499808 -375.221769) (xy 382.503416 -375.235032)
			(xy 382.506728 -375.241058) (xy 382.523078 -375.269404) (xy 382.548795 -375.329578) (xy 382.566202 -375.39266)
			(xy 382.574982 -375.457508) (xy 382.574979 -375.522947) (xy 382.56619 -375.587794) (xy 382.548777 -375.650874)
			(xy 382.523053 -375.711045) (xy 382.506728 -375.739406) (xy 382.503413 -375.745431) (xy 382.499807 -375.758694)
			(xy 382.499616 -375.765568) (xy 382.499616 -376.514868) (xy 382.499818 -376.52174) (xy 382.503419 -376.535003)
			(xy 382.506728 -376.54103) (xy 382.523055 -376.569389) (xy 382.548774 -376.62956) (xy 382.566183 -376.69264)
			(xy 382.574966 -376.757485) (xy 382.574966 -376.790204) (xy 386.004308 -376.790204) (xy 386.004852 -376.757474)
			(xy 386.013714 -376.692615) (xy 386.031211 -376.629535) (xy 386.057025 -376.569377) (xy 386.073396 -376.54103)
			(xy 386.0767 -376.535) (xy 386.080312 -376.52174) (xy 386.080508 -376.514868) (xy 386.080508 -375.765568)
			(xy 386.080327 -375.758694) (xy 386.076711 -375.745431) (xy 386.073396 -375.739406) (xy 386.057032 -375.711056)
			(xy 386.03123 -375.650897) (xy 386.01374 -375.587817) (xy 386.004879 -375.522961) (xy 386.004308 -375.490232)
			(xy 386.004865 -375.457502) (xy 386.013723 -375.392644) (xy 386.031216 -375.329563) (xy 386.057026 -375.269406)
			(xy 386.073396 -375.241058) (xy 386.076725 -375.235041) (xy 386.080322 -375.221771) (xy 386.080508 -375.214896)
			(xy 386.080508 -374.928638) (xy 386.081057 -374.918518) (xy 386.088766 -374.899804) (xy 386.103033 -374.885447)
			(xy 386.121699 -374.877621) (xy 386.131816 -374.877076) (xy 386.848096 -374.877076) (xy 386.858247 -374.877524)
			(xy 386.876995 -374.885314) (xy 386.891317 -374.899702) (xy 386.899021 -374.918485) (xy 386.899404 -374.928638)
			(xy 386.899404 -375.214896) (xy 386.899597 -375.221769) (xy 386.903204 -375.235032) (xy 386.906516 -375.241058)
			(xy 386.922866 -375.269416) (xy 386.948672 -375.329572) (xy 386.966165 -375.392649) (xy 386.975031 -375.457504)
			(xy 386.975604 -375.490232) (xy 386.97503 -375.522961) (xy 386.966176 -375.587819) (xy 386.948688 -375.650899)
			(xy 386.922883 -375.711058) (xy 386.906516 -375.739406) (xy 386.9032 -375.74543) (xy 386.899595 -375.758694)
			(xy 386.899404 -375.765568) (xy 386.899404 -376.514868) (xy 386.899608 -376.52174) (xy 386.903208 -376.535003)
			(xy 386.906516 -376.54103) (xy 386.922895 -376.569372) (xy 386.948693 -376.629534) (xy 386.966179 -376.692616)
			(xy 386.975036 -376.757474) (xy 386.975036 -376.757485) (xy 390.404948 -376.757485) (xy 390.413732 -376.69264)
			(xy 390.431141 -376.629561) (xy 390.456861 -376.569391) (xy 390.473184 -376.54103) (xy 390.476487 -376.535)
			(xy 390.4801 -376.52174) (xy 390.480296 -376.514868) (xy 390.480296 -375.765568) (xy 390.480117 -375.758694)
			(xy 390.4765 -375.745431) (xy 390.473184 -375.739406) (xy 390.456887 -375.71103) (xy 390.431165 -375.650863)
			(xy 390.413752 -375.587787) (xy 390.404964 -375.522945) (xy 390.404961 -375.45751) (xy 390.413741 -375.392667)
			(xy 390.431147 -375.329589) (xy 390.456863 -375.269419) (xy 390.473184 -375.241058) (xy 390.476513 -375.23504)
			(xy 390.48011 -375.221771) (xy 390.480296 -375.214896) (xy 390.480296 -374.928638) (xy 390.480864 -374.918488)
			(xy 390.488618 -374.899728) (xy 390.502961 -374.885363) (xy 390.521709 -374.877579) (xy 390.531858 -374.877076)
			(xy 391.248138 -374.877076) (xy 391.258303 -374.877503) (xy 391.27708 -374.885297) (xy 391.291445 -374.899684)
			(xy 391.299212 -374.918472) (xy 391.2997 -374.928638) (xy 391.2997 -375.214896) (xy 391.299893 -375.221769)
			(xy 391.3035 -375.235032) (xy 391.306812 -375.241058) (xy 391.32316 -375.269405) (xy 391.348872 -375.32958)
			(xy 391.366275 -375.392662) (xy 391.375055 -375.457508) (xy 391.375051 -375.522947) (xy 391.366264 -375.587792)
			(xy 391.348854 -375.650872) (xy 391.332074 -375.69013) (xy 392.603744 -375.69013) (xy 392.607735 -375.627963)
			(xy 392.619644 -375.566816) (xy 392.639273 -375.507695) (xy 392.666302 -375.451569) (xy 392.700286 -375.39936)
			(xy 392.740668 -375.351925) (xy 392.786784 -375.310044) (xy 392.837876 -375.274404) (xy 392.893107 -375.24559)
			(xy 392.951569 -375.224076) (xy 393.012303 -375.210214) (xy 393.07431 -375.204232) (xy 393.136573 -375.206228)
			(xy 393.19807 -375.216171) (xy 393.257791 -375.233895) (xy 393.314754 -375.259112) (xy 393.368025 -375.291405)
			(xy 393.41673 -375.330245) (xy 393.460067 -375.374995) (xy 393.497327 -375.424919) (xy 393.527896 -375.479198)
			(xy 393.532363 -375.490232) (xy 394.803892 -375.490232) (xy 394.807883 -375.428065) (xy 394.819792 -375.366918)
			(xy 394.839421 -375.307797) (xy 394.86645 -375.251671) (xy 394.900434 -375.199462) (xy 394.940816 -375.152027)
			(xy 394.986932 -375.110146) (xy 395.038024 -375.074506) (xy 395.093255 -375.045692) (xy 395.151717 -375.024178)
			(xy 395.212451 -375.010316) (xy 395.274458 -375.004334) (xy 395.336721 -375.00633) (xy 395.398218 -375.016273)
			(xy 395.457939 -375.033997) (xy 395.514902 -375.059214) (xy 395.568173 -375.091507) (xy 395.616878 -375.130347)
			(xy 395.660215 -375.175097) (xy 395.697475 -375.225021) (xy 395.728044 -375.2793) (xy 395.751422 -375.337043)
			(xy 395.767223 -375.397301) (xy 395.775189 -375.459084) (xy 395.775688 -375.490232) (xy 395.775189 -375.52138)
			(xy 395.767223 -375.583163) (xy 395.751422 -375.643421) (xy 395.728044 -375.701164) (xy 395.697475 -375.755443)
			(xy 395.660215 -375.805367) (xy 395.616878 -375.850117) (xy 395.568173 -375.888957) (xy 395.514902 -375.92125)
			(xy 395.457939 -375.946467) (xy 395.398218 -375.964191) (xy 395.336721 -375.974134) (xy 395.274458 -375.97613)
			(xy 395.212451 -375.970148) (xy 395.151717 -375.956286) (xy 395.093255 -375.934772) (xy 395.038024 -375.905958)
			(xy 394.986932 -375.870318) (xy 394.940816 -375.828437) (xy 394.900434 -375.781002) (xy 394.86645 -375.728793)
			(xy 394.839421 -375.672667) (xy 394.819792 -375.613546) (xy 394.807883 -375.552399) (xy 394.803892 -375.490232)
			(xy 393.532363 -375.490232) (xy 393.551274 -375.536941) (xy 393.567075 -375.597199) (xy 393.575041 -375.658982)
			(xy 393.57554 -375.69013) (xy 393.575041 -375.721278) (xy 393.567075 -375.783061) (xy 393.551274 -375.843319)
			(xy 393.527896 -375.901062) (xy 393.497327 -375.955341) (xy 393.460067 -376.005265) (xy 393.41673 -376.050015)
			(xy 393.368025 -376.088855) (xy 393.314754 -376.121148) (xy 393.257791 -376.146365) (xy 393.19807 -376.164089)
			(xy 393.136573 -376.174032) (xy 393.07431 -376.176028) (xy 393.012303 -376.170046) (xy 392.951569 -376.156184)
			(xy 392.893107 -376.13467) (xy 392.837876 -376.105856) (xy 392.786784 -376.070216) (xy 392.740668 -376.028335)
			(xy 392.700286 -375.9809) (xy 392.666302 -375.928691) (xy 392.639273 -375.872565) (xy 392.619644 -375.813444)
			(xy 392.607735 -375.752297) (xy 392.603744 -375.69013) (xy 391.332074 -375.69013) (xy 391.323135 -375.711044)
			(xy 391.306812 -375.739406) (xy 391.303496 -375.74543) (xy 391.299891 -375.758694) (xy 391.2997 -375.765568)
			(xy 391.2997 -376.514868) (xy 391.299904 -376.52174) (xy 391.303504 -376.535003) (xy 391.306812 -376.54103)
			(xy 391.323136 -376.56939) (xy 391.348851 -376.629562) (xy 391.366257 -376.692641) (xy 391.375039 -376.757485)
			(xy 391.375038 -376.790204) (xy 394.803892 -376.790204) (xy 394.807883 -376.728037) (xy 394.819792 -376.66689)
			(xy 394.839421 -376.607769) (xy 394.86645 -376.551643) (xy 394.900434 -376.499434) (xy 394.940816 -376.451999)
			(xy 394.986932 -376.410118) (xy 395.038024 -376.374478) (xy 395.093255 -376.345664) (xy 395.151717 -376.32415)
			(xy 395.212451 -376.310288) (xy 395.274458 -376.304306) (xy 395.336721 -376.306302) (xy 395.398218 -376.316245)
			(xy 395.457939 -376.333969) (xy 395.514902 -376.359186) (xy 395.568173 -376.391479) (xy 395.616878 -376.430319)
			(xy 395.660215 -376.475069) (xy 395.697475 -376.524993) (xy 395.728044 -376.579272) (xy 395.751422 -376.637015)
			(xy 395.767223 -376.697273) (xy 395.775189 -376.759056) (xy 395.775688 -376.790204) (xy 395.775189 -376.821352)
			(xy 395.767223 -376.883135) (xy 395.751422 -376.943393) (xy 395.728044 -377.001136) (xy 395.697475 -377.055415)
			(xy 395.660215 -377.105339) (xy 395.616878 -377.150089) (xy 395.568173 -377.188929) (xy 395.514902 -377.221222)
			(xy 395.457939 -377.246439) (xy 395.398218 -377.264163) (xy 395.336721 -377.274106) (xy 395.274458 -377.276102)
			(xy 395.212451 -377.27012) (xy 395.151717 -377.256258) (xy 395.093255 -377.234744) (xy 395.038024 -377.20593)
			(xy 394.986932 -377.17029) (xy 394.940816 -377.128409) (xy 394.900434 -377.080974) (xy 394.86645 -377.028765)
			(xy 394.839421 -376.972639) (xy 394.819792 -376.913518) (xy 394.807883 -376.852371) (xy 394.803892 -376.790204)
			(xy 391.375038 -376.790204) (xy 391.375038 -376.822922) (xy 391.366255 -376.887766) (xy 391.348848 -376.950845)
			(xy 391.323133 -377.011016) (xy 391.306812 -377.039378) (xy 391.303506 -377.045407) (xy 391.299895 -377.058667)
			(xy 391.2997 -377.06554) (xy 391.2997 -377.35129) (xy 391.299159 -377.361442) (xy 391.291395 -377.380204)
			(xy 391.277044 -377.394568) (xy 391.25829 -377.40235) (xy 391.248138 -377.402852) (xy 390.531858 -377.402852)
			(xy 390.521696 -377.402401) (xy 390.502924 -377.394611) (xy 390.48856 -377.380232) (xy 390.480789 -377.361452)
			(xy 390.480296 -377.35129) (xy 390.480296 -377.06554) (xy 390.480089 -377.058668) (xy 390.476491 -377.045405)
			(xy 390.473184 -377.039378) (xy 390.456864 -377.011015) (xy 390.431143 -376.950845) (xy 390.413733 -376.887767)
			(xy 390.404949 -376.822922) (xy 390.404948 -376.757485) (xy 386.975036 -376.757485) (xy 386.975604 -376.790204)
			(xy 386.975062 -376.822934) (xy 386.966199 -376.887794) (xy 386.948702 -376.950874) (xy 386.922888 -377.011031)
			(xy 386.906516 -377.039378) (xy 386.90321 -377.045407) (xy 386.899599 -377.058667) (xy 386.899404 -377.06554)
			(xy 386.899404 -377.35129) (xy 386.898867 -377.361411) (xy 386.89115 -377.380123) (xy 386.87688 -377.394478)
			(xy 386.858214 -377.402306) (xy 386.848096 -377.402852) (xy 386.131816 -377.402852) (xy 386.121669 -377.402366)
			(xy 386.102927 -377.394586) (xy 386.088605 -377.380209) (xy 386.080896 -377.361438) (xy 386.080508 -377.35129)
			(xy 386.080508 -377.06554) (xy 386.0803 -377.058668) (xy 386.076702 -377.045405) (xy 386.073396 -377.039378)
			(xy 386.057021 -377.011034) (xy 386.031222 -376.950872) (xy 386.013735 -376.887791) (xy 386.004877 -376.822933)
			(xy 386.004308 -376.790204) (xy 382.574966 -376.790204) (xy 382.574966 -376.822922) (xy 382.566181 -376.887767)
			(xy 382.548771 -376.950846) (xy 382.523052 -377.011017) (xy 382.506728 -377.039378) (xy 382.503423 -377.045407)
			(xy 382.499811 -377.058667) (xy 382.499616 -377.06554) (xy 382.499616 -377.35129) (xy 382.499227 -377.361467)
			(xy 382.491437 -377.38027) (xy 382.47704 -377.394657) (xy 382.458231 -377.402434) (xy 382.448054 -377.402852)
			(xy 381.731774 -377.402852) (xy 381.721613 -377.402388) (xy 381.702842 -377.394603) (xy 381.688477 -377.380228)
			(xy 381.680705 -377.361451) (xy 381.680212 -377.35129) (xy 381.680212 -377.06554) (xy 381.680003 -377.058668)
			(xy 381.676406 -377.045405) (xy 381.6731 -377.039378) (xy 381.656782 -377.011014) (xy 381.631067 -376.950843)
			(xy 381.613659 -376.887765) (xy 381.604876 -376.822921) (xy 378.174976 -376.822921) (xy 378.174976 -376.822934)
			(xy 378.166113 -376.887793) (xy 378.148617 -376.950873) (xy 378.122803 -377.011031) (xy 378.106432 -377.039378)
			(xy 378.103128 -377.045408) (xy 378.099515 -377.058668) (xy 378.09932 -377.06554) (xy 378.09932 -377.35129)
			(xy 378.098864 -377.361421) (xy 378.091132 -377.38015) (xy 378.076836 -377.394508) (xy 378.058141 -377.40232)
			(xy 378.048012 -377.402852) (xy 377.331732 -377.402852) (xy 377.321586 -377.402353) (xy 377.302845 -377.394578)
			(xy 377.288522 -377.380206) (xy 377.280812 -377.361437) (xy 377.280424 -377.35129) (xy 377.280424 -377.06554)
			(xy 377.280214 -377.058668) (xy 377.276618 -377.045405) (xy 377.273312 -377.039378) (xy 377.256939 -377.011033)
			(xy 377.231139 -376.950872) (xy 377.213651 -376.887791) (xy 377.204793 -376.822933) (xy 377.204224 -376.790204)
			(xy 351.775776 -376.790204) (xy 351.775277 -376.821352) (xy 351.767311 -376.883135) (xy 351.75151 -376.943393)
			(xy 351.728132 -377.001136) (xy 351.697563 -377.055415) (xy 351.660303 -377.105339) (xy 351.616966 -377.150089)
			(xy 351.568261 -377.188929) (xy 351.51499 -377.221222) (xy 351.458027 -377.246439) (xy 351.398306 -377.264163)
			(xy 351.336809 -377.274106) (xy 351.274546 -377.276102) (xy 351.212539 -377.27012) (xy 351.151805 -377.256258)
			(xy 351.093343 -377.234744) (xy 351.038112 -377.20593) (xy 350.98702 -377.17029) (xy 350.940904 -377.128409)
			(xy 350.900522 -377.080974) (xy 350.866538 -377.028765) (xy 350.839509 -376.972639) (xy 350.81988 -376.913518)
			(xy 350.807971 -376.852371) (xy 350.80398 -376.790204) (xy 347.375128 -376.790204) (xy 347.375128 -376.822922)
			(xy 347.366345 -376.887766) (xy 347.348937 -376.950845) (xy 347.323221 -377.011016) (xy 347.3069 -377.039378)
			(xy 347.303593 -377.045406) (xy 347.299983 -377.058667) (xy 347.299788 -377.06554) (xy 347.299788 -377.35129)
			(xy 347.299259 -377.361444) (xy 347.291493 -377.380208) (xy 347.277138 -377.394573) (xy 347.25838 -377.402352)
			(xy 347.248226 -377.402852) (xy 346.531946 -377.402852) (xy 346.521776 -377.402398) (xy 346.502981 -377.394627)
			(xy 346.488594 -377.38025) (xy 346.480809 -377.36146) (xy 346.480384 -377.35129) (xy 346.480384 -377.06554)
			(xy 346.480179 -377.058668) (xy 346.47658 -377.045405) (xy 346.473272 -377.039378) (xy 346.456952 -377.011015)
			(xy 346.431232 -376.950845) (xy 346.413823 -376.887766) (xy 346.405038 -376.822922) (xy 342.975152 -376.822922)
			(xy 342.975152 -376.822934) (xy 342.966289 -376.887794) (xy 342.948791 -376.950874) (xy 342.922976 -377.011031)
			(xy 342.906604 -377.039378) (xy 342.903297 -377.045407) (xy 342.899687 -377.058667) (xy 342.899492 -377.06554)
			(xy 342.899492 -377.35129) (xy 342.898966 -377.361412) (xy 342.891248 -377.380127) (xy 342.876974 -377.394483)
			(xy 342.858303 -377.402308) (xy 342.848184 -377.402852) (xy 342.131904 -377.402852) (xy 342.121757 -377.402376)
			(xy 342.103014 -377.394592) (xy 342.088693 -377.380212) (xy 342.080984 -377.361439) (xy 342.080596 -377.35129)
			(xy 342.080596 -377.06554) (xy 342.080389 -377.058668) (xy 342.076791 -377.045405) (xy 342.073484 -377.039378)
			(xy 342.057108 -377.011034) (xy 342.031309 -376.950873) (xy 342.013822 -376.887792) (xy 342.004965 -376.822933)
			(xy 342.004396 -376.790204) (xy 338.575056 -376.790204) (xy 338.575056 -376.822922) (xy 338.566271 -376.887767)
			(xy 338.54886 -376.950846) (xy 338.52314 -377.011017) (xy 338.506816 -377.039378) (xy 338.50351 -377.045407)
			(xy 338.499899 -377.058667) (xy 338.499704 -377.06554) (xy 338.499704 -377.35129) (xy 338.49916 -377.361442)
			(xy 338.491396 -377.380203) (xy 338.477047 -377.394567) (xy 338.458293 -377.402349) (xy 338.448142 -377.402852)
			(xy 337.731862 -377.402852) (xy 337.721701 -377.402397) (xy 337.702929 -377.394609) (xy 337.688564 -377.380231)
			(xy 337.680793 -377.361452) (xy 337.6803 -377.35129) (xy 337.6803 -377.06554) (xy 337.680093 -377.058668)
			(xy 337.676495 -377.045405) (xy 337.673188 -377.039378) (xy 337.656871 -377.011014) (xy 337.631156 -376.950843)
			(xy 337.613749 -376.887765) (xy 337.604966 -376.822921) (xy 337.604965 -376.757486) (xy 334.17504 -376.757486)
			(xy 334.175608 -376.790204) (xy 334.175066 -376.822934) (xy 334.166203 -376.887793) (xy 334.148706 -376.950874)
			(xy 334.122892 -377.011031) (xy 334.10652 -377.039378) (xy 334.103214 -377.045407) (xy 334.099603 -377.058667)
			(xy 334.099408 -377.06554) (xy 334.099408 -377.35129) (xy 334.098867 -377.36141) (xy 334.091151 -377.380122)
			(xy 334.076882 -377.394477) (xy 334.058217 -377.402305) (xy 334.0481 -377.402852) (xy 333.33182 -377.402852)
			(xy 333.321674 -377.402363) (xy 333.302932 -377.394584) (xy 333.288609 -377.380209) (xy 333.2809 -377.361438)
			(xy 333.280512 -377.35129) (xy 333.280512 -377.06554) (xy 333.280303 -377.058668) (xy 333.276706 -377.045405)
			(xy 333.2734 -377.039378) (xy 333.257026 -377.011034) (xy 333.231226 -376.950872) (xy 333.213739 -376.887791)
			(xy 333.204881 -376.822933) (xy 333.204312 -376.790204) (xy 309.717694 -376.790204) (xy 309.717694 -378.322797)
			(xy 331.005004 -378.322797) (xy 331.005007 -378.257358) (xy 331.013794 -378.192512) (xy 331.031206 -378.129433)
			(xy 331.056928 -378.069261) (xy 331.073252 -378.0409) (xy 331.076563 -378.034873) (xy 331.080172 -378.021611)
			(xy 331.080364 -378.014738) (xy 331.080364 -377.728734) (xy 331.080792 -377.718561) (xy 331.088571 -377.699763)
			(xy 331.102956 -377.685376) (xy 331.121753 -377.677594) (xy 331.131926 -377.677172) (xy 331.848206 -377.677172)
			(xy 331.858382 -377.67756) (xy 331.877184 -377.685353) (xy 331.891569 -377.69975) (xy 331.899348 -377.718557)
			(xy 331.899768 -377.728734) (xy 331.899768 -378.014738) (xy 331.899987 -378.021609) (xy 331.903577 -378.034872)
			(xy 331.90688 -378.0409) (xy 331.92318 -378.069274) (xy 331.948898 -378.129442) (xy 331.966308 -378.192518)
			(xy 331.975094 -378.25736) (xy 331.975097 -378.322795) (xy 331.966317 -378.387638) (xy 331.948913 -378.450716)
			(xy 331.9232 -378.510887) (xy 331.90688 -378.539248) (xy 331.903547 -378.545264) (xy 331.899953 -378.558534)
			(xy 331.899768 -378.56541) (xy 331.899768 -379.31471) (xy 331.89996 -379.321583) (xy 331.903569 -379.334846)
			(xy 331.90688 -379.340872) (xy 331.923241 -379.369212) (xy 331.948954 -379.429388) (xy 331.966357 -379.492471)
			(xy 331.975135 -379.55732) (xy 331.97513 -379.622759) (xy 331.966341 -379.687606) (xy 331.948927 -379.750686)
			(xy 331.923205 -379.810858) (xy 331.90688 -379.83922) (xy 331.903557 -379.84524) (xy 331.899957 -379.858507)
			(xy 331.899768 -379.865382) (xy 331.899768 -380.151386) (xy 331.899325 -380.161556) (xy 331.891546 -380.180349)
			(xy 331.877166 -380.194734) (xy 331.858376 -380.202521) (xy 331.848206 -380.202948) (xy 331.131926 -380.202948)
			(xy 331.121754 -380.202514) (xy 331.102958 -380.194735) (xy 331.088571 -380.180352) (xy 331.080788 -380.161558)
			(xy 331.080364 -380.151386) (xy 331.080364 -379.865382) (xy 331.080183 -379.858508) (xy 331.076568 -379.845245)
			(xy 331.073252 -379.83922) (xy 331.056968 -379.810837) (xy 331.031246 -379.750671) (xy 331.013834 -379.687597)
			(xy 331.005045 -379.622756) (xy 331.00504 -379.557323) (xy 331.013818 -379.49248) (xy 331.03122 -379.429403)
			(xy 331.056932 -379.369233) (xy 331.073252 -379.340872) (xy 331.076573 -379.33485) (xy 331.080175 -379.321584)
			(xy 331.080364 -379.31471) (xy 331.080364 -378.56541) (xy 331.080173 -378.558537) (xy 331.076564 -378.545274)
			(xy 331.073252 -378.539248) (xy 331.056907 -378.510899) (xy 331.031191 -378.450725) (xy 331.013785 -378.387644)
			(xy 331.005004 -378.322797) (xy 309.717694 -378.322797) (xy 309.717694 -380.69012) (xy 333.204312 -380.69012)
			(xy 333.204863 -380.65739) (xy 333.213723 -380.592531) (xy 333.231217 -380.529451) (xy 333.257029 -380.469294)
			(xy 333.2734 -380.440946) (xy 333.276698 -380.434913) (xy 333.280314 -380.421656) (xy 333.280512 -380.414784)
			(xy 333.280512 -379.665484) (xy 333.280325 -379.65861) (xy 333.276713 -379.645348) (xy 333.2734 -379.639322)
			(xy 333.257043 -379.610968) (xy 333.231239 -379.55081) (xy 333.213747 -379.487732) (xy 333.204884 -379.422877)
			(xy 333.204312 -379.390148) (xy 333.204875 -379.357418) (xy 333.213732 -379.29256) (xy 333.231223 -379.22948)
			(xy 333.257031 -379.169322) (xy 333.2734 -379.140974) (xy 333.276724 -379.134954) (xy 333.280324 -379.121687)
			(xy 333.280512 -379.114812) (xy 333.280512 -378.828554) (xy 333.280988 -378.818428) (xy 333.288726 -378.799711)
			(xy 333.303015 -378.785357) (xy 333.321696 -378.777535) (xy 333.33182 -378.776992) (xy 334.0481 -378.776992)
			(xy 334.058253 -378.777422) (xy 334.077004 -378.785216) (xy 334.091327 -378.79961) (xy 334.099028 -378.818399)
			(xy 334.099408 -378.828554) (xy 334.099408 -379.114812) (xy 334.099594 -379.121686) (xy 334.103206 -379.134949)
			(xy 334.10652 -379.140974) (xy 334.122877 -379.169328) (xy 334.148681 -379.229486) (xy 334.166172 -379.292564)
			(xy 334.175036 -379.357419) (xy 334.175608 -379.390148) (xy 334.17504 -379.422877) (xy 334.166185 -379.487736)
			(xy 334.148695 -379.550816) (xy 334.131866 -379.590046) (xy 335.40446 -379.590046) (xy 335.405029 -379.557317)
			(xy 335.413885 -379.492459) (xy 335.431374 -379.429379) (xy 335.45718 -379.36922) (xy 335.473548 -379.340872)
			(xy 335.476869 -379.33485) (xy 335.480471 -379.321584) (xy 335.48066 -379.31471) (xy 335.48066 -378.56541)
			(xy 335.480469 -378.558537) (xy 335.476861 -378.545274) (xy 335.473548 -378.539248) (xy 335.457166 -378.510908)
			(xy 335.431367 -378.450745) (xy 335.413882 -378.387663) (xy 335.405027 -378.322804) (xy 335.40446 -378.290074)
			(xy 335.405042 -378.257345) (xy 335.413894 -378.192488) (xy 335.431379 -378.129407) (xy 335.457182 -378.069249)
			(xy 335.473548 -378.0409) (xy 335.476859 -378.034873) (xy 335.480467 -378.021611) (xy 335.48066 -378.014738)
			(xy 335.48066 -377.728734) (xy 335.481155 -377.718607) (xy 335.488875 -377.699883) (xy 335.50316 -377.685525)
			(xy 335.521844 -377.677708) (xy 335.531968 -377.677172) (xy 336.248248 -377.677172) (xy 336.258402 -377.677582)
			(xy 336.27715 -377.685388) (xy 336.29147 -377.699787) (xy 336.299173 -377.718578) (xy 336.299556 -377.728734)
			(xy 336.299556 -378.014738) (xy 336.299764 -378.02161) (xy 336.303361 -378.034873) (xy 336.306668 -378.0409)
			(xy 336.323031 -378.069251) (xy 336.348834 -378.12941) (xy 336.366324 -378.192489) (xy 336.375185 -378.257345)
			(xy 336.375756 -378.290074) (xy 336.375193 -378.322797) (xy 339.80509 -378.322797) (xy 339.805093 -378.257358)
			(xy 339.81388 -378.192513) (xy 339.831291 -378.129433) (xy 339.857012 -378.069261) (xy 339.873336 -378.0409)
			(xy 339.876646 -378.034873) (xy 339.880255 -378.021611) (xy 339.880448 -378.014738) (xy 339.880448 -377.728734)
			(xy 339.880892 -377.718563) (xy 339.888668 -377.699768) (xy 339.903047 -377.685381) (xy 339.92184 -377.677597)
			(xy 339.93201 -377.677172) (xy 340.64829 -377.677172) (xy 340.658465 -377.677573) (xy 340.677266 -377.685361)
			(xy 340.691653 -377.699754) (xy 340.699432 -377.718559) (xy 340.699852 -377.728734) (xy 340.699852 -378.014738)
			(xy 340.700061 -378.02161) (xy 340.703657 -378.034873) (xy 340.706964 -378.0409) (xy 340.723264 -378.069273)
			(xy 340.748984 -378.129442) (xy 340.766394 -378.192518) (xy 340.77518 -378.25736) (xy 340.775183 -378.322795)
			(xy 340.775183 -378.322797) (xy 344.20488 -378.322797) (xy 344.204883 -378.257359) (xy 344.213669 -378.192513)
			(xy 344.23108 -378.129433) (xy 344.2568 -378.069261) (xy 344.273124 -378.0409) (xy 344.27644 -378.034876)
			(xy 344.280045 -378.021612) (xy 344.280236 -378.014738) (xy 344.280236 -377.728734) (xy 344.280692 -377.718565)
			(xy 344.288465 -377.699771) (xy 344.302841 -377.685385) (xy 344.321629 -377.677599) (xy 344.331798 -377.677172)
			(xy 345.048078 -377.677172) (xy 345.058252 -377.677583) (xy 345.077053 -377.685367) (xy 345.09144 -377.699757)
			(xy 345.099219 -377.71856) (xy 345.09964 -377.728734) (xy 345.09964 -378.014738) (xy 345.099851 -378.02161)
			(xy 345.103446 -378.034873) (xy 345.106752 -378.0409) (xy 345.123052 -378.069273) (xy 345.148773 -378.129442)
			(xy 345.166183 -378.192518) (xy 345.17497 -378.25736) (xy 345.174971 -378.290074) (xy 348.603832 -378.290074)
			(xy 348.607823 -378.227907) (xy 348.619732 -378.16676) (xy 348.639361 -378.107639) (xy 348.66639 -378.051513)
			(xy 348.700374 -377.999304) (xy 348.740756 -377.951869) (xy 348.786872 -377.909988) (xy 348.837964 -377.874348)
			(xy 348.893195 -377.845534) (xy 348.951657 -377.82402) (xy 349.012391 -377.810158) (xy 349.074398 -377.804176)
			(xy 349.136661 -377.806172) (xy 349.198158 -377.816115) (xy 349.257879 -377.833839) (xy 349.314842 -377.859056)
			(xy 349.368113 -377.891349) (xy 349.416818 -377.930189) (xy 349.460155 -377.974939) (xy 349.497415 -378.024863)
			(xy 349.527984 -378.079142) (xy 349.551362 -378.136885) (xy 349.567163 -378.197143) (xy 349.575129 -378.258926)
			(xy 349.575628 -378.290074) (xy 349.575129 -378.321222) (xy 349.574926 -378.322797) (xy 375.004914 -378.322797)
			(xy 375.004917 -378.257358) (xy 375.013704 -378.192512) (xy 375.031117 -378.129432) (xy 375.056839 -378.069261)
			(xy 375.073164 -378.0409) (xy 375.076476 -378.034874) (xy 375.080084 -378.021611) (xy 375.080276 -378.014738)
			(xy 375.080276 -377.728734) (xy 375.080693 -377.71856) (xy 375.088474 -377.699759) (xy 375.102862 -377.685371)
			(xy 375.121664 -377.677592) (xy 375.131838 -377.677172) (xy 375.848118 -377.677172) (xy 375.858295 -377.67755)
			(xy 375.877097 -377.685347) (xy 375.891482 -377.699747) (xy 375.89926 -377.718557) (xy 375.89968 -377.728734)
			(xy 375.89968 -378.014738) (xy 375.899898 -378.021609) (xy 375.903489 -378.034872) (xy 375.906792 -378.0409)
			(xy 375.923091 -378.069274) (xy 375.948809 -378.129442) (xy 375.966219 -378.192518) (xy 375.975004 -378.25736)
			(xy 375.975007 -378.322795) (xy 375.966228 -378.387638) (xy 375.948824 -378.450715) (xy 375.923112 -378.510886)
			(xy 375.906792 -378.539248) (xy 375.90346 -378.545264) (xy 375.899865 -378.558534) (xy 375.89968 -378.56541)
			(xy 375.89968 -379.31471) (xy 375.899871 -379.321583) (xy 375.90348 -379.334846) (xy 375.906792 -379.340872)
			(xy 375.923152 -379.369212) (xy 375.948865 -379.429389) (xy 375.966267 -379.492472) (xy 375.975045 -379.55732)
			(xy 375.97504 -379.622759) (xy 375.966251 -379.687606) (xy 375.948838 -379.750686) (xy 375.923116 -379.810858)
			(xy 375.906792 -379.83922) (xy 375.90347 -379.845241) (xy 375.899869 -379.858508) (xy 375.89968 -379.865382)
			(xy 375.89968 -380.151386) (xy 375.899156 -380.161541) (xy 375.891389 -380.180306) (xy 375.877033 -380.194671)
			(xy 375.858272 -380.202449) (xy 375.848118 -380.202948) (xy 375.131838 -380.202948) (xy 375.121667 -380.202505)
			(xy 375.102871 -380.19473) (xy 375.088484 -380.18035) (xy 375.0807 -380.161557) (xy 375.080276 -380.151386)
			(xy 375.080276 -379.865382) (xy 375.080094 -379.858508) (xy 375.076479 -379.845245) (xy 375.073164 -379.83922)
			(xy 375.05688 -379.810838) (xy 375.031157 -379.750672) (xy 375.013744 -379.687597) (xy 375.004955 -379.622756)
			(xy 375.00495 -379.557323) (xy 375.013728 -379.49248) (xy 375.031131 -379.429403) (xy 375.056844 -379.369233)
			(xy 375.073164 -379.340872) (xy 375.076486 -379.334851) (xy 375.080087 -379.321584) (xy 375.080276 -379.31471)
			(xy 375.080276 -378.56541) (xy 375.080083 -378.558537) (xy 375.076476 -378.545274) (xy 375.073164 -378.539248)
			(xy 375.056819 -378.510899) (xy 375.031102 -378.450725) (xy 375.013695 -378.387644) (xy 375.004914 -378.322797)
			(xy 349.574926 -378.322797) (xy 349.567163 -378.383005) (xy 349.551362 -378.443263) (xy 349.527984 -378.501006)
			(xy 349.497415 -378.555285) (xy 349.460155 -378.605209) (xy 349.416818 -378.649959) (xy 349.368113 -378.688799)
			(xy 349.314842 -378.721092) (xy 349.257879 -378.746309) (xy 349.198158 -378.764033) (xy 349.136661 -378.773976)
			(xy 349.074398 -378.775972) (xy 349.012391 -378.76999) (xy 348.951657 -378.756128) (xy 348.893195 -378.734614)
			(xy 348.837964 -378.7058) (xy 348.786872 -378.67016) (xy 348.740756 -378.628279) (xy 348.700374 -378.580844)
			(xy 348.66639 -378.528635) (xy 348.639361 -378.472509) (xy 348.619732 -378.413388) (xy 348.607823 -378.352241)
			(xy 348.603832 -378.290074) (xy 345.174971 -378.290074) (xy 345.174973 -378.322795) (xy 345.166192 -378.387638)
			(xy 345.148787 -378.450716) (xy 345.123073 -378.510887) (xy 345.106752 -378.539248) (xy 345.103424 -378.545266)
			(xy 345.099826 -378.558535) (xy 345.09964 -378.56541) (xy 345.09964 -379.31471) (xy 345.099823 -379.321584)
			(xy 345.103437 -379.334847) (xy 345.106752 -379.340872) (xy 345.123113 -379.369212) (xy 345.148828 -379.429388)
			(xy 345.166232 -379.492471) (xy 345.175011 -379.557319) (xy 345.175006 -379.622759) (xy 345.166216 -379.687607)
			(xy 345.148802 -379.750687) (xy 345.123078 -379.810859) (xy 345.106752 -379.83922) (xy 345.103434 -379.845243)
			(xy 345.09983 -379.858508) (xy 345.09964 -379.865382) (xy 345.09964 -380.151386) (xy 345.099224 -380.161559)
			(xy 345.09144 -380.180358) (xy 345.077051 -380.194744) (xy 345.058252 -380.202526) (xy 345.048078 -380.202948)
			(xy 344.331798 -380.202948) (xy 344.321625 -380.202537) (xy 344.302827 -380.194749) (xy 344.288442 -380.180359)
			(xy 344.280659 -380.16156) (xy 344.280236 -380.151386) (xy 344.280236 -379.865382) (xy 344.280046 -379.858509)
			(xy 344.276436 -379.845246) (xy 344.273124 -379.83922) (xy 344.256841 -379.810837) (xy 344.231121 -379.750671)
			(xy 344.213709 -379.687597) (xy 344.204921 -379.622756) (xy 344.204915 -379.557323) (xy 344.213693 -379.492481)
			(xy 344.231095 -379.429404) (xy 344.256805 -379.369233) (xy 344.273124 -379.340872) (xy 344.27645 -379.334853)
			(xy 344.280048 -379.321585) (xy 344.280236 -379.31471) (xy 344.280236 -378.56541) (xy 344.280036 -378.558537)
			(xy 344.276433 -378.545275) (xy 344.273124 -378.539248) (xy 344.25678 -378.510899) (xy 344.231065 -378.450725)
			(xy 344.21366 -378.387643) (xy 344.20488 -378.322797) (xy 340.775183 -378.322797) (xy 340.766403 -378.387638)
			(xy 340.748998 -378.450716) (xy 340.723284 -378.510887) (xy 340.706964 -378.539248) (xy 340.703637 -378.545267)
			(xy 340.700038 -378.558535) (xy 340.699852 -378.56541) (xy 340.699852 -379.31471) (xy 340.700034 -379.321584)
			(xy 340.703648 -379.334847) (xy 340.706964 -379.340872) (xy 340.723325 -379.369212) (xy 340.749039 -379.429388)
			(xy 340.766443 -379.492471) (xy 340.775221 -379.55732) (xy 340.775216 -379.622759) (xy 340.766427 -379.687606)
			(xy 340.749013 -379.750687) (xy 340.723289 -379.810859) (xy 340.706964 -379.83922) (xy 340.703647 -379.845244)
			(xy 340.700042 -379.858508) (xy 340.699852 -379.865382) (xy 340.699852 -380.151386) (xy 340.699425 -380.161558)
			(xy 340.691642 -380.180354) (xy 340.677258 -380.19474) (xy 340.658462 -380.202524) (xy 340.64829 -380.202948)
			(xy 339.93201 -380.202948) (xy 339.921837 -380.202528) (xy 339.90304 -380.194743) (xy 339.888654 -380.180357)
			(xy 339.880871 -380.161559) (xy 339.880448 -380.151386) (xy 339.880448 -379.865382) (xy 339.880269 -379.858508)
			(xy 339.876653 -379.845245) (xy 339.873336 -379.83922) (xy 339.857053 -379.810837) (xy 339.831332 -379.750671)
			(xy 339.813919 -379.687597) (xy 339.805131 -379.622756) (xy 339.805126 -379.557323) (xy 339.813904 -379.492481)
			(xy 339.831306 -379.429404) (xy 339.857017 -379.369233) (xy 339.873336 -379.340872) (xy 339.876656 -379.33485)
			(xy 339.880259 -379.321584) (xy 339.880448 -379.31471) (xy 339.880448 -378.56541) (xy 339.880259 -378.558536)
			(xy 339.876649 -378.545273) (xy 339.873336 -378.539248) (xy 339.856992 -378.510899) (xy 339.831276 -378.450725)
			(xy 339.813871 -378.387644) (xy 339.80509 -378.322797) (xy 336.375193 -378.322797) (xy 336.375193 -378.322804)
			(xy 336.366336 -378.387662) (xy 336.348844 -378.450742) (xy 336.323037 -378.5109) (xy 336.306668 -378.539248)
			(xy 336.303334 -378.545263) (xy 336.299741 -378.558534) (xy 336.299556 -378.56541) (xy 336.299556 -379.31471)
			(xy 336.299737 -379.321584) (xy 336.303352 -379.334847) (xy 336.306668 -379.340872) (xy 336.323019 -379.369229)
			(xy 336.348825 -379.429386) (xy 336.366319 -379.492463) (xy 336.375184 -379.557318) (xy 336.375756 -379.590046)
			(xy 336.375181 -379.622775) (xy 336.366327 -379.687633) (xy 336.348839 -379.750713) (xy 336.323035 -379.810871)
			(xy 336.306668 -379.83922) (xy 336.303344 -379.84524) (xy 336.299745 -379.858507) (xy 336.299556 -379.865382)
			(xy 336.299556 -380.151386) (xy 336.299062 -380.161512) (xy 336.291338 -380.180234) (xy 336.277054 -380.194591)
			(xy 336.258372 -380.20241) (xy 336.248248 -380.202948) (xy 335.531968 -380.202948) (xy 335.521818 -380.202506)
			(xy 335.503074 -380.194708) (xy 335.488753 -380.180319) (xy 335.481046 -380.161538) (xy 335.48066 -380.151386)
			(xy 335.48066 -379.865382) (xy 335.48048 -379.858508) (xy 335.476864 -379.845245) (xy 335.473548 -379.83922)
			(xy 335.457195 -379.810864) (xy 335.431389 -379.750707) (xy 335.413896 -379.68763) (xy 335.405032 -379.622774)
			(xy 335.40446 -379.590046) (xy 334.131866 -379.590046) (xy 334.122888 -379.610974) (xy 334.10652 -379.639322)
			(xy 334.103199 -379.645344) (xy 334.099597 -379.65861) (xy 334.099408 -379.665484) (xy 334.099408 -380.414784)
			(xy 334.099605 -380.421657) (xy 334.10321 -380.43492) (xy 334.10652 -380.440946) (xy 334.122906 -380.469284)
			(xy 334.148702 -380.529448) (xy 334.166186 -380.592531) (xy 334.175041 -380.65739) (xy 334.175041 -380.6574)
			(xy 337.604973 -380.6574) (xy 337.613753 -380.592557) (xy 337.631156 -380.529479) (xy 337.656869 -380.469308)
			(xy 337.673188 -380.440946) (xy 337.676486 -380.434913) (xy 337.680102 -380.421656) (xy 337.6803 -380.414784)
			(xy 337.6803 -379.665484) (xy 337.680114 -379.65861) (xy 337.676502 -379.645347) (xy 337.673188 -379.639322)
			(xy 337.656908 -379.610938) (xy 337.631189 -379.550771) (xy 337.613779 -379.487698) (xy 337.604991 -379.422858)
			(xy 337.604985 -379.357425) (xy 337.613762 -379.292583) (xy 337.631162 -379.229506) (xy 337.656871 -379.169336)
			(xy 337.673188 -379.140974) (xy 337.676511 -379.134953) (xy 337.680112 -379.121687) (xy 337.6803 -379.114812)
			(xy 337.6803 -378.828554) (xy 337.680795 -378.818398) (xy 337.688577 -378.799635) (xy 337.702942 -378.785273)
			(xy 337.721706 -378.777493) (xy 337.731862 -378.776992) (xy 338.448142 -378.776992) (xy 338.458297 -378.777498)
			(xy 338.477058 -378.785278) (xy 338.49142 -378.799639) (xy 338.499201 -378.818399) (xy 338.499704 -378.828554)
			(xy 338.499704 -379.114812) (xy 338.499891 -379.121686) (xy 338.503502 -379.134948) (xy 338.506816 -379.140974)
			(xy 338.52318 -379.169312) (xy 338.548896 -379.229488) (xy 338.566302 -379.292572) (xy 338.575081 -379.357421)
			(xy 338.575076 -379.422861) (xy 338.566285 -379.487709) (xy 338.548869 -379.55079) (xy 338.523143 -379.610961)
			(xy 338.506816 -379.639322) (xy 338.503495 -379.645343) (xy 338.499893 -379.65861) (xy 338.499704 -379.665484)
			(xy 338.499704 -380.414784) (xy 338.499902 -380.421657) (xy 338.503506 -380.43492) (xy 338.506816 -380.440946)
			(xy 338.523157 -380.469297) (xy 338.548875 -380.52947) (xy 338.566283 -380.592551) (xy 338.575065 -380.657398)
			(xy 338.575064 -380.69012) (xy 342.004396 -380.69012) (xy 342.004949 -380.65739) (xy 342.013808 -380.592531)
			(xy 342.031302 -380.529451) (xy 342.057113 -380.469293) (xy 342.073484 -380.440946) (xy 342.076781 -380.434913)
			(xy 342.080398 -380.421656) (xy 342.080596 -380.414784) (xy 342.080596 -379.665484) (xy 342.080411 -379.65861)
			(xy 342.076798 -379.645347) (xy 342.073484 -379.639322) (xy 342.057126 -379.610969) (xy 342.031322 -379.550811)
			(xy 342.013831 -379.487732) (xy 342.004968 -379.422877) (xy 342.004396 -379.390148) (xy 342.004962 -379.357418)
			(xy 342.013818 -379.29256) (xy 342.031308 -379.22948) (xy 342.057116 -379.169322) (xy 342.073484 -379.140974)
			(xy 342.076807 -379.134953) (xy 342.080408 -379.121687) (xy 342.080596 -379.114812) (xy 342.080596 -378.828554)
			(xy 342.081088 -378.81843) (xy 342.088822 -378.799716) (xy 342.103106 -378.785363) (xy 342.121782 -378.777538)
			(xy 342.131904 -378.776992) (xy 342.848184 -378.776992) (xy 342.858336 -378.777434) (xy 342.877087 -378.785223)
			(xy 342.89141 -378.799614) (xy 342.899112 -378.8184) (xy 342.899492 -378.828554) (xy 342.899492 -379.114812)
			(xy 342.89968 -379.121685) (xy 342.903291 -379.134948) (xy 342.906604 -379.140974) (xy 342.92296 -379.169329)
			(xy 342.948764 -379.229486) (xy 342.966256 -379.292564) (xy 342.97512 -379.357419) (xy 342.975692 -379.390148)
			(xy 342.975126 -379.422878) (xy 342.966271 -379.487736) (xy 342.94878 -379.550816) (xy 342.922973 -379.610974)
			(xy 342.906604 -379.639322) (xy 342.903282 -379.645343) (xy 342.899681 -379.65861) (xy 342.899492 -379.665484)
			(xy 342.899492 -380.414784) (xy 342.899691 -380.421657) (xy 342.903294 -380.43492) (xy 342.906604 -380.440946)
			(xy 342.922988 -380.469285) (xy 342.948786 -380.529448) (xy 342.96627 -380.592531) (xy 342.975125 -380.65739)
			(xy 342.975125 -380.657399) (xy 346.405045 -380.657399) (xy 346.413827 -380.592555) (xy 346.431233 -380.529477)
			(xy 346.45695 -380.469307) (xy 346.473272 -380.440946) (xy 346.476568 -380.434912) (xy 346.480186 -380.421656)
			(xy 346.480384 -380.414784) (xy 346.480384 -379.665484) (xy 346.4802 -379.65861) (xy 346.476587 -379.645347)
			(xy 346.473272 -379.639322) (xy 346.456989 -379.610939) (xy 346.431266 -379.550773) (xy 346.413852 -379.487699)
			(xy 346.405063 -379.422858) (xy 346.405058 -379.357424) (xy 346.413836 -379.292582) (xy 346.431239 -379.229505)
			(xy 346.456952 -379.169335) (xy 346.473272 -379.140974) (xy 346.476594 -379.134953) (xy 346.480196 -379.121686)
			(xy 346.480384 -379.114812) (xy 346.480384 -378.828554) (xy 346.480797 -378.818388) (xy 346.488595 -378.799609)
			(xy 346.502986 -378.785243) (xy 346.521779 -378.777479) (xy 346.531946 -378.776992) (xy 347.248226 -378.776992)
			(xy 347.25838 -378.777511) (xy 347.277141 -378.785285) (xy 347.291504 -378.799642) (xy 347.299285 -378.8184)
			(xy 347.299788 -378.828554) (xy 347.299788 -379.114812) (xy 347.299977 -379.121685) (xy 347.303587 -379.134948)
			(xy 347.3069 -379.140974) (xy 347.323262 -379.169313) (xy 347.348973 -379.22949) (xy 347.366376 -379.292573)
			(xy 347.375153 -379.357421) (xy 347.375148 -379.422861) (xy 347.366359 -379.487708) (xy 347.348946 -379.550788)
			(xy 347.332164 -379.590046) (xy 348.603832 -379.590046) (xy 348.607823 -379.527879) (xy 348.619732 -379.466732)
			(xy 348.639361 -379.407611) (xy 348.66639 -379.351485) (xy 348.700374 -379.299276) (xy 348.740756 -379.251841)
			(xy 348.786872 -379.20996) (xy 348.837964 -379.17432) (xy 348.893195 -379.145506) (xy 348.951657 -379.123992)
			(xy 349.012391 -379.11013) (xy 349.074398 -379.104148) (xy 349.136661 -379.106144) (xy 349.198158 -379.116087)
			(xy 349.257879 -379.133811) (xy 349.314842 -379.159028) (xy 349.368113 -379.191321) (xy 349.416818 -379.230161)
			(xy 349.460155 -379.274911) (xy 349.497415 -379.324835) (xy 349.527984 -379.379114) (xy 349.532451 -379.390148)
			(xy 350.80398 -379.390148) (xy 350.807971 -379.327981) (xy 350.81988 -379.266834) (xy 350.839509 -379.207713)
			(xy 350.866538 -379.151587) (xy 350.900522 -379.099378) (xy 350.940904 -379.051943) (xy 350.98702 -379.010062)
			(xy 351.038112 -378.974422) (xy 351.093343 -378.945608) (xy 351.151805 -378.924094) (xy 351.212539 -378.910232)
			(xy 351.274546 -378.90425) (xy 351.336809 -378.906246) (xy 351.398306 -378.916189) (xy 351.458027 -378.933913)
			(xy 351.51499 -378.95913) (xy 351.568261 -378.991423) (xy 351.616966 -379.030263) (xy 351.660303 -379.075013)
			(xy 351.670291 -379.088396) (xy 362.932978 -379.088396) (xy 362.937049 -379.032774) (xy 362.949175 -378.978337)
			(xy 362.969098 -378.926246) (xy 362.996394 -378.877611) (xy 363.03048 -378.833468) (xy 363.070629 -378.794759)
			(xy 363.115987 -378.762308) (xy 363.165587 -378.736807) (xy 363.218371 -378.7188) (xy 363.273214 -378.70867)
			(xy 363.328948 -378.706633) (xy 363.384385 -378.712733) (xy 363.438342 -378.726839) (xy 363.489671 -378.748651)
			(xy 363.537277 -378.777705) (xy 363.580145 -378.81338) (xy 363.617362 -378.854917) (xy 363.648135 -378.90143)
			(xy 363.671807 -378.951927) (xy 363.687875 -379.005334) (xy 363.695995 -379.06051) (xy 363.696504 -379.088396)
			(xy 363.695995 -379.116282) (xy 363.687875 -379.171458) (xy 363.671807 -379.224865) (xy 363.648135 -379.275362)
			(xy 363.617362 -379.321875) (xy 363.580145 -379.363412) (xy 363.537277 -379.399087) (xy 363.489671 -379.428141)
			(xy 363.438342 -379.449953) (xy 363.384385 -379.464059) (xy 363.328948 -379.470159) (xy 363.273214 -379.468122)
			(xy 363.218371 -379.457992) (xy 363.165587 -379.439985) (xy 363.115987 -379.414484) (xy 363.070629 -379.382033)
			(xy 363.03048 -379.343324) (xy 362.996394 -379.299181) (xy 362.969098 -379.250546) (xy 362.949175 -379.198455)
			(xy 362.937049 -379.144018) (xy 362.932978 -379.088396) (xy 351.670291 -379.088396) (xy 351.697563 -379.124937)
			(xy 351.728132 -379.179216) (xy 351.75151 -379.236959) (xy 351.767311 -379.297217) (xy 351.775277 -379.359)
			(xy 351.775776 -379.390148) (xy 351.775277 -379.421296) (xy 351.767311 -379.483079) (xy 351.75151 -379.543337)
			(xy 351.728132 -379.60108) (xy 351.697583 -379.655324) (xy 360.52074 -379.655324) (xy 360.524811 -379.599702)
			(xy 360.536937 -379.545265) (xy 360.55686 -379.493174) (xy 360.584156 -379.444539) (xy 360.618242 -379.400396)
			(xy 360.658391 -379.361687) (xy 360.703749 -379.329236) (xy 360.753349 -379.303735) (xy 360.806133 -379.285728)
			(xy 360.860976 -379.275598) (xy 360.91671 -379.273561) (xy 360.972147 -379.279661) (xy 361.026104 -379.293767)
			(xy 361.077433 -379.315579) (xy 361.125039 -379.344633) (xy 361.167907 -379.380308) (xy 361.205124 -379.421845)
			(xy 361.235897 -379.468358) (xy 361.259569 -379.518855) (xy 361.275637 -379.572262) (xy 361.283757 -379.627438)
			(xy 361.284266 -379.655324) (xy 361.283757 -379.68321) (xy 361.275637 -379.738386) (xy 361.259569 -379.791793)
			(xy 361.235897 -379.84229) (xy 361.205124 -379.888803) (xy 361.167907 -379.93034) (xy 361.125039 -379.966015)
			(xy 361.077433 -379.995069) (xy 361.026104 -380.016881) (xy 360.972147 -380.030987) (xy 360.91671 -380.037087)
			(xy 360.860976 -380.03505) (xy 360.806133 -380.02492) (xy 360.753349 -380.006913) (xy 360.703749 -379.981412)
			(xy 360.658391 -379.948961) (xy 360.618242 -379.910252) (xy 360.584156 -379.866109) (xy 360.55686 -379.817474)
			(xy 360.536937 -379.765383) (xy 360.524811 -379.710946) (xy 360.52074 -379.655324) (xy 351.697583 -379.655324)
			(xy 351.697563 -379.655359) (xy 351.660303 -379.705283) (xy 351.616966 -379.750033) (xy 351.568261 -379.788873)
			(xy 351.51499 -379.821166) (xy 351.458027 -379.846383) (xy 351.398306 -379.864107) (xy 351.336809 -379.87405)
			(xy 351.274546 -379.876046) (xy 351.212539 -379.870064) (xy 351.151805 -379.856202) (xy 351.093343 -379.834688)
			(xy 351.038112 -379.805874) (xy 350.98702 -379.770234) (xy 350.940904 -379.728353) (xy 350.900522 -379.680918)
			(xy 350.866538 -379.628709) (xy 350.839509 -379.572583) (xy 350.81988 -379.513462) (xy 350.807971 -379.452315)
			(xy 350.80398 -379.390148) (xy 349.532451 -379.390148) (xy 349.551362 -379.436857) (xy 349.567163 -379.497115)
			(xy 349.575129 -379.558898) (xy 349.575628 -379.590046) (xy 349.575129 -379.621194) (xy 349.567163 -379.682977)
			(xy 349.551362 -379.743235) (xy 349.527984 -379.800978) (xy 349.497415 -379.855257) (xy 349.460155 -379.905181)
			(xy 349.416818 -379.949931) (xy 349.368113 -379.988771) (xy 349.314842 -380.021064) (xy 349.257879 -380.046281)
			(xy 349.198158 -380.064005) (xy 349.136661 -380.073948) (xy 349.074398 -380.075944) (xy 349.012391 -380.069962)
			(xy 348.951657 -380.0561) (xy 348.893195 -380.034586) (xy 348.837964 -380.005772) (xy 348.786872 -379.970132)
			(xy 348.740756 -379.928251) (xy 348.700374 -379.880816) (xy 348.66639 -379.828607) (xy 348.639361 -379.772481)
			(xy 348.619732 -379.71336) (xy 348.607823 -379.652213) (xy 348.603832 -379.590046) (xy 347.332164 -379.590046)
			(xy 347.323224 -379.61096) (xy 347.3069 -379.639322) (xy 347.303577 -379.645343) (xy 347.299977 -379.65861)
			(xy 347.299788 -379.665484) (xy 347.299788 -380.414784) (xy 347.299987 -380.421657) (xy 347.303591 -380.434919)
			(xy 347.3069 -380.440946) (xy 347.323238 -380.469298) (xy 347.348952 -380.529472) (xy 347.366357 -380.592553)
			(xy 347.375137 -380.657398) (xy 347.375136 -380.69012) (xy 350.80398 -380.69012) (xy 350.807971 -380.627953)
			(xy 350.81988 -380.566806) (xy 350.839509 -380.507685) (xy 350.866538 -380.451559) (xy 350.900522 -380.39935)
			(xy 350.940904 -380.351915) (xy 350.98702 -380.310034) (xy 351.038112 -380.274394) (xy 351.093343 -380.24558)
			(xy 351.151805 -380.224066) (xy 351.212539 -380.210204) (xy 351.274546 -380.204222) (xy 351.336809 -380.206218)
			(xy 351.398306 -380.216161) (xy 351.458027 -380.233885) (xy 351.51499 -380.259102) (xy 351.568261 -380.291395)
			(xy 351.616966 -380.330235) (xy 351.660303 -380.374985) (xy 351.697563 -380.424909) (xy 351.728132 -380.479188)
			(xy 351.75151 -380.536931) (xy 351.767311 -380.597189) (xy 351.775277 -380.658972) (xy 351.775776 -380.69012)
			(xy 377.204224 -380.69012) (xy 377.204773 -380.65739) (xy 377.213633 -380.592531) (xy 377.231128 -380.529451)
			(xy 377.256941 -380.469293) (xy 377.273312 -380.440946) (xy 377.276611 -380.434914) (xy 377.280226 -380.421656)
			(xy 377.280424 -380.414784) (xy 377.280424 -379.665484) (xy 377.280235 -379.658611) (xy 377.276624 -379.645348)
			(xy 377.273312 -379.639322) (xy 377.256956 -379.610967) (xy 377.231152 -379.55081) (xy 377.213659 -379.487732)
			(xy 377.204796 -379.422877) (xy 377.204224 -379.390148) (xy 377.204786 -379.357418) (xy 377.213642 -379.29256)
			(xy 377.231134 -379.22948) (xy 377.256943 -379.169322) (xy 377.273312 -379.140974) (xy 377.276637 -379.134954)
			(xy 377.280236 -379.121687) (xy 377.280424 -379.114812) (xy 377.280424 -378.828554) (xy 377.280888 -378.818426)
			(xy 377.288628 -378.799707) (xy 377.302921 -378.785353) (xy 377.321607 -378.777533) (xy 377.331732 -378.776992)
			(xy 378.048012 -378.776992) (xy 378.058166 -378.777411) (xy 378.076917 -378.785209) (xy 378.09124 -378.799607)
			(xy 378.098941 -378.818398) (xy 378.09932 -378.828554) (xy 378.09932 -379.114812) (xy 378.099505 -379.121686)
			(xy 378.103118 -379.134949) (xy 378.106432 -379.140974) (xy 378.122781 -379.169333) (xy 378.148588 -379.229488)
			(xy 378.166083 -379.292565) (xy 378.174948 -379.35742) (xy 378.17552 -379.390148) (xy 378.17495 -379.422877)
			(xy 378.166095 -379.487735) (xy 378.148606 -379.550815) (xy 378.131777 -379.590046) (xy 379.404372 -379.590046)
			(xy 379.40494 -379.557317) (xy 379.413795 -379.492458) (xy 379.431285 -379.429378) (xy 379.457092 -379.36922)
			(xy 379.47346 -379.340872) (xy 379.476781 -379.334851) (xy 379.480383 -379.321584) (xy 379.480572 -379.31471)
			(xy 379.480572 -378.56541) (xy 379.48038 -378.558537) (xy 379.476772 -378.545274) (xy 379.47346 -378.539248)
			(xy 379.457079 -378.510907) (xy 379.43128 -378.450745) (xy 379.413794 -378.387663) (xy 379.404939 -378.322804)
			(xy 379.404372 -378.290074) (xy 379.404953 -378.257345) (xy 379.413805 -378.192487) (xy 379.431291 -378.129407)
			(xy 379.457094 -378.069249) (xy 379.47346 -378.0409) (xy 379.476771 -378.034874) (xy 379.48038 -378.021611)
			(xy 379.480572 -378.014738) (xy 379.480572 -377.728734) (xy 379.481056 -377.718606) (xy 379.488778 -377.699879)
			(xy 379.503066 -377.685521) (xy 379.521754 -377.677706) (xy 379.53188 -377.677172) (xy 380.24816 -377.677172)
			(xy 380.258308 -377.677654) (xy 380.277054 -377.685431) (xy 380.291378 -377.699809) (xy 380.299084 -377.718584)
			(xy 380.299468 -377.728734) (xy 380.299468 -378.014738) (xy 380.299687 -378.021609) (xy 380.303277 -378.034872)
			(xy 380.30658 -378.0409) (xy 380.322944 -378.06925) (xy 380.348746 -378.129409) (xy 380.366237 -378.192488)
			(xy 380.375097 -378.257345) (xy 380.375668 -378.290074) (xy 380.375104 -378.322797) (xy 383.805 -378.322797)
			(xy 383.805003 -378.257358) (xy 383.81379 -378.192512) (xy 383.831202 -378.129433) (xy 383.856924 -378.069261)
			(xy 383.873248 -378.0409) (xy 383.876559 -378.034873) (xy 383.880167 -378.021611) (xy 383.88036 -378.014738)
			(xy 383.88036 -377.728734) (xy 383.880792 -377.718562) (xy 383.88857 -377.699764) (xy 383.902954 -377.685377)
			(xy 383.92175 -377.677595) (xy 383.931922 -377.677172) (xy 384.648202 -377.677172) (xy 384.658378 -377.677563)
			(xy 384.677179 -377.685355) (xy 384.691565 -377.699751) (xy 384.699344 -377.718558) (xy 384.699764 -377.728734)
			(xy 384.699764 -378.014738) (xy 384.699984 -378.021609) (xy 384.703574 -378.034872) (xy 384.706876 -378.0409)
			(xy 384.723176 -378.069274) (xy 384.748895 -378.129442) (xy 384.766305 -378.192518) (xy 384.775091 -378.25736)
			(xy 384.775094 -378.322795) (xy 384.775094 -378.322797) (xy 388.20479 -378.322797) (xy 388.204793 -378.257358)
			(xy 388.21358 -378.192513) (xy 388.230991 -378.129433) (xy 388.256712 -378.069261) (xy 388.273036 -378.0409)
			(xy 388.276346 -378.034873) (xy 388.279955 -378.021611) (xy 388.280148 -378.014738) (xy 388.280148 -377.728734)
			(xy 388.280592 -377.718563) (xy 388.288368 -377.699768) (xy 388.302747 -377.685381) (xy 388.32154 -377.677597)
			(xy 388.33171 -377.677172) (xy 389.04799 -377.677172) (xy 389.058165 -377.677573) (xy 389.076966 -377.685361)
			(xy 389.091353 -377.699754) (xy 389.099132 -377.718559) (xy 389.099552 -377.728734) (xy 389.099552 -378.014738)
			(xy 389.099761 -378.02161) (xy 389.103357 -378.034873) (xy 389.106664 -378.0409) (xy 389.122964 -378.069273)
			(xy 389.148684 -378.129442) (xy 389.166094 -378.192518) (xy 389.17488 -378.25736) (xy 389.174881 -378.290074)
			(xy 392.603744 -378.290074) (xy 392.607735 -378.227907) (xy 392.619644 -378.16676) (xy 392.639273 -378.107639)
			(xy 392.666302 -378.051513) (xy 392.700286 -377.999304) (xy 392.740668 -377.951869) (xy 392.786784 -377.909988)
			(xy 392.837876 -377.874348) (xy 392.893107 -377.845534) (xy 392.951569 -377.82402) (xy 393.012303 -377.810158)
			(xy 393.07431 -377.804176) (xy 393.136573 -377.806172) (xy 393.19807 -377.816115) (xy 393.257791 -377.833839)
			(xy 393.314754 -377.859056) (xy 393.368025 -377.891349) (xy 393.41673 -377.930189) (xy 393.460067 -377.974939)
			(xy 393.497327 -378.024863) (xy 393.526672 -378.076968) (xy 406.020014 -378.076968) (xy 406.024085 -378.021346)
			(xy 406.036211 -377.966909) (xy 406.056134 -377.914818) (xy 406.08343 -377.866183) (xy 406.117516 -377.82204)
			(xy 406.157665 -377.783331) (xy 406.203023 -377.75088) (xy 406.252623 -377.725379) (xy 406.305407 -377.707372)
			(xy 406.36025 -377.697242) (xy 406.415984 -377.695205) (xy 406.471421 -377.701305) (xy 406.525378 -377.715411)
			(xy 406.576707 -377.737223) (xy 406.624313 -377.766277) (xy 406.667181 -377.801952) (xy 406.704398 -377.843489)
			(xy 406.735171 -377.890002) (xy 406.758843 -377.940499) (xy 406.774911 -377.993906) (xy 406.783031 -378.049082)
			(xy 406.78354 -378.076968) (xy 406.783031 -378.104854) (xy 406.774911 -378.16003) (xy 406.758843 -378.213437)
			(xy 406.735171 -378.263934) (xy 406.704398 -378.310447) (xy 406.667181 -378.351984) (xy 406.624313 -378.387659)
			(xy 406.576707 -378.416713) (xy 406.525378 -378.438525) (xy 406.471421 -378.452631) (xy 406.415984 -378.458731)
			(xy 406.36025 -378.456694) (xy 406.305407 -378.446564) (xy 406.252623 -378.428557) (xy 406.203023 -378.403056)
			(xy 406.157665 -378.370605) (xy 406.117516 -378.331896) (xy 406.08343 -378.287753) (xy 406.056134 -378.239118)
			(xy 406.036211 -378.187027) (xy 406.024085 -378.13259) (xy 406.020014 -378.076968) (xy 393.526672 -378.076968)
			(xy 393.527896 -378.079142) (xy 393.551274 -378.136885) (xy 393.567075 -378.197143) (xy 393.575041 -378.258926)
			(xy 393.57554 -378.290074) (xy 393.575041 -378.321222) (xy 393.567075 -378.383005) (xy 393.551274 -378.443263)
			(xy 393.527896 -378.501006) (xy 393.497327 -378.555285) (xy 393.460067 -378.605209) (xy 393.41673 -378.649959)
			(xy 393.368025 -378.688799) (xy 393.314754 -378.721092) (xy 393.257791 -378.746309) (xy 393.19807 -378.764033)
			(xy 393.136573 -378.773976) (xy 393.07431 -378.775972) (xy 393.012303 -378.76999) (xy 392.951569 -378.756128)
			(xy 392.893107 -378.734614) (xy 392.837876 -378.7058) (xy 392.786784 -378.67016) (xy 392.740668 -378.628279)
			(xy 392.700286 -378.580844) (xy 392.666302 -378.528635) (xy 392.639273 -378.472509) (xy 392.619644 -378.413388)
			(xy 392.607735 -378.352241) (xy 392.603744 -378.290074) (xy 389.174881 -378.290074) (xy 389.174883 -378.322795)
			(xy 389.166103 -378.387638) (xy 389.148698 -378.450716) (xy 389.122984 -378.510887) (xy 389.106664 -378.539248)
			(xy 389.103337 -378.545267) (xy 389.099738 -378.558535) (xy 389.099552 -378.56541) (xy 389.099552 -379.31471)
			(xy 389.099734 -379.321584) (xy 389.103348 -379.334847) (xy 389.106664 -379.340872) (xy 389.123025 -379.369212)
			(xy 389.148739 -379.429388) (xy 389.166143 -379.492471) (xy 389.174921 -379.55732) (xy 389.174916 -379.622759)
			(xy 389.166127 -379.687606) (xy 389.148713 -379.750687) (xy 389.122989 -379.810859) (xy 389.106664 -379.83922)
			(xy 389.103347 -379.845244) (xy 389.099742 -379.858508) (xy 389.099552 -379.865382) (xy 389.099552 -380.151386)
			(xy 389.099125 -380.161558) (xy 389.091342 -380.180354) (xy 389.076958 -380.19474) (xy 389.058162 -380.202524)
			(xy 389.04799 -380.202948) (xy 388.33171 -380.202948) (xy 388.321537 -380.202528) (xy 388.30274 -380.194743)
			(xy 388.288354 -380.180357) (xy 388.280571 -380.161559) (xy 388.280148 -380.151386) (xy 388.280148 -379.865382)
			(xy 388.279969 -379.858508) (xy 388.276353 -379.845245) (xy 388.273036 -379.83922) (xy 388.256753 -379.810837)
			(xy 388.231032 -379.750671) (xy 388.213619 -379.687597) (xy 388.204831 -379.622756) (xy 388.204826 -379.557323)
			(xy 388.213604 -379.492481) (xy 388.231006 -379.429404) (xy 388.256717 -379.369233) (xy 388.273036 -379.340872)
			(xy 388.276356 -379.33485) (xy 388.279959 -379.321584) (xy 388.280148 -379.31471) (xy 388.280148 -378.56541)
			(xy 388.279959 -378.558536) (xy 388.276349 -378.545273) (xy 388.273036 -378.539248) (xy 388.256692 -378.510899)
			(xy 388.230976 -378.450725) (xy 388.213571 -378.387644) (xy 388.20479 -378.322797) (xy 384.775094 -378.322797)
			(xy 384.766314 -378.387638) (xy 384.748909 -378.450716) (xy 384.723196 -378.510887) (xy 384.706876 -378.539248)
			(xy 384.703543 -378.545263) (xy 384.699949 -378.558534) (xy 384.699764 -378.56541) (xy 384.699764 -379.31471)
			(xy 384.699957 -379.321583) (xy 384.703565 -379.334846) (xy 384.706876 -379.340872) (xy 384.723237 -379.369212)
			(xy 384.74895 -379.429388) (xy 384.766353 -379.492471) (xy 384.775132 -379.55732) (xy 384.775126 -379.622759)
			(xy 384.766337 -379.687606) (xy 384.748924 -379.750686) (xy 384.723201 -379.810859) (xy 384.706876 -379.83922)
			(xy 384.703552 -379.84524) (xy 384.699953 -379.858507) (xy 384.699764 -379.865382) (xy 384.699764 -380.151386)
			(xy 384.699325 -380.161556) (xy 384.691545 -380.180351) (xy 384.677164 -380.194736) (xy 384.658372 -380.202522)
			(xy 384.648202 -380.202948) (xy 383.931922 -380.202948) (xy 383.92175 -380.202518) (xy 383.902953 -380.194737)
			(xy 383.888567 -380.180353) (xy 383.880784 -380.161558) (xy 383.88036 -380.151386) (xy 383.88036 -379.865382)
			(xy 383.88018 -379.858508) (xy 383.876564 -379.845245) (xy 383.873248 -379.83922) (xy 383.856964 -379.810837)
			(xy 383.831243 -379.750671) (xy 383.81383 -379.687597) (xy 383.805041 -379.622756) (xy 383.805036 -379.557323)
			(xy 383.813814 -379.49248) (xy 383.831217 -379.429403) (xy 383.856929 -379.369233) (xy 383.873248 -379.340872)
			(xy 383.876569 -379.33485) (xy 383.880171 -379.321584) (xy 383.88036 -379.31471) (xy 383.88036 -378.56541)
			(xy 383.880169 -378.558537) (xy 383.876561 -378.545274) (xy 383.873248 -378.539248) (xy 383.856903 -378.510899)
			(xy 383.831187 -378.450725) (xy 383.813781 -378.387644) (xy 383.805 -378.322797) (xy 380.375104 -378.322797)
			(xy 380.375104 -378.322803) (xy 380.366246 -378.387661) (xy 380.348755 -378.450741) (xy 380.322948 -378.5109)
			(xy 380.30658 -378.539248) (xy 380.303247 -378.545264) (xy 380.299653 -378.558534) (xy 380.299468 -378.56541)
			(xy 380.299468 -379.31471) (xy 380.29966 -379.321583) (xy 380.303269 -379.334846) (xy 380.30658 -379.340872)
			(xy 380.322933 -379.369228) (xy 380.348738 -379.429385) (xy 380.366231 -379.492462) (xy 380.375096 -379.557318)
			(xy 380.375668 -379.590046) (xy 380.375091 -379.622775) (xy 380.366237 -379.687633) (xy 380.34875 -379.750713)
			(xy 380.322947 -379.810871) (xy 380.30658 -379.83922) (xy 380.303257 -379.84524) (xy 380.299657 -379.858507)
			(xy 380.299468 -379.865382) (xy 380.299468 -380.151386) (xy 380.298962 -380.161511) (xy 380.291241 -380.18023)
			(xy 380.27696 -380.194587) (xy 380.258282 -380.202408) (xy 380.24816 -380.202948) (xy 379.53188 -380.202948)
			(xy 379.521731 -380.202496) (xy 379.502987 -380.194703) (xy 379.488666 -380.180316) (xy 379.480958 -380.161537)
			(xy 379.480572 -380.151386) (xy 379.480572 -379.865382) (xy 379.48039 -379.858508) (xy 379.476775 -379.845245)
			(xy 379.47346 -379.83922) (xy 379.457108 -379.810863) (xy 379.431302 -379.750707) (xy 379.413808 -379.68763)
			(xy 379.404944 -379.622774) (xy 379.404372 -379.590046) (xy 378.131777 -379.590046) (xy 378.1228 -379.610974)
			(xy 378.106432 -379.639322) (xy 378.103112 -379.645344) (xy 378.099509 -379.65861) (xy 378.09932 -379.665484)
			(xy 378.09932 -380.414784) (xy 378.099516 -380.421657) (xy 378.103121 -380.43492) (xy 378.106432 -380.440946)
			(xy 378.122809 -380.469289) (xy 378.14861 -380.52945) (xy 378.166097 -380.592532) (xy 378.174952 -380.65739)
			(xy 378.174952 -380.6574) (xy 381.604883 -380.6574) (xy 381.613663 -380.592557) (xy 381.631067 -380.529479)
			(xy 381.65678 -380.469308) (xy 381.6731 -380.440946) (xy 381.676398 -380.434913) (xy 381.680014 -380.421656)
			(xy 381.680212 -380.414784) (xy 381.680212 -379.665484) (xy 381.680025 -379.65861) (xy 381.676413 -379.645348)
			(xy 381.6731 -379.639322) (xy 381.65682 -379.610938) (xy 381.6311 -379.550772) (xy 381.613689 -379.487698)
			(xy 381.604901 -379.422858) (xy 381.604896 -379.357425) (xy 381.613673 -379.292583) (xy 381.631073 -379.229506)
			(xy 381.656782 -379.169336) (xy 381.6731 -379.140974) (xy 381.676424 -379.134954) (xy 381.680024 -379.121687)
			(xy 381.680212 -379.114812) (xy 381.680212 -378.828554) (xy 381.680695 -378.818397) (xy 381.68848 -378.799631)
			(xy 381.702848 -378.785269) (xy 381.721616 -378.777491) (xy 381.731774 -378.776992) (xy 382.448054 -378.776992)
			(xy 382.458203 -378.77757) (xy 382.476962 -378.785321) (xy 382.491328 -378.79966) (xy 382.499112 -378.818406)
			(xy 382.499616 -378.828554) (xy 382.499616 -379.114812) (xy 382.499801 -379.121686) (xy 382.503414 -379.134949)
			(xy 382.506728 -379.140974) (xy 382.523092 -379.169312) (xy 382.548807 -379.229489) (xy 382.566212 -379.292572)
			(xy 382.574991 -379.357421) (xy 382.574986 -379.422861) (xy 382.566196 -379.487709) (xy 382.54878 -379.550789)
			(xy 382.523054 -379.610961) (xy 382.506728 -379.639322) (xy 382.503407 -379.645344) (xy 382.499805 -379.65861)
			(xy 382.499616 -379.665484) (xy 382.499616 -380.414784) (xy 382.499812 -380.421657) (xy 382.503417 -380.43492)
			(xy 382.506728 -380.440946) (xy 382.523068 -380.469298) (xy 382.548786 -380.529471) (xy 382.566193 -380.592551)
			(xy 382.574975 -380.657398) (xy 382.574974 -380.69012) (xy 386.004308 -380.69012) (xy 386.004859 -380.65739)
			(xy 386.013719 -380.592531) (xy 386.031214 -380.529451) (xy 386.057026 -380.469294) (xy 386.073396 -380.440946)
			(xy 386.076694 -380.434913) (xy 386.08031 -380.421656) (xy 386.080508 -380.414784) (xy 386.080508 -379.665484)
			(xy 386.080321 -379.65861) (xy 386.076709 -379.645348) (xy 386.073396 -379.639322) (xy 386.057039 -379.610968)
			(xy 386.031235 -379.55081) (xy 386.013743 -379.487732) (xy 386.00488 -379.422877) (xy 386.004308 -379.390148)
			(xy 386.004872 -379.357418) (xy 386.013728 -379.29256) (xy 386.031219 -379.22948) (xy 386.057027 -379.169322)
			(xy 386.073396 -379.140974) (xy 386.07672 -379.134954) (xy 386.08032 -379.121687) (xy 386.080508 -379.114812)
			(xy 386.080508 -378.828554) (xy 386.080988 -378.818428) (xy 386.088725 -378.799712) (xy 386.103012 -378.785359)
			(xy 386.121693 -378.777535) (xy 386.131816 -378.776992) (xy 386.848096 -378.776992) (xy 386.858249 -378.777425)
			(xy 386.877 -378.785218) (xy 386.891323 -378.799611) (xy 386.899024 -378.818399) (xy 386.899404 -378.828554)
			(xy 386.899404 -379.114812) (xy 386.899591 -379.121686) (xy 386.903202 -379.134948) (xy 386.906516 -379.140974)
			(xy 386.922873 -379.169328) (xy 386.948676 -379.229486) (xy 386.966168 -379.292564) (xy 386.975032 -379.357419)
			(xy 386.975604 -379.390148) (xy 386.975037 -379.422877) (xy 386.966181 -379.487736) (xy 386.948691 -379.550816)
			(xy 386.922884 -379.610974) (xy 386.906516 -379.639322) (xy 386.903195 -379.645343) (xy 386.899593 -379.65861)
			(xy 386.899404 -379.665484) (xy 386.899404 -380.414784) (xy 386.899602 -380.421657) (xy 386.903206 -380.43492)
			(xy 386.906516 -380.440946) (xy 386.922901 -380.469284) (xy 386.948698 -380.529448) (xy 386.966182 -380.592531)
			(xy 386.975037 -380.65739) (xy 386.975037 -380.657399) (xy 390.404955 -380.657399) (xy 390.413737 -380.592555)
			(xy 390.431144 -380.529477) (xy 390.456862 -380.469307) (xy 390.473184 -380.440946) (xy 390.476481 -380.434913)
			(xy 390.480098 -380.421656) (xy 390.480296 -380.414784) (xy 390.480296 -379.665484) (xy 390.480111 -379.65861)
			(xy 390.476498 -379.645347) (xy 390.473184 -379.639322) (xy 390.456901 -379.610939) (xy 390.431177 -379.550773)
			(xy 390.413763 -379.487699) (xy 390.404974 -379.422858) (xy 390.404968 -379.357424) (xy 390.413746 -379.292582)
			(xy 390.43115 -379.229505) (xy 390.456864 -379.169335) (xy 390.473184 -379.140974) (xy 390.476507 -379.134953)
			(xy 390.480108 -379.121687) (xy 390.480296 -379.114812) (xy 390.480296 -378.828554) (xy 390.480795 -378.818398)
			(xy 390.488576 -378.799636) (xy 390.50294 -378.785274) (xy 390.521702 -378.777494) (xy 390.531858 -378.776992)
			(xy 391.248138 -378.776992) (xy 391.258293 -378.777501) (xy 391.277054 -378.785279) (xy 391.291416 -378.79964)
			(xy 391.299197 -378.8184) (xy 391.2997 -378.828554) (xy 391.2997 -379.114812) (xy 391.299887 -379.121686)
			(xy 391.303499 -379.134948) (xy 391.306812 -379.140974) (xy 391.323173 -379.169313) (xy 391.348884 -379.22949)
			(xy 391.366286 -379.292573) (xy 391.375064 -379.357421) (xy 391.375058 -379.422861) (xy 391.36627 -379.487707)
			(xy 391.348857 -379.550788) (xy 391.332076 -379.590046) (xy 392.603744 -379.590046) (xy 392.607735 -379.527879)
			(xy 392.619644 -379.466732) (xy 392.639273 -379.407611) (xy 392.666302 -379.351485) (xy 392.700286 -379.299276)
			(xy 392.740668 -379.251841) (xy 392.786784 -379.20996) (xy 392.837876 -379.17432) (xy 392.893107 -379.145506)
			(xy 392.951569 -379.123992) (xy 393.012303 -379.11013) (xy 393.07431 -379.104148) (xy 393.136573 -379.106144)
			(xy 393.19807 -379.116087) (xy 393.257791 -379.133811) (xy 393.314754 -379.159028) (xy 393.368025 -379.191321)
			(xy 393.41673 -379.230161) (xy 393.460067 -379.274911) (xy 393.497327 -379.324835) (xy 393.527896 -379.379114)
			(xy 393.532363 -379.390148) (xy 394.803892 -379.390148) (xy 394.807883 -379.327981) (xy 394.819792 -379.266834)
			(xy 394.839421 -379.207713) (xy 394.86645 -379.151587) (xy 394.900434 -379.099378) (xy 394.940816 -379.051943)
			(xy 394.986932 -379.010062) (xy 395.038024 -378.974422) (xy 395.093255 -378.945608) (xy 395.151717 -378.924094)
			(xy 395.212451 -378.910232) (xy 395.274458 -378.90425) (xy 395.336721 -378.906246) (xy 395.398218 -378.916189)
			(xy 395.457939 -378.933913) (xy 395.514902 -378.95913) (xy 395.529534 -378.968) (xy 405.011634 -378.968)
			(xy 405.015705 -378.912378) (xy 405.027831 -378.857941) (xy 405.047754 -378.80585) (xy 405.07505 -378.757215)
			(xy 405.109136 -378.713072) (xy 405.149285 -378.674363) (xy 405.194643 -378.641912) (xy 405.244243 -378.616411)
			(xy 405.297027 -378.598404) (xy 405.35187 -378.588274) (xy 405.407604 -378.586237) (xy 405.463041 -378.592337)
			(xy 405.516998 -378.606443) (xy 405.568327 -378.628255) (xy 405.615933 -378.657309) (xy 405.658801 -378.692984)
			(xy 405.696018 -378.734521) (xy 405.726791 -378.781034) (xy 405.750463 -378.831531) (xy 405.766531 -378.884938)
			(xy 405.774651 -378.940114) (xy 405.77516 -378.968) (xy 405.774651 -378.995886) (xy 405.766531 -379.051062)
			(xy 405.750463 -379.104469) (xy 405.726791 -379.154966) (xy 405.696018 -379.201479) (xy 405.658801 -379.243016)
			(xy 405.615933 -379.278691) (xy 405.568327 -379.307745) (xy 405.516998 -379.329557) (xy 405.463041 -379.343663)
			(xy 405.407604 -379.349763) (xy 405.35187 -379.347726) (xy 405.297027 -379.337596) (xy 405.244243 -379.319589)
			(xy 405.194643 -379.294088) (xy 405.149285 -379.261637) (xy 405.109136 -379.222928) (xy 405.07505 -379.178785)
			(xy 405.047754 -379.13015) (xy 405.027831 -379.078059) (xy 405.015705 -379.023622) (xy 405.011634 -378.968)
			(xy 395.529534 -378.968) (xy 395.568173 -378.991423) (xy 395.616878 -379.030263) (xy 395.660215 -379.075013)
			(xy 395.697475 -379.124937) (xy 395.728044 -379.179216) (xy 395.751422 -379.236959) (xy 395.767223 -379.297217)
			(xy 395.775189 -379.359) (xy 395.775688 -379.390148) (xy 395.775189 -379.421296) (xy 395.767223 -379.483079)
			(xy 395.751422 -379.543337) (xy 395.728044 -379.60108) (xy 395.697475 -379.655359) (xy 395.660215 -379.705283)
			(xy 395.616878 -379.750033) (xy 395.568173 -379.788873) (xy 395.514902 -379.821166) (xy 395.457939 -379.846383)
			(xy 395.398218 -379.864107) (xy 395.336721 -379.87405) (xy 395.274458 -379.876046) (xy 395.212451 -379.870064)
			(xy 395.151717 -379.856202) (xy 395.093255 -379.834688) (xy 395.038024 -379.805874) (xy 394.986932 -379.770234)
			(xy 394.940816 -379.728353) (xy 394.900434 -379.680918) (xy 394.86645 -379.628709) (xy 394.839421 -379.572583)
			(xy 394.819792 -379.513462) (xy 394.807883 -379.452315) (xy 394.803892 -379.390148) (xy 393.532363 -379.390148)
			(xy 393.551274 -379.436857) (xy 393.567075 -379.497115) (xy 393.575041 -379.558898) (xy 393.57554 -379.590046)
			(xy 393.575041 -379.621194) (xy 393.567075 -379.682977) (xy 393.551274 -379.743235) (xy 393.527896 -379.800978)
			(xy 393.497327 -379.855257) (xy 393.460067 -379.905181) (xy 393.41673 -379.949931) (xy 393.368025 -379.988771)
			(xy 393.314754 -380.021064) (xy 393.257791 -380.046281) (xy 393.19807 -380.064005) (xy 393.136573 -380.073948)
			(xy 393.07431 -380.075944) (xy 393.012303 -380.069962) (xy 392.951569 -380.0561) (xy 392.893107 -380.034586)
			(xy 392.837876 -380.005772) (xy 392.786784 -379.970132) (xy 392.740668 -379.928251) (xy 392.700286 -379.880816)
			(xy 392.666302 -379.828607) (xy 392.639273 -379.772481) (xy 392.619644 -379.71336) (xy 392.607735 -379.652213)
			(xy 392.603744 -379.590046) (xy 391.332076 -379.590046) (xy 391.323136 -379.61096) (xy 391.306812 -379.639322)
			(xy 391.30349 -379.645343) (xy 391.299889 -379.65861) (xy 391.2997 -379.665484) (xy 391.2997 -380.414784)
			(xy 391.299898 -380.421657) (xy 391.303502 -380.43492) (xy 391.306812 -380.440946) (xy 391.32315 -380.469298)
			(xy 391.348863 -380.529472) (xy 391.366267 -380.592553) (xy 391.375048 -380.657398) (xy 391.375046 -380.69012)
			(xy 394.803892 -380.69012) (xy 394.807883 -380.627953) (xy 394.819792 -380.566806) (xy 394.839421 -380.507685)
			(xy 394.86645 -380.451559) (xy 394.900434 -380.39935) (xy 394.940816 -380.351915) (xy 394.986932 -380.310034)
			(xy 395.038024 -380.274394) (xy 395.093255 -380.24558) (xy 395.151717 -380.224066) (xy 395.212451 -380.210204)
			(xy 395.274458 -380.204222) (xy 395.336721 -380.206218) (xy 395.398218 -380.216161) (xy 395.457939 -380.233885)
			(xy 395.514902 -380.259102) (xy 395.568173 -380.291395) (xy 395.616878 -380.330235) (xy 395.660215 -380.374985)
			(xy 395.697475 -380.424909) (xy 395.728044 -380.479188) (xy 395.751422 -380.536931) (xy 395.767223 -380.597189)
			(xy 395.775189 -380.658972) (xy 395.775688 -380.69012) (xy 395.775189 -380.721268) (xy 395.767223 -380.783051)
			(xy 395.751422 -380.843309) (xy 395.728044 -380.901052) (xy 395.697475 -380.955331) (xy 395.660215 -381.005255)
			(xy 395.616878 -381.050005) (xy 395.568173 -381.088845) (xy 395.514902 -381.121138) (xy 395.457939 -381.146355)
			(xy 395.398218 -381.164079) (xy 395.336721 -381.174022) (xy 395.274458 -381.176018) (xy 395.212451 -381.170036)
			(xy 395.151717 -381.156174) (xy 395.093255 -381.13466) (xy 395.038024 -381.105846) (xy 394.986932 -381.070206)
			(xy 394.940816 -381.028325) (xy 394.900434 -380.98089) (xy 394.86645 -380.928681) (xy 394.839421 -380.872555)
			(xy 394.819792 -380.813434) (xy 394.807883 -380.752287) (xy 394.803892 -380.69012) (xy 391.375046 -380.69012)
			(xy 391.375045 -380.722836) (xy 391.36626 -380.787681) (xy 391.348852 -380.85076) (xy 391.323134 -380.910932)
			(xy 391.306812 -380.939294) (xy 391.3035 -380.94532) (xy 391.299892 -380.958583) (xy 391.2997 -380.965456)
			(xy 391.2997 -381.251206) (xy 391.299172 -381.261359) (xy 391.291403 -381.280121) (xy 391.277048 -381.294485)
			(xy 391.258291 -381.302266) (xy 391.248138 -381.302768) (xy 390.531858 -381.302768) (xy 390.521698 -381.302301)
			(xy 390.502929 -381.294514) (xy 390.488566 -381.28014) (xy 390.480792 -381.261366) (xy 390.480296 -381.251206)
			(xy 390.480296 -380.965456) (xy 390.480083 -380.958584) (xy 390.476489 -380.945322) (xy 390.473184 -380.939294)
			(xy 390.456877 -380.910924) (xy 390.431156 -380.850755) (xy 390.413744 -380.787678) (xy 390.404958 -380.722835)
			(xy 390.404955 -380.657399) (xy 386.975037 -380.657399) (xy 386.975604 -380.69012) (xy 386.975024 -380.722849)
			(xy 386.966172 -380.787707) (xy 386.948686 -380.850787) (xy 386.922883 -380.910945) (xy 386.906516 -380.939294)
			(xy 386.903205 -380.94532) (xy 386.899597 -380.958583) (xy 386.899404 -380.965456) (xy 386.899404 -381.251206)
			(xy 386.89888 -381.261328) (xy 386.891158 -381.280041) (xy 386.876884 -381.294395) (xy 386.858215 -381.302222)
			(xy 386.848096 -381.302768) (xy 386.131816 -381.302768) (xy 386.121659 -381.302365) (xy 386.102901 -381.294568)
			(xy 386.088576 -381.280166) (xy 386.080881 -381.261365) (xy 386.080508 -381.251206) (xy 386.080508 -380.965456)
			(xy 386.080293 -380.958584) (xy 386.0767 -380.945322) (xy 386.073396 -380.939294) (xy 386.057028 -380.910946)
			(xy 386.031227 -380.850786) (xy 386.013738 -380.787706) (xy 386.004878 -380.722849) (xy 386.004308 -380.69012)
			(xy 382.574974 -380.69012) (xy 382.574973 -380.722836) (xy 382.566187 -380.787682) (xy 382.548775 -380.850762)
			(xy 382.523053 -380.910933) (xy 382.506728 -380.939294) (xy 382.503417 -380.945321) (xy 382.499809 -380.958583)
			(xy 382.499616 -380.965456) (xy 382.499616 -381.251206) (xy 382.49924 -381.261384) (xy 382.491444 -381.280187)
			(xy 382.477044 -381.294574) (xy 382.458232 -381.30235) (xy 382.448054 -381.302768) (xy 381.731774 -381.302768)
			(xy 381.721615 -381.302288) (xy 381.702847 -381.294506) (xy 381.688482 -381.280137) (xy 381.680708 -381.261365)
			(xy 381.680212 -381.251206) (xy 381.680212 -380.965456) (xy 381.679997 -380.958584) (xy 381.676404 -380.945322)
			(xy 381.6731 -380.939294) (xy 381.656796 -380.910923) (xy 381.631079 -380.850754) (xy 381.61367 -380.787677)
			(xy 381.604885 -380.722835) (xy 381.604883 -380.6574) (xy 378.174952 -380.6574) (xy 378.17552 -380.69012)
			(xy 378.174938 -380.722849) (xy 378.166087 -380.787706) (xy 378.148601 -380.850787) (xy 378.122798 -380.910945)
			(xy 378.106432 -380.939294) (xy 378.103122 -380.945321) (xy 378.099513 -380.958583) (xy 378.09932 -380.965456)
			(xy 378.09932 -381.251206) (xy 378.098877 -381.261338) (xy 378.09114 -381.280067) (xy 378.07684 -381.294424)
			(xy 378.058142 -381.302236) (xy 378.048012 -381.302768) (xy 377.331732 -381.302768) (xy 377.321576 -381.302352)
			(xy 377.302818 -381.294561) (xy 377.288492 -381.280162) (xy 377.280797 -381.261364) (xy 377.280424 -381.251206)
			(xy 377.280424 -380.965456) (xy 377.280208 -380.958585) (xy 377.276616 -380.945322) (xy 377.273312 -380.939294)
			(xy 377.256945 -380.910945) (xy 377.231143 -380.850786) (xy 377.213654 -380.787706) (xy 377.204794 -380.722849)
			(xy 377.204224 -380.69012) (xy 351.775776 -380.69012) (xy 351.775277 -380.721268) (xy 351.767311 -380.783051)
			(xy 351.75151 -380.843309) (xy 351.728132 -380.901052) (xy 351.697563 -380.955331) (xy 351.660303 -381.005255)
			(xy 351.616966 -381.050005) (xy 351.568261 -381.088845) (xy 351.51499 -381.121138) (xy 351.458027 -381.146355)
			(xy 351.398306 -381.164079) (xy 351.336809 -381.174022) (xy 351.274546 -381.176018) (xy 351.212539 -381.170036)
			(xy 351.151805 -381.156174) (xy 351.093343 -381.13466) (xy 351.038112 -381.105846) (xy 350.98702 -381.070206)
			(xy 350.940904 -381.028325) (xy 350.900522 -380.98089) (xy 350.866538 -380.928681) (xy 350.839509 -380.872555)
			(xy 350.81988 -380.813434) (xy 350.807971 -380.752287) (xy 350.80398 -380.69012) (xy 347.375136 -380.69012)
			(xy 347.375135 -380.722836) (xy 347.36635 -380.787681) (xy 347.348941 -380.85076) (xy 347.323222 -380.910932)
			(xy 347.3069 -380.939294) (xy 347.303587 -380.94532) (xy 347.29998 -380.958583) (xy 347.299788 -380.965456)
			(xy 347.299788 -381.251206) (xy 347.299272 -381.261361) (xy 347.2915 -381.280125) (xy 347.277142 -381.294489)
			(xy 347.258381 -381.302268) (xy 347.248226 -381.302768) (xy 346.531946 -381.302768) (xy 346.521778 -381.302299)
			(xy 346.502986 -381.29453) (xy 346.488599 -381.280158) (xy 346.480812 -381.261373) (xy 346.480384 -381.251206)
			(xy 346.480384 -380.965456) (xy 346.480173 -380.958584) (xy 346.476578 -380.945321) (xy 346.473272 -380.939294)
			(xy 346.456966 -380.910924) (xy 346.431245 -380.850755) (xy 346.413834 -380.787678) (xy 346.405047 -380.722835)
			(xy 346.405045 -380.657399) (xy 342.975125 -380.657399) (xy 342.975692 -380.69012) (xy 342.975114 -380.722849)
			(xy 342.966262 -380.787707) (xy 342.948775 -380.850787) (xy 342.922971 -380.910946) (xy 342.906604 -380.939294)
			(xy 342.903292 -380.94532) (xy 342.899684 -380.958583) (xy 342.899492 -380.965456) (xy 342.899492 -381.251206)
			(xy 342.898979 -381.261329) (xy 342.891255 -381.280044) (xy 342.876978 -381.294399) (xy 342.858304 -381.302224)
			(xy 342.848184 -381.302768) (xy 342.131904 -381.302768) (xy 342.121746 -381.302374) (xy 342.102988 -381.294574)
			(xy 342.088663 -381.280168) (xy 342.080969 -381.261366) (xy 342.080596 -381.251206) (xy 342.080596 -380.965456)
			(xy 342.080383 -380.958584) (xy 342.076789 -380.945322) (xy 342.073484 -380.939294) (xy 342.057115 -380.910947)
			(xy 342.031314 -380.850787) (xy 342.013826 -380.787706) (xy 342.004966 -380.722849) (xy 342.004396 -380.69012)
			(xy 338.575064 -380.69012) (xy 338.575063 -380.722836) (xy 338.566276 -380.787683) (xy 338.548864 -380.850762)
			(xy 338.523141 -380.910933) (xy 338.506816 -380.939294) (xy 338.503505 -380.94532) (xy 338.499897 -380.958583)
			(xy 338.499704 -380.965456) (xy 338.499704 -381.251206) (xy 338.499172 -381.261359) (xy 338.491404 -381.28012)
			(xy 338.47705 -381.294484) (xy 338.458295 -381.302265) (xy 338.448142 -381.302768) (xy 337.731862 -381.302768)
			(xy 337.721703 -381.302298) (xy 337.702934 -381.294512) (xy 337.68857 -381.280139) (xy 337.680796 -381.261366)
			(xy 337.6803 -381.251206) (xy 337.6803 -380.965456) (xy 337.680086 -380.958584) (xy 337.676493 -380.945322)
			(xy 337.673188 -380.939294) (xy 337.656884 -380.910923) (xy 337.631168 -380.850753) (xy 337.61376 -380.787677)
			(xy 337.604975 -380.722834) (xy 337.604973 -380.6574) (xy 334.175041 -380.6574) (xy 334.175608 -380.69012)
			(xy 334.175028 -380.722849) (xy 334.166176 -380.787707) (xy 334.14869 -380.850787) (xy 334.122886 -380.910945)
			(xy 334.10652 -380.939294) (xy 334.103209 -380.94532) (xy 334.099601 -380.958583) (xy 334.099408 -380.965456)
			(xy 334.099408 -381.251206) (xy 334.09888 -381.261327) (xy 334.091159 -381.280039) (xy 334.076886 -381.294394)
			(xy 334.058218 -381.302221) (xy 334.0481 -381.302768) (xy 333.33182 -381.302768) (xy 333.321663 -381.302362)
			(xy 333.302905 -381.294567) (xy 333.28858 -381.280165) (xy 333.280885 -381.261365) (xy 333.280512 -381.251206)
			(xy 333.280512 -380.965456) (xy 333.280297 -380.958584) (xy 333.276704 -380.945322) (xy 333.2734 -380.939294)
			(xy 333.257032 -380.910946) (xy 333.231231 -380.850786) (xy 333.213742 -380.787706) (xy 333.204882 -380.722849)
			(xy 333.204312 -380.69012) (xy 309.717694 -380.69012) (xy 309.717694 -382.22271) (xy 331.005013 -382.22271)
			(xy 331.005014 -382.157273) (xy 331.013799 -382.092427) (xy 331.031209 -382.029348) (xy 331.056929 -381.969177)
			(xy 331.073252 -381.940816) (xy 331.076557 -381.934787) (xy 331.080169 -381.921527) (xy 331.080364 -381.914654)
			(xy 331.080364 -381.628904) (xy 331.080824 -381.618755) (xy 331.088612 -381.600009) (xy 331.102996 -381.585687)
			(xy 331.121775 -381.577981) (xy 331.131926 -381.577596) (xy 331.848206 -381.577596) (xy 331.858328 -381.57812)
			(xy 331.877041 -381.585842) (xy 331.891395 -381.600116) (xy 331.899222 -381.618785) (xy 331.899768 -381.628904)
			(xy 331.899768 -381.914654) (xy 331.899981 -381.921526) (xy 331.903575 -381.934788) (xy 331.90688 -381.940816)
			(xy 331.923193 -381.969182) (xy 331.948911 -382.029352) (xy 331.966319 -382.09243) (xy 331.975103 -382.157274)
			(xy 331.975104 -382.222709) (xy 331.966322 -382.287553) (xy 331.948916 -382.350631) (xy 331.923201 -382.410803)
			(xy 331.90688 -382.439164) (xy 331.903577 -382.445194) (xy 331.899964 -382.458454) (xy 331.899768 -382.465326)
			(xy 331.899768 -383.21488) (xy 331.899972 -383.221752) (xy 331.903572 -383.235015) (xy 331.90688 -383.241042)
			(xy 331.923215 -383.269396) (xy 331.948931 -383.329569) (xy 331.966336 -383.392649) (xy 331.975118 -383.457495)
			(xy 331.975116 -383.522933) (xy 331.966331 -383.587778) (xy 331.948921 -383.650857) (xy 331.923203 -383.711029)
			(xy 331.90688 -383.73939) (xy 331.903567 -383.745416) (xy 331.899961 -383.758679) (xy 331.899768 -383.765552)
			(xy 331.899768 -384.051556) (xy 331.899342 -384.061711) (xy 331.891555 -384.080469) (xy 331.877159 -384.094795)
			(xy 331.858363 -384.10249) (xy 331.848206 -384.102864) (xy 331.131926 -384.102864) (xy 331.121801 -384.102352)
			(xy 331.103082 -384.094634) (xy 331.088724 -384.080355) (xy 331.080904 -384.061678) (xy 331.080364 -384.051556)
			(xy 331.080364 -383.765552) (xy 331.080157 -383.75868) (xy 331.076559 -383.745417) (xy 331.073252 -383.73939)
			(xy 331.056943 -383.711021) (xy 331.031223 -383.650852) (xy 331.013813 -383.587775) (xy 331.005028 -383.522932)
			(xy 331.005026 -383.457496) (xy 331.013808 -383.392652) (xy 331.031214 -383.329574) (xy 331.05693 -383.269403)
			(xy 331.073252 -383.241042) (xy 331.076548 -383.235008) (xy 331.080166 -383.221752) (xy 331.080364 -383.21488)
			(xy 331.080364 -382.465326) (xy 331.080167 -382.458453) (xy 331.076563 -382.44519) (xy 331.073252 -382.439164)
			(xy 331.056921 -382.410808) (xy 331.031203 -382.350635) (xy 331.013796 -382.287556) (xy 331.005013 -382.22271)
			(xy 309.717694 -382.22271) (xy 309.717694 -384.590036) (xy 333.204312 -384.590036) (xy 333.20487 -384.557306)
			(xy 333.213728 -384.492448) (xy 333.23122 -384.429367) (xy 333.25703 -384.36921) (xy 333.2734 -384.340862)
			(xy 333.276728 -384.334844) (xy 333.280325 -384.321575) (xy 333.280512 -384.3147) (xy 333.280512 -383.5654)
			(xy 333.280319 -383.558527) (xy 333.276711 -383.545264) (xy 333.2734 -383.539238) (xy 333.25705 -383.51088)
			(xy 333.231244 -383.450724) (xy 333.21375 -383.387647) (xy 333.204885 -383.322792) (xy 333.204312 -383.290064)
			(xy 333.204882 -383.257335) (xy 333.213737 -383.192477) (xy 333.231226 -383.129396) (xy 333.257032 -383.069238)
			(xy 333.2734 -383.04089) (xy 333.276718 -383.034867) (xy 333.280322 -383.021602) (xy 333.280512 -383.014728)
			(xy 333.280512 -382.728724) (xy 333.280936 -382.718602) (xy 333.288678 -382.699896) (xy 333.302993 -382.685581)
			(xy 333.321698 -382.677837) (xy 333.33182 -382.677416) (xy 334.0481 -382.677416) (xy 334.058224 -382.677816)
			(xy 334.076931 -382.685568) (xy 334.091246 -382.699889) (xy 334.098988 -382.718599) (xy 334.099408 -382.728724)
			(xy 334.099408 -383.014728) (xy 334.099588 -383.021602) (xy 334.103204 -383.034865) (xy 334.10652 -383.04089)
			(xy 334.122884 -383.06924) (xy 334.148685 -383.1294) (xy 334.166176 -383.192479) (xy 334.175037 -383.257335)
			(xy 334.175608 -383.290064) (xy 334.175047 -383.322794) (xy 334.16619 -383.387652) (xy 334.148698 -383.450732)
			(xy 334.131759 -383.490216) (xy 335.40446 -383.490216) (xy 335.405016 -383.457486) (xy 335.413875 -383.392628)
			(xy 335.431369 -383.329548) (xy 335.457178 -383.26939) (xy 335.473548 -383.241042) (xy 335.476844 -383.235008)
			(xy 335.480462 -383.221752) (xy 335.48066 -383.21488) (xy 335.48066 -382.465326) (xy 335.480463 -382.458453)
			(xy 335.476859 -382.44519) (xy 335.473548 -382.439164) (xy 335.457173 -382.41082) (xy 335.431372 -382.350659)
			(xy 335.413885 -382.287578) (xy 335.405028 -382.22272) (xy 335.40446 -382.18999) (xy 335.405049 -382.157261)
			(xy 335.413899 -382.092404) (xy 335.431383 -382.029324) (xy 335.457183 -381.969165) (xy 335.473548 -381.940816)
			(xy 335.476853 -381.934786) (xy 335.480465 -381.921527) (xy 335.48066 -381.914654) (xy 335.48066 -381.628904)
			(xy 335.481187 -381.6188) (xy 335.488916 -381.60013) (xy 335.5032 -381.585837) (xy 335.521865 -381.578095)
			(xy 335.531968 -381.577596) (xy 336.248248 -381.577596) (xy 336.258359 -381.578046) (xy 336.277038 -381.585799)
			(xy 336.291331 -381.600106) (xy 336.299064 -381.618792) (xy 336.299556 -381.628904) (xy 336.299556 -381.914654)
			(xy 336.299758 -381.921527) (xy 336.303359 -381.93479) (xy 336.306668 -381.940816) (xy 336.323037 -381.969163)
			(xy 336.348839 -382.029323) (xy 336.366327 -382.092403) (xy 336.375187 -382.157261) (xy 336.375756 -382.18999)
			(xy 336.375201 -382.22271) (xy 339.805099 -382.22271) (xy 339.8051 -382.157273) (xy 339.813885 -382.092428)
			(xy 339.831294 -382.029349) (xy 339.857013 -381.969177) (xy 339.873336 -381.940816) (xy 339.87664 -381.934786)
			(xy 339.880253 -381.921527) (xy 339.880448 -381.914654) (xy 339.880448 -381.628904) (xy 339.880924 -381.618757)
			(xy 339.888708 -381.600014) (xy 339.903088 -381.585693) (xy 339.921861 -381.577984) (xy 339.93201 -381.577596)
			(xy 340.64829 -381.577596) (xy 340.658411 -381.578133) (xy 340.677123 -381.58585) (xy 340.691478 -381.60012)
			(xy 340.699306 -381.618786) (xy 340.699852 -381.628904) (xy 340.699852 -381.914654) (xy 340.700055 -381.921527)
			(xy 340.703655 -381.93479) (xy 340.706964 -381.940816) (xy 340.723278 -381.969182) (xy 340.748996 -382.029352)
			(xy 340.766405 -382.09243) (xy 340.775189 -382.157273) (xy 340.775191 -382.222709) (xy 340.775191 -382.22271)
			(xy 344.204889 -382.22271) (xy 344.20489 -382.157273) (xy 344.213675 -382.092428) (xy 344.231083 -382.029349)
			(xy 344.256802 -381.969177) (xy 344.273124 -381.940816) (xy 344.276435 -381.934789) (xy 344.280042 -381.921527)
			(xy 344.280236 -381.914654) (xy 344.280236 -381.628904) (xy 344.280626 -381.618746) (xy 344.288427 -381.599986)
			(xy 344.302834 -381.585662) (xy 344.321637 -381.577968) (xy 344.331798 -381.577596) (xy 345.048078 -381.577596)
			(xy 345.058198 -381.578143) (xy 345.07691 -381.585856) (xy 345.091266 -381.600123) (xy 345.099094 -381.618787)
			(xy 345.09964 -381.628904) (xy 345.09964 -381.914654) (xy 345.099844 -381.921526) (xy 345.103444 -381.934789)
			(xy 345.106752 -381.940816) (xy 345.123066 -381.969182) (xy 345.148785 -382.029352) (xy 345.166194 -382.09243)
			(xy 345.174979 -382.157273) (xy 345.174979 -382.18999) (xy 348.603832 -382.18999) (xy 348.607823 -382.127823)
			(xy 348.619732 -382.066676) (xy 348.639361 -382.007555) (xy 348.66639 -381.951429) (xy 348.700374 -381.89922)
			(xy 348.740756 -381.851785) (xy 348.786872 -381.809904) (xy 348.837964 -381.774264) (xy 348.893195 -381.74545)
			(xy 348.951657 -381.723936) (xy 349.012391 -381.710074) (xy 349.074398 -381.704092) (xy 349.136661 -381.706088)
			(xy 349.188701 -381.714502) (xy 360.796838 -381.714502) (xy 360.800909 -381.65888) (xy 360.813035 -381.604443)
			(xy 360.832958 -381.552352) (xy 360.860254 -381.503717) (xy 360.89434 -381.459574) (xy 360.934489 -381.420865)
			(xy 360.979847 -381.388414) (xy 361.029447 -381.362913) (xy 361.082231 -381.344906) (xy 361.137074 -381.334776)
			(xy 361.192808 -381.332739) (xy 361.248245 -381.338839) (xy 361.302202 -381.352945) (xy 361.353531 -381.374757)
			(xy 361.401137 -381.403811) (xy 361.444005 -381.439486) (xy 361.481222 -381.481023) (xy 361.495709 -381.50292)
			(xy 403.816564 -381.50292) (xy 403.820635 -381.447298) (xy 403.832761 -381.392861) (xy 403.852684 -381.34077)
			(xy 403.87998 -381.292135) (xy 403.914066 -381.247992) (xy 403.954215 -381.209283) (xy 403.999573 -381.176832)
			(xy 404.049173 -381.151331) (xy 404.101957 -381.133324) (xy 404.1568 -381.123194) (xy 404.212534 -381.121157)
			(xy 404.267971 -381.127257) (xy 404.321928 -381.141363) (xy 404.373257 -381.163175) (xy 404.420863 -381.192229)
			(xy 404.463731 -381.227904) (xy 404.500948 -381.269441) (xy 404.531721 -381.315954) (xy 404.555393 -381.366451)
			(xy 404.571461 -381.419858) (xy 404.579581 -381.475034) (xy 404.58009 -381.50292) (xy 404.579581 -381.530806)
			(xy 404.571461 -381.585982) (xy 404.555393 -381.639389) (xy 404.531721 -381.689886) (xy 404.500948 -381.736399)
			(xy 404.463731 -381.777936) (xy 404.420863 -381.813611) (xy 404.373257 -381.842665) (xy 404.321928 -381.864477)
			(xy 404.267971 -381.878583) (xy 404.212534 -381.884683) (xy 404.1568 -381.882646) (xy 404.101957 -381.872516)
			(xy 404.049173 -381.854509) (xy 403.999573 -381.829008) (xy 403.954215 -381.796557) (xy 403.914066 -381.757848)
			(xy 403.87998 -381.713705) (xy 403.852684 -381.66507) (xy 403.832761 -381.612979) (xy 403.820635 -381.558542)
			(xy 403.816564 -381.50292) (xy 361.495709 -381.50292) (xy 361.511995 -381.527536) (xy 361.535667 -381.578033)
			(xy 361.551735 -381.63144) (xy 361.559855 -381.686616) (xy 361.560364 -381.714502) (xy 361.559855 -381.742388)
			(xy 361.551735 -381.797564) (xy 361.535667 -381.850971) (xy 361.511995 -381.901468) (xy 361.481222 -381.947981)
			(xy 361.444005 -381.989518) (xy 361.401137 -382.025193) (xy 361.353531 -382.054247) (xy 361.302202 -382.076059)
			(xy 361.248245 -382.090165) (xy 361.192808 -382.096265) (xy 361.137074 -382.094228) (xy 361.082231 -382.084098)
			(xy 361.029447 -382.066091) (xy 360.979847 -382.04059) (xy 360.934489 -382.008139) (xy 360.89434 -381.96943)
			(xy 360.860254 -381.925287) (xy 360.832958 -381.876652) (xy 360.813035 -381.824561) (xy 360.800909 -381.770124)
			(xy 360.796838 -381.714502) (xy 349.188701 -381.714502) (xy 349.198158 -381.716031) (xy 349.257879 -381.733755)
			(xy 349.314842 -381.758972) (xy 349.368113 -381.791265) (xy 349.416818 -381.830105) (xy 349.460155 -381.874855)
			(xy 349.497415 -381.924779) (xy 349.527984 -381.979058) (xy 349.551362 -382.036801) (xy 349.567163 -382.097059)
			(xy 349.575129 -382.158842) (xy 349.575628 -382.18999) (xy 349.575129 -382.221138) (xy 349.574926 -382.22271)
			(xy 375.004923 -382.22271) (xy 375.004924 -382.157273) (xy 375.01371 -382.092427) (xy 375.03112 -382.029348)
			(xy 375.05684 -381.969177) (xy 375.073164 -381.940816) (xy 375.07647 -381.934787) (xy 375.080082 -381.921527)
			(xy 375.080276 -381.914654) (xy 375.080276 -381.628904) (xy 375.080724 -381.618753) (xy 375.088514 -381.600005)
			(xy 375.102902 -381.585683) (xy 375.121685 -381.577979) (xy 375.131838 -381.577596) (xy 375.848118 -381.577596)
			(xy 375.85824 -381.57811) (xy 375.876954 -381.585836) (xy 375.891308 -381.600113) (xy 375.899134 -381.618784)
			(xy 375.89968 -381.628904) (xy 375.89968 -381.914654) (xy 375.899892 -381.921526) (xy 375.903487 -381.934788)
			(xy 375.906792 -381.940816) (xy 375.923105 -381.969182) (xy 375.948822 -382.029353) (xy 375.966229 -382.09243)
			(xy 375.975013 -382.157274) (xy 375.975015 -382.222709) (xy 375.966233 -382.287553) (xy 375.948827 -382.350631)
			(xy 375.923113 -382.410802) (xy 375.906792 -382.439164) (xy 375.903489 -382.445195) (xy 375.899876 -382.458454)
			(xy 375.89968 -382.465326) (xy 375.89968 -383.21488) (xy 375.899882 -383.221752) (xy 375.903484 -383.235015)
			(xy 375.906792 -383.241042) (xy 375.923127 -383.269396) (xy 375.948842 -383.329569) (xy 375.966247 -383.392649)
			(xy 375.975028 -383.457495) (xy 375.975026 -383.522932) (xy 375.966241 -383.587777) (xy 375.948832 -383.650857)
			(xy 375.923114 -383.711028) (xy 375.906792 -383.73939) (xy 375.90348 -383.745416) (xy 375.899873 -383.758679)
			(xy 375.89968 -383.765552) (xy 375.89968 -384.051556) (xy 375.899242 -384.06171) (xy 375.891457 -384.080465)
			(xy 375.877065 -384.094791) (xy 375.858274 -384.102488) (xy 375.848118 -384.102864) (xy 375.131838 -384.102864)
			(xy 375.121714 -384.102342) (xy 375.102995 -384.094628) (xy 375.088637 -384.080352) (xy 375.080816 -384.061677)
			(xy 375.080276 -384.051556) (xy 375.080276 -383.765552) (xy 375.080067 -383.75868) (xy 375.076471 -383.745417)
			(xy 375.073164 -383.73939) (xy 375.056855 -383.711022) (xy 375.031134 -383.650852) (xy 375.013724 -383.587775)
			(xy 375.004938 -383.522932) (xy 375.004936 -383.457496) (xy 375.013718 -383.392652) (xy 375.031125 -383.329574)
			(xy 375.056842 -383.269403) (xy 375.073164 -383.241042) (xy 375.076461 -383.235009) (xy 375.080078 -383.221752)
			(xy 375.080276 -383.21488) (xy 375.080276 -382.465326) (xy 375.080077 -382.458453) (xy 375.076474 -382.44519)
			(xy 375.073164 -382.439164) (xy 375.056833 -382.410808) (xy 375.031114 -382.350636) (xy 375.013706 -382.287556)
			(xy 375.004923 -382.22271) (xy 349.574926 -382.22271) (xy 349.567163 -382.282921) (xy 349.551362 -382.343179)
			(xy 349.527984 -382.400922) (xy 349.497415 -382.455201) (xy 349.460155 -382.505125) (xy 349.416818 -382.549875)
			(xy 349.368113 -382.588715) (xy 349.314842 -382.621008) (xy 349.257879 -382.646225) (xy 349.198158 -382.663949)
			(xy 349.136661 -382.673892) (xy 349.074398 -382.675888) (xy 349.012391 -382.669906) (xy 348.951657 -382.656044)
			(xy 348.893195 -382.63453) (xy 348.837964 -382.605716) (xy 348.786872 -382.570076) (xy 348.740756 -382.528195)
			(xy 348.700374 -382.48076) (xy 348.66639 -382.428551) (xy 348.639361 -382.372425) (xy 348.619732 -382.313304)
			(xy 348.607823 -382.252157) (xy 348.603832 -382.18999) (xy 345.174979 -382.18999) (xy 345.17498 -382.222709)
			(xy 345.166198 -382.287554) (xy 345.148791 -382.350632) (xy 345.123074 -382.410803) (xy 345.106752 -382.439164)
			(xy 345.103454 -382.445197) (xy 345.099837 -382.458454) (xy 345.09964 -382.465326) (xy 345.09964 -383.21488)
			(xy 345.099835 -383.221753) (xy 345.103441 -383.235016) (xy 345.106752 -383.241042) (xy 345.123088 -383.269396)
			(xy 345.145907 -383.322789) (xy 346.405015 -383.322789) (xy 346.40502 -383.257349) (xy 346.413808 -383.192503)
			(xy 346.431222 -383.129422) (xy 346.456946 -383.069251) (xy 346.473272 -383.04089) (xy 346.476588 -383.034866)
			(xy 346.480193 -383.021602) (xy 346.480384 -383.014728) (xy 346.480384 -382.728724) (xy 346.480841 -382.718573)
			(xy 346.488625 -382.699825) (xy 346.503011 -382.685501) (xy 346.521794 -382.677797) (xy 346.531946 -382.677416)
			(xy 347.248226 -382.677416) (xy 347.258351 -382.677904) (xy 347.277069 -382.685636) (xy 347.291423 -382.699921)
			(xy 347.299246 -382.718601) (xy 347.299788 -382.728724) (xy 347.299788 -383.014728) (xy 347.299971 -383.021602)
			(xy 347.303585 -383.034865) (xy 347.3069 -383.04089) (xy 347.323191 -383.069268) (xy 347.348909 -383.129436)
			(xy 347.366319 -383.192511) (xy 347.375106 -383.257352) (xy 347.37511 -383.322786) (xy 347.366331 -383.387628)
			(xy 347.348929 -383.450706) (xy 347.332047 -383.490216) (xy 348.603832 -383.490216) (xy 348.607823 -383.428049)
			(xy 348.619732 -383.366902) (xy 348.639361 -383.307781) (xy 348.66639 -383.251655) (xy 348.700374 -383.199446)
			(xy 348.740756 -383.152011) (xy 348.786872 -383.11013) (xy 348.837964 -383.07449) (xy 348.893195 -383.045676)
			(xy 348.951657 -383.024162) (xy 349.012391 -383.0103) (xy 349.074398 -383.004318) (xy 349.136661 -383.006314)
			(xy 349.198158 -383.016257) (xy 349.257879 -383.033981) (xy 349.314842 -383.059198) (xy 349.368113 -383.091491)
			(xy 349.416818 -383.130331) (xy 349.460155 -383.175081) (xy 349.497415 -383.225005) (xy 349.527984 -383.279284)
			(xy 349.532348 -383.290064) (xy 350.80398 -383.290064) (xy 350.807971 -383.227897) (xy 350.81988 -383.16675)
			(xy 350.839509 -383.107629) (xy 350.866538 -383.051503) (xy 350.900522 -382.999294) (xy 350.940904 -382.951859)
			(xy 350.98702 -382.909978) (xy 351.038112 -382.874338) (xy 351.093343 -382.845524) (xy 351.151805 -382.82401)
			(xy 351.212539 -382.810148) (xy 351.274546 -382.804166) (xy 351.336809 -382.806162) (xy 351.398306 -382.816105)
			(xy 351.458027 -382.833829) (xy 351.51499 -382.859046) (xy 351.568261 -382.891339) (xy 351.616966 -382.930179)
			(xy 351.660303 -382.974929) (xy 351.697563 -383.024853) (xy 351.728132 -383.079132) (xy 351.75151 -383.136875)
			(xy 351.767311 -383.197133) (xy 351.775277 -383.258916) (xy 351.775776 -383.290064) (xy 351.775277 -383.321212)
			(xy 351.767311 -383.382995) (xy 351.75151 -383.443253) (xy 351.728132 -383.500996) (xy 351.697563 -383.555275)
			(xy 351.660303 -383.605199) (xy 351.616966 -383.649949) (xy 351.568261 -383.688789) (xy 351.51499 -383.721082)
			(xy 351.458027 -383.746299) (xy 351.398306 -383.764023) (xy 351.336809 -383.773966) (xy 351.274546 -383.775962)
			(xy 351.212539 -383.76998) (xy 351.151805 -383.756118) (xy 351.093343 -383.734604) (xy 351.038112 -383.70579)
			(xy 350.98702 -383.67015) (xy 350.940904 -383.628269) (xy 350.900522 -383.580834) (xy 350.866538 -383.528625)
			(xy 350.839509 -383.472499) (xy 350.81988 -383.413378) (xy 350.807971 -383.352231) (xy 350.80398 -383.290064)
			(xy 349.532348 -383.290064) (xy 349.551362 -383.337027) (xy 349.567163 -383.397285) (xy 349.575129 -383.459068)
			(xy 349.575628 -383.490216) (xy 349.575129 -383.521364) (xy 349.567163 -383.583147) (xy 349.551362 -383.643405)
			(xy 349.527984 -383.701148) (xy 349.497415 -383.755427) (xy 349.460155 -383.805351) (xy 349.416818 -383.850101)
			(xy 349.368113 -383.888941) (xy 349.314842 -383.921234) (xy 349.257879 -383.946451) (xy 349.198158 -383.964175)
			(xy 349.136661 -383.974118) (xy 349.074398 -383.976114) (xy 349.012391 -383.970132) (xy 348.951657 -383.95627)
			(xy 348.893195 -383.934756) (xy 348.837964 -383.905942) (xy 348.786872 -383.870302) (xy 348.740756 -383.828421)
			(xy 348.700374 -383.780986) (xy 348.66639 -383.728777) (xy 348.639361 -383.672651) (xy 348.619732 -383.61353)
			(xy 348.607823 -383.552383) (xy 348.603832 -383.490216) (xy 347.332047 -383.490216) (xy 347.323219 -383.510876)
			(xy 347.3069 -383.539238) (xy 347.303572 -383.545256) (xy 347.299975 -383.558525) (xy 347.299788 -383.5654)
			(xy 347.299788 -384.3147) (xy 347.299981 -384.321573) (xy 347.303589 -384.334836) (xy 347.3069 -384.340862)
			(xy 347.323252 -384.369207) (xy 347.348964 -384.429382) (xy 347.366368 -384.492464) (xy 347.375147 -384.557312)
			(xy 347.375144 -384.590036) (xy 350.80398 -384.590036) (xy 350.807971 -384.527869) (xy 350.81988 -384.466722)
			(xy 350.839509 -384.407601) (xy 350.866538 -384.351475) (xy 350.900522 -384.299266) (xy 350.940904 -384.251831)
			(xy 350.98702 -384.20995) (xy 351.038112 -384.17431) (xy 351.093343 -384.145496) (xy 351.151805 -384.123982)
			(xy 351.212539 -384.11012) (xy 351.274546 -384.104138) (xy 351.336809 -384.106134) (xy 351.398306 -384.116077)
			(xy 351.458027 -384.133801) (xy 351.51499 -384.159018) (xy 351.568261 -384.191311) (xy 351.616966 -384.230151)
			(xy 351.660303 -384.274901) (xy 351.697563 -384.324825) (xy 351.728132 -384.379104) (xy 351.75151 -384.436847)
			(xy 351.767311 -384.497105) (xy 351.775277 -384.558888) (xy 351.775776 -384.590036) (xy 377.204224 -384.590036)
			(xy 377.20478 -384.557306) (xy 377.213638 -384.492447) (xy 377.231131 -384.429367) (xy 377.256942 -384.36921)
			(xy 377.273312 -384.340862) (xy 377.276641 -384.334844) (xy 377.280237 -384.321575) (xy 377.280424 -384.3147)
			(xy 377.280424 -383.5654) (xy 377.280229 -383.558527) (xy 377.276623 -383.545264) (xy 377.273312 -383.539238)
			(xy 377.256963 -383.51088) (xy 377.231157 -383.450724) (xy 377.213662 -383.387647) (xy 377.204797 -383.322792)
			(xy 377.204224 -383.290064) (xy 377.204793 -383.257335) (xy 377.213647 -383.192476) (xy 377.231136 -383.129396)
			(xy 377.256944 -383.069238) (xy 377.273312 -383.04089) (xy 377.276631 -383.034868) (xy 377.280234 -383.021602)
			(xy 377.280424 -383.014728) (xy 377.280424 -382.728724) (xy 377.280836 -382.7186) (xy 377.288581 -382.699892)
			(xy 377.302899 -382.685576) (xy 377.321608 -382.677834) (xy 377.331732 -382.677416) (xy 378.048012 -382.677416)
			(xy 378.058137 -382.677806) (xy 378.076844 -382.685561) (xy 378.091159 -382.699886) (xy 378.098901 -382.718598)
			(xy 378.09932 -382.728724) (xy 378.09932 -383.014728) (xy 378.099499 -383.021602) (xy 378.103116 -383.034865)
			(xy 378.106432 -383.04089) (xy 378.122787 -383.069245) (xy 378.148593 -383.129402) (xy 378.166086 -383.19248)
			(xy 378.174949 -383.257335) (xy 378.17552 -383.290064) (xy 378.174958 -383.322794) (xy 378.166101 -383.387652)
			(xy 378.148609 -383.450732) (xy 378.13167 -383.490216) (xy 379.404372 -383.490216) (xy 379.404926 -383.457486)
			(xy 379.413786 -383.392628) (xy 379.43128 -383.329547) (xy 379.45709 -383.26939) (xy 379.47346 -383.241042)
			(xy 379.476757 -383.235008) (xy 379.480374 -383.221752) (xy 379.480572 -383.21488) (xy 379.480572 -382.465326)
			(xy 379.480374 -382.458453) (xy 379.47677 -382.44519) (xy 379.47346 -382.439164) (xy 379.457086 -382.410819)
			(xy 379.431285 -382.350659) (xy 379.413797 -382.287578) (xy 379.40494 -382.222719) (xy 379.404372 -382.18999)
			(xy 379.40496 -382.157261) (xy 379.41381 -382.092404) (xy 379.431294 -382.029324) (xy 379.457095 -381.969165)
			(xy 379.47346 -381.940816) (xy 379.476766 -381.934787) (xy 379.480377 -381.921527) (xy 379.480572 -381.914654)
			(xy 379.480572 -381.628904) (xy 379.481088 -381.618799) (xy 379.488819 -381.600126) (xy 379.503106 -381.585832)
			(xy 379.521775 -381.578092) (xy 379.53188 -381.577596) (xy 380.24816 -381.577596) (xy 380.258279 -381.578049)
			(xy 380.276981 -381.585783) (xy 380.291297 -381.600088) (xy 380.299044 -381.618785) (xy 380.299468 -381.628904)
			(xy 380.299468 -381.914654) (xy 380.299681 -381.921526) (xy 380.303275 -381.934788) (xy 380.30658 -381.940816)
			(xy 380.32295 -381.969163) (xy 380.348751 -382.029323) (xy 380.36624 -382.092403) (xy 380.375099 -382.157261)
			(xy 380.375668 -382.18999) (xy 380.375111 -382.22271) (xy 383.80501 -382.22271) (xy 383.805011 -382.157273)
			(xy 383.813796 -382.092428) (xy 383.831205 -382.029348) (xy 383.856925 -381.969177) (xy 383.873248 -381.940816)
			(xy 383.876553 -381.934786) (xy 383.880165 -381.921527) (xy 383.88036 -381.914654) (xy 383.88036 -381.628904)
			(xy 383.880824 -381.618755) (xy 383.888611 -381.600011) (xy 383.902994 -381.585689) (xy 383.921771 -381.577981)
			(xy 383.931922 -381.577596) (xy 384.648202 -381.577596) (xy 384.658323 -381.578124) (xy 384.677036 -381.585844)
			(xy 384.691391 -381.600117) (xy 384.699218 -381.618786) (xy 384.699764 -381.628904) (xy 384.699764 -381.914654)
			(xy 384.699978 -381.921526) (xy 384.703572 -381.934788) (xy 384.706876 -381.940816) (xy 384.723189 -381.969182)
			(xy 384.748907 -382.029352) (xy 384.766315 -382.09243) (xy 384.7751 -382.157274) (xy 384.775101 -382.222709)
			(xy 384.775101 -382.22271) (xy 388.204799 -382.22271) (xy 388.2048 -382.157273) (xy 388.213585 -382.092428)
			(xy 388.230994 -382.029349) (xy 388.256713 -381.969177) (xy 388.273036 -381.940816) (xy 388.27634 -381.934786)
			(xy 388.279953 -381.921527) (xy 388.280148 -381.914654) (xy 388.280148 -381.628904) (xy 388.280624 -381.618757)
			(xy 388.288408 -381.600014) (xy 388.302788 -381.585693) (xy 388.321561 -381.577984) (xy 388.33171 -381.577596)
			(xy 389.04799 -381.577596) (xy 389.058111 -381.578133) (xy 389.076823 -381.58585) (xy 389.091178 -381.60012)
			(xy 389.099006 -381.618786) (xy 389.099552 -381.628904) (xy 389.099552 -381.914654) (xy 389.099755 -381.921527)
			(xy 389.103355 -381.93479) (xy 389.106664 -381.940816) (xy 389.122978 -381.969182) (xy 389.148696 -382.029352)
			(xy 389.166105 -382.09243) (xy 389.174889 -382.157273) (xy 389.17489 -382.18999) (xy 392.603744 -382.18999)
			(xy 392.607735 -382.127823) (xy 392.619644 -382.066676) (xy 392.639273 -382.007555) (xy 392.666302 -381.951429)
			(xy 392.700286 -381.89922) (xy 392.740668 -381.851785) (xy 392.786784 -381.809904) (xy 392.837876 -381.774264)
			(xy 392.893107 -381.74545) (xy 392.951569 -381.723936) (xy 393.012303 -381.710074) (xy 393.07431 -381.704092)
			(xy 393.136573 -381.706088) (xy 393.19807 -381.716031) (xy 393.257791 -381.733755) (xy 393.314754 -381.758972)
			(xy 393.368025 -381.791265) (xy 393.41673 -381.830105) (xy 393.460067 -381.874855) (xy 393.497327 -381.924779)
			(xy 393.527896 -381.979058) (xy 393.551274 -382.036801) (xy 393.567075 -382.097059) (xy 393.575041 -382.158842)
			(xy 393.57554 -382.18999) (xy 393.575041 -382.221138) (xy 393.567075 -382.282921) (xy 393.551274 -382.343179)
			(xy 393.527896 -382.400922) (xy 393.497327 -382.455201) (xy 393.460067 -382.505125) (xy 393.441788 -382.524)
			(xy 408.176982 -382.524) (xy 408.181053 -382.468378) (xy 408.193179 -382.413941) (xy 408.213102 -382.36185)
			(xy 408.240398 -382.313215) (xy 408.274484 -382.269072) (xy 408.314633 -382.230363) (xy 408.359991 -382.197912)
			(xy 408.409591 -382.172411) (xy 408.462375 -382.154404) (xy 408.517218 -382.144274) (xy 408.572952 -382.142237)
			(xy 408.628389 -382.148337) (xy 408.682346 -382.162443) (xy 408.733675 -382.184255) (xy 408.781281 -382.213309)
			(xy 408.824149 -382.248984) (xy 408.861366 -382.290521) (xy 408.892139 -382.337034) (xy 408.915811 -382.387531)
			(xy 408.931879 -382.440938) (xy 408.939999 -382.496114) (xy 408.940508 -382.524) (xy 408.939999 -382.551886)
			(xy 408.931879 -382.607062) (xy 408.915811 -382.660469) (xy 408.892139 -382.710966) (xy 408.861366 -382.757479)
			(xy 408.824149 -382.799016) (xy 408.781281 -382.834691) (xy 408.733675 -382.863745) (xy 408.682346 -382.885557)
			(xy 408.628389 -382.899663) (xy 408.572952 -382.905763) (xy 408.517218 -382.903726) (xy 408.462375 -382.893596)
			(xy 408.409591 -382.875589) (xy 408.359991 -382.850088) (xy 408.314633 -382.817637) (xy 408.274484 -382.778928)
			(xy 408.240398 -382.734785) (xy 408.213102 -382.68615) (xy 408.193179 -382.634059) (xy 408.181053 -382.579622)
			(xy 408.176982 -382.524) (xy 393.441788 -382.524) (xy 393.41673 -382.549875) (xy 393.368025 -382.588715)
			(xy 393.314754 -382.621008) (xy 393.257791 -382.646225) (xy 393.19807 -382.663949) (xy 393.136573 -382.673892)
			(xy 393.07431 -382.675888) (xy 393.012303 -382.669906) (xy 392.951569 -382.656044) (xy 392.893107 -382.63453)
			(xy 392.837876 -382.605716) (xy 392.786784 -382.570076) (xy 392.740668 -382.528195) (xy 392.700286 -382.48076)
			(xy 392.666302 -382.428551) (xy 392.639273 -382.372425) (xy 392.619644 -382.313304) (xy 392.607735 -382.252157)
			(xy 392.603744 -382.18999) (xy 389.17489 -382.18999) (xy 389.174891 -382.222709) (xy 389.166108 -382.287553)
			(xy 389.148702 -382.350632) (xy 389.122985 -382.410803) (xy 389.106664 -382.439164) (xy 389.103367 -382.445197)
			(xy 389.099749 -382.458454) (xy 389.099552 -382.465326) (xy 389.099552 -383.21488) (xy 389.099745 -383.221753)
			(xy 389.103352 -383.235016) (xy 389.106664 -383.241042) (xy 389.123 -383.269396) (xy 389.145818 -383.322789)
			(xy 390.404926 -383.322789) (xy 390.40493 -383.257349) (xy 390.413719 -383.192502) (xy 390.431133 -383.129422)
			(xy 390.456858 -383.069251) (xy 390.473184 -383.04089) (xy 390.476501 -383.034867) (xy 390.480106 -383.021602)
			(xy 390.480296 -383.014728) (xy 390.480296 -382.728724) (xy 390.480741 -382.718572) (xy 390.488528 -382.699821)
			(xy 390.502918 -382.685497) (xy 390.521704 -382.677795) (xy 390.531858 -382.677416) (xy 391.248138 -382.677416)
			(xy 391.258264 -382.677895) (xy 391.276982 -382.685631) (xy 391.291336 -382.699919) (xy 391.299158 -382.7186)
			(xy 391.2997 -382.728724) (xy 391.2997 -383.014728) (xy 391.299881 -383.021602) (xy 391.303497 -383.034865)
			(xy 391.306812 -383.04089) (xy 391.323102 -383.069269) (xy 391.34882 -383.129436) (xy 391.36623 -383.192511)
			(xy 391.375016 -383.257352) (xy 391.37502 -383.322786) (xy 391.366242 -383.387628) (xy 391.34884 -383.450705)
			(xy 391.331958 -383.490216) (xy 392.603744 -383.490216) (xy 392.607735 -383.428049) (xy 392.619644 -383.366902)
			(xy 392.639273 -383.307781) (xy 392.666302 -383.251655) (xy 392.700286 -383.199446) (xy 392.740668 -383.152011)
			(xy 392.786784 -383.11013) (xy 392.837876 -383.07449) (xy 392.893107 -383.045676) (xy 392.951569 -383.024162)
			(xy 393.012303 -383.0103) (xy 393.07431 -383.004318) (xy 393.136573 -383.006314) (xy 393.19807 -383.016257)
			(xy 393.257791 -383.033981) (xy 393.314754 -383.059198) (xy 393.368025 -383.091491) (xy 393.41673 -383.130331)
			(xy 393.460067 -383.175081) (xy 393.497327 -383.225005) (xy 393.527896 -383.279284) (xy 393.53226 -383.290064)
			(xy 394.803892 -383.290064) (xy 394.807883 -383.227897) (xy 394.819792 -383.16675) (xy 394.839421 -383.107629)
			(xy 394.86645 -383.051503) (xy 394.900434 -382.999294) (xy 394.940816 -382.951859) (xy 394.986932 -382.909978)
			(xy 395.038024 -382.874338) (xy 395.093255 -382.845524) (xy 395.151717 -382.82401) (xy 395.212451 -382.810148)
			(xy 395.274458 -382.804166) (xy 395.336721 -382.806162) (xy 395.398218 -382.816105) (xy 395.457939 -382.833829)
			(xy 395.514902 -382.859046) (xy 395.568173 -382.891339) (xy 395.616878 -382.930179) (xy 395.660215 -382.974929)
			(xy 395.697475 -383.024853) (xy 395.728044 -383.079132) (xy 395.751422 -383.136875) (xy 395.767223 -383.197133)
			(xy 395.775189 -383.258916) (xy 395.775688 -383.290064) (xy 395.775189 -383.321212) (xy 395.767223 -383.382995)
			(xy 395.751422 -383.443253) (xy 395.728044 -383.500996) (xy 395.697475 -383.555275) (xy 395.660215 -383.605199)
			(xy 395.616878 -383.649949) (xy 395.568173 -383.688789) (xy 395.514902 -383.721082) (xy 395.457939 -383.746299)
			(xy 395.398218 -383.764023) (xy 395.336721 -383.773966) (xy 395.274458 -383.775962) (xy 395.212451 -383.76998)
			(xy 395.151717 -383.756118) (xy 395.093255 -383.734604) (xy 395.038024 -383.70579) (xy 394.986932 -383.67015)
			(xy 394.940816 -383.628269) (xy 394.900434 -383.580834) (xy 394.86645 -383.528625) (xy 394.839421 -383.472499)
			(xy 394.819792 -383.413378) (xy 394.807883 -383.352231) (xy 394.803892 -383.290064) (xy 393.53226 -383.290064)
			(xy 393.551274 -383.337027) (xy 393.567075 -383.397285) (xy 393.575041 -383.459068) (xy 393.57554 -383.490216)
			(xy 393.575041 -383.521364) (xy 393.567075 -383.583147) (xy 393.551274 -383.643405) (xy 393.527896 -383.701148)
			(xy 393.497327 -383.755427) (xy 393.460067 -383.805351) (xy 393.41673 -383.850101) (xy 393.368025 -383.888941)
			(xy 393.314754 -383.921234) (xy 393.257791 -383.946451) (xy 393.19807 -383.964175) (xy 393.136573 -383.974118)
			(xy 393.07431 -383.976114) (xy 393.012303 -383.970132) (xy 392.951569 -383.95627) (xy 392.893107 -383.934756)
			(xy 392.837876 -383.905942) (xy 392.786784 -383.870302) (xy 392.740668 -383.828421) (xy 392.700286 -383.780986)
			(xy 392.666302 -383.728777) (xy 392.639273 -383.672651) (xy 392.619644 -383.61353) (xy 392.607735 -383.552383)
			(xy 392.603744 -383.490216) (xy 391.331958 -383.490216) (xy 391.32313 -383.510876) (xy 391.306812 -383.539238)
			(xy 391.303485 -383.545256) (xy 391.299887 -383.558525) (xy 391.2997 -383.5654) (xy 391.2997 -384.06705)
			(xy 403.966932 -384.06705) (xy 403.971003 -384.011428) (xy 403.983129 -383.956991) (xy 404.003052 -383.9049)
			(xy 404.030348 -383.856265) (xy 404.064434 -383.812122) (xy 404.104583 -383.773413) (xy 404.149941 -383.740962)
			(xy 404.199541 -383.715461) (xy 404.252325 -383.697454) (xy 404.307168 -383.687324) (xy 404.362902 -383.685287)
			(xy 404.418339 -383.691387) (xy 404.472296 -383.705493) (xy 404.523625 -383.727305) (xy 404.571231 -383.756359)
			(xy 404.614099 -383.792034) (xy 404.651316 -383.833571) (xy 404.682089 -383.880084) (xy 404.705761 -383.930581)
			(xy 404.721829 -383.983988) (xy 404.729949 -384.039164) (xy 404.730458 -384.06705) (xy 404.729949 -384.094936)
			(xy 404.721829 -384.150112) (xy 404.705761 -384.203519) (xy 404.682089 -384.254016) (xy 404.651316 -384.300529)
			(xy 404.614099 -384.342066) (xy 404.571231 -384.377741) (xy 404.523625 -384.406795) (xy 404.472296 -384.428607)
			(xy 404.418339 -384.442713) (xy 404.362902 -384.448813) (xy 404.307168 -384.446776) (xy 404.252325 -384.436646)
			(xy 404.199541 -384.418639) (xy 404.149941 -384.393138) (xy 404.104583 -384.360687) (xy 404.064434 -384.321978)
			(xy 404.030348 -384.277835) (xy 404.003052 -384.2292) (xy 403.983129 -384.177109) (xy 403.971003 -384.122672)
			(xy 403.966932 -384.06705) (xy 391.2997 -384.06705) (xy 391.2997 -384.3147) (xy 391.299892 -384.321573)
			(xy 391.3035 -384.334836) (xy 391.306812 -384.340862) (xy 391.323163 -384.369207) (xy 391.348875 -384.429383)
			(xy 391.366278 -384.492465) (xy 391.375057 -384.557312) (xy 391.375055 -384.590036) (xy 394.803892 -384.590036)
			(xy 394.807883 -384.527869) (xy 394.819792 -384.466722) (xy 394.839421 -384.407601) (xy 394.86645 -384.351475)
			(xy 394.900434 -384.299266) (xy 394.940816 -384.251831) (xy 394.986932 -384.20995) (xy 395.038024 -384.17431)
			(xy 395.093255 -384.145496) (xy 395.151717 -384.123982) (xy 395.212451 -384.11012) (xy 395.274458 -384.104138)
			(xy 395.336721 -384.106134) (xy 395.398218 -384.116077) (xy 395.457939 -384.133801) (xy 395.514902 -384.159018)
			(xy 395.568173 -384.191311) (xy 395.616878 -384.230151) (xy 395.660215 -384.274901) (xy 395.697475 -384.324825)
			(xy 395.728044 -384.379104) (xy 395.751422 -384.436847) (xy 395.767223 -384.497105) (xy 395.775189 -384.558888)
			(xy 395.775688 -384.590036) (xy 395.775189 -384.621184) (xy 395.767223 -384.682967) (xy 395.767214 -384.683)
			(xy 406.398982 -384.683) (xy 406.403053 -384.627378) (xy 406.415179 -384.572941) (xy 406.435102 -384.52085)
			(xy 406.462398 -384.472215) (xy 406.496484 -384.428072) (xy 406.536633 -384.389363) (xy 406.581991 -384.356912)
			(xy 406.631591 -384.331411) (xy 406.684375 -384.313404) (xy 406.739218 -384.303274) (xy 406.794952 -384.301237)
			(xy 406.850389 -384.307337) (xy 406.904346 -384.321443) (xy 406.955675 -384.343255) (xy 407.003281 -384.372309)
			(xy 407.046149 -384.407984) (xy 407.083366 -384.449521) (xy 407.114139 -384.496034) (xy 407.137811 -384.546531)
			(xy 407.153879 -384.599938) (xy 407.161999 -384.655114) (xy 407.162508 -384.683) (xy 407.161999 -384.710886)
			(xy 407.153879 -384.766062) (xy 407.14066 -384.81) (xy 408.176982 -384.81) (xy 408.181053 -384.754378)
			(xy 408.193179 -384.699941) (xy 408.213102 -384.64785) (xy 408.240398 -384.599215) (xy 408.274484 -384.555072)
			(xy 408.314633 -384.516363) (xy 408.359991 -384.483912) (xy 408.409591 -384.458411) (xy 408.462375 -384.440404)
			(xy 408.517218 -384.430274) (xy 408.572952 -384.428237) (xy 408.628389 -384.434337) (xy 408.682346 -384.448443)
			(xy 408.733675 -384.470255) (xy 408.781281 -384.499309) (xy 408.824149 -384.534984) (xy 408.861366 -384.576521)
			(xy 408.892139 -384.623034) (xy 408.915811 -384.673531) (xy 408.931879 -384.726938) (xy 408.939999 -384.782114)
			(xy 408.940508 -384.81) (xy 408.939999 -384.837886) (xy 408.931879 -384.893062) (xy 408.915811 -384.946469)
			(xy 408.892139 -384.996966) (xy 408.861366 -385.043479) (xy 408.824149 -385.085016) (xy 408.781281 -385.120691)
			(xy 408.733675 -385.149745) (xy 408.682346 -385.171557) (xy 408.628389 -385.185663) (xy 408.572952 -385.191763)
			(xy 408.517218 -385.189726) (xy 408.462375 -385.179596) (xy 408.409591 -385.161589) (xy 408.359991 -385.136088)
			(xy 408.314633 -385.103637) (xy 408.274484 -385.064928) (xy 408.240398 -385.020785) (xy 408.213102 -384.97215)
			(xy 408.193179 -384.920059) (xy 408.181053 -384.865622) (xy 408.176982 -384.81) (xy 407.14066 -384.81)
			(xy 407.137811 -384.819469) (xy 407.114139 -384.869966) (xy 407.083366 -384.916479) (xy 407.046149 -384.958016)
			(xy 407.003281 -384.993691) (xy 406.955675 -385.022745) (xy 406.904346 -385.044557) (xy 406.850389 -385.058663)
			(xy 406.794952 -385.064763) (xy 406.739218 -385.062726) (xy 406.684375 -385.052596) (xy 406.631591 -385.034589)
			(xy 406.581991 -385.009088) (xy 406.536633 -384.976637) (xy 406.496484 -384.937928) (xy 406.462398 -384.893785)
			(xy 406.435102 -384.84515) (xy 406.415179 -384.793059) (xy 406.403053 -384.738622) (xy 406.398982 -384.683)
			(xy 395.767214 -384.683) (xy 395.751422 -384.743225) (xy 395.728044 -384.800968) (xy 395.697475 -384.855247)
			(xy 395.660215 -384.905171) (xy 395.616878 -384.949921) (xy 395.568173 -384.988761) (xy 395.514902 -385.021054)
			(xy 395.457939 -385.046271) (xy 395.398218 -385.063995) (xy 395.336721 -385.073938) (xy 395.274458 -385.075934)
			(xy 395.212451 -385.069952) (xy 395.151717 -385.05609) (xy 395.093255 -385.034576) (xy 395.038024 -385.005762)
			(xy 394.986932 -384.970122) (xy 394.940816 -384.928241) (xy 394.900434 -384.880806) (xy 394.86645 -384.828597)
			(xy 394.839421 -384.772471) (xy 394.819792 -384.71335) (xy 394.807883 -384.652203) (xy 394.803892 -384.590036)
			(xy 391.375055 -384.590036) (xy 391.375053 -384.62275) (xy 391.366266 -384.687596) (xy 391.348855 -384.750676)
			(xy 391.323135 -384.810848) (xy 391.306812 -384.83921) (xy 391.303495 -384.845233) (xy 391.29989 -384.858498)
			(xy 391.2997 -384.865372) (xy 391.2997 -385.151376) (xy 391.299259 -385.161529) (xy 391.291471 -385.180281)
			(xy 391.27708 -385.194605) (xy 391.258292 -385.202305) (xy 391.248138 -385.202684) (xy 390.531858 -385.202684)
			(xy 390.521732 -385.202209) (xy 390.503014 -385.194471) (xy 390.48866 -385.180182) (xy 390.480838 -385.1615)
			(xy 390.480296 -385.151376) (xy 390.480296 -384.865372) (xy 390.480115 -384.858498) (xy 390.4765 -384.845235)
			(xy 390.473184 -384.83921) (xy 390.456891 -384.810832) (xy 390.431168 -384.750666) (xy 390.413755 -384.68759)
			(xy 390.404967 -384.622748) (xy 390.404963 -384.557313) (xy 390.413743 -384.49247) (xy 390.431148 -384.429393)
			(xy 390.456863 -384.369223) (xy 390.473184 -384.340862) (xy 390.476511 -384.334843) (xy 390.480109 -384.321575)
			(xy 390.480296 -384.3147) (xy 390.480296 -383.5654) (xy 390.480105 -383.558527) (xy 390.476496 -383.545264)
			(xy 390.473184 -383.539238) (xy 390.45683 -383.510894) (xy 390.431113 -383.450719) (xy 390.413706 -383.387637)
			(xy 390.404926 -383.322789) (xy 389.145818 -383.322789) (xy 389.148716 -383.329569) (xy 389.166122 -383.392649)
			(xy 389.174904 -383.457495) (xy 389.174902 -383.522933) (xy 389.166117 -383.587778) (xy 389.148707 -383.650857)
			(xy 389.122987 -383.711029) (xy 389.106664 -383.73939) (xy 389.103358 -383.745419) (xy 389.099746 -383.758679)
			(xy 389.099552 -383.765552) (xy 389.099552 -384.051556) (xy 389.099043 -384.061701) (xy 389.091272 -384.080442)
			(xy 389.076902 -384.094765) (xy 389.058136 -384.102476) (xy 389.04799 -384.102864) (xy 388.33171 -384.102864)
			(xy 388.321584 -384.102365) (xy 388.302864 -384.094642) (xy 388.288508 -384.080359) (xy 388.280687 -384.061679)
			(xy 388.280148 -384.051556) (xy 388.280148 -383.765552) (xy 388.279943 -383.75868) (xy 388.276344 -383.745417)
			(xy 388.273036 -383.73939) (xy 388.256727 -383.711021) (xy 388.231009 -383.650852) (xy 388.213599 -383.587775)
			(xy 388.204814 -383.522932) (xy 388.204812 -383.457496) (xy 388.213594 -383.392652) (xy 388.231 -383.329574)
			(xy 388.256715 -383.269403) (xy 388.273036 -383.241042) (xy 388.276331 -383.235007) (xy 388.27995 -383.221751)
			(xy 388.280148 -383.21488) (xy 388.280148 -382.465326) (xy 388.279953 -382.458453) (xy 388.276347 -382.44519)
			(xy 388.273036 -382.439164) (xy 388.256705 -382.410807) (xy 388.230989 -382.350635) (xy 388.213582 -382.287555)
			(xy 388.204799 -382.22271) (xy 384.775101 -382.22271) (xy 384.766319 -382.287553) (xy 384.748913 -382.350631)
			(xy 384.723197 -382.410803) (xy 384.706876 -382.439164) (xy 384.703572 -382.445194) (xy 384.69996 -382.458454)
			(xy 384.699764 -382.465326) (xy 384.699764 -383.21488) (xy 384.699968 -383.221752) (xy 384.703569 -383.235015)
			(xy 384.706876 -383.241042) (xy 384.723211 -383.269396) (xy 384.748927 -383.329569) (xy 384.766333 -383.392649)
			(xy 384.775115 -383.457495) (xy 384.775113 -383.522933) (xy 384.766327 -383.587778) (xy 384.748918 -383.650857)
			(xy 384.723199 -383.711029) (xy 384.706876 -383.73939) (xy 384.703563 -383.745415) (xy 384.699957 -383.758679)
			(xy 384.699764 -383.765552) (xy 384.699764 -384.051556) (xy 384.699342 -384.061712) (xy 384.691554 -384.08047)
			(xy 384.677156 -384.094796) (xy 384.65836 -384.102491) (xy 384.648202 -384.102864) (xy 383.931922 -384.102864)
			(xy 383.921797 -384.102356) (xy 383.903077 -384.094636) (xy 383.88872 -384.080356) (xy 383.8809 -384.061678)
			(xy 383.88036 -384.051556) (xy 383.88036 -383.765552) (xy 383.880153 -383.75868) (xy 383.876556 -383.745417)
			(xy 383.873248 -383.73939) (xy 383.856939 -383.711021) (xy 383.83122 -383.650852) (xy 383.81381 -383.587775)
			(xy 383.805024 -383.522932) (xy 383.805023 -383.457496) (xy 383.813804 -383.392652) (xy 383.831211 -383.329574)
			(xy 383.856927 -383.269403) (xy 383.873248 -383.241042) (xy 383.876544 -383.235008) (xy 383.880162 -383.221752)
			(xy 383.88036 -383.21488) (xy 383.88036 -382.465326) (xy 383.880163 -382.458453) (xy 383.876559 -382.44519)
			(xy 383.873248 -382.439164) (xy 383.856917 -382.410808) (xy 383.8312 -382.350635) (xy 383.813792 -382.287556)
			(xy 383.80501 -382.22271) (xy 380.375111 -382.22271) (xy 380.375111 -382.22272) (xy 380.366251 -382.287578)
			(xy 380.348758 -382.350658) (xy 380.322949 -382.410816) (xy 380.30658 -382.439164) (xy 380.303277 -382.445194)
			(xy 380.299664 -382.458454) (xy 380.299468 -382.465326) (xy 380.299468 -383.21488) (xy 380.299672 -383.221752)
			(xy 380.303272 -383.235015) (xy 380.30658 -383.241042) (xy 380.32296 -383.269383) (xy 380.345861 -383.322788)
			(xy 381.604853 -383.322788) (xy 381.604858 -383.25735) (xy 381.613645 -383.192504) (xy 381.631056 -383.129424)
			(xy 381.656777 -383.069252) (xy 381.6731 -383.04089) (xy 381.676418 -383.034867) (xy 381.680022 -383.021602)
			(xy 381.680212 -383.014728) (xy 381.680212 -382.728724) (xy 381.680641 -382.71857) (xy 381.688431 -382.699816)
			(xy 381.702826 -382.685491) (xy 381.721618 -382.677793) (xy 381.731774 -382.677416) (xy 382.448054 -382.677416)
			(xy 382.458175 -382.677964) (xy 382.47689 -382.685672) (xy 382.491247 -382.699939) (xy 382.499072 -382.718606)
			(xy 382.499616 -382.728724) (xy 382.499616 -383.014728) (xy 382.499795 -383.021602) (xy 382.503412 -383.034865)
			(xy 382.506728 -383.04089) (xy 382.523021 -383.069268) (xy 382.548743 -383.129435) (xy 382.566156 -383.19251)
			(xy 382.574944 -383.257352) (xy 382.574948 -383.322786) (xy 382.566168 -383.387629) (xy 382.548763 -383.450707)
			(xy 382.523049 -383.510877) (xy 382.506728 -383.539238) (xy 382.503402 -383.545257) (xy 382.499803 -383.558525)
			(xy 382.499616 -383.5654) (xy 382.499616 -384.3147) (xy 382.499806 -384.321573) (xy 382.503416 -384.334836)
			(xy 382.506728 -384.340862) (xy 382.523082 -384.369206) (xy 382.548798 -384.429381) (xy 382.566204 -384.492463)
			(xy 382.574985 -384.557311) (xy 382.574982 -384.590036) (xy 386.004308 -384.590036) (xy 386.004867 -384.557306)
			(xy 386.013724 -384.492448) (xy 386.031217 -384.429368) (xy 386.057026 -384.36921) (xy 386.073396 -384.340862)
			(xy 386.076724 -384.334844) (xy 386.080321 -384.321575) (xy 386.080508 -384.3147) (xy 386.080508 -383.5654)
			(xy 386.080315 -383.558527) (xy 386.076708 -383.545264) (xy 386.073396 -383.539238) (xy 386.057045 -383.510881)
			(xy 386.03124 -383.450724) (xy 386.013746 -383.387647) (xy 386.004881 -383.322792) (xy 386.004308 -383.290064)
			(xy 386.004879 -383.257335) (xy 386.013733 -383.192477) (xy 386.031222 -383.129396) (xy 386.057028 -383.069238)
			(xy 386.073396 -383.04089) (xy 386.076714 -383.034867) (xy 386.080318 -383.021602) (xy 386.080508 -383.014728)
			(xy 386.080508 -382.728724) (xy 386.080936 -382.718602) (xy 386.088677 -382.699897) (xy 386.102991 -382.685582)
			(xy 386.121694 -382.677837) (xy 386.131816 -382.677416) (xy 386.848096 -382.677416) (xy 386.85822 -382.67782)
			(xy 386.876927 -382.685569) (xy 386.891242 -382.69989) (xy 386.898984 -382.7186) (xy 386.899404 -382.728724)
			(xy 386.899404 -383.014728) (xy 386.899585 -383.021602) (xy 386.9032 -383.034865) (xy 386.906516 -383.04089)
			(xy 386.922879 -383.069241) (xy 386.948681 -383.1294) (xy 386.966171 -383.192479) (xy 386.975033 -383.257335)
			(xy 386.975604 -383.290064) (xy 386.975044 -383.322794) (xy 386.966186 -383.387652) (xy 386.948694 -383.450732)
			(xy 386.922885 -383.51089) (xy 386.906516 -383.539238) (xy 386.903189 -383.545257) (xy 386.899591 -383.558525)
			(xy 386.899404 -383.5654) (xy 386.899404 -384.3147) (xy 386.899595 -384.321573) (xy 386.903204 -384.334836)
			(xy 386.906516 -384.340862) (xy 386.922868 -384.369219) (xy 386.948673 -384.429376) (xy 386.966166 -384.492453)
			(xy 386.975031 -384.557308) (xy 386.975604 -384.590036) (xy 386.975031 -384.622765) (xy 386.966177 -384.687623)
			(xy 386.948689 -384.750703) (xy 386.922884 -384.810862) (xy 386.906516 -384.83921) (xy 386.903199 -384.845233)
			(xy 386.899594 -384.858498) (xy 386.899404 -384.865372) (xy 386.899404 -385.151376) (xy 386.898965 -385.161496)
			(xy 386.891225 -385.180199) (xy 386.876916 -385.194514) (xy 386.858216 -385.202261) (xy 386.848096 -385.202684)
			(xy 386.131816 -385.202684) (xy 386.121693 -385.202271) (xy 386.102986 -385.194525) (xy 386.088671 -385.180207)
			(xy 386.080928 -385.1615) (xy 386.080508 -385.151376) (xy 386.080508 -384.865372) (xy 386.080326 -384.858498)
			(xy 386.076711 -384.845235) (xy 386.073396 -384.83921) (xy 386.057034 -384.810859) (xy 386.031231 -384.7507)
			(xy 386.013741 -384.687621) (xy 386.004879 -384.622765) (xy 386.004308 -384.590036) (xy 382.574982 -384.590036)
			(xy 382.57498 -384.622751) (xy 382.566192 -384.687597) (xy 382.548778 -384.750678) (xy 382.523054 -384.810849)
			(xy 382.506728 -384.83921) (xy 382.503412 -384.845234) (xy 382.499807 -384.858498) (xy 382.499616 -384.865372)
			(xy 382.499616 -385.151376) (xy 382.499159 -385.161527) (xy 382.491375 -385.180275) (xy 382.476989 -385.194599)
			(xy 382.458206 -385.202303) (xy 382.448054 -385.202684) (xy 381.731774 -385.202684) (xy 381.721649 -385.202196)
			(xy 381.702931 -385.194464) (xy 381.688577 -385.180179) (xy 381.680754 -385.161499) (xy 381.680212 -385.151376)
			(xy 381.680212 -384.865372) (xy 381.680029 -384.858498) (xy 381.676415 -384.845235) (xy 381.6731 -384.83921)
			(xy 381.656809 -384.810832) (xy 381.631091 -384.750664) (xy 381.613681 -384.687589) (xy 381.604894 -384.622748)
			(xy 381.60489 -384.557314) (xy 381.613669 -384.492472) (xy 381.631071 -384.429394) (xy 381.656781 -384.369224)
			(xy 381.6731 -384.340862) (xy 381.676428 -384.334844) (xy 381.680025 -384.321575) (xy 381.680212 -384.3147)
			(xy 381.680212 -383.5654) (xy 381.680019 -383.558527) (xy 381.676411 -383.545264) (xy 381.6731 -383.539238)
			(xy 381.656748 -383.510893) (xy 381.631036 -383.450718) (xy 381.613632 -383.387636) (xy 381.604853 -383.322788)
			(xy 380.345861 -383.322788) (xy 380.348759 -383.329545) (xy 380.366245 -383.392627) (xy 380.3751 -383.457486)
			(xy 380.375668 -383.490216) (xy 380.375078 -383.522945) (xy 380.366228 -383.587802) (xy 380.348745 -383.650882)
			(xy 380.322945 -383.711041) (xy 380.30658 -383.73939) (xy 380.303267 -383.745416) (xy 380.299661 -383.758679)
			(xy 380.299468 -383.765552) (xy 380.299468 -384.051556) (xy 380.299047 -384.06168) (xy 380.291308 -384.080388)
			(xy 380.276992 -384.094705) (xy 380.258284 -384.102446) (xy 380.24816 -384.102864) (xy 379.53188 -384.102864)
			(xy 379.521752 -384.1025) (xy 379.503041 -384.094738) (xy 379.488726 -384.080405) (xy 379.480988 -384.061685)
			(xy 379.480572 -384.051556) (xy 379.480572 -383.765552) (xy 379.480364 -383.75868) (xy 379.476767 -383.745417)
			(xy 379.47346 -383.73939) (xy 379.457096 -383.71104) (xy 379.431293 -383.650881) (xy 379.413802 -383.587802)
			(xy 379.404942 -383.522945) (xy 379.404372 -383.490216) (xy 378.13167 -383.490216) (xy 378.122801 -383.51089)
			(xy 378.106432 -383.539238) (xy 378.103106 -383.545257) (xy 378.099507 -383.558525) (xy 378.09932 -383.5654)
			(xy 378.09932 -384.3147) (xy 378.09951 -384.321573) (xy 378.103119 -384.334836) (xy 378.106432 -384.340862)
			(xy 378.122776 -384.369223) (xy 378.148585 -384.429378) (xy 378.166081 -384.492454) (xy 378.174947 -384.557308)
			(xy 378.17552 -384.590036) (xy 378.174945 -384.622765) (xy 378.166092 -384.687623) (xy 378.148604 -384.750703)
			(xy 378.122799 -384.810861) (xy 378.106432 -384.83921) (xy 378.103116 -384.845234) (xy 378.099511 -384.858498)
			(xy 378.09932 -384.865372) (xy 378.09932 -385.151376) (xy 378.098865 -385.161494) (xy 378.091128 -385.180194)
			(xy 378.076824 -385.194508) (xy 378.05813 -385.202258) (xy 378.048012 -385.202684) (xy 377.331732 -385.202684)
			(xy 377.32161 -385.202258) (xy 377.302903 -385.194517) (xy 377.288587 -385.180203) (xy 377.280844 -385.161498)
			(xy 377.280424 -385.151376) (xy 377.280424 -384.865372) (xy 377.28024 -384.858498) (xy 377.276626 -384.845236)
			(xy 377.273312 -384.83921) (xy 377.256952 -384.810858) (xy 377.231148 -384.7507) (xy 377.213657 -384.687621)
			(xy 377.204795 -384.622765) (xy 377.204224 -384.590036) (xy 351.775776 -384.590036) (xy 351.775277 -384.621184)
			(xy 351.767311 -384.682967) (xy 351.75151 -384.743225) (xy 351.728132 -384.800968) (xy 351.697563 -384.855247)
			(xy 351.660303 -384.905171) (xy 351.616966 -384.949921) (xy 351.568261 -384.988761) (xy 351.51499 -385.021054)
			(xy 351.458027 -385.046271) (xy 351.398306 -385.063995) (xy 351.336809 -385.073938) (xy 351.274546 -385.075934)
			(xy 351.212539 -385.069952) (xy 351.151805 -385.05609) (xy 351.093343 -385.034576) (xy 351.038112 -385.005762)
			(xy 350.98702 -384.970122) (xy 350.940904 -384.928241) (xy 350.900522 -384.880806) (xy 350.866538 -384.828597)
			(xy 350.839509 -384.772471) (xy 350.81988 -384.71335) (xy 350.807971 -384.652203) (xy 350.80398 -384.590036)
			(xy 347.375144 -384.590036) (xy 347.375142 -384.62275) (xy 347.366355 -384.687596) (xy 347.348944 -384.750676)
			(xy 347.323223 -384.810848) (xy 347.3069 -384.83921) (xy 347.303582 -384.845233) (xy 347.299978 -384.858498)
			(xy 347.299788 -384.865372) (xy 347.299788 -385.151376) (xy 347.299359 -385.16153) (xy 347.291569 -385.180284)
			(xy 347.277174 -385.194609) (xy 347.258382 -385.202307) (xy 347.248226 -385.202684) (xy 346.531946 -385.202684)
			(xy 346.521825 -385.202136) (xy 346.50311 -385.194428) (xy 346.488753 -385.180161) (xy 346.480928 -385.161494)
			(xy 346.480384 -385.151376) (xy 346.480384 -384.865372) (xy 346.480205 -384.858498) (xy 346.476588 -384.845235)
			(xy 346.473272 -384.83921) (xy 346.456979 -384.810832) (xy 346.431257 -384.750665) (xy 346.413844 -384.68759)
			(xy 346.405056 -384.622748) (xy 346.405052 -384.557314) (xy 346.413832 -384.492471) (xy 346.431237 -384.429393)
			(xy 346.456951 -384.369223) (xy 346.473272 -384.340862) (xy 346.476598 -384.334843) (xy 346.480197 -384.321575)
			(xy 346.480384 -384.3147) (xy 346.480384 -383.5654) (xy 346.480194 -383.558527) (xy 346.476584 -383.545264)
			(xy 346.473272 -383.539238) (xy 346.456918 -383.510894) (xy 346.431202 -383.450719) (xy 346.413796 -383.387637)
			(xy 346.405015 -383.322789) (xy 345.145907 -383.322789) (xy 345.148805 -383.329569) (xy 345.166212 -383.392649)
			(xy 345.174994 -383.457495) (xy 345.174992 -383.522933) (xy 345.166206 -383.587778) (xy 345.148796 -383.650857)
			(xy 345.123076 -383.711029) (xy 345.106752 -383.73939) (xy 345.103445 -383.745418) (xy 345.099834 -383.758679)
			(xy 345.09964 -383.765552) (xy 345.09964 -384.051556) (xy 345.099143 -384.061702) (xy 345.09137 -384.080446)
			(xy 345.076996 -384.094769) (xy 345.058226 -384.102478) (xy 345.048078 -384.102864) (xy 344.331798 -384.102864)
			(xy 344.321672 -384.102375) (xy 344.302951 -384.094647) (xy 344.288595 -384.080362) (xy 344.280775 -384.06168)
			(xy 344.280236 -384.051556) (xy 344.280236 -383.765552) (xy 344.28002 -383.758681) (xy 344.276428 -383.745418)
			(xy 344.273124 -383.73939) (xy 344.256816 -383.711021) (xy 344.231098 -383.650852) (xy 344.213689 -383.587774)
			(xy 344.204904 -383.522931) (xy 344.204902 -383.457496) (xy 344.213683 -383.392652) (xy 344.231089 -383.329574)
			(xy 344.256803 -383.269403) (xy 344.273124 -383.241042) (xy 344.276426 -383.235011) (xy 344.280039 -383.221752)
			(xy 344.280236 -383.21488) (xy 344.280236 -382.465326) (xy 344.28003 -382.458454) (xy 344.276431 -382.445191)
			(xy 344.273124 -382.439164) (xy 344.256794 -382.410807) (xy 344.231078 -382.350635) (xy 344.213671 -382.287555)
			(xy 344.204889 -382.22271) (xy 340.775191 -382.22271) (xy 340.766408 -382.287553) (xy 340.749002 -382.350632)
			(xy 340.723285 -382.410803) (xy 340.706964 -382.439164) (xy 340.703667 -382.445197) (xy 340.700049 -382.458454)
			(xy 340.699852 -382.465326) (xy 340.699852 -383.21488) (xy 340.700045 -383.221753) (xy 340.703652 -383.235016)
			(xy 340.706964 -383.241042) (xy 340.7233 -383.269396) (xy 340.749016 -383.329569) (xy 340.766422 -383.392649)
			(xy 340.775204 -383.457495) (xy 340.775202 -383.522933) (xy 340.766417 -383.587778) (xy 340.749007 -383.650857)
			(xy 340.723287 -383.711029) (xy 340.706964 -383.73939) (xy 340.703658 -383.745419) (xy 340.700046 -383.758679)
			(xy 340.699852 -383.765552) (xy 340.699852 -384.051556) (xy 340.699343 -384.061701) (xy 340.691572 -384.080442)
			(xy 340.677202 -384.094765) (xy 340.658436 -384.102476) (xy 340.64829 -384.102864) (xy 339.93201 -384.102864)
			(xy 339.921884 -384.102365) (xy 339.903164 -384.094642) (xy 339.888808 -384.080359) (xy 339.880987 -384.061679)
			(xy 339.880448 -384.051556) (xy 339.880448 -383.765552) (xy 339.880243 -383.75868) (xy 339.876644 -383.745417)
			(xy 339.873336 -383.73939) (xy 339.857027 -383.711021) (xy 339.831309 -383.650852) (xy 339.813899 -383.587775)
			(xy 339.805114 -383.522932) (xy 339.805112 -383.457496) (xy 339.813894 -383.392652) (xy 339.8313 -383.329574)
			(xy 339.857015 -383.269403) (xy 339.873336 -383.241042) (xy 339.876631 -383.235007) (xy 339.88025 -383.221751)
			(xy 339.880448 -383.21488) (xy 339.880448 -382.465326) (xy 339.880253 -382.458453) (xy 339.876647 -382.44519)
			(xy 339.873336 -382.439164) (xy 339.857005 -382.410807) (xy 339.831289 -382.350635) (xy 339.813882 -382.287555)
			(xy 339.805099 -382.22271) (xy 336.375201 -382.22271) (xy 336.375201 -382.22272) (xy 336.366341 -382.287578)
			(xy 336.348847 -382.350658) (xy 336.323038 -382.410816) (xy 336.306668 -382.439164) (xy 336.303364 -382.445194)
			(xy 336.299752 -382.458454) (xy 336.299556 -382.465326) (xy 336.299556 -383.21488) (xy 336.299749 -383.221753)
			(xy 336.303356 -383.235016) (xy 336.306668 -383.241042) (xy 336.323047 -383.269384) (xy 336.345949 -383.322788)
			(xy 337.604943 -383.322788) (xy 337.604947 -383.25735) (xy 337.613734 -383.192504) (xy 337.631145 -383.129424)
			(xy 337.656865 -383.069252) (xy 337.673188 -383.04089) (xy 337.676505 -383.034867) (xy 337.68011 -383.021602)
			(xy 337.6803 -383.014728) (xy 337.6803 -382.728724) (xy 337.680741 -382.718571) (xy 337.688529 -382.699819)
			(xy 337.70292 -382.685495) (xy 337.721708 -382.677795) (xy 337.731862 -382.677416) (xy 338.448142 -382.677416)
			(xy 338.458268 -382.677891) (xy 338.476986 -382.685629) (xy 338.49134 -382.699918) (xy 338.499162 -382.7186)
			(xy 338.499704 -382.728724) (xy 338.499704 -383.014728) (xy 338.499885 -383.021602) (xy 338.5035 -383.034865)
			(xy 338.506816 -383.04089) (xy 338.523109 -383.069268) (xy 338.548832 -383.129434) (xy 338.566245 -383.19251)
			(xy 338.575033 -383.257352) (xy 338.575037 -383.322787) (xy 338.566257 -383.38763) (xy 338.548852 -383.450707)
			(xy 338.523137 -383.510877) (xy 338.506816 -383.539238) (xy 338.503489 -383.545257) (xy 338.499891 -383.558525)
			(xy 338.499704 -383.5654) (xy 338.499704 -384.3147) (xy 338.499895 -384.321573) (xy 338.503504 -384.334836)
			(xy 338.506816 -384.340862) (xy 338.52317 -384.369206) (xy 338.548887 -384.429381) (xy 338.566294 -384.492463)
			(xy 338.575074 -384.557311) (xy 338.575072 -384.590036) (xy 342.004396 -384.590036) (xy 342.004956 -384.557306)
			(xy 342.013814 -384.492448) (xy 342.031306 -384.429368) (xy 342.057115 -384.36921) (xy 342.073484 -384.340862)
			(xy 342.076811 -384.334843) (xy 342.080409 -384.321575) (xy 342.080596 -384.3147) (xy 342.080596 -383.5654)
			(xy 342.080405 -383.558527) (xy 342.076796 -383.545264) (xy 342.073484 -383.539238) (xy 342.057132 -383.510881)
			(xy 342.031327 -383.450724) (xy 342.013834 -383.387647) (xy 342.004969 -383.322792) (xy 342.004396 -383.290064)
			(xy 342.004969 -383.257335) (xy 342.013823 -383.192477) (xy 342.031311 -383.129397) (xy 342.057116 -383.069238)
			(xy 342.073484 -383.04089) (xy 342.076801 -383.034867) (xy 342.080406 -383.021602) (xy 342.080596 -383.014728)
			(xy 342.080596 -382.728724) (xy 342.081035 -382.718604) (xy 342.088775 -382.699901) (xy 342.103084 -382.685586)
			(xy 342.121784 -382.677839) (xy 342.131904 -382.677416) (xy 342.848184 -382.677416) (xy 342.858307 -382.677829)
			(xy 342.877014 -382.685575) (xy 342.891329 -382.699893) (xy 342.899072 -382.7186) (xy 342.899492 -382.728724)
			(xy 342.899492 -383.014728) (xy 342.899674 -383.021602) (xy 342.903289 -383.034865) (xy 342.906604 -383.04089)
			(xy 342.922966 -383.069241) (xy 342.948769 -383.1294) (xy 342.966259 -383.192479) (xy 342.975121 -383.257335)
			(xy 342.975692 -383.290064) (xy 342.975133 -383.322794) (xy 342.966276 -383.387652) (xy 342.948783 -383.450732)
			(xy 342.922974 -383.51089) (xy 342.906604 -383.539238) (xy 342.903276 -383.545256) (xy 342.899679 -383.558525)
			(xy 342.899492 -383.5654) (xy 342.899492 -384.3147) (xy 342.899685 -384.321573) (xy 342.903292 -384.334836)
			(xy 342.906604 -384.340862) (xy 342.922955 -384.369219) (xy 342.94876 -384.429376) (xy 342.966254 -384.492453)
			(xy 342.975119 -384.557308) (xy 342.975692 -384.590036) (xy 342.975121 -384.622765) (xy 342.966267 -384.687623)
			(xy 342.948778 -384.750704) (xy 342.922972 -384.810862) (xy 342.906604 -384.83921) (xy 342.903286 -384.845233)
			(xy 342.899682 -384.858498) (xy 342.899492 -384.865372) (xy 342.899492 -385.151376) (xy 342.899064 -385.161498)
			(xy 342.891323 -385.180203) (xy 342.877009 -385.194518) (xy 342.858306 -385.202263) (xy 342.848184 -385.202684)
			(xy 342.131904 -385.202684) (xy 342.12178 -385.20228) (xy 342.103073 -385.194531) (xy 342.088758 -385.18021)
			(xy 342.081016 -385.1615) (xy 342.080596 -385.151376) (xy 342.080596 -384.865372) (xy 342.080415 -384.858498)
			(xy 342.0768 -384.845235) (xy 342.073484 -384.83921) (xy 342.057121 -384.810859) (xy 342.031319 -384.7507)
			(xy 342.013829 -384.687621) (xy 342.004967 -384.622765) (xy 342.004396 -384.590036) (xy 338.575072 -384.590036)
			(xy 338.57507 -384.622751) (xy 338.566281 -384.687598) (xy 338.548867 -384.750678) (xy 338.523142 -384.810849)
			(xy 338.506816 -384.83921) (xy 338.503499 -384.845233) (xy 338.499894 -384.858498) (xy 338.499704 -384.865372)
			(xy 338.499704 -385.151376) (xy 338.499259 -385.161528) (xy 338.491472 -385.180279) (xy 338.477082 -385.194603)
			(xy 338.458296 -385.202305) (xy 338.448142 -385.202684) (xy 337.731862 -385.202684) (xy 337.721736 -385.202205)
			(xy 337.703018 -385.194469) (xy 337.688664 -385.180181) (xy 337.680842 -385.1615) (xy 337.6803 -385.151376)
			(xy 337.6803 -384.865372) (xy 337.680119 -384.858498) (xy 337.676503 -384.845235) (xy 337.673188 -384.83921)
			(xy 337.656898 -384.810831) (xy 337.63118 -384.750664) (xy 337.61377 -384.687589) (xy 337.604984 -384.622748)
			(xy 337.60498 -384.557314) (xy 337.613758 -384.492472) (xy 337.63116 -384.429395) (xy 337.65687 -384.369224)
			(xy 337.673188 -384.340862) (xy 337.676515 -384.334844) (xy 337.680113 -384.321575) (xy 337.6803 -384.3147)
			(xy 337.6803 -383.5654) (xy 337.680108 -383.558527) (xy 337.6765 -383.545264) (xy 337.673188 -383.539238)
			(xy 337.656837 -383.510893) (xy 337.631125 -383.450717) (xy 337.613722 -383.387635) (xy 337.604943 -383.322788)
			(xy 336.345949 -383.322788) (xy 336.348847 -383.329546) (xy 336.366332 -383.392628) (xy 336.375188 -383.457486)
			(xy 336.375756 -383.490216) (xy 336.375168 -383.522945) (xy 336.366317 -383.587802) (xy 336.348834 -383.650882)
			(xy 336.323033 -383.711041) (xy 336.306668 -383.73939) (xy 336.303355 -383.745415) (xy 336.299749 -383.758679)
			(xy 336.299556 -383.765552) (xy 336.299556 -384.051556) (xy 336.29898 -384.061655) (xy 336.291267 -384.080321)
			(xy 336.276999 -384.094616) (xy 336.258346 -384.102362) (xy 336.248248 -384.102864) (xy 335.531968 -384.102864)
			(xy 335.521839 -384.102509) (xy 335.503128 -384.094744) (xy 335.488813 -384.080408) (xy 335.481076 -384.061686)
			(xy 335.48066 -384.051556) (xy 335.48066 -383.765552) (xy 335.480453 -383.75868) (xy 335.476856 -383.745417)
			(xy 335.473548 -383.73939) (xy 335.457183 -383.71104) (xy 335.43138 -383.650881) (xy 335.41389 -383.587802)
			(xy 335.40503 -383.522945) (xy 335.40446 -383.490216) (xy 334.131759 -383.490216) (xy 334.122889 -383.51089)
			(xy 334.10652 -383.539238) (xy 334.103193 -383.545257) (xy 334.099595 -383.558525) (xy 334.099408 -383.5654)
			(xy 334.099408 -384.3147) (xy 334.099599 -384.321573) (xy 334.103208 -384.334836) (xy 334.10652 -384.340862)
			(xy 334.122872 -384.369218) (xy 334.148677 -384.429376) (xy 334.16617 -384.492453) (xy 334.175035 -384.557308)
			(xy 334.175608 -384.590036) (xy 334.175035 -384.622765) (xy 334.166181 -384.687623) (xy 334.148693 -384.750703)
			(xy 334.122887 -384.810862) (xy 334.10652 -384.83921) (xy 334.103203 -384.845234) (xy 334.099598 -384.858498)
			(xy 334.099408 -384.865372) (xy 334.099408 -385.151376) (xy 334.098965 -385.161496) (xy 334.091226 -385.180198)
			(xy 334.076918 -385.194512) (xy 334.05822 -385.20226) (xy 334.0481 -385.202684) (xy 333.33182 -385.202684)
			(xy 333.321697 -385.202267) (xy 333.302991 -385.194523) (xy 333.288675 -385.180206) (xy 333.280932 -385.161499)
			(xy 333.280512 -385.151376) (xy 333.280512 -384.865372) (xy 333.280329 -384.858498) (xy 333.276715 -384.845235)
			(xy 333.2734 -384.83921) (xy 333.257038 -384.810859) (xy 333.231236 -384.7507) (xy 333.213745 -384.687621)
			(xy 333.204883 -384.622765) (xy 333.204312 -384.590036) (xy 309.717694 -384.590036) (xy 309.717694 -385.98983)
			(xy 318.109598 -385.98983) (xy 318.113669 -385.934208) (xy 318.125795 -385.879771) (xy 318.145718 -385.82768)
			(xy 318.173014 -385.779045) (xy 318.2071 -385.734902) (xy 318.247249 -385.696193) (xy 318.292607 -385.663742)
			(xy 318.342207 -385.638241) (xy 318.394991 -385.620234) (xy 318.449834 -385.610104) (xy 318.505568 -385.608067)
			(xy 318.561005 -385.614167) (xy 318.614962 -385.628273) (xy 318.666291 -385.650085) (xy 318.713897 -385.679139)
			(xy 318.756765 -385.714814) (xy 318.793982 -385.756351) (xy 318.824755 -385.802864) (xy 318.848427 -385.853361)
			(xy 318.864495 -385.906768) (xy 318.872615 -385.961944) (xy 318.873124 -385.98983) (xy 318.872615 -386.017716)
			(xy 318.864495 -386.072892) (xy 318.848427 -386.126299) (xy 318.82679 -386.172456) (xy 361.296202 -386.172456)
			(xy 361.300273 -386.116834) (xy 361.312399 -386.062397) (xy 361.332322 -386.010306) (xy 361.359618 -385.961671)
			(xy 361.393704 -385.917528) (xy 361.433853 -385.878819) (xy 361.479211 -385.846368) (xy 361.528811 -385.820867)
			(xy 361.581595 -385.80286) (xy 361.636438 -385.79273) (xy 361.692172 -385.790693) (xy 361.747609 -385.796793)
			(xy 361.801566 -385.810899) (xy 361.837102 -385.826) (xy 407.033982 -385.826) (xy 407.038053 -385.770378)
			(xy 407.050179 -385.715941) (xy 407.070102 -385.66385) (xy 407.097398 -385.615215) (xy 407.131484 -385.571072)
			(xy 407.171633 -385.532363) (xy 407.216991 -385.499912) (xy 407.266591 -385.474411) (xy 407.319375 -385.456404)
			(xy 407.374218 -385.446274) (xy 407.429952 -385.444237) (xy 407.485389 -385.450337) (xy 407.539346 -385.464443)
			(xy 407.590675 -385.486255) (xy 407.638281 -385.515309) (xy 407.681149 -385.550984) (xy 407.718366 -385.592521)
			(xy 407.749139 -385.639034) (xy 407.772811 -385.689531) (xy 407.788879 -385.742938) (xy 407.796999 -385.798114)
			(xy 407.797508 -385.826) (xy 407.796999 -385.853886) (xy 407.788879 -385.909062) (xy 407.772811 -385.962469)
			(xy 407.749139 -386.012966) (xy 407.718366 -386.059479) (xy 407.681149 -386.101016) (xy 407.638281 -386.136691)
			(xy 407.590675 -386.165745) (xy 407.539346 -386.187557) (xy 407.485389 -386.201663) (xy 407.429952 -386.207763)
			(xy 407.374218 -386.205726) (xy 407.319375 -386.195596) (xy 407.266591 -386.177589) (xy 407.216991 -386.152088)
			(xy 407.171633 -386.119637) (xy 407.131484 -386.080928) (xy 407.097398 -386.036785) (xy 407.070102 -385.98815)
			(xy 407.050179 -385.936059) (xy 407.038053 -385.881622) (xy 407.033982 -385.826) (xy 361.837102 -385.826)
			(xy 361.852895 -385.832711) (xy 361.900501 -385.861765) (xy 361.943369 -385.89744) (xy 361.980586 -385.938977)
			(xy 362.011359 -385.98549) (xy 362.035031 -386.035987) (xy 362.051099 -386.089394) (xy 362.059219 -386.14457)
			(xy 362.059728 -386.172456) (xy 362.059219 -386.200342) (xy 362.051099 -386.255518) (xy 362.035031 -386.308925)
			(xy 362.011359 -386.359422) (xy 361.980586 -386.405935) (xy 361.943369 -386.447472) (xy 361.900501 -386.483147)
			(xy 361.852895 -386.512201) (xy 361.801566 -386.534013) (xy 361.747609 -386.548119) (xy 361.692172 -386.554219)
			(xy 361.636438 -386.552182) (xy 361.581595 -386.542052) (xy 361.528811 -386.524045) (xy 361.479211 -386.498544)
			(xy 361.433853 -386.466093) (xy 361.393704 -386.427384) (xy 361.359618 -386.383241) (xy 361.332322 -386.334606)
			(xy 361.312399 -386.282515) (xy 361.300273 -386.228078) (xy 361.296202 -386.172456) (xy 318.82679 -386.172456)
			(xy 318.824755 -386.176796) (xy 318.793982 -386.223309) (xy 318.756765 -386.264846) (xy 318.713897 -386.300521)
			(xy 318.666291 -386.329575) (xy 318.614962 -386.351387) (xy 318.561005 -386.365493) (xy 318.505568 -386.371593)
			(xy 318.449834 -386.369556) (xy 318.394991 -386.359426) (xy 318.342207 -386.341419) (xy 318.292607 -386.315918)
			(xy 318.247249 -386.283467) (xy 318.2071 -386.244758) (xy 318.173014 -386.200615) (xy 318.145718 -386.15198)
			(xy 318.125795 -386.099889) (xy 318.113669 -386.045452) (xy 318.109598 -385.98983) (xy 309.717694 -385.98983)
			(xy 309.717694 -386.937758) (xy 403.667974 -386.937758) (xy 403.672045 -386.882136) (xy 403.684171 -386.827699)
			(xy 403.704094 -386.775608) (xy 403.73139 -386.726973) (xy 403.765476 -386.68283) (xy 403.805625 -386.644121)
			(xy 403.850983 -386.61167) (xy 403.900583 -386.586169) (xy 403.953367 -386.568162) (xy 404.00821 -386.558032)
			(xy 404.063944 -386.555995) (xy 404.119381 -386.562095) (xy 404.173338 -386.576201) (xy 404.224667 -386.598013)
			(xy 404.272273 -386.627067) (xy 404.315141 -386.662742) (xy 404.352358 -386.704279) (xy 404.383131 -386.750792)
			(xy 404.406803 -386.801289) (xy 404.422871 -386.854696) (xy 404.430991 -386.909872) (xy 404.4315 -386.937758)
			(xy 404.430991 -386.965644) (xy 404.422871 -387.02082) (xy 404.406803 -387.074227) (xy 404.383131 -387.124724)
			(xy 404.352358 -387.171237) (xy 404.315141 -387.212774) (xy 404.272273 -387.248449) (xy 404.224667 -387.277503)
			(xy 404.173338 -387.299315) (xy 404.119381 -387.313421) (xy 404.063944 -387.319521) (xy 404.00821 -387.317484)
			(xy 403.953367 -387.307354) (xy 403.900583 -387.289347) (xy 403.850983 -387.263846) (xy 403.805625 -387.231395)
			(xy 403.765476 -387.192686) (xy 403.73139 -387.148543) (xy 403.704094 -387.099908) (xy 403.684171 -387.047817)
			(xy 403.672045 -386.99338) (xy 403.667974 -386.937758) (xy 309.717694 -386.937758) (xy 309.717694 -388.06247)
			(xy 317.091058 -388.06247) (xy 317.095129 -388.006848) (xy 317.107255 -387.952411) (xy 317.127178 -387.90032)
			(xy 317.154474 -387.851685) (xy 317.18856 -387.807542) (xy 317.228709 -387.768833) (xy 317.274067 -387.736382)
			(xy 317.323667 -387.710881) (xy 317.376451 -387.692874) (xy 317.431294 -387.682744) (xy 317.487028 -387.680707)
			(xy 317.542465 -387.686807) (xy 317.596422 -387.700913) (xy 317.647751 -387.722725) (xy 317.695357 -387.751779)
			(xy 317.738225 -387.787454) (xy 317.775442 -387.828991) (xy 317.806215 -387.875504) (xy 317.829887 -387.926001)
			(xy 317.834952 -387.942836) (xy 320.392296 -387.942836) (xy 320.396367 -387.887214) (xy 320.408493 -387.832777)
			(xy 320.428416 -387.780686) (xy 320.455712 -387.732051) (xy 320.489798 -387.687908) (xy 320.529947 -387.649199)
			(xy 320.575305 -387.616748) (xy 320.624905 -387.591247) (xy 320.677689 -387.57324) (xy 320.732532 -387.56311)
			(xy 320.788266 -387.561073) (xy 320.843703 -387.567173) (xy 320.89766 -387.581279) (xy 320.948989 -387.603091)
			(xy 320.996595 -387.632145) (xy 321.039463 -387.66782) (xy 321.07668 -387.709357) (xy 321.107453 -387.75587)
			(xy 321.131125 -387.806367) (xy 321.147193 -387.859774) (xy 321.155313 -387.91495) (xy 321.155822 -387.942836)
			(xy 321.155313 -387.970722) (xy 321.155081 -387.9723) (xy 362.73308 -387.9723) (xy 362.737151 -387.916678)
			(xy 362.749277 -387.862241) (xy 362.7692 -387.81015) (xy 362.796496 -387.761515) (xy 362.830582 -387.717372)
			(xy 362.870731 -387.678663) (xy 362.916089 -387.646212) (xy 362.965689 -387.620711) (xy 363.018473 -387.602704)
			(xy 363.073316 -387.592574) (xy 363.12905 -387.590537) (xy 363.184487 -387.596637) (xy 363.238444 -387.610743)
			(xy 363.289773 -387.632555) (xy 363.337379 -387.661609) (xy 363.380247 -387.697284) (xy 363.417464 -387.738821)
			(xy 363.448237 -387.785334) (xy 363.471909 -387.835831) (xy 363.487977 -387.889238) (xy 363.490893 -387.909054)
			(xy 366.166144 -387.909054) (xy 366.170215 -387.853432) (xy 366.182341 -387.798995) (xy 366.202264 -387.746904)
			(xy 366.22956 -387.698269) (xy 366.263646 -387.654126) (xy 366.303795 -387.615417) (xy 366.349153 -387.582966)
			(xy 366.398753 -387.557465) (xy 366.451537 -387.539458) (xy 366.50638 -387.529328) (xy 366.562114 -387.527291)
			(xy 366.617551 -387.533391) (xy 366.671508 -387.547497) (xy 366.722837 -387.569309) (xy 366.770443 -387.598363)
			(xy 366.813311 -387.634038) (xy 366.850528 -387.675575) (xy 366.881301 -387.722088) (xy 366.904973 -387.772585)
			(xy 366.921041 -387.825992) (xy 366.929161 -387.881168) (xy 366.92967 -387.909054) (xy 366.929161 -387.93694)
			(xy 366.928293 -387.942836) (xy 408.392374 -387.942836) (xy 408.396445 -387.887214) (xy 408.408571 -387.832777)
			(xy 408.428494 -387.780686) (xy 408.45579 -387.732051) (xy 408.489876 -387.687908) (xy 408.530025 -387.649199)
			(xy 408.575383 -387.616748) (xy 408.624983 -387.591247) (xy 408.677767 -387.57324) (xy 408.73261 -387.56311)
			(xy 408.788344 -387.561073) (xy 408.843781 -387.567173) (xy 408.897738 -387.581279) (xy 408.949067 -387.603091)
			(xy 408.996673 -387.632145) (xy 409.039541 -387.66782) (xy 409.076758 -387.709357) (xy 409.107531 -387.75587)
			(xy 409.131203 -387.806367) (xy 409.147271 -387.859774) (xy 409.155391 -387.91495) (xy 409.1559 -387.942836)
			(xy 409.155391 -387.970722) (xy 409.147271 -388.025898) (xy 409.131203 -388.079305) (xy 409.107531 -388.129802)
			(xy 409.076758 -388.176315) (xy 409.039541 -388.217852) (xy 408.996673 -388.253527) (xy 408.949067 -388.282581)
			(xy 408.897738 -388.304393) (xy 408.843781 -388.318499) (xy 408.788344 -388.324599) (xy 408.73261 -388.322562)
			(xy 408.677767 -388.312432) (xy 408.624983 -388.294425) (xy 408.575383 -388.268924) (xy 408.530025 -388.236473)
			(xy 408.489876 -388.197764) (xy 408.45579 -388.153621) (xy 408.428494 -388.104986) (xy 408.408571 -388.052895)
			(xy 408.396445 -387.998458) (xy 408.392374 -387.942836) (xy 366.928293 -387.942836) (xy 366.921041 -387.992116)
			(xy 366.904973 -388.045523) (xy 366.881301 -388.09602) (xy 366.850528 -388.142533) (xy 366.813311 -388.18407)
			(xy 366.770443 -388.219745) (xy 366.722837 -388.248799) (xy 366.671508 -388.270611) (xy 366.617551 -388.284717)
			(xy 366.562114 -388.290817) (xy 366.50638 -388.28878) (xy 366.451537 -388.27865) (xy 366.398753 -388.260643)
			(xy 366.349153 -388.235142) (xy 366.303795 -388.202691) (xy 366.263646 -388.163982) (xy 366.22956 -388.119839)
			(xy 366.202264 -388.071204) (xy 366.182341 -388.019113) (xy 366.170215 -387.964676) (xy 366.166144 -387.909054)
			(xy 363.490893 -387.909054) (xy 363.496097 -387.944414) (xy 363.496606 -387.9723) (xy 363.496097 -388.000186)
			(xy 363.487977 -388.055362) (xy 363.471909 -388.108769) (xy 363.448237 -388.159266) (xy 363.417464 -388.205779)
			(xy 363.380247 -388.247316) (xy 363.337379 -388.282991) (xy 363.289773 -388.312045) (xy 363.238444 -388.333857)
			(xy 363.184487 -388.347963) (xy 363.12905 -388.354063) (xy 363.073316 -388.352026) (xy 363.018473 -388.341896)
			(xy 362.965689 -388.323889) (xy 362.916089 -388.298388) (xy 362.870731 -388.265937) (xy 362.830582 -388.227228)
			(xy 362.796496 -388.183085) (xy 362.7692 -388.13445) (xy 362.749277 -388.082359) (xy 362.737151 -388.027922)
			(xy 362.73308 -387.9723) (xy 321.155081 -387.9723) (xy 321.147193 -388.025898) (xy 321.131125 -388.079305)
			(xy 321.107453 -388.129802) (xy 321.07668 -388.176315) (xy 321.039463 -388.217852) (xy 320.996595 -388.253527)
			(xy 320.948989 -388.282581) (xy 320.89766 -388.304393) (xy 320.843703 -388.318499) (xy 320.788266 -388.324599)
			(xy 320.732532 -388.322562) (xy 320.677689 -388.312432) (xy 320.624905 -388.294425) (xy 320.575305 -388.268924)
			(xy 320.529947 -388.236473) (xy 320.489798 -388.197764) (xy 320.455712 -388.153621) (xy 320.428416 -388.104986)
			(xy 320.408493 -388.052895) (xy 320.396367 -387.998458) (xy 320.392296 -387.942836) (xy 317.834952 -387.942836)
			(xy 317.845955 -387.979408) (xy 317.854075 -388.034584) (xy 317.854584 -388.06247) (xy 317.854075 -388.090356)
			(xy 317.845955 -388.145532) (xy 317.829887 -388.198939) (xy 317.806215 -388.249436) (xy 317.775442 -388.295949)
			(xy 317.738225 -388.337486) (xy 317.695357 -388.373161) (xy 317.647751 -388.402215) (xy 317.596422 -388.424027)
			(xy 317.542465 -388.438133) (xy 317.487028 -388.444233) (xy 317.431294 -388.442196) (xy 317.376451 -388.432066)
			(xy 317.323667 -388.414059) (xy 317.274067 -388.388558) (xy 317.228709 -388.356107) (xy 317.18856 -388.317398)
			(xy 317.154474 -388.273255) (xy 317.127178 -388.22462) (xy 317.107255 -388.172529) (xy 317.095129 -388.118092)
			(xy 317.091058 -388.06247) (xy 309.717694 -388.06247) (xy 309.717694 -388.958836) (xy 318.203832 -388.958836)
			(xy 318.207903 -388.903214) (xy 318.220029 -388.848777) (xy 318.239952 -388.796686) (xy 318.267248 -388.748051)
			(xy 318.301334 -388.703908) (xy 318.341483 -388.665199) (xy 318.386841 -388.632748) (xy 318.436441 -388.607247)
			(xy 318.489225 -388.58924) (xy 318.544068 -388.57911) (xy 318.599802 -388.577073) (xy 318.655239 -388.583173)
			(xy 318.709196 -388.597279) (xy 318.760525 -388.619091) (xy 318.808131 -388.648145) (xy 318.850999 -388.68382)
			(xy 318.888216 -388.725357) (xy 318.918989 -388.77187) (xy 318.942661 -388.822367) (xy 318.958729 -388.875774)
			(xy 318.966849 -388.93095) (xy 318.967358 -388.958836) (xy 321.520564 -388.958836) (xy 321.524635 -388.903214)
			(xy 321.536761 -388.848777) (xy 321.556684 -388.796686) (xy 321.58398 -388.748051) (xy 321.618066 -388.703908)
			(xy 321.658215 -388.665199) (xy 321.703573 -388.632748) (xy 321.753173 -388.607247) (xy 321.805957 -388.58924)
			(xy 321.8608 -388.57911) (xy 321.916534 -388.577073) (xy 321.971971 -388.583173) (xy 322.025928 -388.597279)
			(xy 322.077257 -388.619091) (xy 322.124863 -388.648145) (xy 322.167731 -388.68382) (xy 322.204948 -388.725357)
			(xy 322.235721 -388.77187) (xy 322.259393 -388.822367) (xy 322.265451 -388.842504) (xy 366.936272 -388.842504)
			(xy 366.940343 -388.786882) (xy 366.952469 -388.732445) (xy 366.972392 -388.680354) (xy 366.999688 -388.631719)
			(xy 367.033774 -388.587576) (xy 367.073923 -388.548867) (xy 367.119281 -388.516416) (xy 367.168881 -388.490915)
			(xy 367.221665 -388.472908) (xy 367.276508 -388.462778) (xy 367.332242 -388.460741) (xy 367.387679 -388.466841)
			(xy 367.441636 -388.480947) (xy 367.492965 -388.502759) (xy 367.540571 -388.531813) (xy 367.583439 -388.567488)
			(xy 367.620656 -388.609025) (xy 367.651429 -388.655538) (xy 367.675101 -388.706035) (xy 367.691169 -388.759442)
			(xy 367.699289 -388.814618) (xy 367.699798 -388.842504) (xy 367.699289 -388.87039) (xy 367.691169 -388.925566)
			(xy 367.681159 -388.958836) (xy 409.520642 -388.958836) (xy 409.524713 -388.903214) (xy 409.536839 -388.848777)
			(xy 409.556762 -388.796686) (xy 409.584058 -388.748051) (xy 409.618144 -388.703908) (xy 409.658293 -388.665199)
			(xy 409.703651 -388.632748) (xy 409.753251 -388.607247) (xy 409.806035 -388.58924) (xy 409.860878 -388.57911)
			(xy 409.916612 -388.577073) (xy 409.972049 -388.583173) (xy 410.026006 -388.597279) (xy 410.077335 -388.619091)
			(xy 410.124941 -388.648145) (xy 410.167809 -388.68382) (xy 410.205026 -388.725357) (xy 410.235799 -388.77187)
			(xy 410.259471 -388.822367) (xy 410.275539 -388.875774) (xy 410.283659 -388.93095) (xy 410.284168 -388.958836)
			(xy 410.283659 -388.986722) (xy 410.275539 -389.041898) (xy 410.259471 -389.095305) (xy 410.235799 -389.145802)
			(xy 410.205026 -389.192315) (xy 410.167809 -389.233852) (xy 410.124941 -389.269527) (xy 410.077335 -389.298581)
			(xy 410.026006 -389.320393) (xy 409.972049 -389.334499) (xy 409.916612 -389.340599) (xy 409.860878 -389.338562)
			(xy 409.806035 -389.328432) (xy 409.753251 -389.310425) (xy 409.703651 -389.284924) (xy 409.658293 -389.252473)
			(xy 409.618144 -389.213764) (xy 409.584058 -389.169621) (xy 409.556762 -389.120986) (xy 409.536839 -389.068895)
			(xy 409.524713 -389.014458) (xy 409.520642 -388.958836) (xy 367.681159 -388.958836) (xy 367.675101 -388.978973)
			(xy 367.651429 -389.02947) (xy 367.620656 -389.075983) (xy 367.583439 -389.11752) (xy 367.540571 -389.153195)
			(xy 367.492965 -389.182249) (xy 367.441636 -389.204061) (xy 367.387679 -389.218167) (xy 367.332242 -389.224267)
			(xy 367.276508 -389.22223) (xy 367.221665 -389.2121) (xy 367.168881 -389.194093) (xy 367.119281 -389.168592)
			(xy 367.073923 -389.136141) (xy 367.033774 -389.097432) (xy 366.999688 -389.053289) (xy 366.972392 -389.004654)
			(xy 366.952469 -388.952563) (xy 366.940343 -388.898126) (xy 366.936272 -388.842504) (xy 322.265451 -388.842504)
			(xy 322.275461 -388.875774) (xy 322.283581 -388.93095) (xy 322.28409 -388.958836) (xy 322.283581 -388.986722)
			(xy 322.275461 -389.041898) (xy 322.259393 -389.095305) (xy 322.235721 -389.145802) (xy 322.204948 -389.192315)
			(xy 322.167731 -389.233852) (xy 322.124863 -389.269527) (xy 322.077257 -389.298581) (xy 322.025928 -389.320393)
			(xy 321.971971 -389.334499) (xy 321.916534 -389.340599) (xy 321.8608 -389.338562) (xy 321.805957 -389.328432)
			(xy 321.753173 -389.310425) (xy 321.703573 -389.284924) (xy 321.658215 -389.252473) (xy 321.618066 -389.213764)
			(xy 321.58398 -389.169621) (xy 321.556684 -389.120986) (xy 321.536761 -389.068895) (xy 321.524635 -389.014458)
			(xy 321.520564 -388.958836) (xy 318.967358 -388.958836) (xy 318.966849 -388.986722) (xy 318.958729 -389.041898)
			(xy 318.942661 -389.095305) (xy 318.918989 -389.145802) (xy 318.888216 -389.192315) (xy 318.850999 -389.233852)
			(xy 318.808131 -389.269527) (xy 318.760525 -389.298581) (xy 318.709196 -389.320393) (xy 318.655239 -389.334499)
			(xy 318.599802 -389.340599) (xy 318.544068 -389.338562) (xy 318.489225 -389.328432) (xy 318.436441 -389.310425)
			(xy 318.386841 -389.284924) (xy 318.341483 -389.252473) (xy 318.301334 -389.213764) (xy 318.267248 -389.169621)
			(xy 318.239952 -389.120986) (xy 318.220029 -389.068895) (xy 318.207903 -389.014458) (xy 318.203832 -388.958836)
			(xy 309.717694 -388.958836) (xy 309.717694 -389.974836) (xy 317.228218 -389.974836) (xy 317.232289 -389.919214)
			(xy 317.244415 -389.864777) (xy 317.264338 -389.812686) (xy 317.291634 -389.764051) (xy 317.32572 -389.719908)
			(xy 317.365869 -389.681199) (xy 317.411227 -389.648748) (xy 317.460827 -389.623247) (xy 317.513611 -389.60524)
			(xy 317.568454 -389.59511) (xy 317.624188 -389.593073) (xy 317.679625 -389.599173) (xy 317.733582 -389.613279)
			(xy 317.784911 -389.635091) (xy 317.832517 -389.664145) (xy 317.875385 -389.69982) (xy 317.912602 -389.741357)
			(xy 317.943375 -389.78787) (xy 317.967047 -389.838367) (xy 317.983115 -389.891774) (xy 317.991235 -389.94695)
			(xy 317.991744 -389.974836) (xy 320.392296 -389.974836) (xy 320.396367 -389.919214) (xy 320.408493 -389.864777)
			(xy 320.428416 -389.812686) (xy 320.455712 -389.764051) (xy 320.489798 -389.719908) (xy 320.529947 -389.681199)
			(xy 320.575305 -389.648748) (xy 320.624905 -389.623247) (xy 320.677689 -389.60524) (xy 320.732532 -389.59511)
			(xy 320.788266 -389.593073) (xy 320.843703 -389.599173) (xy 320.89766 -389.613279) (xy 320.948989 -389.635091)
			(xy 320.996595 -389.664145) (xy 321.039463 -389.69982) (xy 321.07668 -389.741357) (xy 321.107453 -389.78787)
			(xy 321.131125 -389.838367) (xy 321.147193 -389.891774) (xy 321.155313 -389.94695) (xy 321.155822 -389.974836)
			(xy 321.155313 -390.002722) (xy 321.147193 -390.057898) (xy 321.131125 -390.111305) (xy 321.107453 -390.161802)
			(xy 321.07668 -390.208315) (xy 321.039463 -390.249852) (xy 320.996595 -390.285527) (xy 320.991265 -390.28878)
			(xy 357.386126 -390.28878) (xy 357.390197 -390.233158) (xy 357.402323 -390.178721) (xy 357.422246 -390.12663)
			(xy 357.449542 -390.077995) (xy 357.483628 -390.033852) (xy 357.523777 -389.995143) (xy 357.569135 -389.962692)
			(xy 357.618735 -389.937191) (xy 357.671519 -389.919184) (xy 357.726362 -389.909054) (xy 357.782096 -389.907017)
			(xy 357.837533 -389.913117) (xy 357.89149 -389.927223) (xy 357.942819 -389.949035) (xy 357.985095 -389.974836)
			(xy 408.392374 -389.974836) (xy 408.396445 -389.919214) (xy 408.408571 -389.864777) (xy 408.428494 -389.812686)
			(xy 408.45579 -389.764051) (xy 408.489876 -389.719908) (xy 408.530025 -389.681199) (xy 408.575383 -389.648748)
			(xy 408.624983 -389.623247) (xy 408.677767 -389.60524) (xy 408.73261 -389.59511) (xy 408.788344 -389.593073)
			(xy 408.843781 -389.599173) (xy 408.897738 -389.613279) (xy 408.949067 -389.635091) (xy 408.996673 -389.664145)
			(xy 409.039541 -389.69982) (xy 409.076758 -389.741357) (xy 409.107531 -389.78787) (xy 409.131203 -389.838367)
			(xy 409.147271 -389.891774) (xy 409.155391 -389.94695) (xy 409.1559 -389.974836) (xy 409.155391 -390.002722)
			(xy 409.147271 -390.057898) (xy 409.131203 -390.111305) (xy 409.107531 -390.161802) (xy 409.076758 -390.208315)
			(xy 409.039541 -390.249852) (xy 408.996673 -390.285527) (xy 408.949067 -390.314581) (xy 408.897738 -390.336393)
			(xy 408.843781 -390.350499) (xy 408.788344 -390.356599) (xy 408.73261 -390.354562) (xy 408.677767 -390.344432)
			(xy 408.624983 -390.326425) (xy 408.575383 -390.300924) (xy 408.530025 -390.268473) (xy 408.489876 -390.229764)
			(xy 408.45579 -390.185621) (xy 408.428494 -390.136986) (xy 408.408571 -390.084895) (xy 408.396445 -390.030458)
			(xy 408.392374 -389.974836) (xy 357.985095 -389.974836) (xy 357.990425 -389.978089) (xy 358.033293 -390.013764)
			(xy 358.07051 -390.055301) (xy 358.101283 -390.101814) (xy 358.124955 -390.152311) (xy 358.141023 -390.205718)
			(xy 358.149143 -390.260894) (xy 358.149652 -390.28878) (xy 358.149143 -390.316666) (xy 358.141023 -390.371842)
			(xy 358.124955 -390.425249) (xy 358.101283 -390.475746) (xy 358.07051 -390.522259) (xy 358.033293 -390.563796)
			(xy 357.990425 -390.599471) (xy 357.942819 -390.628525) (xy 357.89149 -390.650337) (xy 357.837533 -390.664443)
			(xy 357.782096 -390.670543) (xy 357.726362 -390.668506) (xy 357.671519 -390.658376) (xy 357.618735 -390.640369)
			(xy 357.569135 -390.614868) (xy 357.523777 -390.582417) (xy 357.483628 -390.543708) (xy 357.449542 -390.499565)
			(xy 357.422246 -390.45093) (xy 357.402323 -390.398839) (xy 357.390197 -390.344402) (xy 357.386126 -390.28878)
			(xy 320.991265 -390.28878) (xy 320.948989 -390.314581) (xy 320.89766 -390.336393) (xy 320.843703 -390.350499)
			(xy 320.788266 -390.356599) (xy 320.732532 -390.354562) (xy 320.677689 -390.344432) (xy 320.624905 -390.326425)
			(xy 320.575305 -390.300924) (xy 320.529947 -390.268473) (xy 320.489798 -390.229764) (xy 320.455712 -390.185621)
			(xy 320.428416 -390.136986) (xy 320.408493 -390.084895) (xy 320.396367 -390.030458) (xy 320.392296 -389.974836)
			(xy 317.991744 -389.974836) (xy 317.991235 -390.002722) (xy 317.983115 -390.057898) (xy 317.967047 -390.111305)
			(xy 317.943375 -390.161802) (xy 317.912602 -390.208315) (xy 317.875385 -390.249852) (xy 317.832517 -390.285527)
			(xy 317.784911 -390.314581) (xy 317.733582 -390.336393) (xy 317.679625 -390.350499) (xy 317.624188 -390.356599)
			(xy 317.568454 -390.354562) (xy 317.513611 -390.344432) (xy 317.460827 -390.326425) (xy 317.411227 -390.300924)
			(xy 317.365869 -390.268473) (xy 317.32572 -390.229764) (xy 317.291634 -390.185621) (xy 317.264338 -390.136986)
			(xy 317.244415 -390.084895) (xy 317.232289 -390.030458) (xy 317.228218 -389.974836) (xy 309.717694 -389.974836)
			(xy 309.717694 -390.990836) (xy 318.203832 -390.990836) (xy 318.207903 -390.935214) (xy 318.220029 -390.880777)
			(xy 318.239952 -390.828686) (xy 318.267248 -390.780051) (xy 318.301334 -390.735908) (xy 318.341483 -390.697199)
			(xy 318.386841 -390.664748) (xy 318.436441 -390.639247) (xy 318.489225 -390.62124) (xy 318.544068 -390.61111)
			(xy 318.599802 -390.609073) (xy 318.655239 -390.615173) (xy 318.709196 -390.629279) (xy 318.760525 -390.651091)
			(xy 318.808131 -390.680145) (xy 318.850999 -390.71582) (xy 318.888216 -390.757357) (xy 318.918989 -390.80387)
			(xy 318.942661 -390.854367) (xy 318.958729 -390.907774) (xy 318.966849 -390.96295) (xy 318.967358 -390.990836)
			(xy 321.482464 -390.990836) (xy 321.486535 -390.935214) (xy 321.498661 -390.880777) (xy 321.518584 -390.828686)
			(xy 321.54588 -390.780051) (xy 321.579966 -390.735908) (xy 321.620115 -390.697199) (xy 321.665473 -390.664748)
			(xy 321.715073 -390.639247) (xy 321.767857 -390.62124) (xy 321.8227 -390.61111) (xy 321.878434 -390.609073)
			(xy 321.933871 -390.615173) (xy 321.987828 -390.629279) (xy 322.039157 -390.651091) (xy 322.086763 -390.680145)
			(xy 322.129631 -390.71582) (xy 322.166848 -390.757357) (xy 322.197621 -390.80387) (xy 322.221293 -390.854367)
			(xy 322.237361 -390.907774) (xy 322.245481 -390.96295) (xy 322.24599 -390.990836) (xy 322.245481 -391.018722)
			(xy 322.237361 -391.073898) (xy 322.221293 -391.127305) (xy 322.197621 -391.177802) (xy 322.166848 -391.224315)
			(xy 322.130027 -391.26541) (xy 365.668812 -391.26541) (xy 365.672883 -391.209788) (xy 365.685009 -391.155351)
			(xy 365.704932 -391.10326) (xy 365.732228 -391.054625) (xy 365.766314 -391.010482) (xy 365.806463 -390.971773)
			(xy 365.851821 -390.939322) (xy 365.901421 -390.913821) (xy 365.954205 -390.895814) (xy 366.009048 -390.885684)
			(xy 366.064782 -390.883647) (xy 366.120219 -390.889747) (xy 366.174176 -390.903853) (xy 366.225505 -390.925665)
			(xy 366.273111 -390.954719) (xy 366.315979 -390.990394) (xy 366.316375 -390.990836) (xy 406.20391 -390.990836)
			(xy 406.207981 -390.935214) (xy 406.220107 -390.880777) (xy 406.24003 -390.828686) (xy 406.267326 -390.780051)
			(xy 406.301412 -390.735908) (xy 406.341561 -390.697199) (xy 406.386919 -390.664748) (xy 406.436519 -390.639247)
			(xy 406.489303 -390.62124) (xy 406.544146 -390.61111) (xy 406.59988 -390.609073) (xy 406.655317 -390.615173)
			(xy 406.709274 -390.629279) (xy 406.760603 -390.651091) (xy 406.808209 -390.680145) (xy 406.851077 -390.71582)
			(xy 406.888294 -390.757357) (xy 406.919067 -390.80387) (xy 406.942739 -390.854367) (xy 406.958807 -390.907774)
			(xy 406.966927 -390.96295) (xy 406.967436 -390.990836) (xy 406.966927 -391.018722) (xy 406.958807 -391.073898)
			(xy 406.942739 -391.127305) (xy 406.919067 -391.177802) (xy 406.888294 -391.224315) (xy 406.851077 -391.265852)
			(xy 406.808209 -391.301527) (xy 406.760603 -391.330581) (xy 406.709274 -391.352393) (xy 406.655317 -391.366499)
			(xy 406.59988 -391.372599) (xy 406.544146 -391.370562) (xy 406.489303 -391.360432) (xy 406.436519 -391.342425)
			(xy 406.386919 -391.316924) (xy 406.341561 -391.284473) (xy 406.301412 -391.245764) (xy 406.267326 -391.201621)
			(xy 406.24003 -391.152986) (xy 406.220107 -391.100895) (xy 406.207981 -391.046458) (xy 406.20391 -390.990836)
			(xy 366.316375 -390.990836) (xy 366.353196 -391.031931) (xy 366.383969 -391.078444) (xy 366.407641 -391.128941)
			(xy 366.423709 -391.182348) (xy 366.431829 -391.237524) (xy 366.432338 -391.26541) (xy 366.431829 -391.293296)
			(xy 366.423709 -391.348472) (xy 366.407641 -391.401879) (xy 366.383969 -391.452376) (xy 366.353196 -391.498889)
			(xy 366.315979 -391.540426) (xy 366.273111 -391.576101) (xy 366.225505 -391.605155) (xy 366.174176 -391.626967)
			(xy 366.120219 -391.641073) (xy 366.064782 -391.647173) (xy 366.009048 -391.645136) (xy 365.954205 -391.635006)
			(xy 365.901421 -391.616999) (xy 365.851821 -391.591498) (xy 365.806463 -391.559047) (xy 365.766314 -391.520338)
			(xy 365.732228 -391.476195) (xy 365.704932 -391.42756) (xy 365.685009 -391.375469) (xy 365.672883 -391.321032)
			(xy 365.668812 -391.26541) (xy 322.130027 -391.26541) (xy 322.129631 -391.265852) (xy 322.086763 -391.301527)
			(xy 322.039157 -391.330581) (xy 321.987828 -391.352393) (xy 321.933871 -391.366499) (xy 321.878434 -391.372599)
			(xy 321.8227 -391.370562) (xy 321.767857 -391.360432) (xy 321.715073 -391.342425) (xy 321.665473 -391.316924)
			(xy 321.620115 -391.284473) (xy 321.579966 -391.245764) (xy 321.54588 -391.201621) (xy 321.518584 -391.152986)
			(xy 321.498661 -391.100895) (xy 321.486535 -391.046458) (xy 321.482464 -390.990836) (xy 318.967358 -390.990836)
			(xy 318.966849 -391.018722) (xy 318.958729 -391.073898) (xy 318.942661 -391.127305) (xy 318.918989 -391.177802)
			(xy 318.888216 -391.224315) (xy 318.850999 -391.265852) (xy 318.808131 -391.301527) (xy 318.760525 -391.330581)
			(xy 318.709196 -391.352393) (xy 318.655239 -391.366499) (xy 318.599802 -391.372599) (xy 318.544068 -391.370562)
			(xy 318.489225 -391.360432) (xy 318.436441 -391.342425) (xy 318.386841 -391.316924) (xy 318.341483 -391.284473)
			(xy 318.301334 -391.245764) (xy 318.267248 -391.201621) (xy 318.239952 -391.152986) (xy 318.220029 -391.100895)
			(xy 318.207903 -391.046458) (xy 318.203832 -390.990836) (xy 309.717694 -390.990836) (xy 309.717694 -392.016742)
			(xy 405.655778 -392.016742) (xy 405.659849 -391.96112) (xy 405.671975 -391.906683) (xy 405.691898 -391.854592)
			(xy 405.719194 -391.805957) (xy 405.75328 -391.761814) (xy 405.793429 -391.723105) (xy 405.838787 -391.690654)
			(xy 405.888387 -391.665153) (xy 405.941171 -391.647146) (xy 405.996014 -391.637016) (xy 406.051748 -391.634979)
			(xy 406.107185 -391.641079) (xy 406.161142 -391.655185) (xy 406.212471 -391.676997) (xy 406.260077 -391.706051)
			(xy 406.302945 -391.741726) (xy 406.340162 -391.783263) (xy 406.370935 -391.829776) (xy 406.394607 -391.880273)
			(xy 406.410675 -391.93368) (xy 406.418795 -391.988856) (xy 406.419304 -392.016742) (xy 406.418795 -392.044628)
			(xy 406.410675 -392.099804) (xy 406.394607 -392.153211) (xy 406.370935 -392.203708) (xy 406.340162 -392.250221)
			(xy 406.302945 -392.291758) (xy 406.260077 -392.327433) (xy 406.212471 -392.356487) (xy 406.161142 -392.378299)
			(xy 406.107185 -392.392405) (xy 406.051748 -392.398505) (xy 405.996014 -392.396468) (xy 405.941171 -392.386338)
			(xy 405.888387 -392.368331) (xy 405.838787 -392.34283) (xy 405.793429 -392.310379) (xy 405.75328 -392.27167)
			(xy 405.719194 -392.227527) (xy 405.691898 -392.178892) (xy 405.671975 -392.126801) (xy 405.659849 -392.072364)
			(xy 405.655778 -392.016742) (xy 309.717694 -392.016742) (xy 309.717694 -392.684254) (xy 363.702852 -392.684254)
			(xy 363.706923 -392.628632) (xy 363.719049 -392.574195) (xy 363.738972 -392.522104) (xy 363.766268 -392.473469)
			(xy 363.800354 -392.429326) (xy 363.840503 -392.390617) (xy 363.885861 -392.358166) (xy 363.935461 -392.332665)
			(xy 363.988245 -392.314658) (xy 364.043088 -392.304528) (xy 364.098822 -392.302491) (xy 364.154259 -392.308591)
			(xy 364.208216 -392.322697) (xy 364.259545 -392.344509) (xy 364.307151 -392.373563) (xy 364.350019 -392.409238)
			(xy 364.387236 -392.450775) (xy 364.418009 -392.497288) (xy 364.441681 -392.547785) (xy 364.457749 -392.601192)
			(xy 364.465869 -392.656368) (xy 364.466378 -392.684254) (xy 364.465869 -392.71214) (xy 364.457749 -392.767316)
			(xy 364.441681 -392.820723) (xy 364.418009 -392.87122) (xy 364.387236 -392.917733) (xy 364.350019 -392.95927)
			(xy 364.307151 -392.994945) (xy 364.259545 -393.023999) (xy 364.208216 -393.045811) (xy 364.154259 -393.059917)
			(xy 364.098822 -393.066017) (xy 364.043088 -393.06398) (xy 363.988245 -393.05385) (xy 363.935461 -393.035843)
			(xy 363.885861 -393.010342) (xy 363.840503 -392.977891) (xy 363.800354 -392.939182) (xy 363.766268 -392.895039)
			(xy 363.738972 -392.846404) (xy 363.719049 -392.794313) (xy 363.706923 -392.739876) (xy 363.702852 -392.684254)
			(xy 309.717694 -392.684254) (xy 309.717694 -393.459716) (xy 357.18572 -393.459716) (xy 357.189791 -393.404094)
			(xy 357.201917 -393.349657) (xy 357.22184 -393.297566) (xy 357.249136 -393.248931) (xy 357.283222 -393.204788)
			(xy 357.323371 -393.166079) (xy 357.368729 -393.133628) (xy 357.418329 -393.108127) (xy 357.471113 -393.09012)
			(xy 357.525956 -393.07999) (xy 357.58169 -393.077953) (xy 357.637127 -393.084053) (xy 357.691084 -393.098159)
			(xy 357.742413 -393.119971) (xy 357.790019 -393.149025) (xy 357.832887 -393.1847) (xy 357.870104 -393.226237)
			(xy 357.900877 -393.27275) (xy 357.924549 -393.323247) (xy 357.940617 -393.376654) (xy 357.948737 -393.43183)
			(xy 357.949246 -393.459716) (xy 357.948737 -393.487602) (xy 357.940617 -393.542778) (xy 357.924549 -393.596185)
			(xy 357.900877 -393.646682) (xy 357.870104 -393.693195) (xy 357.832887 -393.734732) (xy 357.790019 -393.770407)
			(xy 357.742413 -393.799461) (xy 357.691084 -393.821273) (xy 357.637127 -393.835379) (xy 357.58169 -393.841479)
			(xy 357.525956 -393.839442) (xy 357.471113 -393.829312) (xy 357.418329 -393.811305) (xy 357.368729 -393.785804)
			(xy 357.323371 -393.753353) (xy 357.283222 -393.714644) (xy 357.249136 -393.670501) (xy 357.22184 -393.621866)
			(xy 357.201917 -393.569775) (xy 357.189791 -393.515338) (xy 357.18572 -393.459716) (xy 309.717694 -393.459716)
			(xy 309.717694 -413.376364) (xy 309.71871 -413.386016) (xy 309.720332 -413.393263) (xy 309.727165 -413.406441)
			(xy 309.732172 -413.411924) (xy 310.018684 -413.698436) (xy 310.024182 -413.703425) (xy 310.037348 -413.710275)
			(xy 310.044592 -413.711898) (xy 310.054244 -413.712914) (xy 312.711338 -413.712914) (xy 312.72099 -413.711898)
			(xy 312.728232 -413.710267) (xy 312.741397 -413.703421) (xy 312.746898 -413.698436) (xy 313.059318 -413.386016)
			(xy 313.064309 -413.380518) (xy 313.071161 -413.367354) (xy 313.07278 -413.360108) (xy 313.073796 -413.350456)
			(xy 313.073796 -394.32992) (xy 313.073796 -394.27912) (xy 326.480424 -394.27912) (xy 326.485504 -394.280136)
			(xy 326.494211 -394.282363) (xy 326.509391 -394.291962) (xy 326.520314 -394.306219) (xy 326.52335 -394.31468)
			(xy 326.525636 -394.321792) (xy 326.525636 -397.822887) (xy 331.004997 -397.822887) (xy 331.005001 -397.757448)
			(xy 331.01379 -397.692601) (xy 331.031203 -397.629521) (xy 331.056927 -397.569349) (xy 331.073252 -397.540988)
			(xy 331.076567 -397.534964) (xy 331.080173 -397.5217) (xy 331.080364 -397.514826) (xy 331.080364 -396.765526)
			(xy 331.080167 -396.758653) (xy 331.076563 -396.74539) (xy 331.073252 -396.739364) (xy 331.056921 -396.711008)
			(xy 331.031203 -396.650835) (xy 331.013796 -396.587756) (xy 331.005013 -396.52291) (xy 331.005014 -396.457473)
			(xy 331.013799 -396.392627) (xy 331.031209 -396.329548) (xy 331.056929 -396.269377) (xy 331.073252 -396.241016)
			(xy 331.076557 -396.234987) (xy 331.080169 -396.221727) (xy 331.080364 -396.214854) (xy 331.080364 -395.92885)
			(xy 331.080805 -395.918678) (xy 331.088579 -395.89988) (xy 331.10296 -395.885492) (xy 331.121755 -395.87771)
			(xy 331.131926 -395.877288) (xy 331.848206 -395.877288) (xy 331.858384 -395.87766) (xy 331.877189 -395.885456)
			(xy 331.891575 -395.899859) (xy 331.899351 -395.918671) (xy 331.899768 -395.92885) (xy 331.899768 -396.214854)
			(xy 331.899981 -396.221726) (xy 331.903575 -396.234988) (xy 331.90688 -396.241016) (xy 331.923193 -396.269382)
			(xy 331.948911 -396.329552) (xy 331.966319 -396.39263) (xy 331.975103 -396.457474) (xy 331.975104 -396.522909)
			(xy 331.966322 -396.587753) (xy 331.948916 -396.650831) (xy 331.923201 -396.711003) (xy 331.90688 -396.739364)
			(xy 331.903577 -396.745394) (xy 331.899964 -396.758654) (xy 331.899768 -396.765526) (xy 331.899768 -397.514826)
			(xy 331.899954 -397.5217) (xy 331.903567 -397.534962) (xy 331.90688 -397.540988) (xy 331.923169 -397.569367)
			(xy 331.948889 -397.629534) (xy 331.9663 -397.692609) (xy 331.975087 -397.75745) (xy 331.975092 -397.822884)
			(xy 331.966313 -397.887727) (xy 331.948911 -397.950804) (xy 331.923199 -398.010975) (xy 331.90688 -398.039336)
			(xy 331.903551 -398.045354) (xy 331.899955 -398.058623) (xy 331.899768 -398.065498) (xy 331.899768 -398.351502)
			(xy 331.899268 -398.361659) (xy 331.891494 -398.380427) (xy 331.877131 -398.394792) (xy 331.858363 -398.402568)
			(xy 331.848206 -398.403064) (xy 331.131926 -398.403064) (xy 331.121756 -398.402615) (xy 331.102963 -398.394839)
			(xy 331.088577 -398.380461) (xy 331.080791 -398.361671) (xy 331.080364 -398.351502) (xy 331.080364 -398.065498)
			(xy 331.080177 -398.058624) (xy 331.076566 -398.045361) (xy 331.073252 -398.039336) (xy 331.056897 -398.010993)
			(xy 331.031182 -397.950817) (xy 331.013777 -397.887735) (xy 331.004997 -397.822887) (xy 326.525636 -397.822887)
			(xy 326.525636 -398.890236) (xy 333.204312 -398.890236) (xy 333.20487 -398.857506) (xy 333.213728 -398.792648)
			(xy 333.23122 -398.729567) (xy 333.25703 -398.66941) (xy 333.2734 -398.641062) (xy 333.276728 -398.635044)
			(xy 333.280325 -398.621775) (xy 333.280512 -398.6149) (xy 333.280512 -397.865346) (xy 333.280301 -397.858474)
			(xy 333.276705 -397.845212) (xy 333.2734 -397.839184) (xy 333.257028 -397.810838) (xy 333.231228 -397.750677)
			(xy 333.21374 -397.687597) (xy 333.204881 -397.622739) (xy 333.204312 -397.59001) (xy 333.204858 -397.55728)
			(xy 333.21372 -397.492421) (xy 333.231216 -397.429341) (xy 333.257029 -397.369183) (xy 333.2734 -397.340836)
			(xy 333.276702 -397.334805) (xy 333.280316 -397.321546) (xy 333.280512 -397.314674) (xy 333.280512 -397.028924)
			(xy 333.280936 -397.018802) (xy 333.288678 -397.000096) (xy 333.302993 -396.985781) (xy 333.321698 -396.978037)
			(xy 333.33182 -396.977616) (xy 334.0481 -396.977616) (xy 334.058224 -396.978016) (xy 334.076931 -396.985768)
			(xy 334.091246 -397.000089) (xy 334.098988 -397.018799) (xy 334.099408 -397.028924) (xy 334.099408 -397.314674)
			(xy 334.099609 -397.321547) (xy 334.103211 -397.334809) (xy 334.10652 -397.340836) (xy 334.122902 -397.369176)
			(xy 334.148699 -397.429339) (xy 334.166184 -397.492421) (xy 334.17504 -397.55728) (xy 334.175608 -397.59001)
			(xy 334.175023 -397.622739) (xy 334.166173 -397.687596) (xy 334.148688 -397.750677) (xy 334.131753 -397.790162)
			(xy 335.40446 -397.790162) (xy 335.405036 -397.757433) (xy 335.41389 -397.692575) (xy 335.431377 -397.629495)
			(xy 335.457181 -397.569336) (xy 335.473548 -397.540988) (xy 335.476863 -397.534963) (xy 335.480469 -397.5217)
			(xy 335.48066 -397.514826) (xy 335.48066 -396.765526) (xy 335.480463 -396.758653) (xy 335.476859 -396.74539)
			(xy 335.473548 -396.739364) (xy 335.457173 -396.71102) (xy 335.431372 -396.650859) (xy 335.413885 -396.587778)
			(xy 335.405028 -396.52292) (xy 335.40446 -396.49019) (xy 335.405049 -396.457461) (xy 335.413899 -396.392604)
			(xy 335.431383 -396.329524) (xy 335.457183 -396.269365) (xy 335.473548 -396.241016) (xy 335.476853 -396.234986)
			(xy 335.480465 -396.221727) (xy 335.48066 -396.214854) (xy 335.48066 -395.92885) (xy 335.481168 -395.918724)
			(xy 335.488883 -395.9) (xy 335.503164 -395.885642) (xy 335.521845 -395.877824) (xy 335.531968 -395.877288)
			(xy 336.248248 -395.877288) (xy 336.258404 -395.877682) (xy 336.277155 -395.885491) (xy 336.291476 -395.899896)
			(xy 336.299176 -395.918692) (xy 336.299556 -395.92885) (xy 336.299556 -396.214854) (xy 336.299758 -396.221727)
			(xy 336.303359 -396.23499) (xy 336.306668 -396.241016) (xy 336.323037 -396.269363) (xy 336.348839 -396.329523)
			(xy 336.366327 -396.392603) (xy 336.375187 -396.457461) (xy 336.375756 -396.49019) (xy 336.375201 -396.52292)
			(xy 336.366341 -396.587778) (xy 336.348847 -396.650858) (xy 336.323038 -396.711016) (xy 336.306668 -396.739364)
			(xy 336.303364 -396.745394) (xy 336.299752 -396.758654) (xy 336.299556 -396.765526) (xy 336.299556 -397.514826)
			(xy 336.299731 -397.521701) (xy 336.30335 -397.534964) (xy 336.306668 -397.540988) (xy 336.316074 -397.557291)
			(xy 337.604968 -397.557291) (xy 337.613749 -397.492447) (xy 337.631154 -397.429369) (xy 337.656868 -397.369198)
			(xy 337.673188 -397.340836) (xy 337.676489 -397.334805) (xy 337.680104 -397.321546) (xy 337.6803 -397.314674)
			(xy 337.6803 -397.028924) (xy 337.680741 -397.018771) (xy 337.688529 -397.000019) (xy 337.70292 -396.985695)
			(xy 337.721708 -396.977995) (xy 337.731862 -396.977616) (xy 338.448142 -396.977616) (xy 338.458268 -396.978091)
			(xy 338.476986 -396.985829) (xy 338.49134 -397.000118) (xy 338.499162 -397.0188) (xy 338.499704 -397.028924)
			(xy 338.499704 -397.314674) (xy 338.499906 -397.321547) (xy 338.503507 -397.334809) (xy 338.506816 -397.340836)
			(xy 338.523148 -397.369192) (xy 338.548867 -397.429364) (xy 338.566276 -397.492444) (xy 338.575059 -397.55729)
			(xy 338.575058 -397.622728) (xy 338.566273 -397.687573) (xy 338.548862 -397.750652) (xy 338.52314 -397.810823)
			(xy 338.516196 -397.822887) (xy 339.805083 -397.822887) (xy 339.805088 -397.757448) (xy 339.813876 -397.692601)
			(xy 339.831289 -397.629521) (xy 339.857011 -397.569349) (xy 339.873336 -397.540988) (xy 339.87665 -397.534963)
			(xy 339.880257 -397.5217) (xy 339.880448 -397.514826) (xy 339.880448 -396.765526) (xy 339.880253 -396.758653)
			(xy 339.876647 -396.74539) (xy 339.873336 -396.739364) (xy 339.857005 -396.711007) (xy 339.831289 -396.650835)
			(xy 339.813882 -396.587755) (xy 339.805099 -396.52291) (xy 339.8051 -396.457473) (xy 339.813885 -396.392628)
			(xy 339.831294 -396.329549) (xy 339.857013 -396.269377) (xy 339.873336 -396.241016) (xy 339.87664 -396.234986)
			(xy 339.880253 -396.221727) (xy 339.880448 -396.214854) (xy 339.880448 -395.92885) (xy 339.880905 -395.91868)
			(xy 339.888675 -395.899885) (xy 339.903051 -395.885498) (xy 339.921841 -395.877713) (xy 339.93201 -395.877288)
			(xy 340.64829 -395.877288) (xy 340.658467 -395.877673) (xy 340.677271 -395.885464) (xy 340.691658 -395.899862)
			(xy 340.699435 -395.918672) (xy 340.699852 -395.92885) (xy 340.699852 -396.214854) (xy 340.700055 -396.221727)
			(xy 340.703655 -396.23499) (xy 340.706964 -396.241016) (xy 340.723278 -396.269382) (xy 340.748996 -396.329552)
			(xy 340.766405 -396.39263) (xy 340.775189 -396.457473) (xy 340.775191 -396.522909) (xy 340.766408 -396.587753)
			(xy 340.749002 -396.650832) (xy 340.723285 -396.711003) (xy 340.706964 -396.739364) (xy 340.703667 -396.745397)
			(xy 340.700049 -396.758654) (xy 340.699852 -396.765526) (xy 340.699852 -397.514826) (xy 340.700028 -397.521701)
			(xy 340.703646 -397.534964) (xy 340.706964 -397.540988) (xy 340.723254 -397.569367) (xy 340.748974 -397.629534)
			(xy 340.766386 -397.692609) (xy 340.775173 -397.75745) (xy 340.775178 -397.822884) (xy 340.766399 -397.887727)
			(xy 340.748996 -397.950804) (xy 340.723284 -398.010975) (xy 340.706964 -398.039336) (xy 340.703641 -398.045357)
			(xy 340.70004 -398.058623) (xy 340.699852 -398.065498) (xy 340.699852 -398.351502) (xy 340.699438 -398.361675)
			(xy 340.69165 -398.380472) (xy 340.677262 -398.394857) (xy 340.658463 -398.40264) (xy 340.64829 -398.403064)
			(xy 339.93201 -398.403064) (xy 339.921839 -398.402628) (xy 339.903045 -398.394847) (xy 339.88866 -398.380465)
			(xy 339.880874 -398.361673) (xy 339.880448 -398.351502) (xy 339.880448 -398.065498) (xy 339.880263 -398.058624)
			(xy 339.876651 -398.045361) (xy 339.873336 -398.039336) (xy 339.856982 -398.010992) (xy 339.831267 -397.950817)
			(xy 339.813863 -397.887735) (xy 339.805083 -397.822887) (xy 338.516196 -397.822887) (xy 338.506816 -397.839184)
			(xy 338.503508 -397.845212) (xy 338.499898 -397.858473) (xy 338.499704 -397.865346) (xy 338.499704 -398.6149)
			(xy 338.499895 -398.621773) (xy 338.503504 -398.635036) (xy 338.506816 -398.641062) (xy 338.52317 -398.669406)
			(xy 338.548887 -398.729581) (xy 338.566294 -398.792663) (xy 338.575074 -398.857511) (xy 338.575072 -398.890236)
			(xy 342.004396 -398.890236) (xy 342.004956 -398.857506) (xy 342.013814 -398.792648) (xy 342.031306 -398.729568)
			(xy 342.057115 -398.66941) (xy 342.073484 -398.641062) (xy 342.076811 -398.635043) (xy 342.080409 -398.621775)
			(xy 342.080596 -398.6149) (xy 342.080596 -397.865346) (xy 342.080387 -397.858474) (xy 342.07679 -397.845211)
			(xy 342.073484 -397.839184) (xy 342.057111 -397.810839) (xy 342.031311 -397.750678) (xy 342.013824 -397.687597)
			(xy 342.004965 -397.622739) (xy 342.004396 -397.59001) (xy 342.004944 -397.55728) (xy 342.013805 -397.492421)
			(xy 342.031301 -397.429341) (xy 342.057113 -397.369183) (xy 342.073484 -397.340836) (xy 342.076785 -397.334805)
			(xy 342.0804 -397.321546) (xy 342.080596 -397.314674) (xy 342.080596 -397.028924) (xy 342.081035 -397.018804)
			(xy 342.088775 -397.000101) (xy 342.103084 -396.985786) (xy 342.121784 -396.978039) (xy 342.131904 -396.977616)
			(xy 342.848184 -396.977616) (xy 342.858307 -396.978029) (xy 342.877014 -396.985775) (xy 342.891329 -397.000093)
			(xy 342.899072 -397.0188) (xy 342.899492 -397.028924) (xy 342.899492 -397.314674) (xy 342.899695 -397.321546)
			(xy 342.903296 -397.334809) (xy 342.906604 -397.340836) (xy 342.922984 -397.369177) (xy 342.948782 -397.42934)
			(xy 342.966268 -397.492422) (xy 342.975124 -397.55728) (xy 342.975692 -397.59001) (xy 342.975109 -397.622739)
			(xy 342.966259 -397.687597) (xy 342.948773 -397.750677) (xy 342.92297 -397.810835) (xy 342.916012 -397.822887)
			(xy 344.204873 -397.822887) (xy 344.204877 -397.757448) (xy 344.213665 -397.692601) (xy 344.231078 -397.629521)
			(xy 344.2568 -397.569349) (xy 344.273124 -397.540988) (xy 344.276445 -397.534966) (xy 344.280046 -397.5217)
			(xy 344.280236 -397.514826) (xy 344.280236 -396.765526) (xy 344.28003 -396.758654) (xy 344.276431 -396.745391)
			(xy 344.273124 -396.739364) (xy 344.256794 -396.711007) (xy 344.231078 -396.650835) (xy 344.213671 -396.587755)
			(xy 344.204889 -396.52291) (xy 344.20489 -396.457473) (xy 344.213675 -396.392628) (xy 344.231083 -396.329549)
			(xy 344.256802 -396.269377) (xy 344.273124 -396.241016) (xy 344.276435 -396.234989) (xy 344.280042 -396.221727)
			(xy 344.280236 -396.214854) (xy 344.280236 -395.92885) (xy 344.280705 -395.918682) (xy 344.288473 -395.899889)
			(xy 344.302845 -395.885502) (xy 344.32163 -395.877715) (xy 344.331798 -395.877288) (xy 345.048078 -395.877288)
			(xy 345.058254 -395.877683) (xy 345.077058 -395.88547) (xy 345.091445 -395.899866) (xy 345.099222 -395.918673)
			(xy 345.09964 -395.92885) (xy 345.09964 -396.214854) (xy 345.099844 -396.221726) (xy 345.103444 -396.234989)
			(xy 345.106752 -396.241016) (xy 345.123066 -396.269382) (xy 345.148785 -396.329552) (xy 345.166194 -396.39263)
			(xy 345.174979 -396.457473) (xy 345.174979 -396.49019) (xy 348.603832 -396.49019) (xy 348.607823 -396.428023)
			(xy 348.619732 -396.366876) (xy 348.639361 -396.307755) (xy 348.66639 -396.251629) (xy 348.700374 -396.19942)
			(xy 348.740756 -396.151985) (xy 348.786872 -396.110104) (xy 348.837964 -396.074464) (xy 348.893195 -396.04565)
			(xy 348.951657 -396.024136) (xy 349.012391 -396.010274) (xy 349.074398 -396.004292) (xy 349.136661 -396.006288)
			(xy 349.198158 -396.016231) (xy 349.257879 -396.033955) (xy 349.314842 -396.059172) (xy 349.322351 -396.063724)
			(xy 357.261158 -396.063724) (xy 357.265229 -396.008102) (xy 357.277355 -395.953665) (xy 357.297278 -395.901574)
			(xy 357.324574 -395.852939) (xy 357.35866 -395.808796) (xy 357.398809 -395.770087) (xy 357.444167 -395.737636)
			(xy 357.493767 -395.712135) (xy 357.546551 -395.694128) (xy 357.601394 -395.683998) (xy 357.657128 -395.681961)
			(xy 357.712565 -395.688061) (xy 357.766522 -395.702167) (xy 357.817851 -395.723979) (xy 357.865457 -395.753033)
			(xy 357.908325 -395.788708) (xy 357.945542 -395.830245) (xy 357.976315 -395.876758) (xy 357.999987 -395.927255)
			(xy 358.016055 -395.980662) (xy 358.024175 -396.035838) (xy 358.024684 -396.063724) (xy 358.024175 -396.09161)
			(xy 358.016055 -396.146786) (xy 357.999987 -396.200193) (xy 357.976315 -396.25069) (xy 357.945542 -396.297203)
			(xy 357.908325 -396.33874) (xy 357.865457 -396.374415) (xy 357.817851 -396.403469) (xy 357.766522 -396.425281)
			(xy 357.712565 -396.439387) (xy 357.657128 -396.445487) (xy 357.601394 -396.44345) (xy 357.546551 -396.43332)
			(xy 357.493767 -396.415313) (xy 357.444167 -396.389812) (xy 357.398809 -396.357361) (xy 357.35866 -396.318652)
			(xy 357.324574 -396.274509) (xy 357.297278 -396.225874) (xy 357.277355 -396.173783) (xy 357.265229 -396.119346)
			(xy 357.261158 -396.063724) (xy 349.322351 -396.063724) (xy 349.368113 -396.091465) (xy 349.416818 -396.130305)
			(xy 349.460155 -396.175055) (xy 349.497415 -396.224979) (xy 349.527984 -396.279258) (xy 349.551362 -396.337001)
			(xy 349.567163 -396.397259) (xy 349.575129 -396.459042) (xy 349.575628 -396.49019) (xy 349.575129 -396.521338)
			(xy 349.567163 -396.583121) (xy 349.551362 -396.643379) (xy 349.527984 -396.701122) (xy 349.497415 -396.755401)
			(xy 349.460155 -396.805325) (xy 349.416818 -396.850075) (xy 349.368113 -396.888915) (xy 349.314842 -396.921208)
			(xy 349.257879 -396.946425) (xy 349.198158 -396.964149) (xy 349.136661 -396.974092) (xy 349.074398 -396.976088)
			(xy 349.012391 -396.970106) (xy 348.951657 -396.956244) (xy 348.893195 -396.93473) (xy 348.837964 -396.905916)
			(xy 348.786872 -396.870276) (xy 348.740756 -396.828395) (xy 348.700374 -396.78096) (xy 348.66639 -396.728751)
			(xy 348.639361 -396.672625) (xy 348.619732 -396.613504) (xy 348.607823 -396.552357) (xy 348.603832 -396.49019)
			(xy 345.174979 -396.49019) (xy 345.17498 -396.522909) (xy 345.166198 -396.587754) (xy 345.148791 -396.650832)
			(xy 345.123074 -396.711003) (xy 345.106752 -396.739364) (xy 345.103454 -396.745397) (xy 345.099837 -396.758654)
			(xy 345.09964 -396.765526) (xy 345.09964 -397.514826) (xy 345.099817 -397.5217) (xy 345.103435 -397.534963)
			(xy 345.106752 -397.540988) (xy 345.11611 -397.55729) (xy 346.40504 -397.55729) (xy 346.413823 -397.492446)
			(xy 346.431231 -397.429368) (xy 346.456949 -397.369197) (xy 346.473272 -397.340836) (xy 346.476572 -397.334804)
			(xy 346.480187 -397.321546) (xy 346.480384 -397.314674) (xy 346.480384 -397.028924) (xy 346.480841 -397.018773)
			(xy 346.488625 -397.000025) (xy 346.503011 -396.985701) (xy 346.521794 -396.977997) (xy 346.531946 -396.977616)
			(xy 347.248226 -396.977616) (xy 347.258351 -396.978104) (xy 347.277069 -396.985836) (xy 347.291423 -397.000121)
			(xy 347.299246 -397.018801) (xy 347.299611 -397.025622) (xy 365.416844 -397.025622) (xy 365.420915 -396.97)
			(xy 365.433041 -396.915563) (xy 365.452964 -396.863472) (xy 365.48026 -396.814837) (xy 365.514346 -396.770694)
			(xy 365.554495 -396.731985) (xy 365.599853 -396.699534) (xy 365.649453 -396.674033) (xy 365.702237 -396.656026)
			(xy 365.75708 -396.645896) (xy 365.812814 -396.643859) (xy 365.868251 -396.649959) (xy 365.922208 -396.664065)
			(xy 365.973537 -396.685877) (xy 366.021143 -396.714931) (xy 366.064011 -396.750606) (xy 366.101048 -396.791942)
			(xy 366.335308 -396.791942) (xy 366.339379 -396.73632) (xy 366.351505 -396.681883) (xy 366.371428 -396.629792)
			(xy 366.398724 -396.581157) (xy 366.43281 -396.537014) (xy 366.472959 -396.498305) (xy 366.518317 -396.465854)
			(xy 366.567917 -396.440353) (xy 366.620701 -396.422346) (xy 366.675544 -396.412216) (xy 366.731278 -396.410179)
			(xy 366.786715 -396.416279) (xy 366.840672 -396.430385) (xy 366.892001 -396.452197) (xy 366.939607 -396.481251)
			(xy 366.982475 -396.516926) (xy 367.019692 -396.558463) (xy 367.050465 -396.604976) (xy 367.074137 -396.655473)
			(xy 367.090205 -396.70888) (xy 367.098325 -396.764056) (xy 367.098834 -396.791942) (xy 367.098325 -396.819828)
			(xy 367.090205 -396.875004) (xy 367.074137 -396.928411) (xy 367.050465 -396.978908) (xy 367.019692 -397.025421)
			(xy 366.982475 -397.066958) (xy 366.939607 -397.102633) (xy 366.892001 -397.131687) (xy 366.840672 -397.153499)
			(xy 366.786715 -397.167605) (xy 366.731278 -397.173705) (xy 366.675544 -397.171668) (xy 366.620701 -397.161538)
			(xy 366.567917 -397.143531) (xy 366.518317 -397.11803) (xy 366.472959 -397.085579) (xy 366.43281 -397.04687)
			(xy 366.398724 -397.002727) (xy 366.371428 -396.954092) (xy 366.351505 -396.902001) (xy 366.339379 -396.847564)
			(xy 366.335308 -396.791942) (xy 366.101048 -396.791942) (xy 366.101228 -396.792143) (xy 366.132001 -396.838656)
			(xy 366.155673 -396.889153) (xy 366.171741 -396.94256) (xy 366.179861 -396.997736) (xy 366.18037 -397.025622)
			(xy 366.179861 -397.053508) (xy 366.171741 -397.108684) (xy 366.155673 -397.162091) (xy 366.132001 -397.212588)
			(xy 366.101228 -397.259101) (xy 366.064011 -397.300638) (xy 366.021143 -397.336313) (xy 365.973537 -397.365367)
			(xy 365.922208 -397.387179) (xy 365.868251 -397.401285) (xy 365.812814 -397.407385) (xy 365.75708 -397.405348)
			(xy 365.702237 -397.395218) (xy 365.649453 -397.377211) (xy 365.599853 -397.35171) (xy 365.554495 -397.319259)
			(xy 365.514346 -397.28055) (xy 365.48026 -397.236407) (xy 365.452964 -397.187772) (xy 365.433041 -397.135681)
			(xy 365.420915 -397.081244) (xy 365.416844 -397.025622) (xy 347.299611 -397.025622) (xy 347.299788 -397.028924)
			(xy 347.299788 -397.314674) (xy 347.299991 -397.321546) (xy 347.303592 -397.334809) (xy 347.3069 -397.340836)
			(xy 347.323229 -397.369193) (xy 347.348944 -397.429366) (xy 347.36635 -397.492445) (xy 347.375132 -397.55729)
			(xy 347.375131 -397.622727) (xy 347.366347 -397.687572) (xy 347.348939 -397.750651) (xy 347.332052 -397.790162)
			(xy 348.603832 -397.790162) (xy 348.607823 -397.727995) (xy 348.619732 -397.666848) (xy 348.639361 -397.607727)
			(xy 348.66639 -397.551601) (xy 348.700374 -397.499392) (xy 348.740756 -397.451957) (xy 348.786872 -397.410076)
			(xy 348.837964 -397.374436) (xy 348.893195 -397.345622) (xy 348.951657 -397.324108) (xy 349.012391 -397.310246)
			(xy 349.074398 -397.304264) (xy 349.136661 -397.30626) (xy 349.198158 -397.316203) (xy 349.257879 -397.333927)
			(xy 349.314842 -397.359144) (xy 349.368113 -397.391437) (xy 349.416818 -397.430277) (xy 349.460155 -397.475027)
			(xy 349.497415 -397.524951) (xy 349.527984 -397.57923) (xy 349.532348 -397.59001) (xy 350.80398 -397.59001)
			(xy 350.807971 -397.527843) (xy 350.81988 -397.466696) (xy 350.839509 -397.407575) (xy 350.866538 -397.351449)
			(xy 350.900522 -397.29924) (xy 350.940904 -397.251805) (xy 350.98702 -397.209924) (xy 351.038112 -397.174284)
			(xy 351.093343 -397.14547) (xy 351.151805 -397.123956) (xy 351.212539 -397.110094) (xy 351.274546 -397.104112)
			(xy 351.336809 -397.106108) (xy 351.398306 -397.116051) (xy 351.458027 -397.133775) (xy 351.51499 -397.158992)
			(xy 351.568261 -397.191285) (xy 351.616966 -397.230125) (xy 351.660303 -397.274875) (xy 351.697563 -397.324799)
			(xy 351.728132 -397.379078) (xy 351.75151 -397.436821) (xy 351.767311 -397.497079) (xy 351.775277 -397.558862)
			(xy 351.775776 -397.59001) (xy 351.775277 -397.621158) (xy 351.767311 -397.682941) (xy 351.75151 -397.743199)
			(xy 351.728132 -397.800942) (xy 351.715773 -397.822887) (xy 375.004907 -397.822887) (xy 375.004912 -397.757448)
			(xy 375.0137 -397.692601) (xy 375.031114 -397.629521) (xy 375.056838 -397.569349) (xy 375.073164 -397.540988)
			(xy 375.07648 -397.534964) (xy 375.080085 -397.5217) (xy 375.080276 -397.514826) (xy 375.080276 -396.765526)
			(xy 375.080077 -396.758653) (xy 375.076474 -396.74539) (xy 375.073164 -396.739364) (xy 375.056833 -396.711008)
			(xy 375.031114 -396.650836) (xy 375.013706 -396.587756) (xy 375.004923 -396.52291) (xy 375.004924 -396.457473)
			(xy 375.01371 -396.392627) (xy 375.03112 -396.329548) (xy 375.05684 -396.269377) (xy 375.073164 -396.241016)
			(xy 375.07647 -396.234987) (xy 375.080082 -396.221727) (xy 375.080276 -396.214854) (xy 375.080276 -395.92885)
			(xy 375.080706 -395.918677) (xy 375.088481 -395.899876) (xy 375.102866 -395.885488) (xy 375.121665 -395.877708)
			(xy 375.131838 -395.877288) (xy 375.848118 -395.877288) (xy 375.858297 -395.87765) (xy 375.877102 -395.885451)
			(xy 375.891487 -395.899856) (xy 375.899263 -395.91867) (xy 375.89968 -395.92885) (xy 375.89968 -396.214854)
			(xy 375.899892 -396.221726) (xy 375.903487 -396.234988) (xy 375.906792 -396.241016) (xy 375.923105 -396.269382)
			(xy 375.948822 -396.329553) (xy 375.966229 -396.39263) (xy 375.975013 -396.457474) (xy 375.975015 -396.522909)
			(xy 375.966233 -396.587753) (xy 375.948827 -396.650831) (xy 375.923113 -396.711002) (xy 375.906792 -396.739364)
			(xy 375.903489 -396.745395) (xy 375.899876 -396.758654) (xy 375.89968 -396.765526) (xy 375.89968 -397.514826)
			(xy 375.899865 -397.5217) (xy 375.903478 -397.534962) (xy 375.906792 -397.540988) (xy 375.923081 -397.569367)
			(xy 375.9488 -397.629535) (xy 375.966211 -397.69261) (xy 375.974998 -397.757451) (xy 375.975002 -397.822884)
			(xy 375.966224 -397.887726) (xy 375.948822 -397.950804) (xy 375.923111 -398.010974) (xy 375.906792 -398.039336)
			(xy 375.903464 -398.045354) (xy 375.899867 -398.058623) (xy 375.89968 -398.065498) (xy 375.89968 -398.351502)
			(xy 375.899169 -398.361658) (xy 375.891397 -398.380423) (xy 375.877037 -398.394788) (xy 375.858274 -398.402565)
			(xy 375.848118 -398.403064) (xy 375.131838 -398.403064) (xy 375.121669 -398.402605) (xy 375.102876 -398.394833)
			(xy 375.08849 -398.380458) (xy 375.080703 -398.361671) (xy 375.080276 -398.351502) (xy 375.080276 -398.065498)
			(xy 375.080088 -398.058624) (xy 375.076477 -398.045362) (xy 375.073164 -398.039336) (xy 375.056809 -398.010993)
			(xy 375.031093 -397.950818) (xy 375.013687 -397.887735) (xy 375.004907 -397.822887) (xy 351.715773 -397.822887)
			(xy 351.697563 -397.855221) (xy 351.660303 -397.905145) (xy 351.616966 -397.949895) (xy 351.568261 -397.988735)
			(xy 351.51499 -398.021028) (xy 351.458027 -398.046245) (xy 351.398306 -398.063969) (xy 351.336809 -398.073912)
			(xy 351.274546 -398.075908) (xy 351.212539 -398.069926) (xy 351.151805 -398.056064) (xy 351.093343 -398.03455)
			(xy 351.038112 -398.005736) (xy 350.98702 -397.970096) (xy 350.940904 -397.928215) (xy 350.900522 -397.88078)
			(xy 350.866538 -397.828571) (xy 350.839509 -397.772445) (xy 350.81988 -397.713324) (xy 350.807971 -397.652177)
			(xy 350.80398 -397.59001) (xy 349.532348 -397.59001) (xy 349.551362 -397.636973) (xy 349.567163 -397.697231)
			(xy 349.575129 -397.759014) (xy 349.575628 -397.790162) (xy 349.575129 -397.82131) (xy 349.567163 -397.883093)
			(xy 349.551362 -397.943351) (xy 349.527984 -398.001094) (xy 349.497415 -398.055373) (xy 349.460155 -398.105297)
			(xy 349.416818 -398.150047) (xy 349.368113 -398.188887) (xy 349.314842 -398.22118) (xy 349.257879 -398.246397)
			(xy 349.198158 -398.264121) (xy 349.136661 -398.274064) (xy 349.074398 -398.27606) (xy 349.012391 -398.270078)
			(xy 348.951657 -398.256216) (xy 348.893195 -398.234702) (xy 348.837964 -398.205888) (xy 348.786872 -398.170248)
			(xy 348.740756 -398.128367) (xy 348.700374 -398.080932) (xy 348.66639 -398.028723) (xy 348.639361 -397.972597)
			(xy 348.619732 -397.913476) (xy 348.607823 -397.852329) (xy 348.603832 -397.790162) (xy 347.332052 -397.790162)
			(xy 347.323222 -397.810822) (xy 347.3069 -397.839184) (xy 347.303591 -397.845211) (xy 347.299982 -397.858473)
			(xy 347.299788 -397.865346) (xy 347.299788 -398.6149) (xy 347.299981 -398.621773) (xy 347.303589 -398.635036)
			(xy 347.3069 -398.641062) (xy 347.323252 -398.669407) (xy 347.348964 -398.729582) (xy 347.366368 -398.792664)
			(xy 347.375147 -398.857512) (xy 347.375144 -398.890236) (xy 350.80398 -398.890236) (xy 350.807971 -398.828069)
			(xy 350.81988 -398.766922) (xy 350.839509 -398.707801) (xy 350.866538 -398.651675) (xy 350.900522 -398.599466)
			(xy 350.940904 -398.552031) (xy 350.98702 -398.51015) (xy 351.038112 -398.47451) (xy 351.093343 -398.445696)
			(xy 351.151805 -398.424182) (xy 351.212539 -398.41032) (xy 351.274546 -398.404338) (xy 351.336809 -398.406334)
			(xy 351.398306 -398.416277) (xy 351.458027 -398.434001) (xy 351.481667 -398.444466) (xy 363.577884 -398.444466)
			(xy 363.581955 -398.388844) (xy 363.594081 -398.334407) (xy 363.614004 -398.282316) (xy 363.6413 -398.233681)
			(xy 363.675386 -398.189538) (xy 363.715535 -398.150829) (xy 363.760893 -398.118378) (xy 363.810493 -398.092877)
			(xy 363.863277 -398.07487) (xy 363.91812 -398.06474) (xy 363.973854 -398.062703) (xy 364.029291 -398.068803)
			(xy 364.083248 -398.082909) (xy 364.134577 -398.104721) (xy 364.182183 -398.133775) (xy 364.225051 -398.16945)
			(xy 364.262268 -398.210987) (xy 364.293041 -398.2575) (xy 364.316713 -398.307997) (xy 364.332781 -398.361404)
			(xy 364.340901 -398.41658) (xy 364.34141 -398.444466) (xy 364.340901 -398.472352) (xy 364.332781 -398.527528)
			(xy 364.316713 -398.580935) (xy 364.293041 -398.631432) (xy 364.262268 -398.677945) (xy 364.225051 -398.719482)
			(xy 364.182183 -398.755157) (xy 364.134577 -398.784211) (xy 364.083248 -398.806023) (xy 364.029291 -398.820129)
			(xy 363.973854 -398.826229) (xy 363.91812 -398.824192) (xy 363.863277 -398.814062) (xy 363.810493 -398.796055)
			(xy 363.760893 -398.770554) (xy 363.715535 -398.738103) (xy 363.675386 -398.699394) (xy 363.6413 -398.655251)
			(xy 363.614004 -398.606616) (xy 363.594081 -398.554525) (xy 363.581955 -398.500088) (xy 363.577884 -398.444466)
			(xy 351.481667 -398.444466) (xy 351.51499 -398.459218) (xy 351.568261 -398.491511) (xy 351.616966 -398.530351)
			(xy 351.660303 -398.575101) (xy 351.697563 -398.625025) (xy 351.728132 -398.679304) (xy 351.75151 -398.737047)
			(xy 351.767311 -398.797305) (xy 351.775277 -398.859088) (xy 351.775776 -398.890236) (xy 351.775277 -398.921384)
			(xy 351.767311 -398.983167) (xy 351.75151 -399.043425) (xy 351.728132 -399.101168) (xy 351.697563 -399.155447)
			(xy 351.660303 -399.205371) (xy 351.646206 -399.219928) (xy 357.060752 -399.219928) (xy 357.064823 -399.164306)
			(xy 357.076949 -399.109869) (xy 357.096872 -399.057778) (xy 357.124168 -399.009143) (xy 357.158254 -398.965)
			(xy 357.198403 -398.926291) (xy 357.243761 -398.89384) (xy 357.293361 -398.868339) (xy 357.346145 -398.850332)
			(xy 357.400988 -398.840202) (xy 357.456722 -398.838165) (xy 357.512159 -398.844265) (xy 357.566116 -398.858371)
			(xy 357.617445 -398.880183) (xy 357.633917 -398.890236) (xy 377.204224 -398.890236) (xy 377.20478 -398.857506)
			(xy 377.213638 -398.792647) (xy 377.231131 -398.729567) (xy 377.256942 -398.66941) (xy 377.273312 -398.641062)
			(xy 377.276641 -398.635044) (xy 377.280237 -398.621775) (xy 377.280424 -398.6149) (xy 377.280424 -397.865346)
			(xy 377.280212 -397.858474) (xy 377.276617 -397.845212) (xy 377.273312 -397.839184) (xy 377.256941 -397.810838)
			(xy 377.23114 -397.750677) (xy 377.213652 -397.687597) (xy 377.204793 -397.622739) (xy 377.204224 -397.59001)
			(xy 377.204769 -397.55728) (xy 377.21363 -397.492421) (xy 377.231127 -397.42934) (xy 377.25694 -397.369183)
			(xy 377.273312 -397.340836) (xy 377.276615 -397.334806) (xy 377.280228 -397.321546) (xy 377.280424 -397.314674)
			(xy 377.280424 -397.028924) (xy 377.280836 -397.0188) (xy 377.288581 -397.000092) (xy 377.302899 -396.985776)
			(xy 377.321608 -396.978034) (xy 377.331732 -396.977616) (xy 378.048012 -396.977616) (xy 378.058137 -396.978006)
			(xy 378.076844 -396.985761) (xy 378.091159 -397.000086) (xy 378.098901 -397.018798) (xy 378.09932 -397.028924)
			(xy 378.09932 -397.314674) (xy 378.09952 -397.321547) (xy 378.103122 -397.33481) (xy 378.106432 -397.340836)
			(xy 378.122805 -397.369181) (xy 378.148607 -397.429342) (xy 378.166095 -397.492422) (xy 378.174952 -397.557281)
			(xy 378.17552 -397.59001) (xy 378.174933 -397.622739) (xy 378.166083 -397.687596) (xy 378.148599 -397.750676)
			(xy 378.131664 -397.790162) (xy 379.404372 -397.790162) (xy 379.404947 -397.757433) (xy 379.413801 -397.692575)
			(xy 379.431288 -397.629495) (xy 379.457093 -397.569337) (xy 379.47346 -397.540988) (xy 379.476776 -397.534964)
			(xy 379.480381 -397.5217) (xy 379.480572 -397.514826) (xy 379.480572 -396.765526) (xy 379.480374 -396.758653)
			(xy 379.47677 -396.74539) (xy 379.47346 -396.739364) (xy 379.457086 -396.711019) (xy 379.431285 -396.650859)
			(xy 379.413797 -396.587778) (xy 379.40494 -396.522919) (xy 379.404372 -396.49019) (xy 379.40496 -396.457461)
			(xy 379.41381 -396.392604) (xy 379.431294 -396.329524) (xy 379.457095 -396.269365) (xy 379.47346 -396.241016)
			(xy 379.476766 -396.234987) (xy 379.480377 -396.221727) (xy 379.480572 -396.214854) (xy 379.480572 -395.92885)
			(xy 379.481069 -395.918723) (xy 379.488786 -395.899996) (xy 379.50307 -395.885637) (xy 379.521755 -395.877822)
			(xy 379.53188 -395.877288) (xy 380.24816 -395.877288) (xy 380.25831 -395.877754) (xy 380.277059 -395.885534)
			(xy 380.291384 -395.899917) (xy 380.299087 -395.918698) (xy 380.299468 -395.92885) (xy 380.299468 -396.214854)
			(xy 380.299681 -396.221726) (xy 380.303275 -396.234988) (xy 380.30658 -396.241016) (xy 380.32295 -396.269363)
			(xy 380.348751 -396.329523) (xy 380.36624 -396.392603) (xy 380.375099 -396.457461) (xy 380.375668 -396.49019)
			(xy 380.375111 -396.52292) (xy 380.366251 -396.587778) (xy 380.348758 -396.650858) (xy 380.322949 -396.711016)
			(xy 380.30658 -396.739364) (xy 380.303277 -396.745394) (xy 380.299664 -396.758654) (xy 380.299468 -396.765526)
			(xy 380.299468 -397.514826) (xy 380.299654 -397.5217) (xy 380.303267 -397.534962) (xy 380.30658 -397.540988)
			(xy 380.315986 -397.557291) (xy 381.604878 -397.557291) (xy 381.61366 -397.492447) (xy 381.631065 -397.429369)
			(xy 381.65678 -397.369198) (xy 381.6731 -397.340836) (xy 381.676402 -397.334805) (xy 381.680016 -397.321546)
			(xy 381.680212 -397.314674) (xy 381.680212 -397.028924) (xy 381.680641 -397.01877) (xy 381.688431 -397.000016)
			(xy 381.702826 -396.985691) (xy 381.721618 -396.977993) (xy 381.731774 -396.977616) (xy 382.448054 -396.977616)
			(xy 382.458175 -396.978164) (xy 382.47689 -396.985872) (xy 382.491247 -397.000139) (xy 382.499072 -397.018806)
			(xy 382.499616 -397.028924) (xy 382.499616 -397.314674) (xy 382.499816 -397.321547) (xy 382.503419 -397.334809)
			(xy 382.506728 -397.340836) (xy 382.52306 -397.369192) (xy 382.548778 -397.429364) (xy 382.566187 -397.492444)
			(xy 382.57497 -397.55729) (xy 382.574969 -397.622727) (xy 382.566183 -397.687573) (xy 382.548773 -397.750652)
			(xy 382.523052 -397.810823) (xy 382.516108 -397.822887) (xy 383.804994 -397.822887) (xy 383.804998 -397.757448)
			(xy 383.813786 -397.692601) (xy 383.8312 -397.629521) (xy 383.856923 -397.569349) (xy 383.873248 -397.540988)
			(xy 383.876563 -397.534963) (xy 383.880169 -397.5217) (xy 383.88036 -397.514826) (xy 383.88036 -396.765526)
			(xy 383.880163 -396.758653) (xy 383.876559 -396.74539) (xy 383.873248 -396.739364) (xy 383.856917 -396.711008)
			(xy 383.8312 -396.650835) (xy 383.813792 -396.587756) (xy 383.80501 -396.52291) (xy 383.805011 -396.457473)
			(xy 383.813796 -396.392628) (xy 383.831205 -396.329548) (xy 383.856925 -396.269377) (xy 383.873248 -396.241016)
			(xy 383.876553 -396.234986) (xy 383.880165 -396.221727) (xy 383.88036 -396.214854) (xy 383.88036 -395.92885)
			(xy 383.880805 -395.918679) (xy 383.888578 -395.899881) (xy 383.902958 -395.885494) (xy 383.921751 -395.877711)
			(xy 383.931922 -395.877288) (xy 384.648202 -395.877288) (xy 384.65838 -395.877663) (xy 384.677184 -395.885458)
			(xy 384.691571 -395.899859) (xy 384.699347 -395.918672) (xy 384.699764 -395.92885) (xy 384.699764 -396.214854)
			(xy 384.699978 -396.221726) (xy 384.703572 -396.234988) (xy 384.706876 -396.241016) (xy 384.723189 -396.269382)
			(xy 384.748907 -396.329552) (xy 384.766315 -396.39263) (xy 384.7751 -396.457474) (xy 384.775101 -396.522909)
			(xy 384.766319 -396.587753) (xy 384.748913 -396.650831) (xy 384.723197 -396.711003) (xy 384.706876 -396.739364)
			(xy 384.703572 -396.745394) (xy 384.69996 -396.758654) (xy 384.699764 -396.765526) (xy 384.699764 -397.514826)
			(xy 384.699951 -397.5217) (xy 384.703563 -397.534962) (xy 384.706876 -397.540988) (xy 384.723166 -397.569367)
			(xy 384.748885 -397.629534) (xy 384.766296 -397.692609) (xy 384.775084 -397.75745) (xy 384.775088 -397.822884)
			(xy 384.76631 -397.887727) (xy 384.748907 -397.950804) (xy 384.723195 -398.010975) (xy 384.706876 -398.039336)
			(xy 384.703547 -398.045353) (xy 384.699951 -398.058623) (xy 384.699764 -398.065498) (xy 384.699764 -398.351502)
			(xy 384.699268 -398.36166) (xy 384.691494 -398.380428) (xy 384.677128 -398.394794) (xy 384.65836 -398.402568)
			(xy 384.648202 -398.403064) (xy 383.931922 -398.403064) (xy 383.921752 -398.402618) (xy 383.902958 -398.394841)
			(xy 383.888573 -398.380462) (xy 383.880787 -398.361672) (xy 383.88036 -398.351502) (xy 383.88036 -398.065498)
			(xy 383.880174 -398.058624) (xy 383.876562 -398.045361) (xy 383.873248 -398.039336) (xy 383.856893 -398.010993)
			(xy 383.831178 -397.950817) (xy 383.813773 -397.887735) (xy 383.804994 -397.822887) (xy 382.516108 -397.822887)
			(xy 382.506728 -397.839184) (xy 382.503421 -397.845212) (xy 382.49981 -397.858473) (xy 382.499616 -397.865346)
			(xy 382.499616 -398.6149) (xy 382.499806 -398.621773) (xy 382.503416 -398.635036) (xy 382.506728 -398.641062)
			(xy 382.523082 -398.669406) (xy 382.548798 -398.729581) (xy 382.566204 -398.792663) (xy 382.574985 -398.857511)
			(xy 382.574982 -398.890236) (xy 386.004308 -398.890236) (xy 386.004867 -398.857506) (xy 386.013724 -398.792648)
			(xy 386.031217 -398.729568) (xy 386.057026 -398.66941) (xy 386.073396 -398.641062) (xy 386.076724 -398.635044)
			(xy 386.080321 -398.621775) (xy 386.080508 -398.6149) (xy 386.080508 -397.865346) (xy 386.080297 -397.858474)
			(xy 386.076702 -397.845211) (xy 386.073396 -397.839184) (xy 386.057024 -397.810838) (xy 386.031224 -397.750678)
			(xy 386.013736 -397.687597) (xy 386.004877 -397.622739) (xy 386.004308 -397.59001) (xy 386.004855 -397.55728)
			(xy 386.013716 -397.492421) (xy 386.031212 -397.429341) (xy 386.057025 -397.369183) (xy 386.073396 -397.340836)
			(xy 386.076698 -397.334805) (xy 386.080312 -397.321546) (xy 386.080508 -397.314674) (xy 386.080508 -397.028924)
			(xy 386.080936 -397.018802) (xy 386.088677 -397.000097) (xy 386.102991 -396.985782) (xy 386.121694 -396.978037)
			(xy 386.131816 -396.977616) (xy 386.848096 -396.977616) (xy 386.85822 -396.97802) (xy 386.876927 -396.985769)
			(xy 386.891242 -397.00009) (xy 386.898984 -397.0188) (xy 386.899404 -397.028924) (xy 386.899404 -397.314674)
			(xy 386.899606 -397.321547) (xy 386.903207 -397.334809) (xy 386.906516 -397.340836) (xy 386.922897 -397.369176)
			(xy 386.948695 -397.429339) (xy 386.96618 -397.492421) (xy 386.975036 -397.55728) (xy 386.975604 -397.59001)
			(xy 386.97502 -397.622739) (xy 386.966169 -397.687596) (xy 386.948684 -397.750677) (xy 386.922882 -397.810835)
			(xy 386.915924 -397.822887) (xy 388.204783 -397.822887) (xy 388.204788 -397.757448) (xy 388.213576 -397.692601)
			(xy 388.230989 -397.629521) (xy 388.256711 -397.569349) (xy 388.273036 -397.540988) (xy 388.27635 -397.534963)
			(xy 388.279957 -397.5217) (xy 388.280148 -397.514826) (xy 388.280148 -396.765526) (xy 388.279953 -396.758653)
			(xy 388.276347 -396.74539) (xy 388.273036 -396.739364) (xy 388.256705 -396.711007) (xy 388.230989 -396.650835)
			(xy 388.213582 -396.587755) (xy 388.204799 -396.52291) (xy 388.2048 -396.457473) (xy 388.213585 -396.392628)
			(xy 388.230994 -396.329549) (xy 388.256713 -396.269377) (xy 388.273036 -396.241016) (xy 388.27634 -396.234986)
			(xy 388.279953 -396.221727) (xy 388.280148 -396.214854) (xy 388.280148 -395.92885) (xy 388.280605 -395.91868)
			(xy 388.288375 -395.899885) (xy 388.302751 -395.885498) (xy 388.321541 -395.877713) (xy 388.33171 -395.877288)
			(xy 389.04799 -395.877288) (xy 389.058167 -395.877673) (xy 389.076971 -395.885464) (xy 389.091358 -395.899862)
			(xy 389.099135 -395.918672) (xy 389.099552 -395.92885) (xy 389.099552 -396.214854) (xy 389.099755 -396.221727)
			(xy 389.103355 -396.23499) (xy 389.106664 -396.241016) (xy 389.122978 -396.269382) (xy 389.148696 -396.329552)
			(xy 389.166105 -396.39263) (xy 389.174889 -396.457473) (xy 389.17489 -396.49019) (xy 392.603744 -396.49019)
			(xy 392.607735 -396.428023) (xy 392.619644 -396.366876) (xy 392.639273 -396.307755) (xy 392.666302 -396.251629)
			(xy 392.700286 -396.19942) (xy 392.740668 -396.151985) (xy 392.786784 -396.110104) (xy 392.837876 -396.074464)
			(xy 392.893107 -396.04565) (xy 392.951569 -396.024136) (xy 393.012303 -396.010274) (xy 393.07431 -396.004292)
			(xy 393.136573 -396.006288) (xy 393.19807 -396.016231) (xy 393.257791 -396.033955) (xy 393.314754 -396.059172)
			(xy 393.368025 -396.091465) (xy 393.41673 -396.130305) (xy 393.460067 -396.175055) (xy 393.497327 -396.224979)
			(xy 393.527896 -396.279258) (xy 393.551274 -396.337001) (xy 393.567075 -396.397259) (xy 393.575041 -396.459042)
			(xy 393.57554 -396.49019) (xy 393.575041 -396.521338) (xy 393.567075 -396.583121) (xy 393.551274 -396.643379)
			(xy 393.527896 -396.701122) (xy 393.497327 -396.755401) (xy 393.460067 -396.805325) (xy 393.41673 -396.850075)
			(xy 393.368025 -396.888915) (xy 393.314754 -396.921208) (xy 393.257791 -396.946425) (xy 393.19807 -396.964149)
			(xy 393.136573 -396.974092) (xy 393.07431 -396.976088) (xy 393.012303 -396.970106) (xy 392.951569 -396.956244)
			(xy 392.893107 -396.93473) (xy 392.837876 -396.905916) (xy 392.786784 -396.870276) (xy 392.740668 -396.828395)
			(xy 392.700286 -396.78096) (xy 392.666302 -396.728751) (xy 392.639273 -396.672625) (xy 392.619644 -396.613504)
			(xy 392.607735 -396.552357) (xy 392.603744 -396.49019) (xy 389.17489 -396.49019) (xy 389.174891 -396.522909)
			(xy 389.166108 -396.587753) (xy 389.148702 -396.650832) (xy 389.122985 -396.711003) (xy 389.106664 -396.739364)
			(xy 389.103367 -396.745397) (xy 389.099749 -396.758654) (xy 389.099552 -396.765526) (xy 389.099552 -397.514826)
			(xy 389.099728 -397.521701) (xy 389.103346 -397.534964) (xy 389.106664 -397.540988) (xy 389.116022 -397.55729)
			(xy 390.404951 -397.55729) (xy 390.413734 -397.492446) (xy 390.431142 -397.429367) (xy 390.456861 -397.369197)
			(xy 390.473184 -397.340836) (xy 390.476485 -397.334805) (xy 390.4801 -397.321546) (xy 390.480296 -397.314674)
			(xy 390.480296 -397.028924) (xy 390.480741 -397.018772) (xy 390.488528 -397.000021) (xy 390.502918 -396.985697)
			(xy 390.521704 -396.977995) (xy 390.531858 -396.977616) (xy 391.248138 -396.977616) (xy 391.258264 -396.978095)
			(xy 391.276982 -396.985831) (xy 391.291336 -397.000119) (xy 391.299158 -397.0188) (xy 391.2997 -397.028924)
			(xy 391.2997 -397.314674) (xy 391.299902 -397.321546) (xy 391.303504 -397.334809) (xy 391.306812 -397.340836)
			(xy 391.323141 -397.369193) (xy 391.348855 -397.429366) (xy 391.366261 -397.492445) (xy 391.375042 -397.55729)
			(xy 391.375041 -397.622727) (xy 391.366257 -397.687571) (xy 391.34885 -397.75065) (xy 391.331963 -397.790162)
			(xy 392.603744 -397.790162) (xy 392.607735 -397.727995) (xy 392.619644 -397.666848) (xy 392.639273 -397.607727)
			(xy 392.666302 -397.551601) (xy 392.700286 -397.499392) (xy 392.740668 -397.451957) (xy 392.786784 -397.410076)
			(xy 392.837876 -397.374436) (xy 392.893107 -397.345622) (xy 392.951569 -397.324108) (xy 393.012303 -397.310246)
			(xy 393.07431 -397.304264) (xy 393.136573 -397.30626) (xy 393.19807 -397.316203) (xy 393.257791 -397.333927)
			(xy 393.314754 -397.359144) (xy 393.368025 -397.391437) (xy 393.41673 -397.430277) (xy 393.460067 -397.475027)
			(xy 393.497327 -397.524951) (xy 393.527896 -397.57923) (xy 393.53226 -397.59001) (xy 394.803892 -397.59001)
			(xy 394.807883 -397.527843) (xy 394.819792 -397.466696) (xy 394.839421 -397.407575) (xy 394.86645 -397.351449)
			(xy 394.900434 -397.29924) (xy 394.940816 -397.251805) (xy 394.986932 -397.209924) (xy 395.038024 -397.174284)
			(xy 395.093255 -397.14547) (xy 395.151717 -397.123956) (xy 395.212451 -397.110094) (xy 395.274458 -397.104112)
			(xy 395.336721 -397.106108) (xy 395.398218 -397.116051) (xy 395.457939 -397.133775) (xy 395.514902 -397.158992)
			(xy 395.568173 -397.191285) (xy 395.616878 -397.230125) (xy 395.660215 -397.274875) (xy 395.697475 -397.324799)
			(xy 395.728044 -397.379078) (xy 395.751422 -397.436821) (xy 395.767223 -397.497079) (xy 395.775189 -397.558862)
			(xy 395.775688 -397.59001) (xy 395.775189 -397.621158) (xy 395.767223 -397.682941) (xy 395.751422 -397.743199)
			(xy 395.728044 -397.800942) (xy 395.697475 -397.855221) (xy 395.660215 -397.905145) (xy 395.616878 -397.949895)
			(xy 395.568173 -397.988735) (xy 395.514902 -398.021028) (xy 395.457939 -398.046245) (xy 395.398218 -398.063969)
			(xy 395.336721 -398.073912) (xy 395.274458 -398.075908) (xy 395.212451 -398.069926) (xy 395.151717 -398.056064)
			(xy 395.093255 -398.03455) (xy 395.038024 -398.005736) (xy 394.986932 -397.970096) (xy 394.940816 -397.928215)
			(xy 394.900434 -397.88078) (xy 394.86645 -397.828571) (xy 394.839421 -397.772445) (xy 394.819792 -397.713324)
			(xy 394.807883 -397.652177) (xy 394.803892 -397.59001) (xy 393.53226 -397.59001) (xy 393.551274 -397.636973)
			(xy 393.567075 -397.697231) (xy 393.575041 -397.759014) (xy 393.57554 -397.790162) (xy 393.575041 -397.82131)
			(xy 393.567075 -397.883093) (xy 393.551274 -397.943351) (xy 393.527896 -398.001094) (xy 393.497327 -398.055373)
			(xy 393.460067 -398.105297) (xy 393.41673 -398.150047) (xy 393.368025 -398.188887) (xy 393.314754 -398.22118)
			(xy 393.257791 -398.246397) (xy 393.19807 -398.264121) (xy 393.136573 -398.274064) (xy 393.07431 -398.27606)
			(xy 393.012303 -398.270078) (xy 392.951569 -398.256216) (xy 392.893107 -398.234702) (xy 392.837876 -398.205888)
			(xy 392.786784 -398.170248) (xy 392.740668 -398.128367) (xy 392.700286 -398.080932) (xy 392.666302 -398.028723)
			(xy 392.639273 -397.972597) (xy 392.619644 -397.913476) (xy 392.607735 -397.852329) (xy 392.603744 -397.790162)
			(xy 391.331963 -397.790162) (xy 391.323133 -397.810822) (xy 391.306812 -397.839184) (xy 391.303504 -397.845212)
			(xy 391.299894 -397.858473) (xy 391.2997 -397.865346) (xy 391.2997 -398.6149) (xy 391.299892 -398.621773)
			(xy 391.3035 -398.635036) (xy 391.306812 -398.641062) (xy 391.323163 -398.669407) (xy 391.348875 -398.729583)
			(xy 391.366278 -398.792665) (xy 391.375057 -398.857512) (xy 391.375055 -398.890236) (xy 394.803892 -398.890236)
			(xy 394.807883 -398.828069) (xy 394.819792 -398.766922) (xy 394.839421 -398.707801) (xy 394.86645 -398.651675)
			(xy 394.900434 -398.599466) (xy 394.940816 -398.552031) (xy 394.986932 -398.51015) (xy 395.038024 -398.47451)
			(xy 395.093255 -398.445696) (xy 395.151717 -398.424182) (xy 395.212451 -398.41032) (xy 395.274458 -398.404338)
			(xy 395.336721 -398.406334) (xy 395.398218 -398.416277) (xy 395.457939 -398.434001) (xy 395.514902 -398.459218)
			(xy 395.568173 -398.491511) (xy 395.616878 -398.530351) (xy 395.660215 -398.575101) (xy 395.697475 -398.625025)
			(xy 395.728044 -398.679304) (xy 395.751422 -398.737047) (xy 395.767223 -398.797305) (xy 395.775189 -398.859088)
			(xy 395.775688 -398.890236) (xy 395.775189 -398.921384) (xy 395.767223 -398.983167) (xy 395.751422 -399.043425)
			(xy 395.728044 -399.101168) (xy 395.697475 -399.155447) (xy 395.660215 -399.205371) (xy 395.616878 -399.250121)
			(xy 395.568173 -399.288961) (xy 395.514902 -399.321254) (xy 395.457939 -399.346471) (xy 395.398218 -399.364195)
			(xy 395.336721 -399.374138) (xy 395.274458 -399.376134) (xy 395.212451 -399.370152) (xy 395.151717 -399.35629)
			(xy 395.093255 -399.334776) (xy 395.038024 -399.305962) (xy 394.986932 -399.270322) (xy 394.940816 -399.228441)
			(xy 394.900434 -399.181006) (xy 394.86645 -399.128797) (xy 394.839421 -399.072671) (xy 394.819792 -399.01355)
			(xy 394.807883 -398.952403) (xy 394.803892 -398.890236) (xy 391.375055 -398.890236) (xy 391.375053 -398.92295)
			(xy 391.366266 -398.987796) (xy 391.348855 -399.050876) (xy 391.323135 -399.111048) (xy 391.306812 -399.13941)
			(xy 391.303495 -399.145433) (xy 391.29989 -399.158698) (xy 391.2997 -399.165572) (xy 391.2997 -399.451576)
			(xy 391.299259 -399.461729) (xy 391.291471 -399.480481) (xy 391.27708 -399.494805) (xy 391.258292 -399.502505)
			(xy 391.248138 -399.502884) (xy 390.531858 -399.502884) (xy 390.521732 -399.502409) (xy 390.503014 -399.494671)
			(xy 390.48866 -399.480382) (xy 390.480838 -399.4617) (xy 390.480296 -399.451576) (xy 390.480296 -399.165572)
			(xy 390.480115 -399.158698) (xy 390.4765 -399.145435) (xy 390.473184 -399.13941) (xy 390.456891 -399.111032)
			(xy 390.431168 -399.050866) (xy 390.413755 -398.98779) (xy 390.404967 -398.922948) (xy 390.404963 -398.857513)
			(xy 390.413743 -398.79267) (xy 390.431148 -398.729593) (xy 390.456863 -398.669423) (xy 390.473184 -398.641062)
			(xy 390.476511 -398.635043) (xy 390.480109 -398.621775) (xy 390.480296 -398.6149) (xy 390.480296 -397.865346)
			(xy 390.480087 -397.858474) (xy 390.47649 -397.845211) (xy 390.473184 -397.839184) (xy 390.456869 -397.810819)
			(xy 390.431148 -397.750649) (xy 390.413737 -397.687571) (xy 390.404952 -397.622727) (xy 390.404951 -397.55729)
			(xy 389.116022 -397.55729) (xy 389.122954 -397.569367) (xy 389.148674 -397.629534) (xy 389.166086 -397.692609)
			(xy 389.174873 -397.75745) (xy 389.174878 -397.822884) (xy 389.166099 -397.887727) (xy 389.148696 -397.950804)
			(xy 389.122984 -398.010975) (xy 389.106664 -398.039336) (xy 389.103341 -398.045357) (xy 389.09974 -398.058623)
			(xy 389.099552 -398.065498) (xy 389.099552 -398.351502) (xy 389.099138 -398.361675) (xy 389.09135 -398.380472)
			(xy 389.076962 -398.394857) (xy 389.058163 -398.40264) (xy 389.04799 -398.403064) (xy 388.33171 -398.403064)
			(xy 388.321539 -398.402628) (xy 388.302745 -398.394847) (xy 388.28836 -398.380465) (xy 388.280574 -398.361673)
			(xy 388.280148 -398.351502) (xy 388.280148 -398.065498) (xy 388.279963 -398.058624) (xy 388.276351 -398.045361)
			(xy 388.273036 -398.039336) (xy 388.256682 -398.010992) (xy 388.230967 -397.950817) (xy 388.213563 -397.887735)
			(xy 388.204783 -397.822887) (xy 386.915924 -397.822887) (xy 386.906516 -397.839184) (xy 386.903208 -397.845212)
			(xy 386.899598 -397.858473) (xy 386.899404 -397.865346) (xy 386.899404 -398.6149) (xy 386.899595 -398.621773)
			(xy 386.903204 -398.635036) (xy 386.906516 -398.641062) (xy 386.922868 -398.669419) (xy 386.948673 -398.729576)
			(xy 386.966166 -398.792653) (xy 386.975031 -398.857508) (xy 386.975604 -398.890236) (xy 386.975031 -398.922965)
			(xy 386.966177 -398.987823) (xy 386.948689 -399.050903) (xy 386.922884 -399.111062) (xy 386.906516 -399.13941)
			(xy 386.903199 -399.145433) (xy 386.899594 -399.158698) (xy 386.899404 -399.165572) (xy 386.899404 -399.451576)
			(xy 386.898965 -399.461696) (xy 386.891225 -399.480399) (xy 386.876916 -399.494714) (xy 386.858216 -399.502461)
			(xy 386.848096 -399.502884) (xy 386.131816 -399.502884) (xy 386.121693 -399.502471) (xy 386.102986 -399.494725)
			(xy 386.088671 -399.480407) (xy 386.080928 -399.4617) (xy 386.080508 -399.451576) (xy 386.080508 -399.165572)
			(xy 386.080326 -399.158698) (xy 386.076711 -399.145435) (xy 386.073396 -399.13941) (xy 386.057034 -399.111059)
			(xy 386.031231 -399.0509) (xy 386.013741 -398.987821) (xy 386.004879 -398.922965) (xy 386.004308 -398.890236)
			(xy 382.574982 -398.890236) (xy 382.57498 -398.922951) (xy 382.566192 -398.987797) (xy 382.548778 -399.050878)
			(xy 382.523054 -399.111049) (xy 382.506728 -399.13941) (xy 382.503412 -399.145434) (xy 382.499807 -399.158698)
			(xy 382.499616 -399.165572) (xy 382.499616 -399.451576) (xy 382.499159 -399.461727) (xy 382.491375 -399.480475)
			(xy 382.476989 -399.494799) (xy 382.458206 -399.502503) (xy 382.448054 -399.502884) (xy 381.731774 -399.502884)
			(xy 381.721649 -399.502396) (xy 381.702931 -399.494664) (xy 381.688577 -399.480379) (xy 381.680754 -399.461699)
			(xy 381.680212 -399.451576) (xy 381.680212 -399.165572) (xy 381.680029 -399.158698) (xy 381.676415 -399.145435)
			(xy 381.6731 -399.13941) (xy 381.656809 -399.111032) (xy 381.631091 -399.050864) (xy 381.613681 -398.987789)
			(xy 381.604894 -398.922948) (xy 381.60489 -398.857514) (xy 381.613669 -398.792672) (xy 381.631071 -398.729594)
			(xy 381.656781 -398.669424) (xy 381.6731 -398.641062) (xy 381.676428 -398.635044) (xy 381.680025 -398.621775)
			(xy 381.680212 -398.6149) (xy 381.680212 -397.865346) (xy 381.680001 -397.858474) (xy 381.676405 -397.845212)
			(xy 381.6731 -397.839184) (xy 381.656787 -397.810818) (xy 381.631071 -397.750647) (xy 381.613663 -397.68757)
			(xy 381.60488 -397.622726) (xy 381.604878 -397.557291) (xy 380.315986 -397.557291) (xy 380.322939 -397.569341)
			(xy 380.348743 -397.629499) (xy 380.366234 -397.692577) (xy 380.375097 -397.757433) (xy 380.375668 -397.790162)
			(xy 380.375098 -397.822891) (xy 380.366242 -397.887749) (xy 380.348753 -397.950829) (xy 380.322948 -398.010988)
			(xy 380.30658 -398.039336) (xy 380.303251 -398.045354) (xy 380.299655 -398.058623) (xy 380.299468 -398.065498)
			(xy 380.299468 -398.351502) (xy 380.298975 -398.361628) (xy 380.291248 -398.380347) (xy 380.276964 -398.394703)
			(xy 380.258283 -398.402524) (xy 380.24816 -398.403064) (xy 379.53188 -398.403064) (xy 379.52172 -398.402694)
			(xy 379.50296 -398.394885) (xy 379.488636 -398.380472) (xy 379.480944 -398.361664) (xy 379.480572 -398.351502)
			(xy 379.480572 -398.065498) (xy 379.480384 -398.058624) (xy 379.476773 -398.045362) (xy 379.47346 -398.039336)
			(xy 379.457114 -398.010976) (xy 379.431306 -397.950821) (xy 379.413811 -397.887744) (xy 379.404945 -397.82289)
			(xy 379.404372 -397.790162) (xy 378.131664 -397.790162) (xy 378.122798 -397.810835) (xy 378.106432 -397.839184)
			(xy 378.103126 -397.845213) (xy 378.099514 -397.858473) (xy 378.09932 -397.865346) (xy 378.09932 -398.6149)
			(xy 378.09951 -398.621773) (xy 378.103119 -398.635036) (xy 378.106432 -398.641062) (xy 378.122776 -398.669423)
			(xy 378.148585 -398.729578) (xy 378.166081 -398.792654) (xy 378.174947 -398.857508) (xy 378.17552 -398.890236)
			(xy 378.174945 -398.922965) (xy 378.166092 -398.987823) (xy 378.148604 -399.050903) (xy 378.122799 -399.111061)
			(xy 378.106432 -399.13941) (xy 378.103116 -399.145434) (xy 378.099511 -399.158698) (xy 378.09932 -399.165572)
			(xy 378.09932 -399.451576) (xy 378.098865 -399.461694) (xy 378.091128 -399.480394) (xy 378.076824 -399.494708)
			(xy 378.05813 -399.502458) (xy 378.048012 -399.502884) (xy 377.331732 -399.502884) (xy 377.32161 -399.502458)
			(xy 377.302903 -399.494717) (xy 377.288587 -399.480403) (xy 377.280844 -399.461698) (xy 377.280424 -399.451576)
			(xy 377.280424 -399.165572) (xy 377.28024 -399.158698) (xy 377.276626 -399.145436) (xy 377.273312 -399.13941)
			(xy 377.256952 -399.111058) (xy 377.231148 -399.0509) (xy 377.213657 -398.987821) (xy 377.204795 -398.922965)
			(xy 377.204224 -398.890236) (xy 357.633917 -398.890236) (xy 357.665051 -398.909237) (xy 357.707919 -398.944912)
			(xy 357.745136 -398.986449) (xy 357.775909 -399.032962) (xy 357.799581 -399.083459) (xy 357.815649 -399.136866)
			(xy 357.823769 -399.192042) (xy 357.824278 -399.219928) (xy 357.823769 -399.247814) (xy 357.815649 -399.30299)
			(xy 357.799581 -399.356397) (xy 357.775909 -399.406894) (xy 357.745136 -399.453407) (xy 357.707919 -399.494944)
			(xy 357.665051 -399.530619) (xy 357.617445 -399.559673) (xy 357.566116 -399.581485) (xy 357.512159 -399.595591)
			(xy 357.456722 -399.601691) (xy 357.400988 -399.599654) (xy 357.346145 -399.589524) (xy 357.293361 -399.571517)
			(xy 357.243761 -399.546016) (xy 357.198403 -399.513565) (xy 357.158254 -399.474856) (xy 357.124168 -399.430713)
			(xy 357.096872 -399.382078) (xy 357.076949 -399.329987) (xy 357.064823 -399.27555) (xy 357.060752 -399.219928)
			(xy 351.646206 -399.219928) (xy 351.616966 -399.250121) (xy 351.568261 -399.288961) (xy 351.51499 -399.321254)
			(xy 351.458027 -399.346471) (xy 351.398306 -399.364195) (xy 351.336809 -399.374138) (xy 351.274546 -399.376134)
			(xy 351.212539 -399.370152) (xy 351.151805 -399.35629) (xy 351.093343 -399.334776) (xy 351.038112 -399.305962)
			(xy 350.98702 -399.270322) (xy 350.940904 -399.228441) (xy 350.900522 -399.181006) (xy 350.866538 -399.128797)
			(xy 350.839509 -399.072671) (xy 350.81988 -399.01355) (xy 350.807971 -398.952403) (xy 350.80398 -398.890236)
			(xy 347.375144 -398.890236) (xy 347.375142 -398.92295) (xy 347.366355 -398.987796) (xy 347.348944 -399.050876)
			(xy 347.323223 -399.111048) (xy 347.3069 -399.13941) (xy 347.303582 -399.145433) (xy 347.299978 -399.158698)
			(xy 347.299788 -399.165572) (xy 347.299788 -399.451576) (xy 347.299359 -399.46173) (xy 347.291569 -399.480484)
			(xy 347.277174 -399.494809) (xy 347.258382 -399.502507) (xy 347.248226 -399.502884) (xy 346.531946 -399.502884)
			(xy 346.521825 -399.502336) (xy 346.50311 -399.494628) (xy 346.488753 -399.480361) (xy 346.480928 -399.461694)
			(xy 346.480384 -399.451576) (xy 346.480384 -399.165572) (xy 346.480205 -399.158698) (xy 346.476588 -399.145435)
			(xy 346.473272 -399.13941) (xy 346.456979 -399.111032) (xy 346.431257 -399.050865) (xy 346.413844 -398.98779)
			(xy 346.405056 -398.922948) (xy 346.405052 -398.857514) (xy 346.413832 -398.792671) (xy 346.431237 -398.729593)
			(xy 346.456951 -398.669423) (xy 346.473272 -398.641062) (xy 346.476598 -398.635043) (xy 346.480197 -398.621775)
			(xy 346.480384 -398.6149) (xy 346.480384 -397.865346) (xy 346.480176 -397.858474) (xy 346.476579 -397.845211)
			(xy 346.473272 -397.839184) (xy 346.456957 -397.810818) (xy 346.431237 -397.750649) (xy 346.413827 -397.687571)
			(xy 346.405042 -397.622727) (xy 346.40504 -397.55729) (xy 345.11611 -397.55729) (xy 345.123042 -397.569367)
			(xy 345.148763 -397.629534) (xy 345.166175 -397.692609) (xy 345.174963 -397.75745) (xy 345.174967 -397.822885)
			(xy 345.166188 -397.887727) (xy 345.148785 -397.950804) (xy 345.123072 -398.010975) (xy 345.106752 -398.039336)
			(xy 345.103429 -398.045356) (xy 345.099828 -398.058623) (xy 345.09964 -398.065498) (xy 345.09964 -398.351502)
			(xy 345.099237 -398.361676) (xy 345.091447 -398.380475) (xy 345.077055 -398.394861) (xy 345.058253 -398.402642)
			(xy 345.048078 -398.403064) (xy 344.331798 -398.403064) (xy 344.32164 -398.402568) (xy 344.302872 -398.394794)
			(xy 344.288506 -398.380428) (xy 344.280732 -398.36166) (xy 344.280236 -398.351502) (xy 344.280236 -398.065498)
			(xy 344.28004 -398.058625) (xy 344.276434 -398.045362) (xy 344.273124 -398.039336) (xy 344.25677 -398.010992)
			(xy 344.231056 -397.950817) (xy 344.213652 -397.887735) (xy 344.204873 -397.822887) (xy 342.916012 -397.822887)
			(xy 342.906604 -397.839184) (xy 342.903295 -397.845212) (xy 342.899686 -397.858473) (xy 342.899492 -397.865346)
			(xy 342.899492 -398.6149) (xy 342.899685 -398.621773) (xy 342.903292 -398.635036) (xy 342.906604 -398.641062)
			(xy 342.922955 -398.669419) (xy 342.94876 -398.729576) (xy 342.966254 -398.792653) (xy 342.975119 -398.857508)
			(xy 342.975692 -398.890236) (xy 342.975121 -398.922965) (xy 342.966267 -398.987823) (xy 342.948778 -399.050904)
			(xy 342.922972 -399.111062) (xy 342.906604 -399.13941) (xy 342.903286 -399.145433) (xy 342.899682 -399.158698)
			(xy 342.899492 -399.165572) (xy 342.899492 -399.451576) (xy 342.899064 -399.461698) (xy 342.891323 -399.480403)
			(xy 342.877009 -399.494718) (xy 342.858306 -399.502463) (xy 342.848184 -399.502884) (xy 342.131904 -399.502884)
			(xy 342.12178 -399.50248) (xy 342.103073 -399.494731) (xy 342.088758 -399.48041) (xy 342.081016 -399.4617)
			(xy 342.080596 -399.451576) (xy 342.080596 -399.165572) (xy 342.080415 -399.158698) (xy 342.0768 -399.145435)
			(xy 342.073484 -399.13941) (xy 342.057121 -399.111059) (xy 342.031319 -399.0509) (xy 342.013829 -398.987821)
			(xy 342.004967 -398.922965) (xy 342.004396 -398.890236) (xy 338.575072 -398.890236) (xy 338.57507 -398.922951)
			(xy 338.566281 -398.987798) (xy 338.548867 -399.050878) (xy 338.523142 -399.111049) (xy 338.506816 -399.13941)
			(xy 338.503499 -399.145433) (xy 338.499894 -399.158698) (xy 338.499704 -399.165572) (xy 338.499704 -399.451576)
			(xy 338.499259 -399.461728) (xy 338.491472 -399.480479) (xy 338.477082 -399.494803) (xy 338.458296 -399.502505)
			(xy 338.448142 -399.502884) (xy 337.731862 -399.502884) (xy 337.721736 -399.502405) (xy 337.703018 -399.494669)
			(xy 337.688664 -399.480381) (xy 337.680842 -399.4617) (xy 337.6803 -399.451576) (xy 337.6803 -399.165572)
			(xy 337.680119 -399.158698) (xy 337.676503 -399.145435) (xy 337.673188 -399.13941) (xy 337.656898 -399.111031)
			(xy 337.63118 -399.050864) (xy 337.61377 -398.987789) (xy 337.604984 -398.922948) (xy 337.60498 -398.857514)
			(xy 337.613758 -398.792672) (xy 337.63116 -398.729595) (xy 337.65687 -398.669424) (xy 337.673188 -398.641062)
			(xy 337.676515 -398.635044) (xy 337.680113 -398.621775) (xy 337.6803 -398.6149) (xy 337.6803 -397.865346)
			(xy 337.68009 -397.858474) (xy 337.676494 -397.845211) (xy 337.673188 -397.839184) (xy 337.656876 -397.810818)
			(xy 337.63116 -397.750647) (xy 337.613753 -397.687569) (xy 337.604969 -397.622726) (xy 337.604968 -397.557291)
			(xy 336.316074 -397.557291) (xy 336.323026 -397.569342) (xy 336.34883 -397.629499) (xy 336.366322 -397.692577)
			(xy 336.375185 -397.757433) (xy 336.375756 -397.790162) (xy 336.375188 -397.822891) (xy 336.366332 -397.887749)
			(xy 336.348842 -397.950829) (xy 336.323036 -398.010988) (xy 336.306668 -398.039336) (xy 336.303338 -398.045353)
			(xy 336.299743 -398.058623) (xy 336.299556 -398.065498) (xy 336.299556 -398.351502) (xy 336.299075 -398.361629)
			(xy 336.291346 -398.380351) (xy 336.277058 -398.394708) (xy 336.258373 -398.402526) (xy 336.248248 -398.403064)
			(xy 335.531968 -398.403064) (xy 335.521807 -398.402704) (xy 335.503047 -398.394891) (xy 335.488724 -398.380475)
			(xy 335.481032 -398.361665) (xy 335.48066 -398.351502) (xy 335.48066 -398.065498) (xy 335.480474 -398.058624)
			(xy 335.476862 -398.045361) (xy 335.473548 -398.039336) (xy 335.457201 -398.010976) (xy 335.431394 -397.950821)
			(xy 335.413899 -397.887745) (xy 335.405033 -397.82289) (xy 335.40446 -397.790162) (xy 334.131753 -397.790162)
			(xy 334.122886 -397.810835) (xy 334.10652 -397.839184) (xy 334.103212 -397.845212) (xy 334.099602 -397.858473)
			(xy 334.099408 -397.865346) (xy 334.099408 -398.6149) (xy 334.099599 -398.621773) (xy 334.103208 -398.635036)
			(xy 334.10652 -398.641062) (xy 334.122872 -398.669418) (xy 334.148677 -398.729576) (xy 334.16617 -398.792653)
			(xy 334.175035 -398.857508) (xy 334.175608 -398.890236) (xy 334.175035 -398.922965) (xy 334.166181 -398.987823)
			(xy 334.148693 -399.050903) (xy 334.122887 -399.111062) (xy 334.10652 -399.13941) (xy 334.103203 -399.145434)
			(xy 334.099598 -399.158698) (xy 334.099408 -399.165572) (xy 334.099408 -399.451576) (xy 334.098965 -399.461696)
			(xy 334.091226 -399.480398) (xy 334.076918 -399.494712) (xy 334.05822 -399.50246) (xy 334.0481 -399.502884)
			(xy 333.33182 -399.502884) (xy 333.321697 -399.502467) (xy 333.302991 -399.494723) (xy 333.288675 -399.480406)
			(xy 333.280932 -399.461699) (xy 333.280512 -399.451576) (xy 333.280512 -399.165572) (xy 333.280329 -399.158698)
			(xy 333.276715 -399.145435) (xy 333.2734 -399.13941) (xy 333.257038 -399.111059) (xy 333.231236 -399.0509)
			(xy 333.213745 -398.987821) (xy 333.204883 -398.922965) (xy 333.204312 -398.890236) (xy 326.525636 -398.890236)
			(xy 326.525636 -401.7228) (xy 331.005006 -401.7228) (xy 331.005009 -401.657362) (xy 331.013795 -401.592516)
			(xy 331.031207 -401.529437) (xy 331.056928 -401.469265) (xy 331.073252 -401.440904) (xy 331.076561 -401.434877)
			(xy 331.080171 -401.421615) (xy 331.080364 -401.414742) (xy 331.080364 -400.665442) (xy 331.08016 -400.65857)
			(xy 331.076561 -400.645307) (xy 331.073252 -400.63928) (xy 331.056934 -400.610916) (xy 331.031216 -400.550746)
			(xy 331.013807 -400.487668) (xy 331.005022 -400.422823) (xy 331.005021 -400.357387) (xy 331.013804 -400.292543)
			(xy 331.031212 -400.229464) (xy 331.05693 -400.169293) (xy 331.073252 -400.140932) (xy 331.076552 -400.1349)
			(xy 331.080167 -400.121642) (xy 331.080364 -400.11477) (xy 331.080364 -399.828766) (xy 331.080806 -399.818603)
			(xy 331.088597 -399.799828) (xy 331.102978 -399.785463) (xy 331.121762 -399.777694) (xy 331.131926 -399.777204)
			(xy 331.848206 -399.777204) (xy 331.85836 -399.777728) (xy 331.877123 -399.785498) (xy 331.891486 -399.799854)
			(xy 331.899267 -399.818612) (xy 331.899768 -399.828766) (xy 331.899768 -400.11477) (xy 331.899975 -400.121642)
			(xy 331.903573 -400.134905) (xy 331.90688 -400.140932) (xy 331.923207 -400.169291) (xy 331.948923 -400.229463)
			(xy 331.96633 -400.292542) (xy 331.975112 -400.357387) (xy 331.975112 -400.422824) (xy 331.966328 -400.487668)
			(xy 331.948919 -400.550747) (xy 331.923202 -400.610919) (xy 331.90688 -400.63928) (xy 331.903571 -400.645307)
			(xy 331.899962 -400.658569) (xy 331.899768 -400.665442) (xy 331.899768 -401.414742) (xy 331.899986 -401.421613)
			(xy 331.903577 -401.434876) (xy 331.90688 -401.440904) (xy 331.923183 -401.469276) (xy 331.948901 -401.529445)
			(xy 331.966311 -401.592521) (xy 331.975096 -401.657364) (xy 331.975099 -401.722799) (xy 331.966318 -401.787642)
			(xy 331.948914 -401.85072) (xy 331.9232 -401.910891) (xy 331.90688 -401.939252) (xy 331.903545 -401.945267)
			(xy 331.899953 -401.958538) (xy 331.899768 -401.965414) (xy 331.899768 -402.251418) (xy 331.899282 -402.261576)
			(xy 331.891502 -402.280345) (xy 331.877135 -402.294709) (xy 331.858364 -402.302484) (xy 331.848206 -402.30298)
			(xy 331.131926 -402.30298) (xy 331.121758 -402.302515) (xy 331.102968 -402.294742) (xy 331.088583 -402.280369)
			(xy 331.080794 -402.261585) (xy 331.080364 -402.251418) (xy 331.080364 -401.965414) (xy 331.080171 -401.958541)
			(xy 331.076564 -401.945278) (xy 331.073252 -401.939252) (xy 331.056911 -401.910901) (xy 331.031194 -401.850728)
			(xy 331.013788 -401.787647) (xy 331.005006 -401.7228) (xy 326.525636 -401.7228) (xy 326.525636 -402.790152)
			(xy 333.204312 -402.790152) (xy 333.204877 -402.757422) (xy 333.213733 -402.692564) (xy 333.231223 -402.629484)
			(xy 333.257031 -402.569326) (xy 333.2734 -402.540978) (xy 333.276723 -402.534957) (xy 333.280323 -402.52169)
			(xy 333.280512 -402.514816) (xy 333.280512 -401.765516) (xy 333.280313 -401.758643) (xy 333.276709 -401.745381)
			(xy 333.2734 -401.739354) (xy 333.257016 -401.711015) (xy 333.231219 -401.650852) (xy 333.213734 -401.587769)
			(xy 333.204879 -401.52291) (xy 333.204312 -401.49018) (xy 333.20489 -401.457451) (xy 333.213742 -401.392593)
			(xy 333.231228 -401.329513) (xy 333.257033 -401.269354) (xy 333.2734 -401.241006) (xy 333.276713 -401.23498)
			(xy 333.28032 -401.221717) (xy 333.280512 -401.214844) (xy 333.280512 -400.92884) (xy 333.280949 -400.918719)
			(xy 333.288686 -400.900014) (xy 333.302997 -400.885698) (xy 333.321699 -400.877953) (xy 333.33182 -400.877532)
			(xy 334.0481 -400.877532) (xy 334.058226 -400.877917) (xy 334.076936 -400.885671) (xy 334.091252 -400.899997)
			(xy 334.098991 -400.918713) (xy 334.099408 -400.92884) (xy 334.099408 -401.214844) (xy 334.09962 -401.221716)
			(xy 334.103215 -401.234979) (xy 334.10652 -401.241006) (xy 334.12289 -401.269353) (xy 334.14869 -401.329513)
			(xy 334.166179 -401.392594) (xy 334.175038 -401.457451) (xy 334.175608 -401.49018) (xy 334.175055 -401.52291)
			(xy 334.166195 -401.587769) (xy 334.148701 -401.650849) (xy 334.131869 -401.690078) (xy 335.40446 -401.690078)
			(xy 335.405043 -401.657349) (xy 335.413895 -401.592492) (xy 335.43138 -401.529412) (xy 335.457182 -401.469253)
			(xy 335.473548 -401.440904) (xy 335.476857 -401.434877) (xy 335.480467 -401.421615) (xy 335.48066 -401.414742)
			(xy 335.48066 -400.665442) (xy 335.480457 -400.65857) (xy 335.476857 -400.645307) (xy 335.473548 -400.63928)
			(xy 335.457179 -400.610933) (xy 335.431377 -400.550773) (xy 335.413888 -400.487693) (xy 335.405029 -400.422835)
			(xy 335.40446 -400.390106) (xy 335.405011 -400.357376) (xy 335.413872 -400.292517) (xy 335.431367 -400.229437)
			(xy 335.457178 -400.16928) (xy 335.473548 -400.140932) (xy 335.476847 -400.1349) (xy 335.480463 -400.121642)
			(xy 335.48066 -400.11477) (xy 335.48066 -399.828766) (xy 335.481099 -399.818635) (xy 335.488842 -399.799909)
			(xy 335.503143 -399.785553) (xy 335.521839 -399.777739) (xy 335.531968 -399.777204) (xy 336.248248 -399.777204)
			(xy 336.258406 -399.777583) (xy 336.27716 -399.785395) (xy 336.291482 -399.799804) (xy 336.299179 -399.818606)
			(xy 336.299556 -399.828766) (xy 336.299556 -400.11477) (xy 336.299752 -400.121643) (xy 336.303357 -400.134906)
			(xy 336.306668 -400.140932) (xy 336.323043 -400.169276) (xy 336.348843 -400.229437) (xy 336.366331 -400.292518)
			(xy 336.375188 -400.357377) (xy 336.375756 -400.390106) (xy 336.375163 -400.422834) (xy 336.366314 -400.487692)
			(xy 336.348832 -400.550772) (xy 336.323033 -400.610931) (xy 336.306668 -400.63928) (xy 336.303358 -400.645307)
			(xy 336.29975 -400.658569) (xy 336.299556 -400.665442) (xy 336.299556 -401.414742) (xy 336.299763 -401.421614)
			(xy 336.30336 -401.434877) (xy 336.306668 -401.440904) (xy 336.323032 -401.469254) (xy 336.348835 -401.529413)
			(xy 336.366325 -401.592492) (xy 336.375186 -401.657349) (xy 336.375756 -401.690078) (xy 336.375195 -401.722808)
			(xy 336.366337 -401.787666) (xy 336.348845 -401.850746) (xy 336.323037 -401.910904) (xy 336.306668 -401.939252)
			(xy 336.303333 -401.945266) (xy 336.299741 -401.958538) (xy 336.299556 -401.965414) (xy 336.299556 -402.251418)
			(xy 336.299088 -402.261546) (xy 336.291354 -402.280269) (xy 336.277062 -402.294625) (xy 336.258374 -402.302443)
			(xy 336.248248 -402.30298) (xy 335.531968 -402.30298) (xy 335.521809 -402.302604) (xy 335.503052 -402.294794)
			(xy 335.488729 -402.280384) (xy 335.481034 -402.261579) (xy 335.48066 -402.251418) (xy 335.48066 -401.965414)
			(xy 335.480468 -401.958541) (xy 335.47686 -401.945278) (xy 335.473548 -401.939252) (xy 335.457168 -401.910911)
			(xy 335.431368 -401.850749) (xy 335.413883 -401.787667) (xy 335.405027 -401.722808) (xy 335.40446 -401.690078)
			(xy 334.131869 -401.690078) (xy 334.12289 -401.711006) (xy 334.10652 -401.739354) (xy 334.103223 -401.745387)
			(xy 334.099606 -401.758644) (xy 334.099408 -401.765516) (xy 334.099408 -402.514816) (xy 334.099593 -402.52169)
			(xy 334.103206 -402.534953) (xy 334.10652 -402.540978) (xy 334.122879 -402.569331) (xy 334.148682 -402.629489)
			(xy 334.166173 -402.692568) (xy 334.175036 -402.757423) (xy 334.175608 -402.790152) (xy 334.175042 -402.822879)
			(xy 337.604936 -402.822879) (xy 337.604942 -402.757439) (xy 337.61373 -402.692593) (xy 337.631143 -402.629512)
			(xy 337.656864 -402.56934) (xy 337.673188 -402.540978) (xy 337.67651 -402.534957) (xy 337.680111 -402.52169)
			(xy 337.6803 -402.514816) (xy 337.6803 -401.765516) (xy 337.680102 -401.758643) (xy 337.676498 -401.74538)
			(xy 337.673188 -401.739354) (xy 337.65685 -401.711002) (xy 337.631137 -401.650828) (xy 337.613733 -401.587747)
			(xy 337.604952 -401.522902) (xy 337.604955 -401.457464) (xy 337.61374 -401.392619) (xy 337.631148 -401.32954)
			(xy 337.656866 -401.269368) (xy 337.673188 -401.241006) (xy 337.6765 -401.23498) (xy 337.680108 -401.221717)
			(xy 337.6803 -401.214844) (xy 337.6803 -400.92884) (xy 337.680755 -400.918688) (xy 337.688537 -400.899937)
			(xy 337.702924 -400.885612) (xy 337.721709 -400.877911) (xy 337.731862 -400.877532) (xy 338.448142 -400.877532)
			(xy 338.45827 -400.877992) (xy 338.476991 -400.885732) (xy 338.491346 -400.900026) (xy 338.499165 -400.918714)
			(xy 338.499704 -400.92884) (xy 338.499704 -401.214844) (xy 338.499917 -401.221716) (xy 338.503511 -401.234978)
			(xy 338.506816 -401.241006) (xy 338.523123 -401.269376) (xy 338.548844 -401.329545) (xy 338.566256 -401.392622)
			(xy 338.575042 -401.457465) (xy 338.575045 -401.522901) (xy 338.566263 -401.587745) (xy 338.548856 -401.650823)
			(xy 338.523138 -401.710993) (xy 338.516343 -401.7228) (xy 339.805092 -401.7228) (xy 339.805095 -401.657362)
			(xy 339.813881 -401.592516) (xy 339.831292 -401.529437) (xy 339.857012 -401.469265) (xy 339.873336 -401.440904)
			(xy 339.876644 -401.434876) (xy 339.880255 -401.421615) (xy 339.880448 -401.414742) (xy 339.880448 -400.665442)
			(xy 339.880247 -400.658569) (xy 339.876646 -400.645306) (xy 339.873336 -400.63928) (xy 339.857019 -400.610916)
			(xy 339.831301 -400.550745) (xy 339.813892 -400.487667) (xy 339.805108 -400.422823) (xy 339.805108 -400.357387)
			(xy 339.81389 -400.292543) (xy 339.831298 -400.229464) (xy 339.857014 -400.169293) (xy 339.873336 -400.140932)
			(xy 339.876634 -400.134899) (xy 339.880251 -400.121642) (xy 339.880448 -400.11477) (xy 339.880448 -399.828766)
			(xy 339.880906 -399.818605) (xy 339.888693 -399.799833) (xy 339.90307 -399.785469) (xy 339.921848 -399.777697)
			(xy 339.93201 -399.777204) (xy 340.64829 -399.777204) (xy 340.658443 -399.777741) (xy 340.677205 -399.785506)
			(xy 340.69157 -399.799858) (xy 340.699351 -399.818613) (xy 340.699852 -399.828766) (xy 340.699852 -400.11477)
			(xy 340.700049 -400.121643) (xy 340.703653 -400.134906) (xy 340.706964 -400.140932) (xy 340.723291 -400.16929)
			(xy 340.749008 -400.229462) (xy 340.766416 -400.292542) (xy 340.775198 -400.357387) (xy 340.775198 -400.422824)
			(xy 340.766414 -400.487669) (xy 340.749005 -400.550747) (xy 340.723287 -400.610919) (xy 340.706964 -400.63928)
			(xy 340.703661 -400.645311) (xy 340.700047 -400.65857) (xy 340.699852 -400.665442) (xy 340.699852 -401.414742)
			(xy 340.700059 -401.421614) (xy 340.703656 -401.434877) (xy 340.706964 -401.440904) (xy 340.723268 -401.469276)
			(xy 340.748987 -401.529444) (xy 340.766397 -401.592521) (xy 340.775183 -401.657364) (xy 340.775185 -401.722799)
			(xy 340.766404 -401.787642) (xy 340.748999 -401.85072) (xy 340.723285 -401.910891) (xy 340.706964 -401.939252)
			(xy 340.703636 -401.94527) (xy 340.700038 -401.958539) (xy 340.699852 -401.965414) (xy 340.699852 -402.251418)
			(xy 340.699381 -402.261578) (xy 340.691599 -402.28035) (xy 340.677226 -402.294715) (xy 340.65845 -402.302487)
			(xy 340.64829 -402.30298) (xy 339.93201 -402.30298) (xy 339.921855 -402.302459) (xy 339.90309 -402.294691)
			(xy 339.888725 -402.280334) (xy 339.880947 -402.261573) (xy 339.880448 -402.251418) (xy 339.880448 -401.965414)
			(xy 339.880257 -401.958541) (xy 339.876649 -401.945278) (xy 339.873336 -401.939252) (xy 339.856995 -401.910901)
			(xy 339.83128 -401.850727) (xy 339.813874 -401.787647) (xy 339.805092 -401.7228) (xy 338.516343 -401.7228)
			(xy 338.506816 -401.739354) (xy 338.503519 -401.745387) (xy 338.499902 -401.758644) (xy 338.499704 -401.765516)
			(xy 338.499704 -402.514816) (xy 338.499889 -402.52169) (xy 338.503502 -402.534953) (xy 338.506816 -402.540978)
			(xy 338.523099 -402.569361) (xy 338.548823 -402.629527) (xy 338.566237 -402.692601) (xy 338.575026 -402.757442)
			(xy 338.575029 -402.790152) (xy 342.004396 -402.790152) (xy 342.004963 -402.757423) (xy 342.013819 -402.692564)
			(xy 342.031309 -402.629484) (xy 342.057116 -402.569326) (xy 342.073484 -402.540978) (xy 342.076805 -402.534957)
			(xy 342.080407 -402.52169) (xy 342.080596 -402.514816) (xy 342.080596 -401.765516) (xy 342.080398 -401.758643)
			(xy 342.076794 -401.74538) (xy 342.073484 -401.739354) (xy 342.057099 -401.711016) (xy 342.031302 -401.650852)
			(xy 342.013818 -401.587769) (xy 342.004963 -401.52291) (xy 342.004396 -401.49018) (xy 342.004976 -401.457451)
			(xy 342.013828 -401.392593) (xy 342.031314 -401.329513) (xy 342.057117 -401.269355) (xy 342.073484 -401.241006)
			(xy 342.076795 -401.23498) (xy 342.080403 -401.221717) (xy 342.080596 -401.214844) (xy 342.080596 -400.92884)
			(xy 342.081049 -400.918721) (xy 342.088783 -400.900019) (xy 342.103088 -400.885703) (xy 342.121785 -400.877956)
			(xy 342.131904 -400.877532) (xy 342.848184 -400.877532) (xy 342.858309 -400.87793) (xy 342.877019 -400.885679)
			(xy 342.891335 -400.900001) (xy 342.899075 -400.918714) (xy 342.899492 -400.92884) (xy 342.899492 -401.214844)
			(xy 342.899707 -401.221716) (xy 342.9033 -401.234978) (xy 342.906604 -401.241006) (xy 342.922972 -401.269354)
			(xy 342.948773 -401.329514) (xy 342.966262 -401.392594) (xy 342.975122 -401.457451) (xy 342.975692 -401.49018)
			(xy 342.975141 -401.52291) (xy 342.966281 -401.587769) (xy 342.948786 -401.650849) (xy 342.922974 -401.711006)
			(xy 342.916163 -401.7228) (xy 344.204882 -401.7228) (xy 344.204885 -401.657362) (xy 344.213671 -401.592517)
			(xy 344.231081 -401.529437) (xy 344.256801 -401.469265) (xy 344.273124 -401.440904) (xy 344.276439 -401.43488)
			(xy 344.280044 -401.421616) (xy 344.280236 -401.414742) (xy 344.280236 -400.665442) (xy 344.280024 -400.65857)
			(xy 344.276429 -400.645308) (xy 344.273124 -400.63928) (xy 344.256807 -400.610916) (xy 344.23109 -400.550745)
			(xy 344.213682 -400.487667) (xy 344.204898 -400.422823) (xy 344.204897 -400.357387) (xy 344.21368 -400.292543)
			(xy 344.231087 -400.229465) (xy 344.256803 -400.169293) (xy 344.273124 -400.140932) (xy 344.276429 -400.134903)
			(xy 344.28004 -400.121643) (xy 344.280236 -400.11477) (xy 344.280236 -399.828766) (xy 344.280705 -399.818606)
			(xy 344.288491 -399.799837) (xy 344.302864 -399.785473) (xy 344.321638 -399.777699) (xy 344.331798 -399.777204)
			(xy 345.048078 -399.777204) (xy 345.05823 -399.77775) (xy 345.076992 -399.785511) (xy 345.091357 -399.799861)
			(xy 345.099139 -399.818614) (xy 345.09964 -399.828766) (xy 345.09964 -400.11477) (xy 345.099838 -400.121643)
			(xy 345.103442 -400.134906) (xy 345.106752 -400.140932) (xy 345.12308 -400.16929) (xy 345.148797 -400.229462)
			(xy 345.166205 -400.292541) (xy 345.174988 -400.357387) (xy 345.174987 -400.390106) (xy 348.603832 -400.390106)
			(xy 348.607823 -400.327939) (xy 348.619732 -400.266792) (xy 348.639361 -400.207671) (xy 348.66639 -400.151545)
			(xy 348.700374 -400.099336) (xy 348.740756 -400.051901) (xy 348.786872 -400.01002) (xy 348.837964 -399.97438)
			(xy 348.893195 -399.945566) (xy 348.951657 -399.924052) (xy 349.012391 -399.91019) (xy 349.074398 -399.904208)
			(xy 349.136661 -399.906204) (xy 349.198158 -399.916147) (xy 349.257879 -399.933871) (xy 349.314842 -399.959088)
			(xy 349.368113 -399.991381) (xy 349.416818 -400.030221) (xy 349.460155 -400.074971) (xy 349.497415 -400.124895)
			(xy 349.527984 -400.179174) (xy 349.551362 -400.236917) (xy 349.567163 -400.297175) (xy 349.575129 -400.358958)
			(xy 349.575628 -400.390106) (xy 349.575129 -400.421254) (xy 349.567163 -400.483037) (xy 349.551362 -400.543295)
			(xy 349.527984 -400.601038) (xy 349.497415 -400.655317) (xy 349.460155 -400.705241) (xy 349.416818 -400.749991)
			(xy 349.368113 -400.788831) (xy 349.314842 -400.821124) (xy 349.257879 -400.846341) (xy 349.198158 -400.864065)
			(xy 349.136661 -400.874008) (xy 349.074398 -400.876004) (xy 349.012391 -400.870022) (xy 348.951657 -400.85616)
			(xy 348.893195 -400.834646) (xy 348.837964 -400.805832) (xy 348.786872 -400.770192) (xy 348.740756 -400.728311)
			(xy 348.700374 -400.680876) (xy 348.66639 -400.628667) (xy 348.639361 -400.572541) (xy 348.619732 -400.51342)
			(xy 348.607823 -400.452273) (xy 348.603832 -400.390106) (xy 345.174987 -400.390106) (xy 345.174987 -400.422824)
			(xy 345.166203 -400.487669) (xy 345.148794 -400.550748) (xy 345.123075 -400.610919) (xy 345.106752 -400.63928)
			(xy 345.103449 -400.64531) (xy 345.099835 -400.65857) (xy 345.09964 -400.665442) (xy 345.09964 -401.414742)
			(xy 345.099849 -401.421614) (xy 345.103445 -401.434877) (xy 345.106752 -401.440904) (xy 345.123056 -401.469275)
			(xy 345.148776 -401.529444) (xy 345.166186 -401.592521) (xy 345.174972 -401.657363) (xy 345.174975 -401.722799)
			(xy 345.166194 -401.787642) (xy 345.148788 -401.85072) (xy 345.123073 -401.910891) (xy 345.106752 -401.939252)
			(xy 345.103423 -401.94527) (xy 345.099826 -401.958539) (xy 345.09964 -401.965414) (xy 345.09964 -402.251418)
			(xy 345.09925 -402.261593) (xy 345.091455 -402.280393) (xy 345.077059 -402.294778) (xy 345.058254 -402.302558)
			(xy 345.048078 -402.30298) (xy 344.331798 -402.30298) (xy 344.321642 -402.302469) (xy 344.302877 -402.294697)
			(xy 344.288512 -402.280337) (xy 344.280735 -402.261574) (xy 344.280236 -402.251418) (xy 344.280236 -401.965414)
			(xy 344.280034 -401.958542) (xy 344.276432 -401.945279) (xy 344.273124 -401.939252) (xy 344.256784 -401.910901)
			(xy 344.231069 -401.850727) (xy 344.213663 -401.787646) (xy 344.204882 -401.7228) (xy 342.916163 -401.7228)
			(xy 342.906604 -401.739354) (xy 342.903306 -401.745387) (xy 342.89969 -401.758644) (xy 342.899492 -401.765516)
			(xy 342.899492 -402.514816) (xy 342.899679 -402.52169) (xy 342.903291 -402.534952) (xy 342.906604 -402.540978)
			(xy 342.922961 -402.569332) (xy 342.948765 -402.62949) (xy 342.966257 -402.692568) (xy 342.97512 -402.757423)
			(xy 342.975692 -402.790152) (xy 342.975128 -402.822879) (xy 346.405009 -402.822879) (xy 346.405014 -402.757439)
			(xy 346.413804 -402.692591) (xy 346.43122 -402.629511) (xy 346.456946 -402.569339) (xy 346.473272 -402.540978)
			(xy 346.476593 -402.534956) (xy 346.480195 -402.52169) (xy 346.480384 -402.514816) (xy 346.480384 -401.765516)
			(xy 346.480188 -401.758643) (xy 346.476583 -401.74538) (xy 346.473272 -401.739354) (xy 346.456932 -401.711002)
			(xy 346.431214 -401.650829) (xy 346.413807 -401.587749) (xy 346.405025 -401.522902) (xy 346.405027 -401.457464)
			(xy 346.413813 -401.392618) (xy 346.431225 -401.329538) (xy 346.456947 -401.269367) (xy 346.473272 -401.241006)
			(xy 346.476583 -401.234979) (xy 346.480191 -401.221717) (xy 346.480384 -401.214844) (xy 346.480384 -400.92884)
			(xy 346.480854 -400.91869) (xy 346.488634 -400.899942) (xy 346.503015 -400.885618) (xy 346.521795 -400.877914)
			(xy 346.531946 -400.877532) (xy 347.248226 -400.877532) (xy 347.258353 -400.878005) (xy 347.277074 -400.88574)
			(xy 347.291429 -400.90003) (xy 347.299249 -400.918715) (xy 347.299788 -400.92884) (xy 347.299788 -401.214844)
			(xy 347.300003 -401.221716) (xy 347.303596 -401.234978) (xy 347.3069 -401.241006) (xy 347.323204 -401.269377)
			(xy 347.348921 -401.329546) (xy 347.36633 -401.392623) (xy 347.375115 -401.457465) (xy 347.375117 -401.5229)
			(xy 347.366337 -401.587743) (xy 347.348933 -401.650821) (xy 347.332157 -401.690078) (xy 348.603832 -401.690078)
			(xy 348.607823 -401.627911) (xy 348.619732 -401.566764) (xy 348.639361 -401.507643) (xy 348.66639 -401.451517)
			(xy 348.700374 -401.399308) (xy 348.740756 -401.351873) (xy 348.786872 -401.309992) (xy 348.837964 -401.274352)
			(xy 348.893195 -401.245538) (xy 348.951657 -401.224024) (xy 349.012391 -401.210162) (xy 349.074398 -401.20418)
			(xy 349.136661 -401.206176) (xy 349.198158 -401.216119) (xy 349.257879 -401.233843) (xy 349.314842 -401.25906)
			(xy 349.368113 -401.291353) (xy 349.416818 -401.330193) (xy 349.460155 -401.374943) (xy 349.497415 -401.424867)
			(xy 349.527984 -401.479146) (xy 349.532451 -401.49018) (xy 350.80398 -401.49018) (xy 350.807971 -401.428013)
			(xy 350.81988 -401.366866) (xy 350.839509 -401.307745) (xy 350.866538 -401.251619) (xy 350.900522 -401.19941)
			(xy 350.940904 -401.151975) (xy 350.98702 -401.110094) (xy 351.038112 -401.074454) (xy 351.093343 -401.04564)
			(xy 351.151805 -401.024126) (xy 351.212539 -401.010264) (xy 351.274546 -401.004282) (xy 351.336809 -401.006278)
			(xy 351.398306 -401.016221) (xy 351.458027 -401.033945) (xy 351.51499 -401.059162) (xy 351.568261 -401.091455)
			(xy 351.616966 -401.130295) (xy 351.660303 -401.175045) (xy 351.697563 -401.224969) (xy 351.728132 -401.279248)
			(xy 351.75151 -401.336991) (xy 351.767311 -401.397249) (xy 351.775277 -401.459032) (xy 351.775776 -401.49018)
			(xy 351.775277 -401.521328) (xy 351.767311 -401.583111) (xy 351.75151 -401.643369) (xy 351.728132 -401.701112)
			(xy 351.715918 -401.7228) (xy 375.004916 -401.7228) (xy 375.004919 -401.657362) (xy 375.013706 -401.592516)
			(xy 375.031118 -401.529436) (xy 375.05684 -401.469265) (xy 375.073164 -401.440904) (xy 375.076474 -401.434877)
			(xy 375.080083 -401.421615) (xy 375.080276 -401.414742) (xy 375.080276 -400.665442) (xy 375.080071 -400.65857)
			(xy 375.076472 -400.645307) (xy 375.073164 -400.63928) (xy 375.056846 -400.610916) (xy 375.031127 -400.550746)
			(xy 375.013717 -400.487668) (xy 375.004932 -400.422823) (xy 375.004932 -400.357387) (xy 375.013715 -400.292542)
			(xy 375.031123 -400.229464) (xy 375.056841 -400.169293) (xy 375.073164 -400.140932) (xy 375.076464 -400.1349)
			(xy 375.080079 -400.121642) (xy 375.080276 -400.11477) (xy 375.080276 -399.828766) (xy 375.080637 -399.818587)
			(xy 375.08844 -399.799785) (xy 375.102845 -399.7854) (xy 375.121659 -399.777623) (xy 375.131838 -399.777204)
			(xy 375.848118 -399.777204) (xy 375.858273 -399.777718) (xy 375.877036 -399.785492) (xy 375.891399 -399.799851)
			(xy 375.899179 -399.818611) (xy 375.89968 -399.828766) (xy 375.89968 -400.11477) (xy 375.899886 -400.121642)
			(xy 375.903485 -400.134905) (xy 375.906792 -400.140932) (xy 375.923118 -400.169291) (xy 375.948834 -400.229463)
			(xy 375.96624 -400.292542) (xy 375.975023 -400.357387) (xy 375.975022 -400.422824) (xy 375.966238 -400.487668)
			(xy 375.94883 -400.550747) (xy 375.923114 -400.610918) (xy 375.906792 -400.63928) (xy 375.903484 -400.645308)
			(xy 375.899874 -400.658569) (xy 375.89968 -400.665442) (xy 375.89968 -401.414742) (xy 375.899897 -401.421613)
			(xy 375.903489 -401.434876) (xy 375.906792 -401.440904) (xy 375.923095 -401.469276) (xy 375.948812 -401.529445)
			(xy 375.966221 -401.592521) (xy 375.975007 -401.657364) (xy 375.975009 -401.722799) (xy 375.966229 -401.787642)
			(xy 375.948825 -401.850719) (xy 375.923112 -401.91089) (xy 375.906792 -401.939252) (xy 375.903458 -401.945267)
			(xy 375.899865 -401.958538) (xy 375.89968 -401.965414) (xy 375.89968 -402.251418) (xy 375.899182 -402.261575)
			(xy 375.891405 -402.280341) (xy 375.877041 -402.294705) (xy 375.858275 -402.302482) (xy 375.848118 -402.30298)
			(xy 375.131838 -402.30298) (xy 375.121671 -402.302505) (xy 375.102881 -402.294736) (xy 375.088495 -402.280366)
			(xy 375.080706 -402.261584) (xy 375.080276 -402.251418) (xy 375.080276 -401.965414) (xy 375.080082 -401.958541)
			(xy 375.076475 -401.945278) (xy 375.073164 -401.939252) (xy 375.056822 -401.910901) (xy 375.031105 -401.850728)
			(xy 375.013698 -401.787647) (xy 375.004916 -401.7228) (xy 351.715918 -401.7228) (xy 351.697563 -401.755391)
			(xy 351.660303 -401.805315) (xy 351.616966 -401.850065) (xy 351.568261 -401.888905) (xy 351.51499 -401.921198)
			(xy 351.458027 -401.946415) (xy 351.398306 -401.964139) (xy 351.336809 -401.974082) (xy 351.274546 -401.976078)
			(xy 351.212539 -401.970096) (xy 351.151805 -401.956234) (xy 351.093343 -401.93472) (xy 351.038112 -401.905906)
			(xy 350.98702 -401.870266) (xy 350.940904 -401.828385) (xy 350.900522 -401.78095) (xy 350.866538 -401.728741)
			(xy 350.839509 -401.672615) (xy 350.81988 -401.613494) (xy 350.807971 -401.552347) (xy 350.80398 -401.49018)
			(xy 349.532451 -401.49018) (xy 349.551362 -401.536889) (xy 349.567163 -401.597147) (xy 349.575129 -401.65893)
			(xy 349.575628 -401.690078) (xy 349.575129 -401.721226) (xy 349.567163 -401.783009) (xy 349.551362 -401.843267)
			(xy 349.527984 -401.90101) (xy 349.497415 -401.955289) (xy 349.460155 -402.005213) (xy 349.416818 -402.049963)
			(xy 349.368113 -402.088803) (xy 349.314842 -402.121096) (xy 349.257879 -402.146313) (xy 349.198158 -402.164037)
			(xy 349.136661 -402.17398) (xy 349.074398 -402.175976) (xy 349.012391 -402.169994) (xy 348.951657 -402.156132)
			(xy 348.893195 -402.134618) (xy 348.837964 -402.105804) (xy 348.786872 -402.070164) (xy 348.740756 -402.028283)
			(xy 348.700374 -401.980848) (xy 348.66639 -401.928639) (xy 348.639361 -401.872513) (xy 348.619732 -401.813392)
			(xy 348.607823 -401.752245) (xy 348.603832 -401.690078) (xy 347.332157 -401.690078) (xy 347.32322 -401.710992)
			(xy 347.3069 -401.739354) (xy 347.303602 -401.745387) (xy 347.299986 -401.758644) (xy 347.299788 -401.765516)
			(xy 347.299788 -402.514816) (xy 347.299975 -402.52169) (xy 347.303587 -402.534952) (xy 347.3069 -402.540978)
			(xy 347.32318 -402.569362) (xy 347.3489 -402.629528) (xy 347.366311 -402.692602) (xy 347.375099 -402.757442)
			(xy 347.375101 -402.790152) (xy 350.80398 -402.790152) (xy 350.807971 -402.727985) (xy 350.81988 -402.666838)
			(xy 350.839509 -402.607717) (xy 350.866538 -402.551591) (xy 350.900522 -402.499382) (xy 350.940904 -402.451947)
			(xy 350.98702 -402.410066) (xy 351.038112 -402.374426) (xy 351.093343 -402.345612) (xy 351.151805 -402.324098)
			(xy 351.212539 -402.310236) (xy 351.274546 -402.304254) (xy 351.336809 -402.30625) (xy 351.398306 -402.316193)
			(xy 351.458027 -402.333917) (xy 351.51499 -402.359134) (xy 351.568261 -402.391427) (xy 351.616966 -402.430267)
			(xy 351.660303 -402.475017) (xy 351.697563 -402.524941) (xy 351.728132 -402.57922) (xy 351.75151 -402.636963)
			(xy 351.767311 -402.697221) (xy 351.775277 -402.759004) (xy 351.775776 -402.790152) (xy 377.204224 -402.790152)
			(xy 377.204787 -402.757422) (xy 377.213643 -402.692564) (xy 377.231134 -402.629484) (xy 377.256943 -402.569326)
			(xy 377.273312 -402.540978) (xy 377.276635 -402.534958) (xy 377.280235 -402.521691) (xy 377.280424 -402.514816)
			(xy 377.280424 -401.765516) (xy 377.280223 -401.758643) (xy 377.276621 -401.745381) (xy 377.273312 -401.739354)
			(xy 377.256929 -401.711014) (xy 377.231131 -401.650851) (xy 377.213646 -401.587769) (xy 377.204791 -401.52291)
			(xy 377.204224 -401.49018) (xy 377.2048 -401.457451) (xy 377.213652 -401.392593) (xy 377.231139 -401.329513)
			(xy 377.256945 -401.269354) (xy 377.273312 -401.241006) (xy 377.276625 -401.234981) (xy 377.280232 -401.221717)
			(xy 377.280424 -401.214844) (xy 377.280424 -400.92884) (xy 377.280849 -400.918717) (xy 377.288589 -400.90001)
			(xy 377.302903 -400.885693) (xy 377.321609 -400.877951) (xy 377.331732 -400.877532) (xy 378.048012 -400.877532)
			(xy 378.058139 -400.877907) (xy 378.076849 -400.885665) (xy 378.091164 -400.899994) (xy 378.098904 -400.918712)
			(xy 378.09932 -400.92884) (xy 378.09932 -401.214844) (xy 378.099531 -401.221716) (xy 378.103126 -401.234979)
			(xy 378.106432 -401.241006) (xy 378.122793 -401.269358) (xy 378.148598 -401.329516) (xy 378.166089 -401.392595)
			(xy 378.17495 -401.457451) (xy 378.17552 -401.49018) (xy 378.174965 -401.52291) (xy 378.166106 -401.587768)
			(xy 378.148612 -401.650849) (xy 378.131781 -401.690078) (xy 379.404372 -401.690078) (xy 379.404954 -401.657349)
			(xy 379.413806 -401.592492) (xy 379.431291 -401.529412) (xy 379.457094 -401.469253) (xy 379.47346 -401.440904)
			(xy 379.47677 -401.434877) (xy 379.480379 -401.421615) (xy 379.480572 -401.414742) (xy 379.480572 -400.665442)
			(xy 379.480367 -400.65857) (xy 379.476768 -400.645307) (xy 379.47346 -400.63928) (xy 379.457092 -400.610932)
			(xy 379.43129 -400.550772) (xy 379.4138 -400.487692) (xy 379.404941 -400.422835) (xy 379.404372 -400.390106)
			(xy 379.404922 -400.357376) (xy 379.413783 -400.292517) (xy 379.431278 -400.229437) (xy 379.457089 -400.16928)
			(xy 379.47346 -400.140932) (xy 379.47676 -400.1349) (xy 379.480375 -400.121642) (xy 379.480572 -400.11477)
			(xy 379.480572 -399.828766) (xy 379.481 -399.818633) (xy 379.488744 -399.799905) (xy 379.503049 -399.785549)
			(xy 379.521749 -399.777737) (xy 379.53188 -399.777204) (xy 380.24816 -399.777204) (xy 380.258312 -399.777655)
			(xy 380.277064 -399.785438) (xy 380.291389 -399.799826) (xy 380.29909 -399.818612) (xy 380.299468 -399.828766)
			(xy 380.299468 -400.11477) (xy 380.299675 -400.121642) (xy 380.303273 -400.134905) (xy 380.30658 -400.140932)
			(xy 380.322956 -400.169275) (xy 380.348756 -400.229437) (xy 380.366243 -400.292518) (xy 380.3751 -400.357376)
			(xy 380.375668 -400.390106) (xy 380.375073 -400.422834) (xy 380.366225 -400.487691) (xy 380.348743 -400.550771)
			(xy 380.322944 -400.610931) (xy 380.30658 -400.63928) (xy 380.303271 -400.645307) (xy 380.299662 -400.658569)
			(xy 380.299468 -400.665442) (xy 380.299468 -401.414742) (xy 380.299686 -401.421613) (xy 380.303277 -401.434876)
			(xy 380.30658 -401.440904) (xy 380.322945 -401.469253) (xy 380.348748 -401.529413) (xy 380.366237 -401.592492)
			(xy 380.375098 -401.657349) (xy 380.375668 -401.690078) (xy 380.375106 -401.722808) (xy 380.366247 -401.787666)
			(xy 380.348756 -401.850746) (xy 380.322948 -401.910904) (xy 380.30658 -401.939252) (xy 380.303245 -401.945267)
			(xy 380.299653 -401.958538) (xy 380.299468 -401.965414) (xy 380.299468 -402.251418) (xy 380.298989 -402.261545)
			(xy 380.291256 -402.280265) (xy 380.276968 -402.29462) (xy 380.258284 -402.30244) (xy 380.24816 -402.30298)
			(xy 379.53188 -402.30298) (xy 379.521722 -402.302595) (xy 379.502965 -402.294789) (xy 379.488642 -402.280381)
			(xy 379.480946 -402.261578) (xy 379.480572 -402.251418) (xy 379.480572 -401.965414) (xy 379.480378 -401.958541)
			(xy 379.476771 -401.945278) (xy 379.47346 -401.939252) (xy 379.457081 -401.91091) (xy 379.431281 -401.850748)
			(xy 379.413795 -401.787666) (xy 379.404939 -401.722808) (xy 379.404372 -401.690078) (xy 378.131781 -401.690078)
			(xy 378.122802 -401.711006) (xy 378.106432 -401.739354) (xy 378.103136 -401.745388) (xy 378.099518 -401.758644)
			(xy 378.09932 -401.765516) (xy 378.09932 -402.514816) (xy 378.099503 -402.52169) (xy 378.103117 -402.534953)
			(xy 378.106432 -402.540978) (xy 378.122782 -402.569336) (xy 378.148589 -402.629492) (xy 378.166084 -402.692569)
			(xy 378.174948 -402.757424) (xy 378.17552 -402.790152) (xy 378.174953 -402.822879) (xy 381.604847 -402.822879)
			(xy 381.604852 -402.757439) (xy 381.613641 -402.692592) (xy 381.631054 -402.629512) (xy 381.656776 -402.56934)
			(xy 381.6731 -402.540978) (xy 381.676423 -402.534957) (xy 381.680023 -402.52169) (xy 381.680212 -402.514816)
			(xy 381.680212 -401.765516) (xy 381.680013 -401.758643) (xy 381.676409 -401.745381) (xy 381.6731 -401.739354)
			(xy 381.656762 -401.711002) (xy 381.631048 -401.650828) (xy 381.613643 -401.587747) (xy 381.604863 -401.522902)
			(xy 381.604865 -401.457464) (xy 381.61365 -401.392619) (xy 381.631059 -401.32954) (xy 381.656778 -401.269368)
			(xy 381.6731 -401.241006) (xy 381.676413 -401.23498) (xy 381.68002 -401.221717) (xy 381.680212 -401.214844)
			(xy 381.680212 -400.92884) (xy 381.680655 -400.918687) (xy 381.688439 -400.899933) (xy 381.70283 -400.885608)
			(xy 381.721619 -400.877909) (xy 381.731774 -400.877532) (xy 382.448054 -400.877532) (xy 382.458177 -400.878064)
			(xy 382.476895 -400.885775) (xy 382.491253 -400.900048) (xy 382.499075 -400.91872) (xy 382.499616 -400.92884)
			(xy 382.499616 -401.214844) (xy 382.499827 -401.221716) (xy 382.503422 -401.234979) (xy 382.506728 -401.241006)
			(xy 382.523034 -401.269376) (xy 382.548755 -401.329545) (xy 382.566166 -401.392622) (xy 382.574953 -401.457465)
			(xy 382.574955 -401.522901) (xy 382.566173 -401.587745) (xy 382.548767 -401.650823) (xy 382.52305 -401.710993)
			(xy 382.516255 -401.7228) (xy 383.805003 -401.7228) (xy 383.805005 -401.657362) (xy 383.813792 -401.592516)
			(xy 383.831203 -401.529437) (xy 383.856924 -401.469265) (xy 383.873248 -401.440904) (xy 383.876557 -401.434877)
			(xy 383.880167 -401.421615) (xy 383.88036 -401.414742) (xy 383.88036 -400.665442) (xy 383.880157 -400.65857)
			(xy 383.876557 -400.645307) (xy 383.873248 -400.63928) (xy 383.856931 -400.610916) (xy 383.831212 -400.550746)
			(xy 383.813803 -400.487667) (xy 383.805019 -400.422823) (xy 383.805018 -400.357387) (xy 383.813801 -400.292543)
			(xy 383.831209 -400.229464) (xy 383.856926 -400.169293) (xy 383.873248 -400.140932) (xy 383.876547 -400.1349)
			(xy 383.880163 -400.121642) (xy 383.88036 -400.11477) (xy 383.88036 -399.828766) (xy 383.880806 -399.818603)
			(xy 383.888596 -399.799829) (xy 383.902976 -399.785464) (xy 383.921759 -399.777695) (xy 383.931922 -399.777204)
			(xy 384.648202 -399.777204) (xy 384.658356 -399.777731) (xy 384.677118 -399.7855) (xy 384.691482 -399.799855)
			(xy 384.699263 -399.818613) (xy 384.699764 -399.828766) (xy 384.699764 -400.11477) (xy 384.699972 -400.121642)
			(xy 384.70357 -400.134905) (xy 384.706876 -400.140932) (xy 384.723203 -400.169291) (xy 384.748919 -400.229463)
			(xy 384.766326 -400.292542) (xy 384.775109 -400.357387) (xy 384.775108 -400.422824) (xy 384.766324 -400.487668)
			(xy 384.748916 -400.550747) (xy 384.723198 -400.610919) (xy 384.706876 -400.63928) (xy 384.703567 -400.645307)
			(xy 384.699958 -400.658569) (xy 384.699764 -400.665442) (xy 384.699764 -401.414742) (xy 384.699982 -401.421613)
			(xy 384.703573 -401.434876) (xy 384.706876 -401.440904) (xy 384.723179 -401.469276) (xy 384.748898 -401.529445)
			(xy 384.766307 -401.592521) (xy 384.775093 -401.657364) (xy 384.775095 -401.722799) (xy 384.766315 -401.787642)
			(xy 384.74891 -401.85072) (xy 384.723196 -401.910891) (xy 384.706876 -401.939252) (xy 384.703541 -401.945267)
			(xy 384.699949 -401.958538) (xy 384.699764 -401.965414) (xy 384.699764 -402.251418) (xy 384.699282 -402.261577)
			(xy 384.691502 -402.280346) (xy 384.677133 -402.294711) (xy 384.658361 -402.302485) (xy 384.648202 -402.30298)
			(xy 383.931922 -402.30298) (xy 383.921754 -402.302518) (xy 383.902963 -402.294744) (xy 383.888578 -402.28037)
			(xy 383.88079 -402.261586) (xy 383.88036 -402.251418) (xy 383.88036 -401.965414) (xy 383.880168 -401.958541)
			(xy 383.87656 -401.945278) (xy 383.873248 -401.939252) (xy 383.856907 -401.910901) (xy 383.831191 -401.850728)
			(xy 383.813784 -401.787647) (xy 383.805003 -401.7228) (xy 382.516255 -401.7228) (xy 382.506728 -401.739354)
			(xy 382.503432 -401.745388) (xy 382.499814 -401.758644) (xy 382.499616 -401.765516) (xy 382.499616 -402.514816)
			(xy 382.4998 -402.52169) (xy 382.503413 -402.534953) (xy 382.506728 -402.540978) (xy 382.523011 -402.569361)
			(xy 382.548734 -402.629527) (xy 382.566148 -402.692601) (xy 382.574937 -402.757442) (xy 382.574939 -402.790152)
			(xy 386.004308 -402.790152) (xy 386.004874 -402.757422) (xy 386.013729 -402.692564) (xy 386.03122 -402.629484)
			(xy 386.057027 -402.569326) (xy 386.073396 -402.540978) (xy 386.076718 -402.534957) (xy 386.080319 -402.52169)
			(xy 386.080508 -402.514816) (xy 386.080508 -401.765516) (xy 386.080309 -401.758643) (xy 386.076706 -401.74538)
			(xy 386.073396 -401.739354) (xy 386.057012 -401.711015) (xy 386.031214 -401.650852) (xy 386.01373 -401.587769)
			(xy 386.004875 -401.52291) (xy 386.004308 -401.49018) (xy 386.004886 -401.457451) (xy 386.013738 -401.392593)
			(xy 386.031225 -401.329513) (xy 386.057029 -401.269354) (xy 386.073396 -401.241006) (xy 386.076708 -401.23498)
			(xy 386.080316 -401.221717) (xy 386.080508 -401.214844) (xy 386.080508 -400.92884) (xy 386.080949 -400.918719)
			(xy 386.088686 -400.900015) (xy 386.102995 -400.885699) (xy 386.121695 -400.877954) (xy 386.131816 -400.877532)
			(xy 386.848096 -400.877532) (xy 386.858222 -400.87792) (xy 386.876932 -400.885673) (xy 386.891247 -400.899998)
			(xy 386.898987 -400.918714) (xy 386.899404 -400.92884) (xy 386.899404 -401.214844) (xy 386.899617 -401.221716)
			(xy 386.903211 -401.234978) (xy 386.906516 -401.241006) (xy 386.922885 -401.269353) (xy 386.948686 -401.329513)
			(xy 386.966174 -401.392594) (xy 386.975034 -401.457451) (xy 386.975604 -401.49018) (xy 386.975051 -401.52291)
			(xy 386.966192 -401.587769) (xy 386.948698 -401.650849) (xy 386.922887 -401.711007) (xy 386.916076 -401.7228)
			(xy 388.204792 -401.7228) (xy 388.204795 -401.657362) (xy 388.213581 -401.592516) (xy 388.230992 -401.529437)
			(xy 388.256712 -401.469265) (xy 388.273036 -401.440904) (xy 388.276344 -401.434876) (xy 388.279955 -401.421615)
			(xy 388.280148 -401.414742) (xy 388.280148 -400.665442) (xy 388.279947 -400.658569) (xy 388.276346 -400.645306)
			(xy 388.273036 -400.63928) (xy 388.256719 -400.610916) (xy 388.231001 -400.550745) (xy 388.213592 -400.487667)
			(xy 388.204808 -400.422823) (xy 388.204808 -400.357387) (xy 388.21359 -400.292543) (xy 388.230998 -400.229464)
			(xy 388.256714 -400.169293) (xy 388.273036 -400.140932) (xy 388.276334 -400.134899) (xy 388.279951 -400.121642)
			(xy 388.280148 -400.11477) (xy 388.280148 -399.828766) (xy 388.280606 -399.818605) (xy 388.288393 -399.799833)
			(xy 388.30277 -399.785469) (xy 388.321548 -399.777697) (xy 388.33171 -399.777204) (xy 389.04799 -399.777204)
			(xy 389.058143 -399.777741) (xy 389.076905 -399.785506) (xy 389.09127 -399.799858) (xy 389.099051 -399.818613)
			(xy 389.099552 -399.828766) (xy 389.099552 -400.11477) (xy 389.099749 -400.121643) (xy 389.103353 -400.134906)
			(xy 389.106664 -400.140932) (xy 389.122991 -400.16929) (xy 389.148708 -400.229462) (xy 389.166116 -400.292542)
			(xy 389.174898 -400.357387) (xy 389.174898 -400.390106) (xy 392.603744 -400.390106) (xy 392.607735 -400.327939)
			(xy 392.619644 -400.266792) (xy 392.639273 -400.207671) (xy 392.666302 -400.151545) (xy 392.700286 -400.099336)
			(xy 392.740668 -400.051901) (xy 392.786784 -400.01002) (xy 392.837876 -399.97438) (xy 392.893107 -399.945566)
			(xy 392.951569 -399.924052) (xy 393.012303 -399.91019) (xy 393.07431 -399.904208) (xy 393.136573 -399.906204)
			(xy 393.19807 -399.916147) (xy 393.257791 -399.933871) (xy 393.314754 -399.959088) (xy 393.368025 -399.991381)
			(xy 393.41673 -400.030221) (xy 393.460067 -400.074971) (xy 393.497327 -400.124895) (xy 393.527896 -400.179174)
			(xy 393.551274 -400.236917) (xy 393.567075 -400.297175) (xy 393.575041 -400.358958) (xy 393.57554 -400.390106)
			(xy 393.575041 -400.421254) (xy 393.567075 -400.483037) (xy 393.551274 -400.543295) (xy 393.527896 -400.601038)
			(xy 393.497327 -400.655317) (xy 393.460067 -400.705241) (xy 393.41673 -400.749991) (xy 393.368025 -400.788831)
			(xy 393.314754 -400.821124) (xy 393.257791 -400.846341) (xy 393.19807 -400.864065) (xy 393.136573 -400.874008)
			(xy 393.07431 -400.876004) (xy 393.012303 -400.870022) (xy 392.951569 -400.85616) (xy 392.893107 -400.834646)
			(xy 392.837876 -400.805832) (xy 392.786784 -400.770192) (xy 392.740668 -400.728311) (xy 392.700286 -400.680876)
			(xy 392.666302 -400.628667) (xy 392.639273 -400.572541) (xy 392.619644 -400.51342) (xy 392.607735 -400.452273)
			(xy 392.603744 -400.390106) (xy 389.174898 -400.390106) (xy 389.174898 -400.422824) (xy 389.166114 -400.487669)
			(xy 389.148705 -400.550747) (xy 389.122987 -400.610919) (xy 389.106664 -400.63928) (xy 389.103361 -400.645311)
			(xy 389.099747 -400.65857) (xy 389.099552 -400.665442) (xy 389.099552 -401.414742) (xy 389.099759 -401.421614)
			(xy 389.103356 -401.434877) (xy 389.106664 -401.440904) (xy 389.122968 -401.469276) (xy 389.148687 -401.529444)
			(xy 389.166097 -401.592521) (xy 389.174883 -401.657364) (xy 389.174885 -401.722799) (xy 389.166104 -401.787642)
			(xy 389.148699 -401.85072) (xy 389.122985 -401.910891) (xy 389.106664 -401.939252) (xy 389.103336 -401.94527)
			(xy 389.099738 -401.958539) (xy 389.099552 -401.965414) (xy 389.099552 -402.251418) (xy 389.099081 -402.261578)
			(xy 389.091299 -402.28035) (xy 389.076926 -402.294715) (xy 389.05815 -402.302487) (xy 389.04799 -402.30298)
			(xy 388.33171 -402.30298) (xy 388.321555 -402.302459) (xy 388.30279 -402.294691) (xy 388.288425 -402.280334)
			(xy 388.280647 -402.261573) (xy 388.280148 -402.251418) (xy 388.280148 -401.965414) (xy 388.279957 -401.958541)
			(xy 388.276349 -401.945278) (xy 388.273036 -401.939252) (xy 388.256695 -401.910901) (xy 388.23098 -401.850727)
			(xy 388.213574 -401.787647) (xy 388.204792 -401.7228) (xy 386.916076 -401.7228) (xy 386.906516 -401.739354)
			(xy 386.903219 -401.745387) (xy 386.899602 -401.758644) (xy 386.899404 -401.765516) (xy 386.899404 -402.514816)
			(xy 386.899589 -402.52169) (xy 386.903202 -402.534953) (xy 386.906516 -402.540978) (xy 386.922874 -402.569331)
			(xy 386.948678 -402.629489) (xy 386.966169 -402.692568) (xy 386.975032 -402.757423) (xy 386.975604 -402.790152)
			(xy 386.975038 -402.822879) (xy 390.404919 -402.822879) (xy 390.404924 -402.757439) (xy 390.413715 -402.692591)
			(xy 390.431131 -402.62951) (xy 390.456857 -402.569339) (xy 390.473184 -402.540978) (xy 390.476505 -402.534957)
			(xy 390.480107 -402.52169) (xy 390.480296 -402.514816) (xy 390.480296 -401.765516) (xy 390.480098 -401.758643)
			(xy 390.476494 -401.74538) (xy 390.473184 -401.739354) (xy 390.456843 -401.711003) (xy 390.431125 -401.65083)
			(xy 390.413717 -401.587749) (xy 390.404935 -401.522902) (xy 390.404937 -401.457464) (xy 390.413724 -401.392617)
			(xy 390.431136 -401.329538) (xy 390.456859 -401.269367) (xy 390.473184 -401.241006) (xy 390.476495 -401.23498)
			(xy 390.480103 -401.221717) (xy 390.480296 -401.214844) (xy 390.480296 -400.92884) (xy 390.480754 -400.918689)
			(xy 390.488536 -400.899938) (xy 390.502922 -400.885614) (xy 390.521705 -400.877912) (xy 390.531858 -400.877532)
			(xy 391.248138 -400.877532) (xy 391.258266 -400.877995) (xy 391.276987 -400.885734) (xy 391.291341 -400.900027)
			(xy 391.299161 -400.918714) (xy 391.2997 -400.92884) (xy 391.2997 -401.214844) (xy 391.299914 -401.221716)
			(xy 391.303507 -401.234978) (xy 391.306812 -401.241006) (xy 391.323116 -401.269377) (xy 391.348832 -401.329547)
			(xy 391.36624 -401.392623) (xy 391.375025 -401.457466) (xy 391.375027 -401.5229) (xy 391.366247 -401.587743)
			(xy 391.348844 -401.650821) (xy 391.332068 -401.690078) (xy 392.603744 -401.690078) (xy 392.607735 -401.627911)
			(xy 392.619644 -401.566764) (xy 392.639273 -401.507643) (xy 392.666302 -401.451517) (xy 392.700286 -401.399308)
			(xy 392.740668 -401.351873) (xy 392.786784 -401.309992) (xy 392.837876 -401.274352) (xy 392.893107 -401.245538)
			(xy 392.951569 -401.224024) (xy 393.012303 -401.210162) (xy 393.07431 -401.20418) (xy 393.136573 -401.206176)
			(xy 393.19807 -401.216119) (xy 393.257791 -401.233843) (xy 393.314754 -401.25906) (xy 393.368025 -401.291353)
			(xy 393.41673 -401.330193) (xy 393.460067 -401.374943) (xy 393.497327 -401.424867) (xy 393.527896 -401.479146)
			(xy 393.532363 -401.49018) (xy 394.803892 -401.49018) (xy 394.807883 -401.428013) (xy 394.819792 -401.366866)
			(xy 394.839421 -401.307745) (xy 394.86645 -401.251619) (xy 394.900434 -401.19941) (xy 394.940816 -401.151975)
			(xy 394.986932 -401.110094) (xy 395.038024 -401.074454) (xy 395.093255 -401.04564) (xy 395.151717 -401.024126)
			(xy 395.212451 -401.010264) (xy 395.274458 -401.004282) (xy 395.336721 -401.006278) (xy 395.398218 -401.016221)
			(xy 395.457939 -401.033945) (xy 395.514902 -401.059162) (xy 395.568173 -401.091455) (xy 395.616878 -401.130295)
			(xy 395.660215 -401.175045) (xy 395.697475 -401.224969) (xy 395.728044 -401.279248) (xy 395.751422 -401.336991)
			(xy 395.767223 -401.397249) (xy 395.775189 -401.459032) (xy 395.775688 -401.49018) (xy 395.775189 -401.521328)
			(xy 395.767223 -401.583111) (xy 395.751422 -401.643369) (xy 395.728044 -401.701112) (xy 395.697475 -401.755391)
			(xy 395.660215 -401.805315) (xy 395.616878 -401.850065) (xy 395.568173 -401.888905) (xy 395.514902 -401.921198)
			(xy 395.457939 -401.946415) (xy 395.398218 -401.964139) (xy 395.336721 -401.974082) (xy 395.274458 -401.976078)
			(xy 395.212451 -401.970096) (xy 395.151717 -401.956234) (xy 395.093255 -401.93472) (xy 395.038024 -401.905906)
			(xy 394.986932 -401.870266) (xy 394.940816 -401.828385) (xy 394.900434 -401.78095) (xy 394.86645 -401.728741)
			(xy 394.839421 -401.672615) (xy 394.819792 -401.613494) (xy 394.807883 -401.552347) (xy 394.803892 -401.49018)
			(xy 393.532363 -401.49018) (xy 393.551274 -401.536889) (xy 393.567075 -401.597147) (xy 393.575041 -401.65893)
			(xy 393.57554 -401.690078) (xy 393.575041 -401.721226) (xy 393.567075 -401.783009) (xy 393.551274 -401.843267)
			(xy 393.527896 -401.90101) (xy 393.497327 -401.955289) (xy 393.460067 -402.005213) (xy 393.41673 -402.049963)
			(xy 393.368025 -402.088803) (xy 393.314754 -402.121096) (xy 393.257791 -402.146313) (xy 393.19807 -402.164037)
			(xy 393.136573 -402.17398) (xy 393.07431 -402.175976) (xy 393.012303 -402.169994) (xy 392.951569 -402.156132)
			(xy 392.893107 -402.134618) (xy 392.837876 -402.105804) (xy 392.786784 -402.070164) (xy 392.740668 -402.028283)
			(xy 392.700286 -401.980848) (xy 392.666302 -401.928639) (xy 392.639273 -401.872513) (xy 392.619644 -401.813392)
			(xy 392.607735 -401.752245) (xy 392.603744 -401.690078) (xy 391.332068 -401.690078) (xy 391.323131 -401.710992)
			(xy 391.306812 -401.739354) (xy 391.303514 -401.745387) (xy 391.299898 -401.758644) (xy 391.2997 -401.765516)
			(xy 391.2997 -402.514816) (xy 391.299886 -402.52169) (xy 391.303498 -402.534953) (xy 391.306812 -402.540978)
			(xy 391.323092 -402.569362) (xy 391.348811 -402.629529) (xy 391.366221 -402.692602) (xy 391.375009 -402.757442)
			(xy 391.375012 -402.790152) (xy 394.803892 -402.790152) (xy 394.807883 -402.727985) (xy 394.819792 -402.666838)
			(xy 394.839421 -402.607717) (xy 394.86645 -402.551591) (xy 394.900434 -402.499382) (xy 394.940816 -402.451947)
			(xy 394.986932 -402.410066) (xy 395.038024 -402.374426) (xy 395.093255 -402.345612) (xy 395.151717 -402.324098)
			(xy 395.212451 -402.310236) (xy 395.274458 -402.304254) (xy 395.336721 -402.30625) (xy 395.398218 -402.316193)
			(xy 395.457939 -402.333917) (xy 395.514902 -402.359134) (xy 395.568173 -402.391427) (xy 395.616878 -402.430267)
			(xy 395.660215 -402.475017) (xy 395.697475 -402.524941) (xy 395.728044 -402.57922) (xy 395.751422 -402.636963)
			(xy 395.767223 -402.697221) (xy 395.775189 -402.759004) (xy 395.775688 -402.790152) (xy 395.775189 -402.8213)
			(xy 395.767223 -402.883083) (xy 395.751422 -402.943341) (xy 395.728044 -403.001084) (xy 395.697475 -403.055363)
			(xy 395.660215 -403.105287) (xy 395.616878 -403.150037) (xy 395.568173 -403.188877) (xy 395.514902 -403.22117)
			(xy 395.457939 -403.246387) (xy 395.398218 -403.264111) (xy 395.336721 -403.274054) (xy 395.274458 -403.27605)
			(xy 395.212451 -403.270068) (xy 395.151717 -403.256206) (xy 395.093255 -403.234692) (xy 395.038024 -403.205878)
			(xy 394.986932 -403.170238) (xy 394.940816 -403.128357) (xy 394.900434 -403.080922) (xy 394.86645 -403.028713)
			(xy 394.839421 -402.972587) (xy 394.819792 -402.913466) (xy 394.807883 -402.852319) (xy 394.803892 -402.790152)
			(xy 391.375012 -402.790152) (xy 391.375015 -402.822875) (xy 391.366238 -402.887717) (xy 391.348838 -402.950794)
			(xy 391.323129 -403.010964) (xy 391.306812 -403.039326) (xy 391.303489 -403.045347) (xy 391.299888 -403.058613)
			(xy 391.2997 -403.065488) (xy 391.2997 -403.351492) (xy 391.299272 -403.361646) (xy 391.291479 -403.380398)
			(xy 391.277084 -403.394721) (xy 391.258294 -403.402421) (xy 391.248138 -403.4028) (xy 390.531858 -403.4028)
			(xy 390.521734 -403.402309) (xy 390.503019 -403.394575) (xy 390.488666 -403.380291) (xy 390.480841 -403.361614)
			(xy 390.480296 -403.351492) (xy 390.480296 -403.065488) (xy 390.480109 -403.058614) (xy 390.476498 -403.045352)
			(xy 390.473184 -403.039326) (xy 390.45682 -403.010988) (xy 390.431104 -402.950812) (xy 390.413698 -402.887728)
			(xy 390.404919 -402.822879) (xy 386.975038 -402.822879) (xy 386.975038 -402.822882) (xy 386.966182 -402.88774)
			(xy 386.948692 -402.95082) (xy 386.922884 -403.010978) (xy 386.906516 -403.039326) (xy 386.903193 -403.045347)
			(xy 386.899592 -403.058613) (xy 386.899404 -403.065488) (xy 386.899404 -403.351492) (xy 386.898978 -403.361613)
			(xy 386.891233 -403.380316) (xy 386.87692 -403.394631) (xy 386.858217 -403.402377) (xy 386.848096 -403.4028)
			(xy 386.131816 -403.4028) (xy 386.121695 -403.402371) (xy 386.102991 -403.394628) (xy 386.088676 -403.380315)
			(xy 386.080931 -403.361613) (xy 386.080508 -403.351492) (xy 386.080508 -403.065488) (xy 386.08032 -403.058615)
			(xy 386.076709 -403.045352) (xy 386.073396 -403.039326) (xy 386.05704 -403.010971) (xy 386.031236 -402.950814)
			(xy 386.013744 -402.887736) (xy 386.00488 -402.822881) (xy 386.004308 -402.790152) (xy 382.574939 -402.790152)
			(xy 382.574942 -402.822876) (xy 382.566164 -402.887718) (xy 382.548761 -402.950795) (xy 382.523048 -403.010965)
			(xy 382.506728 -403.039326) (xy 382.503406 -403.045347) (xy 382.499804 -403.058614) (xy 382.499616 -403.065488)
			(xy 382.499616 -403.351492) (xy 382.499172 -403.361644) (xy 382.491382 -403.380393) (xy 382.476993 -403.394716)
			(xy 382.458207 -403.402419) (xy 382.448054 -403.4028) (xy 381.731774 -403.4028) (xy 381.721651 -403.402296)
			(xy 381.702936 -403.394567) (xy 381.688582 -403.380287) (xy 381.680757 -403.361613) (xy 381.680212 -403.351492)
			(xy 381.680212 -403.065488) (xy 381.680023 -403.058615) (xy 381.676413 -403.045352) (xy 381.6731 -403.039326)
			(xy 381.656738 -403.010987) (xy 381.631027 -402.95081) (xy 381.613624 -402.887727) (xy 381.604847 -402.822879)
			(xy 378.174953 -402.822879) (xy 378.174953 -402.822881) (xy 378.166097 -402.88774) (xy 378.148607 -402.95082)
			(xy 378.1228 -403.010978) (xy 378.106432 -403.039326) (xy 378.103111 -403.045347) (xy 378.099509 -403.058614)
			(xy 378.09932 -403.065488) (xy 378.09932 -403.351492) (xy 378.098809 -403.361598) (xy 378.091078 -403.380272)
			(xy 378.076789 -403.394566) (xy 378.058118 -403.402305) (xy 378.048012 -403.4028) (xy 377.331732 -403.4028)
			(xy 377.321612 -403.402358) (xy 377.302909 -403.39462) (xy 377.288593 -403.380312) (xy 377.280847 -403.361612)
			(xy 377.280424 -403.351492) (xy 377.280424 -403.065488) (xy 377.280234 -403.058615) (xy 377.276624 -403.045352)
			(xy 377.273312 -403.039326) (xy 377.256958 -403.01097) (xy 377.231153 -402.950813) (xy 377.21366 -402.887736)
			(xy 377.204796 -402.82288) (xy 377.204224 -402.790152) (xy 351.775776 -402.790152) (xy 351.775277 -402.8213)
			(xy 351.767311 -402.883083) (xy 351.75151 -402.943341) (xy 351.728132 -403.001084) (xy 351.697563 -403.055363)
			(xy 351.660303 -403.105287) (xy 351.616966 -403.150037) (xy 351.568261 -403.188877) (xy 351.51499 -403.22117)
			(xy 351.458027 -403.246387) (xy 351.398306 -403.264111) (xy 351.336809 -403.274054) (xy 351.274546 -403.27605)
			(xy 351.212539 -403.270068) (xy 351.151805 -403.256206) (xy 351.093343 -403.234692) (xy 351.038112 -403.205878)
			(xy 350.98702 -403.170238) (xy 350.940904 -403.128357) (xy 350.900522 -403.080922) (xy 350.866538 -403.028713)
			(xy 350.839509 -402.972587) (xy 350.81988 -402.913466) (xy 350.807971 -402.852319) (xy 350.80398 -402.790152)
			(xy 347.375101 -402.790152) (xy 347.375104 -402.822875) (xy 347.366327 -402.887717) (xy 347.348927 -402.950794)
			(xy 347.323218 -403.010964) (xy 347.3069 -403.039326) (xy 347.303576 -403.045346) (xy 347.299976 -403.058613)
			(xy 347.299788 -403.065488) (xy 347.299788 -403.351492) (xy 347.299372 -403.361647) (xy 347.291576 -403.380402)
			(xy 347.277178 -403.394726) (xy 347.258383 -403.402424) (xy 347.248226 -403.4028) (xy 346.531946 -403.4028)
			(xy 346.521827 -403.402237) (xy 346.503115 -403.394532) (xy 346.488758 -403.380269) (xy 346.48093 -403.361607)
			(xy 346.480384 -403.351492) (xy 346.480384 -403.065488) (xy 346.480199 -403.058614) (xy 346.476586 -403.045351)
			(xy 346.473272 -403.039326) (xy 346.456908 -403.010988) (xy 346.431193 -402.950811) (xy 346.413788 -402.887728)
			(xy 346.405009 -402.822879) (xy 342.975128 -402.822879) (xy 342.975128 -402.822882) (xy 342.966272 -402.88774)
			(xy 342.948781 -402.95082) (xy 342.922973 -403.010978) (xy 342.906604 -403.039326) (xy 342.90328 -403.045346)
			(xy 342.89968 -403.058613) (xy 342.899492 -403.065488) (xy 342.899492 -403.351492) (xy 342.899077 -403.361615)
			(xy 342.89133 -403.38032) (xy 342.877013 -403.394635) (xy 342.858307 -403.402379) (xy 342.848184 -403.4028)
			(xy 342.131904 -403.4028) (xy 342.121782 -403.402381) (xy 342.103078 -403.394634) (xy 342.088764 -403.380318)
			(xy 342.081019 -403.361614) (xy 342.080596 -403.351492) (xy 342.080596 -403.065488) (xy 342.080409 -403.058614)
			(xy 342.076798 -403.045352) (xy 342.073484 -403.039326) (xy 342.057127 -403.010972) (xy 342.031324 -402.950814)
			(xy 342.013832 -402.887736) (xy 342.004968 -402.822881) (xy 342.004396 -402.790152) (xy 338.575029 -402.790152)
			(xy 338.575032 -402.822876) (xy 338.566254 -402.887718) (xy 338.54885 -402.950795) (xy 338.523136 -403.010965)
			(xy 338.506816 -403.039326) (xy 338.503493 -403.045347) (xy 338.499892 -403.058613) (xy 338.499704 -403.065488)
			(xy 338.499704 -403.351492) (xy 338.499272 -403.361645) (xy 338.49148 -403.380397) (xy 338.477086 -403.39472)
			(xy 338.458297 -403.402421) (xy 338.448142 -403.4028) (xy 337.731862 -403.4028) (xy 337.721738 -403.402306)
			(xy 337.703023 -403.394573) (xy 337.68867 -403.38029) (xy 337.680845 -403.361614) (xy 337.6803 -403.351492)
			(xy 337.6803 -403.065488) (xy 337.680113 -403.058614) (xy 337.676501 -403.045352) (xy 337.673188 -403.039326)
			(xy 337.656827 -403.010987) (xy 337.631116 -402.95081) (xy 337.613714 -402.887727) (xy 337.604936 -402.822879)
			(xy 334.175042 -402.822879) (xy 334.175042 -402.822881) (xy 334.166186 -402.88774) (xy 334.148696 -402.95082)
			(xy 334.122888 -403.010978) (xy 334.10652 -403.039326) (xy 334.103197 -403.045347) (xy 334.099596 -403.058613)
			(xy 334.099408 -403.065488) (xy 334.099408 -403.351492) (xy 334.098978 -403.361613) (xy 334.091234 -403.380315)
			(xy 334.076922 -403.394629) (xy 334.058221 -403.402376) (xy 334.0481 -403.4028) (xy 333.33182 -403.4028)
			(xy 333.321699 -403.402368) (xy 333.302996 -403.394626) (xy 333.288681 -403.380315) (xy 333.280935 -403.361613)
			(xy 333.280512 -403.351492) (xy 333.280512 -403.065488) (xy 333.280323 -403.058615) (xy 333.276713 -403.045352)
			(xy 333.2734 -403.039326) (xy 333.257045 -403.010971) (xy 333.23124 -402.950814) (xy 333.213748 -402.887736)
			(xy 333.204884 -402.822881) (xy 333.204312 -402.790152) (xy 326.525636 -402.790152) (xy 326.525636 -405.622714)
			(xy 331.005015 -405.622714) (xy 331.005016 -405.557276) (xy 331.013801 -405.492431) (xy 331.03121 -405.429352)
			(xy 331.056929 -405.369181) (xy 331.073252 -405.34082) (xy 331.076556 -405.33479) (xy 331.080169 -405.32153)
			(xy 331.080364 -405.314658) (xy 331.080364 -404.565358) (xy 331.080154 -404.558486) (xy 331.076559 -404.545223)
			(xy 331.073252 -404.539196) (xy 331.056948 -404.510825) (xy 331.031228 -404.450656) (xy 331.013817 -404.387579)
			(xy 331.005031 -404.322737) (xy 331.005029 -404.257301) (xy 331.01381 -404.192458) (xy 331.031215 -404.12938)
			(xy 331.056931 -404.069209) (xy 331.073252 -404.040848) (xy 331.076581 -404.03483) (xy 331.080178 -404.021561)
			(xy 331.080364 -404.014686) (xy 331.080364 -403.728682) (xy 331.08075 -403.718506) (xy 331.088546 -403.699706)
			(xy 331.102943 -403.685321) (xy 331.12175 -403.677541) (xy 331.131926 -403.67712) (xy 331.848206 -403.67712)
			(xy 331.858362 -403.677628) (xy 331.877128 -403.685401) (xy 331.891492 -403.699762) (xy 331.899269 -403.718526)
			(xy 331.899768 -403.728682) (xy 331.899768 -404.014686) (xy 331.899969 -404.021558) (xy 331.903572 -404.034821)
			(xy 331.90688 -404.040848) (xy 331.92322 -404.069199) (xy 331.948935 -404.129373) (xy 331.966341 -404.192454)
			(xy 331.975121 -404.2573) (xy 331.975119 -404.322738) (xy 331.966333 -404.387583) (xy 331.948923 -404.450663)
			(xy 331.923203 -404.510835) (xy 331.90688 -404.539196) (xy 331.903565 -404.545221) (xy 331.89996 -404.558484)
			(xy 331.899768 -404.565358) (xy 331.899768 -405.314658) (xy 331.89998 -405.32153) (xy 331.903575 -405.334792)
			(xy 331.90688 -405.34082) (xy 331.923197 -405.369184) (xy 331.948914 -405.429355) (xy 331.966322 -405.492433)
			(xy 331.975105 -405.557277) (xy 331.975106 -405.622713) (xy 331.966324 -405.687557) (xy 331.948917 -405.750635)
			(xy 331.923201 -405.810807) (xy 331.90688 -405.839168) (xy 331.903575 -405.845197) (xy 331.899964 -405.858458)
			(xy 331.899768 -405.86533) (xy 331.899768 -406.151334) (xy 331.899295 -406.161493) (xy 331.89151 -406.180262)
			(xy 331.877138 -406.194626) (xy 331.858365 -406.2024) (xy 331.848206 -406.202896) (xy 331.131926 -406.202896)
			(xy 331.121774 -406.202346) (xy 331.103012 -406.194587) (xy 331.088647 -406.180238) (xy 331.080865 -406.161485)
			(xy 331.080364 -406.151334) (xy 331.080364 -405.86533) (xy 331.080165 -405.858457) (xy 331.076562 -405.845194)
			(xy 331.073252 -405.839168) (xy 331.056924 -405.81081) (xy 331.031206 -405.750638) (xy 331.013798 -405.687559)
			(xy 331.005015 -405.622714) (xy 326.525636 -405.622714) (xy 326.525636 -406.690068) (xy 333.204312 -406.690068)
			(xy 333.204884 -406.657339) (xy 333.213738 -406.592481) (xy 333.231226 -406.5294) (xy 333.257032 -406.469242)
			(xy 333.2734 -406.440894) (xy 333.276717 -406.43487) (xy 333.280321 -406.421606) (xy 333.280512 -406.414732)
			(xy 333.280512 -405.665432) (xy 333.280307 -405.65856) (xy 333.276707 -405.645297) (xy 333.2734 -405.63927)
			(xy 333.257022 -405.610927) (xy 333.231224 -405.550765) (xy 333.213737 -405.487684) (xy 333.20488 -405.422826)
			(xy 333.204312 -405.390096) (xy 333.204852 -405.357366) (xy 333.213715 -405.292506) (xy 333.231213 -405.229426)
			(xy 333.257028 -405.169269) (xy 333.2734 -405.140922) (xy 333.276707 -405.134894) (xy 333.280317 -405.121633)
			(xy 333.280512 -405.11476) (xy 333.280512 -404.828756) (xy 333.280949 -404.818643) (xy 333.288704 -404.799961)
			(xy 333.303015 -404.785668) (xy 333.321706 -404.777937) (xy 333.33182 -404.777448) (xy 334.0481 -404.777448)
			(xy 334.058202 -404.777984) (xy 334.076871 -404.785712) (xy 334.091163 -404.799993) (xy 334.098907 -404.818654)
			(xy 334.099408 -404.828756) (xy 334.099408 -405.11476) (xy 334.099614 -405.121632) (xy 334.103213 -405.134895)
			(xy 334.10652 -405.140922) (xy 334.122896 -405.169265) (xy 334.148695 -405.229427) (xy 334.166182 -405.292508)
			(xy 334.175039 -405.357367) (xy 334.175608 -405.390096) (xy 334.175062 -405.422826) (xy 334.1662 -405.487685)
			(xy 334.148704 -405.550765) (xy 334.131871 -405.589994) (xy 335.40446 -405.589994) (xy 335.405051 -405.557265)
			(xy 335.4139 -405.492408) (xy 335.431383 -405.429328) (xy 335.457183 -405.369169) (xy 335.473548 -405.34082)
			(xy 335.476851 -405.33479) (xy 335.480465 -405.32153) (xy 335.48066 -405.314658) (xy 335.48066 -404.565358)
			(xy 335.480451 -404.558486) (xy 335.476855 -404.545223) (xy 335.473548 -404.539196) (xy 335.457185 -404.510845)
			(xy 335.431382 -404.450686) (xy 335.413891 -404.387607) (xy 335.40503 -404.322751) (xy 335.40446 -404.290022)
			(xy 335.405018 -404.257292) (xy 335.413877 -404.192434) (xy 335.43137 -404.129354) (xy 335.457179 -404.069196)
			(xy 335.473548 -404.040848) (xy 335.476877 -404.03483) (xy 335.480474 -404.021561) (xy 335.48066 -404.014686)
			(xy 335.48066 -403.728682) (xy 335.481112 -403.718552) (xy 335.48885 -403.699826) (xy 335.503147 -403.68547)
			(xy 335.52184 -403.677655) (xy 335.531968 -403.67712) (xy 336.248248 -403.67712) (xy 336.258408 -403.677483)
			(xy 336.277165 -403.685298) (xy 336.291487 -403.699713) (xy 336.299182 -403.71852) (xy 336.299556 -403.728682)
			(xy 336.299556 -404.014686) (xy 336.299746 -404.021559) (xy 336.303355 -404.034823) (xy 336.306668 -404.040848)
			(xy 336.32305 -404.069188) (xy 336.348848 -404.129351) (xy 336.366334 -404.192433) (xy 336.375189 -404.257292)
			(xy 336.375756 -404.290022) (xy 336.37517 -404.322751) (xy 336.366319 -404.387608) (xy 336.348835 -404.450688)
			(xy 336.323034 -404.510847) (xy 336.306668 -404.539196) (xy 336.303352 -404.54522) (xy 336.299748 -404.558484)
			(xy 336.299556 -404.565358) (xy 336.299556 -405.314658) (xy 336.299757 -405.321531) (xy 336.303358 -405.334794)
			(xy 336.306668 -405.34082) (xy 336.323038 -405.369167) (xy 336.34884 -405.429327) (xy 336.366328 -405.492407)
			(xy 336.375187 -405.557265) (xy 336.375756 -405.589994) (xy 336.375202 -405.622724) (xy 336.366342 -405.687582)
			(xy 336.348848 -405.750662) (xy 336.323038 -405.81082) (xy 336.306668 -405.839168) (xy 336.303362 -405.845197)
			(xy 336.299752 -405.858457) (xy 336.299556 -405.86533) (xy 336.299556 -406.151334) (xy 336.299101 -406.161463)
			(xy 336.291362 -406.180186) (xy 336.277066 -406.194541) (xy 336.258375 -406.202359) (xy 336.248248 -406.202896)
			(xy 335.531968 -406.202896) (xy 335.521811 -406.202505) (xy 335.503057 -406.194698) (xy 335.488735 -406.180292)
			(xy 335.481037 -406.161493) (xy 335.48066 -406.151334) (xy 335.48066 -405.86533) (xy 335.480462 -405.858457)
			(xy 335.476858 -405.845194) (xy 335.473548 -405.839168) (xy 335.457174 -405.810823) (xy 335.431373 -405.750662)
			(xy 335.413886 -405.687581) (xy 335.405028 -405.622723) (xy 335.40446 -405.589994) (xy 334.131871 -405.589994)
			(xy 334.122891 -405.610923) (xy 334.10652 -405.63927) (xy 334.103217 -405.645301) (xy 334.099604 -405.65856)
			(xy 334.099408 -405.665432) (xy 334.099408 -406.414732) (xy 334.099587 -406.421606) (xy 334.103204 -406.434869)
			(xy 334.10652 -406.440894) (xy 334.122885 -406.469243) (xy 334.148687 -406.529403) (xy 334.166176 -406.592482)
			(xy 334.175037 -406.657339) (xy 334.175608 -406.690068) (xy 334.175049 -406.722792) (xy 337.604945 -406.722792)
			(xy 337.604949 -406.657353) (xy 337.613736 -406.592508) (xy 337.631146 -406.529428) (xy 337.656865 -406.469256)
			(xy 337.673188 -406.440894) (xy 337.676504 -406.43487) (xy 337.680109 -406.421606) (xy 337.6803 -406.414732)
			(xy 337.6803 -405.665432) (xy 337.680096 -405.65856) (xy 337.676496 -405.645297) (xy 337.673188 -405.63927)
			(xy 337.656864 -405.61091) (xy 337.631149 -405.550738) (xy 337.613743 -405.487659) (xy 337.604961 -405.422815)
			(xy 337.604962 -405.357378) (xy 337.613745 -405.292534) (xy 337.631152 -405.229455) (xy 337.656867 -405.169284)
			(xy 337.673188 -405.140922) (xy 337.676494 -405.134893) (xy 337.680105 -405.121633) (xy 337.6803 -405.11476)
			(xy 337.6803 -404.828756) (xy 337.680686 -404.818599) (xy 337.688496 -404.799846) (xy 337.702903 -404.785524)
			(xy 337.721703 -404.777826) (xy 337.731862 -404.777448) (xy 338.448142 -404.777448) (xy 338.458272 -404.777892)
			(xy 338.476996 -404.785635) (xy 338.491351 -404.799934) (xy 338.499167 -404.818628) (xy 338.499704 -404.828756)
			(xy 338.499704 -405.11476) (xy 338.499911 -405.121632) (xy 338.503509 -405.134895) (xy 338.506816 -405.140922)
			(xy 338.523136 -405.169285) (xy 338.548857 -405.229455) (xy 338.566267 -405.292533) (xy 338.575051 -405.357378)
			(xy 338.575052 -405.422815) (xy 338.566268 -405.48766) (xy 338.548859 -405.550739) (xy 338.523139 -405.610909)
			(xy 338.516345 -405.622713) (xy 339.805102 -405.622713) (xy 339.805102 -405.557276) (xy 339.813886 -405.492431)
			(xy 339.831295 -405.429353) (xy 339.857013 -405.369181) (xy 339.873336 -405.34082) (xy 339.876639 -405.334789)
			(xy 339.880253 -405.32153) (xy 339.880448 -405.314658) (xy 339.880448 -404.565358) (xy 339.880241 -404.558486)
			(xy 339.876644 -404.545223) (xy 339.873336 -404.539196) (xy 339.857032 -404.510824) (xy 339.831313 -404.450656)
			(xy 339.813903 -404.387579) (xy 339.805117 -404.322736) (xy 339.805115 -404.257301) (xy 339.813896 -404.192458)
			(xy 339.831301 -404.12938) (xy 339.857015 -404.069209) (xy 339.873336 -404.040848) (xy 339.876664 -404.03483)
			(xy 339.880262 -404.021561) (xy 339.880448 -404.014686) (xy 339.880448 -403.728682) (xy 339.880919 -403.718522)
			(xy 339.888701 -403.69975) (xy 339.903074 -403.685385) (xy 339.92185 -403.677613) (xy 339.93201 -403.67712)
			(xy 340.64829 -403.67712) (xy 340.658445 -403.677641) (xy 340.67721 -403.685409) (xy 340.691575 -403.699766)
			(xy 340.699353 -403.718527) (xy 340.699852 -403.728682) (xy 340.699852 -404.014686) (xy 340.700043 -404.021559)
			(xy 340.703651 -404.034822) (xy 340.706964 -404.040848) (xy 340.723305 -404.069199) (xy 340.74902 -404.129373)
			(xy 340.766426 -404.192453) (xy 340.775208 -404.2573) (xy 340.775205 -404.322738) (xy 340.766419 -404.387584)
			(xy 340.749008 -404.450663) (xy 340.723288 -404.510835) (xy 340.706964 -404.539196) (xy 340.703656 -404.545224)
			(xy 340.700045 -404.558485) (xy 340.699852 -404.565358) (xy 340.699852 -405.314658) (xy 340.700053 -405.321531)
			(xy 340.703654 -405.334794) (xy 340.706964 -405.34082) (xy 340.723281 -405.369184) (xy 340.748999 -405.429355)
			(xy 340.766408 -405.492433) (xy 340.775192 -405.557277) (xy 340.775192 -405.622713) (xy 340.76641 -405.687557)
			(xy 340.749002 -405.750636) (xy 340.723286 -405.810807) (xy 340.706964 -405.839168) (xy 340.703666 -405.845201)
			(xy 340.700049 -405.858458) (xy 340.699852 -405.86533) (xy 340.699852 -406.151334) (xy 340.699394 -406.161495)
			(xy 340.691607 -406.180267) (xy 340.67723 -406.194631) (xy 340.658452 -406.202403) (xy 340.64829 -406.202896)
			(xy 339.93201 -406.202896) (xy 339.921857 -406.202359) (xy 339.903095 -406.194594) (xy 339.88873 -406.180242)
			(xy 339.880949 -406.161487) (xy 339.880448 -406.151334) (xy 339.880448 -405.86533) (xy 339.880251 -405.858457)
			(xy 339.876647 -405.845194) (xy 339.873336 -405.839168) (xy 339.857009 -405.81081) (xy 339.831292 -405.750638)
			(xy 339.813884 -405.687558) (xy 339.805102 -405.622713) (xy 338.516345 -405.622713) (xy 338.506816 -405.63927)
			(xy 338.503513 -405.6453) (xy 338.4999 -405.65856) (xy 338.499704 -405.665432) (xy 338.499704 -406.414732)
			(xy 338.499883 -406.421606) (xy 338.5035 -406.434869) (xy 338.506816 -406.440894) (xy 338.523113 -406.46927)
			(xy 338.548835 -406.529437) (xy 338.566248 -406.592513) (xy 338.575036 -406.657355) (xy 338.575037 -406.690068)
			(xy 342.004396 -406.690068) (xy 342.00497 -406.657339) (xy 342.013824 -406.592481) (xy 342.031312 -406.529401)
			(xy 342.057117 -406.469242) (xy 342.073484 -406.440894) (xy 342.0768 -406.43487) (xy 342.080405 -406.421606)
			(xy 342.080596 -406.414732) (xy 342.080596 -405.665432) (xy 342.080392 -405.65856) (xy 342.076792 -405.645297)
			(xy 342.073484 -405.63927) (xy 342.057105 -405.610928) (xy 342.031307 -405.550766) (xy 342.013821 -405.487684)
			(xy 342.004964 -405.422826) (xy 342.004396 -405.390096) (xy 342.004938 -405.357366) (xy 342.013801 -405.292506)
			(xy 342.031298 -405.229426) (xy 342.057112 -405.169269) (xy 342.073484 -405.140922) (xy 342.07679 -405.134893)
			(xy 342.080401 -405.121633) (xy 342.080596 -405.11476) (xy 342.080596 -404.828756) (xy 342.081049 -404.818645)
			(xy 342.0888 -404.799967) (xy 342.103107 -404.785673) (xy 342.121793 -404.77794) (xy 342.131904 -404.777448)
			(xy 342.848184 -404.777448) (xy 342.858285 -404.777997) (xy 342.876953 -404.78572) (xy 342.891247 -404.799996)
			(xy 342.898991 -404.818655) (xy 342.899492 -404.828756) (xy 342.899492 -405.11476) (xy 342.8997 -405.121632)
			(xy 342.903298 -405.134895) (xy 342.906604 -405.140922) (xy 342.922979 -405.169266) (xy 342.948778 -405.229428)
			(xy 342.966265 -405.292509) (xy 342.975123 -405.357367) (xy 342.975692 -405.390096) (xy 342.975148 -405.422826)
			(xy 342.966286 -405.487685) (xy 342.948789 -405.550765) (xy 342.922975 -405.610923) (xy 342.916166 -405.622713)
			(xy 344.204891 -405.622713) (xy 344.204892 -405.557276) (xy 344.213676 -405.492432) (xy 344.231084 -405.429353)
			(xy 344.256802 -405.369181) (xy 344.273124 -405.34082) (xy 344.276433 -405.334793) (xy 344.280042 -405.321531)
			(xy 344.280236 -405.314658) (xy 344.280236 -404.565358) (xy 344.280018 -404.558487) (xy 344.276427 -404.545224)
			(xy 344.273124 -404.539196) (xy 344.256821 -404.510824) (xy 344.231102 -404.450655) (xy 344.213693 -404.387579)
			(xy 344.204907 -404.322736) (xy 344.204905 -404.257301) (xy 344.213685 -404.192458) (xy 344.23109 -404.12938)
			(xy 344.256804 -404.069209) (xy 344.273124 -404.040848) (xy 344.276459 -404.034833) (xy 344.280051 -404.021562)
			(xy 344.280236 -404.014686) (xy 344.280236 -403.728682) (xy 344.280718 -403.718523) (xy 344.288498 -403.699754)
			(xy 344.302867 -403.685389) (xy 344.321639 -403.677615) (xy 344.331798 -403.67712) (xy 345.048078 -403.67712)
			(xy 345.058246 -403.677582) (xy 345.077037 -403.685356) (xy 345.091422 -403.69973) (xy 345.09921 -403.718514)
			(xy 345.09964 -403.728682) (xy 345.09964 -404.014686) (xy 345.099832 -404.021559) (xy 345.10344 -404.034822)
			(xy 345.106752 -404.040848) (xy 345.123093 -404.069199) (xy 345.148809 -404.129372) (xy 345.166216 -404.192453)
			(xy 345.174997 -404.2573) (xy 345.174996 -404.290022) (xy 348.603832 -404.290022) (xy 348.607823 -404.227855)
			(xy 348.619732 -404.166708) (xy 348.639361 -404.107587) (xy 348.66639 -404.051461) (xy 348.700374 -403.999252)
			(xy 348.740756 -403.951817) (xy 348.786872 -403.909936) (xy 348.837964 -403.874296) (xy 348.893195 -403.845482)
			(xy 348.951657 -403.823968) (xy 349.012391 -403.810106) (xy 349.074398 -403.804124) (xy 349.136661 -403.80612)
			(xy 349.198158 -403.816063) (xy 349.257879 -403.833787) (xy 349.314842 -403.859004) (xy 349.368113 -403.891297)
			(xy 349.416818 -403.930137) (xy 349.460155 -403.974887) (xy 349.497415 -404.024811) (xy 349.527984 -404.07909)
			(xy 349.551362 -404.136833) (xy 349.567163 -404.197091) (xy 349.575129 -404.258874) (xy 349.575628 -404.290022)
			(xy 349.575129 -404.32117) (xy 349.567163 -404.382953) (xy 349.551362 -404.443211) (xy 349.527984 -404.500954)
			(xy 349.497415 -404.555233) (xy 349.460155 -404.605157) (xy 349.416818 -404.649907) (xy 349.368113 -404.688747)
			(xy 349.314842 -404.72104) (xy 349.257879 -404.746257) (xy 349.198158 -404.763981) (xy 349.136661 -404.773924)
			(xy 349.074398 -404.77592) (xy 349.012391 -404.769938) (xy 348.951657 -404.756076) (xy 348.893195 -404.734562)
			(xy 348.837964 -404.705748) (xy 348.786872 -404.670108) (xy 348.740756 -404.628227) (xy 348.700374 -404.580792)
			(xy 348.66639 -404.528583) (xy 348.639361 -404.472457) (xy 348.619732 -404.413336) (xy 348.607823 -404.352189)
			(xy 348.603832 -404.290022) (xy 345.174996 -404.290022) (xy 345.174995 -404.322738) (xy 345.166208 -404.387584)
			(xy 345.148797 -404.450663) (xy 345.123076 -404.510835) (xy 345.106752 -404.539196) (xy 345.103443 -404.545223)
			(xy 345.099833 -404.558485) (xy 345.09964 -404.565358) (xy 345.09964 -405.314658) (xy 345.099843 -405.32153)
			(xy 345.103443 -405.334793) (xy 345.106752 -405.34082) (xy 345.123069 -405.369184) (xy 345.148788 -405.429354)
			(xy 345.166197 -405.492433) (xy 345.174981 -405.557277) (xy 345.174982 -405.622713) (xy 345.166199 -405.687557)
			(xy 345.148791 -405.750636) (xy 345.123074 -405.810807) (xy 345.106752 -405.839168) (xy 345.103453 -405.8452)
			(xy 345.099837 -405.858458) (xy 345.09964 -405.86533) (xy 345.09964 -406.151334) (xy 345.099194 -406.161497)
			(xy 345.091404 -406.180271) (xy 345.077024 -406.194636) (xy 345.058241 -406.202405) (xy 345.048078 -406.202896)
			(xy 344.331798 -406.202896) (xy 344.321644 -406.202369) (xy 344.302882 -406.1946) (xy 344.288518 -406.180245)
			(xy 344.280737 -406.161487) (xy 344.280236 -406.151334) (xy 344.280236 -405.86533) (xy 344.280028 -405.858458)
			(xy 344.27643 -405.845195) (xy 344.273124 -405.839168) (xy 344.256797 -405.810809) (xy 344.231081 -405.750637)
			(xy 344.213674 -405.687558) (xy 344.204891 -405.622713) (xy 342.916166 -405.622713) (xy 342.906604 -405.63927)
			(xy 342.9033 -405.6453) (xy 342.899688 -405.65856) (xy 342.899492 -405.665432) (xy 342.899492 -406.414732)
			(xy 342.899673 -406.421606) (xy 342.903289 -406.434869) (xy 342.906604 -406.440894) (xy 342.922968 -406.469244)
			(xy 342.94877 -406.529403) (xy 342.96626 -406.592483) (xy 342.975121 -406.657339) (xy 342.975692 -406.690068)
			(xy 342.975135 -406.722792) (xy 346.405018 -406.722792) (xy 346.405021 -406.657353) (xy 346.41381 -406.592506)
			(xy 346.431223 -406.529426) (xy 346.456947 -406.469255) (xy 346.473272 -406.440894) (xy 346.476587 -406.434869)
			(xy 346.480193 -406.421606) (xy 346.480384 -406.414732) (xy 346.480384 -405.665432) (xy 346.480182 -405.65856)
			(xy 346.476581 -405.645297) (xy 346.473272 -405.63927) (xy 346.456945 -405.610911) (xy 346.431226 -405.55074)
			(xy 346.413817 -405.48766) (xy 346.405034 -405.422815) (xy 346.405034 -405.357378) (xy 346.413819 -405.292533)
			(xy 346.431229 -405.229454) (xy 346.456948 -405.169283) (xy 346.473272 -405.140922) (xy 346.476577 -405.134893)
			(xy 346.480189 -405.121633) (xy 346.480384 -405.11476) (xy 346.480384 -404.828756) (xy 346.480785 -404.818601)
			(xy 346.488592 -404.799851) (xy 346.502995 -404.78553) (xy 346.521789 -404.777829) (xy 346.531946 -404.777448)
			(xy 347.248226 -404.777448) (xy 347.258355 -404.777905) (xy 347.277079 -404.785643) (xy 347.291434 -404.799938)
			(xy 347.299251 -404.818629) (xy 347.299788 -404.828756) (xy 347.299788 -405.11476) (xy 347.299997 -405.121632)
			(xy 347.303594 -405.134895) (xy 347.3069 -405.140922) (xy 347.323218 -405.169286) (xy 347.348933 -405.229457)
			(xy 347.366341 -405.292535) (xy 347.375124 -405.357379) (xy 347.375124 -405.422815) (xy 347.366342 -405.487658)
			(xy 347.348936 -405.550737) (xy 347.332159 -405.589994) (xy 348.603832 -405.589994) (xy 348.607823 -405.527827)
			(xy 348.619732 -405.46668) (xy 348.639361 -405.407559) (xy 348.66639 -405.351433) (xy 348.700374 -405.299224)
			(xy 348.740756 -405.251789) (xy 348.786872 -405.209908) (xy 348.837964 -405.174268) (xy 348.893195 -405.145454)
			(xy 348.951657 -405.12394) (xy 349.012391 -405.110078) (xy 349.074398 -405.104096) (xy 349.136661 -405.106092)
			(xy 349.198158 -405.116035) (xy 349.257879 -405.133759) (xy 349.314842 -405.158976) (xy 349.368113 -405.191269)
			(xy 349.416818 -405.230109) (xy 349.460155 -405.274859) (xy 349.497415 -405.324783) (xy 349.527984 -405.379062)
			(xy 349.532451 -405.390096) (xy 350.80398 -405.390096) (xy 350.807971 -405.327929) (xy 350.81988 -405.266782)
			(xy 350.839509 -405.207661) (xy 350.866538 -405.151535) (xy 350.900522 -405.099326) (xy 350.940904 -405.051891)
			(xy 350.98702 -405.01001) (xy 351.038112 -404.97437) (xy 351.093343 -404.945556) (xy 351.151805 -404.924042)
			(xy 351.212539 -404.91018) (xy 351.274546 -404.904198) (xy 351.336809 -404.906194) (xy 351.398306 -404.916137)
			(xy 351.458027 -404.933861) (xy 351.51499 -404.959078) (xy 351.568261 -404.991371) (xy 351.616966 -405.030211)
			(xy 351.660303 -405.074961) (xy 351.697563 -405.124885) (xy 351.728132 -405.179164) (xy 351.75151 -405.236907)
			(xy 351.767311 -405.297165) (xy 351.775277 -405.358948) (xy 351.775776 -405.390096) (xy 351.775277 -405.421244)
			(xy 351.767311 -405.483027) (xy 351.75151 -405.543285) (xy 351.728132 -405.601028) (xy 351.715919 -405.622714)
			(xy 375.004926 -405.622714) (xy 375.004926 -405.557276) (xy 375.013711 -405.492431) (xy 375.031121 -405.429352)
			(xy 375.056841 -405.369181) (xy 375.073164 -405.34082) (xy 375.076469 -405.33479) (xy 375.080081 -405.321531)
			(xy 375.080276 -405.314658) (xy 375.080276 -404.565358) (xy 375.080065 -404.558486) (xy 375.07647 -404.545223)
			(xy 375.073164 -404.539196) (xy 375.05686 -404.510825) (xy 375.031139 -404.450656) (xy 375.013728 -404.38758)
			(xy 375.004942 -404.322737) (xy 375.004939 -404.257301) (xy 375.01372 -404.192457) (xy 375.031126 -404.12938)
			(xy 375.056842 -404.069209) (xy 375.073164 -404.040848) (xy 375.076494 -404.034831) (xy 375.08009 -404.021561)
			(xy 375.080276 -404.014686) (xy 375.080276 -403.728682) (xy 375.08065 -403.718505) (xy 375.088448 -403.699702)
			(xy 375.102849 -403.685317) (xy 375.12166 -403.677539) (xy 375.131838 -403.67712) (xy 375.848118 -403.67712)
			(xy 375.858275 -403.677618) (xy 375.877041 -403.685395) (xy 375.891405 -403.699759) (xy 375.899182 -403.718525)
			(xy 375.89968 -403.728682) (xy 375.89968 -404.014686) (xy 375.89988 -404.021559) (xy 375.903483 -404.034821)
			(xy 375.906792 -404.040848) (xy 375.923132 -404.069199) (xy 375.948846 -404.129373) (xy 375.966251 -404.192454)
			(xy 375.975032 -404.2573) (xy 375.975029 -404.322738) (xy 375.966243 -404.387583) (xy 375.948834 -404.450663)
			(xy 375.923115 -404.510834) (xy 375.906792 -404.539196) (xy 375.903478 -404.545221) (xy 375.899872 -404.558484)
			(xy 375.89968 -404.565358) (xy 375.89968 -405.314658) (xy 375.89989 -405.32153) (xy 375.903486 -405.334793)
			(xy 375.906792 -405.34082) (xy 375.923108 -405.369184) (xy 375.948825 -405.429355) (xy 375.966232 -405.492433)
			(xy 375.975016 -405.557277) (xy 375.975016 -405.622713) (xy 375.966234 -405.687557) (xy 375.948828 -405.750635)
			(xy 375.923113 -405.810806) (xy 375.906792 -405.839168) (xy 375.903488 -405.845198) (xy 375.899876 -405.858458)
			(xy 375.89968 -405.86533) (xy 375.89968 -406.151334) (xy 375.899195 -406.161492) (xy 375.891413 -406.180258)
			(xy 375.877045 -406.194622) (xy 375.858276 -406.202398) (xy 375.848118 -406.202896) (xy 375.131838 -406.202896)
			(xy 375.121673 -406.202406) (xy 375.102886 -406.19464) (xy 375.088501 -406.180275) (xy 375.080708 -406.161498)
			(xy 375.080276 -406.151334) (xy 375.080276 -405.86533) (xy 375.080075 -405.858457) (xy 375.076473 -405.845194)
			(xy 375.073164 -405.839168) (xy 375.056836 -405.81081) (xy 375.031117 -405.750638) (xy 375.013709 -405.687559)
			(xy 375.004926 -405.622714) (xy 351.715919 -405.622714) (xy 351.697563 -405.655307) (xy 351.660303 -405.705231)
			(xy 351.616966 -405.749981) (xy 351.568261 -405.788821) (xy 351.51499 -405.821114) (xy 351.458027 -405.846331)
			(xy 351.398306 -405.864055) (xy 351.336809 -405.873998) (xy 351.274546 -405.875994) (xy 351.212539 -405.870012)
			(xy 351.151805 -405.85615) (xy 351.093343 -405.834636) (xy 351.038112 -405.805822) (xy 350.98702 -405.770182)
			(xy 350.940904 -405.728301) (xy 350.900522 -405.680866) (xy 350.866538 -405.628657) (xy 350.839509 -405.572531)
			(xy 350.81988 -405.51341) (xy 350.807971 -405.452263) (xy 350.80398 -405.390096) (xy 349.532451 -405.390096)
			(xy 349.551362 -405.436805) (xy 349.567163 -405.497063) (xy 349.575129 -405.558846) (xy 349.575628 -405.589994)
			(xy 349.575129 -405.621142) (xy 349.567163 -405.682925) (xy 349.551362 -405.743183) (xy 349.527984 -405.800926)
			(xy 349.497415 -405.855205) (xy 349.460155 -405.905129) (xy 349.416818 -405.949879) (xy 349.368113 -405.988719)
			(xy 349.314842 -406.021012) (xy 349.257879 -406.046229) (xy 349.198158 -406.063953) (xy 349.136661 -406.073896)
			(xy 349.074398 -406.075892) (xy 349.012391 -406.06991) (xy 348.951657 -406.056048) (xy 348.893195 -406.034534)
			(xy 348.837964 -406.00572) (xy 348.786872 -405.97008) (xy 348.740756 -405.928199) (xy 348.700374 -405.880764)
			(xy 348.66639 -405.828555) (xy 348.639361 -405.772429) (xy 348.619732 -405.713308) (xy 348.607823 -405.652161)
			(xy 348.603832 -405.589994) (xy 347.332159 -405.589994) (xy 347.323221 -405.610908) (xy 347.3069 -405.63927)
			(xy 347.303596 -405.6453) (xy 347.299984 -405.65856) (xy 347.299788 -405.665432) (xy 347.299788 -406.414732)
			(xy 347.299969 -406.421606) (xy 347.303585 -406.434869) (xy 347.3069 -406.440894) (xy 347.323194 -406.469271)
			(xy 347.348912 -406.529439) (xy 347.366322 -406.592514) (xy 347.375108 -406.657356) (xy 347.37511 -406.690068)
			(xy 350.80398 -406.690068) (xy 350.807971 -406.627901) (xy 350.81988 -406.566754) (xy 350.839509 -406.507633)
			(xy 350.866538 -406.451507) (xy 350.900522 -406.399298) (xy 350.940904 -406.351863) (xy 350.98702 -406.309982)
			(xy 351.038112 -406.274342) (xy 351.093343 -406.245528) (xy 351.151805 -406.224014) (xy 351.212539 -406.210152)
			(xy 351.274546 -406.20417) (xy 351.336809 -406.206166) (xy 351.398306 -406.216109) (xy 351.458027 -406.233833)
			(xy 351.51499 -406.25905) (xy 351.568261 -406.291343) (xy 351.616966 -406.330183) (xy 351.660303 -406.374933)
			(xy 351.697563 -406.424857) (xy 351.728132 -406.479136) (xy 351.75151 -406.536879) (xy 351.767311 -406.597137)
			(xy 351.775277 -406.65892) (xy 351.775776 -406.690068) (xy 377.204224 -406.690068) (xy 377.204795 -406.657339)
			(xy 377.213648 -406.59248) (xy 377.231137 -406.5294) (xy 377.256944 -406.469242) (xy 377.273312 -406.440894)
			(xy 377.27663 -406.434871) (xy 377.280233 -406.421606) (xy 377.280424 -406.414732) (xy 377.280424 -405.665432)
			(xy 377.280217 -405.65856) (xy 377.276619 -405.645297) (xy 377.273312 -405.63927) (xy 377.256936 -405.610927)
			(xy 377.231136 -405.550765) (xy 377.213649 -405.487684) (xy 377.204793 -405.422826) (xy 377.204224 -405.390096)
			(xy 377.204762 -405.357365) (xy 377.213626 -405.292506) (xy 377.231124 -405.229426) (xy 377.25694 -405.169269)
			(xy 377.273312 -405.140922) (xy 377.27662 -405.134894) (xy 377.28023 -405.121633) (xy 377.280424 -405.11476)
			(xy 377.280424 -404.828756) (xy 377.28085 -404.818641) (xy 377.288606 -404.799958) (xy 377.302922 -404.785664)
			(xy 377.321617 -404.777935) (xy 377.331732 -404.777448) (xy 378.048012 -404.777448) (xy 378.058115 -404.777974)
			(xy 378.076783 -404.785706) (xy 378.091076 -404.79999) (xy 378.098819 -404.818653) (xy 378.09932 -404.828756)
			(xy 378.09932 -405.11476) (xy 378.099525 -405.121632) (xy 378.103124 -405.134895) (xy 378.106432 -405.140922)
			(xy 378.1228 -405.16927) (xy 378.148603 -405.22943) (xy 378.166092 -405.292509) (xy 378.174951 -405.357367)
			(xy 378.17552 -405.390096) (xy 378.174972 -405.422826) (xy 378.166111 -405.487685) (xy 378.148615 -405.550765)
			(xy 378.131783 -405.589994) (xy 379.404372 -405.589994) (xy 379.404961 -405.557265) (xy 379.413811 -405.492408)
			(xy 379.431294 -405.429328) (xy 379.457095 -405.369169) (xy 379.47346 -405.34082) (xy 379.476764 -405.33479)
			(xy 379.480377 -405.321531) (xy 379.480572 -405.314658) (xy 379.480572 -404.565358) (xy 379.480361 -404.558486)
			(xy 379.476766 -404.545223) (xy 379.47346 -404.539196) (xy 379.457099 -404.510844) (xy 379.431294 -404.450686)
			(xy 379.413803 -404.387607) (xy 379.404942 -404.322751) (xy 379.404372 -404.290022) (xy 379.404929 -404.257292)
			(xy 379.413788 -404.192434) (xy 379.431281 -404.129354) (xy 379.45709 -404.069196) (xy 379.47346 -404.040848)
			(xy 379.47679 -404.034831) (xy 379.480386 -404.021561) (xy 379.480572 -404.014686) (xy 379.480572 -403.728682)
			(xy 379.481013 -403.71855) (xy 379.488752 -403.699822) (xy 379.503053 -403.685466) (xy 379.52175 -403.677653)
			(xy 379.53188 -403.67712) (xy 380.24816 -403.67712) (xy 380.258314 -403.677555) (xy 380.277069 -403.685341)
			(xy 380.291395 -403.699734) (xy 380.299092 -403.718526) (xy 380.299468 -403.728682) (xy 380.299468 -404.014686)
			(xy 380.299669 -404.021558) (xy 380.303272 -404.034821) (xy 380.30658 -404.040848) (xy 380.322963 -404.069188)
			(xy 380.348761 -404.129351) (xy 380.366246 -404.192433) (xy 380.375101 -404.257292) (xy 380.375668 -404.290022)
			(xy 380.375081 -404.322751) (xy 380.36623 -404.387608) (xy 380.348746 -404.450688) (xy 380.322945 -404.510847)
			(xy 380.30658 -404.539196) (xy 380.303265 -404.545221) (xy 380.29966 -404.558484) (xy 380.299468 -404.565358)
			(xy 380.299468 -405.314658) (xy 380.29968 -405.32153) (xy 380.303275 -405.334792) (xy 380.30658 -405.34082)
			(xy 380.322952 -405.369166) (xy 380.348752 -405.429327) (xy 380.36624 -405.492407) (xy 380.375099 -405.557265)
			(xy 380.375668 -405.589994) (xy 380.375113 -405.622724) (xy 380.366252 -405.687582) (xy 380.348759 -405.750662)
			(xy 380.322949 -405.81082) (xy 380.30658 -405.839168) (xy 380.303275 -405.845197) (xy 380.299664 -405.858458)
			(xy 380.299468 -405.86533) (xy 380.299468 -406.151334) (xy 380.299002 -406.161462) (xy 380.291264 -406.180182)
			(xy 380.276972 -406.194537) (xy 380.258286 -406.202357) (xy 380.24816 -406.202896) (xy 379.53188 -406.202896)
			(xy 379.521724 -406.202495) (xy 379.50297 -406.194692) (xy 379.488648 -406.180289) (xy 379.480949 -406.161492)
			(xy 379.480572 -406.151334) (xy 379.480572 -405.86533) (xy 379.480372 -405.858457) (xy 379.47677 -405.845194)
			(xy 379.47346 -405.839168) (xy 379.457087 -405.810823) (xy 379.431286 -405.750662) (xy 379.413798 -405.687581)
			(xy 379.40494 -405.622723) (xy 379.404372 -405.589994) (xy 378.131783 -405.589994) (xy 378.122803 -405.610923)
			(xy 378.106432 -405.63927) (xy 378.103131 -405.645301) (xy 378.099516 -405.65856) (xy 378.09932 -405.665432)
			(xy 378.09932 -406.414732) (xy 378.099497 -406.421606) (xy 378.103115 -406.434869) (xy 378.106432 -406.440894)
			(xy 378.122789 -406.469248) (xy 378.148594 -406.529405) (xy 378.166087 -406.592483) (xy 378.174949 -406.657339)
			(xy 378.17552 -406.690068) (xy 378.17496 -406.722792) (xy 381.604856 -406.722792) (xy 381.604859 -406.657353)
			(xy 381.613646 -406.592508) (xy 381.631057 -406.529428) (xy 381.656777 -406.469256) (xy 381.6731 -406.440894)
			(xy 381.676417 -406.43487) (xy 381.680021 -406.421606) (xy 381.680212 -406.414732) (xy 381.680212 -405.665432)
			(xy 381.680007 -405.65856) (xy 381.676407 -405.645297) (xy 381.6731 -405.63927) (xy 381.656776 -405.61091)
			(xy 381.63106 -405.550738) (xy 381.613654 -405.487659) (xy 381.604872 -405.422815) (xy 381.604872 -405.357378)
			(xy 381.613655 -405.292534) (xy 381.631063 -405.229455) (xy 381.656779 -405.169284) (xy 381.6731 -405.140922)
			(xy 381.676407 -405.134894) (xy 381.680017 -405.121633) (xy 381.680212 -405.11476) (xy 381.680212 -404.828756)
			(xy 381.680586 -404.818598) (xy 381.688398 -404.799842) (xy 381.702809 -404.78552) (xy 381.721613 -404.777824)
			(xy 381.731774 -404.777448) (xy 382.448054 -404.777448) (xy 382.458179 -404.777965) (xy 382.4769 -404.785679)
			(xy 382.491258 -404.799956) (xy 382.499078 -404.818634) (xy 382.499616 -404.828756) (xy 382.499616 -405.11476)
			(xy 382.499821 -405.121632) (xy 382.50342 -405.134895) (xy 382.506728 -405.140922) (xy 382.523048 -405.169285)
			(xy 382.548768 -405.229455) (xy 382.566177 -405.292534) (xy 382.574962 -405.357378) (xy 382.574962 -405.422815)
			(xy 382.566179 -405.48766) (xy 382.54877 -405.550738) (xy 382.523051 -405.610909) (xy 382.516257 -405.622713)
			(xy 383.805012 -405.622713) (xy 383.805013 -405.557276) (xy 383.813797 -405.492431) (xy 383.831206 -405.429352)
			(xy 383.856925 -405.369181) (xy 383.873248 -405.34082) (xy 383.876551 -405.33479) (xy 383.880165 -405.32153)
			(xy 383.88036 -405.314658) (xy 383.88036 -404.565358) (xy 383.880151 -404.558486) (xy 383.876555 -404.545223)
			(xy 383.873248 -404.539196) (xy 383.856944 -404.510825) (xy 383.831224 -404.450656) (xy 383.813814 -404.387579)
			(xy 383.805028 -404.322737) (xy 383.805025 -404.257301) (xy 383.813806 -404.192458) (xy 383.831212 -404.12938)
			(xy 383.856927 -404.069209) (xy 383.873248 -404.040848) (xy 383.876577 -404.03483) (xy 383.880174 -404.021561)
			(xy 383.88036 -404.014686) (xy 383.88036 -403.728682) (xy 383.88075 -403.718507) (xy 383.888545 -403.699707)
			(xy 383.902941 -403.685322) (xy 383.921746 -403.677542) (xy 383.931922 -403.67712) (xy 384.648202 -403.67712)
			(xy 384.658358 -403.677631) (xy 384.677123 -403.685403) (xy 384.691488 -403.699763) (xy 384.699265 -403.718526)
			(xy 384.699764 -403.728682) (xy 384.699764 -404.014686) (xy 384.699966 -404.021558) (xy 384.703568 -404.034821)
			(xy 384.706876 -404.040848) (xy 384.723216 -404.069199) (xy 384.748931 -404.129373) (xy 384.766337 -404.192454)
			(xy 384.775118 -404.2573) (xy 384.775115 -404.322738) (xy 384.766329 -404.387583) (xy 384.748919 -404.450663)
			(xy 384.723199 -404.510835) (xy 384.706876 -404.539196) (xy 384.703561 -404.54522) (xy 384.699956 -404.558484)
			(xy 384.699764 -404.565358) (xy 384.699764 -405.314658) (xy 384.699976 -405.32153) (xy 384.703571 -405.334792)
			(xy 384.706876 -405.34082) (xy 384.723193 -405.369184) (xy 384.74891 -405.429355) (xy 384.766318 -405.492433)
			(xy 384.775102 -405.557277) (xy 384.775103 -405.622713) (xy 384.76632 -405.687557) (xy 384.748913 -405.750635)
			(xy 384.723197 -405.810807) (xy 384.706876 -405.839168) (xy 384.703571 -405.845197) (xy 384.69996 -405.858457)
			(xy 384.699764 -405.86533) (xy 384.699764 -406.151334) (xy 384.699295 -406.161494) (xy 384.691509 -406.180263)
			(xy 384.677136 -406.194627) (xy 384.658362 -406.202401) (xy 384.648202 -406.202896) (xy 383.931922 -406.202896)
			(xy 383.92177 -406.20235) (xy 383.903008 -406.194589) (xy 383.888643 -406.180239) (xy 383.880861 -406.161486)
			(xy 383.88036 -406.151334) (xy 383.88036 -405.86533) (xy 383.880162 -405.858457) (xy 383.876558 -405.845194)
			(xy 383.873248 -405.839168) (xy 383.85692 -405.81081) (xy 383.831203 -405.750638) (xy 383.813795 -405.687559)
			(xy 383.805012 -405.622713) (xy 382.516257 -405.622713) (xy 382.506728 -405.63927) (xy 382.503426 -405.645301)
			(xy 382.499812 -405.65856) (xy 382.499616 -405.665432) (xy 382.499616 -406.414732) (xy 382.499794 -406.421606)
			(xy 382.503411 -406.434869) (xy 382.506728 -406.440894) (xy 382.523024 -406.46927) (xy 382.548746 -406.529437)
			(xy 382.566158 -406.592513) (xy 382.574946 -406.657355) (xy 382.574948 -406.690068) (xy 386.004308 -406.690068)
			(xy 386.004881 -406.657339) (xy 386.013734 -406.592481) (xy 386.031223 -406.5294) (xy 386.057028 -406.469242)
			(xy 386.073396 -406.440894) (xy 386.076713 -406.43487) (xy 386.080317 -406.421606) (xy 386.080508 -406.414732)
			(xy 386.080508 -405.665432) (xy 386.080303 -405.65856) (xy 386.076704 -405.645297) (xy 386.073396 -405.63927)
			(xy 386.057018 -405.610928) (xy 386.031219 -405.550766) (xy 386.013733 -405.487684) (xy 386.004876 -405.422826)
			(xy 386.004308 -405.390096) (xy 386.004848 -405.357366) (xy 386.013711 -405.292506) (xy 386.031209 -405.229426)
			(xy 386.057024 -405.169269) (xy 386.073396 -405.140922) (xy 386.076703 -405.134893) (xy 386.080313 -405.121633)
			(xy 386.080508 -405.11476) (xy 386.080508 -404.828756) (xy 386.080949 -404.818643) (xy 386.088703 -404.799963)
			(xy 386.103013 -404.785669) (xy 386.121703 -404.777938) (xy 386.131816 -404.777448) (xy 386.848096 -404.777448)
			(xy 386.858198 -404.777987) (xy 386.876866 -404.785714) (xy 386.891159 -404.799993) (xy 386.898903 -404.818654)
			(xy 386.899404 -404.828756) (xy 386.899404 -405.11476) (xy 386.899611 -405.121632) (xy 386.903209 -405.134895)
			(xy 386.906516 -405.140922) (xy 386.922892 -405.169266) (xy 386.948691 -405.229427) (xy 386.966178 -405.292508)
			(xy 386.975035 -405.357367) (xy 386.975604 -405.390096) (xy 386.975059 -405.422826) (xy 386.966197 -405.487685)
			(xy 386.948701 -405.550765) (xy 386.922888 -405.610923) (xy 386.916079 -405.622713) (xy 388.204802 -405.622713)
			(xy 388.204802 -405.557276) (xy 388.213586 -405.492431) (xy 388.230995 -405.429353) (xy 388.256713 -405.369181)
			(xy 388.273036 -405.34082) (xy 388.276339 -405.334789) (xy 388.279953 -405.32153) (xy 388.280148 -405.314658)
			(xy 388.280148 -404.565358) (xy 388.279941 -404.558486) (xy 388.276344 -404.545223) (xy 388.273036 -404.539196)
			(xy 388.256732 -404.510824) (xy 388.231013 -404.450656) (xy 388.213603 -404.387579) (xy 388.204817 -404.322736)
			(xy 388.204815 -404.257301) (xy 388.213596 -404.192458) (xy 388.231001 -404.12938) (xy 388.256715 -404.069209)
			(xy 388.273036 -404.040848) (xy 388.276364 -404.03483) (xy 388.279962 -404.021561) (xy 388.280148 -404.014686)
			(xy 388.280148 -403.728682) (xy 388.280619 -403.718522) (xy 388.288401 -403.69975) (xy 388.302774 -403.685385)
			(xy 388.32155 -403.677613) (xy 388.33171 -403.67712) (xy 389.04799 -403.67712) (xy 389.058145 -403.677641)
			(xy 389.07691 -403.685409) (xy 389.091275 -403.699766) (xy 389.099053 -403.718527) (xy 389.099552 -403.728682)
			(xy 389.099552 -404.014686) (xy 389.099743 -404.021559) (xy 389.103351 -404.034822) (xy 389.106664 -404.040848)
			(xy 389.123005 -404.069199) (xy 389.14872 -404.129373) (xy 389.166126 -404.192453) (xy 389.174908 -404.2573)
			(xy 389.174906 -404.290022) (xy 392.603744 -404.290022) (xy 392.607735 -404.227855) (xy 392.619644 -404.166708)
			(xy 392.639273 -404.107587) (xy 392.666302 -404.051461) (xy 392.700286 -403.999252) (xy 392.740668 -403.951817)
			(xy 392.786784 -403.909936) (xy 392.837876 -403.874296) (xy 392.893107 -403.845482) (xy 392.951569 -403.823968)
			(xy 393.012303 -403.810106) (xy 393.07431 -403.804124) (xy 393.136573 -403.80612) (xy 393.19807 -403.816063)
			(xy 393.257791 -403.833787) (xy 393.314754 -403.859004) (xy 393.368025 -403.891297) (xy 393.41673 -403.930137)
			(xy 393.460067 -403.974887) (xy 393.497327 -404.024811) (xy 393.527896 -404.07909) (xy 393.551274 -404.136833)
			(xy 393.567075 -404.197091) (xy 393.575041 -404.258874) (xy 393.57554 -404.290022) (xy 393.575041 -404.32117)
			(xy 393.567075 -404.382953) (xy 393.551274 -404.443211) (xy 393.527896 -404.500954) (xy 393.497327 -404.555233)
			(xy 393.460067 -404.605157) (xy 393.41673 -404.649907) (xy 393.368025 -404.688747) (xy 393.314754 -404.72104)
			(xy 393.257791 -404.746257) (xy 393.19807 -404.763981) (xy 393.136573 -404.773924) (xy 393.07431 -404.77592)
			(xy 393.012303 -404.769938) (xy 392.951569 -404.756076) (xy 392.893107 -404.734562) (xy 392.837876 -404.705748)
			(xy 392.786784 -404.670108) (xy 392.740668 -404.628227) (xy 392.700286 -404.580792) (xy 392.666302 -404.528583)
			(xy 392.639273 -404.472457) (xy 392.619644 -404.413336) (xy 392.607735 -404.352189) (xy 392.603744 -404.290022)
			(xy 389.174906 -404.290022) (xy 389.174905 -404.322738) (xy 389.166119 -404.387584) (xy 389.148708 -404.450663)
			(xy 389.122988 -404.510835) (xy 389.106664 -404.539196) (xy 389.103356 -404.545224) (xy 389.099745 -404.558485)
			(xy 389.099552 -404.565358) (xy 389.099552 -405.314658) (xy 389.099753 -405.321531) (xy 389.103354 -405.334794)
			(xy 389.106664 -405.34082) (xy 389.122981 -405.369184) (xy 389.148699 -405.429355) (xy 389.166108 -405.492433)
			(xy 389.174892 -405.557277) (xy 389.174892 -405.622713) (xy 389.16611 -405.687557) (xy 389.148702 -405.750636)
			(xy 389.122986 -405.810807) (xy 389.106664 -405.839168) (xy 389.103366 -405.845201) (xy 389.099749 -405.858458)
			(xy 389.099552 -405.86533) (xy 389.099552 -406.151334) (xy 389.099094 -406.161495) (xy 389.091307 -406.180267)
			(xy 389.07693 -406.194631) (xy 389.058152 -406.202403) (xy 389.04799 -406.202896) (xy 388.33171 -406.202896)
			(xy 388.321557 -406.202359) (xy 388.302795 -406.194594) (xy 388.28843 -406.180242) (xy 388.280649 -406.161487)
			(xy 388.280148 -406.151334) (xy 388.280148 -405.86533) (xy 388.279951 -405.858457) (xy 388.276347 -405.845194)
			(xy 388.273036 -405.839168) (xy 388.256709 -405.81081) (xy 388.230992 -405.750638) (xy 388.213584 -405.687558)
			(xy 388.204802 -405.622713) (xy 386.916079 -405.622713) (xy 386.906516 -405.63927) (xy 386.903213 -405.6453)
			(xy 386.8996 -405.65856) (xy 386.899404 -405.665432) (xy 386.899404 -406.414732) (xy 386.899583 -406.421606)
			(xy 386.9032 -406.434869) (xy 386.906516 -406.440894) (xy 386.922881 -406.469244) (xy 386.948682 -406.529403)
			(xy 386.966172 -406.592482) (xy 386.975033 -406.657339) (xy 386.975604 -406.690068) (xy 386.975046 -406.722792)
			(xy 390.404928 -406.722792) (xy 390.404932 -406.657353) (xy 390.41372 -406.592506) (xy 390.431134 -406.529426)
			(xy 390.456858 -406.469255) (xy 390.473184 -406.440894) (xy 390.4765 -406.43487) (xy 390.480105 -406.421606)
			(xy 390.480296 -406.414732) (xy 390.480296 -405.665432) (xy 390.480092 -405.65856) (xy 390.476492 -405.645297)
			(xy 390.473184 -405.63927) (xy 390.456857 -405.610911) (xy 390.431137 -405.55074) (xy 390.413728 -405.487661)
			(xy 390.404944 -405.422815) (xy 390.404944 -405.357378) (xy 390.413729 -405.292533) (xy 390.43114 -405.229454)
			(xy 390.45686 -405.169283) (xy 390.473184 -405.140922) (xy 390.47649 -405.134893) (xy 390.480101 -405.121633)
			(xy 390.480296 -405.11476) (xy 390.480296 -404.828756) (xy 390.480686 -404.8186) (xy 390.488495 -404.799847)
			(xy 390.502901 -404.785525) (xy 390.521699 -404.777826) (xy 390.531858 -404.777448) (xy 391.248138 -404.777448)
			(xy 391.258268 -404.777896) (xy 391.276992 -404.785637) (xy 391.291347 -404.799935) (xy 391.299163 -404.818628)
			(xy 391.2997 -404.828756) (xy 391.2997 -405.11476) (xy 391.299907 -405.121632) (xy 391.303505 -405.134895)
			(xy 391.306812 -405.140922) (xy 391.323129 -405.169286) (xy 391.348844 -405.229457) (xy 391.366251 -405.292535)
			(xy 391.375034 -405.357379) (xy 391.375035 -405.422814) (xy 391.366252 -405.487658) (xy 391.348847 -405.550737)
			(xy 391.33207 -405.589994) (xy 392.603744 -405.589994) (xy 392.607735 -405.527827) (xy 392.619644 -405.46668)
			(xy 392.639273 -405.407559) (xy 392.666302 -405.351433) (xy 392.700286 -405.299224) (xy 392.740668 -405.251789)
			(xy 392.786784 -405.209908) (xy 392.837876 -405.174268) (xy 392.893107 -405.145454) (xy 392.951569 -405.12394)
			(xy 393.012303 -405.110078) (xy 393.07431 -405.104096) (xy 393.136573 -405.106092) (xy 393.19807 -405.116035)
			(xy 393.257791 -405.133759) (xy 393.314754 -405.158976) (xy 393.368025 -405.191269) (xy 393.41673 -405.230109)
			(xy 393.460067 -405.274859) (xy 393.497327 -405.324783) (xy 393.527896 -405.379062) (xy 393.532363 -405.390096)
			(xy 394.803892 -405.390096) (xy 394.807883 -405.327929) (xy 394.819792 -405.266782) (xy 394.839421 -405.207661)
			(xy 394.86645 -405.151535) (xy 394.900434 -405.099326) (xy 394.940816 -405.051891) (xy 394.986932 -405.01001)
			(xy 395.038024 -404.97437) (xy 395.093255 -404.945556) (xy 395.151717 -404.924042) (xy 395.212451 -404.91018)
			(xy 395.274458 -404.904198) (xy 395.336721 -404.906194) (xy 395.398218 -404.916137) (xy 395.457939 -404.933861)
			(xy 395.514902 -404.959078) (xy 395.568173 -404.991371) (xy 395.616878 -405.030211) (xy 395.660215 -405.074961)
			(xy 395.697475 -405.124885) (xy 395.728044 -405.179164) (xy 395.751422 -405.236907) (xy 395.767223 -405.297165)
			(xy 395.775189 -405.358948) (xy 395.775688 -405.390096) (xy 395.775189 -405.421244) (xy 395.767223 -405.483027)
			(xy 395.751422 -405.543285) (xy 395.728044 -405.601028) (xy 395.697475 -405.655307) (xy 395.660215 -405.705231)
			(xy 395.616878 -405.749981) (xy 395.568173 -405.788821) (xy 395.514902 -405.821114) (xy 395.457939 -405.846331)
			(xy 395.398218 -405.864055) (xy 395.336721 -405.873998) (xy 395.274458 -405.875994) (xy 395.212451 -405.870012)
			(xy 395.151717 -405.85615) (xy 395.093255 -405.834636) (xy 395.038024 -405.805822) (xy 394.986932 -405.770182)
			(xy 394.940816 -405.728301) (xy 394.900434 -405.680866) (xy 394.86645 -405.628657) (xy 394.839421 -405.572531)
			(xy 394.819792 -405.51341) (xy 394.807883 -405.452263) (xy 394.803892 -405.390096) (xy 393.532363 -405.390096)
			(xy 393.551274 -405.436805) (xy 393.567075 -405.497063) (xy 393.575041 -405.558846) (xy 393.57554 -405.589994)
			(xy 393.575041 -405.621142) (xy 393.567075 -405.682925) (xy 393.551274 -405.743183) (xy 393.527896 -405.800926)
			(xy 393.497327 -405.855205) (xy 393.460067 -405.905129) (xy 393.41673 -405.949879) (xy 393.368025 -405.988719)
			(xy 393.314754 -406.021012) (xy 393.257791 -406.046229) (xy 393.19807 -406.063953) (xy 393.136573 -406.073896)
			(xy 393.07431 -406.075892) (xy 393.012303 -406.06991) (xy 392.951569 -406.056048) (xy 392.893107 -406.034534)
			(xy 392.837876 -406.00572) (xy 392.786784 -405.97008) (xy 392.740668 -405.928199) (xy 392.700286 -405.880764)
			(xy 392.666302 -405.828555) (xy 392.639273 -405.772429) (xy 392.619644 -405.713308) (xy 392.607735 -405.652161)
			(xy 392.603744 -405.589994) (xy 391.33207 -405.589994) (xy 391.323132 -405.610908) (xy 391.306812 -405.63927)
			(xy 391.303509 -405.6453) (xy 391.299896 -405.65856) (xy 391.2997 -405.665432) (xy 391.2997 -406.414732)
			(xy 391.29988 -406.421606) (xy 391.303496 -406.434869) (xy 391.306812 -406.440894) (xy 391.323106 -406.469271)
			(xy 391.348823 -406.529439) (xy 391.366232 -406.592514) (xy 391.375018 -406.657356) (xy 391.37502 -406.690068)
			(xy 394.803892 -406.690068) (xy 394.807883 -406.627901) (xy 394.819792 -406.566754) (xy 394.839421 -406.507633)
			(xy 394.86645 -406.451507) (xy 394.900434 -406.399298) (xy 394.940816 -406.351863) (xy 394.986932 -406.309982)
			(xy 395.038024 -406.274342) (xy 395.093255 -406.245528) (xy 395.151717 -406.224014) (xy 395.212451 -406.210152)
			(xy 395.274458 -406.20417) (xy 395.336721 -406.206166) (xy 395.398218 -406.216109) (xy 395.457939 -406.233833)
			(xy 395.514902 -406.25905) (xy 395.568173 -406.291343) (xy 395.616878 -406.330183) (xy 395.660215 -406.374933)
			(xy 395.697475 -406.424857) (xy 395.728044 -406.479136) (xy 395.751422 -406.536879) (xy 395.767223 -406.597137)
			(xy 395.775189 -406.65892) (xy 395.775688 -406.690068) (xy 395.775189 -406.721216) (xy 395.767223 -406.782999)
			(xy 395.751422 -406.843257) (xy 395.728044 -406.901) (xy 395.697475 -406.955279) (xy 395.660215 -407.005203)
			(xy 395.616878 -407.049953) (xy 395.568173 -407.088793) (xy 395.514902 -407.121086) (xy 395.457939 -407.146303)
			(xy 395.398218 -407.164027) (xy 395.336721 -407.17397) (xy 395.274458 -407.175966) (xy 395.212451 -407.169984)
			(xy 395.151717 -407.156122) (xy 395.093255 -407.134608) (xy 395.038024 -407.105794) (xy 394.986932 -407.070154)
			(xy 394.940816 -407.028273) (xy 394.900434 -406.980838) (xy 394.86645 -406.928629) (xy 394.839421 -406.872503)
			(xy 394.819792 -406.813382) (xy 394.807883 -406.752235) (xy 394.803892 -406.690068) (xy 391.37502 -406.690068)
			(xy 391.375022 -406.722789) (xy 391.366243 -406.787632) (xy 391.348841 -406.850709) (xy 391.323131 -406.91088)
			(xy 391.306812 -406.939242) (xy 391.303483 -406.94526) (xy 391.299886 -406.958529) (xy 391.2997 -406.965404)
			(xy 391.2997 -407.251408) (xy 391.299285 -407.261563) (xy 391.291487 -407.280315) (xy 391.277088 -407.294638)
			(xy 391.258295 -407.302338) (xy 391.248138 -407.302716) (xy 390.531858 -407.302716) (xy 390.521723 -407.302307)
			(xy 390.502993 -407.294557) (xy 390.488636 -407.280247) (xy 390.480826 -407.261541) (xy 390.480296 -407.251408)
			(xy 390.480296 -406.965404) (xy 390.480103 -406.958531) (xy 390.476496 -406.945268) (xy 390.473184 -406.939242)
			(xy 390.456833 -406.910896) (xy 390.431116 -406.850722) (xy 390.413709 -406.78764) (xy 390.404928 -406.722792)
			(xy 386.975046 -406.722792) (xy 386.975046 -406.722798) (xy 386.966187 -406.787656) (xy 386.948695 -406.850736)
			(xy 386.922885 -406.910894) (xy 386.906516 -406.939242) (xy 386.903187 -406.94526) (xy 386.89959 -406.958529)
			(xy 386.899404 -406.965404) (xy 386.899404 -407.251408) (xy 386.898921 -407.261517) (xy 386.891182 -407.280194)
			(xy 386.876884 -407.294489) (xy 386.858205 -407.302224) (xy 386.848096 -407.302716) (xy 386.131816 -407.302716)
			(xy 386.121697 -407.302271) (xy 386.102996 -407.294531) (xy 386.088682 -407.280224) (xy 386.080933 -407.261527)
			(xy 386.080508 -407.251408) (xy 386.080508 -406.965404) (xy 386.080314 -406.958531) (xy 386.076707 -406.945268)
			(xy 386.073396 -406.939242) (xy 386.057047 -406.910884) (xy 386.031241 -406.850727) (xy 386.013747 -406.787651)
			(xy 386.004881 -406.722796) (xy 386.004308 -406.690068) (xy 382.574948 -406.690068) (xy 382.57495 -406.72279)
			(xy 382.566169 -406.787633) (xy 382.548764 -406.850711) (xy 382.523049 -406.910881) (xy 382.506728 -406.939242)
			(xy 382.5034 -406.94526) (xy 382.499802 -406.958529) (xy 382.499616 -406.965404) (xy 382.499616 -407.251408)
			(xy 382.499185 -407.261561) (xy 382.49139 -407.28031) (xy 382.476996 -407.294632) (xy 382.458209 -407.302335)
			(xy 382.448054 -407.302716) (xy 381.731774 -407.302716) (xy 381.72164 -407.302294) (xy 381.70291 -407.294549)
			(xy 381.688553 -407.280243) (xy 381.680743 -407.26154) (xy 381.680212 -407.251408) (xy 381.680212 -406.965404)
			(xy 381.680017 -406.958531) (xy 381.676411 -406.945268) (xy 381.6731 -406.939242) (xy 381.656752 -406.910895)
			(xy 381.631039 -406.85072) (xy 381.613635 -406.787639) (xy 381.604856 -406.722792) (xy 378.17496 -406.722792)
			(xy 378.17496 -406.722798) (xy 378.166102 -406.787656) (xy 378.14861 -406.850736) (xy 378.122801 -406.910894)
			(xy 378.106432 -406.939242) (xy 378.103105 -406.945261) (xy 378.099507 -406.958529) (xy 378.09932 -406.965404)
			(xy 378.09932 -407.251408) (xy 378.098822 -407.261515) (xy 378.091085 -407.280189) (xy 378.076793 -407.294483)
			(xy 378.058119 -407.302221) (xy 378.048012 -407.302716) (xy 377.331732 -407.302716) (xy 377.321614 -407.302258)
			(xy 377.302914 -407.294524) (xy 377.288599 -407.28022) (xy 377.280849 -407.261526) (xy 377.280424 -407.251408)
			(xy 377.280424 -406.965404) (xy 377.280228 -406.958531) (xy 377.276622 -406.945268) (xy 377.273312 -406.939242)
			(xy 377.256964 -406.910883) (xy 377.231158 -406.850727) (xy 377.213663 -406.787651) (xy 377.204797 -406.722796)
			(xy 377.204224 -406.690068) (xy 351.775776 -406.690068) (xy 351.775277 -406.721216) (xy 351.767311 -406.782999)
			(xy 351.75151 -406.843257) (xy 351.728132 -406.901) (xy 351.697563 -406.955279) (xy 351.660303 -407.005203)
			(xy 351.616966 -407.049953) (xy 351.568261 -407.088793) (xy 351.51499 -407.121086) (xy 351.458027 -407.146303)
			(xy 351.398306 -407.164027) (xy 351.336809 -407.17397) (xy 351.274546 -407.175966) (xy 351.212539 -407.169984)
			(xy 351.151805 -407.156122) (xy 351.093343 -407.134608) (xy 351.038112 -407.105794) (xy 350.98702 -407.070154)
			(xy 350.940904 -407.028273) (xy 350.900522 -406.980838) (xy 350.866538 -406.928629) (xy 350.839509 -406.872503)
			(xy 350.81988 -406.813382) (xy 350.807971 -406.752235) (xy 350.80398 -406.690068) (xy 347.37511 -406.690068)
			(xy 347.375112 -406.72279) (xy 347.366333 -406.787632) (xy 347.34893 -406.850709) (xy 347.323219 -406.91088)
			(xy 347.3069 -406.939242) (xy 347.30357 -406.945259) (xy 347.299974 -406.958529) (xy 347.299788 -406.965404)
			(xy 347.299788 -407.251408) (xy 347.299385 -407.261564) (xy 347.291584 -407.280319) (xy 347.277182 -407.294642)
			(xy 347.258384 -407.30234) (xy 347.248226 -407.302716) (xy 346.531946 -407.302716) (xy 346.521817 -407.302234)
			(xy 346.503088 -407.294514) (xy 346.488729 -407.280225) (xy 346.480916 -407.261535) (xy 346.480384 -407.251408)
			(xy 346.480384 -406.965404) (xy 346.480192 -406.958531) (xy 346.476584 -406.945268) (xy 346.473272 -406.939242)
			(xy 346.456922 -406.910896) (xy 346.431205 -406.850722) (xy 346.413798 -406.78764) (xy 346.405018 -406.722792)
			(xy 342.975135 -406.722792) (xy 342.975135 -406.722798) (xy 342.966277 -406.787656) (xy 342.948784 -406.850737)
			(xy 342.922974 -406.910894) (xy 342.906604 -406.939242) (xy 342.903275 -406.945259) (xy 342.899678 -406.958529)
			(xy 342.899492 -406.965404) (xy 342.899492 -407.251408) (xy 342.89909 -407.261532) (xy 342.891338 -407.280237)
			(xy 342.877017 -407.294551) (xy 342.858308 -407.302295) (xy 342.848184 -407.302716) (xy 342.131904 -407.302716)
			(xy 342.121798 -407.302212) (xy 342.103122 -407.294479) (xy 342.088828 -407.280188) (xy 342.08109 -407.261514)
			(xy 342.080596 -407.251408) (xy 342.080596 -406.965404) (xy 342.080403 -406.958531) (xy 342.076796 -406.945268)
			(xy 342.073484 -406.939242) (xy 342.057134 -406.910884) (xy 342.031328 -406.850728) (xy 342.013835 -406.787651)
			(xy 342.004969 -406.722796) (xy 342.004396 -406.690068) (xy 338.575037 -406.690068) (xy 338.575039 -406.72279)
			(xy 338.566259 -406.787633) (xy 338.548853 -406.850711) (xy 338.523137 -406.910881) (xy 338.506816 -406.939242)
			(xy 338.503487 -406.94526) (xy 338.49989 -406.958529) (xy 338.499704 -406.965404) (xy 338.499704 -407.251408)
			(xy 338.499285 -407.261562) (xy 338.491487 -407.280314) (xy 338.47709 -407.294637) (xy 338.458298 -407.302337)
			(xy 338.448142 -407.302716) (xy 337.731862 -407.302716) (xy 337.721727 -407.302303) (xy 337.702997 -407.294555)
			(xy 337.688641 -407.280246) (xy 337.68083 -407.261541) (xy 337.6803 -407.251408) (xy 337.6803 -406.965404)
			(xy 337.680107 -406.958531) (xy 337.6765 -406.945268) (xy 337.673188 -406.939242) (xy 337.65684 -406.910895)
			(xy 337.631128 -406.85072) (xy 337.613725 -406.787638) (xy 337.604945 -406.722792) (xy 334.175049 -406.722792)
			(xy 334.175049 -406.722798) (xy 334.166191 -406.787656) (xy 334.148699 -406.850736) (xy 334.122889 -406.910894)
			(xy 334.10652 -406.939242) (xy 334.103192 -406.94526) (xy 334.099594 -406.958529) (xy 334.099408 -406.965404)
			(xy 334.099408 -407.251408) (xy 334.098921 -407.261516) (xy 334.091183 -407.280193) (xy 334.076886 -407.294487)
			(xy 334.058208 -407.302223) (xy 334.0481 -407.302716) (xy 333.33182 -407.302716) (xy 333.321701 -407.302268)
			(xy 333.303001 -407.29453) (xy 333.288686 -407.280223) (xy 333.280937 -407.261527) (xy 333.280512 -407.251408)
			(xy 333.280512 -406.965404) (xy 333.280317 -406.958531) (xy 333.276711 -406.945268) (xy 333.2734 -406.939242)
			(xy 333.257051 -406.910884) (xy 333.231245 -406.850727) (xy 333.213751 -406.787651) (xy 333.204885 -406.722796)
			(xy 333.204312 -406.690068) (xy 326.525636 -406.690068) (xy 326.525636 -409.522889) (xy 331.004998 -409.522889)
			(xy 331.005002 -409.457449) (xy 331.013791 -409.392603) (xy 331.031204 -409.329523) (xy 331.056927 -409.269351)
			(xy 331.073252 -409.24099) (xy 331.076566 -409.234965) (xy 331.080173 -409.221702) (xy 331.080364 -409.214828)
			(xy 331.080364 -408.465528) (xy 331.080166 -408.458655) (xy 331.076562 -408.445392) (xy 331.073252 -408.439366)
			(xy 331.056923 -408.411009) (xy 331.031205 -408.350837) (xy 331.013797 -408.287757) (xy 331.005014 -408.222912)
			(xy 331.005015 -408.157474) (xy 331.0138 -408.092629) (xy 331.031209 -408.02955) (xy 331.056929 -407.969379)
			(xy 331.073252 -407.941018) (xy 331.076556 -407.934988) (xy 331.080169 -407.921729) (xy 331.080364 -407.914856)
			(xy 331.080364 -407.628852) (xy 331.080782 -407.618699) (xy 331.088586 -407.599953) (xy 331.102983 -407.585633)
			(xy 331.121771 -407.577928) (xy 331.131926 -407.577544) (xy 331.848206 -407.577544) (xy 331.858334 -407.578022)
			(xy 331.877056 -407.585752) (xy 331.891412 -407.600041) (xy 331.89923 -407.618727) (xy 331.899768 -407.628852)
			(xy 331.899768 -407.914856) (xy 331.899981 -407.921728) (xy 331.903575 -407.93499) (xy 331.90688 -407.941018)
			(xy 331.923195 -407.969383) (xy 331.948912 -408.029554) (xy 331.96632 -408.092632) (xy 331.975104 -408.157475)
			(xy 331.975105 -408.222911) (xy 331.966323 -408.287755) (xy 331.948917 -408.350833) (xy 331.923201 -408.411005)
			(xy 331.90688 -408.439366) (xy 331.903576 -408.445396) (xy 331.899964 -408.458656) (xy 331.899768 -408.465528)
			(xy 331.899768 -409.214828) (xy 331.899953 -409.221702) (xy 331.903567 -409.234964) (xy 331.90688 -409.24099)
			(xy 331.923171 -409.269368) (xy 331.948891 -409.329536) (xy 331.966301 -409.392611) (xy 331.975088 -409.457452)
			(xy 331.975093 -409.522886) (xy 331.966314 -409.587729) (xy 331.948911 -409.650806) (xy 331.923199 -409.710977)
			(xy 331.90688 -409.739338) (xy 331.90355 -409.745355) (xy 331.899954 -409.758625) (xy 331.899768 -409.7655)
			(xy 331.899768 -410.051504) (xy 331.899381 -410.061662) (xy 331.891578 -410.080421) (xy 331.87717 -410.094745)
			(xy 331.858367 -410.102439) (xy 331.848206 -410.102812) (xy 331.131926 -410.102812) (xy 331.121807 -410.102254)
			(xy 331.103097 -410.094544) (xy 331.088741 -410.08028) (xy 331.080912 -410.061619) (xy 331.080364 -410.051504)
			(xy 331.080364 -409.7655) (xy 331.080176 -409.758626) (xy 331.076566 -409.745363) (xy 331.073252 -409.739338)
			(xy 331.056899 -409.710994) (xy 331.031183 -409.650819) (xy 331.013778 -409.587736) (xy 331.004998 -409.522889)
			(xy 326.525636 -409.522889) (xy 326.525636 -410.589984) (xy 333.204312 -410.589984) (xy 333.204891 -410.557255)
			(xy 333.213743 -410.492397) (xy 333.231229 -410.429317) (xy 333.257033 -410.369158) (xy 333.2734 -410.34081)
			(xy 333.276711 -410.334784) (xy 333.280319 -410.321521) (xy 333.280512 -410.314648) (xy 333.280512 -409.565348)
			(xy 333.2803 -409.558476) (xy 333.276705 -409.545214) (xy 333.2734 -409.539186) (xy 333.257029 -409.51084)
			(xy 333.231228 -409.450679) (xy 333.21374 -409.387599) (xy 333.204882 -409.322741) (xy 333.204312 -409.290012)
			(xy 333.204859 -409.257282) (xy 333.21372 -409.192423) (xy 333.231216 -409.129343) (xy 333.257029 -409.069185)
			(xy 333.2734 -409.040838) (xy 333.276701 -409.034807) (xy 333.280315 -409.021548) (xy 333.280512 -409.014676)
			(xy 333.280512 -408.728672) (xy 333.280962 -408.71856) (xy 333.288711 -408.699879) (xy 333.303019 -408.685585)
			(xy 333.321708 -408.677853) (xy 333.33182 -408.677364) (xy 334.0481 -408.677364) (xy 334.058204 -408.677884)
			(xy 334.076876 -408.685615) (xy 334.091169 -408.699901) (xy 334.09891 -408.718568) (xy 334.099408 -408.728672)
			(xy 334.099408 -409.014676) (xy 334.099608 -409.021549) (xy 334.103211 -409.034811) (xy 334.10652 -409.040838)
			(xy 334.122903 -409.069178) (xy 334.1487 -409.129341) (xy 334.166185 -409.192423) (xy 334.17504 -409.257282)
			(xy 334.175608 -409.290012) (xy 334.175024 -409.322741) (xy 334.166173 -409.387598) (xy 334.148688 -409.450679)
			(xy 334.131753 -409.490164) (xy 335.40446 -409.490164) (xy 335.405037 -409.457435) (xy 335.41389 -409.392577)
			(xy 335.431377 -409.329497) (xy 335.457181 -409.269338) (xy 335.473548 -409.24099) (xy 335.476862 -409.234965)
			(xy 335.480469 -409.221702) (xy 335.48066 -409.214828) (xy 335.48066 -408.465528) (xy 335.480462 -408.458655)
			(xy 335.476859 -408.445392) (xy 335.473548 -408.439366) (xy 335.457173 -408.411022) (xy 335.431373 -408.350861)
			(xy 335.413885 -408.28778) (xy 335.405028 -408.222921) (xy 335.40446 -408.190192) (xy 335.40505 -408.157463)
			(xy 335.4139 -408.092606) (xy 335.431383 -408.029526) (xy 335.457183 -407.969367) (xy 335.473548 -407.941018)
			(xy 335.476852 -407.934988) (xy 335.480465 -407.921729) (xy 335.48066 -407.914856) (xy 335.48066 -407.628852)
			(xy 335.481145 -407.618745) (xy 335.488891 -407.600074) (xy 335.503187 -407.585782) (xy 335.521861 -407.578042)
			(xy 335.531968 -407.577544) (xy 336.248248 -407.577544) (xy 336.258353 -407.578045) (xy 336.277021 -407.585788)
			(xy 336.291312 -407.600079) (xy 336.299055 -407.618747) (xy 336.299556 -407.628852) (xy 336.299556 -407.914856)
			(xy 336.299758 -407.921729) (xy 336.303358 -407.934992) (xy 336.306668 -407.941018) (xy 336.323038 -407.969365)
			(xy 336.348839 -408.029525) (xy 336.366328 -408.092605) (xy 336.375187 -408.157463) (xy 336.375756 -408.190192)
			(xy 336.375202 -408.222922) (xy 336.366341 -408.28778) (xy 336.348847 -408.35086) (xy 336.323038 -408.411018)
			(xy 336.306668 -408.439366) (xy 336.303363 -408.445395) (xy 336.299752 -408.458656) (xy 336.299556 -408.465528)
			(xy 336.299556 -409.214828) (xy 336.29973 -409.221703) (xy 336.30335 -409.234966) (xy 336.306668 -409.24099)
			(xy 336.323027 -409.269343) (xy 336.348831 -409.329501) (xy 336.366323 -409.392579) (xy 336.375185 -409.457435)
			(xy 336.375756 -409.490164) (xy 336.375189 -409.522893) (xy 336.366332 -409.587751) (xy 336.348842 -409.650831)
			(xy 336.323036 -409.71099) (xy 336.306668 -409.739338) (xy 336.303338 -409.745355) (xy 336.299742 -409.758625)
			(xy 336.299556 -409.7655) (xy 336.299556 -410.051504) (xy 336.299019 -410.061606) (xy 336.291291 -410.080274)
			(xy 336.277011 -410.094566) (xy 336.25835 -410.102311) (xy 336.248248 -410.102812) (xy 335.531968 -410.102812)
			(xy 335.521859 -410.102341) (xy 335.503182 -410.094595) (xy 335.488889 -410.080294) (xy 335.481153 -410.061614)
			(xy 335.48066 -410.051504) (xy 335.48066 -409.7655) (xy 335.480473 -409.758626) (xy 335.476862 -409.745363)
			(xy 335.473548 -409.739338) (xy 335.457202 -409.710978) (xy 335.431394 -409.650823) (xy 335.413899 -409.587746)
			(xy 335.405033 -409.522892) (xy 335.40446 -409.490164) (xy 334.131753 -409.490164) (xy 334.122886 -409.510837)
			(xy 334.10652 -409.539186) (xy 334.103212 -409.545214) (xy 334.099602 -409.558475) (xy 334.099408 -409.565348)
			(xy 334.099408 -410.314648) (xy 334.099619 -410.32152) (xy 334.103214 -410.334783) (xy 334.10652 -410.34081)
			(xy 334.122891 -410.369156) (xy 334.148691 -410.429317) (xy 334.166179 -410.492397) (xy 334.175038 -410.557255)
			(xy 334.175608 -410.589984) (xy 334.175057 -410.622705) (xy 337.604954 -410.622705) (xy 337.604956 -410.557268)
			(xy 337.613741 -410.492423) (xy 337.631149 -410.429344) (xy 337.656866 -410.369172) (xy 337.673188 -410.34081)
			(xy 337.676498 -410.334783) (xy 337.680107 -410.321521) (xy 337.6803 -410.314648) (xy 337.6803 -409.565348)
			(xy 337.68009 -409.558476) (xy 337.676494 -409.545213) (xy 337.673188 -409.539186) (xy 337.656878 -409.510819)
			(xy 337.631162 -409.450648) (xy 337.613754 -409.387571) (xy 337.60497 -409.322728) (xy 337.604969 -409.257293)
			(xy 337.61375 -409.192449) (xy 337.631155 -409.129371) (xy 337.656868 -409.0692) (xy 337.673188 -409.040838)
			(xy 337.676488 -409.034806) (xy 337.680103 -409.021548) (xy 337.6803 -409.014676) (xy 337.6803 -408.728672)
			(xy 337.680699 -408.718516) (xy 337.688503 -408.699763) (xy 337.702907 -408.685441) (xy 337.721704 -408.677742)
			(xy 337.731862 -408.677364) (xy 338.448142 -408.677364) (xy 338.458274 -408.677793) (xy 338.477001 -408.685539)
			(xy 338.491357 -408.699843) (xy 338.49917 -408.718542) (xy 338.499704 -408.728672) (xy 338.499704 -409.014676)
			(xy 338.499905 -409.021549) (xy 338.503507 -409.034811) (xy 338.506816 -409.040838) (xy 338.52315 -409.069193)
			(xy 338.548869 -409.129365) (xy 338.566277 -409.192445) (xy 338.575061 -409.257291) (xy 338.575059 -409.322729)
			(xy 338.566273 -409.387575) (xy 338.548862 -409.450654) (xy 338.52314 -409.510825) (xy 338.516196 -409.522889)
			(xy 339.805084 -409.522889) (xy 339.805089 -409.45745) (xy 339.813877 -409.392603) (xy 339.831289 -409.329523)
			(xy 339.857011 -409.269351) (xy 339.873336 -409.24099) (xy 339.876649 -409.234965) (xy 339.880257 -409.221702)
			(xy 339.880448 -409.214828) (xy 339.880448 -408.465528) (xy 339.880252 -408.458655) (xy 339.876647 -408.445392)
			(xy 339.873336 -408.439366) (xy 339.857007 -408.411008) (xy 339.83129 -408.350836) (xy 339.813883 -408.287757)
			(xy 339.8051 -408.222912) (xy 339.805101 -408.157475) (xy 339.813886 -408.09263) (xy 339.831295 -408.029551)
			(xy 339.857013 -407.969379) (xy 339.873336 -407.941018) (xy 339.876639 -407.934988) (xy 339.880253 -407.921728)
			(xy 339.880448 -407.914856) (xy 339.880448 -407.628852) (xy 339.880881 -407.618701) (xy 339.888683 -407.599958)
			(xy 339.903075 -407.585638) (xy 339.921857 -407.577931) (xy 339.93201 -407.577544) (xy 340.64829 -407.577544)
			(xy 340.658417 -407.578035) (xy 340.677138 -407.58576) (xy 340.691495 -407.600045) (xy 340.699314 -407.618728)
			(xy 340.699852 -407.628852) (xy 340.699852 -407.914856) (xy 340.700054 -407.921729) (xy 340.703655 -407.934992)
			(xy 340.706964 -407.941018) (xy 340.723279 -407.969383) (xy 340.748997 -408.029553) (xy 340.766406 -408.092631)
			(xy 340.775191 -408.157475) (xy 340.775191 -408.222911) (xy 340.766409 -408.287755) (xy 340.749002 -408.350834)
			(xy 340.723286 -408.411005) (xy 340.706964 -408.439366) (xy 340.703666 -408.445399) (xy 340.700049 -408.458656)
			(xy 340.699852 -408.465528) (xy 340.699852 -409.214828) (xy 340.700027 -409.221703) (xy 340.703646 -409.234966)
			(xy 340.706964 -409.24099) (xy 340.723256 -409.269368) (xy 340.748976 -409.329535) (xy 340.766387 -409.392611)
			(xy 340.775175 -409.457452) (xy 340.775179 -409.522886) (xy 340.7664 -409.587729) (xy 340.748996 -409.650806)
			(xy 340.723284 -409.710977) (xy 340.706964 -409.739338) (xy 340.703641 -409.745359) (xy 340.70004 -409.758625)
			(xy 340.699852 -409.7655) (xy 340.699852 -410.051504) (xy 340.699383 -410.061652) (xy 340.691595 -410.080394)
			(xy 340.677214 -410.094716) (xy 340.65844 -410.102424) (xy 340.64829 -410.102812) (xy 339.93201 -410.102812)
			(xy 339.92189 -410.102267) (xy 339.903179 -410.094552) (xy 339.888824 -410.080284) (xy 339.880996 -410.061621)
			(xy 339.880448 -410.051504) (xy 339.880448 -409.7655) (xy 339.880263 -409.758626) (xy 339.876651 -409.745363)
			(xy 339.873336 -409.739338) (xy 339.856983 -409.710994) (xy 339.831269 -409.650818) (xy 339.813864 -409.587736)
			(xy 339.805084 -409.522889) (xy 338.516196 -409.522889) (xy 338.506816 -409.539186) (xy 338.503507 -409.545214)
			(xy 338.499898 -409.558475) (xy 338.499704 -409.565348) (xy 338.499704 -410.314648) (xy 338.499915 -410.32152)
			(xy 338.50351 -410.334783) (xy 338.506816 -410.34081) (xy 338.523126 -410.369178) (xy 338.548847 -410.429347)
			(xy 338.566259 -410.492425) (xy 338.575045 -410.557268) (xy 338.575045 -410.589984) (xy 342.004396 -410.589984)
			(xy 342.004978 -410.557255) (xy 342.013829 -410.492397) (xy 342.031315 -410.429317) (xy 342.057118 -410.369159)
			(xy 342.073484 -410.34081) (xy 342.076794 -410.334783) (xy 342.080403 -410.321521) (xy 342.080596 -410.314648)
			(xy 342.080596 -409.565348) (xy 342.080386 -409.558476) (xy 342.07679 -409.545213) (xy 342.073484 -409.539186)
			(xy 342.057111 -409.510841) (xy 342.031312 -409.45068) (xy 342.013824 -409.387599) (xy 342.004966 -409.322741)
			(xy 342.004396 -409.290012) (xy 342.004945 -409.257282) (xy 342.013806 -409.192423) (xy 342.031301 -409.129343)
			(xy 342.057113 -409.069185) (xy 342.073484 -409.040838) (xy 342.076784 -409.034806) (xy 342.080399 -409.021548)
			(xy 342.080596 -409.014676) (xy 342.080596 -408.728672) (xy 342.081062 -408.718562) (xy 342.088808 -408.699884)
			(xy 342.103111 -408.68559) (xy 342.121794 -408.677856) (xy 342.131904 -408.677364) (xy 342.848184 -408.677364)
			(xy 342.858287 -408.677897) (xy 342.876958 -408.685623) (xy 342.891252 -408.699905) (xy 342.898994 -408.718569)
			(xy 342.899492 -408.728672) (xy 342.899492 -409.014676) (xy 342.899694 -409.021548) (xy 342.903295 -409.034811)
			(xy 342.906604 -409.040838) (xy 342.922985 -409.069179) (xy 342.948783 -409.129341) (xy 342.966268 -409.192423)
			(xy 342.975124 -409.257282) (xy 342.975692 -409.290012) (xy 342.97511 -409.322741) (xy 342.966259 -409.387599)
			(xy 342.948774 -409.450679) (xy 342.92297 -409.510837) (xy 342.916012 -409.522889) (xy 344.204874 -409.522889)
			(xy 344.204878 -409.45745) (xy 344.213666 -409.392603) (xy 344.231078 -409.329523) (xy 344.2568 -409.269351)
			(xy 344.273124 -409.24099) (xy 344.276444 -409.234968) (xy 344.280046 -409.221702) (xy 344.280236 -409.214828)
			(xy 344.280236 -408.465528) (xy 344.280029 -408.458656) (xy 344.276431 -408.445393) (xy 344.273124 -408.439366)
			(xy 344.256795 -408.411008) (xy 344.231079 -408.350836) (xy 344.213672 -408.287757) (xy 344.20489 -408.222912)
			(xy 344.204891 -408.157475) (xy 344.213675 -408.09263) (xy 344.231084 -408.029551) (xy 344.256802 -407.969379)
			(xy 344.273124 -407.941018) (xy 344.276434 -407.934991) (xy 344.280042 -407.921729) (xy 344.280236 -407.914856)
			(xy 344.280236 -407.628852) (xy 344.280583 -407.61869) (xy 344.288401 -407.59993) (xy 344.302821 -407.585607)
			(xy 344.321634 -407.577916) (xy 344.331798 -407.577544) (xy 345.048078 -407.577544) (xy 345.058204 -407.578045)
			(xy 345.076925 -407.585766) (xy 345.091283 -407.600048) (xy 345.099102 -407.618729) (xy 345.09964 -407.628852)
			(xy 345.09964 -407.914856) (xy 345.099844 -407.921728) (xy 345.103443 -407.934991) (xy 345.106752 -407.941018)
			(xy 345.123068 -407.969383) (xy 345.148786 -408.029553) (xy 345.166196 -408.092631) (xy 345.17498 -408.157475)
			(xy 345.17498 -408.190192) (xy 348.603832 -408.190192) (xy 348.607823 -408.128025) (xy 348.619732 -408.066878)
			(xy 348.639361 -408.007757) (xy 348.66639 -407.951631) (xy 348.700374 -407.899422) (xy 348.740756 -407.851987)
			(xy 348.786872 -407.810106) (xy 348.837964 -407.774466) (xy 348.893195 -407.745652) (xy 348.951657 -407.724138)
			(xy 349.012391 -407.710276) (xy 349.074398 -407.704294) (xy 349.136661 -407.70629) (xy 349.198158 -407.716233)
			(xy 349.257879 -407.733957) (xy 349.314842 -407.759174) (xy 349.368113 -407.791467) (xy 349.416818 -407.830307)
			(xy 349.460155 -407.875057) (xy 349.497415 -407.924981) (xy 349.527984 -407.97926) (xy 349.551362 -408.037003)
			(xy 349.567163 -408.097261) (xy 349.575129 -408.159044) (xy 349.575628 -408.190192) (xy 349.575129 -408.22134)
			(xy 349.567163 -408.283123) (xy 349.551362 -408.343381) (xy 349.527984 -408.401124) (xy 349.497415 -408.455403)
			(xy 349.460155 -408.505327) (xy 349.416818 -408.550077) (xy 349.368113 -408.588917) (xy 349.314842 -408.62121)
			(xy 349.257879 -408.646427) (xy 349.198158 -408.664151) (xy 349.136661 -408.674094) (xy 349.074398 -408.67609)
			(xy 349.012391 -408.670108) (xy 348.951657 -408.656246) (xy 348.893195 -408.634732) (xy 348.837964 -408.605918)
			(xy 348.786872 -408.570278) (xy 348.740756 -408.528397) (xy 348.700374 -408.480962) (xy 348.66639 -408.428753)
			(xy 348.639361 -408.372627) (xy 348.619732 -408.313506) (xy 348.607823 -408.252359) (xy 348.603832 -408.190192)
			(xy 345.17498 -408.190192) (xy 345.174981 -408.222911) (xy 345.166198 -408.287755) (xy 345.148791 -408.350834)
			(xy 345.123074 -408.411005) (xy 345.106752 -408.439366) (xy 345.103453 -408.445399) (xy 345.099837 -408.458656)
			(xy 345.09964 -408.465528) (xy 345.09964 -409.214828) (xy 345.099816 -409.221702) (xy 345.103435 -409.234965)
			(xy 345.106752 -409.24099) (xy 345.123044 -409.269368) (xy 345.148765 -409.329535) (xy 345.166177 -409.39261)
			(xy 345.174964 -409.457452) (xy 345.174968 -409.522886) (xy 345.166189 -409.587729) (xy 345.148785 -409.650806)
			(xy 345.123072 -409.710977) (xy 345.106752 -409.739338) (xy 345.103428 -409.745358) (xy 345.099828 -409.758625)
			(xy 345.09964 -409.7655) (xy 345.09964 -410.051504) (xy 345.099182 -410.061653) (xy 345.091393 -410.080398)
			(xy 345.077008 -410.09472) (xy 345.058229 -410.102427) (xy 345.048078 -410.102812) (xy 344.331798 -410.102812)
			(xy 344.321678 -410.102277) (xy 344.302966 -410.094558) (xy 344.288612 -410.080287) (xy 344.280784 -410.061621)
			(xy 344.280236 -410.051504) (xy 344.280236 -409.7655) (xy 344.28004 -409.758627) (xy 344.276434 -409.745365)
			(xy 344.273124 -409.739338) (xy 344.256772 -409.710993) (xy 344.231058 -409.650818) (xy 344.213654 -409.587736)
			(xy 344.204874 -409.522889) (xy 342.916012 -409.522889) (xy 342.906604 -409.539186) (xy 342.903295 -409.545213)
			(xy 342.899685 -409.558475) (xy 342.899492 -409.565348) (xy 342.899492 -410.314648) (xy 342.899705 -410.32152)
			(xy 342.903299 -410.334782) (xy 342.906604 -410.34081) (xy 342.922974 -410.369157) (xy 342.948775 -410.429317)
			(xy 342.966263 -410.492397) (xy 342.975122 -410.557255) (xy 342.975692 -410.589984) (xy 342.975142 -410.622705)
			(xy 346.405027 -410.622705) (xy 346.405029 -410.557267) (xy 346.413815 -410.492421) (xy 346.431226 -410.429342)
			(xy 346.456948 -410.369171) (xy 346.473272 -410.34081) (xy 346.476581 -410.334783) (xy 346.480191 -410.321521)
			(xy 346.480384 -410.314648) (xy 346.480384 -409.565348) (xy 346.480176 -409.558476) (xy 346.476579 -409.545213)
			(xy 346.473272 -409.539186) (xy 346.456959 -409.510819) (xy 346.431239 -409.45065) (xy 346.413828 -409.387572)
			(xy 346.405043 -409.322728) (xy 346.405041 -409.257292) (xy 346.413824 -409.192448) (xy 346.431232 -409.12937)
			(xy 346.45695 -409.069199) (xy 346.473272 -409.040838) (xy 346.476571 -409.034806) (xy 346.480187 -409.021548)
			(xy 346.480384 -409.014676) (xy 346.480384 -408.728672) (xy 346.480798 -408.718518) (xy 346.4886 -408.699768)
			(xy 346.502999 -408.685446) (xy 346.52179 -408.677745) (xy 346.531946 -408.677364) (xy 347.248226 -408.677364)
			(xy 347.258357 -408.677806) (xy 347.277084 -408.685547) (xy 347.29144 -408.699847) (xy 347.299254 -408.718543)
			(xy 347.299788 -408.728672) (xy 347.299788 -409.014676) (xy 347.29999 -409.021548) (xy 347.303592 -409.034811)
			(xy 347.3069 -409.040838) (xy 347.323231 -409.069194) (xy 347.348946 -409.129367) (xy 347.366351 -409.192447)
			(xy 347.375133 -409.257292) (xy 347.375132 -409.322729) (xy 347.366347 -409.387574) (xy 347.348939 -409.450653)
			(xy 347.332052 -409.490164) (xy 348.603832 -409.490164) (xy 348.607823 -409.427997) (xy 348.619732 -409.36685)
			(xy 348.639361 -409.307729) (xy 348.66639 -409.251603) (xy 348.700374 -409.199394) (xy 348.740756 -409.151959)
			(xy 348.786872 -409.110078) (xy 348.837964 -409.074438) (xy 348.893195 -409.045624) (xy 348.951657 -409.02411)
			(xy 349.012391 -409.010248) (xy 349.074398 -409.004266) (xy 349.136661 -409.006262) (xy 349.198158 -409.016205)
			(xy 349.257879 -409.033929) (xy 349.314842 -409.059146) (xy 349.368113 -409.091439) (xy 349.416818 -409.130279)
			(xy 349.460155 -409.175029) (xy 349.497415 -409.224953) (xy 349.527984 -409.279232) (xy 349.532348 -409.290012)
			(xy 350.80398 -409.290012) (xy 350.807971 -409.227845) (xy 350.81988 -409.166698) (xy 350.839509 -409.107577)
			(xy 350.866538 -409.051451) (xy 350.900522 -408.999242) (xy 350.940904 -408.951807) (xy 350.98702 -408.909926)
			(xy 351.038112 -408.874286) (xy 351.093343 -408.845472) (xy 351.151805 -408.823958) (xy 351.212539 -408.810096)
			(xy 351.274546 -408.804114) (xy 351.336809 -408.80611) (xy 351.398306 -408.816053) (xy 351.458027 -408.833777)
			(xy 351.51499 -408.858994) (xy 351.568261 -408.891287) (xy 351.616966 -408.930127) (xy 351.660303 -408.974877)
			(xy 351.697563 -409.024801) (xy 351.728132 -409.07908) (xy 351.75151 -409.136823) (xy 351.767311 -409.197081)
			(xy 351.775277 -409.258864) (xy 351.775776 -409.290012) (xy 351.775277 -409.32116) (xy 351.767311 -409.382943)
			(xy 351.75151 -409.443201) (xy 351.728132 -409.500944) (xy 351.715773 -409.522889) (xy 375.004909 -409.522889)
			(xy 375.004913 -409.457449) (xy 375.013701 -409.392603) (xy 375.031115 -409.329523) (xy 375.056839 -409.269351)
			(xy 375.073164 -409.24099) (xy 375.076479 -409.234966) (xy 375.080085 -409.221702) (xy 375.080276 -409.214828)
			(xy 375.080276 -408.465528) (xy 375.080076 -408.458655) (xy 375.076474 -408.445392) (xy 375.073164 -408.439366)
			(xy 375.056834 -408.411009) (xy 375.031116 -408.350837) (xy 375.013708 -408.287757) (xy 375.004924 -408.222912)
			(xy 375.004925 -408.157474) (xy 375.01371 -408.092629) (xy 375.03112 -408.02955) (xy 375.05684 -407.969379)
			(xy 375.073164 -407.941018) (xy 375.076469 -407.934989) (xy 375.080081 -407.921729) (xy 375.080276 -407.914856)
			(xy 375.080276 -407.628852) (xy 375.080682 -407.618698) (xy 375.088489 -407.599949) (xy 375.10289 -407.585628)
			(xy 375.121682 -407.577926) (xy 375.131838 -407.577544) (xy 375.848118 -407.577544) (xy 375.858246 -407.578012)
			(xy 375.876969 -407.585746) (xy 375.891325 -407.600038) (xy 375.899143 -407.618726) (xy 375.89968 -407.628852)
			(xy 375.89968 -407.914856) (xy 375.899891 -407.921728) (xy 375.903486 -407.934991) (xy 375.906792 -407.941018)
			(xy 375.923106 -407.969383) (xy 375.948823 -408.029554) (xy 375.966231 -408.092632) (xy 375.975015 -408.157475)
			(xy 375.975016 -408.222911) (xy 375.966234 -408.287755) (xy 375.948828 -408.350833) (xy 375.923113 -408.411004)
			(xy 375.906792 -408.439366) (xy 375.903489 -408.445396) (xy 375.899876 -408.458656) (xy 375.89968 -408.465528)
			(xy 375.89968 -409.214828) (xy 375.899864 -409.221702) (xy 375.903478 -409.234964) (xy 375.906792 -409.24099)
			(xy 375.923083 -409.269368) (xy 375.948802 -409.329536) (xy 375.966212 -409.392611) (xy 375.974999 -409.457452)
			(xy 375.975003 -409.522886) (xy 375.966224 -409.587728) (xy 375.948822 -409.650806) (xy 375.923111 -409.710976)
			(xy 375.906792 -409.739338) (xy 375.903463 -409.745356) (xy 375.899867 -409.758625) (xy 375.89968 -409.7655)
			(xy 375.89968 -410.051504) (xy 375.899281 -410.061661) (xy 375.891481 -410.080417) (xy 375.877077 -410.094741)
			(xy 375.858277 -410.102437) (xy 375.848118 -410.102812) (xy 375.131838 -410.102812) (xy 375.12172 -410.102244)
			(xy 375.10301 -410.094538) (xy 375.088654 -410.080277) (xy 375.080824 -410.061618) (xy 375.080276 -410.051504)
			(xy 375.080276 -409.7655) (xy 375.080087 -409.758627) (xy 375.076477 -409.745364) (xy 375.073164 -409.739338)
			(xy 375.05681 -409.710994) (xy 375.031094 -409.650819) (xy 375.013689 -409.587737) (xy 375.004909 -409.522889)
			(xy 351.715773 -409.522889) (xy 351.697563 -409.555223) (xy 351.660303 -409.605147) (xy 351.616966 -409.649897)
			(xy 351.568261 -409.688737) (xy 351.51499 -409.72103) (xy 351.458027 -409.746247) (xy 351.398306 -409.763971)
			(xy 351.336809 -409.773914) (xy 351.274546 -409.77591) (xy 351.212539 -409.769928) (xy 351.151805 -409.756066)
			(xy 351.093343 -409.734552) (xy 351.038112 -409.705738) (xy 350.98702 -409.670098) (xy 350.940904 -409.628217)
			(xy 350.900522 -409.580782) (xy 350.866538 -409.528573) (xy 350.839509 -409.472447) (xy 350.81988 -409.413326)
			(xy 350.807971 -409.352179) (xy 350.80398 -409.290012) (xy 349.532348 -409.290012) (xy 349.551362 -409.336975)
			(xy 349.567163 -409.397233) (xy 349.575129 -409.459016) (xy 349.575628 -409.490164) (xy 349.575129 -409.521312)
			(xy 349.567163 -409.583095) (xy 349.551362 -409.643353) (xy 349.527984 -409.701096) (xy 349.497415 -409.755375)
			(xy 349.460155 -409.805299) (xy 349.416818 -409.850049) (xy 349.368113 -409.888889) (xy 349.314842 -409.921182)
			(xy 349.257879 -409.946399) (xy 349.198158 -409.964123) (xy 349.136661 -409.974066) (xy 349.074398 -409.976062)
			(xy 349.012391 -409.97008) (xy 348.951657 -409.956218) (xy 348.893195 -409.934704) (xy 348.837964 -409.90589)
			(xy 348.786872 -409.87025) (xy 348.740756 -409.828369) (xy 348.700374 -409.780934) (xy 348.66639 -409.728725)
			(xy 348.639361 -409.672599) (xy 348.619732 -409.613478) (xy 348.607823 -409.552331) (xy 348.603832 -409.490164)
			(xy 347.332052 -409.490164) (xy 347.323222 -409.510824) (xy 347.3069 -409.539186) (xy 347.30359 -409.545213)
			(xy 347.299981 -409.558475) (xy 347.299788 -409.565348) (xy 347.299788 -410.314648) (xy 347.300002 -410.32152)
			(xy 347.303595 -410.334782) (xy 347.3069 -410.34081) (xy 347.323207 -410.369179) (xy 347.348924 -410.429349)
			(xy 347.366332 -410.492426) (xy 347.375117 -410.557269) (xy 347.375118 -410.589984) (xy 350.80398 -410.589984)
			(xy 350.807971 -410.527817) (xy 350.81988 -410.46667) (xy 350.839509 -410.407549) (xy 350.866538 -410.351423)
			(xy 350.900522 -410.299214) (xy 350.940904 -410.251779) (xy 350.98702 -410.209898) (xy 351.038112 -410.174258)
			(xy 351.093343 -410.145444) (xy 351.151805 -410.12393) (xy 351.212539 -410.110068) (xy 351.274546 -410.104086)
			(xy 351.336809 -410.106082) (xy 351.398306 -410.116025) (xy 351.458027 -410.133749) (xy 351.51499 -410.158966)
			(xy 351.568261 -410.191259) (xy 351.616966 -410.230099) (xy 351.660303 -410.274849) (xy 351.697563 -410.324773)
			(xy 351.728132 -410.379052) (xy 351.75151 -410.436795) (xy 351.767311 -410.497053) (xy 351.775277 -410.558836)
			(xy 351.775776 -410.589984) (xy 377.204224 -410.589984) (xy 377.204802 -410.557255) (xy 377.213653 -410.492397)
			(xy 377.23114 -410.429317) (xy 377.256945 -410.369158) (xy 377.273312 -410.34081) (xy 377.276624 -410.334784)
			(xy 377.280231 -410.321521) (xy 377.280424 -410.314648) (xy 377.280424 -409.565348) (xy 377.280211 -409.558476)
			(xy 377.276617 -409.545214) (xy 377.273312 -409.539186) (xy 377.256942 -409.510839) (xy 377.231141 -409.450679)
			(xy 377.213653 -409.387599) (xy 377.204794 -409.322741) (xy 377.204224 -409.290012) (xy 377.20477 -409.257282)
			(xy 377.213631 -409.192423) (xy 377.231127 -409.129342) (xy 377.256941 -409.069185) (xy 377.273312 -409.040838)
			(xy 377.276614 -409.034807) (xy 377.280227 -409.021548) (xy 377.280424 -409.014676) (xy 377.280424 -408.728672)
			(xy 377.280794 -408.718545) (xy 377.288555 -408.699836) (xy 377.302886 -408.685522) (xy 377.321604 -408.677782)
			(xy 377.331732 -408.677364) (xy 378.048012 -408.677364) (xy 378.058117 -408.677875) (xy 378.076789 -408.685609)
			(xy 378.091082 -408.699898) (xy 378.098822 -408.718567) (xy 378.09932 -408.728672) (xy 378.09932 -409.014676)
			(xy 378.099519 -409.021549) (xy 378.103122 -409.034812) (xy 378.106432 -409.040838) (xy 378.122806 -409.069183)
			(xy 378.148607 -409.129343) (xy 378.166095 -409.192424) (xy 378.174952 -409.257283) (xy 378.17552 -409.290012)
			(xy 378.174934 -409.322741) (xy 378.166084 -409.387598) (xy 378.148599 -409.450678) (xy 378.131664 -409.490164)
			(xy 379.404372 -409.490164) (xy 379.404948 -409.457435) (xy 379.413801 -409.392577) (xy 379.431289 -409.329497)
			(xy 379.457093 -409.269339) (xy 379.47346 -409.24099) (xy 379.476775 -409.234965) (xy 379.480381 -409.221702)
			(xy 379.480572 -409.214828) (xy 379.480572 -408.465528) (xy 379.480373 -408.458655) (xy 379.47677 -408.445392)
			(xy 379.47346 -408.439366) (xy 379.457087 -408.411021) (xy 379.431285 -408.35086) (xy 379.413798 -408.287779)
			(xy 379.40494 -408.222921) (xy 379.404372 -408.190192) (xy 379.404961 -408.157463) (xy 379.41381 -408.092606)
			(xy 379.431294 -408.029526) (xy 379.457095 -407.969367) (xy 379.47346 -407.941018) (xy 379.476765 -407.934989)
			(xy 379.480377 -407.921729) (xy 379.480572 -407.914856) (xy 379.480572 -407.628852) (xy 379.481045 -407.618744)
			(xy 379.488793 -407.60007) (xy 379.503093 -407.585778) (xy 379.521771 -407.57804) (xy 379.53188 -407.577544)
			(xy 380.24816 -407.577544) (xy 380.258259 -407.578117) (xy 380.276926 -407.585831) (xy 380.29122 -407.6001)
			(xy 380.298966 -407.618754) (xy 380.299468 -407.628852) (xy 380.299468 -407.914856) (xy 380.299681 -407.921728)
			(xy 380.303275 -407.93499) (xy 380.30658 -407.941018) (xy 380.322951 -407.969364) (xy 380.348752 -408.029525)
			(xy 380.36624 -408.092605) (xy 380.375099 -408.157463) (xy 380.375668 -408.190192) (xy 380.375112 -408.222922)
			(xy 380.366252 -408.28778) (xy 380.348758 -408.35086) (xy 380.322949 -408.411018) (xy 380.30658 -408.439366)
			(xy 380.303276 -408.445396) (xy 380.299664 -408.458656) (xy 380.299468 -408.465528) (xy 380.299468 -409.214828)
			(xy 380.299653 -409.221702) (xy 380.303267 -409.234964) (xy 380.30658 -409.24099) (xy 380.32294 -409.269343)
			(xy 380.348743 -409.329501) (xy 380.366235 -409.392579) (xy 380.375097 -409.457435) (xy 380.375668 -409.490164)
			(xy 380.375099 -409.522893) (xy 380.366243 -409.587751) (xy 380.348753 -409.650831) (xy 380.322948 -409.71099)
			(xy 380.30658 -409.739338) (xy 380.30325 -409.745355) (xy 380.299654 -409.758625) (xy 380.299468 -409.7655)
			(xy 380.299468 -410.051504) (xy 380.299086 -410.061631) (xy 380.291331 -410.08034) (xy 380.277003 -410.094656)
			(xy 380.258287 -410.102395) (xy 380.24816 -410.102812) (xy 379.53188 -410.102812) (xy 379.521771 -410.102332)
			(xy 379.503095 -410.09459) (xy 379.488801 -410.080292) (xy 379.481065 -410.061613) (xy 379.480572 -410.051504)
			(xy 379.480572 -409.7655) (xy 379.480383 -409.758626) (xy 379.476773 -409.745364) (xy 379.47346 -409.739338)
			(xy 379.457115 -409.710977) (xy 379.431307 -409.650822) (xy 379.413811 -409.587746) (xy 379.404945 -409.522892)
			(xy 379.404372 -409.490164) (xy 378.131664 -409.490164) (xy 378.122798 -409.510837) (xy 378.106432 -409.539186)
			(xy 378.103125 -409.545214) (xy 378.099514 -409.558475) (xy 378.09932 -409.565348) (xy 378.09932 -410.314648)
			(xy 378.099529 -410.32152) (xy 378.103126 -410.334783) (xy 378.106432 -410.34081) (xy 378.122795 -410.369161)
			(xy 378.148599 -410.429319) (xy 378.16609 -410.492398) (xy 378.17495 -410.557255) (xy 378.17552 -410.589984)
			(xy 378.174967 -410.622705) (xy 381.604865 -410.622705) (xy 381.604867 -410.557268) (xy 381.613651 -410.492423)
			(xy 381.63106 -410.429343) (xy 381.656778 -410.369172) (xy 381.6731 -410.34081) (xy 381.676411 -410.334784)
			(xy 381.680019 -410.321521) (xy 381.680212 -410.314648) (xy 381.680212 -409.565348) (xy 381.68 -409.558476)
			(xy 381.676405 -409.545214) (xy 381.6731 -409.539186) (xy 381.656789 -409.510819) (xy 381.631073 -409.450649)
			(xy 381.613665 -409.387571) (xy 381.604881 -409.322728) (xy 381.604879 -409.257293) (xy 381.613661 -409.192449)
			(xy 381.631066 -409.129371) (xy 381.65678 -409.0692) (xy 381.6731 -409.040838) (xy 381.676401 -409.034807)
			(xy 381.680015 -409.021548) (xy 381.680212 -409.014676) (xy 381.680212 -408.728672) (xy 381.680599 -408.718515)
			(xy 381.688406 -408.699759) (xy 381.702813 -408.685436) (xy 381.721614 -408.67774) (xy 381.731774 -408.677364)
			(xy 382.448054 -408.677364) (xy 382.458181 -408.677865) (xy 382.476905 -408.685582) (xy 382.491264 -408.699865)
			(xy 382.499081 -408.718548) (xy 382.499616 -408.728672) (xy 382.499616 -409.014676) (xy 382.499815 -409.021549)
			(xy 382.503418 -409.034812) (xy 382.506728 -409.040838) (xy 382.523061 -409.069193) (xy 382.54878 -409.129365)
			(xy 382.566188 -409.192445) (xy 382.574971 -409.257291) (xy 382.57497 -409.322729) (xy 382.566184 -409.387575)
			(xy 382.548773 -409.450654) (xy 382.523052 -409.510825) (xy 382.516108 -409.522889) (xy 383.804995 -409.522889)
			(xy 383.804999 -409.457449) (xy 383.813787 -409.392603) (xy 383.8312 -409.329523) (xy 383.856923 -409.269351)
			(xy 383.873248 -409.24099) (xy 383.876562 -409.234965) (xy 383.880169 -409.221702) (xy 383.88036 -409.214828)
			(xy 383.88036 -408.465528) (xy 383.880162 -408.458655) (xy 383.876559 -408.445392) (xy 383.873248 -408.439366)
			(xy 383.856919 -408.411009) (xy 383.831201 -408.350837) (xy 383.813794 -408.287757) (xy 383.805011 -408.222912)
			(xy 383.805012 -408.157474) (xy 383.813796 -408.092629) (xy 383.831206 -408.02955) (xy 383.856925 -407.969379)
			(xy 383.873248 -407.941018) (xy 383.876552 -407.934988) (xy 383.880165 -407.921729) (xy 383.88036 -407.914856)
			(xy 383.88036 -407.628852) (xy 383.880782 -407.6187) (xy 383.888586 -407.599954) (xy 383.902981 -407.585634)
			(xy 383.921768 -407.577929) (xy 383.931922 -407.577544) (xy 384.648202 -407.577544) (xy 384.658329 -407.578025)
			(xy 384.677051 -407.585754) (xy 384.691408 -407.600042) (xy 384.699226 -407.618727) (xy 384.699764 -407.628852)
			(xy 384.699764 -407.914856) (xy 384.699977 -407.921728) (xy 384.703571 -407.93499) (xy 384.706876 -407.941018)
			(xy 384.723191 -407.969383) (xy 384.748908 -408.029554) (xy 384.766317 -408.092631) (xy 384.775101 -408.157475)
			(xy 384.775102 -408.222911) (xy 384.76632 -408.287755) (xy 384.748913 -408.350833) (xy 384.723197 -408.411005)
			(xy 384.706876 -408.439366) (xy 384.703572 -408.445396) (xy 384.69996 -408.458656) (xy 384.699764 -408.465528)
			(xy 384.699764 -409.214828) (xy 384.69995 -409.221702) (xy 384.703563 -409.234964) (xy 384.706876 -409.24099)
			(xy 384.723167 -409.269368) (xy 384.748887 -409.329536) (xy 384.766298 -409.392611) (xy 384.775085 -409.457452)
			(xy 384.775089 -409.522886) (xy 384.76631 -409.587729) (xy 384.748907 -409.650806) (xy 384.723195 -409.710977)
			(xy 384.706876 -409.739338) (xy 384.703546 -409.745355) (xy 384.69995 -409.758625) (xy 384.699764 -409.7655)
			(xy 384.699764 -410.051504) (xy 384.699381 -410.061663) (xy 384.691577 -410.080422) (xy 384.677168 -410.094747)
			(xy 384.658363 -410.10244) (xy 384.648202 -410.102812) (xy 383.931922 -410.102812) (xy 383.921803 -410.102257)
			(xy 383.903092 -410.094546) (xy 383.888737 -410.080281) (xy 383.880908 -410.06162) (xy 383.88036 -410.051504)
			(xy 383.88036 -409.7655) (xy 383.880173 -409.758626) (xy 383.876562 -409.745363) (xy 383.873248 -409.739338)
			(xy 383.856895 -409.710994) (xy 383.83118 -409.650819) (xy 383.813775 -409.587736) (xy 383.804995 -409.522889)
			(xy 382.516108 -409.522889) (xy 382.506728 -409.539186) (xy 382.50342 -409.545214) (xy 382.49981 -409.558475)
			(xy 382.499616 -409.565348) (xy 382.499616 -410.314648) (xy 382.499826 -410.32152) (xy 382.503422 -410.334783)
			(xy 382.506728 -410.34081) (xy 382.523038 -410.369178) (xy 382.548758 -410.429348) (xy 382.566169 -410.492425)
			(xy 382.574955 -410.557268) (xy 382.574956 -410.589984) (xy 386.004308 -410.589984) (xy 386.004888 -410.557255)
			(xy 386.013739 -410.492397) (xy 386.031225 -410.429317) (xy 386.057029 -410.369158) (xy 386.073396 -410.34081)
			(xy 386.076707 -410.334783) (xy 386.080315 -410.321521) (xy 386.080508 -410.314648) (xy 386.080508 -409.565348)
			(xy 386.080296 -409.558476) (xy 386.076701 -409.545214) (xy 386.073396 -409.539186) (xy 386.057024 -409.51084)
			(xy 386.031224 -409.450679) (xy 386.013736 -409.387599) (xy 386.004878 -409.322741) (xy 386.004308 -409.290012)
			(xy 386.004856 -409.257282) (xy 386.013717 -409.192423) (xy 386.031212 -409.129343) (xy 386.057025 -409.069185)
			(xy 386.073396 -409.040838) (xy 386.076697 -409.034807) (xy 386.080311 -409.021548) (xy 386.080508 -409.014676)
			(xy 386.080508 -408.728672) (xy 386.080962 -408.71856) (xy 386.088711 -408.69988) (xy 386.103017 -408.685586)
			(xy 386.121704 -408.677854) (xy 386.131816 -408.677364) (xy 386.848096 -408.677364) (xy 386.8582 -408.677888)
			(xy 386.876871 -408.685617) (xy 386.891165 -408.699902) (xy 386.898906 -408.718568) (xy 386.899404 -408.728672)
			(xy 386.899404 -409.014676) (xy 386.899605 -409.021549) (xy 386.903207 -409.034811) (xy 386.906516 -409.040838)
			(xy 386.922898 -409.069178) (xy 386.948696 -409.129341) (xy 386.966181 -409.192423) (xy 386.975036 -409.257282)
			(xy 386.975604 -409.290012) (xy 386.975021 -409.322741) (xy 386.96617 -409.387598) (xy 386.948685 -409.450679)
			(xy 386.922882 -409.510837) (xy 386.915924 -409.522889) (xy 388.204784 -409.522889) (xy 388.204789 -409.45745)
			(xy 388.213577 -409.392603) (xy 388.230989 -409.329523) (xy 388.256711 -409.269351) (xy 388.273036 -409.24099)
			(xy 388.276349 -409.234965) (xy 388.279957 -409.221702) (xy 388.280148 -409.214828) (xy 388.280148 -408.465528)
			(xy 388.279952 -408.458655) (xy 388.276347 -408.445392) (xy 388.273036 -408.439366) (xy 388.256707 -408.411008)
			(xy 388.23099 -408.350836) (xy 388.213583 -408.287757) (xy 388.2048 -408.222912) (xy 388.204801 -408.157475)
			(xy 388.213586 -408.09263) (xy 388.230995 -408.029551) (xy 388.256713 -407.969379) (xy 388.273036 -407.941018)
			(xy 388.276339 -407.934988) (xy 388.279953 -407.921728) (xy 388.280148 -407.914856) (xy 388.280148 -407.628852)
			(xy 388.280581 -407.618701) (xy 388.288383 -407.599958) (xy 388.302775 -407.585638) (xy 388.321557 -407.577931)
			(xy 388.33171 -407.577544) (xy 389.04799 -407.577544) (xy 389.058117 -407.578035) (xy 389.076838 -407.58576)
			(xy 389.091195 -407.600045) (xy 389.099014 -407.618728) (xy 389.099552 -407.628852) (xy 389.099552 -407.914856)
			(xy 389.099754 -407.921729) (xy 389.103355 -407.934992) (xy 389.106664 -407.941018) (xy 389.122979 -407.969383)
			(xy 389.148697 -408.029553) (xy 389.166106 -408.092631) (xy 389.174891 -408.157475) (xy 389.174891 -408.190192)
			(xy 392.603744 -408.190192) (xy 392.607735 -408.128025) (xy 392.619644 -408.066878) (xy 392.639273 -408.007757)
			(xy 392.666302 -407.951631) (xy 392.700286 -407.899422) (xy 392.740668 -407.851987) (xy 392.786784 -407.810106)
			(xy 392.837876 -407.774466) (xy 392.893107 -407.745652) (xy 392.951569 -407.724138) (xy 393.012303 -407.710276)
			(xy 393.07431 -407.704294) (xy 393.136573 -407.70629) (xy 393.19807 -407.716233) (xy 393.257791 -407.733957)
			(xy 393.314754 -407.759174) (xy 393.368025 -407.791467) (xy 393.41673 -407.830307) (xy 393.460067 -407.875057)
			(xy 393.497327 -407.924981) (xy 393.527896 -407.97926) (xy 393.551274 -408.037003) (xy 393.567075 -408.097261)
			(xy 393.575041 -408.159044) (xy 393.57554 -408.190192) (xy 393.575041 -408.22134) (xy 393.567075 -408.283123)
			(xy 393.551274 -408.343381) (xy 393.527896 -408.401124) (xy 393.497327 -408.455403) (xy 393.460067 -408.505327)
			(xy 393.41673 -408.550077) (xy 393.368025 -408.588917) (xy 393.314754 -408.62121) (xy 393.257791 -408.646427)
			(xy 393.19807 -408.664151) (xy 393.136573 -408.674094) (xy 393.07431 -408.67609) (xy 393.012303 -408.670108)
			(xy 392.951569 -408.656246) (xy 392.893107 -408.634732) (xy 392.837876 -408.605918) (xy 392.786784 -408.570278)
			(xy 392.740668 -408.528397) (xy 392.700286 -408.480962) (xy 392.666302 -408.428753) (xy 392.639273 -408.372627)
			(xy 392.619644 -408.313506) (xy 392.607735 -408.252359) (xy 392.603744 -408.190192) (xy 389.174891 -408.190192)
			(xy 389.174891 -408.222911) (xy 389.166109 -408.287755) (xy 389.148702 -408.350834) (xy 389.122986 -408.411005)
			(xy 389.106664 -408.439366) (xy 389.103366 -408.445399) (xy 389.099749 -408.458656) (xy 389.099552 -408.465528)
			(xy 389.099552 -409.214828) (xy 389.099727 -409.221703) (xy 389.103346 -409.234966) (xy 389.106664 -409.24099)
			(xy 389.122956 -409.269368) (xy 389.148676 -409.329535) (xy 389.166087 -409.392611) (xy 389.174875 -409.457452)
			(xy 389.174879 -409.522886) (xy 389.1661 -409.587729) (xy 389.148696 -409.650806) (xy 389.122984 -409.710977)
			(xy 389.106664 -409.739338) (xy 389.103341 -409.745359) (xy 389.09974 -409.758625) (xy 389.099552 -409.7655)
			(xy 389.099552 -410.051504) (xy 389.099083 -410.061652) (xy 389.091295 -410.080394) (xy 389.076914 -410.094716)
			(xy 389.05814 -410.102424) (xy 389.04799 -410.102812) (xy 388.33171 -410.102812) (xy 388.32159 -410.102267)
			(xy 388.302879 -410.094552) (xy 388.288524 -410.080284) (xy 388.280696 -410.061621) (xy 388.280148 -410.051504)
			(xy 388.280148 -409.7655) (xy 388.279963 -409.758626) (xy 388.276351 -409.745363) (xy 388.273036 -409.739338)
			(xy 388.256683 -409.710994) (xy 388.230969 -409.650818) (xy 388.213564 -409.587736) (xy 388.204784 -409.522889)
			(xy 386.915924 -409.522889) (xy 386.906516 -409.539186) (xy 386.903207 -409.545214) (xy 386.899598 -409.558475)
			(xy 386.899404 -409.565348) (xy 386.899404 -410.314648) (xy 386.899615 -410.32152) (xy 386.90321 -410.334783)
			(xy 386.906516 -410.34081) (xy 386.922887 -410.369156) (xy 386.948687 -410.429317) (xy 386.966175 -410.492397)
			(xy 386.975034 -410.557255) (xy 386.975604 -410.589984) (xy 386.975053 -410.622705) (xy 390.404937 -410.622705)
			(xy 390.404939 -410.557267) (xy 390.413725 -410.492421) (xy 390.431137 -410.429342) (xy 390.456859 -410.369171)
			(xy 390.473184 -410.34081) (xy 390.476494 -410.334783) (xy 390.480103 -410.321521) (xy 390.480296 -410.314648)
			(xy 390.480296 -409.565348) (xy 390.480086 -409.558476) (xy 390.47649 -409.545213) (xy 390.473184 -409.539186)
			(xy 390.456871 -409.51082) (xy 390.43115 -409.45065) (xy 390.413739 -409.387572) (xy 390.404953 -409.322729)
			(xy 390.404952 -409.257292) (xy 390.413735 -409.192448) (xy 390.431143 -409.129369) (xy 390.456861 -409.069199)
			(xy 390.473184 -409.040838) (xy 390.476484 -409.034806) (xy 390.480099 -409.021548) (xy 390.480296 -409.014676)
			(xy 390.480296 -408.728672) (xy 390.480699 -408.718517) (xy 390.488503 -408.699764) (xy 390.502905 -408.685442)
			(xy 390.5217 -408.677743) (xy 390.531858 -408.677364) (xy 391.248138 -408.677364) (xy 391.25827 -408.677796)
			(xy 391.276997 -408.685541) (xy 391.291352 -408.699844) (xy 391.299166 -408.718542) (xy 391.2997 -408.728672)
			(xy 391.2997 -409.014676) (xy 391.299901 -409.021549) (xy 391.303503 -409.034811) (xy 391.306812 -409.040838)
			(xy 391.323143 -409.069194) (xy 391.348857 -409.129367) (xy 391.366262 -409.192447) (xy 391.375043 -409.257292)
			(xy 391.375042 -409.322729) (xy 391.366258 -409.387573) (xy 391.34885 -409.450652) (xy 391.331963 -409.490164)
			(xy 392.603744 -409.490164) (xy 392.607735 -409.427997) (xy 392.619644 -409.36685) (xy 392.639273 -409.307729)
			(xy 392.666302 -409.251603) (xy 392.700286 -409.199394) (xy 392.740668 -409.151959) (xy 392.786784 -409.110078)
			(xy 392.837876 -409.074438) (xy 392.893107 -409.045624) (xy 392.951569 -409.02411) (xy 393.012303 -409.010248)
			(xy 393.07431 -409.004266) (xy 393.136573 -409.006262) (xy 393.19807 -409.016205) (xy 393.257791 -409.033929)
			(xy 393.314754 -409.059146) (xy 393.368025 -409.091439) (xy 393.41673 -409.130279) (xy 393.460067 -409.175029)
			(xy 393.497327 -409.224953) (xy 393.527896 -409.279232) (xy 393.53226 -409.290012) (xy 394.803892 -409.290012)
			(xy 394.807883 -409.227845) (xy 394.819792 -409.166698) (xy 394.839421 -409.107577) (xy 394.86645 -409.051451)
			(xy 394.900434 -408.999242) (xy 394.940816 -408.951807) (xy 394.986932 -408.909926) (xy 395.038024 -408.874286)
			(xy 395.093255 -408.845472) (xy 395.151717 -408.823958) (xy 395.212451 -408.810096) (xy 395.274458 -408.804114)
			(xy 395.336721 -408.80611) (xy 395.398218 -408.816053) (xy 395.457939 -408.833777) (xy 395.514902 -408.858994)
			(xy 395.568173 -408.891287) (xy 395.616878 -408.930127) (xy 395.660215 -408.974877) (xy 395.697475 -409.024801)
			(xy 395.728044 -409.07908) (xy 395.751422 -409.136823) (xy 395.767223 -409.197081) (xy 395.775189 -409.258864)
			(xy 395.775688 -409.290012) (xy 395.775189 -409.32116) (xy 395.767223 -409.382943) (xy 395.751422 -409.443201)
			(xy 395.728044 -409.500944) (xy 395.697475 -409.555223) (xy 395.660215 -409.605147) (xy 395.616878 -409.649897)
			(xy 395.568173 -409.688737) (xy 395.514902 -409.72103) (xy 395.457939 -409.746247) (xy 395.398218 -409.763971)
			(xy 395.336721 -409.773914) (xy 395.274458 -409.77591) (xy 395.212451 -409.769928) (xy 395.151717 -409.756066)
			(xy 395.093255 -409.734552) (xy 395.038024 -409.705738) (xy 394.986932 -409.670098) (xy 394.940816 -409.628217)
			(xy 394.900434 -409.580782) (xy 394.86645 -409.528573) (xy 394.839421 -409.472447) (xy 394.819792 -409.413326)
			(xy 394.807883 -409.352179) (xy 394.803892 -409.290012) (xy 393.53226 -409.290012) (xy 393.551274 -409.336975)
			(xy 393.567075 -409.397233) (xy 393.575041 -409.459016) (xy 393.57554 -409.490164) (xy 393.575041 -409.521312)
			(xy 393.567075 -409.583095) (xy 393.551274 -409.643353) (xy 393.527896 -409.701096) (xy 393.497327 -409.755375)
			(xy 393.460067 -409.805299) (xy 393.41673 -409.850049) (xy 393.368025 -409.888889) (xy 393.314754 -409.921182)
			(xy 393.257791 -409.946399) (xy 393.19807 -409.964123) (xy 393.136573 -409.974066) (xy 393.07431 -409.976062)
			(xy 393.012303 -409.97008) (xy 392.951569 -409.956218) (xy 392.893107 -409.934704) (xy 392.837876 -409.90589)
			(xy 392.786784 -409.87025) (xy 392.740668 -409.828369) (xy 392.700286 -409.780934) (xy 392.666302 -409.728725)
			(xy 392.639273 -409.672599) (xy 392.619644 -409.613478) (xy 392.607735 -409.552331) (xy 392.603744 -409.490164)
			(xy 391.331963 -409.490164) (xy 391.323133 -409.510824) (xy 391.306812 -409.539186) (xy 391.303503 -409.545214)
			(xy 391.299894 -409.558475) (xy 391.2997 -409.565348) (xy 391.2997 -410.314648) (xy 391.299912 -410.32152)
			(xy 391.303507 -410.334782) (xy 391.306812 -410.34081) (xy 391.323119 -410.369179) (xy 391.348835 -410.429349)
			(xy 391.366243 -410.492426) (xy 391.375027 -410.557269) (xy 391.375028 -410.589984) (xy 394.803892 -410.589984)
			(xy 394.807883 -410.527817) (xy 394.819792 -410.46667) (xy 394.839421 -410.407549) (xy 394.86645 -410.351423)
			(xy 394.900434 -410.299214) (xy 394.940816 -410.251779) (xy 394.986932 -410.209898) (xy 395.038024 -410.174258)
			(xy 395.093255 -410.145444) (xy 395.151717 -410.12393) (xy 395.212451 -410.110068) (xy 395.274458 -410.104086)
			(xy 395.336721 -410.106082) (xy 395.398218 -410.116025) (xy 395.457939 -410.133749) (xy 395.514902 -410.158966)
			(xy 395.568173 -410.191259) (xy 395.616878 -410.230099) (xy 395.660215 -410.274849) (xy 395.697475 -410.324773)
			(xy 395.728044 -410.379052) (xy 395.751422 -410.436795) (xy 395.767223 -410.497053) (xy 395.775189 -410.558836)
			(xy 395.775688 -410.589984) (xy 395.775189 -410.621132) (xy 395.767223 -410.682915) (xy 395.751422 -410.743173)
			(xy 395.728044 -410.800916) (xy 395.697475 -410.855195) (xy 395.660215 -410.905119) (xy 395.616878 -410.949869)
			(xy 395.568173 -410.988709) (xy 395.514902 -411.021002) (xy 395.457939 -411.046219) (xy 395.398218 -411.063943)
			(xy 395.336721 -411.073886) (xy 395.274458 -411.075882) (xy 395.212451 -411.0699) (xy 395.151717 -411.056038)
			(xy 395.093255 -411.034524) (xy 395.038024 -411.00571) (xy 394.986932 -410.97007) (xy 394.940816 -410.928189)
			(xy 394.900434 -410.880754) (xy 394.86645 -410.828545) (xy 394.839421 -410.772419) (xy 394.819792 -410.713298)
			(xy 394.807883 -410.652151) (xy 394.803892 -410.589984) (xy 391.375028 -410.589984) (xy 391.375029 -410.622704)
			(xy 391.366249 -410.687547) (xy 391.348844 -410.750625) (xy 391.323132 -410.810796) (xy 391.306812 -410.839158)
			(xy 391.303513 -410.84519) (xy 391.299897 -410.858448) (xy 391.2997 -410.86532) (xy 391.2997 -411.151324)
			(xy 391.299298 -411.16148) (xy 391.291495 -411.180233) (xy 391.277092 -411.194555) (xy 391.258296 -411.202254)
			(xy 391.248138 -411.202632) (xy 390.531858 -411.202632) (xy 390.521725 -411.202207) (xy 390.502998 -411.19446)
			(xy 390.488642 -411.180155) (xy 390.480829 -411.161455) (xy 390.480296 -411.151324) (xy 390.480296 -410.86532)
			(xy 390.480097 -410.858447) (xy 390.476493 -410.845185) (xy 390.473184 -410.839158) (xy 390.456847 -410.810805)
			(xy 390.431128 -410.750632) (xy 390.41372 -410.687552) (xy 390.404937 -410.622705) (xy 386.975053 -410.622705)
			(xy 386.975053 -410.622714) (xy 386.966193 -410.687573) (xy 386.948698 -410.750653) (xy 386.922887 -410.810811)
			(xy 386.906516 -410.839158) (xy 386.903217 -410.845191) (xy 386.899601 -410.858448) (xy 386.899404 -410.86532)
			(xy 386.899404 -411.151324) (xy 386.898935 -411.161434) (xy 386.89119 -411.180112) (xy 386.876888 -411.194406)
			(xy 386.858206 -411.20214) (xy 386.848096 -411.202632) (xy 386.131816 -411.202632) (xy 386.121712 -411.202103)
			(xy 386.10304 -411.194376) (xy 386.088746 -411.180093) (xy 386.081005 -411.161427) (xy 386.080508 -411.151324)
			(xy 386.080508 -410.86532) (xy 386.080308 -410.858447) (xy 386.076705 -410.845185) (xy 386.073396 -410.839158)
			(xy 386.057013 -410.810818) (xy 386.031216 -410.750655) (xy 386.013731 -410.687573) (xy 386.004876 -410.622714)
			(xy 386.004308 -410.589984) (xy 382.574956 -410.589984) (xy 382.574957 -410.622704) (xy 382.566175 -410.687548)
			(xy 382.548767 -410.750627) (xy 382.52305 -410.810797) (xy 382.506728 -410.839158) (xy 382.50343 -410.845191)
			(xy 382.499813 -410.858448) (xy 382.499616 -410.86532) (xy 382.499616 -411.151324) (xy 382.499198 -411.161478)
			(xy 382.491398 -411.180228) (xy 382.477 -411.19455) (xy 382.45821 -411.202251) (xy 382.448054 -411.202632)
			(xy 381.731774 -411.202632) (xy 381.721642 -411.202194) (xy 381.702915 -411.194453) (xy 381.688559 -411.180151)
			(xy 381.680745 -411.161454) (xy 381.680212 -411.151324) (xy 381.680212 -410.86532) (xy 381.680011 -410.858447)
			(xy 381.676409 -410.845185) (xy 381.6731 -410.839158) (xy 381.656765 -410.810804) (xy 381.631051 -410.750631)
			(xy 381.613646 -410.68755) (xy 381.604865 -410.622705) (xy 378.174967 -410.622705) (xy 378.174967 -410.622714)
			(xy 378.166107 -410.687573) (xy 378.148613 -410.750653) (xy 378.122802 -410.81081) (xy 378.106432 -410.839158)
			(xy 378.103135 -410.845191) (xy 378.099518 -410.858448) (xy 378.09932 -410.86532) (xy 378.09932 -411.151324)
			(xy 378.098835 -411.161432) (xy 378.091093 -411.180107) (xy 378.076797 -411.1944) (xy 378.05812 -411.202138)
			(xy 378.048012 -411.202632) (xy 377.331732 -411.202632) (xy 377.321615 -411.202159) (xy 377.302919 -411.194427)
			(xy 377.288604 -411.180128) (xy 377.280852 -411.16144) (xy 377.280424 -411.151324) (xy 377.280424 -410.86532)
			(xy 377.280221 -410.858448) (xy 377.27662 -410.845185) (xy 377.273312 -410.839158) (xy 377.256931 -410.810817)
			(xy 377.231132 -410.750655) (xy 377.213647 -410.687573) (xy 377.204792 -410.622714) (xy 377.204224 -410.589984)
			(xy 351.775776 -410.589984) (xy 351.775277 -410.621132) (xy 351.767311 -410.682915) (xy 351.75151 -410.743173)
			(xy 351.728132 -410.800916) (xy 351.697563 -410.855195) (xy 351.660303 -410.905119) (xy 351.616966 -410.949869)
			(xy 351.568261 -410.988709) (xy 351.51499 -411.021002) (xy 351.458027 -411.046219) (xy 351.398306 -411.063943)
			(xy 351.336809 -411.073886) (xy 351.274546 -411.075882) (xy 351.212539 -411.0699) (xy 351.151805 -411.056038)
			(xy 351.093343 -411.034524) (xy 351.038112 -411.00571) (xy 350.98702 -410.97007) (xy 350.940904 -410.928189)
			(xy 350.900522 -410.880754) (xy 350.866538 -410.828545) (xy 350.839509 -410.772419) (xy 350.81988 -410.713298)
			(xy 350.807971 -410.652151) (xy 350.80398 -410.589984) (xy 347.375118 -410.589984) (xy 347.375119 -410.622704)
			(xy 347.366338 -410.687547) (xy 347.348933 -410.750625) (xy 347.32322 -410.810796) (xy 347.3069 -410.839158)
			(xy 347.3036 -410.84519) (xy 347.299985 -410.858448) (xy 347.299788 -410.86532) (xy 347.299788 -411.151324)
			(xy 347.299398 -411.161481) (xy 347.291592 -411.180236) (xy 347.277186 -411.194559) (xy 347.258386 -411.202256)
			(xy 347.248226 -411.202632) (xy 346.531946 -411.202632) (xy 346.521819 -411.202135) (xy 346.503093 -411.194417)
			(xy 346.488735 -411.180133) (xy 346.480919 -411.161449) (xy 346.480384 -411.151324) (xy 346.480384 -410.86532)
			(xy 346.480186 -410.858447) (xy 346.476582 -410.845184) (xy 346.473272 -410.839158) (xy 346.456935 -410.810805)
			(xy 346.431217 -410.750632) (xy 346.413809 -410.687552) (xy 346.405027 -410.622705) (xy 342.975142 -410.622705)
			(xy 342.975142 -410.622714) (xy 342.966282 -410.687573) (xy 342.948787 -410.750653) (xy 342.922975 -410.81081)
			(xy 342.906604 -410.839158) (xy 342.903304 -410.84519) (xy 342.899689 -410.858448) (xy 342.899492 -410.86532)
			(xy 342.899492 -411.151324) (xy 342.899034 -411.161435) (xy 342.891287 -411.180116) (xy 342.876982 -411.19441)
			(xy 342.858296 -411.202142) (xy 342.848184 -411.202632) (xy 342.131904 -411.202632) (xy 342.121799 -411.202112)
			(xy 342.103128 -411.194382) (xy 342.088834 -411.180096) (xy 342.081093 -411.161428) (xy 342.080596 -411.151324)
			(xy 342.080596 -410.86532) (xy 342.080397 -410.858447) (xy 342.076793 -410.845185) (xy 342.073484 -410.839158)
			(xy 342.0571 -410.810819) (xy 342.031303 -410.750656) (xy 342.013819 -410.687573) (xy 342.004964 -410.622714)
			(xy 342.004396 -410.589984) (xy 338.575045 -410.589984) (xy 338.575046 -410.622704) (xy 338.566264 -410.687549)
			(xy 338.548856 -410.750627) (xy 338.523139 -410.810797) (xy 338.506816 -410.839158) (xy 338.503517 -410.845191)
			(xy 338.499901 -410.858448) (xy 338.499704 -410.86532) (xy 338.499704 -411.151324) (xy 338.499298 -411.161479)
			(xy 338.491495 -411.180231) (xy 338.477094 -411.194554) (xy 338.458299 -411.202253) (xy 338.448142 -411.202632)
			(xy 337.731862 -411.202632) (xy 337.721729 -411.202204) (xy 337.703002 -411.194458) (xy 337.688646 -411.180154)
			(xy 337.680833 -411.161455) (xy 337.6803 -411.151324) (xy 337.6803 -410.86532) (xy 337.6801 -410.858447)
			(xy 337.676497 -410.845185) (xy 337.673188 -410.839158) (xy 337.656854 -410.810804) (xy 337.63114 -410.75063)
			(xy 337.613735 -410.68755) (xy 337.604954 -410.622705) (xy 334.175057 -410.622705) (xy 334.175057 -410.622714)
			(xy 334.166196 -410.687573) (xy 334.148702 -410.750653) (xy 334.122891 -410.810811) (xy 334.10652 -410.839158)
			(xy 334.103222 -410.845191) (xy 334.099605 -410.858448) (xy 334.099408 -410.86532) (xy 334.099408 -411.151324)
			(xy 334.098935 -411.161433) (xy 334.091191 -411.180111) (xy 334.07689 -411.194404) (xy 334.05821 -411.20214)
			(xy 334.0481 -411.202632) (xy 333.33182 -411.202632) (xy 333.321716 -411.202099) (xy 333.303045 -411.194374)
			(xy 333.28875 -411.180092) (xy 333.281009 -411.161427) (xy 333.280512 -411.151324) (xy 333.280512 -410.86532)
			(xy 333.280311 -410.858447) (xy 333.276709 -410.845185) (xy 333.2734 -410.839158) (xy 333.257018 -410.810818)
			(xy 333.23122 -410.750655) (xy 333.213735 -410.687573) (xy 333.20488 -410.622714) (xy 333.204312 -410.589984)
			(xy 326.525636 -410.589984) (xy 326.525636 -412.090108) (xy 331.003918 -412.090108) (xy 331.007909 -412.027941)
			(xy 331.019818 -411.966794) (xy 331.039447 -411.907673) (xy 331.066476 -411.851547) (xy 331.10046 -411.799338)
			(xy 331.140842 -411.751903) (xy 331.186958 -411.710022) (xy 331.23805 -411.674382) (xy 331.293281 -411.645568)
			(xy 331.351743 -411.624054) (xy 331.412477 -411.610192) (xy 331.474484 -411.60421) (xy 331.536747 -411.606206)
			(xy 331.598244 -411.616149) (xy 331.657965 -411.633873) (xy 331.714928 -411.65909) (xy 331.768199 -411.691383)
			(xy 331.816904 -411.730223) (xy 331.860241 -411.774973) (xy 331.897501 -411.824897) (xy 331.92807 -411.879176)
			(xy 331.951448 -411.936919) (xy 331.967249 -411.997177) (xy 331.975215 -412.05896) (xy 331.975714 -412.090108)
			(xy 335.40396 -412.090108) (xy 335.407951 -412.027941) (xy 335.41986 -411.966794) (xy 335.439489 -411.907673)
			(xy 335.466518 -411.851547) (xy 335.500502 -411.799338) (xy 335.540884 -411.751903) (xy 335.587 -411.710022)
			(xy 335.638092 -411.674382) (xy 335.693323 -411.645568) (xy 335.751785 -411.624054) (xy 335.812519 -411.610192)
			(xy 335.874526 -411.60421) (xy 335.936789 -411.606206) (xy 335.998286 -411.616149) (xy 336.058007 -411.633873)
			(xy 336.11497 -411.65909) (xy 336.168241 -411.691383) (xy 336.216946 -411.730223) (xy 336.260283 -411.774973)
			(xy 336.297543 -411.824897) (xy 336.328112 -411.879176) (xy 336.35149 -411.936919) (xy 336.367291 -411.997177)
			(xy 336.375257 -412.05896) (xy 336.375756 -412.090108) (xy 339.804002 -412.090108) (xy 339.807993 -412.027941)
			(xy 339.819902 -411.966794) (xy 339.839531 -411.907673) (xy 339.86656 -411.851547) (xy 339.900544 -411.799338)
			(xy 339.940926 -411.751903) (xy 339.987042 -411.710022) (xy 340.038134 -411.674382) (xy 340.093365 -411.645568)
			(xy 340.151827 -411.624054) (xy 340.212561 -411.610192) (xy 340.274568 -411.60421) (xy 340.336831 -411.606206)
			(xy 340.398328 -411.616149) (xy 340.458049 -411.633873) (xy 340.515012 -411.65909) (xy 340.568283 -411.691383)
			(xy 340.616988 -411.730223) (xy 340.660325 -411.774973) (xy 340.697585 -411.824897) (xy 340.728154 -411.879176)
			(xy 340.751532 -411.936919) (xy 340.767333 -411.997177) (xy 340.775299 -412.05896) (xy 340.775798 -412.090108)
			(xy 344.20379 -412.090108) (xy 344.207781 -412.027941) (xy 344.21969 -411.966794) (xy 344.239319 -411.907673)
			(xy 344.266348 -411.851547) (xy 344.300332 -411.799338) (xy 344.340714 -411.751903) (xy 344.38683 -411.710022)
			(xy 344.437922 -411.674382) (xy 344.493153 -411.645568) (xy 344.551615 -411.624054) (xy 344.612349 -411.610192)
			(xy 344.674356 -411.60421) (xy 344.736619 -411.606206) (xy 344.798116 -411.616149) (xy 344.857837 -411.633873)
			(xy 344.9148 -411.65909) (xy 344.968071 -411.691383) (xy 345.016776 -411.730223) (xy 345.060113 -411.774973)
			(xy 345.097373 -411.824897) (xy 345.127942 -411.879176) (xy 345.15132 -411.936919) (xy 345.167121 -411.997177)
			(xy 345.175087 -412.05896) (xy 345.175586 -412.090108) (xy 348.603832 -412.090108) (xy 348.607823 -412.027941)
			(xy 348.619732 -411.966794) (xy 348.639361 -411.907673) (xy 348.66639 -411.851547) (xy 348.700374 -411.799338)
			(xy 348.740756 -411.751903) (xy 348.786872 -411.710022) (xy 348.837964 -411.674382) (xy 348.893195 -411.645568)
			(xy 348.951657 -411.624054) (xy 349.012391 -411.610192) (xy 349.074398 -411.60421) (xy 349.136661 -411.606206)
			(xy 349.198158 -411.616149) (xy 349.257879 -411.633873) (xy 349.314842 -411.65909) (xy 349.368113 -411.691383)
			(xy 349.416818 -411.730223) (xy 349.460155 -411.774973) (xy 349.497415 -411.824897) (xy 349.527984 -411.879176)
			(xy 349.551362 -411.936919) (xy 349.567163 -411.997177) (xy 349.575129 -412.05896) (xy 349.575628 -412.090108)
			(xy 375.00383 -412.090108) (xy 375.007821 -412.027941) (xy 375.01973 -411.966794) (xy 375.039359 -411.907673)
			(xy 375.066388 -411.851547) (xy 375.100372 -411.799338) (xy 375.140754 -411.751903) (xy 375.18687 -411.710022)
			(xy 375.237962 -411.674382) (xy 375.293193 -411.645568) (xy 375.351655 -411.624054) (xy 375.412389 -411.610192)
			(xy 375.474396 -411.60421) (xy 375.536659 -411.606206) (xy 375.598156 -411.616149) (xy 375.657877 -411.633873)
			(xy 375.71484 -411.65909) (xy 375.768111 -411.691383) (xy 375.816816 -411.730223) (xy 375.860153 -411.774973)
			(xy 375.897413 -411.824897) (xy 375.927982 -411.879176) (xy 375.95136 -411.936919) (xy 375.967161 -411.997177)
			(xy 375.975127 -412.05896) (xy 375.975626 -412.090108) (xy 379.403872 -412.090108) (xy 379.407863 -412.027941)
			(xy 379.419772 -411.966794) (xy 379.439401 -411.907673) (xy 379.46643 -411.851547) (xy 379.500414 -411.799338)
			(xy 379.540796 -411.751903) (xy 379.586912 -411.710022) (xy 379.638004 -411.674382) (xy 379.693235 -411.645568)
			(xy 379.751697 -411.624054) (xy 379.812431 -411.610192) (xy 379.874438 -411.60421) (xy 379.936701 -411.606206)
			(xy 379.998198 -411.616149) (xy 380.057919 -411.633873) (xy 380.114882 -411.65909) (xy 380.168153 -411.691383)
			(xy 380.216858 -411.730223) (xy 380.260195 -411.774973) (xy 380.297455 -411.824897) (xy 380.328024 -411.879176)
			(xy 380.351402 -411.936919) (xy 380.367203 -411.997177) (xy 380.375169 -412.05896) (xy 380.375668 -412.090108)
			(xy 383.803914 -412.090108) (xy 383.807905 -412.027941) (xy 383.819814 -411.966794) (xy 383.839443 -411.907673)
			(xy 383.866472 -411.851547) (xy 383.900456 -411.799338) (xy 383.940838 -411.751903) (xy 383.986954 -411.710022)
			(xy 384.038046 -411.674382) (xy 384.093277 -411.645568) (xy 384.151739 -411.624054) (xy 384.212473 -411.610192)
			(xy 384.27448 -411.60421) (xy 384.336743 -411.606206) (xy 384.39824 -411.616149) (xy 384.457961 -411.633873)
			(xy 384.514924 -411.65909) (xy 384.568195 -411.691383) (xy 384.6169 -411.730223) (xy 384.660237 -411.774973)
			(xy 384.697497 -411.824897) (xy 384.728066 -411.879176) (xy 384.751444 -411.936919) (xy 384.767245 -411.997177)
			(xy 384.775211 -412.05896) (xy 384.77571 -412.090108) (xy 388.203702 -412.090108) (xy 388.207693 -412.027941)
			(xy 388.219602 -411.966794) (xy 388.239231 -411.907673) (xy 388.26626 -411.851547) (xy 388.300244 -411.799338)
			(xy 388.340626 -411.751903) (xy 388.386742 -411.710022) (xy 388.437834 -411.674382) (xy 388.493065 -411.645568)
			(xy 388.551527 -411.624054) (xy 388.612261 -411.610192) (xy 388.674268 -411.60421) (xy 388.736531 -411.606206)
			(xy 388.798028 -411.616149) (xy 388.857749 -411.633873) (xy 388.914712 -411.65909) (xy 388.967983 -411.691383)
			(xy 389.016688 -411.730223) (xy 389.060025 -411.774973) (xy 389.097285 -411.824897) (xy 389.127854 -411.879176)
			(xy 389.151232 -411.936919) (xy 389.167033 -411.997177) (xy 389.174999 -412.05896) (xy 389.175498 -412.090108)
			(xy 392.603744 -412.090108) (xy 392.607735 -412.027941) (xy 392.619644 -411.966794) (xy 392.639273 -411.907673)
			(xy 392.666302 -411.851547) (xy 392.700286 -411.799338) (xy 392.740668 -411.751903) (xy 392.786784 -411.710022)
			(xy 392.837876 -411.674382) (xy 392.893107 -411.645568) (xy 392.951569 -411.624054) (xy 393.012303 -411.610192)
			(xy 393.07431 -411.60421) (xy 393.136573 -411.606206) (xy 393.19807 -411.616149) (xy 393.257791 -411.633873)
			(xy 393.314754 -411.65909) (xy 393.368025 -411.691383) (xy 393.41673 -411.730223) (xy 393.460067 -411.774973)
			(xy 393.497327 -411.824897) (xy 393.527896 -411.879176) (xy 393.551274 -411.936919) (xy 393.567075 -411.997177)
			(xy 393.575041 -412.05896) (xy 393.57554 -412.090108) (xy 393.575041 -412.121256) (xy 393.567075 -412.183039)
			(xy 393.551274 -412.243297) (xy 393.527896 -412.30104) (xy 393.497327 -412.355319) (xy 393.460067 -412.405243)
			(xy 393.41673 -412.449993) (xy 393.368025 -412.488833) (xy 393.314754 -412.521126) (xy 393.257791 -412.546343)
			(xy 393.19807 -412.564067) (xy 393.136573 -412.57401) (xy 393.07431 -412.576006) (xy 393.012303 -412.570024)
			(xy 392.951569 -412.556162) (xy 392.893107 -412.534648) (xy 392.837876 -412.505834) (xy 392.786784 -412.470194)
			(xy 392.740668 -412.428313) (xy 392.700286 -412.380878) (xy 392.666302 -412.328669) (xy 392.639273 -412.272543)
			(xy 392.619644 -412.213422) (xy 392.607735 -412.152275) (xy 392.603744 -412.090108) (xy 389.175498 -412.090108)
			(xy 389.174999 -412.121256) (xy 389.167033 -412.183039) (xy 389.151232 -412.243297) (xy 389.127854 -412.30104)
			(xy 389.097285 -412.355319) (xy 389.060025 -412.405243) (xy 389.016688 -412.449993) (xy 388.967983 -412.488833)
			(xy 388.914712 -412.521126) (xy 388.857749 -412.546343) (xy 388.798028 -412.564067) (xy 388.736531 -412.57401)
			(xy 388.674268 -412.576006) (xy 388.612261 -412.570024) (xy 388.551527 -412.556162) (xy 388.493065 -412.534648)
			(xy 388.437834 -412.505834) (xy 388.386742 -412.470194) (xy 388.340626 -412.428313) (xy 388.300244 -412.380878)
			(xy 388.26626 -412.328669) (xy 388.239231 -412.272543) (xy 388.219602 -412.213422) (xy 388.207693 -412.152275)
			(xy 388.203702 -412.090108) (xy 384.77571 -412.090108) (xy 384.775211 -412.121256) (xy 384.767245 -412.183039)
			(xy 384.751444 -412.243297) (xy 384.728066 -412.30104) (xy 384.697497 -412.355319) (xy 384.660237 -412.405243)
			(xy 384.6169 -412.449993) (xy 384.568195 -412.488833) (xy 384.514924 -412.521126) (xy 384.457961 -412.546343)
			(xy 384.39824 -412.564067) (xy 384.336743 -412.57401) (xy 384.27448 -412.576006) (xy 384.212473 -412.570024)
			(xy 384.151739 -412.556162) (xy 384.093277 -412.534648) (xy 384.038046 -412.505834) (xy 383.986954 -412.470194)
			(xy 383.940838 -412.428313) (xy 383.900456 -412.380878) (xy 383.866472 -412.328669) (xy 383.839443 -412.272543)
			(xy 383.819814 -412.213422) (xy 383.807905 -412.152275) (xy 383.803914 -412.090108) (xy 380.375668 -412.090108)
			(xy 380.375169 -412.121256) (xy 380.367203 -412.183039) (xy 380.351402 -412.243297) (xy 380.328024 -412.30104)
			(xy 380.297455 -412.355319) (xy 380.260195 -412.405243) (xy 380.216858 -412.449993) (xy 380.168153 -412.488833)
			(xy 380.114882 -412.521126) (xy 380.057919 -412.546343) (xy 379.998198 -412.564067) (xy 379.936701 -412.57401)
			(xy 379.874438 -412.576006) (xy 379.812431 -412.570024) (xy 379.751697 -412.556162) (xy 379.693235 -412.534648)
			(xy 379.638004 -412.505834) (xy 379.586912 -412.470194) (xy 379.540796 -412.428313) (xy 379.500414 -412.380878)
			(xy 379.46643 -412.328669) (xy 379.439401 -412.272543) (xy 379.419772 -412.213422) (xy 379.407863 -412.152275)
			(xy 379.403872 -412.090108) (xy 375.975626 -412.090108) (xy 375.975127 -412.121256) (xy 375.967161 -412.183039)
			(xy 375.95136 -412.243297) (xy 375.927982 -412.30104) (xy 375.897413 -412.355319) (xy 375.860153 -412.405243)
			(xy 375.816816 -412.449993) (xy 375.768111 -412.488833) (xy 375.71484 -412.521126) (xy 375.657877 -412.546343)
			(xy 375.598156 -412.564067) (xy 375.536659 -412.57401) (xy 375.474396 -412.576006) (xy 375.412389 -412.570024)
			(xy 375.351655 -412.556162) (xy 375.293193 -412.534648) (xy 375.237962 -412.505834) (xy 375.18687 -412.470194)
			(xy 375.140754 -412.428313) (xy 375.100372 -412.380878) (xy 375.066388 -412.328669) (xy 375.039359 -412.272543)
			(xy 375.01973 -412.213422) (xy 375.007821 -412.152275) (xy 375.00383 -412.090108) (xy 349.575628 -412.090108)
			(xy 349.575129 -412.121256) (xy 349.567163 -412.183039) (xy 349.551362 -412.243297) (xy 349.527984 -412.30104)
			(xy 349.497415 -412.355319) (xy 349.460155 -412.405243) (xy 349.416818 -412.449993) (xy 349.368113 -412.488833)
			(xy 349.314842 -412.521126) (xy 349.257879 -412.546343) (xy 349.198158 -412.564067) (xy 349.136661 -412.57401)
			(xy 349.074398 -412.576006) (xy 349.012391 -412.570024) (xy 348.951657 -412.556162) (xy 348.893195 -412.534648)
			(xy 348.837964 -412.505834) (xy 348.786872 -412.470194) (xy 348.740756 -412.428313) (xy 348.700374 -412.380878)
			(xy 348.66639 -412.328669) (xy 348.639361 -412.272543) (xy 348.619732 -412.213422) (xy 348.607823 -412.152275)
			(xy 348.603832 -412.090108) (xy 345.175586 -412.090108) (xy 345.175087 -412.121256) (xy 345.167121 -412.183039)
			(xy 345.15132 -412.243297) (xy 345.127942 -412.30104) (xy 345.097373 -412.355319) (xy 345.060113 -412.405243)
			(xy 345.016776 -412.449993) (xy 344.968071 -412.488833) (xy 344.9148 -412.521126) (xy 344.857837 -412.546343)
			(xy 344.798116 -412.564067) (xy 344.736619 -412.57401) (xy 344.674356 -412.576006) (xy 344.612349 -412.570024)
			(xy 344.551615 -412.556162) (xy 344.493153 -412.534648) (xy 344.437922 -412.505834) (xy 344.38683 -412.470194)
			(xy 344.340714 -412.428313) (xy 344.300332 -412.380878) (xy 344.266348 -412.328669) (xy 344.239319 -412.272543)
			(xy 344.21969 -412.213422) (xy 344.207781 -412.152275) (xy 344.20379 -412.090108) (xy 340.775798 -412.090108)
			(xy 340.775299 -412.121256) (xy 340.767333 -412.183039) (xy 340.751532 -412.243297) (xy 340.728154 -412.30104)
			(xy 340.697585 -412.355319) (xy 340.660325 -412.405243) (xy 340.616988 -412.449993) (xy 340.568283 -412.488833)
			(xy 340.515012 -412.521126) (xy 340.458049 -412.546343) (xy 340.398328 -412.564067) (xy 340.336831 -412.57401)
			(xy 340.274568 -412.576006) (xy 340.212561 -412.570024) (xy 340.151827 -412.556162) (xy 340.093365 -412.534648)
			(xy 340.038134 -412.505834) (xy 339.987042 -412.470194) (xy 339.940926 -412.428313) (xy 339.900544 -412.380878)
			(xy 339.86656 -412.328669) (xy 339.839531 -412.272543) (xy 339.819902 -412.213422) (xy 339.807993 -412.152275)
			(xy 339.804002 -412.090108) (xy 336.375756 -412.090108) (xy 336.375257 -412.121256) (xy 336.367291 -412.183039)
			(xy 336.35149 -412.243297) (xy 336.328112 -412.30104) (xy 336.297543 -412.355319) (xy 336.260283 -412.405243)
			(xy 336.216946 -412.449993) (xy 336.168241 -412.488833) (xy 336.11497 -412.521126) (xy 336.058007 -412.546343)
			(xy 335.998286 -412.564067) (xy 335.936789 -412.57401) (xy 335.874526 -412.576006) (xy 335.812519 -412.570024)
			(xy 335.751785 -412.556162) (xy 335.693323 -412.534648) (xy 335.638092 -412.505834) (xy 335.587 -412.470194)
			(xy 335.540884 -412.428313) (xy 335.500502 -412.380878) (xy 335.466518 -412.328669) (xy 335.439489 -412.272543)
			(xy 335.41986 -412.213422) (xy 335.407951 -412.152275) (xy 335.40396 -412.090108) (xy 331.975714 -412.090108)
			(xy 331.975215 -412.121256) (xy 331.967249 -412.183039) (xy 331.951448 -412.243297) (xy 331.92807 -412.30104)
			(xy 331.897501 -412.355319) (xy 331.860241 -412.405243) (xy 331.816904 -412.449993) (xy 331.768199 -412.488833)
			(xy 331.714928 -412.521126) (xy 331.657965 -412.546343) (xy 331.598244 -412.564067) (xy 331.536747 -412.57401)
			(xy 331.474484 -412.576006) (xy 331.412477 -412.570024) (xy 331.351743 -412.556162) (xy 331.293281 -412.534648)
			(xy 331.23805 -412.505834) (xy 331.186958 -412.470194) (xy 331.140842 -412.428313) (xy 331.10046 -412.380878)
			(xy 331.066476 -412.328669) (xy 331.039447 -412.272543) (xy 331.019818 -412.213422) (xy 331.007909 -412.152275)
			(xy 331.003918 -412.090108) (xy 326.525636 -412.090108) (xy 326.525636 -416.567112) (xy 326.52676 -416.576618)
			(xy 326.535069 -416.593847) (xy 326.549082 -416.606867) (xy 326.566874 -416.61389) (xy 326.576436 -416.614356)
		)
		(stroke
			(width 0)
			(type solid)
		)
		(fill yes)
		(layer "In11.Cu")
		(net "GND")
	)
	(gr_poly
		(pts
			(xy 398.993868 -318.779144) (xy 399.003505 -318.778687) (xy 399.021404 -318.771523) (xy 399.028666 -318.765174)
			(xy 399.079466 -318.717168) (xy 399.082883 -318.713783) (xy 399.088508 -318.705984) (xy 399.090642 -318.701674)
			(xy 399.094706 -318.693038) (xy 399.095214 -318.683132) (xy 399.097158 -318.657474) (xy 399.108553 -318.607301)
			(xy 399.128197 -318.559747) (xy 399.155533 -318.516158) (xy 399.189789 -318.477767) (xy 399.229994 -318.44566)
			(xy 399.275011 -318.420746) (xy 399.323567 -318.40373) (xy 399.374288 -318.395092) (xy 399.400014 -318.394588)
			(xy 399.431764 -318.396366) (xy 399.442686 -318.397382) (xy 399.452846 -318.39408) (xy 399.461228 -318.390524)
			(xy 399.471388 -318.383412) (xy 399.527268 -318.332866) (xy 399.534771 -318.325319) (xy 399.543416 -318.305899)
			(xy 399.544032 -318.295274) (xy 399.544032 -318.224916) (xy 399.544195 -318.211262) (xy 399.546486 -318.18405)
			(xy 399.548604 -318.17056) (xy 399.550636 -318.158622) (xy 399.54708 -318.147192) (xy 399.545564 -318.142663)
			(xy 399.541084 -318.134228) (xy 399.53819 -318.130428) (xy 399.535396 -318.12738) (xy 399.479008 -318.068452)
			(xy 399.474778 -318.064222) (xy 399.464766 -318.057679) (xy 399.459196 -318.055498) (xy 399.448274 -318.051688)
			(xy 399.436336 -318.053212) (xy 399.427289 -318.054201) (xy 399.409115 -318.055217) (xy 399.400014 -318.055244)
			(xy 399.375189 -318.054759) (xy 399.326194 -318.046729) (xy 399.279143 -318.030877) (xy 399.235277 -318.007622)
			(xy 399.19575 -317.977577) (xy 399.161606 -317.941532) (xy 399.133743 -317.900438) (xy 399.112896 -317.855378)
			(xy 399.099613 -317.807539) (xy 399.094245 -317.75818) (xy 399.096934 -317.708604) (xy 399.107607 -317.660116)
			(xy 399.125986 -317.613993) (xy 399.151584 -317.571451) (xy 399.183727 -317.533612) (xy 399.221569 -317.501471)
			(xy 399.264113 -317.475876) (xy 399.310237 -317.457501) (xy 399.358726 -317.446831) (xy 399.408302 -317.444146)
			(xy 399.45766 -317.449517) (xy 399.505499 -317.462803) (xy 399.550558 -317.483654) (xy 399.591649 -317.51152)
			(xy 399.627692 -317.545667) (xy 399.657734 -317.585195) (xy 399.680986 -317.629063) (xy 399.696834 -317.676115)
			(xy 399.704861 -317.725111) (xy 399.705322 -317.749936) (xy 399.705224 -317.75904) (xy 399.704081 -317.777213)
			(xy 399.703036 -317.786258) (xy 399.701766 -317.79845) (xy 399.705576 -317.809372) (xy 399.707746 -317.814947)
			(xy 399.714302 -317.82495) (xy 399.71853 -317.829184) (xy 399.777458 -317.885318) (xy 399.781879 -317.889306)
			(xy 399.792142 -317.895337) (xy 399.797778 -317.897256) (xy 399.8087 -317.900558) (xy 399.820638 -317.89878)
			(xy 399.834064 -317.896661) (xy 399.861149 -317.894374) (xy 399.87474 -317.894208) (xy 399.884158 -317.894244)
			(xy 399.902965 -317.895261) (xy 399.912332 -317.89624) (xy 399.923762 -317.897764) (xy 399.934684 -317.893954)
			(xy 399.939996 -317.891949) (xy 399.949616 -317.885924) (xy 399.953734 -317.882016) (xy 400.010376 -317.825628)
			(xy 400.014172 -317.821604) (xy 400.020059 -317.812243) (xy 400.02206 -317.807086) (xy 400.026124 -317.796164)
			(xy 400.024854 -317.784734) (xy 400.023076 -317.749936) (xy 400.023577 -317.724234) (xy 400.031611 -317.673463)
			(xy 400.047488 -317.624574) (xy 400.070816 -317.578769) (xy 400.101021 -317.537177) (xy 400.13736 -317.500821)
			(xy 400.178938 -317.470596) (xy 400.224731 -317.447247) (xy 400.273613 -317.431347) (xy 400.324381 -317.423289)
			(xy 400.375784 -317.42327) (xy 400.426557 -317.431292) (xy 400.47545 -317.447156) (xy 400.521261 -317.470473)
			(xy 400.562861 -317.500667) (xy 400.599226 -317.536997) (xy 400.629461 -317.578568) (xy 400.652822 -317.624355)
			(xy 400.668734 -317.673234) (xy 400.676805 -317.723999) (xy 400.676836 -317.775402) (xy 400.668827 -317.826177)
			(xy 400.652975 -317.875075) (xy 400.62967 -317.920891) (xy 400.599486 -317.962498) (xy 400.563165 -317.998872)
			(xy 400.521602 -318.029118) (xy 400.47582 -318.05249) (xy 400.426946 -318.068414) (xy 400.376183 -318.076498)
			(xy 400.350482 -318.077088) (xy 400.349974 -318.077088) (xy 400.315176 -318.075056) (xy 400.303492 -318.073786)
			(xy 400.292824 -318.077596) (xy 400.287513 -318.079602) (xy 400.277896 -318.085631) (xy 400.273774 -318.089534)
			(xy 400.21764 -318.146176) (xy 400.213749 -318.150234) (xy 400.207727 -318.159727) (xy 400.205702 -318.164972)
			(xy 400.201892 -318.175894) (xy 400.203416 -318.187578) (xy 400.204386 -318.196882) (xy 400.205404 -318.215562)
			(xy 400.205448 -318.224916) (xy 400.205448 -318.27343) (xy 400.205915 -318.284085) (xy 400.214611 -318.303538)
			(xy 400.222212 -318.311022) (xy 400.278346 -318.361822) (xy 400.28235 -318.365215) (xy 400.29144 -318.370461)
			(xy 400.29638 -318.372236) (xy 400.306286 -318.375538) (xy 400.317208 -318.374522) (xy 400.349974 -318.372744)
			(xy 400.374828 -318.373205) (xy 400.423965 -318.380724) (xy 400.471398 -318.395591) (xy 400.516036 -318.417466)
			(xy 400.556848 -318.445843) (xy 400.592897 -318.480069) (xy 400.623351 -318.519357) (xy 400.647509 -318.562801)
			(xy 400.664815 -318.6094) (xy 400.674869 -318.658081) (xy 400.676618 -318.682878) (xy 400.677126 -318.692784)
			(xy 400.68119 -318.70142) (xy 400.683309 -318.705739) (xy 400.688937 -318.71354) (xy 400.692366 -318.716914)
			(xy 400.742912 -318.765174) (xy 400.744436 -318.766444) (xy 400.744944 -318.766952) (xy 400.75153 -318.772135)
			(xy 400.76708 -318.77836) (xy 400.775424 -318.779144) (xy 400.893788 -318.779144) (xy 400.903424 -318.778683)
			(xy 400.921317 -318.771514) (xy 400.928586 -318.765174) (xy 400.979386 -318.717168) (xy 400.982802 -318.713783)
			(xy 400.988425 -318.705982) (xy 400.990562 -318.701674) (xy 400.994626 -318.693038) (xy 400.995134 -318.683132)
			(xy 400.997078 -318.657475) (xy 401.008474 -318.607303) (xy 401.028118 -318.55975) (xy 401.055455 -318.516163)
			(xy 401.08971 -318.477774) (xy 401.129915 -318.44567) (xy 401.174932 -318.420759) (xy 401.223488 -318.403745)
			(xy 401.274209 -318.39511) (xy 401.299934 -318.394588) (xy 401.331684 -318.396366) (xy 401.342606 -318.397382)
			(xy 401.352766 -318.39408) (xy 401.361148 -318.390524) (xy 401.371308 -318.383412) (xy 401.427188 -318.332866)
			(xy 401.434688 -318.325318) (xy 401.44333 -318.305898) (xy 401.443952 -318.295274) (xy 401.443952 -318.224916)
			(xy 401.444115 -318.211262) (xy 401.446406 -318.18405) (xy 401.448524 -318.17056) (xy 401.450556 -318.158622)
			(xy 401.447 -318.147192) (xy 401.445484 -318.142662) (xy 401.441006 -318.134227) (xy 401.43811 -318.130428)
			(xy 401.435316 -318.12738) (xy 401.378928 -318.068452) (xy 401.374699 -318.06422) (xy 401.364689 -318.057674)
			(xy 401.359116 -318.055498) (xy 401.348194 -318.051688) (xy 401.336256 -318.053212) (xy 401.327209 -318.054201)
			(xy 401.309035 -318.055218) (xy 401.299934 -318.055244) (xy 401.275109 -318.054761) (xy 401.226112 -318.046733)
			(xy 401.17906 -318.030884) (xy 401.135191 -318.007632) (xy 401.095663 -317.977588) (xy 401.061516 -317.941545)
			(xy 401.033651 -317.900452) (xy 401.012801 -317.855392) (xy 400.999516 -317.807552) (xy 400.994145 -317.758194)
			(xy 400.996832 -317.708617) (xy 401.007504 -317.660127) (xy 401.025881 -317.614003) (xy 401.051477 -317.57146)
			(xy 401.08362 -317.533619) (xy 401.121462 -317.501476) (xy 401.164005 -317.47588) (xy 401.210129 -317.457503)
			(xy 401.258619 -317.446832) (xy 401.308196 -317.444146) (xy 401.357554 -317.449516) (xy 401.405394 -317.462801)
			(xy 401.450454 -317.483652) (xy 401.491546 -317.511517) (xy 401.527589 -317.545665) (xy 401.557633 -317.585193)
			(xy 401.580885 -317.629062) (xy 401.596734 -317.676114) (xy 401.604761 -317.725111) (xy 401.605242 -317.749936)
			(xy 401.605144 -317.75904) (xy 401.604001 -317.777213) (xy 401.602956 -317.786258) (xy 401.601686 -317.79845)
			(xy 401.605496 -317.809372) (xy 401.607662 -317.81495) (xy 401.614212 -317.82496) (xy 401.61845 -317.829184)
			(xy 401.677378 -317.885318) (xy 401.6818 -317.889305) (xy 401.692064 -317.895332) (xy 401.697698 -317.897256)
			(xy 401.70862 -317.900558) (xy 401.720558 -317.89878) (xy 401.733984 -317.896662) (xy 401.761069 -317.894377)
			(xy 401.77466 -317.894208) (xy 401.784078 -317.894244) (xy 401.802885 -317.895262) (xy 401.812252 -317.89624)
			(xy 401.823682 -317.897764) (xy 401.834604 -317.893954) (xy 401.839915 -317.891948) (xy 401.849532 -317.88592)
			(xy 401.853654 -317.882016) (xy 401.910296 -317.825628) (xy 401.91409 -317.821604) (xy 401.919975 -317.812242)
			(xy 401.92198 -317.807086) (xy 401.926044 -317.796164) (xy 401.924774 -317.784734) (xy 401.922996 -317.749936)
			(xy 401.923497 -317.724236) (xy 401.931531 -317.673469) (xy 401.947406 -317.624583) (xy 401.970732 -317.578782)
			(xy 402.000934 -317.537192) (xy 402.03727 -317.500839) (xy 402.078845 -317.470616) (xy 402.124634 -317.447268)
			(xy 402.173513 -317.431368) (xy 402.224276 -317.42331) (xy 402.275675 -317.42329) (xy 402.326445 -317.43131)
			(xy 402.375335 -317.447172) (xy 402.421143 -317.470486) (xy 402.46274 -317.500677) (xy 402.499103 -317.537003)
			(xy 402.529338 -317.578569) (xy 402.552698 -317.624352) (xy 402.568611 -317.673226) (xy 402.576683 -317.723988)
			(xy 402.576717 -317.775387) (xy 402.568711 -317.826158) (xy 402.552862 -317.875053) (xy 402.529561 -317.920867)
			(xy 402.499381 -317.962472) (xy 402.463065 -317.998846) (xy 402.421507 -318.029091) (xy 402.37573 -318.052464)
			(xy 402.32686 -318.06839) (xy 402.276101 -318.076476) (xy 402.250402 -318.077088) (xy 402.249894 -318.077088)
			(xy 402.215096 -318.075056) (xy 402.203412 -318.073786) (xy 402.192744 -318.077596) (xy 402.187432 -318.0796)
			(xy 402.177812 -318.085626) (xy 402.173694 -318.089534) (xy 402.11756 -318.146176) (xy 402.113668 -318.150234)
			(xy 402.107644 -318.159725) (xy 402.105622 -318.164972) (xy 402.101812 -318.175894) (xy 402.103336 -318.187578)
			(xy 402.104306 -318.196882) (xy 402.105324 -318.215562) (xy 402.105368 -318.224916) (xy 402.105368 -318.27343)
			(xy 402.105832 -318.284087) (xy 402.114519 -318.303549) (xy 402.122132 -318.311022) (xy 402.178266 -318.361822)
			(xy 402.182271 -318.365214) (xy 402.191362 -318.370457) (xy 402.1963 -318.372236) (xy 402.206206 -318.375538)
			(xy 402.217128 -318.374522) (xy 402.249894 -318.372744) (xy 402.274747 -318.373207) (xy 402.323882 -318.380728)
			(xy 402.371313 -318.395597) (xy 402.415947 -318.417472) (xy 402.456757 -318.44585) (xy 402.492803 -318.480077)
			(xy 402.523255 -318.519363) (xy 402.547411 -318.562806) (xy 402.564716 -318.609403) (xy 402.574769 -318.658083)
			(xy 402.576538 -318.682878) (xy 402.577046 -318.692784) (xy 402.58111 -318.70142) (xy 402.58323 -318.705738)
			(xy 402.588859 -318.713538) (xy 402.592286 -318.716914) (xy 402.642832 -318.765174) (xy 402.644356 -318.766444)
			(xy 402.644864 -318.766952) (xy 402.651451 -318.772132) (xy 402.667001 -318.778351) (xy 402.675344 -318.779144)
			(xy 402.793708 -318.779144) (xy 402.803342 -318.77868) (xy 402.821231 -318.771506) (xy 402.828506 -318.765174)
			(xy 402.879306 -318.717168) (xy 402.882721 -318.713782) (xy 402.888342 -318.705981) (xy 402.890482 -318.701674)
			(xy 402.894546 -318.693038) (xy 402.895054 -318.683132) (xy 402.896998 -318.657476) (xy 402.908394 -318.607305)
			(xy 402.928039 -318.559754) (xy 402.955376 -318.516168) (xy 402.989631 -318.477781) (xy 403.029837 -318.445679)
			(xy 403.074854 -318.420771) (xy 403.12341 -318.40376) (xy 403.17413 -318.395129) (xy 403.199854 -318.394588)
			(xy 403.231604 -318.396366) (xy 403.242526 -318.397382) (xy 403.252686 -318.39408) (xy 403.261068 -318.390524)
			(xy 403.271228 -318.383412) (xy 403.327108 -318.332866) (xy 403.334606 -318.325317) (xy 403.343244 -318.305898)
			(xy 403.343872 -318.295274) (xy 403.343872 -318.224916) (xy 403.344035 -318.211262) (xy 403.346326 -318.18405)
			(xy 403.348444 -318.17056) (xy 403.350476 -318.158622) (xy 403.34692 -318.147192) (xy 403.345405 -318.142662)
			(xy 403.340928 -318.134226) (xy 403.33803 -318.130428) (xy 403.335236 -318.12738) (xy 403.278848 -318.068452)
			(xy 403.27462 -318.064219) (xy 403.264611 -318.057669) (xy 403.259036 -318.055498) (xy 403.248114 -318.051688)
			(xy 403.236176 -318.053212) (xy 403.227129 -318.054202) (xy 403.208955 -318.05522) (xy 403.199854 -318.055244)
			(xy 403.17503 -318.054754) (xy 403.126038 -318.046715) (xy 403.078993 -318.030856) (xy 403.035132 -318.007594)
			(xy 402.995613 -317.977543) (xy 402.961475 -317.941494) (xy 402.93362 -317.900398) (xy 402.91278 -317.855336)
			(xy 402.899505 -317.807497) (xy 402.894144 -317.75814) (xy 402.896839 -317.708566) (xy 402.907518 -317.660081)
			(xy 402.925901 -317.613962) (xy 402.951502 -317.571425) (xy 402.983648 -317.53359) (xy 403.021492 -317.501454)
			(xy 403.064036 -317.475864) (xy 403.110159 -317.457494) (xy 403.158647 -317.446828) (xy 403.208222 -317.444146)
			(xy 403.257578 -317.44952) (xy 403.305413 -317.462808) (xy 403.350469 -317.48366) (xy 403.391558 -317.511527)
			(xy 403.427598 -317.545674) (xy 403.457638 -317.585201) (xy 403.480888 -317.629068) (xy 403.496735 -317.676118)
			(xy 403.504761 -317.725112) (xy 403.505162 -317.749936) (xy 403.505122 -317.759037) (xy 403.504103 -317.777209)
			(xy 403.50313 -317.786258) (xy 403.501606 -317.798196) (xy 403.505416 -317.809118) (xy 403.507578 -317.814698)
			(xy 403.514122 -317.824715) (xy 403.51837 -317.82893) (xy 403.577298 -317.885318) (xy 403.580346 -317.888112)
			(xy 403.584141 -317.891014) (xy 403.592579 -317.89549) (xy 403.59711 -317.897002) (xy 403.60854 -317.900558)
			(xy 403.620478 -317.898526) (xy 403.633966 -317.896398) (xy 403.66118 -317.894111) (xy 403.674834 -317.893954)
			(xy 403.684188 -317.893995) (xy 403.702869 -317.89501) (xy 403.712172 -317.895986) (xy 403.723856 -317.897256)
			(xy 403.73427 -317.8937) (xy 403.73971 -317.891638) (xy 403.749576 -317.885479) (xy 403.753828 -317.881508)
			(xy 403.810216 -317.825374) (xy 403.814012 -317.821351) (xy 403.819903 -317.811991) (xy 403.8219 -317.806832)
			(xy 403.825964 -317.79591) (xy 403.824694 -317.78448) (xy 403.822916 -317.749936) (xy 403.823417 -317.724229)
			(xy 403.831454 -317.673446) (xy 403.847334 -317.624546) (xy 403.870668 -317.578732) (xy 403.900881 -317.537131)
			(xy 403.937229 -317.500768) (xy 403.978817 -317.470538) (xy 404.024622 -317.447186) (xy 404.073516 -317.431285)
			(xy 404.124295 -317.423228) (xy 404.175709 -317.423212) (xy 404.226493 -317.431239) (xy 404.275397 -317.44711)
			(xy 404.321215 -317.470436) (xy 404.362822 -317.500641) (xy 404.399191 -317.536982) (xy 404.429429 -317.578564)
			(xy 404.452791 -317.624365) (xy 404.468701 -317.673256) (xy 404.476767 -317.724033) (xy 404.476793 -317.775447)
			(xy 404.468775 -317.826233) (xy 404.452913 -317.875139) (xy 404.429597 -317.920962) (xy 404.3994 -317.962574)
			(xy 404.363065 -317.998951) (xy 404.321489 -318.029197) (xy 404.275693 -318.052567) (xy 404.226805 -318.068486)
			(xy 404.176029 -318.076563) (xy 404.150322 -318.077088) (xy 404.149814 -318.077088) (xy 404.11527 -318.075056)
			(xy 404.10384 -318.073786) (xy 404.092918 -318.07785) (xy 404.087778 -318.07988) (xy 404.078436 -318.085783)
			(xy 404.074376 -318.089534) (xy 404.018242 -318.145922) (xy 404.014205 -318.150123) (xy 404.008031 -318.160001)
			(xy 404.00605 -318.16548) (xy 404.002494 -318.175894) (xy 404.003764 -318.187578) (xy 404.004732 -318.196882)
			(xy 404.005749 -318.215562) (xy 404.005796 -318.224916) (xy 404.005796 -318.27343) (xy 404.006261 -318.284086)
			(xy 404.014951 -318.303546) (xy 404.02256 -318.311022) (xy 404.078186 -318.361568) (xy 404.082277 -318.365087)
			(xy 404.09163 -318.370466) (xy 404.096728 -318.372236) (xy 404.106634 -318.375538) (xy 404.117556 -318.374522)
			(xy 404.14956 -318.372744) (xy 404.150068 -318.372744) (xy 404.174912 -318.373219) (xy 404.224026 -318.380761)
			(xy 404.271433 -318.395645) (xy 404.316044 -318.417529) (xy 404.35683 -318.445909) (xy 404.392855 -318.480133)
			(xy 404.423287 -318.519412) (xy 404.447428 -318.562843) (xy 404.464722 -318.609425) (xy 404.47477 -318.658088)
			(xy 404.476458 -318.682878) (xy 404.476966 -318.692784) (xy 404.48103 -318.70142) (xy 404.483147 -318.70574)
			(xy 404.48877 -318.713547) (xy 404.492206 -318.716914) (xy 404.542752 -318.765174) (xy 404.544276 -318.766444)
			(xy 404.544784 -318.766952) (xy 404.551372 -318.77213) (xy 404.566923 -318.778343) (xy 404.575264 -318.779144)
			(xy 404.693882 -318.779144) (xy 404.703518 -318.778684) (xy 404.721413 -318.771517) (xy 404.72868 -318.765174)
			(xy 404.77948 -318.717168) (xy 404.782896 -318.713783) (xy 404.78852 -318.705983) (xy 404.790656 -318.701674)
			(xy 404.79472 -318.693038) (xy 404.795228 -318.683132) (xy 404.797172 -318.657475) (xy 404.808568 -318.607302)
			(xy 404.828212 -318.559749) (xy 404.855548 -318.516161) (xy 404.889804 -318.477772) (xy 404.930009 -318.445667)
			(xy 404.975026 -318.420755) (xy 405.023582 -318.40374) (xy 405.074303 -318.395105) (xy 405.100028 -318.394588)
			(xy 405.132032 -318.396366) (xy 405.142954 -318.397382) (xy 405.153114 -318.39408) (xy 405.15807 -318.39234)
			(xy 405.167168 -318.387094) (xy 405.171148 -318.383666) (xy 405.227536 -318.33312) (xy 405.2316 -318.329056)
			(xy 405.23676 -318.322731) (xy 405.243101 -318.3077) (xy 405.244046 -318.299592) (xy 405.244046 -318.299084)
			(xy 405.2443 -318.295274) (xy 405.2443 -318.224916) (xy 405.244463 -318.211262) (xy 405.246753 -318.18405)
			(xy 405.248872 -318.17056) (xy 405.250904 -318.158622) (xy 405.247348 -318.147192) (xy 405.245833 -318.142662)
			(xy 405.241358 -318.134224) (xy 405.238458 -318.130428) (xy 405.235664 -318.12738) (xy 405.179276 -318.068452)
			(xy 405.175045 -318.064224) (xy 405.165031 -318.057688) (xy 405.159464 -318.055498) (xy 405.148542 -318.051688)
			(xy 405.13635 -318.052958) (xy 405.127306 -318.054007) (xy 405.109132 -318.055152) (xy 405.100028 -318.055244)
			(xy 405.075203 -318.05476) (xy 405.026207 -318.046732) (xy 404.979155 -318.030882) (xy 404.935287 -318.007629)
			(xy 404.895759 -317.977585) (xy 404.861613 -317.941541) (xy 404.833748 -317.900448) (xy 404.812899 -317.855388)
			(xy 404.799615 -317.807548) (xy 404.794245 -317.75819) (xy 404.796932 -317.708613) (xy 404.807605 -317.660124)
			(xy 404.825982 -317.614) (xy 404.851579 -317.571457) (xy 404.883722 -317.533617) (xy 404.921564 -317.501475)
			(xy 404.964107 -317.475878) (xy 405.010231 -317.457503) (xy 405.058721 -317.446831) (xy 405.108298 -317.444146)
			(xy 405.157656 -317.449516) (xy 405.205495 -317.462802) (xy 405.250555 -317.483652) (xy 405.291647 -317.511518)
			(xy 405.32769 -317.545665) (xy 405.357733 -317.585194) (xy 405.380985 -317.629062) (xy 405.396834 -317.676114)
			(xy 405.404861 -317.725111) (xy 405.405336 -317.749936) (xy 405.405238 -317.75904) (xy 405.404095 -317.777213)
			(xy 405.40305 -317.786258) (xy 405.40178 -317.79845) (xy 405.40559 -317.809372) (xy 405.407756 -317.81495)
			(xy 405.414305 -317.824961) (xy 405.418544 -317.829184) (xy 405.477472 -317.885572) (xy 405.48052 -317.888366)
			(xy 405.484315 -317.891267) (xy 405.492753 -317.895743) (xy 405.497284 -317.897256) (xy 405.508714 -317.900812)
			(xy 405.520652 -317.89878) (xy 405.53414 -317.896649) (xy 405.561353 -317.894362) (xy 405.575008 -317.894208)
			(xy 405.584362 -317.894251) (xy 405.603042 -317.895268) (xy 405.612346 -317.89624) (xy 405.62403 -317.897764)
			(xy 405.634698 -317.893954) (xy 405.640009 -317.891948) (xy 405.649627 -317.885921) (xy 405.653748 -317.882016)
			(xy 405.71039 -317.825628) (xy 405.714185 -317.821604) (xy 405.720071 -317.812242) (xy 405.722074 -317.807086)
			(xy 405.726138 -317.796164) (xy 405.724868 -317.78448) (xy 405.722836 -317.75019) (xy 405.722836 -317.749682)
			(xy 405.723356 -317.723985) (xy 405.731426 -317.673228) (xy 405.747334 -317.624358) (xy 405.770687 -317.578575)
			(xy 405.800912 -317.537008) (xy 405.837265 -317.500678) (xy 405.878851 -317.470479) (xy 405.924648 -317.447155)
			(xy 405.973529 -317.431278) (xy 406.024291 -317.42324) (xy 406.049988 -317.422784) (xy 406.075697 -317.423261)
			(xy 406.126483 -317.431304) (xy 406.175385 -317.447193) (xy 406.2212 -317.470537) (xy 406.262798 -317.500761)
			(xy 406.299155 -317.537121) (xy 406.329376 -317.578721) (xy 406.352716 -317.624537) (xy 406.368602 -317.67344)
			(xy 406.376641 -317.724227) (xy 406.37714 -317.749936) (xy 406.694144 -317.749936) (xy 406.698104 -317.700882)
			(xy 406.709881 -317.653098) (xy 406.729172 -317.607822) (xy 406.755475 -317.566226) (xy 406.78811 -317.529389)
			(xy 406.826231 -317.498264) (xy 406.868852 -317.473657) (xy 406.914868 -317.456205) (xy 406.963087 -317.446361)
			(xy 407.012262 -317.44438) (xy 407.061117 -317.450312) (xy 407.108388 -317.464004) (xy 407.15285 -317.485102)
			(xy 407.193353 -317.513058) (xy 407.228846 -317.54715) (xy 407.258411 -317.586494) (xy 407.281282 -317.630071)
			(xy 407.296866 -317.676752) (xy 407.304761 -317.725329) (xy 407.305256 -317.749936) (xy 407.304761 -317.774543)
			(xy 407.296866 -317.82312) (xy 407.281282 -317.869801) (xy 407.258411 -317.913378) (xy 407.228846 -317.952722)
			(xy 407.193353 -317.986814) (xy 407.15285 -318.01477) (xy 407.108388 -318.035868) (xy 407.061117 -318.04956)
			(xy 407.012262 -318.055492) (xy 406.963087 -318.053511) (xy 406.914868 -318.043667) (xy 406.868852 -318.026215)
			(xy 406.826231 -318.001608) (xy 406.78811 -317.970483) (xy 406.755475 -317.933646) (xy 406.729172 -317.89205)
			(xy 406.709881 -317.846774) (xy 406.698104 -317.79899) (xy 406.694144 -317.749936) (xy 406.37714 -317.749936)
			(xy 406.376634 -317.775629) (xy 406.368594 -317.826382) (xy 406.352718 -317.875254) (xy 406.329396 -317.921042)
			(xy 406.299202 -317.962621) (xy 406.262878 -317.998968) (xy 406.221318 -318.029188) (xy 406.175544 -318.052539)
			(xy 406.126682 -318.068446) (xy 406.075935 -318.076518) (xy 406.050242 -318.077088) (xy 406.049734 -318.077088)
			(xy 406.015444 -318.075056) (xy 406.00376 -318.073786) (xy 405.992838 -318.07785) (xy 405.987696 -318.079879)
			(xy 405.978352 -318.085779) (xy 405.974296 -318.089534) (xy 405.917908 -318.146176) (xy 405.914026 -318.150314)
			(xy 405.90801 -318.159931) (xy 405.90597 -318.165226) (xy 405.90216 -318.175894) (xy 405.903684 -318.187578)
			(xy 405.904654 -318.196882) (xy 405.905673 -318.215562) (xy 405.905716 -318.224916) (xy 405.905716 -318.27343)
			(xy 405.906182 -318.284086) (xy 405.914874 -318.303543) (xy 405.92248 -318.311022) (xy 405.978106 -318.361568)
			(xy 405.982198 -318.365086) (xy 405.991552 -318.370461) (xy 405.996648 -318.372236) (xy 406.006554 -318.375538)
			(xy 406.017476 -318.374522) (xy 406.049734 -318.372744) (xy 406.050242 -318.372744) (xy 406.075083 -318.373225)
			(xy 406.124188 -318.380775) (xy 406.171586 -318.395666) (xy 406.216186 -318.417554) (xy 406.256963 -318.445936)
			(xy 406.292978 -318.480159) (xy 406.323403 -318.519436) (xy 406.347537 -318.562862) (xy 406.364826 -318.609439)
			(xy 406.374871 -318.658095) (xy 406.376632 -318.682878) (xy 406.37714 -318.692784) (xy 406.381204 -318.70142)
			(xy 406.383324 -318.705738) (xy 406.388952 -318.713539) (xy 406.39238 -318.716914) (xy 406.442926 -318.765174)
			(xy 406.44445 -318.766444) (xy 406.444958 -318.766952) (xy 406.451545 -318.772133) (xy 406.467095 -318.778354)
			(xy 406.475438 -318.779144) (xy 406.593802 -318.779144) (xy 406.603437 -318.778681) (xy 406.621327 -318.771508)
			(xy 406.6286 -318.765174) (xy 406.6794 -318.717168) (xy 406.682815 -318.713782) (xy 406.688437 -318.705981)
			(xy 406.690576 -318.701674) (xy 406.69464 -318.693038) (xy 406.695148 -318.683132) (xy 406.696962 -318.658827)
			(xy 406.707336 -318.611208) (xy 406.725144 -318.565842) (xy 406.749935 -318.523883) (xy 406.781077 -318.486395)
			(xy 406.81778 -318.454331) (xy 406.859111 -318.428506) (xy 406.904021 -318.409577) (xy 406.951367 -318.398023)
			(xy 406.999948 -318.394139) (xy 407.048529 -318.398023) (xy 407.095875 -318.409577) (xy 407.140785 -318.428506)
			(xy 407.182116 -318.454331) (xy 407.218819 -318.486395) (xy 407.249961 -318.523883) (xy 407.274752 -318.565842)
			(xy 407.29256 -318.611208) (xy 407.302934 -318.658827) (xy 407.304748 -318.683132) (xy 407.305256 -318.693038)
			(xy 407.30932 -318.701674) (xy 407.31144 -318.705992) (xy 407.317068 -318.713793) (xy 407.320496 -318.717168)
			(xy 407.371296 -318.765174) (xy 407.378563 -318.771524) (xy 407.396454 -318.778712) (xy 407.406094 -318.779144)
			(xy 407.524458 -318.779144) (xy 407.532817 -318.778425) (xy 407.548381 -318.772187) (xy 407.554938 -318.766952)
			(xy 407.555446 -318.766444) (xy 407.55697 -318.765174) (xy 407.607516 -318.716914) (xy 407.610933 -318.713529)
			(xy 407.616559 -318.705731) (xy 407.618692 -318.70142) (xy 407.622756 -318.692784) (xy 407.623264 -318.682878)
			(xy 407.625024 -318.6581) (xy 407.635092 -318.609459) (xy 407.652396 -318.562899) (xy 407.676539 -318.51949)
			(xy 407.706967 -318.480228) (xy 407.742979 -318.446017) (xy 407.783749 -318.417643) (xy 407.828339 -318.395757)
			(xy 407.875726 -318.380863) (xy 407.924819 -318.373303) (xy 407.949654 -318.372744) (xy 407.950162 -318.372744)
			(xy 407.98242 -318.374522) (xy 407.993342 -318.375538) (xy 408.003248 -318.372236) (xy 408.008339 -318.370451)
			(xy 408.017683 -318.365066) (xy 408.02179 -318.361568) (xy 408.077416 -318.311022) (xy 408.084922 -318.303476)
			(xy 408.09358 -318.284057) (xy 408.09418 -318.27343) (xy 408.09418 -318.224916) (xy 408.094223 -318.215562)
			(xy 408.095238 -318.196881) (xy 408.096212 -318.187578) (xy 408.097736 -318.175894) (xy 408.093926 -318.165226)
			(xy 408.091921 -318.159914) (xy 408.085895 -318.150296) (xy 408.081988 -318.146176) (xy 408.0256 -318.089534)
			(xy 408.02158 -318.085733) (xy 408.012224 -318.079831) (xy 408.007058 -318.07785) (xy 407.996136 -318.073786)
			(xy 407.984452 -318.075056) (xy 407.950162 -318.077088) (xy 407.949654 -318.077088) (xy 407.923958 -318.076566)
			(xy 407.873203 -318.068492) (xy 407.824335 -318.052583) (xy 407.778555 -318.029228) (xy 407.736989 -317.999003)
			(xy 407.70066 -317.962651) (xy 407.670462 -317.921066) (xy 407.647137 -317.875271) (xy 407.631259 -317.826393)
			(xy 407.623218 -317.775632) (xy 407.622756 -317.749936) (xy 407.623231 -317.724225) (xy 407.631271 -317.673434)
			(xy 407.647157 -317.624527) (xy 407.670499 -317.578707) (xy 407.700723 -317.537104) (xy 407.737082 -317.500741)
			(xy 407.778683 -317.470514) (xy 407.824501 -317.447168) (xy 407.873407 -317.431277) (xy 407.924197 -317.423234)
			(xy 407.949908 -317.422784) (xy 407.975602 -317.423288) (xy 408.026357 -317.431324) (xy 408.075231 -317.447198)
			(xy 408.121021 -317.470519) (xy 408.162602 -317.500713) (xy 408.19895 -317.537038) (xy 408.229171 -317.578599)
			(xy 408.252521 -317.624375) (xy 408.268427 -317.673239) (xy 408.276496 -317.723989) (xy 408.27706 -317.749682)
			(xy 408.27706 -317.75019) (xy 408.275028 -317.78448) (xy 408.273758 -317.796164) (xy 408.277822 -317.807086)
			(xy 408.279843 -317.812232) (xy 408.285731 -317.821588) (xy 408.289506 -317.825628) (xy 408.346148 -317.882016)
			(xy 408.350286 -317.885899) (xy 408.359902 -317.891917) (xy 408.365198 -317.893954) (xy 408.375866 -317.897764)
			(xy 408.38755 -317.89624) (xy 408.396854 -317.895273) (xy 408.415534 -317.894258) (xy 408.424888 -317.894208)
			(xy 408.438542 -317.894371) (xy 408.465754 -317.896662) (xy 408.479244 -317.89878) (xy 408.491182 -317.900812)
			(xy 408.502612 -317.897256) (xy 408.507142 -317.895741) (xy 408.51558 -317.891266) (xy 408.519376 -317.888366)
			(xy 408.522424 -317.885572) (xy 408.581352 -317.829184) (xy 408.58558 -317.824953) (xy 408.592118 -317.814939)
			(xy 408.594306 -317.809372) (xy 408.598116 -317.79845) (xy 408.596846 -317.786258) (xy 408.595797 -317.777214)
			(xy 408.594651 -317.75904) (xy 408.59456 -317.749936) (xy 408.595043 -317.725111) (xy 408.60307 -317.676115)
			(xy 408.618918 -317.629063) (xy 408.64217 -317.585195) (xy 408.672213 -317.545667) (xy 408.708256 -317.511521)
			(xy 408.749348 -317.483655) (xy 408.794407 -317.462805) (xy 408.842246 -317.44952) (xy 408.891604 -317.44415)
			(xy 408.94118 -317.446835) (xy 408.989669 -317.457507) (xy 409.035793 -317.475883) (xy 409.078335 -317.501479)
			(xy 409.116176 -317.533621) (xy 409.148319 -317.571461) (xy 409.173915 -317.614004) (xy 409.192292 -317.660127)
			(xy 409.202964 -317.708616) (xy 409.205651 -317.758192) (xy 409.200281 -317.80755) (xy 409.186996 -317.855389)
			(xy 409.166147 -317.900449) (xy 409.138282 -317.941541) (xy 409.104136 -317.977584) (xy 409.064608 -318.007628)
			(xy 409.02074 -318.03088) (xy 408.973689 -318.046729) (xy 408.924693 -318.054757) (xy 408.899868 -318.055244)
			(xy 408.890764 -318.055146) (xy 408.872591 -318.054003) (xy 408.863546 -318.052958) (xy 408.851354 -318.051688)
			(xy 408.840432 -318.055498) (xy 408.834854 -318.057664) (xy 408.824843 -318.064213) (xy 408.82062 -318.068452)
			(xy 408.764232 -318.12738) (xy 408.761438 -318.130428) (xy 408.758537 -318.134223) (xy 408.754062 -318.142662)
			(xy 408.752548 -318.147192) (xy 408.748992 -318.158622) (xy 408.751024 -318.17056) (xy 408.753154 -318.184048)
			(xy 408.755441 -318.211261) (xy 408.755596 -318.224916) (xy 408.755596 -318.295274) (xy 408.75585 -318.299084)
			(xy 408.75585 -318.299592) (xy 408.756814 -318.307693) (xy 408.763167 -318.322711) (xy 408.768296 -318.329056)
			(xy 408.77236 -318.33312) (xy 408.828748 -318.383666) (xy 408.832754 -318.387057) (xy 408.841845 -318.392298)
			(xy 408.846782 -318.39408) (xy 408.856942 -318.397382) (xy 408.867864 -318.396366) (xy 408.899868 -318.394588)
			(xy 408.925594 -318.395117) (xy 408.976319 -318.40374) (xy 409.02488 -318.420745) (xy 409.069902 -318.445652)
			(xy 409.11011 -318.477756) (xy 409.144365 -318.516147) (xy 409.171699 -318.559739) (xy 409.191336 -318.607297)
			(xy 409.20272 -318.657474) (xy 409.204668 -318.683132) (xy 409.205176 -318.693038) (xy 409.20924 -318.701674)
			(xy 409.211361 -318.705992) (xy 409.21699 -318.713791) (xy 409.220416 -318.717168) (xy 409.271216 -318.765174)
			(xy 409.278484 -318.771521) (xy 409.296375 -318.778703) (xy 409.306014 -318.779144) (xy 409.424378 -318.779144)
			(xy 409.432742 -318.778437) (xy 409.448323 -318.772218) (xy 409.454858 -318.766952) (xy 409.455366 -318.766444)
			(xy 409.45689 -318.765174) (xy 409.507436 -318.716914) (xy 409.510852 -318.713529) (xy 409.516476 -318.705729)
			(xy 409.518612 -318.70142) (xy 409.522676 -318.692784) (xy 409.523184 -318.682878) (xy 409.524944 -318.658101)
			(xy 409.535012 -318.609461) (xy 409.552316 -318.562902) (xy 409.57646 -318.519494) (xy 409.606888 -318.480235)
			(xy 409.642901 -318.446026) (xy 409.683671 -318.417653) (xy 409.728261 -318.39577) (xy 409.775647 -318.380879)
			(xy 409.824739 -318.373322) (xy 409.849574 -318.372744) (xy 409.850082 -318.372744) (xy 409.88234 -318.374522)
			(xy 409.893262 -318.375538) (xy 409.903168 -318.372236) (xy 409.908263 -318.370458) (xy 409.917617 -318.365083)
			(xy 409.92171 -318.361568) (xy 409.977336 -318.311022) (xy 409.984851 -318.30348) (xy 409.993523 -318.28406)
			(xy 409.9941 -318.27343) (xy 409.9941 -318.224916) (xy 409.994143 -318.215562) (xy 409.995158 -318.196881)
			(xy 409.996132 -318.187578) (xy 409.997656 -318.175894) (xy 409.993846 -318.165226) (xy 409.991842 -318.159914)
			(xy 409.985817 -318.150293) (xy 409.981908 -318.146176) (xy 409.92552 -318.089534) (xy 409.921501 -318.085731)
			(xy 409.912146 -318.079826) (xy 409.906978 -318.07785) (xy 409.896056 -318.073786) (xy 409.884372 -318.075056)
			(xy 409.850082 -318.077088) (xy 409.849574 -318.077088) (xy 409.823877 -318.076567) (xy 409.77312 -318.068496)
			(xy 409.724248 -318.052588) (xy 409.678466 -318.029235) (xy 409.636897 -317.99901) (xy 409.600566 -317.962658)
			(xy 409.570366 -317.921072) (xy 409.547039 -317.875276) (xy 409.531159 -317.826395) (xy 409.523118 -317.775633)
			(xy 409.522676 -317.749936) (xy 409.523151 -317.724225) (xy 409.531191 -317.673436) (xy 409.547078 -317.62453)
			(xy 409.57042 -317.578712) (xy 409.600644 -317.53711) (xy 409.637004 -317.500749) (xy 409.678605 -317.470524)
			(xy 409.724423 -317.447181) (xy 409.773328 -317.431293) (xy 409.824117 -317.423252) (xy 409.849828 -317.422784)
			(xy 409.875521 -317.423289) (xy 409.926273 -317.431328) (xy 409.975145 -317.447204) (xy 410.020932 -317.470526)
			(xy 410.06251 -317.500721) (xy 410.098856 -317.537045) (xy 410.129075 -317.578605) (xy 410.152423 -317.62438)
			(xy 410.168327 -317.673242) (xy 410.176396 -317.72399) (xy 410.17698 -317.749682) (xy 410.17698 -317.75019)
			(xy 410.174948 -317.78448) (xy 410.173678 -317.796164) (xy 410.177742 -317.807086) (xy 410.179764 -317.812232)
			(xy 410.185654 -317.821586) (xy 410.189426 -317.825628) (xy 410.246068 -317.882016) (xy 410.250207 -317.885897)
			(xy 410.259824 -317.891912) (xy 410.265118 -317.893954) (xy 410.275786 -317.897764) (xy 410.28747 -317.89624)
			(xy 410.296774 -317.89527) (xy 410.315454 -317.894251) (xy 410.324808 -317.894208) (xy 410.338462 -317.894372)
			(xy 410.365674 -317.896664) (xy 410.379164 -317.89878) (xy 410.391102 -317.900812) (xy 410.402532 -317.897256)
			(xy 410.407062 -317.89574) (xy 410.415497 -317.891262) (xy 410.419296 -317.888366) (xy 410.422344 -317.885572)
			(xy 410.481272 -317.829184) (xy 410.485499 -317.824952) (xy 410.492034 -317.814938) (xy 410.494226 -317.809372)
			(xy 410.498036 -317.79845) (xy 410.496766 -317.786258) (xy 410.495717 -317.777214) (xy 410.494571 -317.75904)
			(xy 410.49448 -317.749936) (xy 410.494963 -317.725113) (xy 410.502989 -317.676121) (xy 410.518836 -317.629073)
			(xy 410.542086 -317.585208) (xy 410.572126 -317.545683) (xy 410.608165 -317.511539) (xy 410.649254 -317.483675)
			(xy 410.694309 -317.462826) (xy 410.742144 -317.449541) (xy 410.791498 -317.44417) (xy 410.84107 -317.446854)
			(xy 410.889556 -317.457524) (xy 410.935676 -317.475897) (xy 410.978216 -317.50149) (xy 411.016055 -317.533628)
			(xy 411.048196 -317.571464) (xy 411.073792 -317.614003) (xy 411.092169 -317.660121) (xy 411.102842 -317.708606)
			(xy 411.105531 -317.758178) (xy 411.100164 -317.807533) (xy 411.086882 -317.855368) (xy 411.066037 -317.900425)
			(xy 411.038176 -317.941516) (xy 411.004035 -317.977558) (xy 410.964512 -318.007601) (xy 410.920649 -318.030854)
			(xy 410.873602 -318.046705) (xy 410.824611 -318.054735) (xy 410.799788 -318.055244) (xy 410.790684 -318.055147)
			(xy 410.77251 -318.054005) (xy 410.763466 -318.052958) (xy 410.751274 -318.051688) (xy 410.740352 -318.055498)
			(xy 410.734773 -318.057662) (xy 410.724759 -318.064209) (xy 410.72054 -318.068452) (xy 410.664152 -318.12738)
			(xy 410.661358 -318.130428) (xy 410.658456 -318.134223) (xy 410.65398 -318.142661) (xy 410.652468 -318.147192)
			(xy 410.648912 -318.158622) (xy 410.650944 -318.17056) (xy 410.653074 -318.184048) (xy 410.655361 -318.211262)
			(xy 410.655516 -318.224916) (xy 410.655516 -318.295274) (xy 410.65577 -318.299084) (xy 410.65577 -318.299592)
			(xy 410.656734 -318.307693) (xy 410.663089 -318.322709) (xy 410.668216 -318.329056) (xy 410.67228 -318.33312)
			(xy 410.728668 -318.383666) (xy 410.732675 -318.387055) (xy 410.741767 -318.392293) (xy 410.746702 -318.39408)
			(xy 410.756862 -318.397382) (xy 410.767784 -318.396366) (xy 410.799788 -318.394588) (xy 410.825513 -318.395119)
			(xy 410.876235 -318.403744) (xy 410.924793 -318.420751) (xy 410.969812 -318.445659) (xy 411.010017 -318.477763)
			(xy 411.044271 -318.516154) (xy 411.071602 -318.559745) (xy 411.091237 -318.607301) (xy 411.102621 -318.657476)
			(xy 411.104588 -318.683132) (xy 411.105096 -318.693038) (xy 411.10916 -318.701674) (xy 411.111282 -318.705991)
			(xy 411.116913 -318.713789) (xy 411.120336 -318.717168) (xy 411.171136 -318.765174) (xy 411.178405 -318.771518)
			(xy 411.196296 -318.778693) (xy 411.205934 -318.779144) (xy 411.324552 -318.779144) (xy 411.332911 -318.778426)
			(xy 411.348476 -318.772189) (xy 411.355032 -318.766952) (xy 411.35554 -318.766444) (xy 411.357064 -318.765174)
			(xy 411.40761 -318.716914) (xy 411.411027 -318.71353) (xy 411.416654 -318.705731) (xy 411.418786 -318.70142)
			(xy 411.42285 -318.692784) (xy 411.423358 -318.682878) (xy 411.425118 -318.6581) (xy 411.435186 -318.609459)
			(xy 411.45249 -318.562898) (xy 411.476633 -318.519488) (xy 411.50706 -318.480226) (xy 411.543073 -318.446015)
			(xy 411.583842 -318.41764) (xy 411.628433 -318.395754) (xy 411.675819 -318.380859) (xy 411.724913 -318.373298)
			(xy 411.749748 -318.372744) (xy 411.750256 -318.372744) (xy 411.78226 -318.374522) (xy 411.793182 -318.375538)
			(xy 411.803088 -318.372236) (xy 411.808182 -318.370457) (xy 411.817533 -318.365079) (xy 411.82163 -318.361568)
			(xy 411.877256 -318.311022) (xy 411.884769 -318.303479) (xy 411.893438 -318.28406) (xy 411.89402 -318.27343)
			(xy 411.89402 -318.224916) (xy 411.894063 -318.215562) (xy 411.89508 -318.196882) (xy 411.896052 -318.187578)
			(xy 411.897322 -318.175894) (xy 411.893766 -318.16548) (xy 411.891711 -318.160035) (xy 411.885564 -318.150157)
			(xy 411.881574 -318.145922) (xy 411.82544 -318.089534) (xy 411.821417 -318.085737) (xy 411.812057 -318.079846)
			(xy 411.806898 -318.07785) (xy 411.795976 -318.073786) (xy 411.784546 -318.075056) (xy 411.750256 -318.077088)
			(xy 411.749748 -318.077088) (xy 411.72407 -318.076565) (xy 411.673351 -318.068495) (xy 411.624519 -318.052592)
			(xy 411.578774 -318.029249) (xy 411.537242 -317.999038) (xy 411.500946 -317.962705) (xy 411.470778 -317.921143)
			(xy 411.447481 -317.875374) (xy 411.431628 -317.826525) (xy 411.423609 -317.775799) (xy 411.423621 -317.724442)
			(xy 411.431665 -317.673719) (xy 411.447542 -317.624878) (xy 411.470861 -317.57912) (xy 411.50105 -317.537573)
			(xy 411.537364 -317.501257) (xy 411.57891 -317.471068) (xy 411.624667 -317.447747) (xy 411.673507 -317.431868)
			(xy 411.72423 -317.423822) (xy 411.775587 -317.423808) (xy 411.826314 -317.431825) (xy 411.875163 -317.447676)
			(xy 411.920933 -317.470971) (xy 411.962496 -317.501138) (xy 411.998831 -317.537433) (xy 412.029042 -317.578963)
			(xy 412.052387 -317.624707) (xy 412.068292 -317.67354) (xy 412.076364 -317.724258) (xy 412.0769 -317.749936)
			(xy 412.075122 -317.78448) (xy 412.073852 -317.79591) (xy 412.077916 -317.806832) (xy 412.07994 -317.811976)
			(xy 412.085834 -317.821327) (xy 412.0896 -317.825374) (xy 412.145988 -317.881508) (xy 412.150194 -317.885537)
			(xy 412.160078 -317.891692) (xy 412.165546 -317.8937) (xy 412.17596 -317.897256) (xy 412.187644 -317.895986)
			(xy 412.196948 -317.895017) (xy 412.215628 -317.893998) (xy 412.224982 -317.893954) (xy 412.238636 -317.894117)
			(xy 412.265848 -317.896407) (xy 412.279338 -317.898526) (xy 412.291276 -317.900558) (xy 412.302706 -317.897002)
			(xy 412.307236 -317.895486) (xy 412.315672 -317.891008) (xy 412.31947 -317.888112) (xy 412.322518 -317.885318)
			(xy 412.381446 -317.82893) (xy 412.385678 -317.824701) (xy 412.392225 -317.814691) (xy 412.3944 -317.809118)
			(xy 412.39821 -317.798196) (xy 412.396686 -317.786258) (xy 412.395697 -317.777211) (xy 412.39468 -317.759037)
			(xy 412.394654 -317.749936) (xy 412.395137 -317.725111) (xy 412.403164 -317.676113) (xy 412.419013 -317.629061)
			(xy 412.442266 -317.585192) (xy 412.472309 -317.545663) (xy 412.508353 -317.511515) (xy 412.549446 -317.483649)
			(xy 412.594506 -317.462799) (xy 412.642346 -317.449514) (xy 412.691705 -317.444143) (xy 412.741283 -317.44683)
			(xy 412.789773 -317.457502) (xy 412.835897 -317.475879) (xy 412.878441 -317.501476) (xy 412.916283 -317.533619)
			(xy 412.948425 -317.571461) (xy 412.974022 -317.614004) (xy 412.992399 -317.660129) (xy 413.00307 -317.708619)
			(xy 413.005756 -317.758197) (xy 413.000386 -317.807556) (xy 412.9871 -317.855396) (xy 412.96625 -317.900456)
			(xy 412.938383 -317.941549) (xy 412.904236 -317.977592) (xy 412.864707 -318.007635) (xy 412.820838 -318.030888)
			(xy 412.773785 -318.046736) (xy 412.724787 -318.054763) (xy 412.699962 -318.055244) (xy 412.690861 -318.055204)
			(xy 412.672689 -318.054185) (xy 412.66364 -318.053212) (xy 412.651702 -318.051688) (xy 412.64078 -318.055498)
			(xy 412.635199 -318.05766) (xy 412.625182 -318.064202) (xy 412.620968 -318.068452) (xy 412.56458 -318.12738)
			(xy 412.561786 -318.130428) (xy 412.558883 -318.134222) (xy 412.554404 -318.142659) (xy 412.552896 -318.147192)
			(xy 412.54934 -318.158622) (xy 412.551372 -318.17056) (xy 412.553501 -318.184048) (xy 412.55579 -318.211262)
			(xy 412.555944 -318.224916) (xy 412.555944 -318.295274) (xy 412.5564 -318.305934) (xy 412.565081 -318.325404)
			(xy 412.572708 -318.332866) (xy 412.628588 -318.383412) (xy 412.638748 -318.390524) (xy 412.64713 -318.39408)
			(xy 412.65729 -318.397382) (xy 412.668212 -318.396366) (xy 412.699962 -318.394588) (xy 412.725689 -318.395117)
			(xy 412.776414 -318.403738) (xy 412.824976 -318.420743) (xy 412.869999 -318.44565) (xy 412.910208 -318.477754)
			(xy 412.944464 -318.516145) (xy 412.971798 -318.559737) (xy 412.991435 -318.607296) (xy 413.00282 -318.657473)
			(xy 413.004762 -318.683132) (xy 413.00527 -318.693038) (xy 413.009334 -318.701674) (xy 413.011455 -318.705992)
			(xy 413.017083 -318.713792) (xy 413.02051 -318.717168) (xy 413.07131 -318.765174) (xy 413.078578 -318.771521)
			(xy 413.096469 -318.778705) (xy 413.106108 -318.779144) (xy 413.224472 -318.779144) (xy 413.232836 -318.778438)
			(xy 413.248418 -318.77222) (xy 413.254952 -318.766952) (xy 413.25546 -318.766444) (xy 413.256984 -318.765174)
			(xy 413.30753 -318.716914) (xy 413.310946 -318.713529) (xy 413.316571 -318.70573) (xy 413.318706 -318.70142)
			(xy 413.32277 -318.692784) (xy 413.323278 -318.682878) (xy 413.325038 -318.658101) (xy 413.335106 -318.609461)
			(xy 413.35241 -318.562901) (xy 413.376554 -318.519493) (xy 413.406981 -318.480233) (xy 413.442994 -318.446023)
			(xy 413.483764 -318.41765) (xy 413.528354 -318.395766) (xy 413.57574 -318.380874) (xy 413.624833 -318.373316)
			(xy 413.649668 -318.372744) (xy 413.650176 -318.372744) (xy 413.68218 -318.374522) (xy 413.693102 -318.375538)
			(xy 413.703008 -318.372236) (xy 413.708101 -318.370455) (xy 413.71745 -318.365074) (xy 413.72155 -318.361568)
			(xy 413.777176 -318.311022) (xy 413.784687 -318.303478) (xy 413.793352 -318.284059) (xy 413.79394 -318.27343)
			(xy 413.79394 -318.224916) (xy 413.793983 -318.215562) (xy 413.795 -318.196882) (xy 413.795972 -318.187578)
			(xy 413.797242 -318.175894) (xy 413.793686 -318.16548) (xy 413.791628 -318.160037) (xy 413.785475 -318.150166)
			(xy 413.781494 -318.145922) (xy 413.72536 -318.089534) (xy 413.721338 -318.085735) (xy 413.711979 -318.079841)
			(xy 413.706818 -318.07785) (xy 413.695896 -318.073786) (xy 413.684466 -318.075056) (xy 413.650176 -318.077088)
			(xy 413.649668 -318.077088) (xy 413.62399 -318.076567) (xy 413.57327 -318.068499) (xy 413.524435 -318.052599)
			(xy 413.478689 -318.029258) (xy 413.437155 -317.999049) (xy 413.400856 -317.962718) (xy 413.370686 -317.921156)
			(xy 413.347386 -317.875388) (xy 413.331531 -317.826539) (xy 413.32351 -317.775812) (xy 413.32352 -317.724455)
			(xy 413.331562 -317.673731) (xy 413.347437 -317.624888) (xy 413.370756 -317.57913) (xy 413.400943 -317.537581)
			(xy 413.437256 -317.501264) (xy 413.478802 -317.471072) (xy 413.524559 -317.44775) (xy 413.5734 -317.43187)
			(xy 413.624123 -317.423823) (xy 413.67548 -317.423807) (xy 413.726208 -317.431823) (xy 413.775059 -317.447674)
			(xy 413.820829 -317.470969) (xy 413.862393 -317.501135) (xy 413.898729 -317.537431) (xy 413.928941 -317.578961)
			(xy 413.952287 -317.624706) (xy 413.968192 -317.673539) (xy 413.976264 -317.724258) (xy 413.97682 -317.749936)
			(xy 413.975042 -317.78448) (xy 413.973772 -317.79591) (xy 413.977836 -317.806832) (xy 413.979862 -317.811976)
			(xy 413.985757 -317.821324) (xy 413.98952 -317.825374) (xy 414.045908 -317.881508) (xy 414.050115 -317.885535)
			(xy 414.060001 -317.891687) (xy 414.065466 -317.8937) (xy 414.07588 -317.897256) (xy 414.087564 -317.895986)
			(xy 414.096868 -317.895018) (xy 414.115548 -317.894) (xy 414.124902 -317.893954) (xy 414.138556 -317.894117)
			(xy 414.165768 -317.89641) (xy 414.179258 -317.898526) (xy 414.191196 -317.900558) (xy 414.202626 -317.897002)
			(xy 414.207155 -317.895485) (xy 414.215589 -317.891004) (xy 414.21939 -317.888112) (xy 414.222438 -317.885318)
			(xy 414.281366 -317.82893) (xy 414.285597 -317.8247) (xy 414.292141 -317.81469) (xy 414.29432 -317.809118)
			(xy 414.29813 -317.798196) (xy 414.296606 -317.786258) (xy 414.295617 -317.777211) (xy 414.294599 -317.759037)
			(xy 414.294574 -317.749936) (xy 414.295057 -317.725113) (xy 414.303084 -317.676119) (xy 414.318931 -317.62907)
			(xy 414.342181 -317.585204) (xy 414.372222 -317.545678) (xy 414.408262 -317.511533) (xy 414.449352 -317.483669)
			(xy 414.494408 -317.46282) (xy 414.542244 -317.449534) (xy 414.591599 -317.444164) (xy 414.641173 -317.446849)
			(xy 414.68966 -317.457519) (xy 414.735781 -317.475893) (xy 414.778322 -317.501486) (xy 414.816162 -317.533626)
			(xy 414.848303 -317.571464) (xy 414.873899 -317.614003) (xy 414.892276 -317.660123) (xy 414.902949 -317.708609)
			(xy 414.905637 -317.758183) (xy 414.900269 -317.807538) (xy 414.886987 -317.855375) (xy 414.86614 -317.900432)
			(xy 414.838278 -317.941524) (xy 414.804135 -317.977566) (xy 414.764611 -318.007609) (xy 414.720747 -318.030862)
			(xy 414.673698 -318.046712) (xy 414.624705 -318.054741) (xy 414.599882 -318.055244) (xy 414.590781 -318.055204)
			(xy 414.572609 -318.054186) (xy 414.56356 -318.053212) (xy 414.551622 -318.051688) (xy 414.5407 -318.055498)
			(xy 414.535118 -318.057658) (xy 414.525097 -318.064198) (xy 414.520888 -318.068452) (xy 414.4645 -318.12738)
			(xy 414.461706 -318.130428) (xy 414.458802 -318.134222) (xy 414.454321 -318.142658) (xy 414.452816 -318.147192)
			(xy 414.44926 -318.158622) (xy 414.451292 -318.17056) (xy 414.453421 -318.184048) (xy 414.455709 -318.211262)
			(xy 414.455864 -318.224916) (xy 414.455864 -318.295274) (xy 414.45632 -318.305934) (xy 414.465004 -318.325402)
			(xy 414.472628 -318.332866) (xy 414.528508 -318.383412) (xy 414.538668 -318.390524) (xy 414.54705 -318.39408)
			(xy 414.55721 -318.397382) (xy 414.568132 -318.396366) (xy 414.599882 -318.394588) (xy 414.625607 -318.395119)
			(xy 414.67633 -318.403743) (xy 414.724889 -318.420749) (xy 414.769909 -318.445657) (xy 414.810115 -318.477761)
			(xy 414.844369 -318.516152) (xy 414.871701 -318.559743) (xy 414.891337 -318.6073) (xy 414.90272 -318.657475)
			(xy 414.904682 -318.683132) (xy 414.90519 -318.693038) (xy 414.909254 -318.701674) (xy 414.911376 -318.705991)
			(xy 414.917006 -318.713789) (xy 414.92043 -318.717168) (xy 414.97123 -318.765174) (xy 414.978498 -318.771519)
			(xy 414.99639 -318.778696) (xy 415.006028 -318.779144) (xy 415.143696 -318.779144) (xy 415.153331 -318.778682)
			(xy 415.171223 -318.771511) (xy 415.178494 -318.765174) (xy 415.229294 -318.717168) (xy 415.232709 -318.713782)
			(xy 415.238332 -318.705982) (xy 415.24047 -318.701674) (xy 415.244534 -318.693038) (xy 415.245042 -318.683132)
			(xy 415.246986 -318.657475) (xy 415.258382 -318.607303) (xy 415.278026 -318.559751) (xy 415.305363 -318.516165)
			(xy 415.339619 -318.477777) (xy 415.379824 -318.445674) (xy 415.424841 -318.420763) (xy 415.473397 -318.403751)
			(xy 415.524117 -318.395118) (xy 415.549842 -318.394588) (xy 415.581592 -318.396366) (xy 415.592514 -318.397382)
			(xy 415.602674 -318.39408) (xy 415.611056 -318.390524) (xy 415.621216 -318.383412) (xy 415.677096 -318.332866)
			(xy 415.684595 -318.325317) (xy 415.693236 -318.305898) (xy 415.69386 -318.295274) (xy 415.69386 -318.224916)
			(xy 415.694023 -318.211262) (xy 415.696314 -318.18405) (xy 415.698432 -318.17056) (xy 415.700464 -318.158622)
			(xy 415.696908 -318.147192) (xy 415.695392 -318.142662) (xy 415.690915 -318.134226) (xy 415.688018 -318.130428)
			(xy 415.685224 -318.12738) (xy 415.628836 -318.068452) (xy 415.624608 -318.06422) (xy 415.614598 -318.057672)
			(xy 415.609024 -318.055498) (xy 415.598102 -318.051688) (xy 415.586164 -318.053212) (xy 415.577117 -318.054202)
			(xy 415.558943 -318.055219) (xy 415.549842 -318.055244) (xy 415.525017 -318.054761) (xy 415.47602 -318.046735)
			(xy 415.428967 -318.030887) (xy 415.385097 -318.007636) (xy 415.345568 -317.977593) (xy 415.31142 -317.94155)
			(xy 415.283554 -317.900457) (xy 415.262703 -317.855398) (xy 415.249417 -317.807558) (xy 415.244046 -317.758199)
			(xy 415.246731 -317.708622) (xy 415.257403 -317.660132) (xy 415.275779 -317.614007) (xy 415.301375 -317.571463)
			(xy 415.333517 -317.533621) (xy 415.371359 -317.501478) (xy 415.413902 -317.475881) (xy 415.460026 -317.457504)
			(xy 415.508516 -317.446832) (xy 415.558093 -317.444145) (xy 415.607452 -317.449515) (xy 415.655292 -317.462801)
			(xy 415.700352 -317.483651) (xy 415.741445 -317.511516) (xy 415.777489 -317.545664) (xy 415.807532 -317.585192)
			(xy 415.830785 -317.629061) (xy 415.846634 -317.676114) (xy 415.854661 -317.725111) (xy 415.85515 -317.749936)
			(xy 415.85511 -317.759037) (xy 415.854091 -317.777209) (xy 415.853118 -317.786258) (xy 415.851594 -317.798196)
			(xy 415.855404 -317.809118) (xy 415.857566 -317.814699) (xy 415.864109 -317.824716) (xy 415.868358 -317.82893)
			(xy 415.927286 -317.885318) (xy 415.930334 -317.888112) (xy 415.934128 -317.891015) (xy 415.942565 -317.895493)
			(xy 415.947098 -317.897002) (xy 415.958528 -317.900558) (xy 415.970466 -317.898526) (xy 415.983954 -317.896397)
			(xy 416.011168 -317.894109) (xy 416.024822 -317.893954) (xy 416.038476 -317.894114) (xy 416.065689 -317.8964)
			(xy 416.079178 -317.898526) (xy 416.091116 -317.900558) (xy 416.102546 -317.897002) (xy 416.107078 -317.895491)
			(xy 416.11552 -317.891021) (xy 416.11931 -317.888112) (xy 416.122358 -317.885318) (xy 416.181286 -317.82893)
			(xy 416.185515 -317.8247) (xy 416.192058 -317.814688) (xy 416.19424 -317.809118) (xy 416.19805 -317.798196)
			(xy 416.196526 -317.786258) (xy 416.195536 -317.777211) (xy 416.194519 -317.759037) (xy 416.194494 -317.749936)
			(xy 416.194977 -317.725115) (xy 416.203003 -317.676125) (xy 416.218848 -317.629079) (xy 416.242097 -317.585217)
			(xy 416.272135 -317.545694) (xy 416.308172 -317.511551) (xy 416.349258 -317.483689) (xy 416.39431 -317.46284)
			(xy 416.442142 -317.449555) (xy 416.491493 -317.444184) (xy 416.541063 -317.446867) (xy 416.589546 -317.457535)
			(xy 416.635664 -317.475907) (xy 416.678203 -317.501497) (xy 416.71604 -317.533633) (xy 416.74818 -317.571467)
			(xy 416.773776 -317.614002) (xy 416.792153 -317.660117) (xy 416.802827 -317.708599) (xy 416.805517 -317.758169)
			(xy 416.800152 -317.80752) (xy 416.786873 -317.855354) (xy 416.76603 -317.900409) (xy 416.738173 -317.941498)
			(xy 416.704034 -317.977539) (xy 416.664515 -318.007583) (xy 416.620655 -318.030837) (xy 416.573612 -318.046688)
			(xy 416.524623 -318.05472) (xy 416.499802 -318.055244) (xy 416.490701 -318.055205) (xy 416.472528 -318.054188)
			(xy 416.46348 -318.053212) (xy 416.451542 -318.051688) (xy 416.44062 -318.055498) (xy 416.435037 -318.057656)
			(xy 416.425013 -318.064193) (xy 416.420808 -318.068452) (xy 416.36442 -318.12738) (xy 416.361626 -318.130428)
			(xy 416.358726 -318.134224) (xy 416.354252 -318.142662) (xy 416.352736 -318.147192) (xy 416.34918 -318.158622)
			(xy 416.351212 -318.17056) (xy 416.353342 -318.184048) (xy 416.35563 -318.211262) (xy 416.355784 -318.224916)
			(xy 416.355784 -318.295274) (xy 416.356238 -318.305936) (xy 416.364912 -318.325413) (xy 416.372548 -318.332866)
			(xy 416.428428 -318.383412) (xy 416.438588 -318.390524) (xy 416.44697 -318.39408) (xy 416.45713 -318.397382)
			(xy 416.468052 -318.396366) (xy 416.499802 -318.394588) (xy 416.525526 -318.39512) (xy 416.576247 -318.403747)
			(xy 416.624803 -318.420755) (xy 416.66982 -318.445664) (xy 416.710023 -318.477769) (xy 416.744274 -318.516159)
			(xy 416.771604 -318.559749) (xy 416.791238 -318.607304) (xy 416.802621 -318.657478) (xy 416.804602 -318.683132)
			(xy 416.80511 -318.693038) (xy 416.809174 -318.701674) (xy 416.811297 -318.70599) (xy 416.816928 -318.713787)
			(xy 416.82035 -318.717168) (xy 416.87115 -318.765174) (xy 416.878419 -318.771516) (xy 416.896311 -318.778686)
			(xy 416.905948 -318.779144) (xy 417.04387 -318.779144) (xy 417.053507 -318.778687) (xy 417.071405 -318.771522)
			(xy 417.078668 -318.765174) (xy 417.129468 -318.717168) (xy 417.132885 -318.713783) (xy 417.13851 -318.705984)
			(xy 417.140644 -318.701674) (xy 417.144708 -318.693038) (xy 417.145216 -318.683132) (xy 417.14716 -318.657474)
			(xy 417.158555 -318.607301) (xy 417.178199 -318.559747) (xy 417.205536 -318.516158) (xy 417.239791 -318.477768)
			(xy 417.279996 -318.445661) (xy 417.325013 -318.420748) (xy 417.373569 -318.403731) (xy 417.42429 -318.395094)
			(xy 417.450016 -318.394588) (xy 417.48202 -318.396366) (xy 417.492942 -318.397382) (xy 417.503102 -318.39408)
			(xy 417.508059 -318.392341) (xy 417.517158 -318.387096) (xy 417.521136 -318.383666) (xy 417.577524 -318.33312)
			(xy 417.581588 -318.329056) (xy 417.586741 -318.322728) (xy 417.59307 -318.307697) (xy 417.594034 -318.299592)
			(xy 417.594034 -318.299084) (xy 417.594288 -318.295274) (xy 417.594288 -318.224916) (xy 417.594451 -318.211262)
			(xy 417.596741 -318.18405) (xy 417.59886 -318.17056) (xy 417.600892 -318.158622) (xy 417.597336 -318.147192)
			(xy 417.595821 -318.142662) (xy 417.591345 -318.134224) (xy 417.588446 -318.130428) (xy 417.585652 -318.12738)
			(xy 417.529264 -318.068452) (xy 417.525037 -318.064217) (xy 417.515029 -318.057664) (xy 417.509452 -318.055498)
			(xy 417.49853 -318.051688) (xy 417.486338 -318.052958) (xy 417.477294 -318.054007) (xy 417.45912 -318.055151)
			(xy 417.450016 -318.055244) (xy 417.425191 -318.054759) (xy 417.376196 -318.046729) (xy 417.329145 -318.030878)
			(xy 417.285278 -318.007623) (xy 417.245752 -317.977578) (xy 417.211607 -317.941534) (xy 417.183744 -317.90044)
			(xy 417.162896 -317.85538) (xy 417.149613 -317.80754) (xy 417.144245 -317.758182) (xy 417.146933 -317.708605)
			(xy 417.157607 -317.660117) (xy 417.175985 -317.613994) (xy 417.201583 -317.571452) (xy 417.233726 -317.533612)
			(xy 417.271568 -317.501471) (xy 417.314112 -317.475876) (xy 417.360236 -317.457501) (xy 417.408725 -317.446831)
			(xy 417.458302 -317.444146) (xy 417.50766 -317.449517) (xy 417.555498 -317.462803) (xy 417.600557 -317.483654)
			(xy 417.641649 -317.51152) (xy 417.677691 -317.545667) (xy 417.707734 -317.585195) (xy 417.730986 -317.629063)
			(xy 417.746834 -317.676115) (xy 417.754861 -317.725111) (xy 417.755324 -317.749936) (xy 417.755226 -317.75904)
			(xy 417.754083 -317.777213) (xy 417.753038 -317.786258) (xy 417.751768 -317.79845) (xy 417.755578 -317.809372)
			(xy 417.757748 -317.814947) (xy 417.764304 -317.82495) (xy 417.768532 -317.829184) (xy 417.82746 -317.885572)
			(xy 417.830508 -317.888366) (xy 417.834303 -317.891268) (xy 417.84274 -317.895746) (xy 417.847272 -317.897256)
			(xy 417.858702 -317.900812) (xy 417.87064 -317.89878) (xy 417.884128 -317.896649) (xy 417.911341 -317.89436)
			(xy 417.924996 -317.894208) (xy 417.93865 -317.894371) (xy 417.965862 -317.896663) (xy 417.979352 -317.89878)
			(xy 417.99129 -317.900812) (xy 418.00272 -317.897256) (xy 418.00725 -317.895741) (xy 418.015687 -317.891265)
			(xy 418.019484 -317.888366) (xy 418.022532 -317.885572) (xy 418.08146 -317.829184) (xy 418.085687 -317.824952)
			(xy 418.092224 -317.814939) (xy 418.094414 -317.809372) (xy 418.098224 -317.79845) (xy 418.096954 -317.786258)
			(xy 418.095905 -317.777214) (xy 418.094759 -317.75904) (xy 418.094668 -317.749936) (xy 418.095151 -317.725112)
			(xy 418.103178 -317.676118) (xy 418.119025 -317.629067) (xy 418.142277 -317.585201) (xy 418.172318 -317.545674)
			(xy 418.20836 -317.511528) (xy 418.24945 -317.483663) (xy 418.294508 -317.462813) (xy 418.342345 -317.449528)
			(xy 418.391701 -317.444158) (xy 418.441276 -317.446843) (xy 418.489764 -317.457514) (xy 418.535886 -317.475888)
			(xy 418.578428 -317.501483) (xy 418.616268 -317.533624) (xy 418.64841 -317.571463) (xy 418.674006 -317.614003)
			(xy 418.692383 -317.660125) (xy 418.703055 -317.708612) (xy 418.705743 -317.758187) (xy 418.700374 -317.807543)
			(xy 418.687091 -317.855381) (xy 418.666243 -317.900439) (xy 418.63838 -317.941531) (xy 418.604235 -317.977574)
			(xy 418.56471 -318.007617) (xy 418.520844 -318.03087) (xy 418.473794 -318.046719) (xy 418.4248 -318.054748)
			(xy 418.399976 -318.055244) (xy 418.390872 -318.055147) (xy 418.372699 -318.054004) (xy 418.363654 -318.052958)
			(xy 418.351462 -318.051688) (xy 418.34054 -318.055498) (xy 418.334962 -318.057663) (xy 418.32495 -318.064211)
			(xy 418.320728 -318.068452) (xy 418.26434 -318.12738) (xy 418.261546 -318.130428) (xy 418.258645 -318.134223)
			(xy 418.254169 -318.142661) (xy 418.252656 -318.147192) (xy 418.2491 -318.158622) (xy 418.251132 -318.17056)
			(xy 418.253262 -318.184048) (xy 418.255549 -318.211262) (xy 418.255704 -318.224916) (xy 418.255704 -318.295274)
			(xy 418.255958 -318.299084) (xy 418.255958 -318.299592) (xy 418.256922 -318.307693) (xy 418.263276 -318.32271)
			(xy 418.268404 -318.329056) (xy 418.272468 -318.33312) (xy 418.328856 -318.383666) (xy 418.332862 -318.387056)
			(xy 418.341954 -318.392296) (xy 418.34689 -318.39408) (xy 418.35705 -318.397382) (xy 418.367972 -318.396366)
			(xy 418.399976 -318.394588) (xy 418.425702 -318.395118) (xy 418.476426 -318.403741) (xy 418.524985 -318.420747)
			(xy 418.570006 -318.445655) (xy 418.610213 -318.477759) (xy 418.644468 -318.51615) (xy 418.6718 -318.559741)
			(xy 418.691436 -318.607298) (xy 418.70282 -318.657475) (xy 418.704776 -318.683132) (xy 418.705284 -318.693038)
			(xy 418.709348 -318.701674) (xy 418.71147 -318.705991) (xy 418.717099 -318.71379) (xy 418.720524 -318.717168)
			(xy 418.771324 -318.765174) (xy 418.778592 -318.771519) (xy 418.796484 -318.778699) (xy 418.806122 -318.779144)
			(xy 418.94379 -318.779144) (xy 418.953426 -318.778683) (xy 418.971318 -318.771513) (xy 418.978588 -318.765174)
			(xy 419.029388 -318.717168) (xy 419.032804 -318.713783) (xy 419.038427 -318.705982) (xy 419.040564 -318.701674)
			(xy 419.044628 -318.693038) (xy 419.045136 -318.683132) (xy 419.04708 -318.657475) (xy 419.058476 -318.607303)
			(xy 419.07812 -318.55975) (xy 419.105457 -318.516163) (xy 419.139712 -318.477775) (xy 419.179917 -318.445671)
			(xy 419.224935 -318.42076) (xy 419.27349 -318.403746) (xy 419.324211 -318.395112) (xy 419.349936 -318.394588)
			(xy 419.38194 -318.396366) (xy 419.392862 -318.397382) (xy 419.403022 -318.39408) (xy 419.407978 -318.392339)
			(xy 419.417075 -318.387092) (xy 419.421056 -318.383666) (xy 419.477444 -318.33312) (xy 419.481508 -318.329056)
			(xy 419.486668 -318.322731) (xy 419.493007 -318.3077) (xy 419.493954 -318.299592) (xy 419.493954 -318.299084)
			(xy 419.494208 -318.295274) (xy 419.494208 -318.224916) (xy 419.494371 -318.211262) (xy 419.496661 -318.18405)
			(xy 419.49878 -318.17056) (xy 419.500812 -318.158622) (xy 419.497256 -318.147192) (xy 419.495742 -318.142661)
			(xy 419.491267 -318.134223) (xy 419.488366 -318.130428) (xy 419.485572 -318.12738) (xy 419.429184 -318.068452)
			(xy 419.424953 -318.064224) (xy 419.41494 -318.057685) (xy 419.409372 -318.055498) (xy 419.39845 -318.051688)
			(xy 419.386258 -318.052958) (xy 419.377214 -318.054007) (xy 419.35904 -318.055153) (xy 419.349936 -318.055244)
			(xy 419.325111 -318.054761) (xy 419.276114 -318.046734) (xy 419.229061 -318.030885) (xy 419.185193 -318.007633)
			(xy 419.145664 -317.977589) (xy 419.111517 -317.941546) (xy 419.083651 -317.900453) (xy 419.062801 -317.855393)
			(xy 419.049516 -317.807554) (xy 419.044146 -317.758195) (xy 419.046832 -317.708618) (xy 419.057504 -317.660128)
			(xy 419.07588 -317.614004) (xy 419.101477 -317.571461) (xy 419.133619 -317.533619) (xy 419.171461 -317.501477)
			(xy 419.214004 -317.47588) (xy 419.260128 -317.457504) (xy 419.308618 -317.446832) (xy 419.358195 -317.444146)
			(xy 419.407554 -317.449516) (xy 419.455393 -317.462801) (xy 419.500453 -317.483651) (xy 419.541546 -317.511517)
			(xy 419.577589 -317.545664) (xy 419.607633 -317.585193) (xy 419.630885 -317.629061) (xy 419.646734 -317.676114)
			(xy 419.654761 -317.725111) (xy 419.655244 -317.749936) (xy 419.655146 -317.75904) (xy 419.654003 -317.777213)
			(xy 419.652958 -317.786258) (xy 419.651688 -317.79845) (xy 419.655498 -317.809372) (xy 419.657664 -317.81495)
			(xy 419.664214 -317.82496) (xy 419.668452 -317.829184) (xy 419.72738 -317.885572) (xy 419.730428 -317.888366)
			(xy 419.734223 -317.891267) (xy 419.742662 -317.895741) (xy 419.747192 -317.897256) (xy 419.758622 -317.900812)
			(xy 419.77056 -317.89878) (xy 419.784048 -317.89665) (xy 419.811261 -317.894363) (xy 419.824916 -317.894208)
			(xy 419.83857 -317.894368) (xy 419.865784 -317.896653) (xy 419.879272 -317.89878) (xy 419.89121 -317.900812)
			(xy 419.90264 -317.897256) (xy 419.907173 -317.895747) (xy 419.915619 -317.891281) (xy 419.919404 -317.888366)
			(xy 419.922452 -317.885572) (xy 419.98138 -317.829184) (xy 419.985606 -317.824952) (xy 419.99214 -317.814937)
			(xy 419.994334 -317.809372) (xy 419.998144 -317.79845) (xy 419.996874 -317.786258) (xy 419.995825 -317.777214)
			(xy 419.994679 -317.75904) (xy 419.994588 -317.749936) (xy 419.995071 -317.725114) (xy 420.003097 -317.676123)
			(xy 420.018943 -317.629077) (xy 420.042192 -317.585213) (xy 420.072231 -317.545689) (xy 420.108269 -317.511546)
			(xy 420.149356 -317.483683) (xy 420.19441 -317.462834) (xy 420.242243 -317.449549) (xy 420.291595 -317.444178)
			(xy 420.341166 -317.446862) (xy 420.38965 -317.45753) (xy 420.435769 -317.475903) (xy 420.478308 -317.501494)
			(xy 420.516147 -317.533631) (xy 420.548287 -317.571466) (xy 420.573883 -317.614002) (xy 420.59226 -317.660119)
			(xy 420.602934 -317.708602) (xy 420.605623 -317.758173) (xy 420.600257 -317.807526) (xy 420.586977 -317.85536)
			(xy 420.566133 -317.900416) (xy 420.538274 -317.941506) (xy 420.504135 -317.977547) (xy 420.464614 -318.007591)
			(xy 420.420753 -318.030844) (xy 420.373708 -318.046695) (xy 420.324718 -318.054726) (xy 420.299896 -318.055244)
			(xy 420.290792 -318.055147) (xy 420.272618 -318.054006) (xy 420.263574 -318.052958) (xy 420.251382 -318.051688)
			(xy 420.24046 -318.055498) (xy 420.234881 -318.057662) (xy 420.224866 -318.064207) (xy 420.220648 -318.068452)
			(xy 420.16426 -318.12738) (xy 420.161466 -318.130428) (xy 420.158564 -318.134223) (xy 420.154087 -318.14266)
			(xy 420.152576 -318.147192) (xy 420.14902 -318.158622) (xy 420.151052 -318.17056) (xy 420.153182 -318.184048)
			(xy 420.155469 -318.211262) (xy 420.155624 -318.224916) (xy 420.155624 -318.295274) (xy 420.155878 -318.299084)
			(xy 420.155878 -318.299592) (xy 420.156843 -318.307693) (xy 420.163199 -318.322708) (xy 420.168324 -318.329056)
			(xy 420.172388 -318.33312) (xy 420.228776 -318.383666) (xy 420.232783 -318.387055) (xy 420.241876 -318.392292)
			(xy 420.24681 -318.39408) (xy 420.25697 -318.397382) (xy 420.267892 -318.396366) (xy 420.299896 -318.394588)
			(xy 420.325621 -318.39512) (xy 420.376342 -318.403746) (xy 420.424899 -318.420754) (xy 420.469917 -318.445662)
			(xy 420.510121 -318.477766) (xy 420.544373 -318.516157) (xy 420.571703 -318.559747) (xy 420.591338 -318.607303)
			(xy 420.602721 -318.657477) (xy 420.604696 -318.683132) (xy 420.605204 -318.693038) (xy 420.609268 -318.701674)
			(xy 420.61139 -318.705991) (xy 420.617021 -318.713788) (xy 420.620444 -318.717168) (xy 420.671244 -318.765174)
			(xy 420.678513 -318.771516) (xy 420.696405 -318.778689) (xy 420.706042 -318.779144) (xy 420.84371 -318.779144)
			(xy 420.853344 -318.77868) (xy 420.871232 -318.771505) (xy 420.878508 -318.765174) (xy 420.929308 -318.717168)
			(xy 420.932723 -318.713782) (xy 420.938344 -318.705981) (xy 420.940484 -318.701674) (xy 420.944548 -318.693038)
			(xy 420.945056 -318.683132) (xy 420.947 -318.657476) (xy 420.958396 -318.607305) (xy 420.978041 -318.559754)
			(xy 421.005378 -318.516169) (xy 421.039634 -318.477782) (xy 421.079839 -318.44568) (xy 421.124856 -318.420772)
			(xy 421.173412 -318.403762) (xy 421.224132 -318.395131) (xy 421.249856 -318.394588) (xy 421.28186 -318.396366)
			(xy 421.292782 -318.397382) (xy 421.302942 -318.39408) (xy 421.307897 -318.392337) (xy 421.316991 -318.387088)
			(xy 421.320976 -318.383666) (xy 421.377364 -318.33312) (xy 421.381428 -318.329056) (xy 421.386586 -318.32273)
			(xy 421.392922 -318.307699) (xy 421.393874 -318.299592) (xy 421.393874 -318.299084) (xy 421.394128 -318.295274)
			(xy 421.394128 -318.224916) (xy 421.394291 -318.211262) (xy 421.396582 -318.18405) (xy 421.3987 -318.17056)
			(xy 421.400732 -318.158622) (xy 421.397176 -318.147192) (xy 421.39566 -318.142663) (xy 421.391179 -318.134229)
			(xy 421.388286 -318.130428) (xy 421.385492 -318.12738) (xy 421.329104 -318.068452) (xy 421.324874 -318.064222)
			(xy 421.314862 -318.05768) (xy 421.309292 -318.055498) (xy 421.29837 -318.051688) (xy 421.286178 -318.052958)
			(xy 421.277134 -318.054005) (xy 421.25896 -318.055146) (xy 421.249856 -318.055244) (xy 421.225032 -318.054754)
			(xy 421.17604 -318.046715) (xy 421.128994 -318.030856) (xy 421.085134 -318.007595) (xy 421.045614 -317.977544)
			(xy 421.011477 -317.941496) (xy 420.983621 -317.900399) (xy 420.962781 -317.855338) (xy 420.949505 -317.807498)
			(xy 420.944144 -317.758141) (xy 420.946839 -317.708567) (xy 420.957518 -317.660082) (xy 420.9759 -317.613963)
			(xy 421.001502 -317.571426) (xy 421.033648 -317.533591) (xy 421.071491 -317.501455) (xy 421.114035 -317.475865)
			(xy 421.160159 -317.457494) (xy 421.208647 -317.446828) (xy 421.258221 -317.444146) (xy 421.307577 -317.44952)
			(xy 421.355413 -317.462808) (xy 421.400469 -317.48366) (xy 421.441558 -317.511527) (xy 421.477598 -317.545674)
			(xy 421.507638 -317.585201) (xy 421.530888 -317.629068) (xy 421.546735 -317.676118) (xy 421.554761 -317.725112)
			(xy 421.555164 -317.749936) (xy 421.555066 -317.75904) (xy 421.553923 -317.777213) (xy 421.552878 -317.786258)
			(xy 421.551608 -317.79845) (xy 421.555418 -317.809372) (xy 421.557585 -317.814949) (xy 421.564137 -317.824957)
			(xy 421.568372 -317.829184) (xy 421.6273 -317.885572) (xy 421.630348 -317.888366) (xy 421.634144 -317.891265)
			(xy 421.642583 -317.895737) (xy 421.647112 -317.897256) (xy 421.658542 -317.900812) (xy 421.67048 -317.89878)
			(xy 421.683968 -317.896651) (xy 421.711182 -317.894365) (xy 421.724836 -317.894208) (xy 421.73849 -317.894369)
			(xy 421.765703 -317.896656) (xy 421.779192 -317.89878) (xy 421.79113 -317.900812) (xy 421.80256 -317.897256)
			(xy 421.807093 -317.895745) (xy 421.815536 -317.891277) (xy 421.819324 -317.888366) (xy 421.822372 -317.885572)
			(xy 421.8813 -317.829184) (xy 421.885531 -317.824955) (xy 421.892076 -317.814944) (xy 421.894254 -317.809372)
			(xy 421.898064 -317.79845) (xy 421.896794 -317.786258) (xy 421.895744 -317.777214) (xy 421.894599 -317.75904)
			(xy 421.894508 -317.749936) (xy 421.894991 -317.725116) (xy 421.903016 -317.676129) (xy 421.918861 -317.629086)
			(xy 421.942108 -317.585226) (xy 421.972144 -317.545705) (xy 422.008179 -317.511564) (xy 422.049262 -317.483702)
			(xy 422.094312 -317.462855) (xy 422.142141 -317.44957) (xy 422.191489 -317.444198) (xy 422.241056 -317.446881)
			(xy 422.289537 -317.457547) (xy 422.335653 -317.475917) (xy 422.378189 -317.501505) (xy 422.416025 -317.533638)
			(xy 422.448165 -317.571469) (xy 422.47376 -317.614001) (xy 422.492137 -317.660113) (xy 422.502812 -317.708592)
			(xy 422.505503 -317.758159) (xy 422.50014 -317.807508) (xy 422.486863 -317.855339) (xy 422.466023 -317.900393)
			(xy 422.438169 -317.941481) (xy 422.404034 -317.977521) (xy 422.364518 -318.007564) (xy 422.320662 -318.030819)
			(xy 422.273621 -318.046671) (xy 422.224636 -318.054705) (xy 422.199816 -318.055244) (xy 422.190712 -318.055145)
			(xy 422.172539 -318.053999) (xy 422.163494 -318.052958) (xy 422.151302 -318.051688) (xy 422.14038 -318.055498)
			(xy 422.134799 -318.05766) (xy 422.124782 -318.064202) (xy 422.120568 -318.068452) (xy 422.06418 -318.12738)
			(xy 422.061386 -318.130428) (xy 422.058483 -318.134222) (xy 422.054004 -318.142659) (xy 422.052496 -318.147192)
			(xy 422.04894 -318.158622) (xy 422.050972 -318.17056) (xy 422.053102 -318.184048) (xy 422.055388 -318.211262)
			(xy 422.055544 -318.224916) (xy 422.055544 -318.295274) (xy 422.055798 -318.299084) (xy 422.055798 -318.299592)
			(xy 422.05676 -318.307694) (xy 422.063108 -318.322716) (xy 422.068244 -318.329056) (xy 422.072308 -318.33312)
			(xy 422.128696 -318.383666) (xy 422.1327 -318.387061) (xy 422.141788 -318.392311) (xy 422.14673 -318.39408)
			(xy 422.15689 -318.397382) (xy 422.167812 -318.396366) (xy 422.199816 -318.394588) (xy 422.225545 -318.395113)
			(xy 422.276277 -318.403729) (xy 422.324845 -318.420729) (xy 422.369874 -318.445634) (xy 422.41009 -318.477737)
			(xy 422.444352 -318.51613) (xy 422.471691 -318.559724) (xy 422.491332 -318.607286) (xy 422.50272 -318.657468)
			(xy 422.504616 -318.683132) (xy 422.505124 -318.693038) (xy 422.509188 -318.701674) (xy 422.511311 -318.70599)
			(xy 422.516944 -318.713786) (xy 422.520364 -318.717168) (xy 422.571164 -318.765174) (xy 422.578434 -318.771514)
			(xy 422.596326 -318.778679) (xy 422.605962 -318.779144) (xy 422.72458 -318.779144) (xy 422.732944 -318.778437)
			(xy 422.748524 -318.772217) (xy 422.75506 -318.766952) (xy 422.755568 -318.766444) (xy 422.757092 -318.765174)
			(xy 422.807638 -318.716914) (xy 422.811054 -318.713528) (xy 422.816678 -318.705729) (xy 422.818814 -318.70142)
			(xy 422.822878 -318.692784) (xy 422.823386 -318.682878) (xy 422.825146 -318.658101) (xy 422.835214 -318.609461)
			(xy 422.852518 -318.562903) (xy 422.876662 -318.519495) (xy 422.90709 -318.480235) (xy 422.943103 -318.446026)
			(xy 422.983873 -318.417654) (xy 423.028463 -318.395772) (xy 423.075849 -318.38088) (xy 423.124941 -318.373324)
			(xy 423.149776 -318.372744) (xy 423.150284 -318.372744) (xy 423.182288 -318.374522) (xy 423.19321 -318.375538)
			(xy 423.203116 -318.372236) (xy 423.208208 -318.370454) (xy 423.217556 -318.365073) (xy 423.221658 -318.361568)
			(xy 423.277284 -318.311022) (xy 423.284794 -318.303477) (xy 423.293457 -318.284058) (xy 423.294048 -318.27343)
			(xy 423.294048 -318.224916) (xy 423.294091 -318.215562) (xy 423.295108 -318.196882) (xy 423.29608 -318.187578)
			(xy 423.29735 -318.175894) (xy 423.293794 -318.16548) (xy 423.291737 -318.160037) (xy 423.285584 -318.150165)
			(xy 423.281602 -318.145922) (xy 423.225468 -318.089534) (xy 423.221447 -318.085735) (xy 423.212088 -318.079839)
			(xy 423.206926 -318.07785) (xy 423.196004 -318.073786) (xy 423.184574 -318.075056) (xy 423.150284 -318.077088)
			(xy 423.149776 -318.077088) (xy 423.124097 -318.076567) (xy 423.073377 -318.068501) (xy 423.024542 -318.052602)
			(xy 422.978795 -318.029261) (xy 422.93726 -317.999054) (xy 422.90096 -317.962723) (xy 422.870789 -317.921162)
			(xy 422.847489 -317.875394) (xy 422.831632 -317.826545) (xy 422.82361 -317.775818) (xy 422.82362 -317.72446)
			(xy 422.831661 -317.673736) (xy 422.847536 -317.624893) (xy 422.870853 -317.579134) (xy 422.90104 -317.537584)
			(xy 422.937353 -317.501266) (xy 422.978899 -317.471074) (xy 423.024656 -317.447751) (xy 423.073497 -317.43187)
			(xy 423.12422 -317.423823) (xy 423.175578 -317.423807) (xy 423.226306 -317.431823) (xy 423.275157 -317.447673)
			(xy 423.320928 -317.470968) (xy 423.362492 -317.501134) (xy 423.398828 -317.53743) (xy 423.429041 -317.578961)
			(xy 423.452387 -317.624705) (xy 423.468292 -317.673538) (xy 423.476364 -317.724258) (xy 423.476928 -317.749936)
			(xy 423.47515 -317.78448) (xy 423.47388 -317.79591) (xy 423.477944 -317.806832) (xy 423.47997 -317.811975)
			(xy 423.485866 -317.821324) (xy 423.489628 -317.825374) (xy 423.546016 -317.881508) (xy 423.550219 -317.885542)
			(xy 423.560099 -317.891711) (xy 423.565574 -317.8937) (xy 423.575988 -317.897256) (xy 423.587672 -317.895986)
			(xy 423.596976 -317.895018) (xy 423.615656 -317.894001) (xy 423.62501 -317.893954) (xy 423.638664 -317.894118)
			(xy 423.665876 -317.896411) (xy 423.679366 -317.898526) (xy 423.691304 -317.900558) (xy 423.702734 -317.897002)
			(xy 423.707263 -317.895484) (xy 423.715695 -317.891003) (xy 423.719498 -317.888112) (xy 423.722546 -317.885318)
			(xy 423.781474 -317.82893) (xy 423.785704 -317.8247) (xy 423.792248 -317.814689) (xy 423.794428 -317.809118)
			(xy 423.798238 -317.798196) (xy 423.796714 -317.786258) (xy 423.795725 -317.777211) (xy 423.794707 -317.759037)
			(xy 423.794682 -317.749936) (xy 423.795165 -317.725113) (xy 423.803191 -317.676122) (xy 423.819038 -317.629074)
			(xy 423.842287 -317.58521) (xy 423.872327 -317.545685) (xy 423.908366 -317.511541) (xy 423.949454 -317.483677)
			(xy 423.994509 -317.462828) (xy 424.042344 -317.449543) (xy 424.091697 -317.444172) (xy 424.141269 -317.446856)
			(xy 424.189754 -317.457525) (xy 424.235874 -317.475898) (xy 424.278414 -317.501491) (xy 424.316253 -317.533629)
			(xy 424.348394 -317.571465) (xy 424.37399 -317.614002) (xy 424.392367 -317.660121) (xy 424.40304 -317.708605)
			(xy 424.405729 -317.758177) (xy 424.400362 -317.807531) (xy 424.387081 -317.855366) (xy 424.366236 -317.900423)
			(xy 424.338376 -317.941513) (xy 424.304235 -317.977555) (xy 424.264712 -318.007599) (xy 424.22085 -318.030852)
			(xy 424.173804 -318.046703) (xy 424.124812 -318.054733) (xy 424.09999 -318.055244) (xy 424.090889 -318.055204)
			(xy 424.072716 -318.054187) (xy 424.063668 -318.053212) (xy 424.05173 -318.051688) (xy 424.040808 -318.055498)
			(xy 424.035226 -318.057657) (xy 424.025204 -318.064196) (xy 424.020996 -318.068452) (xy 423.964608 -318.12738)
			(xy 423.961814 -318.130428) (xy 423.958909 -318.134221) (xy 423.954428 -318.142658) (xy 423.952924 -318.147192)
			(xy 423.949368 -318.158622) (xy 423.9514 -318.17056) (xy 423.953529 -318.184048) (xy 423.955817 -318.211262)
			(xy 423.955972 -318.224916) (xy 423.955972 -318.295274) (xy 423.956426 -318.305936) (xy 423.965098 -318.325415)
			(xy 423.972736 -318.332866) (xy 424.028616 -318.383412) (xy 424.038776 -318.390524) (xy 424.047158 -318.39408)
			(xy 424.057318 -318.397382) (xy 424.06824 -318.396366) (xy 424.09999 -318.394588) (xy 424.125715 -318.395119)
			(xy 424.176437 -318.403744) (xy 424.224995 -318.420752) (xy 424.270013 -318.44566) (xy 424.310218 -318.477764)
			(xy 424.344471 -318.516155) (xy 424.371802 -318.559745) (xy 424.391437 -318.607301) (xy 424.402821 -318.657476)
			(xy 424.40479 -318.683132) (xy 424.405298 -318.693038) (xy 424.409362 -318.701674) (xy 424.411484 -318.705991)
			(xy 424.417115 -318.713788) (xy 424.420538 -318.717168) (xy 424.471338 -318.765174) (xy 424.478607 -318.771517)
			(xy 424.496498 -318.778692) (xy 424.506136 -318.779144) (xy 424.6245 -318.779144) (xy 424.632862 -318.778434)
			(xy 424.648439 -318.772209) (xy 424.65498 -318.766952) (xy 424.655488 -318.766444) (xy 424.657012 -318.765174)
			(xy 424.707558 -318.716914) (xy 424.710973 -318.713528) (xy 424.716595 -318.705727) (xy 424.718734 -318.70142)
			(xy 424.722798 -318.692784) (xy 424.723306 -318.682878) (xy 424.725066 -318.658099) (xy 424.735133 -318.609454)
			(xy 424.752436 -318.56289) (xy 424.776578 -318.519476) (xy 424.807005 -318.48021) (xy 424.843017 -318.445993)
			(xy 424.883786 -318.417613) (xy 424.928377 -318.39572) (xy 424.975764 -318.380818) (xy 425.024859 -318.37325)
			(xy 425.049696 -318.372744) (xy 425.050204 -318.372744) (xy 425.082208 -318.374522) (xy 425.09313 -318.375538)
			(xy 425.103036 -318.372236) (xy 425.108127 -318.370453) (xy 425.117473 -318.365068) (xy 425.121578 -318.361568)
			(xy 425.177204 -318.311022) (xy 425.184711 -318.303476) (xy 425.193371 -318.284057) (xy 425.193968 -318.27343)
			(xy 425.193968 -318.224916) (xy 425.194011 -318.215562) (xy 425.195028 -318.196882) (xy 425.196 -318.187578)
			(xy 425.19727 -318.175894) (xy 425.193714 -318.16548) (xy 425.191657 -318.160037) (xy 425.185506 -318.150163)
			(xy 425.181522 -318.145922) (xy 425.125388 -318.089534) (xy 425.121367 -318.085733) (xy 425.11201 -318.079834)
			(xy 425.106846 -318.07785) (xy 425.095924 -318.073786) (xy 425.084494 -318.075056) (xy 425.050204 -318.077088)
			(xy 425.049696 -318.077088) (xy 425.024017 -318.076569) (xy 424.973296 -318.068505) (xy 424.924459 -318.052609)
			(xy 424.87871 -318.029271) (xy 424.837173 -317.999065) (xy 424.800871 -317.962735) (xy 424.770697 -317.921175)
			(xy 424.747394 -317.875408) (xy 424.731536 -317.826559) (xy 424.723511 -317.775831) (xy 424.723519 -317.724473)
			(xy 424.731558 -317.673748) (xy 424.747431 -317.624904) (xy 424.770748 -317.579143) (xy 424.800934 -317.537592)
			(xy 424.837246 -317.501273) (xy 424.878792 -317.471079) (xy 424.924548 -317.447754) (xy 424.973389 -317.431872)
			(xy 425.024113 -317.423824) (xy 425.075471 -317.423807) (xy 425.126201 -317.431822) (xy 425.175052 -317.447671)
			(xy 425.220824 -317.470966) (xy 425.262389 -317.501132) (xy 425.298726 -317.537427) (xy 425.328939 -317.578959)
			(xy 425.352286 -317.624704) (xy 425.368191 -317.673537) (xy 425.376264 -317.724257) (xy 425.376848 -317.749936)
			(xy 425.37507 -317.78448) (xy 425.3738 -317.79591) (xy 425.377864 -317.806832) (xy 425.379887 -317.811978)
			(xy 425.385776 -317.821332) (xy 425.389548 -317.825374) (xy 425.445936 -317.881508) (xy 425.45014 -317.885541)
			(xy 425.460021 -317.891706) (xy 425.465494 -317.8937) (xy 425.475908 -317.897256) (xy 425.487592 -317.895986)
			(xy 425.496896 -317.895018) (xy 425.515576 -317.894002) (xy 425.52493 -317.893954) (xy 425.538584 -317.894115)
			(xy 425.565797 -317.896401) (xy 425.579286 -317.898526) (xy 425.591224 -317.900558) (xy 425.602654 -317.897002)
			(xy 425.607186 -317.89549) (xy 425.615627 -317.891019) (xy 425.619418 -317.888112) (xy 425.622466 -317.885318)
			(xy 425.681394 -317.82893) (xy 425.685623 -317.824699) (xy 425.692164 -317.814687) (xy 425.694348 -317.809118)
			(xy 425.698158 -317.798196) (xy 425.696634 -317.786258) (xy 425.695644 -317.777211) (xy 425.694627 -317.759037)
			(xy 425.694602 -317.749936) (xy 425.695085 -317.725115) (xy 425.70311 -317.676127) (xy 425.718956 -317.629083)
			(xy 425.742203 -317.585222) (xy 425.77224 -317.5457) (xy 425.808276 -317.511559) (xy 425.84936 -317.483697)
			(xy 425.894411 -317.462848) (xy 425.942242 -317.449564) (xy 425.991591 -317.444192) (xy 426.041159 -317.446875)
			(xy 426.089641 -317.457542) (xy 426.135758 -317.475912) (xy 426.178295 -317.501502) (xy 426.216132 -317.533636)
			(xy 426.248271 -317.571468) (xy 426.273867 -317.614001) (xy 426.292244 -317.660115) (xy 426.302919 -317.708595)
			(xy 426.305609 -317.758163) (xy 426.300245 -317.807513) (xy 426.286967 -317.855346) (xy 426.266126 -317.9004)
			(xy 426.23827 -317.941488) (xy 426.204134 -317.977529) (xy 426.164616 -318.007572) (xy 426.120759 -318.030826)
			(xy 426.073717 -318.046679) (xy 426.02473 -318.054711) (xy 425.99991 -318.055244) (xy 425.990809 -318.055205)
			(xy 425.972636 -318.054189) (xy 425.963588 -318.053212) (xy 425.95165 -318.051688) (xy 425.940728 -318.055498)
			(xy 425.93515 -318.057664) (xy 425.92514 -318.064214) (xy 425.920916 -318.068452) (xy 425.864528 -318.12738)
			(xy 425.861734 -318.130428) (xy 425.858833 -318.134223) (xy 425.854359 -318.142662) (xy 425.852844 -318.147192)
			(xy 425.849288 -318.158622) (xy 425.85132 -318.17056) (xy 425.853449 -318.184048) (xy 425.855738 -318.211262)
			(xy 425.855892 -318.224916) (xy 425.855892 -318.295274) (xy 425.856346 -318.305936) (xy 425.865021 -318.325412)
			(xy 425.872656 -318.332866) (xy 425.928536 -318.383412) (xy 425.938696 -318.390524) (xy 425.947078 -318.39408)
			(xy 425.957238 -318.397382) (xy 425.96816 -318.396366) (xy 425.99991 -318.394588) (xy 426.025634 -318.395121)
			(xy 426.076353 -318.403748) (xy 426.124908 -318.420758) (xy 426.169924 -318.445667) (xy 426.210126 -318.477771)
			(xy 426.244376 -318.516162) (xy 426.271705 -318.559751) (xy 426.291338 -318.607305) (xy 426.302721 -318.657478)
			(xy 426.30471 -318.683132) (xy 426.305218 -318.693038) (xy 426.309282 -318.701674) (xy 426.311405 -318.70599)
			(xy 426.317037 -318.713786) (xy 426.320458 -318.717168) (xy 426.371258 -318.765174) (xy 426.378528 -318.771514)
			(xy 426.396419 -318.778682) (xy 426.406056 -318.779144) (xy 426.52442 -318.779144) (xy 426.532781 -318.77843)
			(xy 426.548353 -318.772201) (xy 426.5549 -318.766952) (xy 426.555408 -318.766444) (xy 426.556932 -318.765174)
			(xy 426.607478 -318.716914) (xy 426.610897 -318.713531) (xy 426.616527 -318.705734) (xy 426.618654 -318.70142)
			(xy 426.622718 -318.692784) (xy 426.623226 -318.682878) (xy 426.624986 -318.658099) (xy 426.635053 -318.609456)
			(xy 426.652357 -318.562893) (xy 426.676499 -318.519481) (xy 426.706926 -318.480216) (xy 426.742938 -318.446002)
			(xy 426.783708 -318.417623) (xy 426.828298 -318.395733) (xy 426.875685 -318.380834) (xy 426.92478 -318.373268)
			(xy 426.949616 -318.372744) (xy 426.950124 -318.372744) (xy 426.982128 -318.374522) (xy 426.99305 -318.375538)
			(xy 427.002956 -318.372236) (xy 427.008046 -318.370451) (xy 427.017389 -318.365064) (xy 427.021498 -318.361568)
			(xy 427.077124 -318.311022) (xy 427.084641 -318.303481) (xy 427.093315 -318.284061) (xy 427.093888 -318.27343)
			(xy 427.093888 -318.224916) (xy 427.093931 -318.215562) (xy 427.094948 -318.196882) (xy 427.09592 -318.187578)
			(xy 427.09719 -318.175894) (xy 427.093634 -318.16548) (xy 427.091578 -318.160036) (xy 427.085428 -318.150161)
			(xy 427.081442 -318.145922) (xy 427.025308 -318.089534) (xy 427.021288 -318.085732) (xy 427.011933 -318.079829)
			(xy 427.006766 -318.07785) (xy 426.995844 -318.073786) (xy 426.984414 -318.075056) (xy 426.950124 -318.077088)
			(xy 426.949616 -318.077088) (xy 426.923939 -318.076563) (xy 426.873222 -318.068488) (xy 426.824391 -318.052581)
			(xy 426.778649 -318.029234) (xy 426.737121 -317.999021) (xy 426.700829 -317.962685) (xy 426.670665 -317.921122)
			(xy 426.647371 -317.875352) (xy 426.631522 -317.826503) (xy 426.623507 -317.775777) (xy 426.623523 -317.724421)
			(xy 426.63157 -317.673699) (xy 426.647449 -317.62486) (xy 426.670771 -317.579105) (xy 426.70096 -317.53756)
			(xy 426.737276 -317.501247) (xy 426.778822 -317.47106) (xy 426.824579 -317.447741) (xy 426.873419 -317.431865)
			(xy 426.924141 -317.423821) (xy 426.975497 -317.423809) (xy 427.026223 -317.431827) (xy 427.075071 -317.447679)
			(xy 427.120839 -317.470975) (xy 427.162401 -317.501142) (xy 427.198734 -317.537436) (xy 427.228944 -317.578966)
			(xy 427.252289 -317.62471) (xy 427.268192 -317.673541) (xy 427.276264 -317.724259) (xy 427.276768 -317.749936)
			(xy 427.27499 -317.78448) (xy 427.27372 -317.79591) (xy 427.277784 -317.806832) (xy 427.279807 -317.811977)
			(xy 427.285698 -317.82133) (xy 427.289468 -317.825374) (xy 427.345856 -317.881508) (xy 427.350061 -317.885539)
			(xy 427.359943 -317.891701) (xy 427.365414 -317.8937) (xy 427.375828 -317.897256) (xy 427.387512 -317.895986)
			(xy 427.396816 -317.895019) (xy 427.415496 -317.894004) (xy 427.42485 -317.893954) (xy 427.438504 -317.894115)
			(xy 427.465717 -317.896404) (xy 427.479206 -317.898526) (xy 427.491144 -317.900558) (xy 427.502574 -317.897002)
			(xy 427.507105 -317.895489) (xy 427.515544 -317.891015) (xy 427.519338 -317.888112) (xy 427.522386 -317.885318)
			(xy 427.581314 -317.82893) (xy 427.585548 -317.824702) (xy 427.592099 -317.814694) (xy 427.594268 -317.809118)
			(xy 427.598078 -317.798196) (xy 427.596554 -317.786258) (xy 427.595565 -317.777211) (xy 427.594548 -317.759037)
			(xy 427.594522 -317.749936) (xy 427.595005 -317.725117) (xy 427.603029 -317.676133) (xy 427.618873 -317.629093)
			(xy 427.642119 -317.585235) (xy 427.672153 -317.545716) (xy 427.708185 -317.511576) (xy 427.749266 -317.483716)
			(xy 427.794313 -317.462869) (xy 427.84214 -317.449584) (xy 427.891485 -317.444212) (xy 427.94105 -317.446894)
			(xy 427.989527 -317.457559) (xy 428.035641 -317.475926) (xy 428.078176 -317.501512) (xy 428.116011 -317.533643)
			(xy 428.148149 -317.571471) (xy 428.173744 -317.614) (xy 428.192122 -317.66011) (xy 428.202797 -317.708585)
			(xy 428.20549 -317.758149) (xy 428.200128 -317.807496) (xy 428.186854 -317.855325) (xy 428.166016 -317.900376)
			(xy 428.138165 -317.941463) (xy 428.104033 -317.977503) (xy 428.064521 -318.007546) (xy 428.020668 -318.030801)
			(xy 427.973631 -318.046655) (xy 427.924648 -318.05469) (xy 427.89983 -318.055244) (xy 427.890729 -318.055206)
			(xy 427.872556 -318.054191) (xy 427.863508 -318.053212) (xy 427.85157 -318.051688) (xy 427.840648 -318.055498)
			(xy 427.835069 -318.057663) (xy 427.825056 -318.06421) (xy 427.820836 -318.068452) (xy 427.764448 -318.12738)
			(xy 427.761654 -318.130428) (xy 427.758752 -318.134223) (xy 427.754276 -318.142661) (xy 427.752764 -318.147192)
			(xy 427.749208 -318.158622) (xy 427.75124 -318.17056) (xy 427.753369 -318.184048) (xy 427.755658 -318.211262)
			(xy 427.755812 -318.224916) (xy 427.755812 -318.295274) (xy 427.756267 -318.305935) (xy 427.764944 -318.325409)
			(xy 427.772576 -318.332866) (xy 427.828456 -318.383412) (xy 427.838616 -318.390524) (xy 427.846998 -318.39408)
			(xy 427.857158 -318.397382) (xy 427.86808 -318.396366) (xy 427.89983 -318.394588) (xy 427.925558 -318.395114)
			(xy 427.976288 -318.403732) (xy 428.024854 -318.420734) (xy 428.069882 -318.445639) (xy 428.110095 -318.477742)
			(xy 428.144356 -318.516135) (xy 428.171693 -318.559728) (xy 428.191333 -318.607289) (xy 428.20272 -318.65747)
			(xy 428.20463 -318.683132) (xy 428.205138 -318.693038) (xy 428.209202 -318.701674) (xy 428.211326 -318.70599)
			(xy 428.216959 -318.713784) (xy 428.220378 -318.717168) (xy 428.271178 -318.765174) (xy 428.278444 -318.771527)
			(xy 428.296335 -318.778722) (xy 428.305976 -318.779144) (xy 428.42434 -318.779144) (xy 428.4327 -318.778427)
			(xy 428.448268 -318.772194) (xy 428.45482 -318.766952) (xy 428.455328 -318.766444) (xy 428.456852 -318.765174)
			(xy 428.507398 -318.716914) (xy 428.510816 -318.71353) (xy 428.516444 -318.705732) (xy 428.518574 -318.70142)
			(xy 428.522638 -318.692784) (xy 428.523146 -318.682878) (xy 428.524906 -318.6581) (xy 428.534973 -318.609458)
			(xy 428.552277 -318.562896) (xy 428.57642 -318.519486) (xy 428.606847 -318.480223) (xy 428.64286 -318.44601)
			(xy 428.683629 -318.417634) (xy 428.72822 -318.395746) (xy 428.775606 -318.380849) (xy 428.8247 -318.373287)
			(xy 428.849536 -318.372744) (xy 428.850044 -318.372744) (xy 428.882048 -318.374522) (xy 428.89297 -318.375538)
			(xy 428.902876 -318.372236) (xy 428.90797 -318.370458) (xy 428.917323 -318.365081) (xy 428.921418 -318.361568)
			(xy 428.977044 -318.311022) (xy 428.984558 -318.303479) (xy 428.993229 -318.28406) (xy 428.993808 -318.27343)
			(xy 428.993808 -318.224916) (xy 428.993851 -318.215562) (xy 428.994868 -318.196882) (xy 428.99584 -318.187578)
			(xy 428.99711 -318.175894) (xy 428.993554 -318.16548) (xy 428.991499 -318.160036) (xy 428.985351 -318.150159)
			(xy 428.981362 -318.145922) (xy 428.925228 -318.089534) (xy 428.921205 -318.085738) (xy 428.911844 -318.079849)
			(xy 428.906686 -318.07785) (xy 428.895764 -318.073786) (xy 428.884334 -318.075056) (xy 428.850044 -318.077088)
			(xy 428.849536 -318.077088) (xy 428.823858 -318.076564) (xy 428.77314 -318.068492) (xy 428.724308 -318.052588)
			(xy 428.678565 -318.029243) (xy 428.637034 -317.999032) (xy 428.600739 -317.962698) (xy 428.570573 -317.921135)
			(xy 428.547277 -317.875366) (xy 428.531426 -317.826517) (xy 428.523408 -317.77579) (xy 428.523422 -317.724434)
			(xy 428.531467 -317.673711) (xy 428.547345 -317.624871) (xy 428.570665 -317.579115) (xy 428.600854 -317.537568)
			(xy 428.637168 -317.501254) (xy 428.678715 -317.471065) (xy 428.724471 -317.447745) (xy 428.773311 -317.431867)
			(xy 428.824034 -317.423822) (xy 428.87539 -317.423808) (xy 428.926117 -317.431826) (xy 428.974966 -317.447677)
			(xy 429.020735 -317.470973) (xy 429.062298 -317.501139) (xy 429.098632 -317.537434) (xy 429.128843 -317.578965)
			(xy 429.152188 -317.624708) (xy 429.168092 -317.67354) (xy 429.176164 -317.724258) (xy 429.176688 -317.749936)
			(xy 429.17491 -317.78448) (xy 429.17364 -317.79591) (xy 429.177704 -317.806832) (xy 429.179728 -317.811977)
			(xy 429.185621 -317.821328) (xy 429.189388 -317.825374) (xy 429.245776 -317.881508) (xy 429.249981 -317.885538)
			(xy 429.259865 -317.891695) (xy 429.265334 -317.8937) (xy 429.275748 -317.897256) (xy 429.287432 -317.895986)
			(xy 429.296736 -317.895017) (xy 429.315416 -317.893997) (xy 429.32477 -317.893954) (xy 429.338488 -317.894107)
			(xy 429.365828 -317.896394) (xy 429.37938 -317.898526) (xy 429.391318 -317.900558) (xy 429.402748 -317.897002)
			(xy 429.40728 -317.895491) (xy 429.415722 -317.89102) (xy 429.419512 -317.888112) (xy 429.42256 -317.885318)
			(xy 429.481488 -317.82893) (xy 429.485717 -317.8247) (xy 429.492259 -317.814688) (xy 429.494442 -317.809118)
			(xy 429.498252 -317.798196) (xy 429.496982 -317.786258) (xy 429.495933 -317.777214) (xy 429.494787 -317.75904)
			(xy 429.494696 -317.749936) (xy 429.495179 -317.725115) (xy 429.503205 -317.676126) (xy 429.51905 -317.62908)
			(xy 429.542298 -317.585219) (xy 429.572336 -317.545696) (xy 429.608373 -317.511553) (xy 429.649459 -317.483691)
			(xy 429.694511 -317.462842) (xy 429.742342 -317.449557) (xy 429.791693 -317.444186) (xy 429.841262 -317.446869)
			(xy 429.889745 -317.457537) (xy 429.935863 -317.475908) (xy 429.978401 -317.501498) (xy 430.016238 -317.533633)
			(xy 430.048378 -317.571467) (xy 430.073974 -317.614002) (xy 430.092351 -317.660117) (xy 430.103025 -317.708598)
			(xy 430.105268 -317.749936) (xy 430.44416 -317.749936) (xy 430.44812 -317.700882) (xy 430.459897 -317.653098)
			(xy 430.479188 -317.607822) (xy 430.505491 -317.566226) (xy 430.538126 -317.529389) (xy 430.576247 -317.498264)
			(xy 430.618868 -317.473657) (xy 430.664884 -317.456205) (xy 430.713103 -317.446361) (xy 430.762278 -317.44438)
			(xy 430.811133 -317.450312) (xy 430.858404 -317.464004) (xy 430.902866 -317.485102) (xy 430.943369 -317.513058)
			(xy 430.978862 -317.54715) (xy 431.008427 -317.586494) (xy 431.031298 -317.630071) (xy 431.046882 -317.676752)
			(xy 431.054777 -317.725329) (xy 431.055272 -317.749936) (xy 431.054777 -317.774543) (xy 431.046882 -317.82312)
			(xy 431.031298 -317.869801) (xy 431.008427 -317.913378) (xy 430.978862 -317.952722) (xy 430.943369 -317.986814)
			(xy 430.902866 -318.01477) (xy 430.858404 -318.035868) (xy 430.811133 -318.04956) (xy 430.762278 -318.055492)
			(xy 430.713103 -318.053511) (xy 430.664884 -318.043667) (xy 430.618868 -318.026215) (xy 430.576247 -318.001608)
			(xy 430.538126 -317.970483) (xy 430.505491 -317.933646) (xy 430.479188 -317.89205) (xy 430.459897 -317.846774)
			(xy 430.44812 -317.79899) (xy 430.44416 -317.749936) (xy 430.105268 -317.749936) (xy 430.105715 -317.758167)
			(xy 430.10035 -317.807519) (xy 430.087072 -317.855352) (xy 430.066229 -317.900407) (xy 430.038372 -317.941496)
			(xy 430.004234 -317.977537) (xy 429.964715 -318.00758) (xy 429.920856 -318.030834) (xy 429.873813 -318.046686)
			(xy 429.824825 -318.054718) (xy 429.800004 -318.055244) (xy 429.7909 -318.055148) (xy 429.772726 -318.054006)
			(xy 429.763682 -318.052958) (xy 429.75149 -318.051688) (xy 429.740568 -318.055498) (xy 429.734988 -318.057661)
			(xy 429.724972 -318.064205) (xy 429.720756 -318.068452) (xy 429.664368 -318.12738) (xy 429.661574 -318.130428)
			(xy 429.658671 -318.134222) (xy 429.654194 -318.14266) (xy 429.652684 -318.147192) (xy 429.649128 -318.158622)
			(xy 429.65116 -318.17056) (xy 429.653289 -318.184048) (xy 429.655578 -318.211262) (xy 429.655732 -318.224916)
			(xy 429.655732 -318.295274) (xy 429.655986 -318.299084) (xy 429.655986 -318.299592) (xy 429.656951 -318.307693)
			(xy 429.663307 -318.322707) (xy 429.668432 -318.329056) (xy 429.672496 -318.33312) (xy 429.728884 -318.383666)
			(xy 429.732888 -318.387061) (xy 429.741975 -318.392313) (xy 429.746918 -318.39408) (xy 429.757078 -318.397382)
			(xy 429.768 -318.396366) (xy 429.800004 -318.394588) (xy 429.825728 -318.39512) (xy 429.876448 -318.403747)
			(xy 429.925004 -318.420756) (xy 429.970021 -318.445665) (xy 430.010224 -318.477769) (xy 430.044475 -318.51616)
			(xy 430.071804 -318.559749) (xy 430.091438 -318.607304) (xy 430.102821 -318.657478) (xy 430.104804 -318.683132)
			(xy 430.105312 -318.693038) (xy 430.109376 -318.701674) (xy 430.111499 -318.70599) (xy 430.11713 -318.713787)
			(xy 430.120552 -318.717168) (xy 430.171352 -318.765174) (xy 430.178621 -318.771515) (xy 430.196513 -318.778685)
			(xy 430.20615 -318.779144) (xy 433.627784 -318.779144) (xy 433.635273 -318.778835) (xy 433.649598 -318.774443)
			(xy 433.655978 -318.770508) (xy 433.673758 -318.75857) (xy 433.68341 -318.750188) (xy 433.687474 -318.745616)
			(xy 433.690522 -318.73952) (xy 433.735032 -318.65287) (xy 433.830178 -318.482858) (xy 433.932178 -318.316868)
			(xy 434.040863 -318.155176) (xy 434.15605 -317.99805) (xy 434.27755 -317.845753) (xy 434.405159 -317.698537)
			(xy 434.538666 -317.556647) (xy 434.677848 -317.42032) (xy 434.822473 -317.289782) (xy 434.972302 -317.16525)
			(xy 435.127084 -317.046932) (xy 435.286563 -316.935025) (xy 435.450472 -316.829714) (xy 435.61854 -316.731175)
			(xy 435.790486 -316.639572) (xy 435.966025 -316.555057) (xy 436.144864 -316.477771) (xy 436.326707 -316.407842)
			(xy 436.51125 -316.345387) (xy 436.698186 -316.29051) (xy 436.887205 -316.243301) (xy 437.077991 -316.20384)
			(xy 437.270228 -316.172192) (xy 437.463596 -316.14841) (xy 437.657773 -316.132533) (xy 437.852436 -316.124589)
			(xy 438.04726 -316.124589) (xy 438.241923 -316.132533) (xy 438.4361 -316.14841) (xy 438.629468 -316.172192)
			(xy 438.821705 -316.20384) (xy 439.012491 -316.243301) (xy 439.20151 -316.29051) (xy 439.388446 -316.345387)
			(xy 439.572989 -316.407842) (xy 439.754832 -316.477771) (xy 439.933671 -316.555057) (xy 440.10921 -316.639572)
			(xy 440.281156 -316.731175) (xy 440.449224 -316.829714) (xy 440.613133 -316.935025) (xy 440.772612 -317.046932)
			(xy 440.927394 -317.16525) (xy 441.077223 -317.289782) (xy 441.221848 -317.42032) (xy 441.36103 -317.556647)
			(xy 441.494537 -317.698537) (xy 441.622146 -317.845753) (xy 441.743646 -317.99805) (xy 441.858833 -318.155176)
			(xy 441.967518 -318.316868) (xy 442.069518 -318.482858) (xy 442.164664 -318.65287) (xy 442.209174 -318.73952)
			(xy 442.212222 -318.745616) (xy 442.216286 -318.750188) (xy 442.225938 -318.75857) (xy 442.243718 -318.770508)
			(xy 442.250081 -318.774478) (xy 442.264417 -318.778854) (xy 442.271912 -318.779144) (xy 446.02527 -318.779144)
			(xy 446.033398 -318.778382) (xy 446.033906 -318.778382) (xy 446.041426 -318.776784) (xy 446.055117 -318.769811)
			(xy 446.06083 -318.764666) (xy 447.999866 -316.82563) (xy 448.004692 -316.820042) (xy 448.009352 -316.813299)
			(xy 448.014517 -316.797753) (xy 448.014852 -316.789562) (xy 448.014852 -312.059066) (xy 448.014356 -312.048226)
			(xy 448.00541 -312.028478) (xy 447.99758 -312.020966) (xy 447.94043 -311.970928) (xy 447.937636 -311.968642)
			(xy 447.93015 -311.963454) (xy 447.912707 -311.958262) (xy 447.9036 -311.958482) (xy 447.900044 -311.958736)
			(xy 447.89852 -311.95899) (xy 447.824393 -311.968466) (xy 447.67552 -311.981671) (xy 447.526209 -311.988286)
			(xy 447.45148 -311.988708) (xy 447.449956 -311.988708) (xy 447.368303 -311.988214) (xy 447.205186 -311.980322)
			(xy 447.042642 -311.964558) (xy 446.881049 -311.94096) (xy 446.720785 -311.909583) (xy 446.562224 -311.870499)
			(xy 446.405736 -311.823801) (xy 446.251687 -311.769596) (xy 446.100437 -311.708013) (xy 445.952339 -311.639193)
			(xy 445.807738 -311.5633) (xy 445.666973 -311.480508) (xy 445.530372 -311.391013) (xy 445.398255 -311.295022)
			(xy 445.27093 -311.192761) (xy 445.148693 -311.084468) (xy 445.031832 -310.970395) (xy 444.920618 -310.85081)
			(xy 444.815311 -310.725991) (xy 444.716158 -310.596231) (xy 444.62339 -310.461831) (xy 444.537223 -310.323107)
			(xy 444.457859 -310.180381) (xy 444.385484 -310.033988) (xy 444.320265 -309.884269) (xy 444.262356 -309.731575)
			(xy 444.211892 -309.57626) (xy 444.16899 -309.418689) (xy 444.133752 -309.25923) (xy 444.106258 -309.098254)
			(xy 444.086574 -308.936137) (xy 444.074745 -308.773259) (xy 444.070798 -308.61) (xy 444.074745 -308.446741)
			(xy 444.086574 -308.283863) (xy 444.106258 -308.121746) (xy 444.133752 -307.96077) (xy 444.16899 -307.801311)
			(xy 444.211892 -307.64374) (xy 444.262356 -307.488425) (xy 444.320265 -307.335731) (xy 444.385484 -307.186012)
			(xy 444.457859 -307.039619) (xy 444.537223 -306.896893) (xy 444.62339 -306.758169) (xy 444.716158 -306.623769)
			(xy 444.815311 -306.494009) (xy 444.920618 -306.36919) (xy 445.031832 -306.249605) (xy 445.148693 -306.135532)
			(xy 445.27093 -306.027239) (xy 445.398255 -305.924978) (xy 445.530372 -305.828987) (xy 445.666973 -305.739492)
			(xy 445.807738 -305.6567) (xy 445.952339 -305.580807) (xy 446.100437 -305.511987) (xy 446.251687 -305.450404)
			(xy 446.405736 -305.396199) (xy 446.562224 -305.349501) (xy 446.720785 -305.310417) (xy 446.881049 -305.27904)
			(xy 447.042642 -305.255442) (xy 447.205186 -305.239678) (xy 447.368303 -305.231786) (xy 447.449956 -305.231292)
			(xy 447.451734 -305.231292) (xy 447.522535 -305.231659) (xy 447.664013 -305.237593) (xy 447.805117 -305.24945)
			(xy 447.875406 -305.257962) (xy 447.887062 -305.258898) (xy 447.909162 -305.251341) (xy 447.917824 -305.243484)
			(xy 449.116196 -304.045112) (xy 449.123594 -304.038263) (xy 449.142192 -304.030526) (xy 449.152264 -304.030126)
			(xy 465.121752 -304.030126) (xy 465.12988 -304.029364) (xy 465.130388 -304.029364) (xy 465.137909 -304.027768)
			(xy 465.151602 -304.020796) (xy 465.157312 -304.015648) (xy 465.644992 -303.527968) (xy 465.6455 -303.52746)
			(xy 465.650702 -303.521785) (xy 465.657702 -303.508083) (xy 465.659216 -303.500536) (xy 465.659216 -303.500028)
			(xy 465.659978 -303.4919) (xy 465.659978 -254.748538) (xy 465.659543 -254.738473) (xy 465.65181 -254.719887)
			(xy 465.644992 -254.71247) (xy 464.68538 -253.752858) (xy 464.678268 -253.745492) (xy 464.668616 -253.741682)
			(xy 464.664049 -253.739927) (xy 464.654457 -253.738008) (xy 464.649566 -253.737872) (xy 459.358238 -253.737872)
			(xy 459.353411 -253.737714) (xy 459.343946 -253.735804) (xy 459.339442 -253.734062) (xy 459.339188 -253.734062)
			(xy 459.329536 -253.730252) (xy 456.886818 -253.730252) (xy 456.879867 -253.730011) (xy 456.866478 -253.72627)
			(xy 456.860402 -253.722886) (xy 456.85456 -253.71933) (xy 456.847194 -253.717044) (xy 456.833478 -253.715266)
			(xy 418.501322 -253.715266) (xy 418.49126 -253.715705) (xy 418.472682 -253.723447) (xy 418.465254 -253.730252)
			(xy 413.269176 -258.92633) (xy 448.944998 -258.92633) (xy 448.949069 -258.870708) (xy 448.961195 -258.816271)
			(xy 448.981118 -258.76418) (xy 449.008414 -258.715545) (xy 449.0425 -258.671402) (xy 449.082649 -258.632693)
			(xy 449.128007 -258.600242) (xy 449.177607 -258.574741) (xy 449.230391 -258.556734) (xy 449.285234 -258.546604)
			(xy 449.340968 -258.544567) (xy 449.396405 -258.550667) (xy 449.450362 -258.564773) (xy 449.501691 -258.586585)
			(xy 449.549297 -258.615639) (xy 449.592165 -258.651314) (xy 449.629382 -258.692851) (xy 449.660155 -258.739364)
			(xy 449.683827 -258.789861) (xy 449.699895 -258.843268) (xy 449.706213 -258.886198) (xy 450.433184 -258.886198)
			(xy 450.437255 -258.830576) (xy 450.449381 -258.776139) (xy 450.469304 -258.724048) (xy 450.4966 -258.675413)
			(xy 450.530686 -258.63127) (xy 450.570835 -258.592561) (xy 450.616193 -258.56011) (xy 450.665793 -258.534609)
			(xy 450.718577 -258.516602) (xy 450.77342 -258.506472) (xy 450.829154 -258.504435) (xy 450.884591 -258.510535)
			(xy 450.938548 -258.524641) (xy 450.989877 -258.546453) (xy 451.037483 -258.575507) (xy 451.080351 -258.611182)
			(xy 451.117568 -258.652719) (xy 451.148341 -258.699232) (xy 451.172013 -258.749729) (xy 451.188081 -258.803136)
			(xy 451.196201 -258.858312) (xy 451.19671 -258.886198) (xy 451.196201 -258.914084) (xy 451.191446 -258.946396)
			(xy 451.94169 -258.946396) (xy 451.945761 -258.890774) (xy 451.957887 -258.836337) (xy 451.97781 -258.784246)
			(xy 452.005106 -258.735611) (xy 452.039192 -258.691468) (xy 452.079341 -258.652759) (xy 452.124699 -258.620308)
			(xy 452.174299 -258.594807) (xy 452.227083 -258.5768) (xy 452.281926 -258.56667) (xy 452.33766 -258.564633)
			(xy 452.393097 -258.570733) (xy 452.447054 -258.584839) (xy 452.498383 -258.606651) (xy 452.545989 -258.635705)
			(xy 452.588857 -258.67138) (xy 452.626074 -258.712917) (xy 452.656847 -258.75943) (xy 452.680519 -258.809927)
			(xy 452.696587 -258.863334) (xy 452.699952 -258.886198) (xy 453.449942 -258.886198) (xy 453.454013 -258.830576)
			(xy 453.466139 -258.776139) (xy 453.486062 -258.724048) (xy 453.513358 -258.675413) (xy 453.547444 -258.63127)
			(xy 453.587593 -258.592561) (xy 453.632951 -258.56011) (xy 453.682551 -258.534609) (xy 453.735335 -258.516602)
			(xy 453.790178 -258.506472) (xy 453.845912 -258.504435) (xy 453.901349 -258.510535) (xy 453.955306 -258.524641)
			(xy 454.006635 -258.546453) (xy 454.054241 -258.575507) (xy 454.097109 -258.611182) (xy 454.134326 -258.652719)
			(xy 454.165099 -258.699232) (xy 454.188771 -258.749729) (xy 454.19353 -258.765548) (xy 455.159362 -258.765548)
			(xy 455.163433 -258.709926) (xy 455.175559 -258.655489) (xy 455.195482 -258.603398) (xy 455.222778 -258.554763)
			(xy 455.256864 -258.51062) (xy 455.297013 -258.471911) (xy 455.342371 -258.43946) (xy 455.391971 -258.413959)
			(xy 455.444755 -258.395952) (xy 455.499598 -258.385822) (xy 455.555332 -258.383785) (xy 455.610769 -258.389885)
			(xy 455.664726 -258.403991) (xy 455.716055 -258.425803) (xy 455.763661 -258.454857) (xy 455.806529 -258.490532)
			(xy 455.843746 -258.532069) (xy 455.874519 -258.578582) (xy 455.898191 -258.629079) (xy 455.914259 -258.682486)
			(xy 455.922379 -258.737662) (xy 455.922888 -258.765548) (xy 455.922379 -258.793434) (xy 455.917624 -258.825746)
			(xy 456.728066 -258.825746) (xy 456.732137 -258.770124) (xy 456.744263 -258.715687) (xy 456.764186 -258.663596)
			(xy 456.791482 -258.614961) (xy 456.825568 -258.570818) (xy 456.865717 -258.532109) (xy 456.911075 -258.499658)
			(xy 456.960675 -258.474157) (xy 457.013459 -258.45615) (xy 457.068302 -258.44602) (xy 457.124036 -258.443983)
			(xy 457.179473 -258.450083) (xy 457.23343 -258.464189) (xy 457.284759 -258.486001) (xy 457.332365 -258.515055)
			(xy 457.375233 -258.55073) (xy 457.41245 -258.592267) (xy 457.443223 -258.63878) (xy 457.466895 -258.689277)
			(xy 457.482963 -258.742684) (xy 457.491083 -258.79786) (xy 457.491592 -258.825746) (xy 457.491226 -258.845812)
			(xy 458.135734 -258.845812) (xy 458.139805 -258.79019) (xy 458.151931 -258.735753) (xy 458.171854 -258.683662)
			(xy 458.19915 -258.635027) (xy 458.233236 -258.590884) (xy 458.273385 -258.552175) (xy 458.318743 -258.519724)
			(xy 458.368343 -258.494223) (xy 458.421127 -258.476216) (xy 458.47597 -258.466086) (xy 458.531704 -258.464049)
			(xy 458.587141 -258.470149) (xy 458.641098 -258.484255) (xy 458.692427 -258.506067) (xy 458.740033 -258.535121)
			(xy 458.782901 -258.570796) (xy 458.820118 -258.612333) (xy 458.850891 -258.658846) (xy 458.874563 -258.709343)
			(xy 458.890631 -258.76275) (xy 458.898751 -258.817926) (xy 458.89926 -258.845812) (xy 458.898751 -258.873698)
			(xy 458.890631 -258.928874) (xy 458.874563 -258.982281) (xy 458.850891 -259.032778) (xy 458.820118 -259.079291)
			(xy 458.782901 -259.120828) (xy 458.740033 -259.156503) (xy 458.692427 -259.185557) (xy 458.641098 -259.207369)
			(xy 458.587141 -259.221475) (xy 458.531704 -259.227575) (xy 458.47597 -259.225538) (xy 458.421127 -259.215408)
			(xy 458.368343 -259.197401) (xy 458.318743 -259.1719) (xy 458.273385 -259.139449) (xy 458.233236 -259.10074)
			(xy 458.19915 -259.056597) (xy 458.171854 -259.007962) (xy 458.151931 -258.955871) (xy 458.139805 -258.901434)
			(xy 458.135734 -258.845812) (xy 457.491226 -258.845812) (xy 457.491083 -258.853632) (xy 457.482963 -258.908808)
			(xy 457.466895 -258.962215) (xy 457.443223 -259.012712) (xy 457.41245 -259.059225) (xy 457.375233 -259.100762)
			(xy 457.332365 -259.136437) (xy 457.284759 -259.165491) (xy 457.23343 -259.187303) (xy 457.179473 -259.201409)
			(xy 457.124036 -259.207509) (xy 457.068302 -259.205472) (xy 457.013459 -259.195342) (xy 456.960675 -259.177335)
			(xy 456.911075 -259.151834) (xy 456.865717 -259.119383) (xy 456.825568 -259.080674) (xy 456.791482 -259.036531)
			(xy 456.764186 -258.987896) (xy 456.744263 -258.935805) (xy 456.732137 -258.881368) (xy 456.728066 -258.825746)
			(xy 455.917624 -258.825746) (xy 455.914259 -258.84861) (xy 455.898191 -258.902017) (xy 455.874519 -258.952514)
			(xy 455.843746 -258.999027) (xy 455.806529 -259.040564) (xy 455.763661 -259.076239) (xy 455.716055 -259.105293)
			(xy 455.664726 -259.127105) (xy 455.610769 -259.141211) (xy 455.555332 -259.147311) (xy 455.499598 -259.145274)
			(xy 455.444755 -259.135144) (xy 455.391971 -259.117137) (xy 455.342371 -259.091636) (xy 455.297013 -259.059185)
			(xy 455.256864 -259.020476) (xy 455.222778 -258.976333) (xy 455.195482 -258.927698) (xy 455.175559 -258.875607)
			(xy 455.163433 -258.82117) (xy 455.159362 -258.765548) (xy 454.19353 -258.765548) (xy 454.204839 -258.803136)
			(xy 454.212959 -258.858312) (xy 454.213468 -258.886198) (xy 454.212959 -258.914084) (xy 454.204839 -258.96926)
			(xy 454.188771 -259.022667) (xy 454.165099 -259.073164) (xy 454.134326 -259.119677) (xy 454.097109 -259.161214)
			(xy 454.054241 -259.196889) (xy 454.006635 -259.225943) (xy 453.955306 -259.247755) (xy 453.901349 -259.261861)
			(xy 453.845912 -259.267961) (xy 453.790178 -259.265924) (xy 453.735335 -259.255794) (xy 453.682551 -259.237787)
			(xy 453.632951 -259.212286) (xy 453.587593 -259.179835) (xy 453.547444 -259.141126) (xy 453.513358 -259.096983)
			(xy 453.486062 -259.048348) (xy 453.466139 -258.996257) (xy 453.454013 -258.94182) (xy 453.449942 -258.886198)
			(xy 452.699952 -258.886198) (xy 452.704707 -258.91851) (xy 452.705216 -258.946396) (xy 452.704707 -258.974282)
			(xy 452.696587 -259.029458) (xy 452.680519 -259.082865) (xy 452.656847 -259.133362) (xy 452.626074 -259.179875)
			(xy 452.588857 -259.221412) (xy 452.545989 -259.257087) (xy 452.498383 -259.286141) (xy 452.447054 -259.307953)
			(xy 452.393097 -259.322059) (xy 452.33766 -259.328159) (xy 452.281926 -259.326122) (xy 452.227083 -259.315992)
			(xy 452.174299 -259.297985) (xy 452.124699 -259.272484) (xy 452.079341 -259.240033) (xy 452.039192 -259.201324)
			(xy 452.005106 -259.157181) (xy 451.97781 -259.108546) (xy 451.957887 -259.056455) (xy 451.945761 -259.002018)
			(xy 451.94169 -258.946396) (xy 451.191446 -258.946396) (xy 451.188081 -258.96926) (xy 451.172013 -259.022667)
			(xy 451.148341 -259.073164) (xy 451.117568 -259.119677) (xy 451.080351 -259.161214) (xy 451.037483 -259.196889)
			(xy 450.989877 -259.225943) (xy 450.938548 -259.247755) (xy 450.884591 -259.261861) (xy 450.829154 -259.267961)
			(xy 450.77342 -259.265924) (xy 450.718577 -259.255794) (xy 450.665793 -259.237787) (xy 450.616193 -259.212286)
			(xy 450.570835 -259.179835) (xy 450.530686 -259.141126) (xy 450.4966 -259.096983) (xy 450.469304 -259.048348)
			(xy 450.449381 -258.996257) (xy 450.437255 -258.94182) (xy 450.433184 -258.886198) (xy 449.706213 -258.886198)
			(xy 449.708015 -258.898444) (xy 449.708524 -258.92633) (xy 449.708015 -258.954216) (xy 449.699895 -259.009392)
			(xy 449.683827 -259.062799) (xy 449.660155 -259.113296) (xy 449.629382 -259.159809) (xy 449.592165 -259.201346)
			(xy 449.549297 -259.237021) (xy 449.501691 -259.266075) (xy 449.450362 -259.287887) (xy 449.396405 -259.301993)
			(xy 449.340968 -259.308093) (xy 449.285234 -259.306056) (xy 449.230391 -259.295926) (xy 449.177607 -259.277919)
			(xy 449.128007 -259.252418) (xy 449.082649 -259.219967) (xy 449.0425 -259.181258) (xy 449.008414 -259.137115)
			(xy 448.981118 -259.08848) (xy 448.961195 -259.036389) (xy 448.949069 -258.981952) (xy 448.944998 -258.92633)
			(xy 413.269176 -258.92633) (xy 412.62173 -259.573776) (xy 446.548508 -259.573776) (xy 446.552579 -259.518154)
			(xy 446.564705 -259.463717) (xy 446.584628 -259.411626) (xy 446.611924 -259.362991) (xy 446.64601 -259.318848)
			(xy 446.686159 -259.280139) (xy 446.731517 -259.247688) (xy 446.781117 -259.222187) (xy 446.833901 -259.20418)
			(xy 446.888744 -259.19405) (xy 446.944478 -259.192013) (xy 446.999915 -259.198113) (xy 447.053872 -259.212219)
			(xy 447.105201 -259.234031) (xy 447.152807 -259.263085) (xy 447.195675 -259.29876) (xy 447.232892 -259.340297)
			(xy 447.242842 -259.355336) (xy 459.730854 -259.355336) (xy 459.734925 -259.299714) (xy 459.747051 -259.245277)
			(xy 459.766974 -259.193186) (xy 459.79427 -259.144551) (xy 459.828356 -259.100408) (xy 459.868505 -259.061699)
			(xy 459.913863 -259.029248) (xy 459.963463 -259.003747) (xy 460.016247 -258.98574) (xy 460.07109 -258.97561)
			(xy 460.126824 -258.973573) (xy 460.182261 -258.979673) (xy 460.236218 -258.993779) (xy 460.287547 -259.015591)
			(xy 460.335153 -259.044645) (xy 460.378021 -259.08032) (xy 460.415238 -259.121857) (xy 460.446011 -259.16837)
			(xy 460.469683 -259.218867) (xy 460.485751 -259.272274) (xy 460.493871 -259.32745) (xy 460.49438 -259.355336)
			(xy 460.493871 -259.383222) (xy 460.485751 -259.438398) (xy 460.469683 -259.491805) (xy 460.446011 -259.542302)
			(xy 460.415238 -259.588815) (xy 460.378021 -259.630352) (xy 460.335153 -259.666027) (xy 460.287547 -259.695081)
			(xy 460.236218 -259.716893) (xy 460.182261 -259.730999) (xy 460.126824 -259.737099) (xy 460.07109 -259.735062)
			(xy 460.016247 -259.724932) (xy 459.963463 -259.706925) (xy 459.913863 -259.681424) (xy 459.868505 -259.648973)
			(xy 459.828356 -259.610264) (xy 459.79427 -259.566121) (xy 459.766974 -259.517486) (xy 459.747051 -259.465395)
			(xy 459.734925 -259.410958) (xy 459.730854 -259.355336) (xy 447.242842 -259.355336) (xy 447.263665 -259.38681)
			(xy 447.287337 -259.437307) (xy 447.303405 -259.490714) (xy 447.311525 -259.54589) (xy 447.312034 -259.573776)
			(xy 447.311525 -259.601662) (xy 447.303405 -259.656838) (xy 447.287337 -259.710245) (xy 447.263665 -259.760742)
			(xy 447.232892 -259.807255) (xy 447.195675 -259.848792) (xy 447.152807 -259.884467) (xy 447.105201 -259.913521)
			(xy 447.053872 -259.935333) (xy 446.999915 -259.949439) (xy 446.944478 -259.955539) (xy 446.888744 -259.953502)
			(xy 446.833901 -259.943372) (xy 446.781117 -259.925365) (xy 446.731517 -259.899864) (xy 446.686159 -259.867413)
			(xy 446.64601 -259.828704) (xy 446.611924 -259.784561) (xy 446.584628 -259.735926) (xy 446.564705 -259.683835)
			(xy 446.552579 -259.629398) (xy 446.548508 -259.573776) (xy 412.62173 -259.573776) (xy 412.17723 -260.018276)
			(xy 448.904358 -260.018276) (xy 448.908429 -259.962654) (xy 448.920555 -259.908217) (xy 448.940478 -259.856126)
			(xy 448.967774 -259.807491) (xy 449.00186 -259.763348) (xy 449.042009 -259.724639) (xy 449.087367 -259.692188)
			(xy 449.136967 -259.666687) (xy 449.189751 -259.64868) (xy 449.244594 -259.63855) (xy 449.300328 -259.636513)
			(xy 449.355765 -259.642613) (xy 449.409722 -259.656719) (xy 449.461051 -259.678531) (xy 449.508657 -259.707585)
			(xy 449.551525 -259.74326) (xy 449.588742 -259.784797) (xy 449.619515 -259.83131) (xy 449.643187 -259.881807)
			(xy 449.659255 -259.935214) (xy 449.667375 -259.99039) (xy 449.667884 -260.018276) (xy 450.428358 -260.018276)
			(xy 450.432429 -259.962654) (xy 450.444555 -259.908217) (xy 450.464478 -259.856126) (xy 450.491774 -259.807491)
			(xy 450.52586 -259.763348) (xy 450.566009 -259.724639) (xy 450.611367 -259.692188) (xy 450.660967 -259.666687)
			(xy 450.713751 -259.64868) (xy 450.768594 -259.63855) (xy 450.824328 -259.636513) (xy 450.879765 -259.642613)
			(xy 450.933722 -259.656719) (xy 450.985051 -259.678531) (xy 451.032657 -259.707585) (xy 451.075525 -259.74326)
			(xy 451.112742 -259.784797) (xy 451.143515 -259.83131) (xy 451.167187 -259.881807) (xy 451.183255 -259.935214)
			(xy 451.185685 -259.951728) (xy 451.492364 -259.951728) (xy 451.496435 -259.896106) (xy 451.508561 -259.841669)
			(xy 451.528484 -259.789578) (xy 451.55578 -259.740943) (xy 451.589866 -259.6968) (xy 451.630015 -259.658091)
			(xy 451.675373 -259.62564) (xy 451.724973 -259.600139) (xy 451.777757 -259.582132) (xy 451.8326 -259.572002)
			(xy 451.888334 -259.569965) (xy 451.943771 -259.576065) (xy 451.997728 -259.590171) (xy 452.049057 -259.611983)
			(xy 452.096663 -259.641037) (xy 452.139531 -259.676712) (xy 452.176748 -259.718249) (xy 452.207521 -259.764762)
			(xy 452.231193 -259.815259) (xy 452.247261 -259.868666) (xy 452.255381 -259.923842) (xy 452.25589 -259.951728)
			(xy 452.255381 -259.979614) (xy 452.249691 -260.018276) (xy 452.714358 -260.018276) (xy 452.718429 -259.962654)
			(xy 452.730555 -259.908217) (xy 452.750478 -259.856126) (xy 452.777774 -259.807491) (xy 452.81186 -259.763348)
			(xy 452.852009 -259.724639) (xy 452.897367 -259.692188) (xy 452.946967 -259.666687) (xy 452.999751 -259.64868)
			(xy 453.054594 -259.63855) (xy 453.110328 -259.636513) (xy 453.165765 -259.642613) (xy 453.219722 -259.656719)
			(xy 453.271051 -259.678531) (xy 453.318657 -259.707585) (xy 453.361525 -259.74326) (xy 453.398742 -259.784797)
			(xy 453.429515 -259.83131) (xy 453.453187 -259.881807) (xy 453.469255 -259.935214) (xy 453.477375 -259.99039)
			(xy 453.477884 -260.018276) (xy 454.238358 -260.018276) (xy 454.242429 -259.962654) (xy 454.254555 -259.908217)
			(xy 454.274478 -259.856126) (xy 454.301774 -259.807491) (xy 454.33586 -259.763348) (xy 454.376009 -259.724639)
			(xy 454.421367 -259.692188) (xy 454.470967 -259.666687) (xy 454.523751 -259.64868) (xy 454.578594 -259.63855)
			(xy 454.634328 -259.636513) (xy 454.689765 -259.642613) (xy 454.743722 -259.656719) (xy 454.795051 -259.678531)
			(xy 454.842657 -259.707585) (xy 454.885525 -259.74326) (xy 454.922742 -259.784797) (xy 454.953515 -259.83131)
			(xy 454.977187 -259.881807) (xy 454.993255 -259.935214) (xy 455.001375 -259.99039) (xy 455.001884 -260.018276)
			(xy 455.762358 -260.018276) (xy 455.766429 -259.962654) (xy 455.778555 -259.908217) (xy 455.798478 -259.856126)
			(xy 455.825774 -259.807491) (xy 455.85986 -259.763348) (xy 455.900009 -259.724639) (xy 455.945367 -259.692188)
			(xy 455.994967 -259.666687) (xy 456.047751 -259.64868) (xy 456.102594 -259.63855) (xy 456.158328 -259.636513)
			(xy 456.213765 -259.642613) (xy 456.267722 -259.656719) (xy 456.319051 -259.678531) (xy 456.366657 -259.707585)
			(xy 456.409525 -259.74326) (xy 456.446742 -259.784797) (xy 456.477515 -259.83131) (xy 456.501187 -259.881807)
			(xy 456.517255 -259.935214) (xy 456.525375 -259.99039) (xy 456.525884 -260.018276) (xy 457.286358 -260.018276)
			(xy 457.290429 -259.962654) (xy 457.302555 -259.908217) (xy 457.322478 -259.856126) (xy 457.349774 -259.807491)
			(xy 457.38386 -259.763348) (xy 457.424009 -259.724639) (xy 457.469367 -259.692188) (xy 457.518967 -259.666687)
			(xy 457.571751 -259.64868) (xy 457.626594 -259.63855) (xy 457.682328 -259.636513) (xy 457.737765 -259.642613)
			(xy 457.791722 -259.656719) (xy 457.843051 -259.678531) (xy 457.890657 -259.707585) (xy 457.933525 -259.74326)
			(xy 457.970742 -259.784797) (xy 458.001515 -259.83131) (xy 458.025187 -259.881807) (xy 458.041255 -259.935214)
			(xy 458.049375 -259.99039) (xy 458.049884 -260.018276) (xy 458.810358 -260.018276) (xy 458.814429 -259.962654)
			(xy 458.826555 -259.908217) (xy 458.846478 -259.856126) (xy 458.873774 -259.807491) (xy 458.90786 -259.763348)
			(xy 458.948009 -259.724639) (xy 458.993367 -259.692188) (xy 459.042967 -259.666687) (xy 459.095751 -259.64868)
			(xy 459.150594 -259.63855) (xy 459.206328 -259.636513) (xy 459.261765 -259.642613) (xy 459.315722 -259.656719)
			(xy 459.367051 -259.678531) (xy 459.414657 -259.707585) (xy 459.457525 -259.74326) (xy 459.494742 -259.784797)
			(xy 459.525515 -259.83131) (xy 459.549187 -259.881807) (xy 459.565255 -259.935214) (xy 459.573375 -259.99039)
			(xy 459.573884 -260.018276) (xy 459.573375 -260.046162) (xy 459.565255 -260.101338) (xy 459.549187 -260.154745)
			(xy 459.525515 -260.205242) (xy 459.494742 -260.251755) (xy 459.457525 -260.293292) (xy 459.414657 -260.328967)
			(xy 459.367051 -260.358021) (xy 459.315722 -260.379833) (xy 459.261765 -260.393939) (xy 459.206328 -260.400039)
			(xy 459.150594 -260.398002) (xy 459.095751 -260.387872) (xy 459.042967 -260.369865) (xy 458.993367 -260.344364)
			(xy 458.948009 -260.311913) (xy 458.90786 -260.273204) (xy 458.873774 -260.229061) (xy 458.846478 -260.180426)
			(xy 458.826555 -260.128335) (xy 458.814429 -260.073898) (xy 458.810358 -260.018276) (xy 458.049884 -260.018276)
			(xy 458.049375 -260.046162) (xy 458.041255 -260.101338) (xy 458.025187 -260.154745) (xy 458.001515 -260.205242)
			(xy 457.970742 -260.251755) (xy 457.933525 -260.293292) (xy 457.890657 -260.328967) (xy 457.843051 -260.358021)
			(xy 457.791722 -260.379833) (xy 457.737765 -260.393939) (xy 457.682328 -260.400039) (xy 457.626594 -260.398002)
			(xy 457.571751 -260.387872) (xy 457.518967 -260.369865) (xy 457.469367 -260.344364) (xy 457.424009 -260.311913)
			(xy 457.38386 -260.273204) (xy 457.349774 -260.229061) (xy 457.322478 -260.180426) (xy 457.302555 -260.128335)
			(xy 457.290429 -260.073898) (xy 457.286358 -260.018276) (xy 456.525884 -260.018276) (xy 456.525375 -260.046162)
			(xy 456.517255 -260.101338) (xy 456.501187 -260.154745) (xy 456.477515 -260.205242) (xy 456.446742 -260.251755)
			(xy 456.409525 -260.293292) (xy 456.366657 -260.328967) (xy 456.319051 -260.358021) (xy 456.267722 -260.379833)
			(xy 456.213765 -260.393939) (xy 456.158328 -260.400039) (xy 456.102594 -260.398002) (xy 456.047751 -260.387872)
			(xy 455.994967 -260.369865) (xy 455.945367 -260.344364) (xy 455.900009 -260.311913) (xy 455.85986 -260.273204)
			(xy 455.825774 -260.229061) (xy 455.798478 -260.180426) (xy 455.778555 -260.128335) (xy 455.766429 -260.073898)
			(xy 455.762358 -260.018276) (xy 455.001884 -260.018276) (xy 455.001375 -260.046162) (xy 454.993255 -260.101338)
			(xy 454.977187 -260.154745) (xy 454.953515 -260.205242) (xy 454.922742 -260.251755) (xy 454.885525 -260.293292)
			(xy 454.842657 -260.328967) (xy 454.795051 -260.358021) (xy 454.743722 -260.379833) (xy 454.689765 -260.393939)
			(xy 454.634328 -260.400039) (xy 454.578594 -260.398002) (xy 454.523751 -260.387872) (xy 454.470967 -260.369865)
			(xy 454.421367 -260.344364) (xy 454.376009 -260.311913) (xy 454.33586 -260.273204) (xy 454.301774 -260.229061)
			(xy 454.274478 -260.180426) (xy 454.254555 -260.128335) (xy 454.242429 -260.073898) (xy 454.238358 -260.018276)
			(xy 453.477884 -260.018276) (xy 453.477375 -260.046162) (xy 453.469255 -260.101338) (xy 453.453187 -260.154745)
			(xy 453.429515 -260.205242) (xy 453.398742 -260.251755) (xy 453.361525 -260.293292) (xy 453.318657 -260.328967)
			(xy 453.271051 -260.358021) (xy 453.219722 -260.379833) (xy 453.165765 -260.393939) (xy 453.110328 -260.400039)
			(xy 453.054594 -260.398002) (xy 452.999751 -260.387872) (xy 452.946967 -260.369865) (xy 452.897367 -260.344364)
			(xy 452.852009 -260.311913) (xy 452.81186 -260.273204) (xy 452.777774 -260.229061) (xy 452.750478 -260.180426)
			(xy 452.730555 -260.128335) (xy 452.718429 -260.073898) (xy 452.714358 -260.018276) (xy 452.249691 -260.018276)
			(xy 452.247261 -260.03479) (xy 452.231193 -260.088197) (xy 452.207521 -260.138694) (xy 452.176748 -260.185207)
			(xy 452.139531 -260.226744) (xy 452.096663 -260.262419) (xy 452.049057 -260.291473) (xy 451.997728 -260.313285)
			(xy 451.943771 -260.327391) (xy 451.888334 -260.333491) (xy 451.8326 -260.331454) (xy 451.777757 -260.321324)
			(xy 451.724973 -260.303317) (xy 451.675373 -260.277816) (xy 451.630015 -260.245365) (xy 451.589866 -260.206656)
			(xy 451.55578 -260.162513) (xy 451.528484 -260.113878) (xy 451.508561 -260.061787) (xy 451.496435 -260.00735)
			(xy 451.492364 -259.951728) (xy 451.185685 -259.951728) (xy 451.191375 -259.99039) (xy 451.191884 -260.018276)
			(xy 451.191375 -260.046162) (xy 451.183255 -260.101338) (xy 451.167187 -260.154745) (xy 451.143515 -260.205242)
			(xy 451.112742 -260.251755) (xy 451.075525 -260.293292) (xy 451.032657 -260.328967) (xy 450.985051 -260.358021)
			(xy 450.933722 -260.379833) (xy 450.879765 -260.393939) (xy 450.824328 -260.400039) (xy 450.768594 -260.398002)
			(xy 450.713751 -260.387872) (xy 450.660967 -260.369865) (xy 450.611367 -260.344364) (xy 450.566009 -260.311913)
			(xy 450.52586 -260.273204) (xy 450.491774 -260.229061) (xy 450.464478 -260.180426) (xy 450.444555 -260.128335)
			(xy 450.432429 -260.073898) (xy 450.428358 -260.018276) (xy 449.667884 -260.018276) (xy 449.667375 -260.046162)
			(xy 449.659255 -260.101338) (xy 449.643187 -260.154745) (xy 449.619515 -260.205242) (xy 449.588742 -260.251755)
			(xy 449.551525 -260.293292) (xy 449.508657 -260.328967) (xy 449.461051 -260.358021) (xy 449.409722 -260.379833)
			(xy 449.355765 -260.393939) (xy 449.300328 -260.400039) (xy 449.244594 -260.398002) (xy 449.189751 -260.387872)
			(xy 449.136967 -260.369865) (xy 449.087367 -260.344364) (xy 449.042009 -260.311913) (xy 449.00186 -260.273204)
			(xy 448.967774 -260.229061) (xy 448.940478 -260.180426) (xy 448.920555 -260.128335) (xy 448.908429 -260.073898)
			(xy 448.904358 -260.018276) (xy 412.17723 -260.018276) (xy 411.247255 -260.948251) (xy 448.90537 -260.948251)
			(xy 448.90537 -260.893749) (xy 448.913126 -260.839803) (xy 448.92848 -260.787509) (xy 448.95112 -260.737932)
			(xy 448.980585 -260.692082) (xy 449.016274 -260.650891) (xy 449.057462 -260.615199) (xy 449.103311 -260.585731)
			(xy 449.152886 -260.563088) (xy 449.205179 -260.547731) (xy 449.259125 -260.539971) (xy 449.286376 -260.539484)
			(xy 449.313443 -260.539965) (xy 449.367035 -260.547614) (xy 449.419007 -260.562762) (xy 449.468316 -260.585105)
			(xy 449.513971 -260.614194) (xy 449.555056 -260.649444) (xy 449.590745 -260.690148) (xy 449.620323 -260.735488)
			(xy 449.643193 -260.784555) (xy 449.658898 -260.836361) (xy 449.667122 -260.889867) (xy 449.667884 -260.916928)
			(xy 449.668059 -260.920992) (xy 450.428358 -260.920992) (xy 450.432429 -260.86537) (xy 450.444555 -260.810933)
			(xy 450.464478 -260.758842) (xy 450.491774 -260.710207) (xy 450.52586 -260.666064) (xy 450.566009 -260.627355)
			(xy 450.611367 -260.594904) (xy 450.660967 -260.569403) (xy 450.713751 -260.551396) (xy 450.768594 -260.541266)
			(xy 450.824328 -260.539229) (xy 450.879765 -260.545329) (xy 450.933722 -260.559435) (xy 450.985051 -260.581247)
			(xy 451.032657 -260.610301) (xy 451.075525 -260.645976) (xy 451.112742 -260.687513) (xy 451.143515 -260.734026)
			(xy 451.167187 -260.784523) (xy 451.183255 -260.83793) (xy 451.191375 -260.893106) (xy 451.191884 -260.920992)
			(xy 451.952358 -260.920992) (xy 451.956429 -260.86537) (xy 451.968555 -260.810933) (xy 451.988478 -260.758842)
			(xy 452.015774 -260.710207) (xy 452.04986 -260.666064) (xy 452.090009 -260.627355) (xy 452.135367 -260.594904)
			(xy 452.184967 -260.569403) (xy 452.237751 -260.551396) (xy 452.292594 -260.541266) (xy 452.348328 -260.539229)
			(xy 452.403765 -260.545329) (xy 452.457722 -260.559435) (xy 452.509051 -260.581247) (xy 452.556657 -260.610301)
			(xy 452.599525 -260.645976) (xy 452.636742 -260.687513) (xy 452.667515 -260.734026) (xy 452.691187 -260.784523)
			(xy 452.707255 -260.83793) (xy 452.715375 -260.893106) (xy 452.715884 -260.920992) (xy 453.476358 -260.920992)
			(xy 453.480429 -260.86537) (xy 453.492555 -260.810933) (xy 453.512478 -260.758842) (xy 453.539774 -260.710207)
			(xy 453.57386 -260.666064) (xy 453.614009 -260.627355) (xy 453.659367 -260.594904) (xy 453.708967 -260.569403)
			(xy 453.761751 -260.551396) (xy 453.816594 -260.541266) (xy 453.872328 -260.539229) (xy 453.927765 -260.545329)
			(xy 453.981722 -260.559435) (xy 454.033051 -260.581247) (xy 454.080657 -260.610301) (xy 454.123525 -260.645976)
			(xy 454.160742 -260.687513) (xy 454.191515 -260.734026) (xy 454.215187 -260.784523) (xy 454.231255 -260.83793)
			(xy 454.239375 -260.893106) (xy 454.239884 -260.920992) (xy 455.000358 -260.920992) (xy 455.004429 -260.86537)
			(xy 455.016555 -260.810933) (xy 455.036478 -260.758842) (xy 455.063774 -260.710207) (xy 455.09786 -260.666064)
			(xy 455.138009 -260.627355) (xy 455.183367 -260.594904) (xy 455.232967 -260.569403) (xy 455.285751 -260.551396)
			(xy 455.340594 -260.541266) (xy 455.396328 -260.539229) (xy 455.451765 -260.545329) (xy 455.505722 -260.559435)
			(xy 455.557051 -260.581247) (xy 455.604657 -260.610301) (xy 455.647525 -260.645976) (xy 455.684742 -260.687513)
			(xy 455.715515 -260.734026) (xy 455.739187 -260.784523) (xy 455.755255 -260.83793) (xy 455.763375 -260.893106)
			(xy 455.763884 -260.920992) (xy 456.524358 -260.920992) (xy 456.528429 -260.86537) (xy 456.540555 -260.810933)
			(xy 456.560478 -260.758842) (xy 456.587774 -260.710207) (xy 456.62186 -260.666064) (xy 456.662009 -260.627355)
			(xy 456.707367 -260.594904) (xy 456.756967 -260.569403) (xy 456.809751 -260.551396) (xy 456.864594 -260.541266)
			(xy 456.920328 -260.539229) (xy 456.975765 -260.545329) (xy 457.029722 -260.559435) (xy 457.081051 -260.581247)
			(xy 457.128657 -260.610301) (xy 457.171525 -260.645976) (xy 457.208742 -260.687513) (xy 457.239515 -260.734026)
			(xy 457.263187 -260.784523) (xy 457.279255 -260.83793) (xy 457.287375 -260.893106) (xy 457.287884 -260.920992)
			(xy 457.287375 -260.948878) (xy 457.283143 -260.977634) (xy 457.669136 -260.977634) (xy 457.673207 -260.922012)
			(xy 457.685333 -260.867575) (xy 457.705256 -260.815484) (xy 457.732552 -260.766849) (xy 457.766638 -260.722706)
			(xy 457.806787 -260.683997) (xy 457.852145 -260.651546) (xy 457.901745 -260.626045) (xy 457.954529 -260.608038)
			(xy 458.009372 -260.597908) (xy 458.065106 -260.595871) (xy 458.120543 -260.601971) (xy 458.1745 -260.616077)
			(xy 458.225829 -260.637889) (xy 458.273435 -260.666943) (xy 458.316303 -260.702618) (xy 458.35352 -260.744155)
			(xy 458.384293 -260.790668) (xy 458.407965 -260.841165) (xy 458.424033 -260.894572) (xy 458.427921 -260.920992)
			(xy 458.810358 -260.920992) (xy 458.814429 -260.86537) (xy 458.826555 -260.810933) (xy 458.846478 -260.758842)
			(xy 458.873774 -260.710207) (xy 458.90786 -260.666064) (xy 458.948009 -260.627355) (xy 458.993367 -260.594904)
			(xy 459.042967 -260.569403) (xy 459.095751 -260.551396) (xy 459.150594 -260.541266) (xy 459.206328 -260.539229)
			(xy 459.261765 -260.545329) (xy 459.315722 -260.559435) (xy 459.367051 -260.581247) (xy 459.414657 -260.610301)
			(xy 459.457525 -260.645976) (xy 459.494742 -260.687513) (xy 459.525515 -260.734026) (xy 459.549187 -260.784523)
			(xy 459.560518 -260.822186) (xy 460.002634 -260.822186) (xy 460.006705 -260.766564) (xy 460.018831 -260.712127)
			(xy 460.038754 -260.660036) (xy 460.06605 -260.611401) (xy 460.100136 -260.567258) (xy 460.140285 -260.528549)
			(xy 460.185643 -260.496098) (xy 460.235243 -260.470597) (xy 460.288027 -260.45259) (xy 460.34287 -260.44246)
			(xy 460.398604 -260.440423) (xy 460.454041 -260.446523) (xy 460.507998 -260.460629) (xy 460.559327 -260.482441)
			(xy 460.606933 -260.511495) (xy 460.649801 -260.54717) (xy 460.687018 -260.588707) (xy 460.717791 -260.63522)
			(xy 460.741463 -260.685717) (xy 460.757531 -260.739124) (xy 460.765651 -260.7943) (xy 460.76616 -260.822186)
			(xy 460.765651 -260.850072) (xy 460.757531 -260.905248) (xy 460.741463 -260.958655) (xy 460.717791 -261.009152)
			(xy 460.687018 -261.055665) (xy 460.649801 -261.097202) (xy 460.606933 -261.132877) (xy 460.559327 -261.161931)
			(xy 460.507998 -261.183743) (xy 460.454041 -261.197849) (xy 460.398604 -261.203949) (xy 460.34287 -261.201912)
			(xy 460.288027 -261.191782) (xy 460.235243 -261.173775) (xy 460.185643 -261.148274) (xy 460.140285 -261.115823)
			(xy 460.100136 -261.077114) (xy 460.06605 -261.032971) (xy 460.038754 -260.984336) (xy 460.018831 -260.932245)
			(xy 460.006705 -260.877808) (xy 460.002634 -260.822186) (xy 459.560518 -260.822186) (xy 459.565255 -260.83793)
			(xy 459.573375 -260.893106) (xy 459.573884 -260.920992) (xy 459.573375 -260.948878) (xy 459.565255 -261.004054)
			(xy 459.549187 -261.057461) (xy 459.525515 -261.107958) (xy 459.494742 -261.154471) (xy 459.457525 -261.196008)
			(xy 459.414657 -261.231683) (xy 459.367051 -261.260737) (xy 459.315722 -261.282549) (xy 459.261765 -261.296655)
			(xy 459.206328 -261.302755) (xy 459.150594 -261.300718) (xy 459.095751 -261.290588) (xy 459.042967 -261.272581)
			(xy 458.993367 -261.24708) (xy 458.948009 -261.214629) (xy 458.90786 -261.17592) (xy 458.873774 -261.131777)
			(xy 458.846478 -261.083142) (xy 458.826555 -261.031051) (xy 458.814429 -260.976614) (xy 458.810358 -260.920992)
			(xy 458.427921 -260.920992) (xy 458.432153 -260.949748) (xy 458.432662 -260.977634) (xy 458.432153 -261.00552)
			(xy 458.424033 -261.060696) (xy 458.407965 -261.114103) (xy 458.384293 -261.1646) (xy 458.35352 -261.211113)
			(xy 458.316303 -261.25265) (xy 458.273435 -261.288325) (xy 458.225829 -261.317379) (xy 458.1745 -261.339191)
			(xy 458.120543 -261.353297) (xy 458.065106 -261.359397) (xy 458.009372 -261.35736) (xy 457.954529 -261.34723)
			(xy 457.901745 -261.329223) (xy 457.852145 -261.303722) (xy 457.806787 -261.271271) (xy 457.766638 -261.232562)
			(xy 457.732552 -261.188419) (xy 457.705256 -261.139784) (xy 457.685333 -261.087693) (xy 457.673207 -261.033256)
			(xy 457.669136 -260.977634) (xy 457.283143 -260.977634) (xy 457.279255 -261.004054) (xy 457.263187 -261.057461)
			(xy 457.239515 -261.107958) (xy 457.208742 -261.154471) (xy 457.171525 -261.196008) (xy 457.128657 -261.231683)
			(xy 457.081051 -261.260737) (xy 457.029722 -261.282549) (xy 456.975765 -261.296655) (xy 456.920328 -261.302755)
			(xy 456.864594 -261.300718) (xy 456.809751 -261.290588) (xy 456.756967 -261.272581) (xy 456.707367 -261.24708)
			(xy 456.662009 -261.214629) (xy 456.62186 -261.17592) (xy 456.587774 -261.131777) (xy 456.560478 -261.083142)
			(xy 456.540555 -261.031051) (xy 456.528429 -260.976614) (xy 456.524358 -260.920992) (xy 455.763884 -260.920992)
			(xy 455.763375 -260.948878) (xy 455.755255 -261.004054) (xy 455.739187 -261.057461) (xy 455.715515 -261.107958)
			(xy 455.684742 -261.154471) (xy 455.647525 -261.196008) (xy 455.604657 -261.231683) (xy 455.557051 -261.260737)
			(xy 455.505722 -261.282549) (xy 455.451765 -261.296655) (xy 455.396328 -261.302755) (xy 455.340594 -261.300718)
			(xy 455.285751 -261.290588) (xy 455.232967 -261.272581) (xy 455.183367 -261.24708) (xy 455.138009 -261.214629)
			(xy 455.09786 -261.17592) (xy 455.063774 -261.131777) (xy 455.036478 -261.083142) (xy 455.016555 -261.031051)
			(xy 455.004429 -260.976614) (xy 455.000358 -260.920992) (xy 454.239884 -260.920992) (xy 454.239375 -260.948878)
			(xy 454.231255 -261.004054) (xy 454.215187 -261.057461) (xy 454.191515 -261.107958) (xy 454.160742 -261.154471)
			(xy 454.123525 -261.196008) (xy 454.080657 -261.231683) (xy 454.033051 -261.260737) (xy 453.981722 -261.282549)
			(xy 453.927765 -261.296655) (xy 453.872328 -261.302755) (xy 453.816594 -261.300718) (xy 453.761751 -261.290588)
			(xy 453.708967 -261.272581) (xy 453.659367 -261.24708) (xy 453.614009 -261.214629) (xy 453.57386 -261.17592)
			(xy 453.539774 -261.131777) (xy 453.512478 -261.083142) (xy 453.492555 -261.031051) (xy 453.480429 -260.976614)
			(xy 453.476358 -260.920992) (xy 452.715884 -260.920992) (xy 452.715375 -260.948878) (xy 452.707255 -261.004054)
			(xy 452.691187 -261.057461) (xy 452.667515 -261.107958) (xy 452.636742 -261.154471) (xy 452.599525 -261.196008)
			(xy 452.556657 -261.231683) (xy 452.509051 -261.260737) (xy 452.457722 -261.282549) (xy 452.403765 -261.296655)
			(xy 452.348328 -261.302755) (xy 452.292594 -261.300718) (xy 452.237751 -261.290588) (xy 452.184967 -261.272581)
			(xy 452.135367 -261.24708) (xy 452.090009 -261.214629) (xy 452.04986 -261.17592) (xy 452.015774 -261.131777)
			(xy 451.988478 -261.083142) (xy 451.968555 -261.031051) (xy 451.956429 -260.976614) (xy 451.952358 -260.920992)
			(xy 451.191884 -260.920992) (xy 451.191375 -260.948878) (xy 451.183255 -261.004054) (xy 451.167187 -261.057461)
			(xy 451.143515 -261.107958) (xy 451.112742 -261.154471) (xy 451.075525 -261.196008) (xy 451.032657 -261.231683)
			(xy 450.985051 -261.260737) (xy 450.933722 -261.282549) (xy 450.879765 -261.296655) (xy 450.824328 -261.302755)
			(xy 450.768594 -261.300718) (xy 450.713751 -261.290588) (xy 450.660967 -261.272581) (xy 450.611367 -261.24708)
			(xy 450.566009 -261.214629) (xy 450.52586 -261.17592) (xy 450.491774 -261.131777) (xy 450.464478 -261.083142)
			(xy 450.444555 -261.031051) (xy 450.432429 -260.976614) (xy 450.428358 -260.920992) (xy 449.668059 -260.920992)
			(xy 449.668467 -260.930483) (xy 449.675847 -260.95658) (xy 449.68984 -260.979811) (xy 449.709457 -260.998537)
			(xy 449.733313 -261.011436) (xy 449.759724 -261.017597) (xy 449.786826 -261.016585) (xy 449.812703 -261.008471)
			(xy 449.824348 -261.00151) (xy 449.847502 -260.987199) (xy 449.89702 -260.964601) (xy 449.949249 -260.949277)
			(xy 450.003127 -260.94154) (xy 450.030342 -260.941058) (xy 450.057589 -260.941615) (xy 450.111527 -260.949376)
			(xy 450.163812 -260.964733) (xy 450.21338 -260.987375) (xy 450.259221 -261.016839) (xy 450.300402 -261.052528)
			(xy 450.336086 -261.093713) (xy 450.365546 -261.139557) (xy 450.388182 -261.189127) (xy 450.403533 -261.241414)
			(xy 450.411288 -261.295353) (xy 450.411288 -261.349847) (xy 450.403533 -261.403786) (xy 450.388182 -261.456073)
			(xy 450.365546 -261.505643) (xy 450.336086 -261.551487) (xy 450.300402 -261.592672) (xy 450.259221 -261.628361)
			(xy 450.21338 -261.657825) (xy 450.163812 -261.680467) (xy 450.111527 -261.695824) (xy 450.057589 -261.703585)
			(xy 450.030342 -261.704074) (xy 450.003273 -261.703617) (xy 449.949679 -261.695969) (xy 449.897704 -261.680821)
			(xy 449.848392 -261.658478) (xy 449.802735 -261.629387) (xy 449.761649 -261.594134) (xy 449.725959 -261.553427)
			(xy 449.696383 -261.508082) (xy 449.673514 -261.459012) (xy 449.657813 -261.407202) (xy 449.649593 -261.353692)
			(xy 449.648834 -261.32663) (xy 449.648254 -261.313076) (xy 449.640865 -261.286985) (xy 449.626869 -261.26376)
			(xy 449.607252 -261.245038) (xy 449.583398 -261.232141) (xy 449.556991 -261.225979) (xy 449.529893 -261.226986)
			(xy 449.504016 -261.235091) (xy 449.49237 -261.242048) (xy 449.469209 -261.256346) (xy 449.419694 -261.278949)
			(xy 449.367467 -261.294276) (xy 449.313591 -261.302016) (xy 449.286376 -261.3025) (xy 449.259125 -261.302029)
			(xy 449.205179 -261.294269) (xy 449.152886 -261.278912) (xy 449.103311 -261.256269) (xy 449.057462 -261.226801)
			(xy 449.016274 -261.191109) (xy 448.980585 -261.149918) (xy 448.95112 -261.104068) (xy 448.92848 -261.054491)
			(xy 448.913126 -261.002197) (xy 448.90537 -260.948251) (xy 411.247255 -260.948251) (xy 410.25445 -261.941056)
			(xy 459.446628 -261.941056) (xy 459.450699 -261.885434) (xy 459.462825 -261.830997) (xy 459.482748 -261.778906)
			(xy 459.510044 -261.730271) (xy 459.54413 -261.686128) (xy 459.584279 -261.647419) (xy 459.629637 -261.614968)
			(xy 459.679237 -261.589467) (xy 459.732021 -261.57146) (xy 459.786864 -261.56133) (xy 459.842598 -261.559293)
			(xy 459.898035 -261.565393) (xy 459.951992 -261.579499) (xy 460.003321 -261.601311) (xy 460.050927 -261.630365)
			(xy 460.093795 -261.66604) (xy 460.131012 -261.707577) (xy 460.161785 -261.75409) (xy 460.185457 -261.804587)
			(xy 460.201525 -261.857994) (xy 460.209645 -261.91317) (xy 460.210154 -261.941056) (xy 460.209645 -261.968942)
			(xy 460.201525 -262.024118) (xy 460.185457 -262.077525) (xy 460.161785 -262.128022) (xy 460.131012 -262.174535)
			(xy 460.093795 -262.216072) (xy 460.050927 -262.251747) (xy 460.003321 -262.280801) (xy 459.951992 -262.302613)
			(xy 459.898035 -262.316719) (xy 459.842598 -262.322819) (xy 459.786864 -262.320782) (xy 459.732021 -262.310652)
			(xy 459.679237 -262.292645) (xy 459.629637 -262.267144) (xy 459.584279 -262.234693) (xy 459.54413 -262.195984)
			(xy 459.510044 -262.151841) (xy 459.482748 -262.103206) (xy 459.462825 -262.051115) (xy 459.450699 -261.996678)
			(xy 459.446628 -261.941056) (xy 410.25445 -261.941056) (xy 408.045666 -264.14984) (xy 408.040482 -264.155478)
			(xy 408.033384 -264.169039) (xy 408.031696 -264.17651) (xy 407.664158 -266.175998) (xy 407.663396 -266.185142)
			(xy 407.663396 -270.89989) (xy 433.198785 -270.89989) (xy 433.202791 -270.704835) (xy 433.214801 -270.510109)
			(xy 433.234796 -270.31604) (xy 433.262741 -270.122956) (xy 433.29859 -269.931181) (xy 433.342282 -269.741041)
			(xy 433.393743 -269.552854) (xy 433.452887 -269.366939) (xy 433.519614 -269.183608) (xy 433.593811 -269.003172)
			(xy 433.675353 -268.825934) (xy 433.764104 -268.652193) (xy 433.859912 -268.482242) (xy 433.962617 -268.316368)
			(xy 434.072045 -268.15485) (xy 434.188012 -267.997961) (xy 434.310323 -267.845966) (xy 434.43877 -267.69912)
			(xy 434.573138 -267.557671) (xy 434.7132 -267.421858) (xy 434.858719 -267.291909) (xy 435.009451 -267.168045)
			(xy 435.165141 -267.050473) (xy 435.325527 -266.939393) (xy 435.490338 -266.83499) (xy 435.659296 -266.737442)
			(xy 435.832117 -266.646913) (xy 436.008509 -266.563555) (xy 436.188174 -266.487509) (xy 436.370809 -266.418904)
			(xy 436.556108 -266.357854) (xy 436.743756 -266.304464) (xy 436.933438 -266.258822) (xy 437.124835 -266.221006)
			(xy 437.317622 -266.19108) (xy 437.511475 -266.169094) (xy 437.706068 -266.155085) (xy 437.901071 -266.149077)
			(xy 438.096157 -266.15108) (xy 438.290996 -266.161091) (xy 438.48526 -266.179092) (xy 438.678621 -266.205054)
			(xy 438.870754 -266.238932) (xy 439.061333 -266.280669) (xy 439.250038 -266.330196) (xy 439.436551 -266.387428)
			(xy 439.620557 -266.452269) (xy 439.801745 -266.52461) (xy 439.979811 -266.604328) (xy 440.154454 -266.69129)
			(xy 440.32538 -266.785349) (xy 440.492299 -266.886345) (xy 440.654932 -266.99411) (xy 440.813003 -267.10846)
			(xy 440.966246 -267.229203) (xy 441.114403 -267.356137) (xy 441.257224 -267.489045) (xy 441.394468 -267.627705)
			(xy 441.525904 -267.771883) (xy 441.651309 -267.921336) (xy 441.770473 -268.07581) (xy 441.883194 -268.235047)
			(xy 441.989283 -268.398778) (xy 442.088561 -268.566725) (xy 442.180859 -268.738608) (xy 442.266024 -268.914134)
			(xy 442.34391 -269.093009) (xy 442.414387 -269.274931) (xy 442.477335 -269.459593) (xy 442.53265 -269.646683)
			(xy 442.580236 -269.835887) (xy 442.620015 -270.026884) (xy 442.651919 -270.219354) (xy 442.675894 -270.412972)
			(xy 442.6919 -270.60741) (xy 442.699909 -270.802342) (xy 442.70041 -270.89989) (xy 442.699909 -270.997438)
			(xy 442.6919 -271.19237) (xy 442.675894 -271.386808) (xy 442.651919 -271.580426) (xy 442.620015 -271.772896)
			(xy 442.580236 -271.963893) (xy 442.53265 -272.153097) (xy 442.477335 -272.340187) (xy 442.414387 -272.524849)
			(xy 442.34391 -272.706771) (xy 442.266024 -272.885646) (xy 442.180859 -273.061172) (xy 442.09302 -273.224752)
			(xy 459.941166 -273.224752) (xy 459.945237 -273.16913) (xy 459.957363 -273.114693) (xy 459.977286 -273.062602)
			(xy 460.004582 -273.013967) (xy 460.038668 -272.969824) (xy 460.078817 -272.931115) (xy 460.124175 -272.898664)
			(xy 460.173775 -272.873163) (xy 460.226559 -272.855156) (xy 460.281402 -272.845026) (xy 460.337136 -272.842989)
			(xy 460.392573 -272.849089) (xy 460.44653 -272.863195) (xy 460.497859 -272.885007) (xy 460.545465 -272.914061)
			(xy 460.588333 -272.949736) (xy 460.62555 -272.991273) (xy 460.656323 -273.037786) (xy 460.679995 -273.088283)
			(xy 460.696063 -273.14169) (xy 460.704183 -273.196866) (xy 460.704692 -273.224752) (xy 460.704183 -273.252638)
			(xy 460.696063 -273.307814) (xy 460.679995 -273.361221) (xy 460.656323 -273.411718) (xy 460.62555 -273.458231)
			(xy 460.588333 -273.499768) (xy 460.545465 -273.535443) (xy 460.497859 -273.564497) (xy 460.44653 -273.586309)
			(xy 460.413936 -273.59483) (xy 463.155028 -273.59483) (xy 463.159099 -273.539208) (xy 463.171225 -273.484771)
			(xy 463.191148 -273.43268) (xy 463.218444 -273.384045) (xy 463.25253 -273.339902) (xy 463.292679 -273.301193)
			(xy 463.338037 -273.268742) (xy 463.387637 -273.243241) (xy 463.440421 -273.225234) (xy 463.495264 -273.215104)
			(xy 463.550998 -273.213067) (xy 463.606435 -273.219167) (xy 463.660392 -273.233273) (xy 463.711721 -273.255085)
			(xy 463.759327 -273.284139) (xy 463.802195 -273.319814) (xy 463.839412 -273.361351) (xy 463.870185 -273.407864)
			(xy 463.893857 -273.458361) (xy 463.909925 -273.511768) (xy 463.918045 -273.566944) (xy 463.918554 -273.59483)
			(xy 463.918045 -273.622716) (xy 463.909925 -273.677892) (xy 463.893857 -273.731299) (xy 463.870185 -273.781796)
			(xy 463.839412 -273.828309) (xy 463.802195 -273.869846) (xy 463.759327 -273.905521) (xy 463.711721 -273.934575)
			(xy 463.660392 -273.956387) (xy 463.606435 -273.970493) (xy 463.550998 -273.976593) (xy 463.495264 -273.974556)
			(xy 463.440421 -273.964426) (xy 463.387637 -273.946419) (xy 463.338037 -273.920918) (xy 463.292679 -273.888467)
			(xy 463.25253 -273.849758) (xy 463.218444 -273.805615) (xy 463.191148 -273.75698) (xy 463.171225 -273.704889)
			(xy 463.159099 -273.650452) (xy 463.155028 -273.59483) (xy 460.413936 -273.59483) (xy 460.392573 -273.600415)
			(xy 460.337136 -273.606515) (xy 460.281402 -273.604478) (xy 460.226559 -273.594348) (xy 460.173775 -273.576341)
			(xy 460.124175 -273.55084) (xy 460.078817 -273.518389) (xy 460.038668 -273.47968) (xy 460.004582 -273.435537)
			(xy 459.977286 -273.386902) (xy 459.957363 -273.334811) (xy 459.945237 -273.280374) (xy 459.941166 -273.224752)
			(xy 442.09302 -273.224752) (xy 442.088561 -273.233055) (xy 441.989283 -273.401002) (xy 441.883194 -273.564733)
			(xy 441.770473 -273.72397) (xy 441.651309 -273.878444) (xy 441.525904 -274.027897) (xy 441.394468 -274.172075)
			(xy 441.257224 -274.310735) (xy 441.114403 -274.443643) (xy 440.966246 -274.570577) (xy 440.813003 -274.69132)
			(xy 440.72343 -274.756118) (xy 457.316076 -274.756118) (xy 457.320147 -274.700496) (xy 457.332273 -274.646059)
			(xy 457.352196 -274.593968) (xy 457.379492 -274.545333) (xy 457.413578 -274.50119) (xy 457.453727 -274.462481)
			(xy 457.499085 -274.43003) (xy 457.548685 -274.404529) (xy 457.601469 -274.386522) (xy 457.656312 -274.376392)
			(xy 457.712046 -274.374355) (xy 457.767483 -274.380455) (xy 457.82144 -274.394561) (xy 457.872769 -274.416373)
			(xy 457.920375 -274.445427) (xy 457.963243 -274.481102) (xy 458.00046 -274.522639) (xy 458.031233 -274.569152)
			(xy 458.054905 -274.619649) (xy 458.070973 -274.673056) (xy 458.079093 -274.728232) (xy 458.079602 -274.756118)
			(xy 458.079093 -274.784004) (xy 458.070973 -274.83918) (xy 458.055232 -274.8915) (xy 459.445866 -274.8915)
			(xy 459.449937 -274.835878) (xy 459.462063 -274.781441) (xy 459.481986 -274.72935) (xy 459.509282 -274.680715)
			(xy 459.543368 -274.636572) (xy 459.583517 -274.597863) (xy 459.628875 -274.565412) (xy 459.678475 -274.539911)
			(xy 459.731259 -274.521904) (xy 459.786102 -274.511774) (xy 459.841836 -274.509737) (xy 459.897273 -274.515837)
			(xy 459.95123 -274.529943) (xy 460.002559 -274.551755) (xy 460.050165 -274.580809) (xy 460.086239 -274.61083)
			(xy 463.093306 -274.61083) (xy 463.097377 -274.555208) (xy 463.109503 -274.500771) (xy 463.129426 -274.44868)
			(xy 463.156722 -274.400045) (xy 463.190808 -274.355902) (xy 463.230957 -274.317193) (xy 463.276315 -274.284742)
			(xy 463.325915 -274.259241) (xy 463.378699 -274.241234) (xy 463.433542 -274.231104) (xy 463.489276 -274.229067)
			(xy 463.544713 -274.235167) (xy 463.59867 -274.249273) (xy 463.649999 -274.271085) (xy 463.697605 -274.300139)
			(xy 463.740473 -274.335814) (xy 463.77769 -274.377351) (xy 463.808463 -274.423864) (xy 463.832135 -274.474361)
			(xy 463.848203 -274.527768) (xy 463.856323 -274.582944) (xy 463.856832 -274.61083) (xy 463.856323 -274.638716)
			(xy 463.848203 -274.693892) (xy 463.832135 -274.747299) (xy 463.808463 -274.797796) (xy 463.77769 -274.844309)
			(xy 463.740473 -274.885846) (xy 463.697605 -274.921521) (xy 463.649999 -274.950575) (xy 463.59867 -274.972387)
			(xy 463.544713 -274.986493) (xy 463.489276 -274.992593) (xy 463.433542 -274.990556) (xy 463.378699 -274.980426)
			(xy 463.325915 -274.962419) (xy 463.276315 -274.936918) (xy 463.230957 -274.904467) (xy 463.190808 -274.865758)
			(xy 463.156722 -274.821615) (xy 463.129426 -274.77298) (xy 463.109503 -274.720889) (xy 463.097377 -274.666452)
			(xy 463.093306 -274.61083) (xy 460.086239 -274.61083) (xy 460.093033 -274.616484) (xy 460.13025 -274.658021)
			(xy 460.161023 -274.704534) (xy 460.184695 -274.755031) (xy 460.200763 -274.808438) (xy 460.208883 -274.863614)
			(xy 460.209392 -274.8915) (xy 460.208883 -274.919386) (xy 460.200763 -274.974562) (xy 460.184695 -275.027969)
			(xy 460.161023 -275.078466) (xy 460.13025 -275.124979) (xy 460.093033 -275.166516) (xy 460.050165 -275.202191)
			(xy 460.002559 -275.231245) (xy 459.95123 -275.253057) (xy 459.897273 -275.267163) (xy 459.841836 -275.273263)
			(xy 459.786102 -275.271226) (xy 459.731259 -275.261096) (xy 459.678475 -275.243089) (xy 459.628875 -275.217588)
			(xy 459.583517 -275.185137) (xy 459.543368 -275.146428) (xy 459.509282 -275.102285) (xy 459.481986 -275.05365)
			(xy 459.462063 -275.001559) (xy 459.449937 -274.947122) (xy 459.445866 -274.8915) (xy 458.055232 -274.8915)
			(xy 458.054905 -274.892587) (xy 458.031233 -274.943084) (xy 458.00046 -274.989597) (xy 457.963243 -275.031134)
			(xy 457.920375 -275.066809) (xy 457.872769 -275.095863) (xy 457.82144 -275.117675) (xy 457.767483 -275.131781)
			(xy 457.712046 -275.137881) (xy 457.656312 -275.135844) (xy 457.601469 -275.125714) (xy 457.548685 -275.107707)
			(xy 457.499085 -275.082206) (xy 457.453727 -275.049755) (xy 457.413578 -275.011046) (xy 457.379492 -274.966903)
			(xy 457.352196 -274.918268) (xy 457.332273 -274.866177) (xy 457.320147 -274.81174) (xy 457.316076 -274.756118)
			(xy 440.72343 -274.756118) (xy 440.654932 -274.80567) (xy 440.492299 -274.913435) (xy 440.32538 -275.014431)
			(xy 440.154454 -275.10849) (xy 439.979811 -275.195452) (xy 439.801745 -275.27517) (xy 439.668473 -275.32838)
			(xy 460.941672 -275.32838) (xy 460.945743 -275.272758) (xy 460.957869 -275.218321) (xy 460.977792 -275.16623)
			(xy 461.005088 -275.117595) (xy 461.039174 -275.073452) (xy 461.079323 -275.034743) (xy 461.124681 -275.002292)
			(xy 461.174281 -274.976791) (xy 461.227065 -274.958784) (xy 461.281908 -274.948654) (xy 461.337642 -274.946617)
			(xy 461.393079 -274.952717) (xy 461.447036 -274.966823) (xy 461.498365 -274.988635) (xy 461.545971 -275.017689)
			(xy 461.588839 -275.053364) (xy 461.626056 -275.094901) (xy 461.656829 -275.141414) (xy 461.680501 -275.191911)
			(xy 461.696569 -275.245318) (xy 461.704689 -275.300494) (xy 461.705198 -275.32838) (xy 461.704689 -275.356266)
			(xy 461.696569 -275.411442) (xy 461.680501 -275.464849) (xy 461.656829 -275.515346) (xy 461.626056 -275.561859)
			(xy 461.588839 -275.603396) (xy 461.56068 -275.62683) (xy 463.093306 -275.62683) (xy 463.097377 -275.571208)
			(xy 463.109503 -275.516771) (xy 463.129426 -275.46468) (xy 463.156722 -275.416045) (xy 463.190808 -275.371902)
			(xy 463.230957 -275.333193) (xy 463.276315 -275.300742) (xy 463.325915 -275.275241) (xy 463.378699 -275.257234)
			(xy 463.433542 -275.247104) (xy 463.489276 -275.245067) (xy 463.544713 -275.251167) (xy 463.59867 -275.265273)
			(xy 463.649999 -275.287085) (xy 463.697605 -275.316139) (xy 463.740473 -275.351814) (xy 463.77769 -275.393351)
			(xy 463.808463 -275.439864) (xy 463.832135 -275.490361) (xy 463.848203 -275.543768) (xy 463.856323 -275.598944)
			(xy 463.856832 -275.62683) (xy 463.856323 -275.654716) (xy 463.848203 -275.709892) (xy 463.832135 -275.763299)
			(xy 463.808463 -275.813796) (xy 463.77769 -275.860309) (xy 463.740473 -275.901846) (xy 463.697605 -275.937521)
			(xy 463.649999 -275.966575) (xy 463.59867 -275.988387) (xy 463.544713 -276.002493) (xy 463.489276 -276.008593)
			(xy 463.433542 -276.006556) (xy 463.378699 -275.996426) (xy 463.325915 -275.978419) (xy 463.276315 -275.952918)
			(xy 463.230957 -275.920467) (xy 463.190808 -275.881758) (xy 463.156722 -275.837615) (xy 463.129426 -275.78898)
			(xy 463.109503 -275.736889) (xy 463.097377 -275.682452) (xy 463.093306 -275.62683) (xy 461.56068 -275.62683)
			(xy 461.545971 -275.639071) (xy 461.498365 -275.668125) (xy 461.447036 -275.689937) (xy 461.393079 -275.704043)
			(xy 461.337642 -275.710143) (xy 461.281908 -275.708106) (xy 461.227065 -275.697976) (xy 461.174281 -275.679969)
			(xy 461.124681 -275.654468) (xy 461.079323 -275.622017) (xy 461.039174 -275.583308) (xy 461.005088 -275.539165)
			(xy 460.977792 -275.49053) (xy 460.957869 -275.438439) (xy 460.945743 -275.384002) (xy 460.941672 -275.32838)
			(xy 439.668473 -275.32838) (xy 439.620557 -275.347511) (xy 439.436551 -275.412352) (xy 439.250038 -275.469584)
			(xy 439.061333 -275.519111) (xy 438.870754 -275.560848) (xy 438.678621 -275.594726) (xy 438.48526 -275.620688)
			(xy 438.290996 -275.638689) (xy 438.096157 -275.6487) (xy 437.901071 -275.650703) (xy 437.706068 -275.644695)
			(xy 437.511475 -275.630686) (xy 437.317622 -275.6087) (xy 437.124835 -275.578774) (xy 436.933438 -275.540958)
			(xy 436.743756 -275.495316) (xy 436.556108 -275.441926) (xy 436.370809 -275.380876) (xy 436.188174 -275.312271)
			(xy 436.008509 -275.236225) (xy 435.832117 -275.152867) (xy 435.659296 -275.062338) (xy 435.490338 -274.96479)
			(xy 435.325527 -274.860387) (xy 435.165141 -274.749307) (xy 435.009451 -274.631735) (xy 434.858719 -274.507871)
			(xy 434.7132 -274.377922) (xy 434.573138 -274.242109) (xy 434.43877 -274.10066) (xy 434.310323 -273.953814)
			(xy 434.188012 -273.801819) (xy 434.072045 -273.64493) (xy 433.962617 -273.483412) (xy 433.859912 -273.317538)
			(xy 433.764104 -273.147587) (xy 433.675353 -272.973846) (xy 433.593811 -272.796608) (xy 433.519614 -272.616172)
			(xy 433.452887 -272.432841) (xy 433.393743 -272.246926) (xy 433.342282 -272.058739) (xy 433.29859 -271.868599)
			(xy 433.262741 -271.676824) (xy 433.234796 -271.48374) (xy 433.214801 -271.289671) (xy 433.202791 -271.094945)
			(xy 433.198785 -270.89989) (xy 407.663396 -270.89989) (xy 407.663396 -271.399) (xy 407.663133 -271.428346)
			(xy 407.659577 -271.486932) (xy 407.656284 -271.516094) (xy 407.65603 -271.518888) (xy 407.65603 -271.790668)
			(xy 407.656373 -271.799403) (xy 407.662241 -271.815857) (xy 407.67333 -271.829354) (xy 407.680668 -271.834102)
			(xy 407.75509 -271.878806) (xy 407.76525 -271.883632) (xy 407.768953 -271.884795) (xy 407.776609 -271.886076)
			(xy 407.78049 -271.886172) (xy 407.793698 -271.886426) (xy 407.805636 -271.880076) (xy 407.827928 -271.868727)
			(xy 407.875293 -271.852646) (xy 407.924644 -271.844493) (xy 407.949654 -271.844008) (xy 407.974913 -271.844497)
			(xy 408.024743 -271.852805) (xy 408.072525 -271.869203) (xy 408.116956 -271.893242) (xy 408.156825 -271.924267)
			(xy 408.191042 -271.961431) (xy 408.218675 -272.003722) (xy 408.238969 -272.049983) (xy 408.251372 -272.098955)
			(xy 408.255544 -272.1493) (xy 408.255522 -272.14957) (xy 409.54377 -272.14957) (xy 409.54773 -272.100516)
			(xy 409.559507 -272.052732) (xy 409.578798 -272.007456) (xy 409.605101 -271.96586) (xy 409.637736 -271.929023)
			(xy 409.675857 -271.897898) (xy 409.718478 -271.873291) (xy 409.764494 -271.855839) (xy 409.812713 -271.845995)
			(xy 409.861888 -271.844014) (xy 409.910743 -271.849946) (xy 409.958014 -271.863638) (xy 410.002476 -271.884736)
			(xy 410.042979 -271.912692) (xy 410.078472 -271.946784) (xy 410.108037 -271.986128) (xy 410.130908 -272.029705)
			(xy 410.146492 -272.076386) (xy 410.154387 -272.124963) (xy 410.154882 -272.14957) (xy 411.443944 -272.14957)
			(xy 411.447904 -272.100516) (xy 411.459681 -272.052732) (xy 411.478972 -272.007456) (xy 411.505275 -271.96586)
			(xy 411.53791 -271.929023) (xy 411.576031 -271.897898) (xy 411.618652 -271.873291) (xy 411.664668 -271.855839)
			(xy 411.712887 -271.845995) (xy 411.762062 -271.844014) (xy 411.810917 -271.849946) (xy 411.858188 -271.863638)
			(xy 411.90265 -271.884736) (xy 411.943153 -271.912692) (xy 411.978646 -271.946784) (xy 412.008211 -271.986128)
			(xy 412.031082 -272.029705) (xy 412.046666 -272.076386) (xy 412.054561 -272.124963) (xy 412.055056 -272.14957)
			(xy 413.343864 -272.14957) (xy 413.347824 -272.100516) (xy 413.359601 -272.052732) (xy 413.378892 -272.007456)
			(xy 413.405195 -271.96586) (xy 413.43783 -271.929023) (xy 413.475951 -271.897898) (xy 413.518572 -271.873291)
			(xy 413.564588 -271.855839) (xy 413.612807 -271.845995) (xy 413.661982 -271.844014) (xy 413.710837 -271.849946)
			(xy 413.758108 -271.863638) (xy 413.80257 -271.884736) (xy 413.843073 -271.912692) (xy 413.878566 -271.946784)
			(xy 413.908131 -271.986128) (xy 413.931002 -272.029705) (xy 413.946586 -272.076386) (xy 413.954481 -272.124963)
			(xy 413.954976 -272.14957) (xy 415.243784 -272.14957) (xy 415.247744 -272.100516) (xy 415.259521 -272.052732)
			(xy 415.278812 -272.007456) (xy 415.305115 -271.96586) (xy 415.33775 -271.929023) (xy 415.375871 -271.897898)
			(xy 415.418492 -271.873291) (xy 415.464508 -271.855839) (xy 415.512727 -271.845995) (xy 415.561902 -271.844014)
			(xy 415.610757 -271.849946) (xy 415.658028 -271.863638) (xy 415.70249 -271.884736) (xy 415.742993 -271.912692)
			(xy 415.778486 -271.946784) (xy 415.808051 -271.986128) (xy 415.830922 -272.029705) (xy 415.846506 -272.076386)
			(xy 415.854401 -272.124963) (xy 415.854896 -272.14957) (xy 417.143958 -272.14957) (xy 417.147918 -272.100516)
			(xy 417.159695 -272.052732) (xy 417.178986 -272.007456) (xy 417.205289 -271.96586) (xy 417.237924 -271.929023)
			(xy 417.276045 -271.897898) (xy 417.318666 -271.873291) (xy 417.364682 -271.855839) (xy 417.412901 -271.845995)
			(xy 417.462076 -271.844014) (xy 417.510931 -271.849946) (xy 417.558202 -271.863638) (xy 417.602664 -271.884736)
			(xy 417.643167 -271.912692) (xy 417.67866 -271.946784) (xy 417.708225 -271.986128) (xy 417.731096 -272.029705)
			(xy 417.74668 -272.076386) (xy 417.754575 -272.124963) (xy 417.75507 -272.14957) (xy 419.043878 -272.14957)
			(xy 419.047838 -272.100516) (xy 419.059615 -272.052732) (xy 419.078906 -272.007456) (xy 419.105209 -271.96586)
			(xy 419.137844 -271.929023) (xy 419.175965 -271.897898) (xy 419.218586 -271.873291) (xy 419.264602 -271.855839)
			(xy 419.312821 -271.845995) (xy 419.361996 -271.844014) (xy 419.410851 -271.849946) (xy 419.458122 -271.863638)
			(xy 419.502584 -271.884736) (xy 419.543087 -271.912692) (xy 419.57858 -271.946784) (xy 419.608145 -271.986128)
			(xy 419.631016 -272.029705) (xy 419.6466 -272.076386) (xy 419.654495 -272.124963) (xy 419.65499 -272.14957)
			(xy 420.943798 -272.14957) (xy 420.947758 -272.100516) (xy 420.959535 -272.052732) (xy 420.978826 -272.007456)
			(xy 421.005129 -271.96586) (xy 421.037764 -271.929023) (xy 421.075885 -271.897898) (xy 421.118506 -271.873291)
			(xy 421.164522 -271.855839) (xy 421.212741 -271.845995) (xy 421.261916 -271.844014) (xy 421.310771 -271.849946)
			(xy 421.358042 -271.863638) (xy 421.402504 -271.884736) (xy 421.443007 -271.912692) (xy 421.4785 -271.946784)
			(xy 421.508065 -271.986128) (xy 421.530936 -272.029705) (xy 421.54652 -272.076386) (xy 421.554415 -272.124963)
			(xy 421.55491 -272.14957) (xy 422.843972 -272.14957) (xy 422.847932 -272.100516) (xy 422.859709 -272.052732)
			(xy 422.879 -272.007456) (xy 422.905303 -271.96586) (xy 422.937938 -271.929023) (xy 422.976059 -271.897898)
			(xy 423.01868 -271.873291) (xy 423.064696 -271.855839) (xy 423.112915 -271.845995) (xy 423.16209 -271.844014)
			(xy 423.210945 -271.849946) (xy 423.258216 -271.863638) (xy 423.302678 -271.884736) (xy 423.343181 -271.912692)
			(xy 423.378674 -271.946784) (xy 423.408239 -271.986128) (xy 423.43111 -272.029705) (xy 423.446694 -272.076386)
			(xy 423.454589 -272.124963) (xy 423.455084 -272.14957) (xy 424.744146 -272.14957) (xy 424.748106 -272.100516)
			(xy 424.759883 -272.052732) (xy 424.779174 -272.007456) (xy 424.805477 -271.96586) (xy 424.838112 -271.929023)
			(xy 424.876233 -271.897898) (xy 424.918854 -271.873291) (xy 424.96487 -271.855839) (xy 425.013089 -271.845995)
			(xy 425.062264 -271.844014) (xy 425.111119 -271.849946) (xy 425.15839 -271.863638) (xy 425.202852 -271.884736)
			(xy 425.243355 -271.912692) (xy 425.278848 -271.946784) (xy 425.308413 -271.986128) (xy 425.331284 -272.029705)
			(xy 425.346868 -272.076386) (xy 425.354763 -272.124963) (xy 425.355258 -272.14957) (xy 426.644066 -272.14957)
			(xy 426.648026 -272.100516) (xy 426.659803 -272.052732) (xy 426.679094 -272.007456) (xy 426.705397 -271.96586)
			(xy 426.738032 -271.929023) (xy 426.776153 -271.897898) (xy 426.818774 -271.873291) (xy 426.86479 -271.855839)
			(xy 426.913009 -271.845995) (xy 426.962184 -271.844014) (xy 427.011039 -271.849946) (xy 427.05831 -271.863638)
			(xy 427.102772 -271.884736) (xy 427.143275 -271.912692) (xy 427.178768 -271.946784) (xy 427.208333 -271.986128)
			(xy 427.231204 -272.029705) (xy 427.246788 -272.076386) (xy 427.254683 -272.124963) (xy 427.255178 -272.14957)
			(xy 428.543986 -272.14957) (xy 428.547946 -272.100516) (xy 428.559723 -272.052732) (xy 428.579014 -272.007456)
			(xy 428.605317 -271.96586) (xy 428.637952 -271.929023) (xy 428.676073 -271.897898) (xy 428.718694 -271.873291)
			(xy 428.76471 -271.855839) (xy 428.812929 -271.845995) (xy 428.862104 -271.844014) (xy 428.910959 -271.849946)
			(xy 428.95823 -271.863638) (xy 429.002692 -271.884736) (xy 429.043195 -271.912692) (xy 429.078688 -271.946784)
			(xy 429.108253 -271.986128) (xy 429.131124 -272.029705) (xy 429.146708 -272.076386) (xy 429.154603 -272.124963)
			(xy 429.155098 -272.14957) (xy 429.154603 -272.174177) (xy 429.146708 -272.222754) (xy 429.131124 -272.269435)
			(xy 429.108253 -272.313012) (xy 429.078688 -272.352356) (xy 429.043195 -272.386448) (xy 429.002692 -272.414404)
			(xy 428.95823 -272.435502) (xy 428.910959 -272.449194) (xy 428.862104 -272.455126) (xy 428.812929 -272.453145)
			(xy 428.76471 -272.443301) (xy 428.718694 -272.425849) (xy 428.676073 -272.401242) (xy 428.637952 -272.370117)
			(xy 428.605317 -272.33328) (xy 428.579014 -272.291684) (xy 428.559723 -272.246408) (xy 428.547946 -272.198624)
			(xy 428.543986 -272.14957) (xy 427.255178 -272.14957) (xy 427.254683 -272.174177) (xy 427.246788 -272.222754)
			(xy 427.231204 -272.269435) (xy 427.208333 -272.313012) (xy 427.178768 -272.352356) (xy 427.143275 -272.386448)
			(xy 427.102772 -272.414404) (xy 427.05831 -272.435502) (xy 427.011039 -272.449194) (xy 426.962184 -272.455126)
			(xy 426.913009 -272.453145) (xy 426.86479 -272.443301) (xy 426.818774 -272.425849) (xy 426.776153 -272.401242)
			(xy 426.738032 -272.370117) (xy 426.705397 -272.33328) (xy 426.679094 -272.291684) (xy 426.659803 -272.246408)
			(xy 426.648026 -272.198624) (xy 426.644066 -272.14957) (xy 425.355258 -272.14957) (xy 425.354763 -272.174177)
			(xy 425.346868 -272.222754) (xy 425.331284 -272.269435) (xy 425.308413 -272.313012) (xy 425.278848 -272.352356)
			(xy 425.243355 -272.386448) (xy 425.202852 -272.414404) (xy 425.15839 -272.435502) (xy 425.111119 -272.449194)
			(xy 425.062264 -272.455126) (xy 425.013089 -272.453145) (xy 424.96487 -272.443301) (xy 424.918854 -272.425849)
			(xy 424.876233 -272.401242) (xy 424.838112 -272.370117) (xy 424.805477 -272.33328) (xy 424.779174 -272.291684)
			(xy 424.759883 -272.246408) (xy 424.748106 -272.198624) (xy 424.744146 -272.14957) (xy 423.455084 -272.14957)
			(xy 423.454589 -272.174177) (xy 423.446694 -272.222754) (xy 423.43111 -272.269435) (xy 423.408239 -272.313012)
			(xy 423.378674 -272.352356) (xy 423.343181 -272.386448) (xy 423.302678 -272.414404) (xy 423.258216 -272.435502)
			(xy 423.210945 -272.449194) (xy 423.16209 -272.455126) (xy 423.112915 -272.453145) (xy 423.064696 -272.443301)
			(xy 423.01868 -272.425849) (xy 422.976059 -272.401242) (xy 422.937938 -272.370117) (xy 422.905303 -272.33328)
			(xy 422.879 -272.291684) (xy 422.859709 -272.246408) (xy 422.847932 -272.198624) (xy 422.843972 -272.14957)
			(xy 421.55491 -272.14957) (xy 421.554415 -272.174177) (xy 421.54652 -272.222754) (xy 421.530936 -272.269435)
			(xy 421.508065 -272.313012) (xy 421.4785 -272.352356) (xy 421.443007 -272.386448) (xy 421.402504 -272.414404)
			(xy 421.358042 -272.435502) (xy 421.310771 -272.449194) (xy 421.261916 -272.455126) (xy 421.212741 -272.453145)
			(xy 421.164522 -272.443301) (xy 421.118506 -272.425849) (xy 421.075885 -272.401242) (xy 421.037764 -272.370117)
			(xy 421.005129 -272.33328) (xy 420.978826 -272.291684) (xy 420.959535 -272.246408) (xy 420.947758 -272.198624)
			(xy 420.943798 -272.14957) (xy 419.65499 -272.14957) (xy 419.654495 -272.174177) (xy 419.6466 -272.222754)
			(xy 419.631016 -272.269435) (xy 419.608145 -272.313012) (xy 419.57858 -272.352356) (xy 419.543087 -272.386448)
			(xy 419.502584 -272.414404) (xy 419.458122 -272.435502) (xy 419.410851 -272.449194) (xy 419.361996 -272.455126)
			(xy 419.312821 -272.453145) (xy 419.264602 -272.443301) (xy 419.218586 -272.425849) (xy 419.175965 -272.401242)
			(xy 419.137844 -272.370117) (xy 419.105209 -272.33328) (xy 419.078906 -272.291684) (xy 419.059615 -272.246408)
			(xy 419.047838 -272.198624) (xy 419.043878 -272.14957) (xy 417.75507 -272.14957) (xy 417.754575 -272.174177)
			(xy 417.74668 -272.222754) (xy 417.731096 -272.269435) (xy 417.708225 -272.313012) (xy 417.67866 -272.352356)
			(xy 417.643167 -272.386448) (xy 417.602664 -272.414404) (xy 417.558202 -272.435502) (xy 417.510931 -272.449194)
			(xy 417.462076 -272.455126) (xy 417.412901 -272.453145) (xy 417.364682 -272.443301) (xy 417.318666 -272.425849)
			(xy 417.276045 -272.401242) (xy 417.237924 -272.370117) (xy 417.205289 -272.33328) (xy 417.178986 -272.291684)
			(xy 417.159695 -272.246408) (xy 417.147918 -272.198624) (xy 417.143958 -272.14957) (xy 415.854896 -272.14957)
			(xy 415.854401 -272.174177) (xy 415.846506 -272.222754) (xy 415.830922 -272.269435) (xy 415.808051 -272.313012)
			(xy 415.778486 -272.352356) (xy 415.742993 -272.386448) (xy 415.70249 -272.414404) (xy 415.658028 -272.435502)
			(xy 415.610757 -272.449194) (xy 415.561902 -272.455126) (xy 415.512727 -272.453145) (xy 415.464508 -272.443301)
			(xy 415.418492 -272.425849) (xy 415.375871 -272.401242) (xy 415.33775 -272.370117) (xy 415.305115 -272.33328)
			(xy 415.278812 -272.291684) (xy 415.259521 -272.246408) (xy 415.247744 -272.198624) (xy 415.243784 -272.14957)
			(xy 413.954976 -272.14957) (xy 413.954481 -272.174177) (xy 413.946586 -272.222754) (xy 413.931002 -272.269435)
			(xy 413.908131 -272.313012) (xy 413.878566 -272.352356) (xy 413.843073 -272.386448) (xy 413.80257 -272.414404)
			(xy 413.758108 -272.435502) (xy 413.710837 -272.449194) (xy 413.661982 -272.455126) (xy 413.612807 -272.453145)
			(xy 413.564588 -272.443301) (xy 413.518572 -272.425849) (xy 413.475951 -272.401242) (xy 413.43783 -272.370117)
			(xy 413.405195 -272.33328) (xy 413.378892 -272.291684) (xy 413.359601 -272.246408) (xy 413.347824 -272.198624)
			(xy 413.343864 -272.14957) (xy 412.055056 -272.14957) (xy 412.054561 -272.174177) (xy 412.046666 -272.222754)
			(xy 412.031082 -272.269435) (xy 412.008211 -272.313012) (xy 411.978646 -272.352356) (xy 411.943153 -272.386448)
			(xy 411.90265 -272.414404) (xy 411.858188 -272.435502) (xy 411.810917 -272.449194) (xy 411.762062 -272.455126)
			(xy 411.712887 -272.453145) (xy 411.664668 -272.443301) (xy 411.618652 -272.425849) (xy 411.576031 -272.401242)
			(xy 411.53791 -272.370117) (xy 411.505275 -272.33328) (xy 411.478972 -272.291684) (xy 411.459681 -272.246408)
			(xy 411.447904 -272.198624) (xy 411.443944 -272.14957) (xy 410.154882 -272.14957) (xy 410.154387 -272.174177)
			(xy 410.146492 -272.222754) (xy 410.130908 -272.269435) (xy 410.108037 -272.313012) (xy 410.078472 -272.352356)
			(xy 410.042979 -272.386448) (xy 410.002476 -272.414404) (xy 409.958014 -272.435502) (xy 409.910743 -272.449194)
			(xy 409.861888 -272.455126) (xy 409.812713 -272.453145) (xy 409.764494 -272.443301) (xy 409.718478 -272.425849)
			(xy 409.675857 -272.401242) (xy 409.637736 -272.370117) (xy 409.605101 -272.33328) (xy 409.578798 -272.291684)
			(xy 409.559507 -272.246408) (xy 409.54773 -272.198624) (xy 409.54377 -272.14957) (xy 408.255522 -272.14957)
			(xy 408.251372 -272.199645) (xy 408.238969 -272.248617) (xy 408.218675 -272.294878) (xy 408.191042 -272.337169)
			(xy 408.156825 -272.374333) (xy 408.116956 -272.405358) (xy 408.072525 -272.429397) (xy 408.024743 -272.445795)
			(xy 407.974913 -272.454103) (xy 407.949654 -272.454624) (xy 407.924646 -272.45412) (xy 407.875298 -272.445966)
			(xy 407.827938 -272.429883) (xy 407.805636 -272.418556) (xy 407.805382 -272.418302) (xy 407.799563 -272.415465)
			(xy 407.786963 -272.412509) (xy 407.78049 -272.41246) (xy 407.767028 -272.412714) (xy 407.680668 -272.46453)
			(xy 407.673391 -272.469345) (xy 407.662347 -272.482839) (xy 407.656445 -272.499247) (xy 407.65603 -272.507964)
			(xy 407.65603 -272.716498) (xy 407.656538 -272.723864) (xy 407.658651 -272.734463) (xy 407.670372 -272.752599)
			(xy 407.679144 -272.758916) (xy 407.679652 -272.759424) (xy 407.68016 -272.759678) (xy 407.753566 -272.80489)
			(xy 407.759262 -272.80822) (xy 407.771874 -272.812077) (xy 407.778458 -272.81251) (xy 407.791158 -272.813018)
			(xy 407.802842 -272.807176) (xy 407.80335 -272.807176) (xy 407.826104 -272.796312) (xy 407.874124 -272.780945)
			(xy 407.923937 -272.773141) (xy 407.949146 -272.772632) (xy 407.949654 -272.772632) (xy 407.975344 -272.773106)
			(xy 408.026092 -272.781137) (xy 408.074958 -272.797009) (xy 408.12074 -272.82033) (xy 408.16231 -272.850527)
			(xy 408.198643 -272.886855) (xy 408.228846 -272.92842) (xy 408.252173 -272.974199) (xy 408.268052 -273.023063)
			(xy 408.27609 -273.07381) (xy 408.27609 -273.099784) (xy 408.594064 -273.099784) (xy 408.598024 -273.05073)
			(xy 408.609801 -273.002946) (xy 408.629092 -272.95767) (xy 408.655395 -272.916074) (xy 408.68803 -272.879237)
			(xy 408.726151 -272.848112) (xy 408.768772 -272.823505) (xy 408.814788 -272.806053) (xy 408.863007 -272.796209)
			(xy 408.912182 -272.794228) (xy 408.961037 -272.80016) (xy 409.008308 -272.813852) (xy 409.05277 -272.83495)
			(xy 409.093273 -272.862906) (xy 409.128766 -272.896998) (xy 409.158331 -272.936342) (xy 409.181202 -272.979919)
			(xy 409.196786 -273.0266) (xy 409.204681 -273.075177) (xy 409.205176 -273.099784) (xy 409.204681 -273.124391)
			(xy 409.204502 -273.125492) (xy 409.522926 -273.125492) (xy 409.522926 -273.074076) (xy 409.530969 -273.023294)
			(xy 409.546857 -272.974395) (xy 409.5702 -272.928583) (xy 409.600421 -272.886987) (xy 409.636777 -272.850631)
			(xy 409.678373 -272.82041) (xy 409.724185 -272.797067) (xy 409.773084 -272.781179) (xy 409.823866 -272.773136)
			(xy 409.875282 -272.773136) (xy 409.926064 -272.781179) (xy 409.974963 -272.797067) (xy 410.020775 -272.82041)
			(xy 410.062371 -272.850631) (xy 410.098727 -272.886987) (xy 410.128948 -272.928583) (xy 410.152291 -272.974395)
			(xy 410.168179 -273.023294) (xy 410.176222 -273.074076) (xy 410.176726 -273.099784) (xy 410.493984 -273.099784)
			(xy 410.497944 -273.05073) (xy 410.509721 -273.002946) (xy 410.529012 -272.95767) (xy 410.555315 -272.916074)
			(xy 410.58795 -272.879237) (xy 410.626071 -272.848112) (xy 410.668692 -272.823505) (xy 410.714708 -272.806053)
			(xy 410.762927 -272.796209) (xy 410.812102 -272.794228) (xy 410.860957 -272.80016) (xy 410.908228 -272.813852)
			(xy 410.95269 -272.83495) (xy 410.993193 -272.862906) (xy 411.028686 -272.896998) (xy 411.058251 -272.936342)
			(xy 411.081122 -272.979919) (xy 411.096706 -273.0266) (xy 411.104601 -273.075177) (xy 411.105096 -273.099784)
			(xy 411.104601 -273.124391) (xy 411.104422 -273.125492) (xy 411.4231 -273.125492) (xy 411.4231 -273.074076)
			(xy 411.431143 -273.023294) (xy 411.447031 -272.974395) (xy 411.470374 -272.928583) (xy 411.500595 -272.886987)
			(xy 411.536951 -272.850631) (xy 411.578547 -272.82041) (xy 411.624359 -272.797067) (xy 411.673258 -272.781179)
			(xy 411.72404 -272.773136) (xy 411.775456 -272.773136) (xy 411.826238 -272.781179) (xy 411.875137 -272.797067)
			(xy 411.920949 -272.82041) (xy 411.962545 -272.850631) (xy 411.998901 -272.886987) (xy 412.029122 -272.928583)
			(xy 412.052465 -272.974395) (xy 412.068353 -273.023294) (xy 412.076396 -273.074076) (xy 412.0769 -273.099784)
			(xy 412.394158 -273.099784) (xy 412.398118 -273.05073) (xy 412.409895 -273.002946) (xy 412.429186 -272.95767)
			(xy 412.455489 -272.916074) (xy 412.488124 -272.879237) (xy 412.526245 -272.848112) (xy 412.568866 -272.823505)
			(xy 412.614882 -272.806053) (xy 412.663101 -272.796209) (xy 412.712276 -272.794228) (xy 412.761131 -272.80016)
			(xy 412.808402 -272.813852) (xy 412.852864 -272.83495) (xy 412.893367 -272.862906) (xy 412.92886 -272.896998)
			(xy 412.958425 -272.936342) (xy 412.981296 -272.979919) (xy 412.99688 -273.0266) (xy 413.004775 -273.075177)
			(xy 413.00527 -273.099784) (xy 413.004775 -273.124391) (xy 413.004596 -273.125492) (xy 413.32302 -273.125492)
			(xy 413.32302 -273.074076) (xy 413.331063 -273.023294) (xy 413.346951 -272.974395) (xy 413.370294 -272.928583)
			(xy 413.400515 -272.886987) (xy 413.436871 -272.850631) (xy 413.478467 -272.82041) (xy 413.524279 -272.797067)
			(xy 413.573178 -272.781179) (xy 413.62396 -272.773136) (xy 413.675376 -272.773136) (xy 413.726158 -272.781179)
			(xy 413.775057 -272.797067) (xy 413.820869 -272.82041) (xy 413.862465 -272.850631) (xy 413.898821 -272.886987)
			(xy 413.929042 -272.928583) (xy 413.952385 -272.974395) (xy 413.968273 -273.023294) (xy 413.976316 -273.074076)
			(xy 413.97682 -273.099784) (xy 414.294078 -273.099784) (xy 414.298038 -273.05073) (xy 414.309815 -273.002946)
			(xy 414.329106 -272.95767) (xy 414.355409 -272.916074) (xy 414.388044 -272.879237) (xy 414.426165 -272.848112)
			(xy 414.468786 -272.823505) (xy 414.514802 -272.806053) (xy 414.563021 -272.796209) (xy 414.612196 -272.794228)
			(xy 414.661051 -272.80016) (xy 414.708322 -272.813852) (xy 414.752784 -272.83495) (xy 414.793287 -272.862906)
			(xy 414.82878 -272.896998) (xy 414.858345 -272.936342) (xy 414.881216 -272.979919) (xy 414.8968 -273.0266)
			(xy 414.904695 -273.075177) (xy 414.90519 -273.099784) (xy 414.904695 -273.124391) (xy 414.904516 -273.125492)
			(xy 415.22294 -273.125492) (xy 415.22294 -273.074076) (xy 415.230983 -273.023294) (xy 415.246871 -272.974395)
			(xy 415.270214 -272.928583) (xy 415.300435 -272.886987) (xy 415.336791 -272.850631) (xy 415.378387 -272.82041)
			(xy 415.424199 -272.797067) (xy 415.473098 -272.781179) (xy 415.52388 -272.773136) (xy 415.575296 -272.773136)
			(xy 415.626078 -272.781179) (xy 415.674977 -272.797067) (xy 415.720789 -272.82041) (xy 415.762385 -272.850631)
			(xy 415.798741 -272.886987) (xy 415.828962 -272.928583) (xy 415.852305 -272.974395) (xy 415.868193 -273.023294)
			(xy 415.876236 -273.074076) (xy 415.87674 -273.099784) (xy 416.193998 -273.099784) (xy 416.197958 -273.05073)
			(xy 416.209735 -273.002946) (xy 416.229026 -272.95767) (xy 416.255329 -272.916074) (xy 416.287964 -272.879237)
			(xy 416.326085 -272.848112) (xy 416.368706 -272.823505) (xy 416.414722 -272.806053) (xy 416.462941 -272.796209)
			(xy 416.512116 -272.794228) (xy 416.560971 -272.80016) (xy 416.608242 -272.813852) (xy 416.652704 -272.83495)
			(xy 416.693207 -272.862906) (xy 416.7287 -272.896998) (xy 416.758265 -272.936342) (xy 416.781136 -272.979919)
			(xy 416.79672 -273.0266) (xy 416.804615 -273.075177) (xy 416.80511 -273.099784) (xy 416.804615 -273.124391)
			(xy 416.804436 -273.125492) (xy 417.123114 -273.125492) (xy 417.123114 -273.074076) (xy 417.131157 -273.023294)
			(xy 417.147045 -272.974395) (xy 417.170388 -272.928583) (xy 417.200609 -272.886987) (xy 417.236965 -272.850631)
			(xy 417.278561 -272.82041) (xy 417.324373 -272.797067) (xy 417.373272 -272.781179) (xy 417.424054 -272.773136)
			(xy 417.47547 -272.773136) (xy 417.526252 -272.781179) (xy 417.575151 -272.797067) (xy 417.620963 -272.82041)
			(xy 417.662559 -272.850631) (xy 417.698915 -272.886987) (xy 417.729136 -272.928583) (xy 417.752479 -272.974395)
			(xy 417.768367 -273.023294) (xy 417.77641 -273.074076) (xy 417.776914 -273.099784) (xy 418.094172 -273.099784)
			(xy 418.098132 -273.05073) (xy 418.109909 -273.002946) (xy 418.1292 -272.95767) (xy 418.155503 -272.916074)
			(xy 418.188138 -272.879237) (xy 418.226259 -272.848112) (xy 418.26888 -272.823505) (xy 418.314896 -272.806053)
			(xy 418.363115 -272.796209) (xy 418.41229 -272.794228) (xy 418.461145 -272.80016) (xy 418.508416 -272.813852)
			(xy 418.552878 -272.83495) (xy 418.593381 -272.862906) (xy 418.628874 -272.896998) (xy 418.658439 -272.936342)
			(xy 418.68131 -272.979919) (xy 418.696894 -273.0266) (xy 418.704789 -273.075177) (xy 418.705284 -273.099784)
			(xy 418.704789 -273.124391) (xy 418.70461 -273.125492) (xy 419.023034 -273.125492) (xy 419.023034 -273.074076)
			(xy 419.031077 -273.023294) (xy 419.046965 -272.974395) (xy 419.070308 -272.928583) (xy 419.100529 -272.886987)
			(xy 419.136885 -272.850631) (xy 419.178481 -272.82041) (xy 419.224293 -272.797067) (xy 419.273192 -272.781179)
			(xy 419.323974 -272.773136) (xy 419.37539 -272.773136) (xy 419.426172 -272.781179) (xy 419.475071 -272.797067)
			(xy 419.520883 -272.82041) (xy 419.562479 -272.850631) (xy 419.598835 -272.886987) (xy 419.629056 -272.928583)
			(xy 419.652399 -272.974395) (xy 419.668287 -273.023294) (xy 419.67633 -273.074076) (xy 419.676834 -273.099784)
			(xy 419.994092 -273.099784) (xy 419.998052 -273.05073) (xy 420.009829 -273.002946) (xy 420.02912 -272.95767)
			(xy 420.055423 -272.916074) (xy 420.088058 -272.879237) (xy 420.126179 -272.848112) (xy 420.1688 -272.823505)
			(xy 420.214816 -272.806053) (xy 420.263035 -272.796209) (xy 420.31221 -272.794228) (xy 420.361065 -272.80016)
			(xy 420.408336 -272.813852) (xy 420.452798 -272.83495) (xy 420.493301 -272.862906) (xy 420.528794 -272.896998)
			(xy 420.558359 -272.936342) (xy 420.58123 -272.979919) (xy 420.596814 -273.0266) (xy 420.604709 -273.075177)
			(xy 420.605204 -273.099784) (xy 420.604709 -273.124391) (xy 420.60453 -273.125492) (xy 420.922954 -273.125492)
			(xy 420.922954 -273.074076) (xy 420.930997 -273.023294) (xy 420.946885 -272.974395) (xy 420.970228 -272.928583)
			(xy 421.000449 -272.886987) (xy 421.036805 -272.850631) (xy 421.078401 -272.82041) (xy 421.124213 -272.797067)
			(xy 421.173112 -272.781179) (xy 421.223894 -272.773136) (xy 421.27531 -272.773136) (xy 421.326092 -272.781179)
			(xy 421.374991 -272.797067) (xy 421.420803 -272.82041) (xy 421.462399 -272.850631) (xy 421.498755 -272.886987)
			(xy 421.528976 -272.928583) (xy 421.552319 -272.974395) (xy 421.568207 -273.023294) (xy 421.57625 -273.074076)
			(xy 421.576754 -273.099784) (xy 421.894012 -273.099784) (xy 421.897972 -273.05073) (xy 421.909749 -273.002946)
			(xy 421.92904 -272.95767) (xy 421.955343 -272.916074) (xy 421.987978 -272.879237) (xy 422.026099 -272.848112)
			(xy 422.06872 -272.823505) (xy 422.114736 -272.806053) (xy 422.162955 -272.796209) (xy 422.21213 -272.794228)
			(xy 422.260985 -272.80016) (xy 422.308256 -272.813852) (xy 422.352718 -272.83495) (xy 422.393221 -272.862906)
			(xy 422.428714 -272.896998) (xy 422.458279 -272.936342) (xy 422.48115 -272.979919) (xy 422.496734 -273.0266)
			(xy 422.504629 -273.075177) (xy 422.505124 -273.099784) (xy 422.504629 -273.124391) (xy 422.50445 -273.125492)
			(xy 422.823128 -273.125492) (xy 422.823128 -273.074076) (xy 422.831171 -273.023294) (xy 422.847059 -272.974395)
			(xy 422.870402 -272.928583) (xy 422.900623 -272.886987) (xy 422.936979 -272.850631) (xy 422.978575 -272.82041)
			(xy 423.024387 -272.797067) (xy 423.073286 -272.781179) (xy 423.124068 -272.773136) (xy 423.175484 -272.773136)
			(xy 423.226266 -272.781179) (xy 423.275165 -272.797067) (xy 423.320977 -272.82041) (xy 423.362573 -272.850631)
			(xy 423.398929 -272.886987) (xy 423.42915 -272.928583) (xy 423.452493 -272.974395) (xy 423.468381 -273.023294)
			(xy 423.476424 -273.074076) (xy 423.476928 -273.099784) (xy 423.794186 -273.099784) (xy 423.798146 -273.05073)
			(xy 423.809923 -273.002946) (xy 423.829214 -272.95767) (xy 423.855517 -272.916074) (xy 423.888152 -272.879237)
			(xy 423.926273 -272.848112) (xy 423.968894 -272.823505) (xy 424.01491 -272.806053) (xy 424.063129 -272.796209)
			(xy 424.112304 -272.794228) (xy 424.161159 -272.80016) (xy 424.20843 -272.813852) (xy 424.252892 -272.83495)
			(xy 424.293395 -272.862906) (xy 424.328888 -272.896998) (xy 424.358453 -272.936342) (xy 424.381324 -272.979919)
			(xy 424.396908 -273.0266) (xy 424.404803 -273.075177) (xy 424.405298 -273.099784) (xy 424.404803 -273.124391)
			(xy 424.404624 -273.125492) (xy 424.723048 -273.125492) (xy 424.723048 -273.074076) (xy 424.731091 -273.023294)
			(xy 424.746979 -272.974395) (xy 424.770322 -272.928583) (xy 424.800543 -272.886987) (xy 424.836899 -272.850631)
			(xy 424.878495 -272.82041) (xy 424.924307 -272.797067) (xy 424.973206 -272.781179) (xy 425.023988 -272.773136)
			(xy 425.075404 -272.773136) (xy 425.126186 -272.781179) (xy 425.175085 -272.797067) (xy 425.220897 -272.82041)
			(xy 425.262493 -272.850631) (xy 425.298849 -272.886987) (xy 425.32907 -272.928583) (xy 425.352413 -272.974395)
			(xy 425.368301 -273.023294) (xy 425.376344 -273.074076) (xy 425.376848 -273.099784) (xy 425.69436 -273.099784)
			(xy 425.69832 -273.05073) (xy 425.710097 -273.002946) (xy 425.729388 -272.95767) (xy 425.755691 -272.916074)
			(xy 425.788326 -272.879237) (xy 425.826447 -272.848112) (xy 425.869068 -272.823505) (xy 425.915084 -272.806053)
			(xy 425.963303 -272.796209) (xy 426.012478 -272.794228) (xy 426.061333 -272.80016) (xy 426.108604 -272.813852)
			(xy 426.153066 -272.83495) (xy 426.193569 -272.862906) (xy 426.229062 -272.896998) (xy 426.258627 -272.936342)
			(xy 426.281498 -272.979919) (xy 426.297082 -273.0266) (xy 426.304977 -273.075177) (xy 426.305472 -273.099784)
			(xy 426.304977 -273.124391) (xy 426.304798 -273.125492) (xy 426.622968 -273.125492) (xy 426.622968 -273.074076)
			(xy 426.631011 -273.023294) (xy 426.646899 -272.974395) (xy 426.670242 -272.928583) (xy 426.700463 -272.886987)
			(xy 426.736819 -272.850631) (xy 426.778415 -272.82041) (xy 426.824227 -272.797067) (xy 426.873126 -272.781179)
			(xy 426.923908 -272.773136) (xy 426.975324 -272.773136) (xy 427.026106 -272.781179) (xy 427.075005 -272.797067)
			(xy 427.120817 -272.82041) (xy 427.162413 -272.850631) (xy 427.198769 -272.886987) (xy 427.22899 -272.928583)
			(xy 427.252333 -272.974395) (xy 427.268221 -273.023294) (xy 427.276264 -273.074076) (xy 427.276768 -273.099784)
			(xy 427.59428 -273.099784) (xy 427.59824 -273.05073) (xy 427.610017 -273.002946) (xy 427.629308 -272.95767)
			(xy 427.655611 -272.916074) (xy 427.688246 -272.879237) (xy 427.726367 -272.848112) (xy 427.768988 -272.823505)
			(xy 427.815004 -272.806053) (xy 427.863223 -272.796209) (xy 427.912398 -272.794228) (xy 427.961253 -272.80016)
			(xy 428.008524 -272.813852) (xy 428.052986 -272.83495) (xy 428.093489 -272.862906) (xy 428.128982 -272.896998)
			(xy 428.158547 -272.936342) (xy 428.181418 -272.979919) (xy 428.197002 -273.0266) (xy 428.204897 -273.075177)
			(xy 428.205392 -273.099784) (xy 428.204897 -273.124391) (xy 428.204718 -273.125492) (xy 428.522888 -273.125492)
			(xy 428.522888 -273.074076) (xy 428.530931 -273.023294) (xy 428.546819 -272.974395) (xy 428.570162 -272.928583)
			(xy 428.600383 -272.886987) (xy 428.636739 -272.850631) (xy 428.678335 -272.82041) (xy 428.724147 -272.797067)
			(xy 428.773046 -272.781179) (xy 428.823828 -272.773136) (xy 428.875244 -272.773136) (xy 428.926026 -272.781179)
			(xy 428.974925 -272.797067) (xy 429.020737 -272.82041) (xy 429.062333 -272.850631) (xy 429.098689 -272.886987)
			(xy 429.12891 -272.928583) (xy 429.152253 -272.974395) (xy 429.168141 -273.023294) (xy 429.176184 -273.074076)
			(xy 429.176688 -273.099784) (xy 429.4942 -273.099784) (xy 429.49816 -273.05073) (xy 429.509937 -273.002946)
			(xy 429.529228 -272.95767) (xy 429.555531 -272.916074) (xy 429.588166 -272.879237) (xy 429.626287 -272.848112)
			(xy 429.668908 -272.823505) (xy 429.714924 -272.806053) (xy 429.763143 -272.796209) (xy 429.812318 -272.794228)
			(xy 429.861173 -272.80016) (xy 429.908444 -272.813852) (xy 429.952906 -272.83495) (xy 429.993409 -272.862906)
			(xy 430.028902 -272.896998) (xy 430.058467 -272.936342) (xy 430.081338 -272.979919) (xy 430.096922 -273.0266)
			(xy 430.104817 -273.075177) (xy 430.105312 -273.099784) (xy 430.104817 -273.124391) (xy 430.096922 -273.172968)
			(xy 430.081338 -273.219649) (xy 430.058467 -273.263226) (xy 430.028902 -273.30257) (xy 429.993409 -273.336662)
			(xy 429.952906 -273.364618) (xy 429.908444 -273.385716) (xy 429.861173 -273.399408) (xy 429.812318 -273.40534)
			(xy 429.763143 -273.403359) (xy 429.714924 -273.393515) (xy 429.668908 -273.376063) (xy 429.626287 -273.351456)
			(xy 429.588166 -273.320331) (xy 429.555531 -273.283494) (xy 429.529228 -273.241898) (xy 429.509937 -273.196622)
			(xy 429.49816 -273.148838) (xy 429.4942 -273.099784) (xy 429.176688 -273.099784) (xy 429.176184 -273.125492)
			(xy 429.168141 -273.176274) (xy 429.152253 -273.225173) (xy 429.12891 -273.270985) (xy 429.098689 -273.312581)
			(xy 429.062333 -273.348937) (xy 429.020737 -273.379158) (xy 428.974925 -273.402501) (xy 428.926026 -273.418389)
			(xy 428.875244 -273.426432) (xy 428.823828 -273.426432) (xy 428.773046 -273.418389) (xy 428.724147 -273.402501)
			(xy 428.678335 -273.379158) (xy 428.636739 -273.348937) (xy 428.600383 -273.312581) (xy 428.570162 -273.270985)
			(xy 428.546819 -273.225173) (xy 428.530931 -273.176274) (xy 428.522888 -273.125492) (xy 428.204718 -273.125492)
			(xy 428.197002 -273.172968) (xy 428.181418 -273.219649) (xy 428.158547 -273.263226) (xy 428.128982 -273.30257)
			(xy 428.093489 -273.336662) (xy 428.052986 -273.364618) (xy 428.008524 -273.385716) (xy 427.961253 -273.399408)
			(xy 427.912398 -273.40534) (xy 427.863223 -273.403359) (xy 427.815004 -273.393515) (xy 427.768988 -273.376063)
			(xy 427.726367 -273.351456) (xy 427.688246 -273.320331) (xy 427.655611 -273.283494) (xy 427.629308 -273.241898)
			(xy 427.610017 -273.196622) (xy 427.59824 -273.148838) (xy 427.59428 -273.099784) (xy 427.276768 -273.099784)
			(xy 427.276264 -273.125492) (xy 427.268221 -273.176274) (xy 427.252333 -273.225173) (xy 427.22899 -273.270985)
			(xy 427.198769 -273.312581) (xy 427.162413 -273.348937) (xy 427.120817 -273.379158) (xy 427.075005 -273.402501)
			(xy 427.026106 -273.418389) (xy 426.975324 -273.426432) (xy 426.923908 -273.426432) (xy 426.873126 -273.418389)
			(xy 426.824227 -273.402501) (xy 426.778415 -273.379158) (xy 426.736819 -273.348937) (xy 426.700463 -273.312581)
			(xy 426.670242 -273.270985) (xy 426.646899 -273.225173) (xy 426.631011 -273.176274) (xy 426.622968 -273.125492)
			(xy 426.304798 -273.125492) (xy 426.297082 -273.172968) (xy 426.281498 -273.219649) (xy 426.258627 -273.263226)
			(xy 426.229062 -273.30257) (xy 426.193569 -273.336662) (xy 426.153066 -273.364618) (xy 426.108604 -273.385716)
			(xy 426.061333 -273.399408) (xy 426.012478 -273.40534) (xy 425.963303 -273.403359) (xy 425.915084 -273.393515)
			(xy 425.869068 -273.376063) (xy 425.826447 -273.351456) (xy 425.788326 -273.320331) (xy 425.755691 -273.283494)
			(xy 425.729388 -273.241898) (xy 425.710097 -273.196622) (xy 425.69832 -273.148838) (xy 425.69436 -273.099784)
			(xy 425.376848 -273.099784) (xy 425.376344 -273.125492) (xy 425.368301 -273.176274) (xy 425.352413 -273.225173)
			(xy 425.32907 -273.270985) (xy 425.298849 -273.312581) (xy 425.262493 -273.348937) (xy 425.220897 -273.379158)
			(xy 425.175085 -273.402501) (xy 425.126186 -273.418389) (xy 425.075404 -273.426432) (xy 425.023988 -273.426432)
			(xy 424.973206 -273.418389) (xy 424.924307 -273.402501) (xy 424.878495 -273.379158) (xy 424.836899 -273.348937)
			(xy 424.800543 -273.312581) (xy 424.770322 -273.270985) (xy 424.746979 -273.225173) (xy 424.731091 -273.176274)
			(xy 424.723048 -273.125492) (xy 424.404624 -273.125492) (xy 424.396908 -273.172968) (xy 424.381324 -273.219649)
			(xy 424.358453 -273.263226) (xy 424.328888 -273.30257) (xy 424.293395 -273.336662) (xy 424.252892 -273.364618)
			(xy 424.20843 -273.385716) (xy 424.161159 -273.399408) (xy 424.112304 -273.40534) (xy 424.063129 -273.403359)
			(xy 424.01491 -273.393515) (xy 423.968894 -273.376063) (xy 423.926273 -273.351456) (xy 423.888152 -273.320331)
			(xy 423.855517 -273.283494) (xy 423.829214 -273.241898) (xy 423.809923 -273.196622) (xy 423.798146 -273.148838)
			(xy 423.794186 -273.099784) (xy 423.476928 -273.099784) (xy 423.476424 -273.125492) (xy 423.468381 -273.176274)
			(xy 423.452493 -273.225173) (xy 423.42915 -273.270985) (xy 423.398929 -273.312581) (xy 423.362573 -273.348937)
			(xy 423.320977 -273.379158) (xy 423.275165 -273.402501) (xy 423.226266 -273.418389) (xy 423.175484 -273.426432)
			(xy 423.124068 -273.426432) (xy 423.073286 -273.418389) (xy 423.024387 -273.402501) (xy 422.978575 -273.379158)
			(xy 422.936979 -273.348937) (xy 422.900623 -273.312581) (xy 422.870402 -273.270985) (xy 422.847059 -273.225173)
			(xy 422.831171 -273.176274) (xy 422.823128 -273.125492) (xy 422.50445 -273.125492) (xy 422.496734 -273.172968)
			(xy 422.48115 -273.219649) (xy 422.458279 -273.263226) (xy 422.428714 -273.30257) (xy 422.393221 -273.336662)
			(xy 422.352718 -273.364618) (xy 422.308256 -273.385716) (xy 422.260985 -273.399408) (xy 422.21213 -273.40534)
			(xy 422.162955 -273.403359) (xy 422.114736 -273.393515) (xy 422.06872 -273.376063) (xy 422.026099 -273.351456)
			(xy 421.987978 -273.320331) (xy 421.955343 -273.283494) (xy 421.92904 -273.241898) (xy 421.909749 -273.196622)
			(xy 421.897972 -273.148838) (xy 421.894012 -273.099784) (xy 421.576754 -273.099784) (xy 421.57625 -273.125492)
			(xy 421.568207 -273.176274) (xy 421.552319 -273.225173) (xy 421.528976 -273.270985) (xy 421.498755 -273.312581)
			(xy 421.462399 -273.348937) (xy 421.420803 -273.379158) (xy 421.374991 -273.402501) (xy 421.326092 -273.418389)
			(xy 421.27531 -273.426432) (xy 421.223894 -273.426432) (xy 421.173112 -273.418389) (xy 421.124213 -273.402501)
			(xy 421.078401 -273.379158) (xy 421.036805 -273.348937) (xy 421.000449 -273.312581) (xy 420.970228 -273.270985)
			(xy 420.946885 -273.225173) (xy 420.930997 -273.176274) (xy 420.922954 -273.125492) (xy 420.60453 -273.125492)
			(xy 420.596814 -273.172968) (xy 420.58123 -273.219649) (xy 420.558359 -273.263226) (xy 420.528794 -273.30257)
			(xy 420.493301 -273.336662) (xy 420.452798 -273.364618) (xy 420.408336 -273.385716) (xy 420.361065 -273.399408)
			(xy 420.31221 -273.40534) (xy 420.263035 -273.403359) (xy 420.214816 -273.393515) (xy 420.1688 -273.376063)
			(xy 420.126179 -273.351456) (xy 420.088058 -273.320331) (xy 420.055423 -273.283494) (xy 420.02912 -273.241898)
			(xy 420.009829 -273.196622) (xy 419.998052 -273.148838) (xy 419.994092 -273.099784) (xy 419.676834 -273.099784)
			(xy 419.67633 -273.125492) (xy 419.668287 -273.176274) (xy 419.652399 -273.225173) (xy 419.629056 -273.270985)
			(xy 419.598835 -273.312581) (xy 419.562479 -273.348937) (xy 419.520883 -273.379158) (xy 419.475071 -273.402501)
			(xy 419.426172 -273.418389) (xy 419.37539 -273.426432) (xy 419.323974 -273.426432) (xy 419.273192 -273.418389)
			(xy 419.224293 -273.402501) (xy 419.178481 -273.379158) (xy 419.136885 -273.348937) (xy 419.100529 -273.312581)
			(xy 419.070308 -273.270985) (xy 419.046965 -273.225173) (xy 419.031077 -273.176274) (xy 419.023034 -273.125492)
			(xy 418.70461 -273.125492) (xy 418.696894 -273.172968) (xy 418.68131 -273.219649) (xy 418.658439 -273.263226)
			(xy 418.628874 -273.30257) (xy 418.593381 -273.336662) (xy 418.552878 -273.364618) (xy 418.508416 -273.385716)
			(xy 418.461145 -273.399408) (xy 418.41229 -273.40534) (xy 418.363115 -273.403359) (xy 418.314896 -273.393515)
			(xy 418.26888 -273.376063) (xy 418.226259 -273.351456) (xy 418.188138 -273.320331) (xy 418.155503 -273.283494)
			(xy 418.1292 -273.241898) (xy 418.109909 -273.196622) (xy 418.098132 -273.148838) (xy 418.094172 -273.099784)
			(xy 417.776914 -273.099784) (xy 417.77641 -273.125492) (xy 417.768367 -273.176274) (xy 417.752479 -273.225173)
			(xy 417.729136 -273.270985) (xy 417.698915 -273.312581) (xy 417.662559 -273.348937) (xy 417.620963 -273.379158)
			(xy 417.575151 -273.402501) (xy 417.526252 -273.418389) (xy 417.47547 -273.426432) (xy 417.424054 -273.426432)
			(xy 417.373272 -273.418389) (xy 417.324373 -273.402501) (xy 417.278561 -273.379158) (xy 417.236965 -273.348937)
			(xy 417.200609 -273.312581) (xy 417.170388 -273.270985) (xy 417.147045 -273.225173) (xy 417.131157 -273.176274)
			(xy 417.123114 -273.125492) (xy 416.804436 -273.125492) (xy 416.79672 -273.172968) (xy 416.781136 -273.219649)
			(xy 416.758265 -273.263226) (xy 416.7287 -273.30257) (xy 416.693207 -273.336662) (xy 416.652704 -273.364618)
			(xy 416.608242 -273.385716) (xy 416.560971 -273.399408) (xy 416.512116 -273.40534) (xy 416.462941 -273.403359)
			(xy 416.414722 -273.393515) (xy 416.368706 -273.376063) (xy 416.326085 -273.351456) (xy 416.287964 -273.320331)
			(xy 416.255329 -273.283494) (xy 416.229026 -273.241898) (xy 416.209735 -273.196622) (xy 416.197958 -273.148838)
			(xy 416.193998 -273.099784) (xy 415.87674 -273.099784) (xy 415.876236 -273.125492) (xy 415.868193 -273.176274)
			(xy 415.852305 -273.225173) (xy 415.828962 -273.270985) (xy 415.798741 -273.312581) (xy 415.762385 -273.348937)
			(xy 415.720789 -273.379158) (xy 415.674977 -273.402501) (xy 415.626078 -273.418389) (xy 415.575296 -273.426432)
			(xy 415.52388 -273.426432) (xy 415.473098 -273.418389) (xy 415.424199 -273.402501) (xy 415.378387 -273.379158)
			(xy 415.336791 -273.348937) (xy 415.300435 -273.312581) (xy 415.270214 -273.270985) (xy 415.246871 -273.225173)
			(xy 415.230983 -273.176274) (xy 415.22294 -273.125492) (xy 414.904516 -273.125492) (xy 414.8968 -273.172968)
			(xy 414.881216 -273.219649) (xy 414.858345 -273.263226) (xy 414.82878 -273.30257) (xy 414.793287 -273.336662)
			(xy 414.752784 -273.364618) (xy 414.708322 -273.385716) (xy 414.661051 -273.399408) (xy 414.612196 -273.40534)
			(xy 414.563021 -273.403359) (xy 414.514802 -273.393515) (xy 414.468786 -273.376063) (xy 414.426165 -273.351456)
			(xy 414.388044 -273.320331) (xy 414.355409 -273.283494) (xy 414.329106 -273.241898) (xy 414.309815 -273.196622)
			(xy 414.298038 -273.148838) (xy 414.294078 -273.099784) (xy 413.97682 -273.099784) (xy 413.976316 -273.125492)
			(xy 413.968273 -273.176274) (xy 413.952385 -273.225173) (xy 413.929042 -273.270985) (xy 413.898821 -273.312581)
			(xy 413.862465 -273.348937) (xy 413.820869 -273.379158) (xy 413.775057 -273.402501) (xy 413.726158 -273.418389)
			(xy 413.675376 -273.426432) (xy 413.62396 -273.426432) (xy 413.573178 -273.418389) (xy 413.524279 -273.402501)
			(xy 413.478467 -273.379158) (xy 413.436871 -273.348937) (xy 413.400515 -273.312581) (xy 413.370294 -273.270985)
			(xy 413.346951 -273.225173) (xy 413.331063 -273.176274) (xy 413.32302 -273.125492) (xy 413.004596 -273.125492)
			(xy 412.99688 -273.172968) (xy 412.981296 -273.219649) (xy 412.958425 -273.263226) (xy 412.92886 -273.30257)
			(xy 412.893367 -273.336662) (xy 412.852864 -273.364618) (xy 412.808402 -273.385716) (xy 412.761131 -273.399408)
			(xy 412.712276 -273.40534) (xy 412.663101 -273.403359) (xy 412.614882 -273.393515) (xy 412.568866 -273.376063)
			(xy 412.526245 -273.351456) (xy 412.488124 -273.320331) (xy 412.455489 -273.283494) (xy 412.429186 -273.241898)
			(xy 412.409895 -273.196622) (xy 412.398118 -273.148838) (xy 412.394158 -273.099784) (xy 412.0769 -273.099784)
			(xy 412.076396 -273.125492) (xy 412.068353 -273.176274) (xy 412.052465 -273.225173) (xy 412.029122 -273.270985)
			(xy 411.998901 -273.312581) (xy 411.962545 -273.348937) (xy 411.920949 -273.379158) (xy 411.875137 -273.402501)
			(xy 411.826238 -273.418389) (xy 411.775456 -273.426432) (xy 411.72404 -273.426432) (xy 411.673258 -273.418389)
			(xy 411.624359 -273.402501) (xy 411.578547 -273.379158) (xy 411.536951 -273.348937) (xy 411.500595 -273.312581)
			(xy 411.470374 -273.270985) (xy 411.447031 -273.225173) (xy 411.431143 -273.176274) (xy 411.4231 -273.125492)
			(xy 411.104422 -273.125492) (xy 411.096706 -273.172968) (xy 411.081122 -273.219649) (xy 411.058251 -273.263226)
			(xy 411.028686 -273.30257) (xy 410.993193 -273.336662) (xy 410.95269 -273.364618) (xy 410.908228 -273.385716)
			(xy 410.860957 -273.399408) (xy 410.812102 -273.40534) (xy 410.762927 -273.403359) (xy 410.714708 -273.393515)
			(xy 410.668692 -273.376063) (xy 410.626071 -273.351456) (xy 410.58795 -273.320331) (xy 410.555315 -273.283494)
			(xy 410.529012 -273.241898) (xy 410.509721 -273.196622) (xy 410.497944 -273.148838) (xy 410.493984 -273.099784)
			(xy 410.176726 -273.099784) (xy 410.176222 -273.125492) (xy 410.168179 -273.176274) (xy 410.152291 -273.225173)
			(xy 410.128948 -273.270985) (xy 410.098727 -273.312581) (xy 410.062371 -273.348937) (xy 410.020775 -273.379158)
			(xy 409.974963 -273.402501) (xy 409.926064 -273.418389) (xy 409.875282 -273.426432) (xy 409.823866 -273.426432)
			(xy 409.773084 -273.418389) (xy 409.724185 -273.402501) (xy 409.678373 -273.379158) (xy 409.636777 -273.348937)
			(xy 409.600421 -273.312581) (xy 409.5702 -273.270985) (xy 409.546857 -273.225173) (xy 409.530969 -273.176274)
			(xy 409.522926 -273.125492) (xy 409.204502 -273.125492) (xy 409.196786 -273.172968) (xy 409.181202 -273.219649)
			(xy 409.158331 -273.263226) (xy 409.128766 -273.30257) (xy 409.093273 -273.336662) (xy 409.05277 -273.364618)
			(xy 409.008308 -273.385716) (xy 408.961037 -273.399408) (xy 408.912182 -273.40534) (xy 408.863007 -273.403359)
			(xy 408.814788 -273.393515) (xy 408.768772 -273.376063) (xy 408.726151 -273.351456) (xy 408.68803 -273.320331)
			(xy 408.655395 -273.283494) (xy 408.629092 -273.241898) (xy 408.609801 -273.196622) (xy 408.598024 -273.148838)
			(xy 408.594064 -273.099784) (xy 408.27609 -273.099784) (xy 408.27609 -273.12519) (xy 408.268052 -273.175937)
			(xy 408.252173 -273.224801) (xy 408.228846 -273.27058) (xy 408.198643 -273.312145) (xy 408.16231 -273.348473)
			(xy 408.12074 -273.37867) (xy 408.074958 -273.401991) (xy 408.026092 -273.417863) (xy 407.975344 -273.425894)
			(xy 407.949654 -273.426428) (xy 407.949146 -273.426428) (xy 407.923937 -273.425921) (xy 407.874127 -273.418105)
			(xy 407.826105 -273.402744) (xy 407.80335 -273.391884) (xy 407.802842 -273.391884) (xy 407.802588 -273.39163)
			(xy 407.79689 -273.389102) (xy 407.784693 -273.386543) (xy 407.778458 -273.38655) (xy 407.764996 -273.387058)
			(xy 407.68016 -273.439382) (xy 407.679652 -273.439636) (xy 407.679144 -273.440144) (xy 407.670348 -273.446434)
			(xy 407.658638 -273.464589) (xy 407.656538 -273.475196) (xy 407.65603 -273.482562) (xy 407.65603 -273.666458)
			(xy 407.656538 -273.673824) (xy 407.658644 -273.684428) (xy 407.670357 -273.702576) (xy 407.679144 -273.708876)
			(xy 407.679652 -273.709384) (xy 407.68016 -273.709638) (xy 407.753566 -273.75485) (xy 407.759261 -273.758182)
			(xy 407.771874 -273.762042) (xy 407.778458 -273.76247) (xy 407.791158 -273.762978) (xy 407.802842 -273.757136)
			(xy 407.80335 -273.757136) (xy 407.826103 -273.74627) (xy 407.874124 -273.7309) (xy 407.923936 -273.723095)
			(xy 407.949146 -273.722592) (xy 407.949654 -273.722592) (xy 407.975347 -273.723066) (xy 408.026101 -273.731098)
			(xy 408.074974 -273.746972) (xy 408.120761 -273.770296) (xy 408.162336 -273.800496) (xy 408.198674 -273.836829)
			(xy 408.22888 -273.878399) (xy 408.252211 -273.924183) (xy 408.268091 -273.973054) (xy 408.27613 -274.023807)
			(xy 408.27613 -274.049744) (xy 408.594064 -274.049744) (xy 408.598024 -274.00069) (xy 408.609801 -273.952906)
			(xy 408.629092 -273.90763) (xy 408.655395 -273.866034) (xy 408.68803 -273.829197) (xy 408.726151 -273.798072)
			(xy 408.768772 -273.773465) (xy 408.814788 -273.756013) (xy 408.863007 -273.746169) (xy 408.912182 -273.744188)
			(xy 408.961037 -273.75012) (xy 409.008308 -273.763812) (xy 409.05277 -273.78491) (xy 409.093273 -273.812866)
			(xy 409.128766 -273.846958) (xy 409.158331 -273.886302) (xy 409.181202 -273.929879) (xy 409.196786 -273.97656)
			(xy 409.204681 -274.025137) (xy 409.205176 -274.049744) (xy 409.204681 -274.074351) (xy 409.204502 -274.075452)
			(xy 409.522926 -274.075452) (xy 409.522926 -274.024036) (xy 409.530969 -273.973254) (xy 409.546857 -273.924355)
			(xy 409.5702 -273.878543) (xy 409.600421 -273.836947) (xy 409.636777 -273.800591) (xy 409.678373 -273.77037)
			(xy 409.724185 -273.747027) (xy 409.773084 -273.731139) (xy 409.823866 -273.723096) (xy 409.875282 -273.723096)
			(xy 409.926064 -273.731139) (xy 409.974963 -273.747027) (xy 410.020775 -273.77037) (xy 410.062371 -273.800591)
			(xy 410.098727 -273.836947) (xy 410.128948 -273.878543) (xy 410.152291 -273.924355) (xy 410.168179 -273.973254)
			(xy 410.176222 -274.024036) (xy 410.176726 -274.049744) (xy 410.493984 -274.049744) (xy 410.497944 -274.00069)
			(xy 410.509721 -273.952906) (xy 410.529012 -273.90763) (xy 410.555315 -273.866034) (xy 410.58795 -273.829197)
			(xy 410.626071 -273.798072) (xy 410.668692 -273.773465) (xy 410.714708 -273.756013) (xy 410.762927 -273.746169)
			(xy 410.812102 -273.744188) (xy 410.860957 -273.75012) (xy 410.908228 -273.763812) (xy 410.95269 -273.78491)
			(xy 410.993193 -273.812866) (xy 411.028686 -273.846958) (xy 411.058251 -273.886302) (xy 411.081122 -273.929879)
			(xy 411.096706 -273.97656) (xy 411.104601 -274.025137) (xy 411.105096 -274.049744) (xy 411.104601 -274.074351)
			(xy 411.104422 -274.075452) (xy 411.4231 -274.075452) (xy 411.4231 -274.024036) (xy 411.431143 -273.973254)
			(xy 411.447031 -273.924355) (xy 411.470374 -273.878543) (xy 411.500595 -273.836947) (xy 411.536951 -273.800591)
			(xy 411.578547 -273.77037) (xy 411.624359 -273.747027) (xy 411.673258 -273.731139) (xy 411.72404 -273.723096)
			(xy 411.775456 -273.723096) (xy 411.826238 -273.731139) (xy 411.875137 -273.747027) (xy 411.920949 -273.77037)
			(xy 411.962545 -273.800591) (xy 411.998901 -273.836947) (xy 412.029122 -273.878543) (xy 412.052465 -273.924355)
			(xy 412.068353 -273.973254) (xy 412.076396 -274.024036) (xy 412.0769 -274.049744) (xy 412.394158 -274.049744)
			(xy 412.398118 -274.00069) (xy 412.409895 -273.952906) (xy 412.429186 -273.90763) (xy 412.455489 -273.866034)
			(xy 412.488124 -273.829197) (xy 412.526245 -273.798072) (xy 412.568866 -273.773465) (xy 412.614882 -273.756013)
			(xy 412.663101 -273.746169) (xy 412.712276 -273.744188) (xy 412.761131 -273.75012) (xy 412.808402 -273.763812)
			(xy 412.852864 -273.78491) (xy 412.893367 -273.812866) (xy 412.92886 -273.846958) (xy 412.958425 -273.886302)
			(xy 412.981296 -273.929879) (xy 412.99688 -273.97656) (xy 413.004775 -274.025137) (xy 413.00527 -274.049744)
			(xy 413.004775 -274.074351) (xy 413.004596 -274.075452) (xy 413.32302 -274.075452) (xy 413.32302 -274.024036)
			(xy 413.331063 -273.973254) (xy 413.346951 -273.924355) (xy 413.370294 -273.878543) (xy 413.400515 -273.836947)
			(xy 413.436871 -273.800591) (xy 413.478467 -273.77037) (xy 413.524279 -273.747027) (xy 413.573178 -273.731139)
			(xy 413.62396 -273.723096) (xy 413.675376 -273.723096) (xy 413.726158 -273.731139) (xy 413.775057 -273.747027)
			(xy 413.820869 -273.77037) (xy 413.862465 -273.800591) (xy 413.898821 -273.836947) (xy 413.929042 -273.878543)
			(xy 413.952385 -273.924355) (xy 413.968273 -273.973254) (xy 413.976316 -274.024036) (xy 413.97682 -274.049744)
			(xy 414.294078 -274.049744) (xy 414.298038 -274.00069) (xy 414.309815 -273.952906) (xy 414.329106 -273.90763)
			(xy 414.355409 -273.866034) (xy 414.388044 -273.829197) (xy 414.426165 -273.798072) (xy 414.468786 -273.773465)
			(xy 414.514802 -273.756013) (xy 414.563021 -273.746169) (xy 414.612196 -273.744188) (xy 414.661051 -273.75012)
			(xy 414.708322 -273.763812) (xy 414.752784 -273.78491) (xy 414.793287 -273.812866) (xy 414.82878 -273.846958)
			(xy 414.858345 -273.886302) (xy 414.881216 -273.929879) (xy 414.8968 -273.97656) (xy 414.904695 -274.025137)
			(xy 414.90519 -274.049744) (xy 414.904695 -274.074351) (xy 414.904516 -274.075452) (xy 415.22294 -274.075452)
			(xy 415.22294 -274.024036) (xy 415.230983 -273.973254) (xy 415.246871 -273.924355) (xy 415.270214 -273.878543)
			(xy 415.300435 -273.836947) (xy 415.336791 -273.800591) (xy 415.378387 -273.77037) (xy 415.424199 -273.747027)
			(xy 415.473098 -273.731139) (xy 415.52388 -273.723096) (xy 415.575296 -273.723096) (xy 415.626078 -273.731139)
			(xy 415.674977 -273.747027) (xy 415.720789 -273.77037) (xy 415.762385 -273.800591) (xy 415.798741 -273.836947)
			(xy 415.828962 -273.878543) (xy 415.852305 -273.924355) (xy 415.868193 -273.973254) (xy 415.876236 -274.024036)
			(xy 415.87674 -274.049744) (xy 416.193998 -274.049744) (xy 416.197958 -274.00069) (xy 416.209735 -273.952906)
			(xy 416.229026 -273.90763) (xy 416.255329 -273.866034) (xy 416.287964 -273.829197) (xy 416.326085 -273.798072)
			(xy 416.368706 -273.773465) (xy 416.414722 -273.756013) (xy 416.462941 -273.746169) (xy 416.512116 -273.744188)
			(xy 416.560971 -273.75012) (xy 416.608242 -273.763812) (xy 416.652704 -273.78491) (xy 416.693207 -273.812866)
			(xy 416.7287 -273.846958) (xy 416.758265 -273.886302) (xy 416.781136 -273.929879) (xy 416.79672 -273.97656)
			(xy 416.804615 -274.025137) (xy 416.80511 -274.049744) (xy 416.804615 -274.074351) (xy 416.804436 -274.075452)
			(xy 417.123114 -274.075452) (xy 417.123114 -274.024036) (xy 417.131157 -273.973254) (xy 417.147045 -273.924355)
			(xy 417.170388 -273.878543) (xy 417.200609 -273.836947) (xy 417.236965 -273.800591) (xy 417.278561 -273.77037)
			(xy 417.324373 -273.747027) (xy 417.373272 -273.731139) (xy 417.424054 -273.723096) (xy 417.47547 -273.723096)
			(xy 417.526252 -273.731139) (xy 417.575151 -273.747027) (xy 417.620963 -273.77037) (xy 417.662559 -273.800591)
			(xy 417.698915 -273.836947) (xy 417.729136 -273.878543) (xy 417.752479 -273.924355) (xy 417.768367 -273.973254)
			(xy 417.77641 -274.024036) (xy 417.776914 -274.049744) (xy 418.094172 -274.049744) (xy 418.098132 -274.00069)
			(xy 418.109909 -273.952906) (xy 418.1292 -273.90763) (xy 418.155503 -273.866034) (xy 418.188138 -273.829197)
			(xy 418.226259 -273.798072) (xy 418.26888 -273.773465) (xy 418.314896 -273.756013) (xy 418.363115 -273.746169)
			(xy 418.41229 -273.744188) (xy 418.461145 -273.75012) (xy 418.508416 -273.763812) (xy 418.552878 -273.78491)
			(xy 418.593381 -273.812866) (xy 418.628874 -273.846958) (xy 418.658439 -273.886302) (xy 418.68131 -273.929879)
			(xy 418.696894 -273.97656) (xy 418.704789 -274.025137) (xy 418.705284 -274.049744) (xy 418.704789 -274.074351)
			(xy 418.70461 -274.075452) (xy 419.023034 -274.075452) (xy 419.023034 -274.024036) (xy 419.031077 -273.973254)
			(xy 419.046965 -273.924355) (xy 419.070308 -273.878543) (xy 419.100529 -273.836947) (xy 419.136885 -273.800591)
			(xy 419.178481 -273.77037) (xy 419.224293 -273.747027) (xy 419.273192 -273.731139) (xy 419.323974 -273.723096)
			(xy 419.37539 -273.723096) (xy 419.426172 -273.731139) (xy 419.475071 -273.747027) (xy 419.520883 -273.77037)
			(xy 419.562479 -273.800591) (xy 419.598835 -273.836947) (xy 419.629056 -273.878543) (xy 419.652399 -273.924355)
			(xy 419.668287 -273.973254) (xy 419.67633 -274.024036) (xy 419.676834 -274.049744) (xy 419.994092 -274.049744)
			(xy 419.998052 -274.00069) (xy 420.009829 -273.952906) (xy 420.02912 -273.90763) (xy 420.055423 -273.866034)
			(xy 420.088058 -273.829197) (xy 420.126179 -273.798072) (xy 420.1688 -273.773465) (xy 420.214816 -273.756013)
			(xy 420.263035 -273.746169) (xy 420.31221 -273.744188) (xy 420.361065 -273.75012) (xy 420.408336 -273.763812)
			(xy 420.452798 -273.78491) (xy 420.493301 -273.812866) (xy 420.528794 -273.846958) (xy 420.558359 -273.886302)
			(xy 420.58123 -273.929879) (xy 420.596814 -273.97656) (xy 420.604709 -274.025137) (xy 420.605204 -274.049744)
			(xy 420.604709 -274.074351) (xy 420.60453 -274.075452) (xy 420.922954 -274.075452) (xy 420.922954 -274.024036)
			(xy 420.930997 -273.973254) (xy 420.946885 -273.924355) (xy 420.970228 -273.878543) (xy 421.000449 -273.836947)
			(xy 421.036805 -273.800591) (xy 421.078401 -273.77037) (xy 421.124213 -273.747027) (xy 421.173112 -273.731139)
			(xy 421.223894 -273.723096) (xy 421.27531 -273.723096) (xy 421.326092 -273.731139) (xy 421.374991 -273.747027)
			(xy 421.420803 -273.77037) (xy 421.462399 -273.800591) (xy 421.498755 -273.836947) (xy 421.528976 -273.878543)
			(xy 421.552319 -273.924355) (xy 421.568207 -273.973254) (xy 421.57625 -274.024036) (xy 421.576754 -274.049744)
			(xy 421.894012 -274.049744) (xy 421.897972 -274.00069) (xy 421.909749 -273.952906) (xy 421.92904 -273.90763)
			(xy 421.955343 -273.866034) (xy 421.987978 -273.829197) (xy 422.026099 -273.798072) (xy 422.06872 -273.773465)
			(xy 422.114736 -273.756013) (xy 422.162955 -273.746169) (xy 422.21213 -273.744188) (xy 422.260985 -273.75012)
			(xy 422.308256 -273.763812) (xy 422.352718 -273.78491) (xy 422.393221 -273.812866) (xy 422.428714 -273.846958)
			(xy 422.458279 -273.886302) (xy 422.48115 -273.929879) (xy 422.496734 -273.97656) (xy 422.504629 -274.025137)
			(xy 422.505124 -274.049744) (xy 422.504629 -274.074351) (xy 422.50445 -274.075452) (xy 422.823128 -274.075452)
			(xy 422.823128 -274.024036) (xy 422.831171 -273.973254) (xy 422.847059 -273.924355) (xy 422.870402 -273.878543)
			(xy 422.900623 -273.836947) (xy 422.936979 -273.800591) (xy 422.978575 -273.77037) (xy 423.024387 -273.747027)
			(xy 423.073286 -273.731139) (xy 423.124068 -273.723096) (xy 423.175484 -273.723096) (xy 423.226266 -273.731139)
			(xy 423.275165 -273.747027) (xy 423.320977 -273.77037) (xy 423.362573 -273.800591) (xy 423.398929 -273.836947)
			(xy 423.42915 -273.878543) (xy 423.452493 -273.924355) (xy 423.468381 -273.973254) (xy 423.476424 -274.024036)
			(xy 423.476928 -274.049744) (xy 423.79444 -274.049744) (xy 423.7984 -274.00069) (xy 423.810177 -273.952906)
			(xy 423.829468 -273.90763) (xy 423.855771 -273.866034) (xy 423.888406 -273.829197) (xy 423.926527 -273.798072)
			(xy 423.969148 -273.773465) (xy 424.015164 -273.756013) (xy 424.063383 -273.746169) (xy 424.112558 -273.744188)
			(xy 424.161413 -273.75012) (xy 424.208684 -273.763812) (xy 424.253146 -273.78491) (xy 424.293649 -273.812866)
			(xy 424.329142 -273.846958) (xy 424.358707 -273.886302) (xy 424.381578 -273.929879) (xy 424.397162 -273.97656)
			(xy 424.405057 -274.025137) (xy 424.405552 -274.049744) (xy 424.405057 -274.074351) (xy 424.404878 -274.075452)
			(xy 424.723048 -274.075452) (xy 424.723048 -274.024036) (xy 424.731091 -273.973254) (xy 424.746979 -273.924355)
			(xy 424.770322 -273.878543) (xy 424.800543 -273.836947) (xy 424.836899 -273.800591) (xy 424.878495 -273.77037)
			(xy 424.924307 -273.747027) (xy 424.973206 -273.731139) (xy 425.023988 -273.723096) (xy 425.075404 -273.723096)
			(xy 425.126186 -273.731139) (xy 425.175085 -273.747027) (xy 425.220897 -273.77037) (xy 425.262493 -273.800591)
			(xy 425.298849 -273.836947) (xy 425.32907 -273.878543) (xy 425.352413 -273.924355) (xy 425.368301 -273.973254)
			(xy 425.376344 -274.024036) (xy 425.376848 -274.049744) (xy 425.69436 -274.049744) (xy 425.69832 -274.00069)
			(xy 425.710097 -273.952906) (xy 425.729388 -273.90763) (xy 425.755691 -273.866034) (xy 425.788326 -273.829197)
			(xy 425.826447 -273.798072) (xy 425.869068 -273.773465) (xy 425.915084 -273.756013) (xy 425.963303 -273.746169)
			(xy 426.012478 -273.744188) (xy 426.061333 -273.75012) (xy 426.108604 -273.763812) (xy 426.153066 -273.78491)
			(xy 426.193569 -273.812866) (xy 426.229062 -273.846958) (xy 426.258627 -273.886302) (xy 426.281498 -273.929879)
			(xy 426.297082 -273.97656) (xy 426.304977 -274.025137) (xy 426.305472 -274.049744) (xy 426.304977 -274.074351)
			(xy 426.304798 -274.075452) (xy 426.622968 -274.075452) (xy 426.622968 -274.024036) (xy 426.631011 -273.973254)
			(xy 426.646899 -273.924355) (xy 426.670242 -273.878543) (xy 426.700463 -273.836947) (xy 426.736819 -273.800591)
			(xy 426.778415 -273.77037) (xy 426.824227 -273.747027) (xy 426.873126 -273.731139) (xy 426.923908 -273.723096)
			(xy 426.975324 -273.723096) (xy 427.026106 -273.731139) (xy 427.075005 -273.747027) (xy 427.120817 -273.77037)
			(xy 427.162413 -273.800591) (xy 427.198769 -273.836947) (xy 427.22899 -273.878543) (xy 427.252333 -273.924355)
			(xy 427.268221 -273.973254) (xy 427.276264 -274.024036) (xy 427.276768 -274.049744) (xy 427.59428 -274.049744)
			(xy 427.59824 -274.00069) (xy 427.610017 -273.952906) (xy 427.629308 -273.90763) (xy 427.655611 -273.866034)
			(xy 427.688246 -273.829197) (xy 427.726367 -273.798072) (xy 427.768988 -273.773465) (xy 427.815004 -273.756013)
			(xy 427.863223 -273.746169) (xy 427.912398 -273.744188) (xy 427.961253 -273.75012) (xy 428.008524 -273.763812)
			(xy 428.052986 -273.78491) (xy 428.093489 -273.812866) (xy 428.128982 -273.846958) (xy 428.158547 -273.886302)
			(xy 428.181418 -273.929879) (xy 428.197002 -273.97656) (xy 428.204897 -274.025137) (xy 428.205392 -274.049744)
			(xy 428.204897 -274.074351) (xy 428.204718 -274.075452) (xy 428.522888 -274.075452) (xy 428.522888 -274.024036)
			(xy 428.530931 -273.973254) (xy 428.546819 -273.924355) (xy 428.570162 -273.878543) (xy 428.600383 -273.836947)
			(xy 428.636739 -273.800591) (xy 428.678335 -273.77037) (xy 428.724147 -273.747027) (xy 428.773046 -273.731139)
			(xy 428.823828 -273.723096) (xy 428.875244 -273.723096) (xy 428.926026 -273.731139) (xy 428.974925 -273.747027)
			(xy 429.020737 -273.77037) (xy 429.062333 -273.800591) (xy 429.098689 -273.836947) (xy 429.12891 -273.878543)
			(xy 429.152253 -273.924355) (xy 429.168141 -273.973254) (xy 429.176184 -274.024036) (xy 429.176688 -274.049744)
			(xy 429.4942 -274.049744) (xy 429.49816 -274.00069) (xy 429.509937 -273.952906) (xy 429.529228 -273.90763)
			(xy 429.555531 -273.866034) (xy 429.588166 -273.829197) (xy 429.626287 -273.798072) (xy 429.668908 -273.773465)
			(xy 429.714924 -273.756013) (xy 429.763143 -273.746169) (xy 429.812318 -273.744188) (xy 429.861173 -273.75012)
			(xy 429.908444 -273.763812) (xy 429.952906 -273.78491) (xy 429.993409 -273.812866) (xy 430.028902 -273.846958)
			(xy 430.058467 -273.886302) (xy 430.081338 -273.929879) (xy 430.096922 -273.97656) (xy 430.104817 -274.025137)
			(xy 430.105312 -274.049744) (xy 430.44416 -274.049744) (xy 430.44812 -274.00069) (xy 430.459897 -273.952906)
			(xy 430.479188 -273.90763) (xy 430.505491 -273.866034) (xy 430.538126 -273.829197) (xy 430.576247 -273.798072)
			(xy 430.618868 -273.773465) (xy 430.664884 -273.756013) (xy 430.713103 -273.746169) (xy 430.762278 -273.744188)
			(xy 430.811133 -273.75012) (xy 430.858404 -273.763812) (xy 430.902866 -273.78491) (xy 430.943369 -273.812866)
			(xy 430.978862 -273.846958) (xy 431.008427 -273.886302) (xy 431.031298 -273.929879) (xy 431.046882 -273.97656)
			(xy 431.054777 -274.025137) (xy 431.055272 -274.049744) (xy 431.054777 -274.074351) (xy 431.046882 -274.122928)
			(xy 431.031298 -274.169609) (xy 431.008427 -274.213186) (xy 430.978862 -274.25253) (xy 430.943369 -274.286622)
			(xy 430.902866 -274.314578) (xy 430.858404 -274.335676) (xy 430.811133 -274.349368) (xy 430.762278 -274.3553)
			(xy 430.713103 -274.353319) (xy 430.664884 -274.343475) (xy 430.618868 -274.326023) (xy 430.576247 -274.301416)
			(xy 430.538126 -274.270291) (xy 430.505491 -274.233454) (xy 430.479188 -274.191858) (xy 430.459897 -274.146582)
			(xy 430.44812 -274.098798) (xy 430.44416 -274.049744) (xy 430.105312 -274.049744) (xy 430.104817 -274.074351)
			(xy 430.096922 -274.122928) (xy 430.081338 -274.169609) (xy 430.058467 -274.213186) (xy 430.028902 -274.25253)
			(xy 429.993409 -274.286622) (xy 429.952906 -274.314578) (xy 429.908444 -274.335676) (xy 429.861173 -274.349368)
			(xy 429.812318 -274.3553) (xy 429.763143 -274.353319) (xy 429.714924 -274.343475) (xy 429.668908 -274.326023)
			(xy 429.626287 -274.301416) (xy 429.588166 -274.270291) (xy 429.555531 -274.233454) (xy 429.529228 -274.191858)
			(xy 429.509937 -274.146582) (xy 429.49816 -274.098798) (xy 429.4942 -274.049744) (xy 429.176688 -274.049744)
			(xy 429.176184 -274.075452) (xy 429.168141 -274.126234) (xy 429.152253 -274.175133) (xy 429.12891 -274.220945)
			(xy 429.098689 -274.262541) (xy 429.062333 -274.298897) (xy 429.020737 -274.329118) (xy 428.974925 -274.352461)
			(xy 428.926026 -274.368349) (xy 428.875244 -274.376392) (xy 428.823828 -274.376392) (xy 428.773046 -274.368349)
			(xy 428.724147 -274.352461) (xy 428.678335 -274.329118) (xy 428.636739 -274.298897) (xy 428.600383 -274.262541)
			(xy 428.570162 -274.220945) (xy 428.546819 -274.175133) (xy 428.530931 -274.126234) (xy 428.522888 -274.075452)
			(xy 428.204718 -274.075452) (xy 428.197002 -274.122928) (xy 428.181418 -274.169609) (xy 428.158547 -274.213186)
			(xy 428.128982 -274.25253) (xy 428.093489 -274.286622) (xy 428.052986 -274.314578) (xy 428.008524 -274.335676)
			(xy 427.961253 -274.349368) (xy 427.912398 -274.3553) (xy 427.863223 -274.353319) (xy 427.815004 -274.343475)
			(xy 427.768988 -274.326023) (xy 427.726367 -274.301416) (xy 427.688246 -274.270291) (xy 427.655611 -274.233454)
			(xy 427.629308 -274.191858) (xy 427.610017 -274.146582) (xy 427.59824 -274.098798) (xy 427.59428 -274.049744)
			(xy 427.276768 -274.049744) (xy 427.276264 -274.075452) (xy 427.268221 -274.126234) (xy 427.252333 -274.175133)
			(xy 427.22899 -274.220945) (xy 427.198769 -274.262541) (xy 427.162413 -274.298897) (xy 427.120817 -274.329118)
			(xy 427.075005 -274.352461) (xy 427.026106 -274.368349) (xy 426.975324 -274.376392) (xy 426.923908 -274.376392)
			(xy 426.873126 -274.368349) (xy 426.824227 -274.352461) (xy 426.778415 -274.329118) (xy 426.736819 -274.298897)
			(xy 426.700463 -274.262541) (xy 426.670242 -274.220945) (xy 426.646899 -274.175133) (xy 426.631011 -274.126234)
			(xy 426.622968 -274.075452) (xy 426.304798 -274.075452) (xy 426.297082 -274.122928) (xy 426.281498 -274.169609)
			(xy 426.258627 -274.213186) (xy 426.229062 -274.25253) (xy 426.193569 -274.286622) (xy 426.153066 -274.314578)
			(xy 426.108604 -274.335676) (xy 426.061333 -274.349368) (xy 426.012478 -274.3553) (xy 425.963303 -274.353319)
			(xy 425.915084 -274.343475) (xy 425.869068 -274.326023) (xy 425.826447 -274.301416) (xy 425.788326 -274.270291)
			(xy 425.755691 -274.233454) (xy 425.729388 -274.191858) (xy 425.710097 -274.146582) (xy 425.69832 -274.098798)
			(xy 425.69436 -274.049744) (xy 425.376848 -274.049744) (xy 425.376344 -274.075452) (xy 425.368301 -274.126234)
			(xy 425.352413 -274.175133) (xy 425.32907 -274.220945) (xy 425.298849 -274.262541) (xy 425.262493 -274.298897)
			(xy 425.220897 -274.329118) (xy 425.175085 -274.352461) (xy 425.126186 -274.368349) (xy 425.075404 -274.376392)
			(xy 425.023988 -274.376392) (xy 424.973206 -274.368349) (xy 424.924307 -274.352461) (xy 424.878495 -274.329118)
			(xy 424.836899 -274.298897) (xy 424.800543 -274.262541) (xy 424.770322 -274.220945) (xy 424.746979 -274.175133)
			(xy 424.731091 -274.126234) (xy 424.723048 -274.075452) (xy 424.404878 -274.075452) (xy 424.397162 -274.122928)
			(xy 424.381578 -274.169609) (xy 424.358707 -274.213186) (xy 424.329142 -274.25253) (xy 424.293649 -274.286622)
			(xy 424.253146 -274.314578) (xy 424.208684 -274.335676) (xy 424.161413 -274.349368) (xy 424.112558 -274.3553)
			(xy 424.063383 -274.353319) (xy 424.015164 -274.343475) (xy 423.969148 -274.326023) (xy 423.926527 -274.301416)
			(xy 423.888406 -274.270291) (xy 423.855771 -274.233454) (xy 423.829468 -274.191858) (xy 423.810177 -274.146582)
			(xy 423.7984 -274.098798) (xy 423.79444 -274.049744) (xy 423.476928 -274.049744) (xy 423.476424 -274.075452)
			(xy 423.468381 -274.126234) (xy 423.452493 -274.175133) (xy 423.42915 -274.220945) (xy 423.398929 -274.262541)
			(xy 423.362573 -274.298897) (xy 423.320977 -274.329118) (xy 423.275165 -274.352461) (xy 423.226266 -274.368349)
			(xy 423.175484 -274.376392) (xy 423.124068 -274.376392) (xy 423.073286 -274.368349) (xy 423.024387 -274.352461)
			(xy 422.978575 -274.329118) (xy 422.936979 -274.298897) (xy 422.900623 -274.262541) (xy 422.870402 -274.220945)
			(xy 422.847059 -274.175133) (xy 422.831171 -274.126234) (xy 422.823128 -274.075452) (xy 422.50445 -274.075452)
			(xy 422.496734 -274.122928) (xy 422.48115 -274.169609) (xy 422.458279 -274.213186) (xy 422.428714 -274.25253)
			(xy 422.393221 -274.286622) (xy 422.352718 -274.314578) (xy 422.308256 -274.335676) (xy 422.260985 -274.349368)
			(xy 422.21213 -274.3553) (xy 422.162955 -274.353319) (xy 422.114736 -274.343475) (xy 422.06872 -274.326023)
			(xy 422.026099 -274.301416) (xy 421.987978 -274.270291) (xy 421.955343 -274.233454) (xy 421.92904 -274.191858)
			(xy 421.909749 -274.146582) (xy 421.897972 -274.098798) (xy 421.894012 -274.049744) (xy 421.576754 -274.049744)
			(xy 421.57625 -274.075452) (xy 421.568207 -274.126234) (xy 421.552319 -274.175133) (xy 421.528976 -274.220945)
			(xy 421.498755 -274.262541) (xy 421.462399 -274.298897) (xy 421.420803 -274.329118) (xy 421.374991 -274.352461)
			(xy 421.326092 -274.368349) (xy 421.27531 -274.376392) (xy 421.223894 -274.376392) (xy 421.173112 -274.368349)
			(xy 421.124213 -274.352461) (xy 421.078401 -274.329118) (xy 421.036805 -274.298897) (xy 421.000449 -274.262541)
			(xy 420.970228 -274.220945) (xy 420.946885 -274.175133) (xy 420.930997 -274.126234) (xy 420.922954 -274.075452)
			(xy 420.60453 -274.075452) (xy 420.596814 -274.122928) (xy 420.58123 -274.169609) (xy 420.558359 -274.213186)
			(xy 420.528794 -274.25253) (xy 420.493301 -274.286622) (xy 420.452798 -274.314578) (xy 420.408336 -274.335676)
			(xy 420.361065 -274.349368) (xy 420.31221 -274.3553) (xy 420.263035 -274.353319) (xy 420.214816 -274.343475)
			(xy 420.1688 -274.326023) (xy 420.126179 -274.301416) (xy 420.088058 -274.270291) (xy 420.055423 -274.233454)
			(xy 420.02912 -274.191858) (xy 420.009829 -274.146582) (xy 419.998052 -274.098798) (xy 419.994092 -274.049744)
			(xy 419.676834 -274.049744) (xy 419.67633 -274.075452) (xy 419.668287 -274.126234) (xy 419.652399 -274.175133)
			(xy 419.629056 -274.220945) (xy 419.598835 -274.262541) (xy 419.562479 -274.298897) (xy 419.520883 -274.329118)
			(xy 419.475071 -274.352461) (xy 419.426172 -274.368349) (xy 419.37539 -274.376392) (xy 419.323974 -274.376392)
			(xy 419.273192 -274.368349) (xy 419.224293 -274.352461) (xy 419.178481 -274.329118) (xy 419.136885 -274.298897)
			(xy 419.100529 -274.262541) (xy 419.070308 -274.220945) (xy 419.046965 -274.175133) (xy 419.031077 -274.126234)
			(xy 419.023034 -274.075452) (xy 418.70461 -274.075452) (xy 418.696894 -274.122928) (xy 418.68131 -274.169609)
			(xy 418.658439 -274.213186) (xy 418.628874 -274.25253) (xy 418.593381 -274.286622) (xy 418.552878 -274.314578)
			(xy 418.508416 -274.335676) (xy 418.461145 -274.349368) (xy 418.41229 -274.3553) (xy 418.363115 -274.353319)
			(xy 418.314896 -274.343475) (xy 418.26888 -274.326023) (xy 418.226259 -274.301416) (xy 418.188138 -274.270291)
			(xy 418.155503 -274.233454) (xy 418.1292 -274.191858) (xy 418.109909 -274.146582) (xy 418.098132 -274.098798)
			(xy 418.094172 -274.049744) (xy 417.776914 -274.049744) (xy 417.77641 -274.075452) (xy 417.768367 -274.126234)
			(xy 417.752479 -274.175133) (xy 417.729136 -274.220945) (xy 417.698915 -274.262541) (xy 417.662559 -274.298897)
			(xy 417.620963 -274.329118) (xy 417.575151 -274.352461) (xy 417.526252 -274.368349) (xy 417.47547 -274.376392)
			(xy 417.424054 -274.376392) (xy 417.373272 -274.368349) (xy 417.324373 -274.352461) (xy 417.278561 -274.329118)
			(xy 417.236965 -274.298897) (xy 417.200609 -274.262541) (xy 417.170388 -274.220945) (xy 417.147045 -274.175133)
			(xy 417.131157 -274.126234) (xy 417.123114 -274.075452) (xy 416.804436 -274.075452) (xy 416.79672 -274.122928)
			(xy 416.781136 -274.169609) (xy 416.758265 -274.213186) (xy 416.7287 -274.25253) (xy 416.693207 -274.286622)
			(xy 416.652704 -274.314578) (xy 416.608242 -274.335676) (xy 416.560971 -274.349368) (xy 416.512116 -274.3553)
			(xy 416.462941 -274.353319) (xy 416.414722 -274.343475) (xy 416.368706 -274.326023) (xy 416.326085 -274.301416)
			(xy 416.287964 -274.270291) (xy 416.255329 -274.233454) (xy 416.229026 -274.191858) (xy 416.209735 -274.146582)
			(xy 416.197958 -274.098798) (xy 416.193998 -274.049744) (xy 415.87674 -274.049744) (xy 415.876236 -274.075452)
			(xy 415.868193 -274.126234) (xy 415.852305 -274.175133) (xy 415.828962 -274.220945) (xy 415.798741 -274.262541)
			(xy 415.762385 -274.298897) (xy 415.720789 -274.329118) (xy 415.674977 -274.352461) (xy 415.626078 -274.368349)
			(xy 415.575296 -274.376392) (xy 415.52388 -274.376392) (xy 415.473098 -274.368349) (xy 415.424199 -274.352461)
			(xy 415.378387 -274.329118) (xy 415.336791 -274.298897) (xy 415.300435 -274.262541) (xy 415.270214 -274.220945)
			(xy 415.246871 -274.175133) (xy 415.230983 -274.126234) (xy 415.22294 -274.075452) (xy 414.904516 -274.075452)
			(xy 414.8968 -274.122928) (xy 414.881216 -274.169609) (xy 414.858345 -274.213186) (xy 414.82878 -274.25253)
			(xy 414.793287 -274.286622) (xy 414.752784 -274.314578) (xy 414.708322 -274.335676) (xy 414.661051 -274.349368)
			(xy 414.612196 -274.3553) (xy 414.563021 -274.353319) (xy 414.514802 -274.343475) (xy 414.468786 -274.326023)
			(xy 414.426165 -274.301416) (xy 414.388044 -274.270291) (xy 414.355409 -274.233454) (xy 414.329106 -274.191858)
			(xy 414.309815 -274.146582) (xy 414.298038 -274.098798) (xy 414.294078 -274.049744) (xy 413.97682 -274.049744)
			(xy 413.976316 -274.075452) (xy 413.968273 -274.126234) (xy 413.952385 -274.175133) (xy 413.929042 -274.220945)
			(xy 413.898821 -274.262541) (xy 413.862465 -274.298897) (xy 413.820869 -274.329118) (xy 413.775057 -274.352461)
			(xy 413.726158 -274.368349) (xy 413.675376 -274.376392) (xy 413.62396 -274.376392) (xy 413.573178 -274.368349)
			(xy 413.524279 -274.352461) (xy 413.478467 -274.329118) (xy 413.436871 -274.298897) (xy 413.400515 -274.262541)
			(xy 413.370294 -274.220945) (xy 413.346951 -274.175133) (xy 413.331063 -274.126234) (xy 413.32302 -274.075452)
			(xy 413.004596 -274.075452) (xy 412.99688 -274.122928) (xy 412.981296 -274.169609) (xy 412.958425 -274.213186)
			(xy 412.92886 -274.25253) (xy 412.893367 -274.286622) (xy 412.852864 -274.314578) (xy 412.808402 -274.335676)
			(xy 412.761131 -274.349368) (xy 412.712276 -274.3553) (xy 412.663101 -274.353319) (xy 412.614882 -274.343475)
			(xy 412.568866 -274.326023) (xy 412.526245 -274.301416) (xy 412.488124 -274.270291) (xy 412.455489 -274.233454)
			(xy 412.429186 -274.191858) (xy 412.409895 -274.146582) (xy 412.398118 -274.098798) (xy 412.394158 -274.049744)
			(xy 412.0769 -274.049744) (xy 412.076396 -274.075452) (xy 412.068353 -274.126234) (xy 412.052465 -274.175133)
			(xy 412.029122 -274.220945) (xy 411.998901 -274.262541) (xy 411.962545 -274.298897) (xy 411.920949 -274.329118)
			(xy 411.875137 -274.352461) (xy 411.826238 -274.368349) (xy 411.775456 -274.376392) (xy 411.72404 -274.376392)
			(xy 411.673258 -274.368349) (xy 411.624359 -274.352461) (xy 411.578547 -274.329118) (xy 411.536951 -274.298897)
			(xy 411.500595 -274.262541) (xy 411.470374 -274.220945) (xy 411.447031 -274.175133) (xy 411.431143 -274.126234)
			(xy 411.4231 -274.075452) (xy 411.104422 -274.075452) (xy 411.096706 -274.122928) (xy 411.081122 -274.169609)
			(xy 411.058251 -274.213186) (xy 411.028686 -274.25253) (xy 410.993193 -274.286622) (xy 410.95269 -274.314578)
			(xy 410.908228 -274.335676) (xy 410.860957 -274.349368) (xy 410.812102 -274.3553) (xy 410.762927 -274.353319)
			(xy 410.714708 -274.343475) (xy 410.668692 -274.326023) (xy 410.626071 -274.301416) (xy 410.58795 -274.270291)
			(xy 410.555315 -274.233454) (xy 410.529012 -274.191858) (xy 410.509721 -274.146582) (xy 410.497944 -274.098798)
			(xy 410.493984 -274.049744) (xy 410.176726 -274.049744) (xy 410.176222 -274.075452) (xy 410.168179 -274.126234)
			(xy 410.152291 -274.175133) (xy 410.128948 -274.220945) (xy 410.098727 -274.262541) (xy 410.062371 -274.298897)
			(xy 410.020775 -274.329118) (xy 409.974963 -274.352461) (xy 409.926064 -274.368349) (xy 409.875282 -274.376392)
			(xy 409.823866 -274.376392) (xy 409.773084 -274.368349) (xy 409.724185 -274.352461) (xy 409.678373 -274.329118)
			(xy 409.636777 -274.298897) (xy 409.600421 -274.262541) (xy 409.5702 -274.220945) (xy 409.546857 -274.175133)
			(xy 409.530969 -274.126234) (xy 409.522926 -274.075452) (xy 409.204502 -274.075452) (xy 409.196786 -274.122928)
			(xy 409.181202 -274.169609) (xy 409.158331 -274.213186) (xy 409.128766 -274.25253) (xy 409.093273 -274.286622)
			(xy 409.05277 -274.314578) (xy 409.008308 -274.335676) (xy 408.961037 -274.349368) (xy 408.912182 -274.3553)
			(xy 408.863007 -274.353319) (xy 408.814788 -274.343475) (xy 408.768772 -274.326023) (xy 408.726151 -274.301416)
			(xy 408.68803 -274.270291) (xy 408.655395 -274.233454) (xy 408.629092 -274.191858) (xy 408.609801 -274.146582)
			(xy 408.598024 -274.098798) (xy 408.594064 -274.049744) (xy 408.27613 -274.049744) (xy 408.27613 -274.075193)
			(xy 408.268091 -274.125946) (xy 408.252211 -274.174817) (xy 408.22888 -274.220601) (xy 408.198674 -274.262171)
			(xy 408.162336 -274.298504) (xy 408.120761 -274.328704) (xy 408.074974 -274.352028) (xy 408.026101 -274.367902)
			(xy 407.975347 -274.375934) (xy 407.949654 -274.376388) (xy 407.949146 -274.376388) (xy 407.923937 -274.375881)
			(xy 407.874128 -274.368064) (xy 407.826106 -274.352701) (xy 407.80335 -274.341844) (xy 407.802842 -274.341844)
			(xy 407.802588 -274.34159) (xy 407.796889 -274.339063) (xy 407.784692 -274.336506) (xy 407.778458 -274.33651)
			(xy 407.764996 -274.337018) (xy 407.68016 -274.389342) (xy 407.679652 -274.389596) (xy 407.679144 -274.390104)
			(xy 407.670343 -274.396391) (xy 407.658618 -274.414543) (xy 407.656538 -274.425156) (xy 407.65603 -274.432522)
			(xy 407.65603 -274.641564) (xy 407.656284 -274.646898) (xy 407.657692 -274.656228) (xy 407.666445 -274.672927)
			(xy 407.673302 -274.67941) (xy 407.680922 -274.684998) (xy 407.755852 -274.729702) (xy 407.761535 -274.732844)
			(xy 407.774007 -274.736444) (xy 407.78049 -274.736814) (xy 407.793698 -274.737322) (xy 407.805636 -274.730972)
			(xy 407.827951 -274.719548) (xy 407.875392 -274.703354) (xy 407.924844 -274.695146) (xy 407.949908 -274.69465)
			(xy 407.975166 -274.695172) (xy 408.024994 -274.703488) (xy 408.072773 -274.719892) (xy 408.117201 -274.743936)
			(xy 408.157065 -274.774965) (xy 408.191279 -274.812132) (xy 408.218908 -274.854423) (xy 408.239201 -274.900685)
			(xy 408.251601 -274.949656) (xy 408.255773 -275) (xy 408.253667 -275.025412) (xy 408.572966 -275.025412)
			(xy 408.572966 -274.973996) (xy 408.581009 -274.923214) (xy 408.596897 -274.874315) (xy 408.62024 -274.828503)
			(xy 408.650461 -274.786907) (xy 408.686817 -274.750551) (xy 408.728413 -274.72033) (xy 408.774225 -274.696987)
			(xy 408.823124 -274.681099) (xy 408.873906 -274.673056) (xy 408.925322 -274.673056) (xy 408.976104 -274.681099)
			(xy 409.025003 -274.696987) (xy 409.070815 -274.72033) (xy 409.112411 -274.750551) (xy 409.148767 -274.786907)
			(xy 409.178988 -274.828503) (xy 409.202331 -274.874315) (xy 409.218219 -274.923214) (xy 409.226262 -274.973996)
			(xy 409.226766 -274.999704) (xy 409.226761 -274.999958) (xy 409.544024 -274.999958) (xy 409.547984 -274.950904)
			(xy 409.559761 -274.90312) (xy 409.579052 -274.857844) (xy 409.605355 -274.816248) (xy 409.63799 -274.779411)
			(xy 409.676111 -274.748286) (xy 409.718732 -274.723679) (xy 409.764748 -274.706227) (xy 409.812967 -274.696383)
			(xy 409.862142 -274.694402) (xy 409.910997 -274.700334) (xy 409.958268 -274.714026) (xy 410.00273 -274.735124)
			(xy 410.043233 -274.76308) (xy 410.078726 -274.797172) (xy 410.108291 -274.836516) (xy 410.131162 -274.880093)
			(xy 410.146746 -274.926774) (xy 410.154641 -274.975351) (xy 410.155136 -274.999958) (xy 410.154641 -275.024565)
			(xy 410.154462 -275.025666) (xy 410.472886 -275.025666) (xy 410.472886 -274.97425) (xy 410.480929 -274.923468)
			(xy 410.496817 -274.874569) (xy 410.52016 -274.828757) (xy 410.550381 -274.787161) (xy 410.586737 -274.750805)
			(xy 410.628333 -274.720584) (xy 410.674145 -274.697241) (xy 410.723044 -274.681353) (xy 410.773826 -274.67331)
			(xy 410.825242 -274.67331) (xy 410.876024 -274.681353) (xy 410.924923 -274.697241) (xy 410.970735 -274.720584)
			(xy 411.012331 -274.750805) (xy 411.048687 -274.787161) (xy 411.078908 -274.828757) (xy 411.102251 -274.874569)
			(xy 411.118139 -274.923468) (xy 411.126182 -274.97425) (xy 411.126686 -274.999958) (xy 411.444198 -274.999958)
			(xy 411.448158 -274.950904) (xy 411.459935 -274.90312) (xy 411.479226 -274.857844) (xy 411.505529 -274.816248)
			(xy 411.538164 -274.779411) (xy 411.576285 -274.748286) (xy 411.618906 -274.723679) (xy 411.664922 -274.706227)
			(xy 411.713141 -274.696383) (xy 411.762316 -274.694402) (xy 411.811171 -274.700334) (xy 411.858442 -274.714026)
			(xy 411.902904 -274.735124) (xy 411.943407 -274.76308) (xy 411.9789 -274.797172) (xy 412.008465 -274.836516)
			(xy 412.031336 -274.880093) (xy 412.04692 -274.926774) (xy 412.054815 -274.975351) (xy 412.05531 -274.999958)
			(xy 412.054815 -275.024565) (xy 412.054677 -275.025412) (xy 412.37306 -275.025412) (xy 412.37306 -274.973996)
			(xy 412.381103 -274.923214) (xy 412.396991 -274.874315) (xy 412.420334 -274.828503) (xy 412.450555 -274.786907)
			(xy 412.486911 -274.750551) (xy 412.528507 -274.72033) (xy 412.574319 -274.696987) (xy 412.623218 -274.681099)
			(xy 412.674 -274.673056) (xy 412.725416 -274.673056) (xy 412.776198 -274.681099) (xy 412.825097 -274.696987)
			(xy 412.870909 -274.72033) (xy 412.912505 -274.750551) (xy 412.948861 -274.786907) (xy 412.979082 -274.828503)
			(xy 413.002425 -274.874315) (xy 413.018313 -274.923214) (xy 413.026356 -274.973996) (xy 413.02686 -274.999704)
			(xy 413.026855 -274.999958) (xy 413.344118 -274.999958) (xy 413.348078 -274.950904) (xy 413.359855 -274.90312)
			(xy 413.379146 -274.857844) (xy 413.405449 -274.816248) (xy 413.438084 -274.779411) (xy 413.476205 -274.748286)
			(xy 413.518826 -274.723679) (xy 413.564842 -274.706227) (xy 413.613061 -274.696383) (xy 413.662236 -274.694402)
			(xy 413.711091 -274.700334) (xy 413.758362 -274.714026) (xy 413.802824 -274.735124) (xy 413.843327 -274.76308)
			(xy 413.87882 -274.797172) (xy 413.908385 -274.836516) (xy 413.931256 -274.880093) (xy 413.94684 -274.926774)
			(xy 413.954735 -274.975351) (xy 413.95523 -274.999958) (xy 413.954735 -275.024565) (xy 413.954556 -275.025666)
			(xy 414.27298 -275.025666) (xy 414.27298 -274.97425) (xy 414.281023 -274.923468) (xy 414.296911 -274.874569)
			(xy 414.320254 -274.828757) (xy 414.350475 -274.787161) (xy 414.386831 -274.750805) (xy 414.428427 -274.720584)
			(xy 414.474239 -274.697241) (xy 414.523138 -274.681353) (xy 414.57392 -274.67331) (xy 414.625336 -274.67331)
			(xy 414.676118 -274.681353) (xy 414.725017 -274.697241) (xy 414.770829 -274.720584) (xy 414.812425 -274.750805)
			(xy 414.848781 -274.787161) (xy 414.879002 -274.828757) (xy 414.902345 -274.874569) (xy 414.918233 -274.923468)
			(xy 414.926276 -274.97425) (xy 414.92678 -274.999958) (xy 415.244038 -274.999958) (xy 415.247998 -274.950904)
			(xy 415.259775 -274.90312) (xy 415.279066 -274.857844) (xy 415.305369 -274.816248) (xy 415.338004 -274.779411)
			(xy 415.376125 -274.748286) (xy 415.418746 -274.723679) (xy 415.464762 -274.706227) (xy 415.512981 -274.696383)
			(xy 415.562156 -274.694402) (xy 415.611011 -274.700334) (xy 415.658282 -274.714026) (xy 415.702744 -274.735124)
			(xy 415.743247 -274.76308) (xy 415.77874 -274.797172) (xy 415.808305 -274.836516) (xy 415.831176 -274.880093)
			(xy 415.84676 -274.926774) (xy 415.854655 -274.975351) (xy 415.85515 -274.999958) (xy 415.854655 -275.024565)
			(xy 415.854517 -275.025412) (xy 416.1729 -275.025412) (xy 416.1729 -274.973996) (xy 416.180943 -274.923214)
			(xy 416.196831 -274.874315) (xy 416.220174 -274.828503) (xy 416.250395 -274.786907) (xy 416.286751 -274.750551)
			(xy 416.328347 -274.72033) (xy 416.374159 -274.696987) (xy 416.423058 -274.681099) (xy 416.47384 -274.673056)
			(xy 416.525256 -274.673056) (xy 416.576038 -274.681099) (xy 416.624937 -274.696987) (xy 416.670749 -274.72033)
			(xy 416.712345 -274.750551) (xy 416.748701 -274.786907) (xy 416.778922 -274.828503) (xy 416.802265 -274.874315)
			(xy 416.818153 -274.923214) (xy 416.826196 -274.973996) (xy 416.8267 -274.999704) (xy 416.826695 -274.999958)
			(xy 417.144212 -274.999958) (xy 417.148172 -274.950904) (xy 417.159949 -274.90312) (xy 417.17924 -274.857844)
			(xy 417.205543 -274.816248) (xy 417.238178 -274.779411) (xy 417.276299 -274.748286) (xy 417.31892 -274.723679)
			(xy 417.364936 -274.706227) (xy 417.413155 -274.696383) (xy 417.46233 -274.694402) (xy 417.511185 -274.700334)
			(xy 417.558456 -274.714026) (xy 417.602918 -274.735124) (xy 417.643421 -274.76308) (xy 417.678914 -274.797172)
			(xy 417.708479 -274.836516) (xy 417.73135 -274.880093) (xy 417.746934 -274.926774) (xy 417.754829 -274.975351)
			(xy 417.755324 -274.999958) (xy 417.754829 -275.024565) (xy 417.75465 -275.025666) (xy 418.07282 -275.025666)
			(xy 418.07282 -274.97425) (xy 418.080863 -274.923468) (xy 418.096751 -274.874569) (xy 418.120094 -274.828757)
			(xy 418.150315 -274.787161) (xy 418.186671 -274.750805) (xy 418.228267 -274.720584) (xy 418.274079 -274.697241)
			(xy 418.322978 -274.681353) (xy 418.37376 -274.67331) (xy 418.425176 -274.67331) (xy 418.475958 -274.681353)
			(xy 418.524857 -274.697241) (xy 418.570669 -274.720584) (xy 418.612265 -274.750805) (xy 418.648621 -274.787161)
			(xy 418.678842 -274.828757) (xy 418.702185 -274.874569) (xy 418.718073 -274.923468) (xy 418.726116 -274.97425)
			(xy 418.72662 -274.999958) (xy 419.044132 -274.999958) (xy 419.048092 -274.950904) (xy 419.059869 -274.90312)
			(xy 419.07916 -274.857844) (xy 419.105463 -274.816248) (xy 419.138098 -274.779411) (xy 419.176219 -274.748286)
			(xy 419.21884 -274.723679) (xy 419.264856 -274.706227) (xy 419.313075 -274.696383) (xy 419.36225 -274.694402)
			(xy 419.411105 -274.700334) (xy 419.458376 -274.714026) (xy 419.502838 -274.735124) (xy 419.543341 -274.76308)
			(xy 419.578834 -274.797172) (xy 419.608399 -274.836516) (xy 419.63127 -274.880093) (xy 419.646854 -274.926774)
			(xy 419.654749 -274.975351) (xy 419.655244 -274.999958) (xy 419.654749 -275.024565) (xy 419.654611 -275.025412)
			(xy 419.972994 -275.025412) (xy 419.972994 -274.973996) (xy 419.981037 -274.923214) (xy 419.996925 -274.874315)
			(xy 420.020268 -274.828503) (xy 420.050489 -274.786907) (xy 420.086845 -274.750551) (xy 420.128441 -274.72033)
			(xy 420.174253 -274.696987) (xy 420.223152 -274.681099) (xy 420.273934 -274.673056) (xy 420.32535 -274.673056)
			(xy 420.376132 -274.681099) (xy 420.425031 -274.696987) (xy 420.470843 -274.72033) (xy 420.512439 -274.750551)
			(xy 420.548795 -274.786907) (xy 420.579016 -274.828503) (xy 420.602359 -274.874315) (xy 420.618247 -274.923214)
			(xy 420.62629 -274.973996) (xy 420.626794 -274.999704) (xy 420.626789 -274.999958) (xy 420.944052 -274.999958)
			(xy 420.948012 -274.950904) (xy 420.959789 -274.90312) (xy 420.97908 -274.857844) (xy 421.005383 -274.816248)
			(xy 421.038018 -274.779411) (xy 421.076139 -274.748286) (xy 421.11876 -274.723679) (xy 421.164776 -274.706227)
			(xy 421.212995 -274.696383) (xy 421.26217 -274.694402) (xy 421.311025 -274.700334) (xy 421.358296 -274.714026)
			(xy 421.402758 -274.735124) (xy 421.443261 -274.76308) (xy 421.478754 -274.797172) (xy 421.508319 -274.836516)
			(xy 421.53119 -274.880093) (xy 421.546774 -274.926774) (xy 421.554669 -274.975351) (xy 421.555164 -274.999958)
			(xy 421.554669 -275.024565) (xy 421.55449 -275.025666) (xy 421.872914 -275.025666) (xy 421.872914 -274.97425)
			(xy 421.880957 -274.923468) (xy 421.896845 -274.874569) (xy 421.920188 -274.828757) (xy 421.950409 -274.787161)
			(xy 421.986765 -274.750805) (xy 422.028361 -274.720584) (xy 422.074173 -274.697241) (xy 422.123072 -274.681353)
			(xy 422.173854 -274.67331) (xy 422.22527 -274.67331) (xy 422.276052 -274.681353) (xy 422.324951 -274.697241)
			(xy 422.370763 -274.720584) (xy 422.412359 -274.750805) (xy 422.448715 -274.787161) (xy 422.478936 -274.828757)
			(xy 422.502279 -274.874569) (xy 422.518167 -274.923468) (xy 422.52621 -274.97425) (xy 422.526714 -274.999958)
			(xy 422.843972 -274.999958) (xy 422.847932 -274.950904) (xy 422.859709 -274.90312) (xy 422.879 -274.857844)
			(xy 422.905303 -274.816248) (xy 422.937938 -274.779411) (xy 422.976059 -274.748286) (xy 423.01868 -274.723679)
			(xy 423.064696 -274.706227) (xy 423.112915 -274.696383) (xy 423.16209 -274.694402) (xy 423.210945 -274.700334)
			(xy 423.258216 -274.714026) (xy 423.302678 -274.735124) (xy 423.343181 -274.76308) (xy 423.378674 -274.797172)
			(xy 423.408239 -274.836516) (xy 423.43111 -274.880093) (xy 423.446694 -274.926774) (xy 423.454589 -274.975351)
			(xy 423.455084 -274.999958) (xy 423.454589 -275.024565) (xy 423.454451 -275.025412) (xy 423.773088 -275.025412)
			(xy 423.773088 -274.973996) (xy 423.781131 -274.923214) (xy 423.797019 -274.874315) (xy 423.820362 -274.828503)
			(xy 423.850583 -274.786907) (xy 423.886939 -274.750551) (xy 423.928535 -274.72033) (xy 423.974347 -274.696987)
			(xy 424.023246 -274.681099) (xy 424.074028 -274.673056) (xy 424.125444 -274.673056) (xy 424.176226 -274.681099)
			(xy 424.225125 -274.696987) (xy 424.270937 -274.72033) (xy 424.312533 -274.750551) (xy 424.348889 -274.786907)
			(xy 424.37911 -274.828503) (xy 424.402453 -274.874315) (xy 424.418341 -274.923214) (xy 424.426384 -274.973996)
			(xy 424.426888 -274.999704) (xy 424.426883 -274.999958) (xy 424.743892 -274.999958) (xy 424.747852 -274.950904)
			(xy 424.759629 -274.90312) (xy 424.77892 -274.857844) (xy 424.805223 -274.816248) (xy 424.837858 -274.779411)
			(xy 424.875979 -274.748286) (xy 424.9186 -274.723679) (xy 424.964616 -274.706227) (xy 425.012835 -274.696383)
			(xy 425.06201 -274.694402) (xy 425.110865 -274.700334) (xy 425.158136 -274.714026) (xy 425.202598 -274.735124)
			(xy 425.243101 -274.76308) (xy 425.278594 -274.797172) (xy 425.308159 -274.836516) (xy 425.33103 -274.880093)
			(xy 425.346614 -274.926774) (xy 425.354509 -274.975351) (xy 425.355004 -274.999958) (xy 425.354509 -275.024565)
			(xy 425.35433 -275.025666) (xy 425.673008 -275.025666) (xy 425.673008 -274.97425) (xy 425.681051 -274.923468)
			(xy 425.696939 -274.874569) (xy 425.720282 -274.828757) (xy 425.750503 -274.787161) (xy 425.786859 -274.750805)
			(xy 425.828455 -274.720584) (xy 425.874267 -274.697241) (xy 425.923166 -274.681353) (xy 425.973948 -274.67331)
			(xy 426.025364 -274.67331) (xy 426.076146 -274.681353) (xy 426.125045 -274.697241) (xy 426.170857 -274.720584)
			(xy 426.212453 -274.750805) (xy 426.248809 -274.787161) (xy 426.27903 -274.828757) (xy 426.302373 -274.874569)
			(xy 426.318261 -274.923468) (xy 426.326304 -274.97425) (xy 426.326808 -274.999958) (xy 426.643812 -274.999958)
			(xy 426.647772 -274.950904) (xy 426.659549 -274.90312) (xy 426.67884 -274.857844) (xy 426.705143 -274.816248)
			(xy 426.737778 -274.779411) (xy 426.775899 -274.748286) (xy 426.81852 -274.723679) (xy 426.864536 -274.706227)
			(xy 426.912755 -274.696383) (xy 426.96193 -274.694402) (xy 427.010785 -274.700334) (xy 427.058056 -274.714026)
			(xy 427.102518 -274.735124) (xy 427.143021 -274.76308) (xy 427.178514 -274.797172) (xy 427.208079 -274.836516)
			(xy 427.23095 -274.880093) (xy 427.246534 -274.926774) (xy 427.254429 -274.975351) (xy 427.254924 -274.999958)
			(xy 427.254429 -275.024565) (xy 427.25425 -275.025666) (xy 427.572928 -275.025666) (xy 427.572928 -274.97425)
			(xy 427.580971 -274.923468) (xy 427.596859 -274.874569) (xy 427.620202 -274.828757) (xy 427.650423 -274.787161)
			(xy 427.686779 -274.750805) (xy 427.728375 -274.720584) (xy 427.774187 -274.697241) (xy 427.823086 -274.681353)
			(xy 427.873868 -274.67331) (xy 427.925284 -274.67331) (xy 427.976066 -274.681353) (xy 428.024965 -274.697241)
			(xy 428.070777 -274.720584) (xy 428.112373 -274.750805) (xy 428.148729 -274.787161) (xy 428.17895 -274.828757)
			(xy 428.202293 -274.874569) (xy 428.218181 -274.923468) (xy 428.226224 -274.97425) (xy 428.226728 -274.999958)
			(xy 428.543986 -274.999958) (xy 428.547946 -274.950904) (xy 428.559723 -274.90312) (xy 428.579014 -274.857844)
			(xy 428.605317 -274.816248) (xy 428.637952 -274.779411) (xy 428.676073 -274.748286) (xy 428.718694 -274.723679)
			(xy 428.76471 -274.706227) (xy 428.812929 -274.696383) (xy 428.862104 -274.694402) (xy 428.910959 -274.700334)
			(xy 428.95823 -274.714026) (xy 429.002692 -274.735124) (xy 429.043195 -274.76308) (xy 429.078688 -274.797172)
			(xy 429.108253 -274.836516) (xy 429.131124 -274.880093) (xy 429.146708 -274.926774) (xy 429.154603 -274.975351)
			(xy 429.155098 -274.999958) (xy 429.154603 -275.024565) (xy 429.154465 -275.025412) (xy 429.473356 -275.025412)
			(xy 429.473356 -274.973996) (xy 429.481399 -274.923214) (xy 429.497287 -274.874315) (xy 429.52063 -274.828503)
			(xy 429.550851 -274.786907) (xy 429.587207 -274.750551) (xy 429.628803 -274.72033) (xy 429.674615 -274.696987)
			(xy 429.723514 -274.681099) (xy 429.774296 -274.673056) (xy 429.825712 -274.673056) (xy 429.876494 -274.681099)
			(xy 429.925393 -274.696987) (xy 429.971205 -274.72033) (xy 430.012801 -274.750551) (xy 430.049157 -274.786907)
			(xy 430.079378 -274.828503) (xy 430.102721 -274.874315) (xy 430.118609 -274.923214) (xy 430.126652 -274.973996)
			(xy 430.127156 -274.999704) (xy 430.126652 -275.025412) (xy 430.423316 -275.025412) (xy 430.423316 -274.973996)
			(xy 430.431359 -274.923214) (xy 430.447247 -274.874315) (xy 430.47059 -274.828503) (xy 430.500811 -274.786907)
			(xy 430.537167 -274.750551) (xy 430.578763 -274.72033) (xy 430.624575 -274.696987) (xy 430.673474 -274.681099)
			(xy 430.724256 -274.673056) (xy 430.775672 -274.673056) (xy 430.826454 -274.681099) (xy 430.875353 -274.696987)
			(xy 430.921165 -274.72033) (xy 430.962761 -274.750551) (xy 430.999117 -274.786907) (xy 431.029338 -274.828503)
			(xy 431.052681 -274.874315) (xy 431.068569 -274.923214) (xy 431.076612 -274.973996) (xy 431.077116 -274.999704)
			(xy 431.077111 -274.999958) (xy 431.394374 -274.999958) (xy 431.398334 -274.950904) (xy 431.410111 -274.90312)
			(xy 431.429402 -274.857844) (xy 431.455705 -274.816248) (xy 431.48834 -274.779411) (xy 431.526461 -274.748286)
			(xy 431.569082 -274.723679) (xy 431.615098 -274.706227) (xy 431.663317 -274.696383) (xy 431.712492 -274.694402)
			(xy 431.761347 -274.700334) (xy 431.808618 -274.714026) (xy 431.85308 -274.735124) (xy 431.893583 -274.76308)
			(xy 431.929076 -274.797172) (xy 431.958641 -274.836516) (xy 431.981512 -274.880093) (xy 431.997096 -274.926774)
			(xy 432.004991 -274.975351) (xy 432.005486 -274.999958) (xy 432.004991 -275.024565) (xy 431.997096 -275.073142)
			(xy 431.981512 -275.119823) (xy 431.958641 -275.1634) (xy 431.929076 -275.202744) (xy 431.893583 -275.236836)
			(xy 431.85308 -275.264792) (xy 431.808618 -275.28589) (xy 431.761347 -275.299582) (xy 431.712492 -275.305514)
			(xy 431.663317 -275.303533) (xy 431.615098 -275.293689) (xy 431.569082 -275.276237) (xy 431.526461 -275.25163)
			(xy 431.48834 -275.220505) (xy 431.455705 -275.183668) (xy 431.429402 -275.142072) (xy 431.410111 -275.096796)
			(xy 431.398334 -275.049012) (xy 431.394374 -274.999958) (xy 431.077111 -274.999958) (xy 431.076612 -275.025412)
			(xy 431.068569 -275.076194) (xy 431.052681 -275.125093) (xy 431.029338 -275.170905) (xy 430.999117 -275.212501)
			(xy 430.962761 -275.248857) (xy 430.921165 -275.279078) (xy 430.875353 -275.302421) (xy 430.826454 -275.318309)
			(xy 430.775672 -275.326352) (xy 430.724256 -275.326352) (xy 430.673474 -275.318309) (xy 430.624575 -275.302421)
			(xy 430.578763 -275.279078) (xy 430.537167 -275.248857) (xy 430.500811 -275.212501) (xy 430.47059 -275.170905)
			(xy 430.447247 -275.125093) (xy 430.431359 -275.076194) (xy 430.423316 -275.025412) (xy 430.126652 -275.025412)
			(xy 430.118609 -275.076194) (xy 430.102721 -275.125093) (xy 430.079378 -275.170905) (xy 430.049157 -275.212501)
			(xy 430.012801 -275.248857) (xy 429.971205 -275.279078) (xy 429.925393 -275.302421) (xy 429.876494 -275.318309)
			(xy 429.825712 -275.326352) (xy 429.774296 -275.326352) (xy 429.723514 -275.318309) (xy 429.674615 -275.302421)
			(xy 429.628803 -275.279078) (xy 429.587207 -275.248857) (xy 429.550851 -275.212501) (xy 429.52063 -275.170905)
			(xy 429.497287 -275.125093) (xy 429.481399 -275.076194) (xy 429.473356 -275.025412) (xy 429.154465 -275.025412)
			(xy 429.146708 -275.073142) (xy 429.131124 -275.119823) (xy 429.108253 -275.1634) (xy 429.078688 -275.202744)
			(xy 429.043195 -275.236836) (xy 429.002692 -275.264792) (xy 428.95823 -275.28589) (xy 428.910959 -275.299582)
			(xy 428.862104 -275.305514) (xy 428.812929 -275.303533) (xy 428.76471 -275.293689) (xy 428.718694 -275.276237)
			(xy 428.676073 -275.25163) (xy 428.637952 -275.220505) (xy 428.605317 -275.183668) (xy 428.579014 -275.142072)
			(xy 428.559723 -275.096796) (xy 428.547946 -275.049012) (xy 428.543986 -274.999958) (xy 428.226728 -274.999958)
			(xy 428.226224 -275.025666) (xy 428.218181 -275.076448) (xy 428.202293 -275.125347) (xy 428.17895 -275.171159)
			(xy 428.148729 -275.212755) (xy 428.112373 -275.249111) (xy 428.070777 -275.279332) (xy 428.024965 -275.302675)
			(xy 427.976066 -275.318563) (xy 427.925284 -275.326606) (xy 427.873868 -275.326606) (xy 427.823086 -275.318563)
			(xy 427.774187 -275.302675) (xy 427.728375 -275.279332) (xy 427.686779 -275.249111) (xy 427.650423 -275.212755)
			(xy 427.620202 -275.171159) (xy 427.596859 -275.125347) (xy 427.580971 -275.076448) (xy 427.572928 -275.025666)
			(xy 427.25425 -275.025666) (xy 427.246534 -275.073142) (xy 427.23095 -275.119823) (xy 427.208079 -275.1634)
			(xy 427.178514 -275.202744) (xy 427.143021 -275.236836) (xy 427.102518 -275.264792) (xy 427.058056 -275.28589)
			(xy 427.010785 -275.299582) (xy 426.96193 -275.305514) (xy 426.912755 -275.303533) (xy 426.864536 -275.293689)
			(xy 426.81852 -275.276237) (xy 426.775899 -275.25163) (xy 426.737778 -275.220505) (xy 426.705143 -275.183668)
			(xy 426.67884 -275.142072) (xy 426.659549 -275.096796) (xy 426.647772 -275.049012) (xy 426.643812 -274.999958)
			(xy 426.326808 -274.999958) (xy 426.326304 -275.025666) (xy 426.318261 -275.076448) (xy 426.302373 -275.125347)
			(xy 426.27903 -275.171159) (xy 426.248809 -275.212755) (xy 426.212453 -275.249111) (xy 426.170857 -275.279332)
			(xy 426.125045 -275.302675) (xy 426.076146 -275.318563) (xy 426.025364 -275.326606) (xy 425.973948 -275.326606)
			(xy 425.923166 -275.318563) (xy 425.874267 -275.302675) (xy 425.828455 -275.279332) (xy 425.786859 -275.249111)
			(xy 425.750503 -275.212755) (xy 425.720282 -275.171159) (xy 425.696939 -275.125347) (xy 425.681051 -275.076448)
			(xy 425.673008 -275.025666) (xy 425.35433 -275.025666) (xy 425.346614 -275.073142) (xy 425.33103 -275.119823)
			(xy 425.308159 -275.1634) (xy 425.278594 -275.202744) (xy 425.243101 -275.236836) (xy 425.202598 -275.264792)
			(xy 425.158136 -275.28589) (xy 425.110865 -275.299582) (xy 425.06201 -275.305514) (xy 425.012835 -275.303533)
			(xy 424.964616 -275.293689) (xy 424.9186 -275.276237) (xy 424.875979 -275.25163) (xy 424.837858 -275.220505)
			(xy 424.805223 -275.183668) (xy 424.77892 -275.142072) (xy 424.759629 -275.096796) (xy 424.747852 -275.049012)
			(xy 424.743892 -274.999958) (xy 424.426883 -274.999958) (xy 424.426384 -275.025412) (xy 424.418341 -275.076194)
			(xy 424.402453 -275.125093) (xy 424.37911 -275.170905) (xy 424.348889 -275.212501) (xy 424.312533 -275.248857)
			(xy 424.270937 -275.279078) (xy 424.225125 -275.302421) (xy 424.176226 -275.318309) (xy 424.125444 -275.326352)
			(xy 424.074028 -275.326352) (xy 424.023246 -275.318309) (xy 423.974347 -275.302421) (xy 423.928535 -275.279078)
			(xy 423.886939 -275.248857) (xy 423.850583 -275.212501) (xy 423.820362 -275.170905) (xy 423.797019 -275.125093)
			(xy 423.781131 -275.076194) (xy 423.773088 -275.025412) (xy 423.454451 -275.025412) (xy 423.446694 -275.073142)
			(xy 423.43111 -275.119823) (xy 423.408239 -275.1634) (xy 423.378674 -275.202744) (xy 423.343181 -275.236836)
			(xy 423.302678 -275.264792) (xy 423.258216 -275.28589) (xy 423.210945 -275.299582) (xy 423.16209 -275.305514)
			(xy 423.112915 -275.303533) (xy 423.064696 -275.293689) (xy 423.01868 -275.276237) (xy 422.976059 -275.25163)
			(xy 422.937938 -275.220505) (xy 422.905303 -275.183668) (xy 422.879 -275.142072) (xy 422.859709 -275.096796)
			(xy 422.847932 -275.049012) (xy 422.843972 -274.999958) (xy 422.526714 -274.999958) (xy 422.52621 -275.025666)
			(xy 422.518167 -275.076448) (xy 422.502279 -275.125347) (xy 422.478936 -275.171159) (xy 422.448715 -275.212755)
			(xy 422.412359 -275.249111) (xy 422.370763 -275.279332) (xy 422.324951 -275.302675) (xy 422.276052 -275.318563)
			(xy 422.22527 -275.326606) (xy 422.173854 -275.326606) (xy 422.123072 -275.318563) (xy 422.074173 -275.302675)
			(xy 422.028361 -275.279332) (xy 421.986765 -275.249111) (xy 421.950409 -275.212755) (xy 421.920188 -275.171159)
			(xy 421.896845 -275.125347) (xy 421.880957 -275.076448) (xy 421.872914 -275.025666) (xy 421.55449 -275.025666)
			(xy 421.546774 -275.073142) (xy 421.53119 -275.119823) (xy 421.508319 -275.1634) (xy 421.478754 -275.202744)
			(xy 421.443261 -275.236836) (xy 421.402758 -275.264792) (xy 421.358296 -275.28589) (xy 421.311025 -275.299582)
			(xy 421.26217 -275.305514) (xy 421.212995 -275.303533) (xy 421.164776 -275.293689) (xy 421.11876 -275.276237)
			(xy 421.076139 -275.25163) (xy 421.038018 -275.220505) (xy 421.005383 -275.183668) (xy 420.97908 -275.142072)
			(xy 420.959789 -275.096796) (xy 420.948012 -275.049012) (xy 420.944052 -274.999958) (xy 420.626789 -274.999958)
			(xy 420.62629 -275.025412) (xy 420.618247 -275.076194) (xy 420.602359 -275.125093) (xy 420.579016 -275.170905)
			(xy 420.548795 -275.212501) (xy 420.512439 -275.248857) (xy 420.470843 -275.279078) (xy 420.425031 -275.302421)
			(xy 420.376132 -275.318309) (xy 420.32535 -275.326352) (xy 420.273934 -275.326352) (xy 420.223152 -275.318309)
			(xy 420.174253 -275.302421) (xy 420.128441 -275.279078) (xy 420.086845 -275.248857) (xy 420.050489 -275.212501)
			(xy 420.020268 -275.170905) (xy 419.996925 -275.125093) (xy 419.981037 -275.076194) (xy 419.972994 -275.025412)
			(xy 419.654611 -275.025412) (xy 419.646854 -275.073142) (xy 419.63127 -275.119823) (xy 419.608399 -275.1634)
			(xy 419.578834 -275.202744) (xy 419.543341 -275.236836) (xy 419.502838 -275.264792) (xy 419.458376 -275.28589)
			(xy 419.411105 -275.299582) (xy 419.36225 -275.305514) (xy 419.313075 -275.303533) (xy 419.264856 -275.293689)
			(xy 419.21884 -275.276237) (xy 419.176219 -275.25163) (xy 419.138098 -275.220505) (xy 419.105463 -275.183668)
			(xy 419.07916 -275.142072) (xy 419.059869 -275.096796) (xy 419.048092 -275.049012) (xy 419.044132 -274.999958)
			(xy 418.72662 -274.999958) (xy 418.726116 -275.025666) (xy 418.718073 -275.076448) (xy 418.702185 -275.125347)
			(xy 418.678842 -275.171159) (xy 418.648621 -275.212755) (xy 418.612265 -275.249111) (xy 418.570669 -275.279332)
			(xy 418.524857 -275.302675) (xy 418.475958 -275.318563) (xy 418.425176 -275.326606) (xy 418.37376 -275.326606)
			(xy 418.322978 -275.318563) (xy 418.274079 -275.302675) (xy 418.228267 -275.279332) (xy 418.186671 -275.249111)
			(xy 418.150315 -275.212755) (xy 418.120094 -275.171159) (xy 418.096751 -275.125347) (xy 418.080863 -275.076448)
			(xy 418.07282 -275.025666) (xy 417.75465 -275.025666) (xy 417.746934 -275.073142) (xy 417.73135 -275.119823)
			(xy 417.708479 -275.1634) (xy 417.678914 -275.202744) (xy 417.643421 -275.236836) (xy 417.602918 -275.264792)
			(xy 417.558456 -275.28589) (xy 417.511185 -275.299582) (xy 417.46233 -275.305514) (xy 417.413155 -275.303533)
			(xy 417.364936 -275.293689) (xy 417.31892 -275.276237) (xy 417.276299 -275.25163) (xy 417.238178 -275.220505)
			(xy 417.205543 -275.183668) (xy 417.17924 -275.142072) (xy 417.159949 -275.096796) (xy 417.148172 -275.049012)
			(xy 417.144212 -274.999958) (xy 416.826695 -274.999958) (xy 416.826196 -275.025412) (xy 416.818153 -275.076194)
			(xy 416.802265 -275.125093) (xy 416.778922 -275.170905) (xy 416.748701 -275.212501) (xy 416.712345 -275.248857)
			(xy 416.670749 -275.279078) (xy 416.624937 -275.302421) (xy 416.576038 -275.318309) (xy 416.525256 -275.326352)
			(xy 416.47384 -275.326352) (xy 416.423058 -275.318309) (xy 416.374159 -275.302421) (xy 416.328347 -275.279078)
			(xy 416.286751 -275.248857) (xy 416.250395 -275.212501) (xy 416.220174 -275.170905) (xy 416.196831 -275.125093)
			(xy 416.180943 -275.076194) (xy 416.1729 -275.025412) (xy 415.854517 -275.025412) (xy 415.84676 -275.073142)
			(xy 415.831176 -275.119823) (xy 415.808305 -275.1634) (xy 415.77874 -275.202744) (xy 415.743247 -275.236836)
			(xy 415.702744 -275.264792) (xy 415.658282 -275.28589) (xy 415.611011 -275.299582) (xy 415.562156 -275.305514)
			(xy 415.512981 -275.303533) (xy 415.464762 -275.293689) (xy 415.418746 -275.276237) (xy 415.376125 -275.25163)
			(xy 415.338004 -275.220505) (xy 415.305369 -275.183668) (xy 415.279066 -275.142072) (xy 415.259775 -275.096796)
			(xy 415.247998 -275.049012) (xy 415.244038 -274.999958) (xy 414.92678 -274.999958) (xy 414.926276 -275.025666)
			(xy 414.918233 -275.076448) (xy 414.902345 -275.125347) (xy 414.879002 -275.171159) (xy 414.848781 -275.212755)
			(xy 414.812425 -275.249111) (xy 414.770829 -275.279332) (xy 414.725017 -275.302675) (xy 414.676118 -275.318563)
			(xy 414.625336 -275.326606) (xy 414.57392 -275.326606) (xy 414.523138 -275.318563) (xy 414.474239 -275.302675)
			(xy 414.428427 -275.279332) (xy 414.386831 -275.249111) (xy 414.350475 -275.212755) (xy 414.320254 -275.171159)
			(xy 414.296911 -275.125347) (xy 414.281023 -275.076448) (xy 414.27298 -275.025666) (xy 413.954556 -275.025666)
			(xy 413.94684 -275.073142) (xy 413.931256 -275.119823) (xy 413.908385 -275.1634) (xy 413.87882 -275.202744)
			(xy 413.843327 -275.236836) (xy 413.802824 -275.264792) (xy 413.758362 -275.28589) (xy 413.711091 -275.299582)
			(xy 413.662236 -275.305514) (xy 413.613061 -275.303533) (xy 413.564842 -275.293689) (xy 413.518826 -275.276237)
			(xy 413.476205 -275.25163) (xy 413.438084 -275.220505) (xy 413.405449 -275.183668) (xy 413.379146 -275.142072)
			(xy 413.359855 -275.096796) (xy 413.348078 -275.049012) (xy 413.344118 -274.999958) (xy 413.026855 -274.999958)
			(xy 413.026356 -275.025412) (xy 413.018313 -275.076194) (xy 413.002425 -275.125093) (xy 412.979082 -275.170905)
			(xy 412.948861 -275.212501) (xy 412.912505 -275.248857) (xy 412.870909 -275.279078) (xy 412.825097 -275.302421)
			(xy 412.776198 -275.318309) (xy 412.725416 -275.326352) (xy 412.674 -275.326352) (xy 412.623218 -275.318309)
			(xy 412.574319 -275.302421) (xy 412.528507 -275.279078) (xy 412.486911 -275.248857) (xy 412.450555 -275.212501)
			(xy 412.420334 -275.170905) (xy 412.396991 -275.125093) (xy 412.381103 -275.076194) (xy 412.37306 -275.025412)
			(xy 412.054677 -275.025412) (xy 412.04692 -275.073142) (xy 412.031336 -275.119823) (xy 412.008465 -275.1634)
			(xy 411.9789 -275.202744) (xy 411.943407 -275.236836) (xy 411.902904 -275.264792) (xy 411.858442 -275.28589)
			(xy 411.811171 -275.299582) (xy 411.762316 -275.305514) (xy 411.713141 -275.303533) (xy 411.664922 -275.293689)
			(xy 411.618906 -275.276237) (xy 411.576285 -275.25163) (xy 411.538164 -275.220505) (xy 411.505529 -275.183668)
			(xy 411.479226 -275.142072) (xy 411.459935 -275.096796) (xy 411.448158 -275.049012) (xy 411.444198 -274.999958)
			(xy 411.126686 -274.999958) (xy 411.126182 -275.025666) (xy 411.118139 -275.076448) (xy 411.102251 -275.125347)
			(xy 411.078908 -275.171159) (xy 411.048687 -275.212755) (xy 411.012331 -275.249111) (xy 410.970735 -275.279332)
			(xy 410.924923 -275.302675) (xy 410.876024 -275.318563) (xy 410.825242 -275.326606) (xy 410.773826 -275.326606)
			(xy 410.723044 -275.318563) (xy 410.674145 -275.302675) (xy 410.628333 -275.279332) (xy 410.586737 -275.249111)
			(xy 410.550381 -275.212755) (xy 410.52016 -275.171159) (xy 410.496817 -275.125347) (xy 410.480929 -275.076448)
			(xy 410.472886 -275.025666) (xy 410.154462 -275.025666) (xy 410.146746 -275.073142) (xy 410.131162 -275.119823)
			(xy 410.108291 -275.1634) (xy 410.078726 -275.202744) (xy 410.043233 -275.236836) (xy 410.00273 -275.264792)
			(xy 409.958268 -275.28589) (xy 409.910997 -275.299582) (xy 409.862142 -275.305514) (xy 409.812967 -275.303533)
			(xy 409.764748 -275.293689) (xy 409.718732 -275.276237) (xy 409.676111 -275.25163) (xy 409.63799 -275.220505)
			(xy 409.605355 -275.183668) (xy 409.579052 -275.142072) (xy 409.559761 -275.096796) (xy 409.547984 -275.049012)
			(xy 409.544024 -274.999958) (xy 409.226761 -274.999958) (xy 409.226262 -275.025412) (xy 409.218219 -275.076194)
			(xy 409.202331 -275.125093) (xy 409.178988 -275.170905) (xy 409.148767 -275.212501) (xy 409.112411 -275.248857)
			(xy 409.070815 -275.279078) (xy 409.025003 -275.302421) (xy 408.976104 -275.318309) (xy 408.925322 -275.326352)
			(xy 408.873906 -275.326352) (xy 408.823124 -275.318309) (xy 408.774225 -275.302421) (xy 408.728413 -275.279078)
			(xy 408.686817 -275.248857) (xy 408.650461 -275.212501) (xy 408.62024 -275.170905) (xy 408.596897 -275.125093)
			(xy 408.581009 -275.076194) (xy 408.572966 -275.025412) (xy 408.253667 -275.025412) (xy 408.251601 -275.050344)
			(xy 408.239201 -275.099315) (xy 408.218908 -275.145577) (xy 408.191279 -275.187868) (xy 408.157065 -275.225035)
			(xy 408.117201 -275.256064) (xy 408.072773 -275.280108) (xy 408.024994 -275.296512) (xy 407.975166 -275.304828)
			(xy 407.949908 -275.305266) (xy 407.924848 -275.304732) (xy 407.875407 -275.296503) (xy 407.827968 -275.280328)
			(xy 407.805636 -275.268944) (xy 407.79954 -275.265642) (xy 407.787094 -275.262848) (xy 407.78049 -275.263102)
			(xy 407.774005 -275.263458) (xy 407.761531 -275.267061) (xy 407.755852 -275.270214) (xy 407.680922 -275.314918)
			(xy 407.673302 -275.320506) (xy 407.666523 -275.327047) (xy 407.657784 -275.343719) (xy 407.656284 -275.353018)
			(xy 407.65603 -275.358352) (xy 407.65603 -275.591524) (xy 407.656284 -275.596858) (xy 407.657686 -275.606191)
			(xy 407.66643 -275.622901) (xy 407.673302 -275.62937) (xy 407.680922 -275.634958) (xy 407.755852 -275.679662)
			(xy 407.761536 -275.682801) (xy 407.774008 -275.686397) (xy 407.78049 -275.686774) (xy 407.793698 -275.687282)
			(xy 407.805636 -275.680932) (xy 407.827952 -275.66951) (xy 407.875392 -275.653317) (xy 407.924844 -275.645111)
			(xy 407.949908 -275.64461) (xy 407.975161 -275.645132) (xy 408.024979 -275.653446) (xy 408.072749 -275.669847)
			(xy 408.117168 -275.693886) (xy 408.157025 -275.724909) (xy 408.191231 -275.762068) (xy 408.218856 -275.804351)
			(xy 408.239144 -275.850604) (xy 408.251542 -275.899566) (xy 408.255713 -275.9499) (xy 408.253602 -275.975372)
			(xy 408.572966 -275.975372) (xy 408.572966 -275.923956) (xy 408.581009 -275.873174) (xy 408.596897 -275.824275)
			(xy 408.62024 -275.778463) (xy 408.650461 -275.736867) (xy 408.686817 -275.700511) (xy 408.728413 -275.67029)
			(xy 408.774225 -275.646947) (xy 408.823124 -275.631059) (xy 408.873906 -275.623016) (xy 408.925322 -275.623016)
			(xy 408.976104 -275.631059) (xy 409.025003 -275.646947) (xy 409.070815 -275.67029) (xy 409.112411 -275.700511)
			(xy 409.148767 -275.736867) (xy 409.178988 -275.778463) (xy 409.202331 -275.824275) (xy 409.218219 -275.873174)
			(xy 409.226262 -275.923956) (xy 409.226766 -275.949664) (xy 409.226761 -275.949918) (xy 409.544024 -275.949918)
			(xy 409.547984 -275.900864) (xy 409.559761 -275.85308) (xy 409.579052 -275.807804) (xy 409.605355 -275.766208)
			(xy 409.63799 -275.729371) (xy 409.676111 -275.698246) (xy 409.718732 -275.673639) (xy 409.764748 -275.656187)
			(xy 409.812967 -275.646343) (xy 409.862142 -275.644362) (xy 409.910997 -275.650294) (xy 409.958268 -275.663986)
			(xy 410.00273 -275.685084) (xy 410.043233 -275.71304) (xy 410.078726 -275.747132) (xy 410.108291 -275.786476)
			(xy 410.131162 -275.830053) (xy 410.146746 -275.876734) (xy 410.154641 -275.925311) (xy 410.155136 -275.949918)
			(xy 410.154641 -275.974525) (xy 410.154462 -275.975626) (xy 410.472886 -275.975626) (xy 410.472886 -275.92421)
			(xy 410.480929 -275.873428) (xy 410.496817 -275.824529) (xy 410.52016 -275.778717) (xy 410.550381 -275.737121)
			(xy 410.586737 -275.700765) (xy 410.628333 -275.670544) (xy 410.674145 -275.647201) (xy 410.723044 -275.631313)
			(xy 410.773826 -275.62327) (xy 410.825242 -275.62327) (xy 410.876024 -275.631313) (xy 410.924923 -275.647201)
			(xy 410.970735 -275.670544) (xy 411.012331 -275.700765) (xy 411.048687 -275.737121) (xy 411.078908 -275.778717)
			(xy 411.102251 -275.824529) (xy 411.118139 -275.873428) (xy 411.126182 -275.92421) (xy 411.126686 -275.949918)
			(xy 411.444198 -275.949918) (xy 411.448158 -275.900864) (xy 411.459935 -275.85308) (xy 411.479226 -275.807804)
			(xy 411.505529 -275.766208) (xy 411.538164 -275.729371) (xy 411.576285 -275.698246) (xy 411.618906 -275.673639)
			(xy 411.664922 -275.656187) (xy 411.713141 -275.646343) (xy 411.762316 -275.644362) (xy 411.811171 -275.650294)
			(xy 411.858442 -275.663986) (xy 411.902904 -275.685084) (xy 411.943407 -275.71304) (xy 411.9789 -275.747132)
			(xy 412.008465 -275.786476) (xy 412.031336 -275.830053) (xy 412.04692 -275.876734) (xy 412.054815 -275.925311)
			(xy 412.05531 -275.949918) (xy 412.054815 -275.974525) (xy 412.054677 -275.975372) (xy 412.37306 -275.975372)
			(xy 412.37306 -275.923956) (xy 412.381103 -275.873174) (xy 412.396991 -275.824275) (xy 412.420334 -275.778463)
			(xy 412.450555 -275.736867) (xy 412.486911 -275.700511) (xy 412.528507 -275.67029) (xy 412.574319 -275.646947)
			(xy 412.623218 -275.631059) (xy 412.674 -275.623016) (xy 412.725416 -275.623016) (xy 412.776198 -275.631059)
			(xy 412.825097 -275.646947) (xy 412.870909 -275.67029) (xy 412.912505 -275.700511) (xy 412.948861 -275.736867)
			(xy 412.979082 -275.778463) (xy 413.002425 -275.824275) (xy 413.018313 -275.873174) (xy 413.026356 -275.923956)
			(xy 413.02686 -275.949664) (xy 413.026855 -275.949918) (xy 413.344118 -275.949918) (xy 413.348078 -275.900864)
			(xy 413.359855 -275.85308) (xy 413.379146 -275.807804) (xy 413.405449 -275.766208) (xy 413.438084 -275.729371)
			(xy 413.476205 -275.698246) (xy 413.518826 -275.673639) (xy 413.564842 -275.656187) (xy 413.613061 -275.646343)
			(xy 413.662236 -275.644362) (xy 413.711091 -275.650294) (xy 413.758362 -275.663986) (xy 413.802824 -275.685084)
			(xy 413.843327 -275.71304) (xy 413.87882 -275.747132) (xy 413.908385 -275.786476) (xy 413.931256 -275.830053)
			(xy 413.94684 -275.876734) (xy 413.954735 -275.925311) (xy 413.95523 -275.949918) (xy 413.954735 -275.974525)
			(xy 413.954556 -275.975626) (xy 414.27298 -275.975626) (xy 414.27298 -275.92421) (xy 414.281023 -275.873428)
			(xy 414.296911 -275.824529) (xy 414.320254 -275.778717) (xy 414.350475 -275.737121) (xy 414.386831 -275.700765)
			(xy 414.428427 -275.670544) (xy 414.474239 -275.647201) (xy 414.523138 -275.631313) (xy 414.57392 -275.62327)
			(xy 414.625336 -275.62327) (xy 414.676118 -275.631313) (xy 414.725017 -275.647201) (xy 414.770829 -275.670544)
			(xy 414.812425 -275.700765) (xy 414.848781 -275.737121) (xy 414.879002 -275.778717) (xy 414.902345 -275.824529)
			(xy 414.918233 -275.873428) (xy 414.926276 -275.92421) (xy 414.92678 -275.949918) (xy 415.244038 -275.949918)
			(xy 415.247998 -275.900864) (xy 415.259775 -275.85308) (xy 415.279066 -275.807804) (xy 415.305369 -275.766208)
			(xy 415.338004 -275.729371) (xy 415.376125 -275.698246) (xy 415.418746 -275.673639) (xy 415.464762 -275.656187)
			(xy 415.512981 -275.646343) (xy 415.562156 -275.644362) (xy 415.611011 -275.650294) (xy 415.658282 -275.663986)
			(xy 415.702744 -275.685084) (xy 415.743247 -275.71304) (xy 415.77874 -275.747132) (xy 415.808305 -275.786476)
			(xy 415.831176 -275.830053) (xy 415.84676 -275.876734) (xy 415.854655 -275.925311) (xy 415.85515 -275.949918)
			(xy 415.854655 -275.974525) (xy 415.854517 -275.975372) (xy 416.1729 -275.975372) (xy 416.1729 -275.923956)
			(xy 416.180943 -275.873174) (xy 416.196831 -275.824275) (xy 416.220174 -275.778463) (xy 416.250395 -275.736867)
			(xy 416.286751 -275.700511) (xy 416.328347 -275.67029) (xy 416.374159 -275.646947) (xy 416.423058 -275.631059)
			(xy 416.47384 -275.623016) (xy 416.525256 -275.623016) (xy 416.576038 -275.631059) (xy 416.624937 -275.646947)
			(xy 416.670749 -275.67029) (xy 416.712345 -275.700511) (xy 416.748701 -275.736867) (xy 416.778922 -275.778463)
			(xy 416.802265 -275.824275) (xy 416.818153 -275.873174) (xy 416.826196 -275.923956) (xy 416.8267 -275.949664)
			(xy 416.826695 -275.949918) (xy 417.144212 -275.949918) (xy 417.148172 -275.900864) (xy 417.159949 -275.85308)
			(xy 417.17924 -275.807804) (xy 417.205543 -275.766208) (xy 417.238178 -275.729371) (xy 417.276299 -275.698246)
			(xy 417.31892 -275.673639) (xy 417.364936 -275.656187) (xy 417.413155 -275.646343) (xy 417.46233 -275.644362)
			(xy 417.511185 -275.650294) (xy 417.558456 -275.663986) (xy 417.602918 -275.685084) (xy 417.643421 -275.71304)
			(xy 417.678914 -275.747132) (xy 417.708479 -275.786476) (xy 417.73135 -275.830053) (xy 417.746934 -275.876734)
			(xy 417.754829 -275.925311) (xy 417.755324 -275.949918) (xy 417.754829 -275.974525) (xy 417.75465 -275.975626)
			(xy 418.07282 -275.975626) (xy 418.07282 -275.92421) (xy 418.080863 -275.873428) (xy 418.096751 -275.824529)
			(xy 418.120094 -275.778717) (xy 418.150315 -275.737121) (xy 418.186671 -275.700765) (xy 418.228267 -275.670544)
			(xy 418.274079 -275.647201) (xy 418.322978 -275.631313) (xy 418.37376 -275.62327) (xy 418.425176 -275.62327)
			(xy 418.475958 -275.631313) (xy 418.524857 -275.647201) (xy 418.570669 -275.670544) (xy 418.612265 -275.700765)
			(xy 418.648621 -275.737121) (xy 418.678842 -275.778717) (xy 418.702185 -275.824529) (xy 418.718073 -275.873428)
			(xy 418.726116 -275.92421) (xy 418.72662 -275.949918) (xy 419.044132 -275.949918) (xy 419.048092 -275.900864)
			(xy 419.059869 -275.85308) (xy 419.07916 -275.807804) (xy 419.105463 -275.766208) (xy 419.138098 -275.729371)
			(xy 419.176219 -275.698246) (xy 419.21884 -275.673639) (xy 419.264856 -275.656187) (xy 419.313075 -275.646343)
			(xy 419.36225 -275.644362) (xy 419.411105 -275.650294) (xy 419.458376 -275.663986) (xy 419.502838 -275.685084)
			(xy 419.543341 -275.71304) (xy 419.578834 -275.747132) (xy 419.608399 -275.786476) (xy 419.63127 -275.830053)
			(xy 419.646854 -275.876734) (xy 419.654749 -275.925311) (xy 419.655244 -275.949918) (xy 419.654749 -275.974525)
			(xy 419.654611 -275.975372) (xy 419.972994 -275.975372) (xy 419.972994 -275.923956) (xy 419.981037 -275.873174)
			(xy 419.996925 -275.824275) (xy 420.020268 -275.778463) (xy 420.050489 -275.736867) (xy 420.086845 -275.700511)
			(xy 420.128441 -275.67029) (xy 420.174253 -275.646947) (xy 420.223152 -275.631059) (xy 420.273934 -275.623016)
			(xy 420.32535 -275.623016) (xy 420.376132 -275.631059) (xy 420.425031 -275.646947) (xy 420.470843 -275.67029)
			(xy 420.512439 -275.700511) (xy 420.548795 -275.736867) (xy 420.579016 -275.778463) (xy 420.602359 -275.824275)
			(xy 420.618247 -275.873174) (xy 420.62629 -275.923956) (xy 420.626794 -275.949664) (xy 420.626789 -275.949918)
			(xy 420.944052 -275.949918) (xy 420.948012 -275.900864) (xy 420.959789 -275.85308) (xy 420.97908 -275.807804)
			(xy 421.005383 -275.766208) (xy 421.038018 -275.729371) (xy 421.076139 -275.698246) (xy 421.11876 -275.673639)
			(xy 421.164776 -275.656187) (xy 421.212995 -275.646343) (xy 421.26217 -275.644362) (xy 421.311025 -275.650294)
			(xy 421.358296 -275.663986) (xy 421.402758 -275.685084) (xy 421.443261 -275.71304) (xy 421.478754 -275.747132)
			(xy 421.508319 -275.786476) (xy 421.53119 -275.830053) (xy 421.546774 -275.876734) (xy 421.554669 -275.925311)
			(xy 421.555164 -275.949918) (xy 421.554669 -275.974525) (xy 421.55449 -275.975626) (xy 421.872914 -275.975626)
			(xy 421.872914 -275.92421) (xy 421.880957 -275.873428) (xy 421.896845 -275.824529) (xy 421.920188 -275.778717)
			(xy 421.950409 -275.737121) (xy 421.986765 -275.700765) (xy 422.028361 -275.670544) (xy 422.074173 -275.647201)
			(xy 422.123072 -275.631313) (xy 422.173854 -275.62327) (xy 422.22527 -275.62327) (xy 422.276052 -275.631313)
			(xy 422.324951 -275.647201) (xy 422.370763 -275.670544) (xy 422.412359 -275.700765) (xy 422.448715 -275.737121)
			(xy 422.478936 -275.778717) (xy 422.502279 -275.824529) (xy 422.518167 -275.873428) (xy 422.52621 -275.92421)
			(xy 422.526714 -275.949918) (xy 422.844226 -275.949918) (xy 422.848186 -275.900864) (xy 422.859963 -275.85308)
			(xy 422.879254 -275.807804) (xy 422.905557 -275.766208) (xy 422.938192 -275.729371) (xy 422.976313 -275.698246)
			(xy 423.018934 -275.673639) (xy 423.06495 -275.656187) (xy 423.113169 -275.646343) (xy 423.162344 -275.644362)
			(xy 423.211199 -275.650294) (xy 423.25847 -275.663986) (xy 423.302932 -275.685084) (xy 423.343435 -275.71304)
			(xy 423.378928 -275.747132) (xy 423.408493 -275.786476) (xy 423.431364 -275.830053) (xy 423.446948 -275.876734)
			(xy 423.454843 -275.925311) (xy 423.455338 -275.949918) (xy 423.454843 -275.974525) (xy 423.454705 -275.975372)
			(xy 423.773088 -275.975372) (xy 423.773088 -275.923956) (xy 423.781131 -275.873174) (xy 423.797019 -275.824275)
			(xy 423.820362 -275.778463) (xy 423.850583 -275.736867) (xy 423.886939 -275.700511) (xy 423.928535 -275.67029)
			(xy 423.974347 -275.646947) (xy 424.023246 -275.631059) (xy 424.074028 -275.623016) (xy 424.125444 -275.623016)
			(xy 424.176226 -275.631059) (xy 424.225125 -275.646947) (xy 424.270937 -275.67029) (xy 424.312533 -275.700511)
			(xy 424.348889 -275.736867) (xy 424.37911 -275.778463) (xy 424.402453 -275.824275) (xy 424.418341 -275.873174)
			(xy 424.426384 -275.923956) (xy 424.426888 -275.949664) (xy 424.426883 -275.949918) (xy 424.744146 -275.949918)
			(xy 424.748106 -275.900864) (xy 424.759883 -275.85308) (xy 424.779174 -275.807804) (xy 424.805477 -275.766208)
			(xy 424.838112 -275.729371) (xy 424.876233 -275.698246) (xy 424.918854 -275.673639) (xy 424.96487 -275.656187)
			(xy 425.013089 -275.646343) (xy 425.062264 -275.644362) (xy 425.111119 -275.650294) (xy 425.15839 -275.663986)
			(xy 425.202852 -275.685084) (xy 425.243355 -275.71304) (xy 425.278848 -275.747132) (xy 425.308413 -275.786476)
			(xy 425.331284 -275.830053) (xy 425.346868 -275.876734) (xy 425.354763 -275.925311) (xy 425.355258 -275.949918)
			(xy 425.354763 -275.974525) (xy 425.354584 -275.975626) (xy 425.673008 -275.975626) (xy 425.673008 -275.92421)
			(xy 425.681051 -275.873428) (xy 425.696939 -275.824529) (xy 425.720282 -275.778717) (xy 425.750503 -275.737121)
			(xy 425.786859 -275.700765) (xy 425.828455 -275.670544) (xy 425.874267 -275.647201) (xy 425.923166 -275.631313)
			(xy 425.973948 -275.62327) (xy 426.025364 -275.62327) (xy 426.076146 -275.631313) (xy 426.125045 -275.647201)
			(xy 426.170857 -275.670544) (xy 426.212453 -275.700765) (xy 426.248809 -275.737121) (xy 426.27903 -275.778717)
			(xy 426.302373 -275.824529) (xy 426.318261 -275.873428) (xy 426.326304 -275.92421) (xy 426.326808 -275.949918)
			(xy 426.644066 -275.949918) (xy 426.648026 -275.900864) (xy 426.659803 -275.85308) (xy 426.679094 -275.807804)
			(xy 426.705397 -275.766208) (xy 426.738032 -275.729371) (xy 426.776153 -275.698246) (xy 426.818774 -275.673639)
			(xy 426.86479 -275.656187) (xy 426.913009 -275.646343) (xy 426.962184 -275.644362) (xy 427.011039 -275.650294)
			(xy 427.05831 -275.663986) (xy 427.102772 -275.685084) (xy 427.143275 -275.71304) (xy 427.178768 -275.747132)
			(xy 427.208333 -275.786476) (xy 427.231204 -275.830053) (xy 427.246788 -275.876734) (xy 427.254683 -275.925311)
			(xy 427.255178 -275.949918) (xy 427.254683 -275.974525) (xy 427.254504 -275.975626) (xy 427.572928 -275.975626)
			(xy 427.572928 -275.92421) (xy 427.580971 -275.873428) (xy 427.596859 -275.824529) (xy 427.620202 -275.778717)
			(xy 427.650423 -275.737121) (xy 427.686779 -275.700765) (xy 427.728375 -275.670544) (xy 427.774187 -275.647201)
			(xy 427.823086 -275.631313) (xy 427.873868 -275.62327) (xy 427.925284 -275.62327) (xy 427.976066 -275.631313)
			(xy 428.024965 -275.647201) (xy 428.070777 -275.670544) (xy 428.112373 -275.700765) (xy 428.148729 -275.737121)
			(xy 428.17895 -275.778717) (xy 428.202293 -275.824529) (xy 428.218181 -275.873428) (xy 428.226224 -275.92421)
			(xy 428.226728 -275.949918) (xy 428.54424 -275.949918) (xy 428.5482 -275.900864) (xy 428.559977 -275.85308)
			(xy 428.579268 -275.807804) (xy 428.605571 -275.766208) (xy 428.638206 -275.729371) (xy 428.676327 -275.698246)
			(xy 428.718948 -275.673639) (xy 428.764964 -275.656187) (xy 428.813183 -275.646343) (xy 428.862358 -275.644362)
			(xy 428.911213 -275.650294) (xy 428.958484 -275.663986) (xy 429.002946 -275.685084) (xy 429.043449 -275.71304)
			(xy 429.078942 -275.747132) (xy 429.108507 -275.786476) (xy 429.131378 -275.830053) (xy 429.146962 -275.876734)
			(xy 429.154857 -275.925311) (xy 429.155352 -275.949918) (xy 429.4942 -275.949918) (xy 429.49816 -275.900864)
			(xy 429.509937 -275.85308) (xy 429.529228 -275.807804) (xy 429.555531 -275.766208) (xy 429.588166 -275.729371)
			(xy 429.626287 -275.698246) (xy 429.668908 -275.673639) (xy 429.714924 -275.656187) (xy 429.763143 -275.646343)
			(xy 429.812318 -275.644362) (xy 429.861173 -275.650294) (xy 429.908444 -275.663986) (xy 429.952906 -275.685084)
			(xy 429.993409 -275.71304) (xy 430.028902 -275.747132) (xy 430.058467 -275.786476) (xy 430.081338 -275.830053)
			(xy 430.096922 -275.876734) (xy 430.104817 -275.925311) (xy 430.105312 -275.949918) (xy 430.44416 -275.949918)
			(xy 430.44812 -275.900864) (xy 430.459897 -275.85308) (xy 430.479188 -275.807804) (xy 430.505491 -275.766208)
			(xy 430.538126 -275.729371) (xy 430.576247 -275.698246) (xy 430.618868 -275.673639) (xy 430.664884 -275.656187)
			(xy 430.713103 -275.646343) (xy 430.762278 -275.644362) (xy 430.811133 -275.650294) (xy 430.858404 -275.663986)
			(xy 430.902866 -275.685084) (xy 430.943369 -275.71304) (xy 430.978862 -275.747132) (xy 431.008427 -275.786476)
			(xy 431.031298 -275.830053) (xy 431.046882 -275.876734) (xy 431.054777 -275.925311) (xy 431.055272 -275.949918)
			(xy 431.054777 -275.974525) (xy 431.046882 -276.023102) (xy 431.031298 -276.069783) (xy 431.008427 -276.11336)
			(xy 430.978862 -276.152704) (xy 430.943369 -276.186796) (xy 430.902866 -276.214752) (xy 430.858404 -276.23585)
			(xy 430.811133 -276.249542) (xy 430.762278 -276.255474) (xy 430.713103 -276.253493) (xy 430.664884 -276.243649)
			(xy 430.618868 -276.226197) (xy 430.576247 -276.20159) (xy 430.538126 -276.170465) (xy 430.505491 -276.133628)
			(xy 430.479188 -276.092032) (xy 430.459897 -276.046756) (xy 430.44812 -275.998972) (xy 430.44416 -275.949918)
			(xy 430.105312 -275.949918) (xy 430.104817 -275.974525) (xy 430.096922 -276.023102) (xy 430.081338 -276.069783)
			(xy 430.058467 -276.11336) (xy 430.028902 -276.152704) (xy 429.993409 -276.186796) (xy 429.952906 -276.214752)
			(xy 429.908444 -276.23585) (xy 429.861173 -276.249542) (xy 429.812318 -276.255474) (xy 429.763143 -276.253493)
			(xy 429.714924 -276.243649) (xy 429.668908 -276.226197) (xy 429.626287 -276.20159) (xy 429.588166 -276.170465)
			(xy 429.555531 -276.133628) (xy 429.529228 -276.092032) (xy 429.509937 -276.046756) (xy 429.49816 -275.998972)
			(xy 429.4942 -275.949918) (xy 429.155352 -275.949918) (xy 429.154857 -275.974525) (xy 429.146962 -276.023102)
			(xy 429.131378 -276.069783) (xy 429.108507 -276.11336) (xy 429.078942 -276.152704) (xy 429.043449 -276.186796)
			(xy 429.002946 -276.214752) (xy 428.958484 -276.23585) (xy 428.911213 -276.249542) (xy 428.862358 -276.255474)
			(xy 428.813183 -276.253493) (xy 428.764964 -276.243649) (xy 428.718948 -276.226197) (xy 428.676327 -276.20159)
			(xy 428.638206 -276.170465) (xy 428.605571 -276.133628) (xy 428.579268 -276.092032) (xy 428.559977 -276.046756)
			(xy 428.5482 -275.998972) (xy 428.54424 -275.949918) (xy 428.226728 -275.949918) (xy 428.226224 -275.975626)
			(xy 428.218181 -276.026408) (xy 428.202293 -276.075307) (xy 428.17895 -276.121119) (xy 428.148729 -276.162715)
			(xy 428.112373 -276.199071) (xy 428.070777 -276.229292) (xy 428.024965 -276.252635) (xy 427.976066 -276.268523)
			(xy 427.925284 -276.276566) (xy 427.873868 -276.276566) (xy 427.823086 -276.268523) (xy 427.774187 -276.252635)
			(xy 427.728375 -276.229292) (xy 427.686779 -276.199071) (xy 427.650423 -276.162715) (xy 427.620202 -276.121119)
			(xy 427.596859 -276.075307) (xy 427.580971 -276.026408) (xy 427.572928 -275.975626) (xy 427.254504 -275.975626)
			(xy 427.246788 -276.023102) (xy 427.231204 -276.069783) (xy 427.208333 -276.11336) (xy 427.178768 -276.152704)
			(xy 427.143275 -276.186796) (xy 427.102772 -276.214752) (xy 427.05831 -276.23585) (xy 427.011039 -276.249542)
			(xy 426.962184 -276.255474) (xy 426.913009 -276.253493) (xy 426.86479 -276.243649) (xy 426.818774 -276.226197)
			(xy 426.776153 -276.20159) (xy 426.738032 -276.170465) (xy 426.705397 -276.133628) (xy 426.679094 -276.092032)
			(xy 426.659803 -276.046756) (xy 426.648026 -275.998972) (xy 426.644066 -275.949918) (xy 426.326808 -275.949918)
			(xy 426.326304 -275.975626) (xy 426.318261 -276.026408) (xy 426.302373 -276.075307) (xy 426.27903 -276.121119)
			(xy 426.248809 -276.162715) (xy 426.212453 -276.199071) (xy 426.170857 -276.229292) (xy 426.125045 -276.252635)
			(xy 426.076146 -276.268523) (xy 426.025364 -276.276566) (xy 425.973948 -276.276566) (xy 425.923166 -276.268523)
			(xy 425.874267 -276.252635) (xy 425.828455 -276.229292) (xy 425.786859 -276.199071) (xy 425.750503 -276.162715)
			(xy 425.720282 -276.121119) (xy 425.696939 -276.075307) (xy 425.681051 -276.026408) (xy 425.673008 -275.975626)
			(xy 425.354584 -275.975626) (xy 425.346868 -276.023102) (xy 425.331284 -276.069783) (xy 425.308413 -276.11336)
			(xy 425.278848 -276.152704) (xy 425.243355 -276.186796) (xy 425.202852 -276.214752) (xy 425.15839 -276.23585)
			(xy 425.111119 -276.249542) (xy 425.062264 -276.255474) (xy 425.013089 -276.253493) (xy 424.96487 -276.243649)
			(xy 424.918854 -276.226197) (xy 424.876233 -276.20159) (xy 424.838112 -276.170465) (xy 424.805477 -276.133628)
			(xy 424.779174 -276.092032) (xy 424.759883 -276.046756) (xy 424.748106 -275.998972) (xy 424.744146 -275.949918)
			(xy 424.426883 -275.949918) (xy 424.426384 -275.975372) (xy 424.418341 -276.026154) (xy 424.402453 -276.075053)
			(xy 424.37911 -276.120865) (xy 424.348889 -276.162461) (xy 424.312533 -276.198817) (xy 424.270937 -276.229038)
			(xy 424.225125 -276.252381) (xy 424.176226 -276.268269) (xy 424.125444 -276.276312) (xy 424.074028 -276.276312)
			(xy 424.023246 -276.268269) (xy 423.974347 -276.252381) (xy 423.928535 -276.229038) (xy 423.886939 -276.198817)
			(xy 423.850583 -276.162461) (xy 423.820362 -276.120865) (xy 423.797019 -276.075053) (xy 423.781131 -276.026154)
			(xy 423.773088 -275.975372) (xy 423.454705 -275.975372) (xy 423.446948 -276.023102) (xy 423.431364 -276.069783)
			(xy 423.408493 -276.11336) (xy 423.378928 -276.152704) (xy 423.343435 -276.186796) (xy 423.302932 -276.214752)
			(xy 423.25847 -276.23585) (xy 423.211199 -276.249542) (xy 423.162344 -276.255474) (xy 423.113169 -276.253493)
			(xy 423.06495 -276.243649) (xy 423.018934 -276.226197) (xy 422.976313 -276.20159) (xy 422.938192 -276.170465)
			(xy 422.905557 -276.133628) (xy 422.879254 -276.092032) (xy 422.859963 -276.046756) (xy 422.848186 -275.998972)
			(xy 422.844226 -275.949918) (xy 422.526714 -275.949918) (xy 422.52621 -275.975626) (xy 422.518167 -276.026408)
			(xy 422.502279 -276.075307) (xy 422.478936 -276.121119) (xy 422.448715 -276.162715) (xy 422.412359 -276.199071)
			(xy 422.370763 -276.229292) (xy 422.324951 -276.252635) (xy 422.276052 -276.268523) (xy 422.22527 -276.276566)
			(xy 422.173854 -276.276566) (xy 422.123072 -276.268523) (xy 422.074173 -276.252635) (xy 422.028361 -276.229292)
			(xy 421.986765 -276.199071) (xy 421.950409 -276.162715) (xy 421.920188 -276.121119) (xy 421.896845 -276.075307)
			(xy 421.880957 -276.026408) (xy 421.872914 -275.975626) (xy 421.55449 -275.975626) (xy 421.546774 -276.023102)
			(xy 421.53119 -276.069783) (xy 421.508319 -276.11336) (xy 421.478754 -276.152704) (xy 421.443261 -276.186796)
			(xy 421.402758 -276.214752) (xy 421.358296 -276.23585) (xy 421.311025 -276.249542) (xy 421.26217 -276.255474)
			(xy 421.212995 -276.253493) (xy 421.164776 -276.243649) (xy 421.11876 -276.226197) (xy 421.076139 -276.20159)
			(xy 421.038018 -276.170465) (xy 421.005383 -276.133628) (xy 420.97908 -276.092032) (xy 420.959789 -276.046756)
			(xy 420.948012 -275.998972) (xy 420.944052 -275.949918) (xy 420.626789 -275.949918) (xy 420.62629 -275.975372)
			(xy 420.618247 -276.026154) (xy 420.602359 -276.075053) (xy 420.579016 -276.120865) (xy 420.548795 -276.162461)
			(xy 420.512439 -276.198817) (xy 420.470843 -276.229038) (xy 420.425031 -276.252381) (xy 420.376132 -276.268269)
			(xy 420.32535 -276.276312) (xy 420.273934 -276.276312) (xy 420.223152 -276.268269) (xy 420.174253 -276.252381)
			(xy 420.128441 -276.229038) (xy 420.086845 -276.198817) (xy 420.050489 -276.162461) (xy 420.020268 -276.120865)
			(xy 419.996925 -276.075053) (xy 419.981037 -276.026154) (xy 419.972994 -275.975372) (xy 419.654611 -275.975372)
			(xy 419.646854 -276.023102) (xy 419.63127 -276.069783) (xy 419.608399 -276.11336) (xy 419.578834 -276.152704)
			(xy 419.543341 -276.186796) (xy 419.502838 -276.214752) (xy 419.458376 -276.23585) (xy 419.411105 -276.249542)
			(xy 419.36225 -276.255474) (xy 419.313075 -276.253493) (xy 419.264856 -276.243649) (xy 419.21884 -276.226197)
			(xy 419.176219 -276.20159) (xy 419.138098 -276.170465) (xy 419.105463 -276.133628) (xy 419.07916 -276.092032)
			(xy 419.059869 -276.046756) (xy 419.048092 -275.998972) (xy 419.044132 -275.949918) (xy 418.72662 -275.949918)
			(xy 418.726116 -275.975626) (xy 418.718073 -276.026408) (xy 418.702185 -276.075307) (xy 418.678842 -276.121119)
			(xy 418.648621 -276.162715) (xy 418.612265 -276.199071) (xy 418.570669 -276.229292) (xy 418.524857 -276.252635)
			(xy 418.475958 -276.268523) (xy 418.425176 -276.276566) (xy 418.37376 -276.276566) (xy 418.322978 -276.268523)
			(xy 418.274079 -276.252635) (xy 418.228267 -276.229292) (xy 418.186671 -276.199071) (xy 418.150315 -276.162715)
			(xy 418.120094 -276.121119) (xy 418.096751 -276.075307) (xy 418.080863 -276.026408) (xy 418.07282 -275.975626)
			(xy 417.75465 -275.975626) (xy 417.746934 -276.023102) (xy 417.73135 -276.069783) (xy 417.708479 -276.11336)
			(xy 417.678914 -276.152704) (xy 417.643421 -276.186796) (xy 417.602918 -276.214752) (xy 417.558456 -276.23585)
			(xy 417.511185 -276.249542) (xy 417.46233 -276.255474) (xy 417.413155 -276.253493) (xy 417.364936 -276.243649)
			(xy 417.31892 -276.226197) (xy 417.276299 -276.20159) (xy 417.238178 -276.170465) (xy 417.205543 -276.133628)
			(xy 417.17924 -276.092032) (xy 417.159949 -276.046756) (xy 417.148172 -275.998972) (xy 417.144212 -275.949918)
			(xy 416.826695 -275.949918) (xy 416.826196 -275.975372) (xy 416.818153 -276.026154) (xy 416.802265 -276.075053)
			(xy 416.778922 -276.120865) (xy 416.748701 -276.162461) (xy 416.712345 -276.198817) (xy 416.670749 -276.229038)
			(xy 416.624937 -276.252381) (xy 416.576038 -276.268269) (xy 416.525256 -276.276312) (xy 416.47384 -276.276312)
			(xy 416.423058 -276.268269) (xy 416.374159 -276.252381) (xy 416.328347 -276.229038) (xy 416.286751 -276.198817)
			(xy 416.250395 -276.162461) (xy 416.220174 -276.120865) (xy 416.196831 -276.075053) (xy 416.180943 -276.026154)
			(xy 416.1729 -275.975372) (xy 415.854517 -275.975372) (xy 415.84676 -276.023102) (xy 415.831176 -276.069783)
			(xy 415.808305 -276.11336) (xy 415.77874 -276.152704) (xy 415.743247 -276.186796) (xy 415.702744 -276.214752)
			(xy 415.658282 -276.23585) (xy 415.611011 -276.249542) (xy 415.562156 -276.255474) (xy 415.512981 -276.253493)
			(xy 415.464762 -276.243649) (xy 415.418746 -276.226197) (xy 415.376125 -276.20159) (xy 415.338004 -276.170465)
			(xy 415.305369 -276.133628) (xy 415.279066 -276.092032) (xy 415.259775 -276.046756) (xy 415.247998 -275.998972)
			(xy 415.244038 -275.949918) (xy 414.92678 -275.949918) (xy 414.926276 -275.975626) (xy 414.918233 -276.026408)
			(xy 414.902345 -276.075307) (xy 414.879002 -276.121119) (xy 414.848781 -276.162715) (xy 414.812425 -276.199071)
			(xy 414.770829 -276.229292) (xy 414.725017 -276.252635) (xy 414.676118 -276.268523) (xy 414.625336 -276.276566)
			(xy 414.57392 -276.276566) (xy 414.523138 -276.268523) (xy 414.474239 -276.252635) (xy 414.428427 -276.229292)
			(xy 414.386831 -276.199071) (xy 414.350475 -276.162715) (xy 414.320254 -276.121119) (xy 414.296911 -276.075307)
			(xy 414.281023 -276.026408) (xy 414.27298 -275.975626) (xy 413.954556 -275.975626) (xy 413.94684 -276.023102)
			(xy 413.931256 -276.069783) (xy 413.908385 -276.11336) (xy 413.87882 -276.152704) (xy 413.843327 -276.186796)
			(xy 413.802824 -276.214752) (xy 413.758362 -276.23585) (xy 413.711091 -276.249542) (xy 413.662236 -276.255474)
			(xy 413.613061 -276.253493) (xy 413.564842 -276.243649) (xy 413.518826 -276.226197) (xy 413.476205 -276.20159)
			(xy 413.438084 -276.170465) (xy 413.405449 -276.133628) (xy 413.379146 -276.092032) (xy 413.359855 -276.046756)
			(xy 413.348078 -275.998972) (xy 413.344118 -275.949918) (xy 413.026855 -275.949918) (xy 413.026356 -275.975372)
			(xy 413.018313 -276.026154) (xy 413.002425 -276.075053) (xy 412.979082 -276.120865) (xy 412.948861 -276.162461)
			(xy 412.912505 -276.198817) (xy 412.870909 -276.229038) (xy 412.825097 -276.252381) (xy 412.776198 -276.268269)
			(xy 412.725416 -276.276312) (xy 412.674 -276.276312) (xy 412.623218 -276.268269) (xy 412.574319 -276.252381)
			(xy 412.528507 -276.229038) (xy 412.486911 -276.198817) (xy 412.450555 -276.162461) (xy 412.420334 -276.120865)
			(xy 412.396991 -276.075053) (xy 412.381103 -276.026154) (xy 412.37306 -275.975372) (xy 412.054677 -275.975372)
			(xy 412.04692 -276.023102) (xy 412.031336 -276.069783) (xy 412.008465 -276.11336) (xy 411.9789 -276.152704)
			(xy 411.943407 -276.186796) (xy 411.902904 -276.214752) (xy 411.858442 -276.23585) (xy 411.811171 -276.249542)
			(xy 411.762316 -276.255474) (xy 411.713141 -276.253493) (xy 411.664922 -276.243649) (xy 411.618906 -276.226197)
			(xy 411.576285 -276.20159) (xy 411.538164 -276.170465) (xy 411.505529 -276.133628) (xy 411.479226 -276.092032)
			(xy 411.459935 -276.046756) (xy 411.448158 -275.998972) (xy 411.444198 -275.949918) (xy 411.126686 -275.949918)
			(xy 411.126182 -275.975626) (xy 411.118139 -276.026408) (xy 411.102251 -276.075307) (xy 411.078908 -276.121119)
			(xy 411.048687 -276.162715) (xy 411.012331 -276.199071) (xy 410.970735 -276.229292) (xy 410.924923 -276.252635)
			(xy 410.876024 -276.268523) (xy 410.825242 -276.276566) (xy 410.773826 -276.276566) (xy 410.723044 -276.268523)
			(xy 410.674145 -276.252635) (xy 410.628333 -276.229292) (xy 410.586737 -276.199071) (xy 410.550381 -276.162715)
			(xy 410.52016 -276.121119) (xy 410.496817 -276.075307) (xy 410.480929 -276.026408) (xy 410.472886 -275.975626)
			(xy 410.154462 -275.975626) (xy 410.146746 -276.023102) (xy 410.131162 -276.069783) (xy 410.108291 -276.11336)
			(xy 410.078726 -276.152704) (xy 410.043233 -276.186796) (xy 410.00273 -276.214752) (xy 409.958268 -276.23585)
			(xy 409.910997 -276.249542) (xy 409.862142 -276.255474) (xy 409.812967 -276.253493) (xy 409.764748 -276.243649)
			(xy 409.718732 -276.226197) (xy 409.676111 -276.20159) (xy 409.63799 -276.170465) (xy 409.605355 -276.133628)
			(xy 409.579052 -276.092032) (xy 409.559761 -276.046756) (xy 409.547984 -275.998972) (xy 409.544024 -275.949918)
			(xy 409.226761 -275.949918) (xy 409.226262 -275.975372) (xy 409.218219 -276.026154) (xy 409.202331 -276.075053)
			(xy 409.178988 -276.120865) (xy 409.148767 -276.162461) (xy 409.112411 -276.198817) (xy 409.070815 -276.229038)
			(xy 409.025003 -276.252381) (xy 408.976104 -276.268269) (xy 408.925322 -276.276312) (xy 408.873906 -276.276312)
			(xy 408.823124 -276.268269) (xy 408.774225 -276.252381) (xy 408.728413 -276.229038) (xy 408.686817 -276.198817)
			(xy 408.650461 -276.162461) (xy 408.62024 -276.120865) (xy 408.596897 -276.075053) (xy 408.581009 -276.026154)
			(xy 408.572966 -275.975372) (xy 408.253602 -275.975372) (xy 408.251542 -276.000234) (xy 408.239144 -276.049196)
			(xy 408.218856 -276.095449) (xy 408.191231 -276.137732) (xy 408.157025 -276.174891) (xy 408.117168 -276.205914)
			(xy 408.072749 -276.229953) (xy 408.024979 -276.246354) (xy 407.975161 -276.254668) (xy 407.949908 -276.255226)
			(xy 407.924848 -276.254692) (xy 407.875408 -276.246462) (xy 407.827969 -276.230285) (xy 407.805636 -276.218904)
			(xy 407.79954 -276.215602) (xy 407.787094 -276.212808) (xy 407.78049 -276.213062) (xy 407.774004 -276.213418)
			(xy 407.761529 -276.217018) (xy 407.755852 -276.220174) (xy 407.680922 -276.264878) (xy 407.673302 -276.270466)
			(xy 407.666517 -276.277005) (xy 407.657766 -276.293675) (xy 407.656284 -276.302978) (xy 407.65603 -276.308312)
			(xy 407.65603 -276.492462) (xy 455.756008 -276.492462) (xy 455.760079 -276.43684) (xy 455.772205 -276.382403)
			(xy 455.792128 -276.330312) (xy 455.819424 -276.281677) (xy 455.85351 -276.237534) (xy 455.893659 -276.198825)
			(xy 455.939017 -276.166374) (xy 455.988617 -276.140873) (xy 456.041401 -276.122866) (xy 456.096244 -276.112736)
			(xy 456.151978 -276.110699) (xy 456.207415 -276.116799) (xy 456.261372 -276.130905) (xy 456.312701 -276.152717)
			(xy 456.360307 -276.181771) (xy 456.403175 -276.217446) (xy 456.440392 -276.258983) (xy 456.471165 -276.305496)
			(xy 456.494837 -276.355993) (xy 456.510905 -276.4094) (xy 456.519025 -276.464576) (xy 456.519534 -276.492462)
			(xy 456.519025 -276.520348) (xy 456.510905 -276.575524) (xy 456.494837 -276.628931) (xy 456.488321 -276.64283)
			(xy 461.074006 -276.64283) (xy 461.078077 -276.587208) (xy 461.090203 -276.532771) (xy 461.110126 -276.48068)
			(xy 461.137422 -276.432045) (xy 461.171508 -276.387902) (xy 461.211657 -276.349193) (xy 461.257015 -276.316742)
			(xy 461.306615 -276.291241) (xy 461.359399 -276.273234) (xy 461.414242 -276.263104) (xy 461.469976 -276.261067)
			(xy 461.525413 -276.267167) (xy 461.57937 -276.281273) (xy 461.630699 -276.303085) (xy 461.678305 -276.332139)
			(xy 461.721173 -276.367814) (xy 461.75839 -276.409351) (xy 461.789163 -276.455864) (xy 461.812835 -276.506361)
			(xy 461.828903 -276.559768) (xy 461.837023 -276.614944) (xy 461.837532 -276.64283) (xy 463.093306 -276.64283)
			(xy 463.097377 -276.587208) (xy 463.109503 -276.532771) (xy 463.129426 -276.48068) (xy 463.156722 -276.432045)
			(xy 463.190808 -276.387902) (xy 463.230957 -276.349193) (xy 463.276315 -276.316742) (xy 463.325915 -276.291241)
			(xy 463.378699 -276.273234) (xy 463.433542 -276.263104) (xy 463.489276 -276.261067) (xy 463.544713 -276.267167)
			(xy 463.59867 -276.281273) (xy 463.649999 -276.303085) (xy 463.697605 -276.332139) (xy 463.740473 -276.367814)
			(xy 463.77769 -276.409351) (xy 463.808463 -276.455864) (xy 463.832135 -276.506361) (xy 463.848203 -276.559768)
			(xy 463.856323 -276.614944) (xy 463.856832 -276.64283) (xy 463.856323 -276.670716) (xy 463.848203 -276.725892)
			(xy 463.832135 -276.779299) (xy 463.808463 -276.829796) (xy 463.77769 -276.876309) (xy 463.740473 -276.917846)
			(xy 463.697605 -276.953521) (xy 463.649999 -276.982575) (xy 463.59867 -277.004387) (xy 463.544713 -277.018493)
			(xy 463.489276 -277.024593) (xy 463.433542 -277.022556) (xy 463.378699 -277.012426) (xy 463.325915 -276.994419)
			(xy 463.276315 -276.968918) (xy 463.230957 -276.936467) (xy 463.190808 -276.897758) (xy 463.156722 -276.853615)
			(xy 463.129426 -276.80498) (xy 463.109503 -276.752889) (xy 463.097377 -276.698452) (xy 463.093306 -276.64283)
			(xy 461.837532 -276.64283) (xy 461.837023 -276.670716) (xy 461.828903 -276.725892) (xy 461.812835 -276.779299)
			(xy 461.789163 -276.829796) (xy 461.75839 -276.876309) (xy 461.721173 -276.917846) (xy 461.678305 -276.953521)
			(xy 461.630699 -276.982575) (xy 461.57937 -277.004387) (xy 461.525413 -277.018493) (xy 461.469976 -277.024593)
			(xy 461.414242 -277.022556) (xy 461.359399 -277.012426) (xy 461.306615 -276.994419) (xy 461.257015 -276.968918)
			(xy 461.211657 -276.936467) (xy 461.171508 -276.897758) (xy 461.137422 -276.853615) (xy 461.110126 -276.80498)
			(xy 461.090203 -276.752889) (xy 461.078077 -276.698452) (xy 461.074006 -276.64283) (xy 456.488321 -276.64283)
			(xy 456.471165 -276.679428) (xy 456.440392 -276.725941) (xy 456.403175 -276.767478) (xy 456.360307 -276.803153)
			(xy 456.312701 -276.832207) (xy 456.261372 -276.854019) (xy 456.207415 -276.868125) (xy 456.151978 -276.874225)
			(xy 456.096244 -276.872188) (xy 456.041401 -276.862058) (xy 455.988617 -276.844051) (xy 455.939017 -276.81855)
			(xy 455.893659 -276.786099) (xy 455.85351 -276.74739) (xy 455.819424 -276.703247) (xy 455.792128 -276.654612)
			(xy 455.772205 -276.602521) (xy 455.760079 -276.548084) (xy 455.756008 -276.492462) (xy 407.65603 -276.492462)
			(xy 407.65603 -276.541484) (xy 407.656284 -276.546818) (xy 407.657696 -276.556146) (xy 407.666452 -276.57284)
			(xy 407.673302 -276.57933) (xy 407.680922 -276.584918) (xy 407.755852 -276.629622) (xy 407.761535 -276.632763)
			(xy 407.774007 -276.636362) (xy 407.78049 -276.636734) (xy 407.793698 -276.637242) (xy 407.805636 -276.630892)
			(xy 407.827951 -276.619468) (xy 407.875391 -276.603272) (xy 407.924844 -276.595064) (xy 407.949908 -276.59457)
			(xy 407.975165 -276.595092) (xy 408.024989 -276.603408) (xy 408.072765 -276.61981) (xy 408.11719 -276.643853)
			(xy 408.157052 -276.674879) (xy 408.191263 -276.712044) (xy 408.218891 -276.754332) (xy 408.239182 -276.800591)
			(xy 408.251582 -276.849559) (xy 408.255751 -276.899878) (xy 408.594064 -276.899878) (xy 408.598024 -276.850824)
			(xy 408.609801 -276.80304) (xy 408.629092 -276.757764) (xy 408.655395 -276.716168) (xy 408.68803 -276.679331)
			(xy 408.726151 -276.648206) (xy 408.768772 -276.623599) (xy 408.814788 -276.606147) (xy 408.863007 -276.596303)
			(xy 408.912182 -276.594322) (xy 408.961037 -276.600254) (xy 409.008308 -276.613946) (xy 409.05277 -276.635044)
			(xy 409.093273 -276.663) (xy 409.128766 -276.697092) (xy 409.158331 -276.736436) (xy 409.181202 -276.780013)
			(xy 409.196786 -276.826694) (xy 409.204681 -276.875271) (xy 409.205176 -276.899878) (xy 409.544024 -276.899878)
			(xy 409.547984 -276.850824) (xy 409.559761 -276.80304) (xy 409.579052 -276.757764) (xy 409.605355 -276.716168)
			(xy 409.63799 -276.679331) (xy 409.676111 -276.648206) (xy 409.718732 -276.623599) (xy 409.764748 -276.606147)
			(xy 409.812967 -276.596303) (xy 409.862142 -276.594322) (xy 409.910997 -276.600254) (xy 409.958268 -276.613946)
			(xy 410.00273 -276.635044) (xy 410.043233 -276.663) (xy 410.078726 -276.697092) (xy 410.108291 -276.736436)
			(xy 410.131162 -276.780013) (xy 410.146746 -276.826694) (xy 410.154641 -276.875271) (xy 410.155136 -276.899878)
			(xy 410.493984 -276.899878) (xy 410.497944 -276.850824) (xy 410.509721 -276.80304) (xy 410.529012 -276.757764)
			(xy 410.555315 -276.716168) (xy 410.58795 -276.679331) (xy 410.626071 -276.648206) (xy 410.668692 -276.623599)
			(xy 410.714708 -276.606147) (xy 410.762927 -276.596303) (xy 410.812102 -276.594322) (xy 410.860957 -276.600254)
			(xy 410.908228 -276.613946) (xy 410.95269 -276.635044) (xy 410.993193 -276.663) (xy 411.028686 -276.697092)
			(xy 411.058251 -276.736436) (xy 411.081122 -276.780013) (xy 411.096706 -276.826694) (xy 411.104601 -276.875271)
			(xy 411.105096 -276.899878) (xy 411.444198 -276.899878) (xy 411.448158 -276.850824) (xy 411.459935 -276.80304)
			(xy 411.479226 -276.757764) (xy 411.505529 -276.716168) (xy 411.538164 -276.679331) (xy 411.576285 -276.648206)
			(xy 411.618906 -276.623599) (xy 411.664922 -276.606147) (xy 411.713141 -276.596303) (xy 411.762316 -276.594322)
			(xy 411.811171 -276.600254) (xy 411.858442 -276.613946) (xy 411.902904 -276.635044) (xy 411.943407 -276.663)
			(xy 411.9789 -276.697092) (xy 412.008465 -276.736436) (xy 412.031336 -276.780013) (xy 412.04692 -276.826694)
			(xy 412.054815 -276.875271) (xy 412.05531 -276.899878) (xy 412.394158 -276.899878) (xy 412.398118 -276.850824)
			(xy 412.409895 -276.80304) (xy 412.429186 -276.757764) (xy 412.455489 -276.716168) (xy 412.488124 -276.679331)
			(xy 412.526245 -276.648206) (xy 412.568866 -276.623599) (xy 412.614882 -276.606147) (xy 412.663101 -276.596303)
			(xy 412.712276 -276.594322) (xy 412.761131 -276.600254) (xy 412.808402 -276.613946) (xy 412.852864 -276.635044)
			(xy 412.893367 -276.663) (xy 412.92886 -276.697092) (xy 412.958425 -276.736436) (xy 412.981296 -276.780013)
			(xy 412.99688 -276.826694) (xy 413.004775 -276.875271) (xy 413.00527 -276.899878) (xy 413.344118 -276.899878)
			(xy 413.348078 -276.850824) (xy 413.359855 -276.80304) (xy 413.379146 -276.757764) (xy 413.405449 -276.716168)
			(xy 413.438084 -276.679331) (xy 413.476205 -276.648206) (xy 413.518826 -276.623599) (xy 413.564842 -276.606147)
			(xy 413.613061 -276.596303) (xy 413.662236 -276.594322) (xy 413.711091 -276.600254) (xy 413.758362 -276.613946)
			(xy 413.802824 -276.635044) (xy 413.843327 -276.663) (xy 413.87882 -276.697092) (xy 413.908385 -276.736436)
			(xy 413.931256 -276.780013) (xy 413.94684 -276.826694) (xy 413.954735 -276.875271) (xy 413.95523 -276.899878)
			(xy 414.294078 -276.899878) (xy 414.298038 -276.850824) (xy 414.309815 -276.80304) (xy 414.329106 -276.757764)
			(xy 414.355409 -276.716168) (xy 414.388044 -276.679331) (xy 414.426165 -276.648206) (xy 414.468786 -276.623599)
			(xy 414.514802 -276.606147) (xy 414.563021 -276.596303) (xy 414.612196 -276.594322) (xy 414.661051 -276.600254)
			(xy 414.708322 -276.613946) (xy 414.752784 -276.635044) (xy 414.793287 -276.663) (xy 414.82878 -276.697092)
			(xy 414.858345 -276.736436) (xy 414.881216 -276.780013) (xy 414.8968 -276.826694) (xy 414.904695 -276.875271)
			(xy 414.90519 -276.899878) (xy 415.244038 -276.899878) (xy 415.247998 -276.850824) (xy 415.259775 -276.80304)
			(xy 415.279066 -276.757764) (xy 415.305369 -276.716168) (xy 415.338004 -276.679331) (xy 415.376125 -276.648206)
			(xy 415.418746 -276.623599) (xy 415.464762 -276.606147) (xy 415.512981 -276.596303) (xy 415.562156 -276.594322)
			(xy 415.611011 -276.600254) (xy 415.658282 -276.613946) (xy 415.702744 -276.635044) (xy 415.743247 -276.663)
			(xy 415.77874 -276.697092) (xy 415.808305 -276.736436) (xy 415.831176 -276.780013) (xy 415.84676 -276.826694)
			(xy 415.854655 -276.875271) (xy 415.85515 -276.899878) (xy 416.193998 -276.899878) (xy 416.197958 -276.850824)
			(xy 416.209735 -276.80304) (xy 416.229026 -276.757764) (xy 416.255329 -276.716168) (xy 416.287964 -276.679331)
			(xy 416.326085 -276.648206) (xy 416.368706 -276.623599) (xy 416.414722 -276.606147) (xy 416.462941 -276.596303)
			(xy 416.512116 -276.594322) (xy 416.560971 -276.600254) (xy 416.608242 -276.613946) (xy 416.652704 -276.635044)
			(xy 416.693207 -276.663) (xy 416.7287 -276.697092) (xy 416.758265 -276.736436) (xy 416.781136 -276.780013)
			(xy 416.79672 -276.826694) (xy 416.804615 -276.875271) (xy 416.80511 -276.899878) (xy 417.144212 -276.899878)
			(xy 417.148172 -276.850824) (xy 417.159949 -276.80304) (xy 417.17924 -276.757764) (xy 417.205543 -276.716168)
			(xy 417.238178 -276.679331) (xy 417.276299 -276.648206) (xy 417.31892 -276.623599) (xy 417.364936 -276.606147)
			(xy 417.413155 -276.596303) (xy 417.46233 -276.594322) (xy 417.511185 -276.600254) (xy 417.558456 -276.613946)
			(xy 417.602918 -276.635044) (xy 417.643421 -276.663) (xy 417.678914 -276.697092) (xy 417.708479 -276.736436)
			(xy 417.73135 -276.780013) (xy 417.746934 -276.826694) (xy 417.754829 -276.875271) (xy 417.755324 -276.899878)
			(xy 418.094172 -276.899878) (xy 418.098132 -276.850824) (xy 418.109909 -276.80304) (xy 418.1292 -276.757764)
			(xy 418.155503 -276.716168) (xy 418.188138 -276.679331) (xy 418.226259 -276.648206) (xy 418.26888 -276.623599)
			(xy 418.314896 -276.606147) (xy 418.363115 -276.596303) (xy 418.41229 -276.594322) (xy 418.461145 -276.600254)
			(xy 418.508416 -276.613946) (xy 418.552878 -276.635044) (xy 418.593381 -276.663) (xy 418.628874 -276.697092)
			(xy 418.658439 -276.736436) (xy 418.68131 -276.780013) (xy 418.696894 -276.826694) (xy 418.704789 -276.875271)
			(xy 418.705284 -276.899878) (xy 419.044132 -276.899878) (xy 419.048092 -276.850824) (xy 419.059869 -276.80304)
			(xy 419.07916 -276.757764) (xy 419.105463 -276.716168) (xy 419.138098 -276.679331) (xy 419.176219 -276.648206)
			(xy 419.21884 -276.623599) (xy 419.264856 -276.606147) (xy 419.313075 -276.596303) (xy 419.36225 -276.594322)
			(xy 419.411105 -276.600254) (xy 419.458376 -276.613946) (xy 419.502838 -276.635044) (xy 419.543341 -276.663)
			(xy 419.578834 -276.697092) (xy 419.608399 -276.736436) (xy 419.63127 -276.780013) (xy 419.646854 -276.826694)
			(xy 419.654749 -276.875271) (xy 419.655244 -276.899878) (xy 419.994092 -276.899878) (xy 419.998052 -276.850824)
			(xy 420.009829 -276.80304) (xy 420.02912 -276.757764) (xy 420.055423 -276.716168) (xy 420.088058 -276.679331)
			(xy 420.126179 -276.648206) (xy 420.1688 -276.623599) (xy 420.214816 -276.606147) (xy 420.263035 -276.596303)
			(xy 420.31221 -276.594322) (xy 420.361065 -276.600254) (xy 420.408336 -276.613946) (xy 420.452798 -276.635044)
			(xy 420.493301 -276.663) (xy 420.528794 -276.697092) (xy 420.558359 -276.736436) (xy 420.58123 -276.780013)
			(xy 420.596814 -276.826694) (xy 420.604709 -276.875271) (xy 420.605204 -276.899878) (xy 420.944052 -276.899878)
			(xy 420.948012 -276.850824) (xy 420.959789 -276.80304) (xy 420.97908 -276.757764) (xy 421.005383 -276.716168)
			(xy 421.038018 -276.679331) (xy 421.076139 -276.648206) (xy 421.11876 -276.623599) (xy 421.164776 -276.606147)
			(xy 421.212995 -276.596303) (xy 421.26217 -276.594322) (xy 421.311025 -276.600254) (xy 421.358296 -276.613946)
			(xy 421.402758 -276.635044) (xy 421.443261 -276.663) (xy 421.478754 -276.697092) (xy 421.508319 -276.736436)
			(xy 421.53119 -276.780013) (xy 421.546774 -276.826694) (xy 421.554669 -276.875271) (xy 421.555164 -276.899878)
			(xy 421.893758 -276.899878) (xy 421.897718 -276.850824) (xy 421.909495 -276.80304) (xy 421.928786 -276.757764)
			(xy 421.955089 -276.716168) (xy 421.987724 -276.679331) (xy 422.025845 -276.648206) (xy 422.068466 -276.623599)
			(xy 422.114482 -276.606147) (xy 422.162701 -276.596303) (xy 422.211876 -276.594322) (xy 422.260731 -276.600254)
			(xy 422.308002 -276.613946) (xy 422.352464 -276.635044) (xy 422.392967 -276.663) (xy 422.42846 -276.697092)
			(xy 422.458025 -276.736436) (xy 422.480896 -276.780013) (xy 422.49648 -276.826694) (xy 422.504375 -276.875271)
			(xy 422.50487 -276.899878) (xy 422.843972 -276.899878) (xy 422.847932 -276.850824) (xy 422.859709 -276.80304)
			(xy 422.879 -276.757764) (xy 422.905303 -276.716168) (xy 422.937938 -276.679331) (xy 422.976059 -276.648206)
			(xy 423.01868 -276.623599) (xy 423.064696 -276.606147) (xy 423.112915 -276.596303) (xy 423.16209 -276.594322)
			(xy 423.210945 -276.600254) (xy 423.258216 -276.613946) (xy 423.302678 -276.635044) (xy 423.343181 -276.663)
			(xy 423.378674 -276.697092) (xy 423.408239 -276.736436) (xy 423.43111 -276.780013) (xy 423.446694 -276.826694)
			(xy 423.454589 -276.875271) (xy 423.455084 -276.899878) (xy 423.793932 -276.899878) (xy 423.797892 -276.850824)
			(xy 423.809669 -276.80304) (xy 423.82896 -276.757764) (xy 423.855263 -276.716168) (xy 423.887898 -276.679331)
			(xy 423.926019 -276.648206) (xy 423.96864 -276.623599) (xy 424.014656 -276.606147) (xy 424.062875 -276.596303)
			(xy 424.11205 -276.594322) (xy 424.160905 -276.600254) (xy 424.208176 -276.613946) (xy 424.252638 -276.635044)
			(xy 424.293141 -276.663) (xy 424.328634 -276.697092) (xy 424.358199 -276.736436) (xy 424.38107 -276.780013)
			(xy 424.396654 -276.826694) (xy 424.404549 -276.875271) (xy 424.405044 -276.899878) (xy 424.743892 -276.899878)
			(xy 424.747852 -276.850824) (xy 424.759629 -276.80304) (xy 424.77892 -276.757764) (xy 424.805223 -276.716168)
			(xy 424.837858 -276.679331) (xy 424.875979 -276.648206) (xy 424.9186 -276.623599) (xy 424.964616 -276.606147)
			(xy 425.012835 -276.596303) (xy 425.06201 -276.594322) (xy 425.110865 -276.600254) (xy 425.158136 -276.613946)
			(xy 425.202598 -276.635044) (xy 425.243101 -276.663) (xy 425.278594 -276.697092) (xy 425.308159 -276.736436)
			(xy 425.33103 -276.780013) (xy 425.346614 -276.826694) (xy 425.354509 -276.875271) (xy 425.355004 -276.899878)
			(xy 425.693852 -276.899878) (xy 425.697812 -276.850824) (xy 425.709589 -276.80304) (xy 425.72888 -276.757764)
			(xy 425.755183 -276.716168) (xy 425.787818 -276.679331) (xy 425.825939 -276.648206) (xy 425.86856 -276.623599)
			(xy 425.914576 -276.606147) (xy 425.962795 -276.596303) (xy 426.01197 -276.594322) (xy 426.060825 -276.600254)
			(xy 426.108096 -276.613946) (xy 426.152558 -276.635044) (xy 426.193061 -276.663) (xy 426.228554 -276.697092)
			(xy 426.258119 -276.736436) (xy 426.28099 -276.780013) (xy 426.296574 -276.826694) (xy 426.304469 -276.875271)
			(xy 426.304964 -276.899878) (xy 426.643812 -276.899878) (xy 426.647772 -276.850824) (xy 426.659549 -276.80304)
			(xy 426.67884 -276.757764) (xy 426.705143 -276.716168) (xy 426.737778 -276.679331) (xy 426.775899 -276.648206)
			(xy 426.81852 -276.623599) (xy 426.864536 -276.606147) (xy 426.912755 -276.596303) (xy 426.96193 -276.594322)
			(xy 427.010785 -276.600254) (xy 427.058056 -276.613946) (xy 427.102518 -276.635044) (xy 427.143021 -276.663)
			(xy 427.178514 -276.697092) (xy 427.208079 -276.736436) (xy 427.23095 -276.780013) (xy 427.246534 -276.826694)
			(xy 427.254429 -276.875271) (xy 427.254924 -276.899878) (xy 427.593772 -276.899878) (xy 427.597732 -276.850824)
			(xy 427.609509 -276.80304) (xy 427.6288 -276.757764) (xy 427.655103 -276.716168) (xy 427.687738 -276.679331)
			(xy 427.725859 -276.648206) (xy 427.76848 -276.623599) (xy 427.814496 -276.606147) (xy 427.862715 -276.596303)
			(xy 427.91189 -276.594322) (xy 427.960745 -276.600254) (xy 428.008016 -276.613946) (xy 428.052478 -276.635044)
			(xy 428.092981 -276.663) (xy 428.128474 -276.697092) (xy 428.158039 -276.736436) (xy 428.18091 -276.780013)
			(xy 428.196494 -276.826694) (xy 428.204389 -276.875271) (xy 428.204884 -276.899878) (xy 428.543986 -276.899878)
			(xy 428.547946 -276.850824) (xy 428.559723 -276.80304) (xy 428.579014 -276.757764) (xy 428.605317 -276.716168)
			(xy 428.637952 -276.679331) (xy 428.676073 -276.648206) (xy 428.718694 -276.623599) (xy 428.76471 -276.606147)
			(xy 428.812929 -276.596303) (xy 428.862104 -276.594322) (xy 428.910959 -276.600254) (xy 428.95823 -276.613946)
			(xy 429.002692 -276.635044) (xy 429.043195 -276.663) (xy 429.078688 -276.697092) (xy 429.108253 -276.736436)
			(xy 429.131124 -276.780013) (xy 429.146708 -276.826694) (xy 429.154603 -276.875271) (xy 429.155098 -276.899878)
			(xy 429.154603 -276.924485) (xy 429.154424 -276.925586) (xy 429.473356 -276.925586) (xy 429.473356 -276.87417)
			(xy 429.481399 -276.823388) (xy 429.497287 -276.774489) (xy 429.52063 -276.728677) (xy 429.550851 -276.687081)
			(xy 429.587207 -276.650725) (xy 429.628803 -276.620504) (xy 429.674615 -276.597161) (xy 429.723514 -276.581273)
			(xy 429.774296 -276.57323) (xy 429.825712 -276.57323) (xy 429.876494 -276.581273) (xy 429.925393 -276.597161)
			(xy 429.971205 -276.620504) (xy 430.012801 -276.650725) (xy 430.049157 -276.687081) (xy 430.079378 -276.728677)
			(xy 430.102721 -276.774489) (xy 430.118609 -276.823388) (xy 430.126652 -276.87417) (xy 430.127156 -276.899878)
			(xy 430.126652 -276.925586) (xy 430.423316 -276.925586) (xy 430.423316 -276.87417) (xy 430.431359 -276.823388)
			(xy 430.447247 -276.774489) (xy 430.47059 -276.728677) (xy 430.500811 -276.687081) (xy 430.537167 -276.650725)
			(xy 430.578763 -276.620504) (xy 430.624575 -276.597161) (xy 430.673474 -276.581273) (xy 430.724256 -276.57323)
			(xy 430.775672 -276.57323) (xy 430.826454 -276.581273) (xy 430.875353 -276.597161) (xy 430.921165 -276.620504)
			(xy 430.962761 -276.650725) (xy 430.999117 -276.687081) (xy 431.029338 -276.728677) (xy 431.052681 -276.774489)
			(xy 431.068569 -276.823388) (xy 431.076612 -276.87417) (xy 431.077116 -276.899878) (xy 431.077111 -276.900132)
			(xy 431.394374 -276.900132) (xy 431.398334 -276.851078) (xy 431.410111 -276.803294) (xy 431.429402 -276.758018)
			(xy 431.455705 -276.716422) (xy 431.48834 -276.679585) (xy 431.526461 -276.64846) (xy 431.569082 -276.623853)
			(xy 431.615098 -276.606401) (xy 431.663317 -276.596557) (xy 431.712492 -276.594576) (xy 431.761347 -276.600508)
			(xy 431.808618 -276.6142) (xy 431.85308 -276.635298) (xy 431.893583 -276.663254) (xy 431.929076 -276.697346)
			(xy 431.958641 -276.73669) (xy 431.981512 -276.780267) (xy 431.997096 -276.826948) (xy 432.004991 -276.875525)
			(xy 432.005486 -276.900132) (xy 432.004991 -276.924739) (xy 431.997096 -276.973316) (xy 431.981512 -277.019997)
			(xy 431.958641 -277.063574) (xy 431.929076 -277.102918) (xy 431.893583 -277.13701) (xy 431.85308 -277.164966)
			(xy 431.808618 -277.186064) (xy 431.761347 -277.199756) (xy 431.712492 -277.205688) (xy 431.663317 -277.203707)
			(xy 431.615098 -277.193863) (xy 431.569082 -277.176411) (xy 431.526461 -277.151804) (xy 431.48834 -277.120679)
			(xy 431.455705 -277.083842) (xy 431.429402 -277.042246) (xy 431.410111 -276.99697) (xy 431.398334 -276.949186)
			(xy 431.394374 -276.900132) (xy 431.077111 -276.900132) (xy 431.076612 -276.925586) (xy 431.068569 -276.976368)
			(xy 431.052681 -277.025267) (xy 431.029338 -277.071079) (xy 430.999117 -277.112675) (xy 430.962761 -277.149031)
			(xy 430.921165 -277.179252) (xy 430.875353 -277.202595) (xy 430.826454 -277.218483) (xy 430.775672 -277.226526)
			(xy 430.724256 -277.226526) (xy 430.673474 -277.218483) (xy 430.624575 -277.202595) (xy 430.578763 -277.179252)
			(xy 430.537167 -277.149031) (xy 430.500811 -277.112675) (xy 430.47059 -277.071079) (xy 430.447247 -277.025267)
			(xy 430.431359 -276.976368) (xy 430.423316 -276.925586) (xy 430.126652 -276.925586) (xy 430.118609 -276.976368)
			(xy 430.102721 -277.025267) (xy 430.079378 -277.071079) (xy 430.049157 -277.112675) (xy 430.012801 -277.149031)
			(xy 429.971205 -277.179252) (xy 429.925393 -277.202595) (xy 429.876494 -277.218483) (xy 429.825712 -277.226526)
			(xy 429.774296 -277.226526) (xy 429.723514 -277.218483) (xy 429.674615 -277.202595) (xy 429.628803 -277.179252)
			(xy 429.587207 -277.149031) (xy 429.550851 -277.112675) (xy 429.52063 -277.071079) (xy 429.497287 -277.025267)
			(xy 429.481399 -276.976368) (xy 429.473356 -276.925586) (xy 429.154424 -276.925586) (xy 429.146708 -276.973062)
			(xy 429.131124 -277.019743) (xy 429.108253 -277.06332) (xy 429.078688 -277.102664) (xy 429.043195 -277.136756)
			(xy 429.002692 -277.164712) (xy 428.95823 -277.18581) (xy 428.910959 -277.199502) (xy 428.862104 -277.205434)
			(xy 428.812929 -277.203453) (xy 428.76471 -277.193609) (xy 428.718694 -277.176157) (xy 428.676073 -277.15155)
			(xy 428.637952 -277.120425) (xy 428.605317 -277.083588) (xy 428.579014 -277.041992) (xy 428.559723 -276.996716)
			(xy 428.547946 -276.948932) (xy 428.543986 -276.899878) (xy 428.204884 -276.899878) (xy 428.204389 -276.924485)
			(xy 428.196494 -276.973062) (xy 428.18091 -277.019743) (xy 428.158039 -277.06332) (xy 428.128474 -277.102664)
			(xy 428.092981 -277.136756) (xy 428.052478 -277.164712) (xy 428.008016 -277.18581) (xy 427.960745 -277.199502)
			(xy 427.91189 -277.205434) (xy 427.862715 -277.203453) (xy 427.814496 -277.193609) (xy 427.76848 -277.176157)
			(xy 427.725859 -277.15155) (xy 427.687738 -277.120425) (xy 427.655103 -277.083588) (xy 427.6288 -277.041992)
			(xy 427.609509 -276.996716) (xy 427.597732 -276.948932) (xy 427.593772 -276.899878) (xy 427.254924 -276.899878)
			(xy 427.254429 -276.924485) (xy 427.246534 -276.973062) (xy 427.23095 -277.019743) (xy 427.208079 -277.06332)
			(xy 427.178514 -277.102664) (xy 427.143021 -277.136756) (xy 427.102518 -277.164712) (xy 427.058056 -277.18581)
			(xy 427.010785 -277.199502) (xy 426.96193 -277.205434) (xy 426.912755 -277.203453) (xy 426.864536 -277.193609)
			(xy 426.81852 -277.176157) (xy 426.775899 -277.15155) (xy 426.737778 -277.120425) (xy 426.705143 -277.083588)
			(xy 426.67884 -277.041992) (xy 426.659549 -276.996716) (xy 426.647772 -276.948932) (xy 426.643812 -276.899878)
			(xy 426.304964 -276.899878) (xy 426.304469 -276.924485) (xy 426.296574 -276.973062) (xy 426.28099 -277.019743)
			(xy 426.258119 -277.06332) (xy 426.228554 -277.102664) (xy 426.193061 -277.136756) (xy 426.152558 -277.164712)
			(xy 426.108096 -277.18581) (xy 426.060825 -277.199502) (xy 426.01197 -277.205434) (xy 425.962795 -277.203453)
			(xy 425.914576 -277.193609) (xy 425.86856 -277.176157) (xy 425.825939 -277.15155) (xy 425.787818 -277.120425)
			(xy 425.755183 -277.083588) (xy 425.72888 -277.041992) (xy 425.709589 -276.996716) (xy 425.697812 -276.948932)
			(xy 425.693852 -276.899878) (xy 425.355004 -276.899878) (xy 425.354509 -276.924485) (xy 425.346614 -276.973062)
			(xy 425.33103 -277.019743) (xy 425.308159 -277.06332) (xy 425.278594 -277.102664) (xy 425.243101 -277.136756)
			(xy 425.202598 -277.164712) (xy 425.158136 -277.18581) (xy 425.110865 -277.199502) (xy 425.06201 -277.205434)
			(xy 425.012835 -277.203453) (xy 424.964616 -277.193609) (xy 424.9186 -277.176157) (xy 424.875979 -277.15155)
			(xy 424.837858 -277.120425) (xy 424.805223 -277.083588) (xy 424.77892 -277.041992) (xy 424.759629 -276.996716)
			(xy 424.747852 -276.948932) (xy 424.743892 -276.899878) (xy 424.405044 -276.899878) (xy 424.404549 -276.924485)
			(xy 424.396654 -276.973062) (xy 424.38107 -277.019743) (xy 424.358199 -277.06332) (xy 424.328634 -277.102664)
			(xy 424.293141 -277.136756) (xy 424.252638 -277.164712) (xy 424.208176 -277.18581) (xy 424.160905 -277.199502)
			(xy 424.11205 -277.205434) (xy 424.062875 -277.203453) (xy 424.014656 -277.193609) (xy 423.96864 -277.176157)
			(xy 423.926019 -277.15155) (xy 423.887898 -277.120425) (xy 423.855263 -277.083588) (xy 423.82896 -277.041992)
			(xy 423.809669 -276.996716) (xy 423.797892 -276.948932) (xy 423.793932 -276.899878) (xy 423.455084 -276.899878)
			(xy 423.454589 -276.924485) (xy 423.446694 -276.973062) (xy 423.43111 -277.019743) (xy 423.408239 -277.06332)
			(xy 423.378674 -277.102664) (xy 423.343181 -277.136756) (xy 423.302678 -277.164712) (xy 423.258216 -277.18581)
			(xy 423.210945 -277.199502) (xy 423.16209 -277.205434) (xy 423.112915 -277.203453) (xy 423.064696 -277.193609)
			(xy 423.01868 -277.176157) (xy 422.976059 -277.15155) (xy 422.937938 -277.120425) (xy 422.905303 -277.083588)
			(xy 422.879 -277.041992) (xy 422.859709 -276.996716) (xy 422.847932 -276.948932) (xy 422.843972 -276.899878)
			(xy 422.50487 -276.899878) (xy 422.504375 -276.924485) (xy 422.49648 -276.973062) (xy 422.480896 -277.019743)
			(xy 422.458025 -277.06332) (xy 422.42846 -277.102664) (xy 422.392967 -277.136756) (xy 422.352464 -277.164712)
			(xy 422.308002 -277.18581) (xy 422.260731 -277.199502) (xy 422.211876 -277.205434) (xy 422.162701 -277.203453)
			(xy 422.114482 -277.193609) (xy 422.068466 -277.176157) (xy 422.025845 -277.15155) (xy 421.987724 -277.120425)
			(xy 421.955089 -277.083588) (xy 421.928786 -277.041992) (xy 421.909495 -276.996716) (xy 421.897718 -276.948932)
			(xy 421.893758 -276.899878) (xy 421.555164 -276.899878) (xy 421.554669 -276.924485) (xy 421.546774 -276.973062)
			(xy 421.53119 -277.019743) (xy 421.508319 -277.06332) (xy 421.478754 -277.102664) (xy 421.443261 -277.136756)
			(xy 421.402758 -277.164712) (xy 421.358296 -277.18581) (xy 421.311025 -277.199502) (xy 421.26217 -277.205434)
			(xy 421.212995 -277.203453) (xy 421.164776 -277.193609) (xy 421.11876 -277.176157) (xy 421.076139 -277.15155)
			(xy 421.038018 -277.120425) (xy 421.005383 -277.083588) (xy 420.97908 -277.041992) (xy 420.959789 -276.996716)
			(xy 420.948012 -276.948932) (xy 420.944052 -276.899878) (xy 420.605204 -276.899878) (xy 420.604709 -276.924485)
			(xy 420.596814 -276.973062) (xy 420.58123 -277.019743) (xy 420.558359 -277.06332) (xy 420.528794 -277.102664)
			(xy 420.493301 -277.136756) (xy 420.452798 -277.164712) (xy 420.408336 -277.18581) (xy 420.361065 -277.199502)
			(xy 420.31221 -277.205434) (xy 420.263035 -277.203453) (xy 420.214816 -277.193609) (xy 420.1688 -277.176157)
			(xy 420.126179 -277.15155) (xy 420.088058 -277.120425) (xy 420.055423 -277.083588) (xy 420.02912 -277.041992)
			(xy 420.009829 -276.996716) (xy 419.998052 -276.948932) (xy 419.994092 -276.899878) (xy 419.655244 -276.899878)
			(xy 419.654749 -276.924485) (xy 419.646854 -276.973062) (xy 419.63127 -277.019743) (xy 419.608399 -277.06332)
			(xy 419.578834 -277.102664) (xy 419.543341 -277.136756) (xy 419.502838 -277.164712) (xy 419.458376 -277.18581)
			(xy 419.411105 -277.199502) (xy 419.36225 -277.205434) (xy 419.313075 -277.203453) (xy 419.264856 -277.193609)
			(xy 419.21884 -277.176157) (xy 419.176219 -277.15155) (xy 419.138098 -277.120425) (xy 419.105463 -277.083588)
			(xy 419.07916 -277.041992) (xy 419.059869 -276.996716) (xy 419.048092 -276.948932) (xy 419.044132 -276.899878)
			(xy 418.705284 -276.899878) (xy 418.704789 -276.924485) (xy 418.696894 -276.973062) (xy 418.68131 -277.019743)
			(xy 418.658439 -277.06332) (xy 418.628874 -277.102664) (xy 418.593381 -277.136756) (xy 418.552878 -277.164712)
			(xy 418.508416 -277.18581) (xy 418.461145 -277.199502) (xy 418.41229 -277.205434) (xy 418.363115 -277.203453)
			(xy 418.314896 -277.193609) (xy 418.26888 -277.176157) (xy 418.226259 -277.15155) (xy 418.188138 -277.120425)
			(xy 418.155503 -277.083588) (xy 418.1292 -277.041992) (xy 418.109909 -276.996716) (xy 418.098132 -276.948932)
			(xy 418.094172 -276.899878) (xy 417.755324 -276.899878) (xy 417.754829 -276.924485) (xy 417.746934 -276.973062)
			(xy 417.73135 -277.019743) (xy 417.708479 -277.06332) (xy 417.678914 -277.102664) (xy 417.643421 -277.136756)
			(xy 417.602918 -277.164712) (xy 417.558456 -277.18581) (xy 417.511185 -277.199502) (xy 417.46233 -277.205434)
			(xy 417.413155 -277.203453) (xy 417.364936 -277.193609) (xy 417.31892 -277.176157) (xy 417.276299 -277.15155)
			(xy 417.238178 -277.120425) (xy 417.205543 -277.083588) (xy 417.17924 -277.041992) (xy 417.159949 -276.996716)
			(xy 417.148172 -276.948932) (xy 417.144212 -276.899878) (xy 416.80511 -276.899878) (xy 416.804615 -276.924485)
			(xy 416.79672 -276.973062) (xy 416.781136 -277.019743) (xy 416.758265 -277.06332) (xy 416.7287 -277.102664)
			(xy 416.693207 -277.136756) (xy 416.652704 -277.164712) (xy 416.608242 -277.18581) (xy 416.560971 -277.199502)
			(xy 416.512116 -277.205434) (xy 416.462941 -277.203453) (xy 416.414722 -277.193609) (xy 416.368706 -277.176157)
			(xy 416.326085 -277.15155) (xy 416.287964 -277.120425) (xy 416.255329 -277.083588) (xy 416.229026 -277.041992)
			(xy 416.209735 -276.996716) (xy 416.197958 -276.948932) (xy 416.193998 -276.899878) (xy 415.85515 -276.899878)
			(xy 415.854655 -276.924485) (xy 415.84676 -276.973062) (xy 415.831176 -277.019743) (xy 415.808305 -277.06332)
			(xy 415.77874 -277.102664) (xy 415.743247 -277.136756) (xy 415.702744 -277.164712) (xy 415.658282 -277.18581)
			(xy 415.611011 -277.199502) (xy 415.562156 -277.205434) (xy 415.512981 -277.203453) (xy 415.464762 -277.193609)
			(xy 415.418746 -277.176157) (xy 415.376125 -277.15155) (xy 415.338004 -277.120425) (xy 415.305369 -277.083588)
			(xy 415.279066 -277.041992) (xy 415.259775 -276.996716) (xy 415.247998 -276.948932) (xy 415.244038 -276.899878)
			(xy 414.90519 -276.899878) (xy 414.904695 -276.924485) (xy 414.8968 -276.973062) (xy 414.881216 -277.019743)
			(xy 414.858345 -277.06332) (xy 414.82878 -277.102664) (xy 414.793287 -277.136756) (xy 414.752784 -277.164712)
			(xy 414.708322 -277.18581) (xy 414.661051 -277.199502) (xy 414.612196 -277.205434) (xy 414.563021 -277.203453)
			(xy 414.514802 -277.193609) (xy 414.468786 -277.176157) (xy 414.426165 -277.15155) (xy 414.388044 -277.120425)
			(xy 414.355409 -277.083588) (xy 414.329106 -277.041992) (xy 414.309815 -276.996716) (xy 414.298038 -276.948932)
			(xy 414.294078 -276.899878) (xy 413.95523 -276.899878) (xy 413.954735 -276.924485) (xy 413.94684 -276.973062)
			(xy 413.931256 -277.019743) (xy 413.908385 -277.06332) (xy 413.87882 -277.102664) (xy 413.843327 -277.136756)
			(xy 413.802824 -277.164712) (xy 413.758362 -277.18581) (xy 413.711091 -277.199502) (xy 413.662236 -277.205434)
			(xy 413.613061 -277.203453) (xy 413.564842 -277.193609) (xy 413.518826 -277.176157) (xy 413.476205 -277.15155)
			(xy 413.438084 -277.120425) (xy 413.405449 -277.083588) (xy 413.379146 -277.041992) (xy 413.359855 -276.996716)
			(xy 413.348078 -276.948932) (xy 413.344118 -276.899878) (xy 413.00527 -276.899878) (xy 413.004775 -276.924485)
			(xy 412.99688 -276.973062) (xy 412.981296 -277.019743) (xy 412.958425 -277.06332) (xy 412.92886 -277.102664)
			(xy 412.893367 -277.136756) (xy 412.852864 -277.164712) (xy 412.808402 -277.18581) (xy 412.761131 -277.199502)
			(xy 412.712276 -277.205434) (xy 412.663101 -277.203453) (xy 412.614882 -277.193609) (xy 412.568866 -277.176157)
			(xy 412.526245 -277.15155) (xy 412.488124 -277.120425) (xy 412.455489 -277.083588) (xy 412.429186 -277.041992)
			(xy 412.409895 -276.996716) (xy 412.398118 -276.948932) (xy 412.394158 -276.899878) (xy 412.05531 -276.899878)
			(xy 412.054815 -276.924485) (xy 412.04692 -276.973062) (xy 412.031336 -277.019743) (xy 412.008465 -277.06332)
			(xy 411.9789 -277.102664) (xy 411.943407 -277.136756) (xy 411.902904 -277.164712) (xy 411.858442 -277.18581)
			(xy 411.811171 -277.199502) (xy 411.762316 -277.205434) (xy 411.713141 -277.203453) (xy 411.664922 -277.193609)
			(xy 411.618906 -277.176157) (xy 411.576285 -277.15155) (xy 411.538164 -277.120425) (xy 411.505529 -277.083588)
			(xy 411.479226 -277.041992) (xy 411.459935 -276.996716) (xy 411.448158 -276.948932) (xy 411.444198 -276.899878)
			(xy 411.105096 -276.899878) (xy 411.104601 -276.924485) (xy 411.096706 -276.973062) (xy 411.081122 -277.019743)
			(xy 411.058251 -277.06332) (xy 411.028686 -277.102664) (xy 410.993193 -277.136756) (xy 410.95269 -277.164712)
			(xy 410.908228 -277.18581) (xy 410.860957 -277.199502) (xy 410.812102 -277.205434) (xy 410.762927 -277.203453)
			(xy 410.714708 -277.193609) (xy 410.668692 -277.176157) (xy 410.626071 -277.15155) (xy 410.58795 -277.120425)
			(xy 410.555315 -277.083588) (xy 410.529012 -277.041992) (xy 410.509721 -276.996716) (xy 410.497944 -276.948932)
			(xy 410.493984 -276.899878) (xy 410.155136 -276.899878) (xy 410.154641 -276.924485) (xy 410.146746 -276.973062)
			(xy 410.131162 -277.019743) (xy 410.108291 -277.06332) (xy 410.078726 -277.102664) (xy 410.043233 -277.136756)
			(xy 410.00273 -277.164712) (xy 409.958268 -277.18581) (xy 409.910997 -277.199502) (xy 409.862142 -277.205434)
			(xy 409.812967 -277.203453) (xy 409.764748 -277.193609) (xy 409.718732 -277.176157) (xy 409.676111 -277.15155)
			(xy 409.63799 -277.120425) (xy 409.605355 -277.083588) (xy 409.579052 -277.041992) (xy 409.559761 -276.996716)
			(xy 409.547984 -276.948932) (xy 409.544024 -276.899878) (xy 409.205176 -276.899878) (xy 409.204681 -276.924485)
			(xy 409.196786 -276.973062) (xy 409.181202 -277.019743) (xy 409.158331 -277.06332) (xy 409.128766 -277.102664)
			(xy 409.093273 -277.136756) (xy 409.05277 -277.164712) (xy 409.008308 -277.18581) (xy 408.961037 -277.199502)
			(xy 408.912182 -277.205434) (xy 408.863007 -277.203453) (xy 408.814788 -277.193609) (xy 408.768772 -277.176157)
			(xy 408.726151 -277.15155) (xy 408.68803 -277.120425) (xy 408.655395 -277.083588) (xy 408.629092 -277.041992)
			(xy 408.609801 -276.996716) (xy 408.598024 -276.948932) (xy 408.594064 -276.899878) (xy 408.255751 -276.899878)
			(xy 408.255753 -276.8999) (xy 408.251582 -276.950241) (xy 408.239182 -276.999209) (xy 408.218891 -277.045468)
			(xy 408.191263 -277.087756) (xy 408.157052 -277.124921) (xy 408.11719 -277.155947) (xy 408.072765 -277.17999)
			(xy 408.024989 -277.196392) (xy 407.975165 -277.204708) (xy 407.949908 -277.205186) (xy 407.924848 -277.204653)
			(xy 407.875407 -277.196423) (xy 407.827967 -277.180249) (xy 407.805636 -277.168864) (xy 407.79954 -277.165562)
			(xy 407.787094 -277.162768) (xy 407.78049 -277.163022) (xy 407.774004 -277.163377) (xy 407.761527 -277.166975)
			(xy 407.755852 -277.170134) (xy 407.680922 -277.214838) (xy 407.673302 -277.220426) (xy 407.666525 -277.226968)
			(xy 407.657793 -277.243641) (xy 407.656284 -277.252938) (xy 407.65603 -277.258272) (xy 407.65603 -277.336758)
			(xy 458.091284 -277.336758) (xy 458.095355 -277.281136) (xy 458.107481 -277.226699) (xy 458.127404 -277.174608)
			(xy 458.1547 -277.125973) (xy 458.188786 -277.08183) (xy 458.228935 -277.043121) (xy 458.274293 -277.01067)
			(xy 458.323893 -276.985169) (xy 458.376677 -276.967162) (xy 458.43152 -276.957032) (xy 458.487254 -276.954995)
			(xy 458.542691 -276.961095) (xy 458.596648 -276.975201) (xy 458.647977 -276.997013) (xy 458.695583 -277.026067)
			(xy 458.738451 -277.061742) (xy 458.775668 -277.103279) (xy 458.806441 -277.149792) (xy 458.830113 -277.200289)
			(xy 458.846181 -277.253696) (xy 458.854301 -277.308872) (xy 458.854601 -277.325328) (xy 459.280766 -277.325328)
			(xy 459.284837 -277.269706) (xy 459.296963 -277.215269) (xy 459.316886 -277.163178) (xy 459.344182 -277.114543)
			(xy 459.378268 -277.0704) (xy 459.418417 -277.031691) (xy 459.463775 -276.99924) (xy 459.513375 -276.973739)
			(xy 459.566159 -276.955732) (xy 459.621002 -276.945602) (xy 459.676736 -276.943565) (xy 459.732173 -276.949665)
			(xy 459.78613 -276.963771) (xy 459.837459 -276.985583) (xy 459.885065 -277.014637) (xy 459.927933 -277.050312)
			(xy 459.96515 -277.091849) (xy 459.995923 -277.138362) (xy 460.019595 -277.188859) (xy 460.035663 -277.242266)
			(xy 460.043783 -277.297442) (xy 460.044292 -277.325328) (xy 460.043783 -277.353214) (xy 460.035663 -277.40839)
			(xy 460.019595 -277.461797) (xy 459.995923 -277.512294) (xy 459.96515 -277.558807) (xy 459.927933 -277.600344)
			(xy 459.885065 -277.636019) (xy 459.837459 -277.665073) (xy 459.78613 -277.686885) (xy 459.732173 -277.700991)
			(xy 459.676736 -277.707091) (xy 459.621002 -277.705054) (xy 459.566159 -277.694924) (xy 459.513375 -277.676917)
			(xy 459.463775 -277.651416) (xy 459.418417 -277.618965) (xy 459.378268 -277.580256) (xy 459.344182 -277.536113)
			(xy 459.316886 -277.487478) (xy 459.296963 -277.435387) (xy 459.284837 -277.38095) (xy 459.280766 -277.325328)
			(xy 458.854601 -277.325328) (xy 458.85481 -277.336758) (xy 458.854301 -277.364644) (xy 458.846181 -277.41982)
			(xy 458.830113 -277.473227) (xy 458.806441 -277.523724) (xy 458.775668 -277.570237) (xy 458.738451 -277.611774)
			(xy 458.695583 -277.647449) (xy 458.647977 -277.676503) (xy 458.596648 -277.698315) (xy 458.542691 -277.712421)
			(xy 458.487254 -277.718521) (xy 458.43152 -277.716484) (xy 458.376677 -277.706354) (xy 458.323893 -277.688347)
			(xy 458.274293 -277.662846) (xy 458.228935 -277.630395) (xy 458.188786 -277.591686) (xy 458.1547 -277.547543)
			(xy 458.127404 -277.498908) (xy 458.107481 -277.446817) (xy 458.095355 -277.39238) (xy 458.091284 -277.336758)
			(xy 407.65603 -277.336758) (xy 407.65603 -277.466806) (xy 407.656538 -277.474172) (xy 407.658635 -277.484782)
			(xy 407.670339 -277.502946) (xy 407.679144 -277.509224) (xy 407.679652 -277.509732) (xy 407.68016 -277.509986)
			(xy 407.753566 -277.555198) (xy 407.759262 -277.558527) (xy 407.771875 -277.562384) (xy 407.778458 -277.562818)
			(xy 407.791158 -277.563326) (xy 407.802842 -277.557484) (xy 407.80335 -277.557484) (xy 407.826104 -277.54662)
			(xy 407.874124 -277.531252) (xy 407.923937 -277.523448) (xy 407.949146 -277.52294) (xy 407.949654 -277.52294)
			(xy 407.975343 -277.523414) (xy 408.02609 -277.531445) (xy 408.074955 -277.547316) (xy 408.120736 -277.570637)
			(xy 408.162305 -277.600833) (xy 408.198637 -277.63716) (xy 408.228839 -277.678725) (xy 408.252166 -277.724502)
			(xy 408.268044 -277.773365) (xy 408.276082 -277.824111) (xy 408.276082 -277.849838) (xy 408.594064 -277.849838)
			(xy 408.598024 -277.800784) (xy 408.609801 -277.753) (xy 408.629092 -277.707724) (xy 408.655395 -277.666128)
			(xy 408.68803 -277.629291) (xy 408.726151 -277.598166) (xy 408.768772 -277.573559) (xy 408.814788 -277.556107)
			(xy 408.863007 -277.546263) (xy 408.912182 -277.544282) (xy 408.961037 -277.550214) (xy 409.008308 -277.563906)
			(xy 409.05277 -277.585004) (xy 409.093273 -277.61296) (xy 409.128766 -277.647052) (xy 409.158331 -277.686396)
			(xy 409.181202 -277.729973) (xy 409.196786 -277.776654) (xy 409.204681 -277.825231) (xy 409.205176 -277.849838)
			(xy 409.204681 -277.874445) (xy 409.204502 -277.875546) (xy 409.522926 -277.875546) (xy 409.522926 -277.82413)
			(xy 409.530969 -277.773348) (xy 409.546857 -277.724449) (xy 409.5702 -277.678637) (xy 409.600421 -277.637041)
			(xy 409.636777 -277.600685) (xy 409.678373 -277.570464) (xy 409.724185 -277.547121) (xy 409.773084 -277.531233)
			(xy 409.823866 -277.52319) (xy 409.875282 -277.52319) (xy 409.926064 -277.531233) (xy 409.974963 -277.547121)
			(xy 410.020775 -277.570464) (xy 410.062371 -277.600685) (xy 410.098727 -277.637041) (xy 410.128948 -277.678637)
			(xy 410.152291 -277.724449) (xy 410.168179 -277.773348) (xy 410.176222 -277.82413) (xy 410.176726 -277.849838)
			(xy 410.493984 -277.849838) (xy 410.497944 -277.800784) (xy 410.509721 -277.753) (xy 410.529012 -277.707724)
			(xy 410.555315 -277.666128) (xy 410.58795 -277.629291) (xy 410.626071 -277.598166) (xy 410.668692 -277.573559)
			(xy 410.714708 -277.556107) (xy 410.762927 -277.546263) (xy 410.812102 -277.544282) (xy 410.860957 -277.550214)
			(xy 410.908228 -277.563906) (xy 410.95269 -277.585004) (xy 410.993193 -277.61296) (xy 411.028686 -277.647052)
			(xy 411.058251 -277.686396) (xy 411.081122 -277.729973) (xy 411.096706 -277.776654) (xy 411.104601 -277.825231)
			(xy 411.105096 -277.849838) (xy 411.104601 -277.874445) (xy 411.104422 -277.875546) (xy 411.4231 -277.875546)
			(xy 411.4231 -277.82413) (xy 411.431143 -277.773348) (xy 411.447031 -277.724449) (xy 411.470374 -277.678637)
			(xy 411.500595 -277.637041) (xy 411.536951 -277.600685) (xy 411.578547 -277.570464) (xy 411.624359 -277.547121)
			(xy 411.673258 -277.531233) (xy 411.72404 -277.52319) (xy 411.775456 -277.52319) (xy 411.826238 -277.531233)
			(xy 411.875137 -277.547121) (xy 411.920949 -277.570464) (xy 411.962545 -277.600685) (xy 411.998901 -277.637041)
			(xy 412.029122 -277.678637) (xy 412.052465 -277.724449) (xy 412.068353 -277.773348) (xy 412.076396 -277.82413)
			(xy 412.0769 -277.849838) (xy 412.394158 -277.849838) (xy 412.398118 -277.800784) (xy 412.409895 -277.753)
			(xy 412.429186 -277.707724) (xy 412.455489 -277.666128) (xy 412.488124 -277.629291) (xy 412.526245 -277.598166)
			(xy 412.568866 -277.573559) (xy 412.614882 -277.556107) (xy 412.663101 -277.546263) (xy 412.712276 -277.544282)
			(xy 412.761131 -277.550214) (xy 412.808402 -277.563906) (xy 412.852864 -277.585004) (xy 412.893367 -277.61296)
			(xy 412.92886 -277.647052) (xy 412.958425 -277.686396) (xy 412.981296 -277.729973) (xy 412.99688 -277.776654)
			(xy 413.004775 -277.825231) (xy 413.00527 -277.849838) (xy 413.004775 -277.874445) (xy 413.004596 -277.875546)
			(xy 413.32302 -277.875546) (xy 413.32302 -277.82413) (xy 413.331063 -277.773348) (xy 413.346951 -277.724449)
			(xy 413.370294 -277.678637) (xy 413.400515 -277.637041) (xy 413.436871 -277.600685) (xy 413.478467 -277.570464)
			(xy 413.524279 -277.547121) (xy 413.573178 -277.531233) (xy 413.62396 -277.52319) (xy 413.675376 -277.52319)
			(xy 413.726158 -277.531233) (xy 413.775057 -277.547121) (xy 413.820869 -277.570464) (xy 413.862465 -277.600685)
			(xy 413.898821 -277.637041) (xy 413.929042 -277.678637) (xy 413.952385 -277.724449) (xy 413.968273 -277.773348)
			(xy 413.976316 -277.82413) (xy 413.97682 -277.849838) (xy 414.294078 -277.849838) (xy 414.298038 -277.800784)
			(xy 414.309815 -277.753) (xy 414.329106 -277.707724) (xy 414.355409 -277.666128) (xy 414.388044 -277.629291)
			(xy 414.426165 -277.598166) (xy 414.468786 -277.573559) (xy 414.514802 -277.556107) (xy 414.563021 -277.546263)
			(xy 414.612196 -277.544282) (xy 414.661051 -277.550214) (xy 414.708322 -277.563906) (xy 414.752784 -277.585004)
			(xy 414.793287 -277.61296) (xy 414.82878 -277.647052) (xy 414.858345 -277.686396) (xy 414.881216 -277.729973)
			(xy 414.8968 -277.776654) (xy 414.904695 -277.825231) (xy 414.90519 -277.849838) (xy 414.904695 -277.874445)
			(xy 414.904516 -277.875546) (xy 415.22294 -277.875546) (xy 415.22294 -277.82413) (xy 415.230983 -277.773348)
			(xy 415.246871 -277.724449) (xy 415.270214 -277.678637) (xy 415.300435 -277.637041) (xy 415.336791 -277.600685)
			(xy 415.378387 -277.570464) (xy 415.424199 -277.547121) (xy 415.473098 -277.531233) (xy 415.52388 -277.52319)
			(xy 415.575296 -277.52319) (xy 415.626078 -277.531233) (xy 415.674977 -277.547121) (xy 415.720789 -277.570464)
			(xy 415.762385 -277.600685) (xy 415.798741 -277.637041) (xy 415.828962 -277.678637) (xy 415.852305 -277.724449)
			(xy 415.868193 -277.773348) (xy 415.876236 -277.82413) (xy 415.87674 -277.849838) (xy 416.193998 -277.849838)
			(xy 416.197958 -277.800784) (xy 416.209735 -277.753) (xy 416.229026 -277.707724) (xy 416.255329 -277.666128)
			(xy 416.287964 -277.629291) (xy 416.326085 -277.598166) (xy 416.368706 -277.573559) (xy 416.414722 -277.556107)
			(xy 416.462941 -277.546263) (xy 416.512116 -277.544282) (xy 416.560971 -277.550214) (xy 416.608242 -277.563906)
			(xy 416.652704 -277.585004) (xy 416.693207 -277.61296) (xy 416.7287 -277.647052) (xy 416.758265 -277.686396)
			(xy 416.781136 -277.729973) (xy 416.79672 -277.776654) (xy 416.804615 -277.825231) (xy 416.80511 -277.849838)
			(xy 416.804615 -277.874445) (xy 416.804436 -277.875546) (xy 417.123114 -277.875546) (xy 417.123114 -277.82413)
			(xy 417.131157 -277.773348) (xy 417.147045 -277.724449) (xy 417.170388 -277.678637) (xy 417.200609 -277.637041)
			(xy 417.236965 -277.600685) (xy 417.278561 -277.570464) (xy 417.324373 -277.547121) (xy 417.373272 -277.531233)
			(xy 417.424054 -277.52319) (xy 417.47547 -277.52319) (xy 417.526252 -277.531233) (xy 417.575151 -277.547121)
			(xy 417.620963 -277.570464) (xy 417.662559 -277.600685) (xy 417.698915 -277.637041) (xy 417.729136 -277.678637)
			(xy 417.752479 -277.724449) (xy 417.768367 -277.773348) (xy 417.77641 -277.82413) (xy 417.776914 -277.849838)
			(xy 418.094172 -277.849838) (xy 418.098132 -277.800784) (xy 418.109909 -277.753) (xy 418.1292 -277.707724)
			(xy 418.155503 -277.666128) (xy 418.188138 -277.629291) (xy 418.226259 -277.598166) (xy 418.26888 -277.573559)
			(xy 418.314896 -277.556107) (xy 418.363115 -277.546263) (xy 418.41229 -277.544282) (xy 418.461145 -277.550214)
			(xy 418.508416 -277.563906) (xy 418.552878 -277.585004) (xy 418.593381 -277.61296) (xy 418.628874 -277.647052)
			(xy 418.658439 -277.686396) (xy 418.68131 -277.729973) (xy 418.696894 -277.776654) (xy 418.704789 -277.825231)
			(xy 418.705284 -277.849838) (xy 418.704789 -277.874445) (xy 418.70461 -277.875546) (xy 419.023034 -277.875546)
			(xy 419.023034 -277.82413) (xy 419.031077 -277.773348) (xy 419.046965 -277.724449) (xy 419.070308 -277.678637)
			(xy 419.100529 -277.637041) (xy 419.136885 -277.600685) (xy 419.178481 -277.570464) (xy 419.224293 -277.547121)
			(xy 419.273192 -277.531233) (xy 419.323974 -277.52319) (xy 419.37539 -277.52319) (xy 419.426172 -277.531233)
			(xy 419.475071 -277.547121) (xy 419.520883 -277.570464) (xy 419.562479 -277.600685) (xy 419.598835 -277.637041)
			(xy 419.629056 -277.678637) (xy 419.652399 -277.724449) (xy 419.668287 -277.773348) (xy 419.67633 -277.82413)
			(xy 419.676834 -277.849838) (xy 419.994092 -277.849838) (xy 419.998052 -277.800784) (xy 420.009829 -277.753)
			(xy 420.02912 -277.707724) (xy 420.055423 -277.666128) (xy 420.088058 -277.629291) (xy 420.126179 -277.598166)
			(xy 420.1688 -277.573559) (xy 420.214816 -277.556107) (xy 420.263035 -277.546263) (xy 420.31221 -277.544282)
			(xy 420.361065 -277.550214) (xy 420.408336 -277.563906) (xy 420.452798 -277.585004) (xy 420.493301 -277.61296)
			(xy 420.528794 -277.647052) (xy 420.558359 -277.686396) (xy 420.58123 -277.729973) (xy 420.596814 -277.776654)
			(xy 420.604709 -277.825231) (xy 420.605204 -277.849838) (xy 420.604709 -277.874445) (xy 420.60453 -277.875546)
			(xy 420.922954 -277.875546) (xy 420.922954 -277.82413) (xy 420.930997 -277.773348) (xy 420.946885 -277.724449)
			(xy 420.970228 -277.678637) (xy 421.000449 -277.637041) (xy 421.036805 -277.600685) (xy 421.078401 -277.570464)
			(xy 421.124213 -277.547121) (xy 421.173112 -277.531233) (xy 421.223894 -277.52319) (xy 421.27531 -277.52319)
			(xy 421.326092 -277.531233) (xy 421.374991 -277.547121) (xy 421.420803 -277.570464) (xy 421.462399 -277.600685)
			(xy 421.498755 -277.637041) (xy 421.528976 -277.678637) (xy 421.552319 -277.724449) (xy 421.568207 -277.773348)
			(xy 421.57625 -277.82413) (xy 421.576754 -277.849838) (xy 421.894012 -277.849838) (xy 421.897972 -277.800784)
			(xy 421.909749 -277.753) (xy 421.92904 -277.707724) (xy 421.955343 -277.666128) (xy 421.987978 -277.629291)
			(xy 422.026099 -277.598166) (xy 422.06872 -277.573559) (xy 422.114736 -277.556107) (xy 422.162955 -277.546263)
			(xy 422.21213 -277.544282) (xy 422.260985 -277.550214) (xy 422.308256 -277.563906) (xy 422.352718 -277.585004)
			(xy 422.393221 -277.61296) (xy 422.428714 -277.647052) (xy 422.458279 -277.686396) (xy 422.48115 -277.729973)
			(xy 422.496734 -277.776654) (xy 422.504629 -277.825231) (xy 422.505124 -277.849838) (xy 422.504629 -277.874445)
			(xy 422.50445 -277.875546) (xy 422.823128 -277.875546) (xy 422.823128 -277.82413) (xy 422.831171 -277.773348)
			(xy 422.847059 -277.724449) (xy 422.870402 -277.678637) (xy 422.900623 -277.637041) (xy 422.936979 -277.600685)
			(xy 422.978575 -277.570464) (xy 423.024387 -277.547121) (xy 423.073286 -277.531233) (xy 423.124068 -277.52319)
			(xy 423.175484 -277.52319) (xy 423.226266 -277.531233) (xy 423.275165 -277.547121) (xy 423.320977 -277.570464)
			(xy 423.362573 -277.600685) (xy 423.398929 -277.637041) (xy 423.42915 -277.678637) (xy 423.452493 -277.724449)
			(xy 423.468381 -277.773348) (xy 423.476424 -277.82413) (xy 423.476928 -277.849838) (xy 423.794186 -277.849838)
			(xy 423.798146 -277.800784) (xy 423.809923 -277.753) (xy 423.829214 -277.707724) (xy 423.855517 -277.666128)
			(xy 423.888152 -277.629291) (xy 423.926273 -277.598166) (xy 423.968894 -277.573559) (xy 424.01491 -277.556107)
			(xy 424.063129 -277.546263) (xy 424.112304 -277.544282) (xy 424.161159 -277.550214) (xy 424.20843 -277.563906)
			(xy 424.252892 -277.585004) (xy 424.293395 -277.61296) (xy 424.328888 -277.647052) (xy 424.358453 -277.686396)
			(xy 424.381324 -277.729973) (xy 424.396908 -277.776654) (xy 424.404803 -277.825231) (xy 424.405298 -277.849838)
			(xy 424.404803 -277.874445) (xy 424.404624 -277.875546) (xy 424.723048 -277.875546) (xy 424.723048 -277.82413)
			(xy 424.731091 -277.773348) (xy 424.746979 -277.724449) (xy 424.770322 -277.678637) (xy 424.800543 -277.637041)
			(xy 424.836899 -277.600685) (xy 424.878495 -277.570464) (xy 424.924307 -277.547121) (xy 424.973206 -277.531233)
			(xy 425.023988 -277.52319) (xy 425.075404 -277.52319) (xy 425.126186 -277.531233) (xy 425.175085 -277.547121)
			(xy 425.220897 -277.570464) (xy 425.262493 -277.600685) (xy 425.298849 -277.637041) (xy 425.32907 -277.678637)
			(xy 425.352413 -277.724449) (xy 425.368301 -277.773348) (xy 425.376344 -277.82413) (xy 425.376848 -277.849838)
			(xy 425.694106 -277.849838) (xy 425.698066 -277.800784) (xy 425.709843 -277.753) (xy 425.729134 -277.707724)
			(xy 425.755437 -277.666128) (xy 425.788072 -277.629291) (xy 425.826193 -277.598166) (xy 425.868814 -277.573559)
			(xy 425.91483 -277.556107) (xy 425.963049 -277.546263) (xy 426.012224 -277.544282) (xy 426.061079 -277.550214)
			(xy 426.10835 -277.563906) (xy 426.152812 -277.585004) (xy 426.193315 -277.61296) (xy 426.228808 -277.647052)
			(xy 426.258373 -277.686396) (xy 426.281244 -277.729973) (xy 426.296828 -277.776654) (xy 426.304723 -277.825231)
			(xy 426.305218 -277.849838) (xy 426.304723 -277.874445) (xy 426.304544 -277.875546) (xy 426.622968 -277.875546)
			(xy 426.622968 -277.82413) (xy 426.631011 -277.773348) (xy 426.646899 -277.724449) (xy 426.670242 -277.678637)
			(xy 426.700463 -277.637041) (xy 426.736819 -277.600685) (xy 426.778415 -277.570464) (xy 426.824227 -277.547121)
			(xy 426.873126 -277.531233) (xy 426.923908 -277.52319) (xy 426.975324 -277.52319) (xy 427.026106 -277.531233)
			(xy 427.075005 -277.547121) (xy 427.120817 -277.570464) (xy 427.162413 -277.600685) (xy 427.198769 -277.637041)
			(xy 427.22899 -277.678637) (xy 427.252333 -277.724449) (xy 427.268221 -277.773348) (xy 427.276264 -277.82413)
			(xy 427.276768 -277.849838) (xy 427.594026 -277.849838) (xy 427.597986 -277.800784) (xy 427.609763 -277.753)
			(xy 427.629054 -277.707724) (xy 427.655357 -277.666128) (xy 427.687992 -277.629291) (xy 427.726113 -277.598166)
			(xy 427.768734 -277.573559) (xy 427.81475 -277.556107) (xy 427.862969 -277.546263) (xy 427.912144 -277.544282)
			(xy 427.960999 -277.550214) (xy 428.00827 -277.563906) (xy 428.052732 -277.585004) (xy 428.093235 -277.61296)
			(xy 428.128728 -277.647052) (xy 428.158293 -277.686396) (xy 428.181164 -277.729973) (xy 428.196748 -277.776654)
			(xy 428.204643 -277.825231) (xy 428.205138 -277.849838) (xy 428.204643 -277.874445) (xy 428.204464 -277.875546)
			(xy 428.523142 -277.875546) (xy 428.523142 -277.82413) (xy 428.531185 -277.773348) (xy 428.547073 -277.724449)
			(xy 428.570416 -277.678637) (xy 428.600637 -277.637041) (xy 428.636993 -277.600685) (xy 428.678589 -277.570464)
			(xy 428.724401 -277.547121) (xy 428.7733 -277.531233) (xy 428.824082 -277.52319) (xy 428.875498 -277.52319)
			(xy 428.92628 -277.531233) (xy 428.975179 -277.547121) (xy 429.020991 -277.570464) (xy 429.062587 -277.600685)
			(xy 429.098943 -277.637041) (xy 429.129164 -277.678637) (xy 429.152507 -277.724449) (xy 429.168395 -277.773348)
			(xy 429.176438 -277.82413) (xy 429.176942 -277.849838) (xy 429.4942 -277.849838) (xy 429.49816 -277.800784)
			(xy 429.509937 -277.753) (xy 429.529228 -277.707724) (xy 429.555531 -277.666128) (xy 429.588166 -277.629291)
			(xy 429.626287 -277.598166) (xy 429.668908 -277.573559) (xy 429.714924 -277.556107) (xy 429.763143 -277.546263)
			(xy 429.812318 -277.544282) (xy 429.861173 -277.550214) (xy 429.908444 -277.563906) (xy 429.952906 -277.585004)
			(xy 429.993409 -277.61296) (xy 430.028902 -277.647052) (xy 430.058467 -277.686396) (xy 430.081338 -277.729973)
			(xy 430.096922 -277.776654) (xy 430.104817 -277.825231) (xy 430.105312 -277.849838) (xy 430.44416 -277.849838)
			(xy 430.44812 -277.800784) (xy 430.459897 -277.753) (xy 430.479188 -277.707724) (xy 430.505491 -277.666128)
			(xy 430.538126 -277.629291) (xy 430.576247 -277.598166) (xy 430.618868 -277.573559) (xy 430.664884 -277.556107)
			(xy 430.713103 -277.546263) (xy 430.762278 -277.544282) (xy 430.811133 -277.550214) (xy 430.858404 -277.563906)
			(xy 430.902866 -277.585004) (xy 430.943369 -277.61296) (xy 430.978862 -277.647052) (xy 431.008427 -277.686396)
			(xy 431.031298 -277.729973) (xy 431.046882 -277.776654) (xy 431.054777 -277.825231) (xy 431.055272 -277.849838)
			(xy 431.054777 -277.874445) (xy 431.046882 -277.923022) (xy 431.031298 -277.969703) (xy 431.008427 -278.01328)
			(xy 430.978862 -278.052624) (xy 430.943369 -278.086716) (xy 430.902866 -278.114672) (xy 430.858404 -278.13577)
			(xy 430.811133 -278.149462) (xy 430.762278 -278.155394) (xy 430.713103 -278.153413) (xy 430.664884 -278.143569)
			(xy 430.618868 -278.126117) (xy 430.576247 -278.10151) (xy 430.538126 -278.070385) (xy 430.505491 -278.033548)
			(xy 430.479188 -277.991952) (xy 430.459897 -277.946676) (xy 430.44812 -277.898892) (xy 430.44416 -277.849838)
			(xy 430.105312 -277.849838) (xy 430.104817 -277.874445) (xy 430.096922 -277.923022) (xy 430.081338 -277.969703)
			(xy 430.058467 -278.01328) (xy 430.028902 -278.052624) (xy 429.993409 -278.086716) (xy 429.952906 -278.114672)
			(xy 429.908444 -278.13577) (xy 429.861173 -278.149462) (xy 429.812318 -278.155394) (xy 429.763143 -278.153413)
			(xy 429.714924 -278.143569) (xy 429.668908 -278.126117) (xy 429.626287 -278.10151) (xy 429.588166 -278.070385)
			(xy 429.555531 -278.033548) (xy 429.529228 -277.991952) (xy 429.509937 -277.946676) (xy 429.49816 -277.898892)
			(xy 429.4942 -277.849838) (xy 429.176942 -277.849838) (xy 429.176438 -277.875546) (xy 429.168395 -277.926328)
			(xy 429.152507 -277.975227) (xy 429.129164 -278.021039) (xy 429.098943 -278.062635) (xy 429.062587 -278.098991)
			(xy 429.020991 -278.129212) (xy 428.975179 -278.152555) (xy 428.92628 -278.168443) (xy 428.875498 -278.176486)
			(xy 428.824082 -278.176486) (xy 428.7733 -278.168443) (xy 428.724401 -278.152555) (xy 428.678589 -278.129212)
			(xy 428.636993 -278.098991) (xy 428.600637 -278.062635) (xy 428.570416 -278.021039) (xy 428.547073 -277.975227)
			(xy 428.531185 -277.926328) (xy 428.523142 -277.875546) (xy 428.204464 -277.875546) (xy 428.196748 -277.923022)
			(xy 428.181164 -277.969703) (xy 428.158293 -278.01328) (xy 428.128728 -278.052624) (xy 428.093235 -278.086716)
			(xy 428.052732 -278.114672) (xy 428.00827 -278.13577) (xy 427.960999 -278.149462) (xy 427.912144 -278.155394)
			(xy 427.862969 -278.153413) (xy 427.81475 -278.143569) (xy 427.768734 -278.126117) (xy 427.726113 -278.10151)
			(xy 427.687992 -278.070385) (xy 427.655357 -278.033548) (xy 427.629054 -277.991952) (xy 427.609763 -277.946676)
			(xy 427.597986 -277.898892) (xy 427.594026 -277.849838) (xy 427.276768 -277.849838) (xy 427.276264 -277.875546)
			(xy 427.268221 -277.926328) (xy 427.252333 -277.975227) (xy 427.22899 -278.021039) (xy 427.198769 -278.062635)
			(xy 427.162413 -278.098991) (xy 427.120817 -278.129212) (xy 427.075005 -278.152555) (xy 427.026106 -278.168443)
			(xy 426.975324 -278.176486) (xy 426.923908 -278.176486) (xy 426.873126 -278.168443) (xy 426.824227 -278.152555)
			(xy 426.778415 -278.129212) (xy 426.736819 -278.098991) (xy 426.700463 -278.062635) (xy 426.670242 -278.021039)
			(xy 426.646899 -277.975227) (xy 426.631011 -277.926328) (xy 426.622968 -277.875546) (xy 426.304544 -277.875546)
			(xy 426.296828 -277.923022) (xy 426.281244 -277.969703) (xy 426.258373 -278.01328) (xy 426.228808 -278.052624)
			(xy 426.193315 -278.086716) (xy 426.152812 -278.114672) (xy 426.10835 -278.13577) (xy 426.061079 -278.149462)
			(xy 426.012224 -278.155394) (xy 425.963049 -278.153413) (xy 425.91483 -278.143569) (xy 425.868814 -278.126117)
			(xy 425.826193 -278.10151) (xy 425.788072 -278.070385) (xy 425.755437 -278.033548) (xy 425.729134 -277.991952)
			(xy 425.709843 -277.946676) (xy 425.698066 -277.898892) (xy 425.694106 -277.849838) (xy 425.376848 -277.849838)
			(xy 425.376344 -277.875546) (xy 425.368301 -277.926328) (xy 425.352413 -277.975227) (xy 425.32907 -278.021039)
			(xy 425.298849 -278.062635) (xy 425.262493 -278.098991) (xy 425.220897 -278.129212) (xy 425.175085 -278.152555)
			(xy 425.126186 -278.168443) (xy 425.075404 -278.176486) (xy 425.023988 -278.176486) (xy 424.973206 -278.168443)
			(xy 424.924307 -278.152555) (xy 424.878495 -278.129212) (xy 424.836899 -278.098991) (xy 424.800543 -278.062635)
			(xy 424.770322 -278.021039) (xy 424.746979 -277.975227) (xy 424.731091 -277.926328) (xy 424.723048 -277.875546)
			(xy 424.404624 -277.875546) (xy 424.396908 -277.923022) (xy 424.381324 -277.969703) (xy 424.358453 -278.01328)
			(xy 424.328888 -278.052624) (xy 424.293395 -278.086716) (xy 424.252892 -278.114672) (xy 424.20843 -278.13577)
			(xy 424.161159 -278.149462) (xy 424.112304 -278.155394) (xy 424.063129 -278.153413) (xy 424.01491 -278.143569)
			(xy 423.968894 -278.126117) (xy 423.926273 -278.10151) (xy 423.888152 -278.070385) (xy 423.855517 -278.033548)
			(xy 423.829214 -277.991952) (xy 423.809923 -277.946676) (xy 423.798146 -277.898892) (xy 423.794186 -277.849838)
			(xy 423.476928 -277.849838) (xy 423.476424 -277.875546) (xy 423.468381 -277.926328) (xy 423.452493 -277.975227)
			(xy 423.42915 -278.021039) (xy 423.398929 -278.062635) (xy 423.362573 -278.098991) (xy 423.320977 -278.129212)
			(xy 423.275165 -278.152555) (xy 423.226266 -278.168443) (xy 423.175484 -278.176486) (xy 423.124068 -278.176486)
			(xy 423.073286 -278.168443) (xy 423.024387 -278.152555) (xy 422.978575 -278.129212) (xy 422.936979 -278.098991)
			(xy 422.900623 -278.062635) (xy 422.870402 -278.021039) (xy 422.847059 -277.975227) (xy 422.831171 -277.926328)
			(xy 422.823128 -277.875546) (xy 422.50445 -277.875546) (xy 422.496734 -277.923022) (xy 422.48115 -277.969703)
			(xy 422.458279 -278.01328) (xy 422.428714 -278.052624) (xy 422.393221 -278.086716) (xy 422.352718 -278.114672)
			(xy 422.308256 -278.13577) (xy 422.260985 -278.149462) (xy 422.21213 -278.155394) (xy 422.162955 -278.153413)
			(xy 422.114736 -278.143569) (xy 422.06872 -278.126117) (xy 422.026099 -278.10151) (xy 421.987978 -278.070385)
			(xy 421.955343 -278.033548) (xy 421.92904 -277.991952) (xy 421.909749 -277.946676) (xy 421.897972 -277.898892)
			(xy 421.894012 -277.849838) (xy 421.576754 -277.849838) (xy 421.57625 -277.875546) (xy 421.568207 -277.926328)
			(xy 421.552319 -277.975227) (xy 421.528976 -278.021039) (xy 421.498755 -278.062635) (xy 421.462399 -278.098991)
			(xy 421.420803 -278.129212) (xy 421.374991 -278.152555) (xy 421.326092 -278.168443) (xy 421.27531 -278.176486)
			(xy 421.223894 -278.176486) (xy 421.173112 -278.168443) (xy 421.124213 -278.152555) (xy 421.078401 -278.129212)
			(xy 421.036805 -278.098991) (xy 421.000449 -278.062635) (xy 420.970228 -278.021039) (xy 420.946885 -277.975227)
			(xy 420.930997 -277.926328) (xy 420.922954 -277.875546) (xy 420.60453 -277.875546) (xy 420.596814 -277.923022)
			(xy 420.58123 -277.969703) (xy 420.558359 -278.01328) (xy 420.528794 -278.052624) (xy 420.493301 -278.086716)
			(xy 420.452798 -278.114672) (xy 420.408336 -278.13577) (xy 420.361065 -278.149462) (xy 420.31221 -278.155394)
			(xy 420.263035 -278.153413) (xy 420.214816 -278.143569) (xy 420.1688 -278.126117) (xy 420.126179 -278.10151)
			(xy 420.088058 -278.070385) (xy 420.055423 -278.033548) (xy 420.02912 -277.991952) (xy 420.009829 -277.946676)
			(xy 419.998052 -277.898892) (xy 419.994092 -277.849838) (xy 419.676834 -277.849838) (xy 419.67633 -277.875546)
			(xy 419.668287 -277.926328) (xy 419.652399 -277.975227) (xy 419.629056 -278.021039) (xy 419.598835 -278.062635)
			(xy 419.562479 -278.098991) (xy 419.520883 -278.129212) (xy 419.475071 -278.152555) (xy 419.426172 -278.168443)
			(xy 419.37539 -278.176486) (xy 419.323974 -278.176486) (xy 419.273192 -278.168443) (xy 419.224293 -278.152555)
			(xy 419.178481 -278.129212) (xy 419.136885 -278.098991) (xy 419.100529 -278.062635) (xy 419.070308 -278.021039)
			(xy 419.046965 -277.975227) (xy 419.031077 -277.926328) (xy 419.023034 -277.875546) (xy 418.70461 -277.875546)
			(xy 418.696894 -277.923022) (xy 418.68131 -277.969703) (xy 418.658439 -278.01328) (xy 418.628874 -278.052624)
			(xy 418.593381 -278.086716) (xy 418.552878 -278.114672) (xy 418.508416 -278.13577) (xy 418.461145 -278.149462)
			(xy 418.41229 -278.155394) (xy 418.363115 -278.153413) (xy 418.314896 -278.143569) (xy 418.26888 -278.126117)
			(xy 418.226259 -278.10151) (xy 418.188138 -278.070385) (xy 418.155503 -278.033548) (xy 418.1292 -277.991952)
			(xy 418.109909 -277.946676) (xy 418.098132 -277.898892) (xy 418.094172 -277.849838) (xy 417.776914 -277.849838)
			(xy 417.77641 -277.875546) (xy 417.768367 -277.926328) (xy 417.752479 -277.975227) (xy 417.729136 -278.021039)
			(xy 417.698915 -278.062635) (xy 417.662559 -278.098991) (xy 417.620963 -278.129212) (xy 417.575151 -278.152555)
			(xy 417.526252 -278.168443) (xy 417.47547 -278.176486) (xy 417.424054 -278.176486) (xy 417.373272 -278.168443)
			(xy 417.324373 -278.152555) (xy 417.278561 -278.129212) (xy 417.236965 -278.098991) (xy 417.200609 -278.062635)
			(xy 417.170388 -278.021039) (xy 417.147045 -277.975227) (xy 417.131157 -277.926328) (xy 417.123114 -277.875546)
			(xy 416.804436 -277.875546) (xy 416.79672 -277.923022) (xy 416.781136 -277.969703) (xy 416.758265 -278.01328)
			(xy 416.7287 -278.052624) (xy 416.693207 -278.086716) (xy 416.652704 -278.114672) (xy 416.608242 -278.13577)
			(xy 416.560971 -278.149462) (xy 416.512116 -278.155394) (xy 416.462941 -278.153413) (xy 416.414722 -278.143569)
			(xy 416.368706 -278.126117) (xy 416.326085 -278.10151) (xy 416.287964 -278.070385) (xy 416.255329 -278.033548)
			(xy 416.229026 -277.991952) (xy 416.209735 -277.946676) (xy 416.197958 -277.898892) (xy 416.193998 -277.849838)
			(xy 415.87674 -277.849838) (xy 415.876236 -277.875546) (xy 415.868193 -277.926328) (xy 415.852305 -277.975227)
			(xy 415.828962 -278.021039) (xy 415.798741 -278.062635) (xy 415.762385 -278.098991) (xy 415.720789 -278.129212)
			(xy 415.674977 -278.152555) (xy 415.626078 -278.168443) (xy 415.575296 -278.176486) (xy 415.52388 -278.176486)
			(xy 415.473098 -278.168443) (xy 415.424199 -278.152555) (xy 415.378387 -278.129212) (xy 415.336791 -278.098991)
			(xy 415.300435 -278.062635) (xy 415.270214 -278.021039) (xy 415.246871 -277.975227) (xy 415.230983 -277.926328)
			(xy 415.22294 -277.875546) (xy 414.904516 -277.875546) (xy 414.8968 -277.923022) (xy 414.881216 -277.969703)
			(xy 414.858345 -278.01328) (xy 414.82878 -278.052624) (xy 414.793287 -278.086716) (xy 414.752784 -278.114672)
			(xy 414.708322 -278.13577) (xy 414.661051 -278.149462) (xy 414.612196 -278.155394) (xy 414.563021 -278.153413)
			(xy 414.514802 -278.143569) (xy 414.468786 -278.126117) (xy 414.426165 -278.10151) (xy 414.388044 -278.070385)
			(xy 414.355409 -278.033548) (xy 414.329106 -277.991952) (xy 414.309815 -277.946676) (xy 414.298038 -277.898892)
			(xy 414.294078 -277.849838) (xy 413.97682 -277.849838) (xy 413.976316 -277.875546) (xy 413.968273 -277.926328)
			(xy 413.952385 -277.975227) (xy 413.929042 -278.021039) (xy 413.898821 -278.062635) (xy 413.862465 -278.098991)
			(xy 413.820869 -278.129212) (xy 413.775057 -278.152555) (xy 413.726158 -278.168443) (xy 413.675376 -278.176486)
			(xy 413.62396 -278.176486) (xy 413.573178 -278.168443) (xy 413.524279 -278.152555) (xy 413.478467 -278.129212)
			(xy 413.436871 -278.098991) (xy 413.400515 -278.062635) (xy 413.370294 -278.021039) (xy 413.346951 -277.975227)
			(xy 413.331063 -277.926328) (xy 413.32302 -277.875546) (xy 413.004596 -277.875546) (xy 412.99688 -277.923022)
			(xy 412.981296 -277.969703) (xy 412.958425 -278.01328) (xy 412.92886 -278.052624) (xy 412.893367 -278.086716)
			(xy 412.852864 -278.114672) (xy 412.808402 -278.13577) (xy 412.761131 -278.149462) (xy 412.712276 -278.155394)
			(xy 412.663101 -278.153413) (xy 412.614882 -278.143569) (xy 412.568866 -278.126117) (xy 412.526245 -278.10151)
			(xy 412.488124 -278.070385) (xy 412.455489 -278.033548) (xy 412.429186 -277.991952) (xy 412.409895 -277.946676)
			(xy 412.398118 -277.898892) (xy 412.394158 -277.849838) (xy 412.0769 -277.849838) (xy 412.076396 -277.875546)
			(xy 412.068353 -277.926328) (xy 412.052465 -277.975227) (xy 412.029122 -278.021039) (xy 411.998901 -278.062635)
			(xy 411.962545 -278.098991) (xy 411.920949 -278.129212) (xy 411.875137 -278.152555) (xy 411.826238 -278.168443)
			(xy 411.775456 -278.176486) (xy 411.72404 -278.176486) (xy 411.673258 -278.168443) (xy 411.624359 -278.152555)
			(xy 411.578547 -278.129212) (xy 411.536951 -278.098991) (xy 411.500595 -278.062635) (xy 411.470374 -278.021039)
			(xy 411.447031 -277.975227) (xy 411.431143 -277.926328) (xy 411.4231 -277.875546) (xy 411.104422 -277.875546)
			(xy 411.096706 -277.923022) (xy 411.081122 -277.969703) (xy 411.058251 -278.01328) (xy 411.028686 -278.052624)
			(xy 410.993193 -278.086716) (xy 410.95269 -278.114672) (xy 410.908228 -278.13577) (xy 410.860957 -278.149462)
			(xy 410.812102 -278.155394) (xy 410.762927 -278.153413) (xy 410.714708 -278.143569) (xy 410.668692 -278.126117)
			(xy 410.626071 -278.10151) (xy 410.58795 -278.070385) (xy 410.555315 -278.033548) (xy 410.529012 -277.991952)
			(xy 410.509721 -277.946676) (xy 410.497944 -277.898892) (xy 410.493984 -277.849838) (xy 410.176726 -277.849838)
			(xy 410.176222 -277.875546) (xy 410.168179 -277.926328) (xy 410.152291 -277.975227) (xy 410.128948 -278.021039)
			(xy 410.098727 -278.062635) (xy 410.062371 -278.098991) (xy 410.020775 -278.129212) (xy 409.974963 -278.152555)
			(xy 409.926064 -278.168443) (xy 409.875282 -278.176486) (xy 409.823866 -278.176486) (xy 409.773084 -278.168443)
			(xy 409.724185 -278.152555) (xy 409.678373 -278.129212) (xy 409.636777 -278.098991) (xy 409.600421 -278.062635)
			(xy 409.5702 -278.021039) (xy 409.546857 -277.975227) (xy 409.530969 -277.926328) (xy 409.522926 -277.875546)
			(xy 409.204502 -277.875546) (xy 409.196786 -277.923022) (xy 409.181202 -277.969703) (xy 409.158331 -278.01328)
			(xy 409.128766 -278.052624) (xy 409.093273 -278.086716) (xy 409.05277 -278.114672) (xy 409.008308 -278.13577)
			(xy 408.961037 -278.149462) (xy 408.912182 -278.155394) (xy 408.863007 -278.153413) (xy 408.814788 -278.143569)
			(xy 408.768772 -278.126117) (xy 408.726151 -278.10151) (xy 408.68803 -278.070385) (xy 408.655395 -278.033548)
			(xy 408.629092 -277.991952) (xy 408.609801 -277.946676) (xy 408.598024 -277.898892) (xy 408.594064 -277.849838)
			(xy 408.276082 -277.849838) (xy 408.276082 -277.875489) (xy 408.268044 -277.926235) (xy 408.252166 -277.975098)
			(xy 408.228839 -278.020875) (xy 408.198637 -278.06244) (xy 408.162305 -278.098767) (xy 408.120736 -278.128963)
			(xy 408.074955 -278.152284) (xy 408.02609 -278.168155) (xy 407.975343 -278.176186) (xy 407.949654 -278.176736)
			(xy 407.949146 -278.176736) (xy 407.923937 -278.176228) (xy 407.874128 -278.168411) (xy 407.826108 -278.153046)
			(xy 407.80335 -278.142192) (xy 407.802842 -278.142192) (xy 407.802588 -278.141938) (xy 407.79689 -278.139409)
			(xy 407.784693 -278.13685) (xy 407.778458 -278.136858) (xy 407.764996 -278.137366) (xy 407.68016 -278.18969)
			(xy 407.679652 -278.189944) (xy 407.679144 -278.190452) (xy 407.670349 -278.196742) (xy 407.658641 -278.214898)
			(xy 407.656538 -278.225504) (xy 407.65603 -278.23287) (xy 407.65603 -278.356822) (xy 456.56703 -278.356822)
			(xy 456.571101 -278.3012) (xy 456.583227 -278.246763) (xy 456.60315 -278.194672) (xy 456.630446 -278.146037)
			(xy 456.664532 -278.101894) (xy 456.704681 -278.063185) (xy 456.750039 -278.030734) (xy 456.799639 -278.005233)
			(xy 456.852423 -277.987226) (xy 456.907266 -277.977096) (xy 456.963 -277.975059) (xy 457.018437 -277.981159)
			(xy 457.072394 -277.995265) (xy 457.123723 -278.017077) (xy 457.171329 -278.046131) (xy 457.214197 -278.081806)
			(xy 457.251414 -278.123343) (xy 457.282187 -278.169856) (xy 457.305859 -278.220353) (xy 457.321927 -278.27376)
			(xy 457.330047 -278.328936) (xy 457.330556 -278.356822) (xy 457.330047 -278.384708) (xy 457.321927 -278.439884)
			(xy 457.305859 -278.493291) (xy 457.301129 -278.50338) (xy 458.091284 -278.50338) (xy 458.095355 -278.447758)
			(xy 458.107481 -278.393321) (xy 458.127404 -278.34123) (xy 458.1547 -278.292595) (xy 458.188786 -278.248452)
			(xy 458.228935 -278.209743) (xy 458.274293 -278.177292) (xy 458.323893 -278.151791) (xy 458.376677 -278.133784)
			(xy 458.43152 -278.123654) (xy 458.487254 -278.121617) (xy 458.542691 -278.127717) (xy 458.596648 -278.141823)
			(xy 458.647977 -278.163635) (xy 458.695583 -278.192689) (xy 458.738451 -278.228364) (xy 458.775668 -278.269901)
			(xy 458.806441 -278.316414) (xy 458.830113 -278.366911) (xy 458.846181 -278.420318) (xy 458.854301 -278.475494)
			(xy 458.854606 -278.492204) (xy 459.269336 -278.492204) (xy 459.273407 -278.436582) (xy 459.285533 -278.382145)
			(xy 459.305456 -278.330054) (xy 459.332752 -278.281419) (xy 459.366838 -278.237276) (xy 459.406987 -278.198567)
			(xy 459.452345 -278.166116) (xy 459.501945 -278.140615) (xy 459.554729 -278.122608) (xy 459.609572 -278.112478)
			(xy 459.665306 -278.110441) (xy 459.720743 -278.116541) (xy 459.7747 -278.130647) (xy 459.826029 -278.152459)
			(xy 459.873635 -278.181513) (xy 459.916503 -278.217188) (xy 459.95372 -278.258725) (xy 459.984493 -278.305238)
			(xy 460.008165 -278.355735) (xy 460.024233 -278.409142) (xy 460.032353 -278.464318) (xy 460.032862 -278.492204)
			(xy 460.032353 -278.52009) (xy 460.024233 -278.575266) (xy 460.008165 -278.628673) (xy 459.986528 -278.67483)
			(xy 461.074516 -278.67483) (xy 461.07505 -278.645914) (xy 461.083775 -278.588743) (xy 461.101029 -278.533544)
			(xy 461.126418 -278.481582) (xy 461.159359 -278.434048) (xy 461.199098 -278.39203) (xy 461.221582 -278.37384)
			(xy 461.228957 -278.367547) (xy 461.238758 -278.350839) (xy 461.240632 -278.341328) (xy 461.24114 -278.333708)
			(xy 461.24114 -278.253952) (xy 461.240632 -278.246332) (xy 461.238765 -278.236818) (xy 461.228967 -278.220104)
			(xy 461.221582 -278.21382) (xy 461.199104 -278.195622) (xy 461.15937 -278.153603) (xy 461.12643 -278.10607)
			(xy 461.101041 -278.05411) (xy 461.083783 -277.998914) (xy 461.075052 -277.941746) (xy 461.074516 -277.91283)
			(xy 461.075002 -277.885579) (xy 461.082758 -277.831631) (xy 461.098113 -277.779336) (xy 461.120755 -277.729759)
			(xy 461.150221 -277.683909) (xy 461.185912 -277.642718) (xy 461.227103 -277.607027) (xy 461.272953 -277.577561)
			(xy 461.32253 -277.554919) (xy 461.374825 -277.539564) (xy 461.428773 -277.531808) (xy 461.483275 -277.531808)
			(xy 461.537223 -277.539564) (xy 461.589518 -277.554919) (xy 461.639095 -277.577561) (xy 461.684945 -277.607027)
			(xy 461.726136 -277.642718) (xy 461.741197 -277.6601) (xy 463.093306 -277.6601) (xy 463.097377 -277.604478)
			(xy 463.109503 -277.550041) (xy 463.129426 -277.49795) (xy 463.156722 -277.449315) (xy 463.190808 -277.405172)
			(xy 463.230957 -277.366463) (xy 463.276315 -277.334012) (xy 463.325915 -277.308511) (xy 463.378699 -277.290504)
			(xy 463.433542 -277.280374) (xy 463.489276 -277.278337) (xy 463.544713 -277.284437) (xy 463.59867 -277.298543)
			(xy 463.649999 -277.320355) (xy 463.697605 -277.349409) (xy 463.740473 -277.385084) (xy 463.77769 -277.426621)
			(xy 463.808463 -277.473134) (xy 463.832135 -277.523631) (xy 463.848203 -277.577038) (xy 463.856323 -277.632214)
			(xy 463.856832 -277.6601) (xy 463.856323 -277.687986) (xy 463.848203 -277.743162) (xy 463.832135 -277.796569)
			(xy 463.808463 -277.847066) (xy 463.77769 -277.893579) (xy 463.740473 -277.935116) (xy 463.697605 -277.970791)
			(xy 463.649999 -277.999845) (xy 463.59867 -278.021657) (xy 463.544713 -278.035763) (xy 463.489276 -278.041863)
			(xy 463.433542 -278.039826) (xy 463.378699 -278.029696) (xy 463.325915 -278.011689) (xy 463.276315 -277.986188)
			(xy 463.230957 -277.953737) (xy 463.190808 -277.915028) (xy 463.156722 -277.870885) (xy 463.129426 -277.82225)
			(xy 463.109503 -277.770159) (xy 463.097377 -277.715722) (xy 463.093306 -277.6601) (xy 461.741197 -277.6601)
			(xy 461.761827 -277.683909) (xy 461.791293 -277.729759) (xy 461.813935 -277.779336) (xy 461.82929 -277.831631)
			(xy 461.837046 -277.885579) (xy 461.837532 -277.91283) (xy 461.836989 -277.941746) (xy 461.828269 -277.998917)
			(xy 461.811017 -278.054117) (xy 461.78563 -278.106079) (xy 461.75269 -278.153614) (xy 461.712951 -278.19563)
			(xy 461.690466 -278.21382) (xy 461.683061 -278.220082) (xy 461.673278 -278.236813) (xy 461.671416 -278.246332)
			(xy 461.670908 -278.253952) (xy 461.670908 -278.333708) (xy 461.671416 -278.341328) (xy 461.673287 -278.350842)
			(xy 461.683081 -278.367557) (xy 461.690466 -278.37384) (xy 461.712962 -278.392017) (xy 461.752698 -278.434039)
			(xy 461.785636 -278.481576) (xy 461.811023 -278.53354) (xy 461.828276 -278.588741) (xy 461.837 -278.645913)
			(xy 461.837532 -278.67483) (xy 461.837046 -278.702081) (xy 461.82929 -278.756029) (xy 461.813935 -278.808324)
			(xy 461.791293 -278.857901) (xy 461.761827 -278.903751) (xy 461.726136 -278.944942) (xy 461.684945 -278.980633)
			(xy 461.639095 -279.010099) (xy 461.589518 -279.032741) (xy 461.537223 -279.048096) (xy 461.483275 -279.055852)
			(xy 461.428773 -279.055852) (xy 461.374825 -279.048096) (xy 461.32253 -279.032741) (xy 461.272953 -279.010099)
			(xy 461.227103 -278.980633) (xy 461.185912 -278.944942) (xy 461.150221 -278.903751) (xy 461.120755 -278.857901)
			(xy 461.098113 -278.808324) (xy 461.082758 -278.756029) (xy 461.075002 -278.702081) (xy 461.074516 -278.67483)
			(xy 459.986528 -278.67483) (xy 459.984493 -278.67917) (xy 459.95372 -278.725683) (xy 459.916503 -278.76722)
			(xy 459.873635 -278.802895) (xy 459.826029 -278.831949) (xy 459.7747 -278.853761) (xy 459.720743 -278.867867)
			(xy 459.665306 -278.873967) (xy 459.609572 -278.87193) (xy 459.554729 -278.8618) (xy 459.501945 -278.843793)
			(xy 459.452345 -278.818292) (xy 459.406987 -278.785841) (xy 459.366838 -278.747132) (xy 459.332752 -278.702989)
			(xy 459.305456 -278.654354) (xy 459.285533 -278.602263) (xy 459.273407 -278.547826) (xy 459.269336 -278.492204)
			(xy 458.854606 -278.492204) (xy 458.85481 -278.50338) (xy 458.854301 -278.531266) (xy 458.846181 -278.586442)
			(xy 458.830113 -278.639849) (xy 458.806441 -278.690346) (xy 458.775668 -278.736859) (xy 458.738451 -278.778396)
			(xy 458.695583 -278.814071) (xy 458.647977 -278.843125) (xy 458.596648 -278.864937) (xy 458.542691 -278.879043)
			(xy 458.487254 -278.885143) (xy 458.43152 -278.883106) (xy 458.376677 -278.872976) (xy 458.323893 -278.854969)
			(xy 458.274293 -278.829468) (xy 458.228935 -278.797017) (xy 458.188786 -278.758308) (xy 458.1547 -278.714165)
			(xy 458.127404 -278.66553) (xy 458.107481 -278.613439) (xy 458.095355 -278.559002) (xy 458.091284 -278.50338)
			(xy 457.301129 -278.50338) (xy 457.282187 -278.543788) (xy 457.251414 -278.590301) (xy 457.214197 -278.631838)
			(xy 457.171329 -278.667513) (xy 457.123723 -278.696567) (xy 457.072394 -278.718379) (xy 457.018437 -278.732485)
			(xy 456.963 -278.738585) (xy 456.907266 -278.736548) (xy 456.852423 -278.726418) (xy 456.799639 -278.708411)
			(xy 456.750039 -278.68291) (xy 456.704681 -278.650459) (xy 456.664532 -278.61175) (xy 456.630446 -278.567607)
			(xy 456.60315 -278.518972) (xy 456.583227 -278.466881) (xy 456.571101 -278.412444) (xy 456.56703 -278.356822)
			(xy 407.65603 -278.356822) (xy 407.65603 -278.416766) (xy 407.656538 -278.424132) (xy 407.658645 -278.434735)
			(xy 407.67036 -278.45288) (xy 407.679144 -278.459184) (xy 407.679652 -278.459692) (xy 407.68016 -278.459946)
			(xy 407.753566 -278.505158) (xy 407.759261 -278.50849) (xy 407.771874 -278.512349) (xy 407.778458 -278.512778)
			(xy 407.791158 -278.513286) (xy 407.802842 -278.507444) (xy 407.80335 -278.507444) (xy 407.826103 -278.496578)
			(xy 407.874124 -278.481207) (xy 407.923936 -278.473402) (xy 407.949146 -278.4729) (xy 407.949654 -278.4729)
			(xy 407.975346 -278.473374) (xy 408.026099 -278.481406) (xy 408.074971 -278.49728) (xy 408.120757 -278.520603)
			(xy 408.16233 -278.550803) (xy 408.198667 -278.587134) (xy 408.228873 -278.628704) (xy 408.252203 -278.674487)
			(xy 408.268083 -278.723356) (xy 408.276122 -278.774108) (xy 408.276122 -278.799798) (xy 408.594064 -278.799798)
			(xy 408.598024 -278.750744) (xy 408.609801 -278.70296) (xy 408.629092 -278.657684) (xy 408.655395 -278.616088)
			(xy 408.68803 -278.579251) (xy 408.726151 -278.548126) (xy 408.768772 -278.523519) (xy 408.814788 -278.506067)
			(xy 408.863007 -278.496223) (xy 408.912182 -278.494242) (xy 408.961037 -278.500174) (xy 409.008308 -278.513866)
			(xy 409.05277 -278.534964) (xy 409.093273 -278.56292) (xy 409.128766 -278.597012) (xy 409.158331 -278.636356)
			(xy 409.181202 -278.679933) (xy 409.196786 -278.726614) (xy 409.204681 -278.775191) (xy 409.205176 -278.799798)
			(xy 409.204681 -278.824405) (xy 409.204502 -278.825506) (xy 409.522926 -278.825506) (xy 409.522926 -278.77409)
			(xy 409.530969 -278.723308) (xy 409.546857 -278.674409) (xy 409.5702 -278.628597) (xy 409.600421 -278.587001)
			(xy 409.636777 -278.550645) (xy 409.678373 -278.520424) (xy 409.724185 -278.497081) (xy 409.773084 -278.481193)
			(xy 409.823866 -278.47315) (xy 409.875282 -278.47315) (xy 409.926064 -278.481193) (xy 409.974963 -278.497081)
			(xy 410.020775 -278.520424) (xy 410.062371 -278.550645) (xy 410.098727 -278.587001) (xy 410.128948 -278.628597)
			(xy 410.152291 -278.674409) (xy 410.168179 -278.723308) (xy 410.176222 -278.77409) (xy 410.176726 -278.799798)
			(xy 410.493984 -278.799798) (xy 410.497944 -278.750744) (xy 410.509721 -278.70296) (xy 410.529012 -278.657684)
			(xy 410.555315 -278.616088) (xy 410.58795 -278.579251) (xy 410.626071 -278.548126) (xy 410.668692 -278.523519)
			(xy 410.714708 -278.506067) (xy 410.762927 -278.496223) (xy 410.812102 -278.494242) (xy 410.860957 -278.500174)
			(xy 410.908228 -278.513866) (xy 410.95269 -278.534964) (xy 410.993193 -278.56292) (xy 411.028686 -278.597012)
			(xy 411.058251 -278.636356) (xy 411.081122 -278.679933) (xy 411.096706 -278.726614) (xy 411.104601 -278.775191)
			(xy 411.105096 -278.799798) (xy 411.104601 -278.824405) (xy 411.104422 -278.825506) (xy 411.4231 -278.825506)
			(xy 411.4231 -278.77409) (xy 411.431143 -278.723308) (xy 411.447031 -278.674409) (xy 411.470374 -278.628597)
			(xy 411.500595 -278.587001) (xy 411.536951 -278.550645) (xy 411.578547 -278.520424) (xy 411.624359 -278.497081)
			(xy 411.673258 -278.481193) (xy 411.72404 -278.47315) (xy 411.775456 -278.47315) (xy 411.826238 -278.481193)
			(xy 411.875137 -278.497081) (xy 411.920949 -278.520424) (xy 411.962545 -278.550645) (xy 411.998901 -278.587001)
			(xy 412.029122 -278.628597) (xy 412.052465 -278.674409) (xy 412.068353 -278.723308) (xy 412.076396 -278.77409)
			(xy 412.0769 -278.799798) (xy 412.394158 -278.799798) (xy 412.398118 -278.750744) (xy 412.409895 -278.70296)
			(xy 412.429186 -278.657684) (xy 412.455489 -278.616088) (xy 412.488124 -278.579251) (xy 412.526245 -278.548126)
			(xy 412.568866 -278.523519) (xy 412.614882 -278.506067) (xy 412.663101 -278.496223) (xy 412.712276 -278.494242)
			(xy 412.761131 -278.500174) (xy 412.808402 -278.513866) (xy 412.852864 -278.534964) (xy 412.893367 -278.56292)
			(xy 412.92886 -278.597012) (xy 412.958425 -278.636356) (xy 412.981296 -278.679933) (xy 412.99688 -278.726614)
			(xy 413.004775 -278.775191) (xy 413.00527 -278.799798) (xy 413.004775 -278.824405) (xy 413.004596 -278.825506)
			(xy 413.32302 -278.825506) (xy 413.32302 -278.77409) (xy 413.331063 -278.723308) (xy 413.346951 -278.674409)
			(xy 413.370294 -278.628597) (xy 413.400515 -278.587001) (xy 413.436871 -278.550645) (xy 413.478467 -278.520424)
			(xy 413.524279 -278.497081) (xy 413.573178 -278.481193) (xy 413.62396 -278.47315) (xy 413.675376 -278.47315)
			(xy 413.726158 -278.481193) (xy 413.775057 -278.497081) (xy 413.820869 -278.520424) (xy 413.862465 -278.550645)
			(xy 413.898821 -278.587001) (xy 413.929042 -278.628597) (xy 413.952385 -278.674409) (xy 413.968273 -278.723308)
			(xy 413.976316 -278.77409) (xy 413.97682 -278.799798) (xy 414.294078 -278.799798) (xy 414.298038 -278.750744)
			(xy 414.309815 -278.70296) (xy 414.329106 -278.657684) (xy 414.355409 -278.616088) (xy 414.388044 -278.579251)
			(xy 414.426165 -278.548126) (xy 414.468786 -278.523519) (xy 414.514802 -278.506067) (xy 414.563021 -278.496223)
			(xy 414.612196 -278.494242) (xy 414.661051 -278.500174) (xy 414.708322 -278.513866) (xy 414.752784 -278.534964)
			(xy 414.793287 -278.56292) (xy 414.82878 -278.597012) (xy 414.858345 -278.636356) (xy 414.881216 -278.679933)
			(xy 414.8968 -278.726614) (xy 414.904695 -278.775191) (xy 414.90519 -278.799798) (xy 414.904695 -278.824405)
			(xy 414.904516 -278.825506) (xy 415.22294 -278.825506) (xy 415.22294 -278.77409) (xy 415.230983 -278.723308)
			(xy 415.246871 -278.674409) (xy 415.270214 -278.628597) (xy 415.300435 -278.587001) (xy 415.336791 -278.550645)
			(xy 415.378387 -278.520424) (xy 415.424199 -278.497081) (xy 415.473098 -278.481193) (xy 415.52388 -278.47315)
			(xy 415.575296 -278.47315) (xy 415.626078 -278.481193) (xy 415.674977 -278.497081) (xy 415.720789 -278.520424)
			(xy 415.762385 -278.550645) (xy 415.798741 -278.587001) (xy 415.828962 -278.628597) (xy 415.852305 -278.674409)
			(xy 415.868193 -278.723308) (xy 415.876236 -278.77409) (xy 415.87674 -278.799798) (xy 416.193998 -278.799798)
			(xy 416.197958 -278.750744) (xy 416.209735 -278.70296) (xy 416.229026 -278.657684) (xy 416.255329 -278.616088)
			(xy 416.287964 -278.579251) (xy 416.326085 -278.548126) (xy 416.368706 -278.523519) (xy 416.414722 -278.506067)
			(xy 416.462941 -278.496223) (xy 416.512116 -278.494242) (xy 416.560971 -278.500174) (xy 416.608242 -278.513866)
			(xy 416.652704 -278.534964) (xy 416.693207 -278.56292) (xy 416.7287 -278.597012) (xy 416.758265 -278.636356)
			(xy 416.781136 -278.679933) (xy 416.79672 -278.726614) (xy 416.804615 -278.775191) (xy 416.80511 -278.799798)
			(xy 416.804615 -278.824405) (xy 416.804436 -278.825506) (xy 417.123114 -278.825506) (xy 417.123114 -278.77409)
			(xy 417.131157 -278.723308) (xy 417.147045 -278.674409) (xy 417.170388 -278.628597) (xy 417.200609 -278.587001)
			(xy 417.236965 -278.550645) (xy 417.278561 -278.520424) (xy 417.324373 -278.497081) (xy 417.373272 -278.481193)
			(xy 417.424054 -278.47315) (xy 417.47547 -278.47315) (xy 417.526252 -278.481193) (xy 417.575151 -278.497081)
			(xy 417.620963 -278.520424) (xy 417.662559 -278.550645) (xy 417.698915 -278.587001) (xy 417.729136 -278.628597)
			(xy 417.752479 -278.674409) (xy 417.768367 -278.723308) (xy 417.77641 -278.77409) (xy 417.776914 -278.799798)
			(xy 418.094172 -278.799798) (xy 418.098132 -278.750744) (xy 418.109909 -278.70296) (xy 418.1292 -278.657684)
			(xy 418.155503 -278.616088) (xy 418.188138 -278.579251) (xy 418.226259 -278.548126) (xy 418.26888 -278.523519)
			(xy 418.314896 -278.506067) (xy 418.363115 -278.496223) (xy 418.41229 -278.494242) (xy 418.461145 -278.500174)
			(xy 418.508416 -278.513866) (xy 418.552878 -278.534964) (xy 418.593381 -278.56292) (xy 418.628874 -278.597012)
			(xy 418.658439 -278.636356) (xy 418.68131 -278.679933) (xy 418.696894 -278.726614) (xy 418.704789 -278.775191)
			(xy 418.705284 -278.799798) (xy 418.704789 -278.824405) (xy 418.70461 -278.825506) (xy 419.023034 -278.825506)
			(xy 419.023034 -278.77409) (xy 419.031077 -278.723308) (xy 419.046965 -278.674409) (xy 419.070308 -278.628597)
			(xy 419.100529 -278.587001) (xy 419.136885 -278.550645) (xy 419.178481 -278.520424) (xy 419.224293 -278.497081)
			(xy 419.273192 -278.481193) (xy 419.323974 -278.47315) (xy 419.37539 -278.47315) (xy 419.426172 -278.481193)
			(xy 419.475071 -278.497081) (xy 419.520883 -278.520424) (xy 419.562479 -278.550645) (xy 419.598835 -278.587001)
			(xy 419.629056 -278.628597) (xy 419.652399 -278.674409) (xy 419.668287 -278.723308) (xy 419.67633 -278.77409)
			(xy 419.676834 -278.799798) (xy 419.994092 -278.799798) (xy 419.998052 -278.750744) (xy 420.009829 -278.70296)
			(xy 420.02912 -278.657684) (xy 420.055423 -278.616088) (xy 420.088058 -278.579251) (xy 420.126179 -278.548126)
			(xy 420.1688 -278.523519) (xy 420.214816 -278.506067) (xy 420.263035 -278.496223) (xy 420.31221 -278.494242)
			(xy 420.361065 -278.500174) (xy 420.408336 -278.513866) (xy 420.452798 -278.534964) (xy 420.493301 -278.56292)
			(xy 420.528794 -278.597012) (xy 420.558359 -278.636356) (xy 420.58123 -278.679933) (xy 420.596814 -278.726614)
			(xy 420.604709 -278.775191) (xy 420.605204 -278.799798) (xy 420.604709 -278.824405) (xy 420.60453 -278.825506)
			(xy 420.922954 -278.825506) (xy 420.922954 -278.77409) (xy 420.930997 -278.723308) (xy 420.946885 -278.674409)
			(xy 420.970228 -278.628597) (xy 421.000449 -278.587001) (xy 421.036805 -278.550645) (xy 421.078401 -278.520424)
			(xy 421.124213 -278.497081) (xy 421.173112 -278.481193) (xy 421.223894 -278.47315) (xy 421.27531 -278.47315)
			(xy 421.326092 -278.481193) (xy 421.374991 -278.497081) (xy 421.420803 -278.520424) (xy 421.462399 -278.550645)
			(xy 421.498755 -278.587001) (xy 421.528976 -278.628597) (xy 421.552319 -278.674409) (xy 421.568207 -278.723308)
			(xy 421.57625 -278.77409) (xy 421.576754 -278.799798) (xy 421.894012 -278.799798) (xy 421.897972 -278.750744)
			(xy 421.909749 -278.70296) (xy 421.92904 -278.657684) (xy 421.955343 -278.616088) (xy 421.987978 -278.579251)
			(xy 422.026099 -278.548126) (xy 422.06872 -278.523519) (xy 422.114736 -278.506067) (xy 422.162955 -278.496223)
			(xy 422.21213 -278.494242) (xy 422.260985 -278.500174) (xy 422.308256 -278.513866) (xy 422.352718 -278.534964)
			(xy 422.393221 -278.56292) (xy 422.428714 -278.597012) (xy 422.458279 -278.636356) (xy 422.48115 -278.679933)
			(xy 422.496734 -278.726614) (xy 422.504629 -278.775191) (xy 422.505124 -278.799798) (xy 422.504629 -278.824405)
			(xy 422.50445 -278.825506) (xy 422.823128 -278.825506) (xy 422.823128 -278.77409) (xy 422.831171 -278.723308)
			(xy 422.847059 -278.674409) (xy 422.870402 -278.628597) (xy 422.900623 -278.587001) (xy 422.936979 -278.550645)
			(xy 422.978575 -278.520424) (xy 423.024387 -278.497081) (xy 423.073286 -278.481193) (xy 423.124068 -278.47315)
			(xy 423.175484 -278.47315) (xy 423.226266 -278.481193) (xy 423.275165 -278.497081) (xy 423.320977 -278.520424)
			(xy 423.362573 -278.550645) (xy 423.398929 -278.587001) (xy 423.42915 -278.628597) (xy 423.452493 -278.674409)
			(xy 423.468381 -278.723308) (xy 423.476424 -278.77409) (xy 423.476928 -278.799798) (xy 423.794186 -278.799798)
			(xy 423.798146 -278.750744) (xy 423.809923 -278.70296) (xy 423.829214 -278.657684) (xy 423.855517 -278.616088)
			(xy 423.888152 -278.579251) (xy 423.926273 -278.548126) (xy 423.968894 -278.523519) (xy 424.01491 -278.506067)
			(xy 424.063129 -278.496223) (xy 424.112304 -278.494242) (xy 424.161159 -278.500174) (xy 424.20843 -278.513866)
			(xy 424.252892 -278.534964) (xy 424.293395 -278.56292) (xy 424.328888 -278.597012) (xy 424.358453 -278.636356)
			(xy 424.381324 -278.679933) (xy 424.396908 -278.726614) (xy 424.404803 -278.775191) (xy 424.405298 -278.799798)
			(xy 424.404803 -278.824405) (xy 424.404624 -278.825506) (xy 424.723048 -278.825506) (xy 424.723048 -278.77409)
			(xy 424.731091 -278.723308) (xy 424.746979 -278.674409) (xy 424.770322 -278.628597) (xy 424.800543 -278.587001)
			(xy 424.836899 -278.550645) (xy 424.878495 -278.520424) (xy 424.924307 -278.497081) (xy 424.973206 -278.481193)
			(xy 425.023988 -278.47315) (xy 425.075404 -278.47315) (xy 425.126186 -278.481193) (xy 425.175085 -278.497081)
			(xy 425.220897 -278.520424) (xy 425.262493 -278.550645) (xy 425.298849 -278.587001) (xy 425.32907 -278.628597)
			(xy 425.352413 -278.674409) (xy 425.368301 -278.723308) (xy 425.376344 -278.77409) (xy 425.376848 -278.799798)
			(xy 425.694106 -278.799798) (xy 425.698066 -278.750744) (xy 425.709843 -278.70296) (xy 425.729134 -278.657684)
			(xy 425.755437 -278.616088) (xy 425.788072 -278.579251) (xy 425.826193 -278.548126) (xy 425.868814 -278.523519)
			(xy 425.91483 -278.506067) (xy 425.963049 -278.496223) (xy 426.012224 -278.494242) (xy 426.061079 -278.500174)
			(xy 426.10835 -278.513866) (xy 426.152812 -278.534964) (xy 426.193315 -278.56292) (xy 426.228808 -278.597012)
			(xy 426.258373 -278.636356) (xy 426.281244 -278.679933) (xy 426.296828 -278.726614) (xy 426.304723 -278.775191)
			(xy 426.305218 -278.799798) (xy 426.304723 -278.824405) (xy 426.304544 -278.825506) (xy 426.622968 -278.825506)
			(xy 426.622968 -278.77409) (xy 426.631011 -278.723308) (xy 426.646899 -278.674409) (xy 426.670242 -278.628597)
			(xy 426.700463 -278.587001) (xy 426.736819 -278.550645) (xy 426.778415 -278.520424) (xy 426.824227 -278.497081)
			(xy 426.873126 -278.481193) (xy 426.923908 -278.47315) (xy 426.975324 -278.47315) (xy 427.026106 -278.481193)
			(xy 427.075005 -278.497081) (xy 427.120817 -278.520424) (xy 427.162413 -278.550645) (xy 427.198769 -278.587001)
			(xy 427.22899 -278.628597) (xy 427.252333 -278.674409) (xy 427.268221 -278.723308) (xy 427.276264 -278.77409)
			(xy 427.276768 -278.799798) (xy 427.594026 -278.799798) (xy 427.597986 -278.750744) (xy 427.609763 -278.70296)
			(xy 427.629054 -278.657684) (xy 427.655357 -278.616088) (xy 427.687992 -278.579251) (xy 427.726113 -278.548126)
			(xy 427.768734 -278.523519) (xy 427.81475 -278.506067) (xy 427.862969 -278.496223) (xy 427.912144 -278.494242)
			(xy 427.960999 -278.500174) (xy 428.00827 -278.513866) (xy 428.052732 -278.534964) (xy 428.093235 -278.56292)
			(xy 428.128728 -278.597012) (xy 428.158293 -278.636356) (xy 428.181164 -278.679933) (xy 428.196748 -278.726614)
			(xy 428.204643 -278.775191) (xy 428.205138 -278.799798) (xy 428.204643 -278.824405) (xy 428.204464 -278.825506)
			(xy 428.523142 -278.825506) (xy 428.523142 -278.77409) (xy 428.531185 -278.723308) (xy 428.547073 -278.674409)
			(xy 428.570416 -278.628597) (xy 428.600637 -278.587001) (xy 428.636993 -278.550645) (xy 428.678589 -278.520424)
			(xy 428.724401 -278.497081) (xy 428.7733 -278.481193) (xy 428.824082 -278.47315) (xy 428.875498 -278.47315)
			(xy 428.92628 -278.481193) (xy 428.975179 -278.497081) (xy 429.020991 -278.520424) (xy 429.062587 -278.550645)
			(xy 429.098943 -278.587001) (xy 429.129164 -278.628597) (xy 429.152507 -278.674409) (xy 429.168395 -278.723308)
			(xy 429.176438 -278.77409) (xy 429.176942 -278.799798) (xy 429.4942 -278.799798) (xy 429.49816 -278.750744)
			(xy 429.509937 -278.70296) (xy 429.529228 -278.657684) (xy 429.555531 -278.616088) (xy 429.588166 -278.579251)
			(xy 429.626287 -278.548126) (xy 429.668908 -278.523519) (xy 429.714924 -278.506067) (xy 429.763143 -278.496223)
			(xy 429.812318 -278.494242) (xy 429.861173 -278.500174) (xy 429.908444 -278.513866) (xy 429.952906 -278.534964)
			(xy 429.993409 -278.56292) (xy 430.028902 -278.597012) (xy 430.058467 -278.636356) (xy 430.081338 -278.679933)
			(xy 430.096922 -278.726614) (xy 430.104817 -278.775191) (xy 430.105312 -278.799798) (xy 430.44416 -278.799798)
			(xy 430.44812 -278.750744) (xy 430.459897 -278.70296) (xy 430.479188 -278.657684) (xy 430.505491 -278.616088)
			(xy 430.538126 -278.579251) (xy 430.576247 -278.548126) (xy 430.618868 -278.523519) (xy 430.664884 -278.506067)
			(xy 430.713103 -278.496223) (xy 430.762278 -278.494242) (xy 430.811133 -278.500174) (xy 430.858404 -278.513866)
			(xy 430.902866 -278.534964) (xy 430.943369 -278.56292) (xy 430.978862 -278.597012) (xy 431.008427 -278.636356)
			(xy 431.031298 -278.679933) (xy 431.046882 -278.726614) (xy 431.054777 -278.775191) (xy 431.055272 -278.799798)
			(xy 431.054777 -278.824405) (xy 431.048786 -278.861266) (xy 447.862958 -278.861266) (xy 447.867029 -278.805644)
			(xy 447.879155 -278.751207) (xy 447.899078 -278.699116) (xy 447.926374 -278.650481) (xy 447.96046 -278.606338)
			(xy 448.000609 -278.567629) (xy 448.045967 -278.535178) (xy 448.095567 -278.509677) (xy 448.148351 -278.49167)
			(xy 448.203194 -278.48154) (xy 448.258928 -278.479503) (xy 448.314365 -278.485603) (xy 448.368322 -278.499709)
			(xy 448.419651 -278.521521) (xy 448.467257 -278.550575) (xy 448.510125 -278.58625) (xy 448.547342 -278.627787)
			(xy 448.578115 -278.6743) (xy 448.601787 -278.724797) (xy 448.617855 -278.778204) (xy 448.625975 -278.83338)
			(xy 448.626484 -278.861266) (xy 448.625975 -278.889152) (xy 448.617855 -278.944328) (xy 448.601787 -278.997735)
			(xy 448.578115 -279.048232) (xy 448.547342 -279.094745) (xy 448.510125 -279.136282) (xy 448.467257 -279.171957)
			(xy 448.422389 -279.19934) (xy 455.00112 -279.19934) (xy 455.005191 -279.143718) (xy 455.017317 -279.089281)
			(xy 455.03724 -279.03719) (xy 455.064536 -278.988555) (xy 455.098622 -278.944412) (xy 455.138771 -278.905703)
			(xy 455.184129 -278.873252) (xy 455.233729 -278.847751) (xy 455.286513 -278.829744) (xy 455.341356 -278.819614)
			(xy 455.39709 -278.817577) (xy 455.452527 -278.823677) (xy 455.506484 -278.837783) (xy 455.557813 -278.859595)
			(xy 455.605419 -278.888649) (xy 455.648287 -278.924324) (xy 455.685504 -278.965861) (xy 455.716277 -279.012374)
			(xy 455.739949 -279.062871) (xy 455.756017 -279.116278) (xy 455.764137 -279.171454) (xy 455.764646 -279.19934)
			(xy 455.764137 -279.227226) (xy 455.756017 -279.282402) (xy 455.739949 -279.335809) (xy 455.716277 -279.386306)
			(xy 455.685504 -279.432819) (xy 455.648287 -279.474356) (xy 455.605419 -279.510031) (xy 455.557813 -279.539085)
			(xy 455.506484 -279.560897) (xy 455.452527 -279.575003) (xy 455.39709 -279.581103) (xy 455.341356 -279.579066)
			(xy 455.286513 -279.568936) (xy 455.233729 -279.550929) (xy 455.184129 -279.525428) (xy 455.138771 -279.492977)
			(xy 455.098622 -279.454268) (xy 455.064536 -279.410125) (xy 455.03724 -279.36149) (xy 455.017317 -279.309399)
			(xy 455.005191 -279.254962) (xy 455.00112 -279.19934) (xy 448.422389 -279.19934) (xy 448.419651 -279.201011)
			(xy 448.368322 -279.222823) (xy 448.314365 -279.236929) (xy 448.258928 -279.243029) (xy 448.203194 -279.240992)
			(xy 448.148351 -279.230862) (xy 448.095567 -279.212855) (xy 448.045967 -279.187354) (xy 448.000609 -279.154903)
			(xy 447.96046 -279.116194) (xy 447.926374 -279.072051) (xy 447.899078 -279.023416) (xy 447.879155 -278.971325)
			(xy 447.867029 -278.916888) (xy 447.862958 -278.861266) (xy 431.048786 -278.861266) (xy 431.046882 -278.872982)
			(xy 431.031298 -278.919663) (xy 431.008427 -278.96324) (xy 430.978862 -279.002584) (xy 430.943369 -279.036676)
			(xy 430.902866 -279.064632) (xy 430.858404 -279.08573) (xy 430.811133 -279.099422) (xy 430.762278 -279.105354)
			(xy 430.713103 -279.103373) (xy 430.664884 -279.093529) (xy 430.618868 -279.076077) (xy 430.576247 -279.05147)
			(xy 430.538126 -279.020345) (xy 430.505491 -278.983508) (xy 430.479188 -278.941912) (xy 430.459897 -278.896636)
			(xy 430.44812 -278.848852) (xy 430.44416 -278.799798) (xy 430.105312 -278.799798) (xy 430.104817 -278.824405)
			(xy 430.096922 -278.872982) (xy 430.081338 -278.919663) (xy 430.058467 -278.96324) (xy 430.028902 -279.002584)
			(xy 429.993409 -279.036676) (xy 429.952906 -279.064632) (xy 429.908444 -279.08573) (xy 429.861173 -279.099422)
			(xy 429.812318 -279.105354) (xy 429.763143 -279.103373) (xy 429.714924 -279.093529) (xy 429.668908 -279.076077)
			(xy 429.626287 -279.05147) (xy 429.588166 -279.020345) (xy 429.555531 -278.983508) (xy 429.529228 -278.941912)
			(xy 429.509937 -278.896636) (xy 429.49816 -278.848852) (xy 429.4942 -278.799798) (xy 429.176942 -278.799798)
			(xy 429.176438 -278.825506) (xy 429.168395 -278.876288) (xy 429.152507 -278.925187) (xy 429.129164 -278.970999)
			(xy 429.098943 -279.012595) (xy 429.062587 -279.048951) (xy 429.020991 -279.079172) (xy 428.975179 -279.102515)
			(xy 428.92628 -279.118403) (xy 428.875498 -279.126446) (xy 428.824082 -279.126446) (xy 428.7733 -279.118403)
			(xy 428.724401 -279.102515) (xy 428.678589 -279.079172) (xy 428.636993 -279.048951) (xy 428.600637 -279.012595)
			(xy 428.570416 -278.970999) (xy 428.547073 -278.925187) (xy 428.531185 -278.876288) (xy 428.523142 -278.825506)
			(xy 428.204464 -278.825506) (xy 428.196748 -278.872982) (xy 428.181164 -278.919663) (xy 428.158293 -278.96324)
			(xy 428.128728 -279.002584) (xy 428.093235 -279.036676) (xy 428.052732 -279.064632) (xy 428.00827 -279.08573)
			(xy 427.960999 -279.099422) (xy 427.912144 -279.105354) (xy 427.862969 -279.103373) (xy 427.81475 -279.093529)
			(xy 427.768734 -279.076077) (xy 427.726113 -279.05147) (xy 427.687992 -279.020345) (xy 427.655357 -278.983508)
			(xy 427.629054 -278.941912) (xy 427.609763 -278.896636) (xy 427.597986 -278.848852) (xy 427.594026 -278.799798)
			(xy 427.276768 -278.799798) (xy 427.276264 -278.825506) (xy 427.268221 -278.876288) (xy 427.252333 -278.925187)
			(xy 427.22899 -278.970999) (xy 427.198769 -279.012595) (xy 427.162413 -279.048951) (xy 427.120817 -279.079172)
			(xy 427.075005 -279.102515) (xy 427.026106 -279.118403) (xy 426.975324 -279.126446) (xy 426.923908 -279.126446)
			(xy 426.873126 -279.118403) (xy 426.824227 -279.102515) (xy 426.778415 -279.079172) (xy 426.736819 -279.048951)
			(xy 426.700463 -279.012595) (xy 426.670242 -278.970999) (xy 426.646899 -278.925187) (xy 426.631011 -278.876288)
			(xy 426.622968 -278.825506) (xy 426.304544 -278.825506) (xy 426.296828 -278.872982) (xy 426.281244 -278.919663)
			(xy 426.258373 -278.96324) (xy 426.228808 -279.002584) (xy 426.193315 -279.036676) (xy 426.152812 -279.064632)
			(xy 426.10835 -279.08573) (xy 426.061079 -279.099422) (xy 426.012224 -279.105354) (xy 425.963049 -279.103373)
			(xy 425.91483 -279.093529) (xy 425.868814 -279.076077) (xy 425.826193 -279.05147) (xy 425.788072 -279.020345)
			(xy 425.755437 -278.983508) (xy 425.729134 -278.941912) (xy 425.709843 -278.896636) (xy 425.698066 -278.848852)
			(xy 425.694106 -278.799798) (xy 425.376848 -278.799798) (xy 425.376344 -278.825506) (xy 425.368301 -278.876288)
			(xy 425.352413 -278.925187) (xy 425.32907 -278.970999) (xy 425.298849 -279.012595) (xy 425.262493 -279.048951)
			(xy 425.220897 -279.079172) (xy 425.175085 -279.102515) (xy 425.126186 -279.118403) (xy 425.075404 -279.126446)
			(xy 425.023988 -279.126446) (xy 424.973206 -279.118403) (xy 424.924307 -279.102515) (xy 424.878495 -279.079172)
			(xy 424.836899 -279.048951) (xy 424.800543 -279.012595) (xy 424.770322 -278.970999) (xy 424.746979 -278.925187)
			(xy 424.731091 -278.876288) (xy 424.723048 -278.825506) (xy 424.404624 -278.825506) (xy 424.396908 -278.872982)
			(xy 424.381324 -278.919663) (xy 424.358453 -278.96324) (xy 424.328888 -279.002584) (xy 424.293395 -279.036676)
			(xy 424.252892 -279.064632) (xy 424.20843 -279.08573) (xy 424.161159 -279.099422) (xy 424.112304 -279.105354)
			(xy 424.063129 -279.103373) (xy 424.01491 -279.093529) (xy 423.968894 -279.076077) (xy 423.926273 -279.05147)
			(xy 423.888152 -279.020345) (xy 423.855517 -278.983508) (xy 423.829214 -278.941912) (xy 423.809923 -278.896636)
			(xy 423.798146 -278.848852) (xy 423.794186 -278.799798) (xy 423.476928 -278.799798) (xy 423.476424 -278.825506)
			(xy 423.468381 -278.876288) (xy 423.452493 -278.925187) (xy 423.42915 -278.970999) (xy 423.398929 -279.012595)
			(xy 423.362573 -279.048951) (xy 423.320977 -279.079172) (xy 423.275165 -279.102515) (xy 423.226266 -279.118403)
			(xy 423.175484 -279.126446) (xy 423.124068 -279.126446) (xy 423.073286 -279.118403) (xy 423.024387 -279.102515)
			(xy 422.978575 -279.079172) (xy 422.936979 -279.048951) (xy 422.900623 -279.012595) (xy 422.870402 -278.970999)
			(xy 422.847059 -278.925187) (xy 422.831171 -278.876288) (xy 422.823128 -278.825506) (xy 422.50445 -278.825506)
			(xy 422.496734 -278.872982) (xy 422.48115 -278.919663) (xy 422.458279 -278.96324) (xy 422.428714 -279.002584)
			(xy 422.393221 -279.036676) (xy 422.352718 -279.064632) (xy 422.308256 -279.08573) (xy 422.260985 -279.099422)
			(xy 422.21213 -279.105354) (xy 422.162955 -279.103373) (xy 422.114736 -279.093529) (xy 422.06872 -279.076077)
			(xy 422.026099 -279.05147) (xy 421.987978 -279.020345) (xy 421.955343 -278.983508) (xy 421.92904 -278.941912)
			(xy 421.909749 -278.896636) (xy 421.897972 -278.848852) (xy 421.894012 -278.799798) (xy 421.576754 -278.799798)
			(xy 421.57625 -278.825506) (xy 421.568207 -278.876288) (xy 421.552319 -278.925187) (xy 421.528976 -278.970999)
			(xy 421.498755 -279.012595) (xy 421.462399 -279.048951) (xy 421.420803 -279.079172) (xy 421.374991 -279.102515)
			(xy 421.326092 -279.118403) (xy 421.27531 -279.126446) (xy 421.223894 -279.126446) (xy 421.173112 -279.118403)
			(xy 421.124213 -279.102515) (xy 421.078401 -279.079172) (xy 421.036805 -279.048951) (xy 421.000449 -279.012595)
			(xy 420.970228 -278.970999) (xy 420.946885 -278.925187) (xy 420.930997 -278.876288) (xy 420.922954 -278.825506)
			(xy 420.60453 -278.825506) (xy 420.596814 -278.872982) (xy 420.58123 -278.919663) (xy 420.558359 -278.96324)
			(xy 420.528794 -279.002584) (xy 420.493301 -279.036676) (xy 420.452798 -279.064632) (xy 420.408336 -279.08573)
			(xy 420.361065 -279.099422) (xy 420.31221 -279.105354) (xy 420.263035 -279.103373) (xy 420.214816 -279.093529)
			(xy 420.1688 -279.076077) (xy 420.126179 -279.05147) (xy 420.088058 -279.020345) (xy 420.055423 -278.983508)
			(xy 420.02912 -278.941912) (xy 420.009829 -278.896636) (xy 419.998052 -278.848852) (xy 419.994092 -278.799798)
			(xy 419.676834 -278.799798) (xy 419.67633 -278.825506) (xy 419.668287 -278.876288) (xy 419.652399 -278.925187)
			(xy 419.629056 -278.970999) (xy 419.598835 -279.012595) (xy 419.562479 -279.048951) (xy 419.520883 -279.079172)
			(xy 419.475071 -279.102515) (xy 419.426172 -279.118403) (xy 419.37539 -279.126446) (xy 419.323974 -279.126446)
			(xy 419.273192 -279.118403) (xy 419.224293 -279.102515) (xy 419.178481 -279.079172) (xy 419.136885 -279.048951)
			(xy 419.100529 -279.012595) (xy 419.070308 -278.970999) (xy 419.046965 -278.925187) (xy 419.031077 -278.876288)
			(xy 419.023034 -278.825506) (xy 418.70461 -278.825506) (xy 418.696894 -278.872982) (xy 418.68131 -278.919663)
			(xy 418.658439 -278.96324) (xy 418.628874 -279.002584) (xy 418.593381 -279.036676) (xy 418.552878 -279.064632)
			(xy 418.508416 -279.08573) (xy 418.461145 -279.099422) (xy 418.41229 -279.105354) (xy 418.363115 -279.103373)
			(xy 418.314896 -279.093529) (xy 418.26888 -279.076077) (xy 418.226259 -279.05147) (xy 418.188138 -279.020345)
			(xy 418.155503 -278.983508) (xy 418.1292 -278.941912) (xy 418.109909 -278.896636) (xy 418.098132 -278.848852)
			(xy 418.094172 -278.799798) (xy 417.776914 -278.799798) (xy 417.77641 -278.825506) (xy 417.768367 -278.876288)
			(xy 417.752479 -278.925187) (xy 417.729136 -278.970999) (xy 417.698915 -279.012595) (xy 417.662559 -279.048951)
			(xy 417.620963 -279.079172) (xy 417.575151 -279.102515) (xy 417.526252 -279.118403) (xy 417.47547 -279.126446)
			(xy 417.424054 -279.126446) (xy 417.373272 -279.118403) (xy 417.324373 -279.102515) (xy 417.278561 -279.079172)
			(xy 417.236965 -279.048951) (xy 417.200609 -279.012595) (xy 417.170388 -278.970999) (xy 417.147045 -278.925187)
			(xy 417.131157 -278.876288) (xy 417.123114 -278.825506) (xy 416.804436 -278.825506) (xy 416.79672 -278.872982)
			(xy 416.781136 -278.919663) (xy 416.758265 -278.96324) (xy 416.7287 -279.002584) (xy 416.693207 -279.036676)
			(xy 416.652704 -279.064632) (xy 416.608242 -279.08573) (xy 416.560971 -279.099422) (xy 416.512116 -279.105354)
			(xy 416.462941 -279.103373) (xy 416.414722 -279.093529) (xy 416.368706 -279.076077) (xy 416.326085 -279.05147)
			(xy 416.287964 -279.020345) (xy 416.255329 -278.983508) (xy 416.229026 -278.941912) (xy 416.209735 -278.896636)
			(xy 416.197958 -278.848852) (xy 416.193998 -278.799798) (xy 415.87674 -278.799798) (xy 415.876236 -278.825506)
			(xy 415.868193 -278.876288) (xy 415.852305 -278.925187) (xy 415.828962 -278.970999) (xy 415.798741 -279.012595)
			(xy 415.762385 -279.048951) (xy 415.720789 -279.079172) (xy 415.674977 -279.102515) (xy 415.626078 -279.118403)
			(xy 415.575296 -279.126446) (xy 415.52388 -279.126446) (xy 415.473098 -279.118403) (xy 415.424199 -279.102515)
			(xy 415.378387 -279.079172) (xy 415.336791 -279.048951) (xy 415.300435 -279.012595) (xy 415.270214 -278.970999)
			(xy 415.246871 -278.925187) (xy 415.230983 -278.876288) (xy 415.22294 -278.825506) (xy 414.904516 -278.825506)
			(xy 414.8968 -278.872982) (xy 414.881216 -278.919663) (xy 414.858345 -278.96324) (xy 414.82878 -279.002584)
			(xy 414.793287 -279.036676) (xy 414.752784 -279.064632) (xy 414.708322 -279.08573) (xy 414.661051 -279.099422)
			(xy 414.612196 -279.105354) (xy 414.563021 -279.103373) (xy 414.514802 -279.093529) (xy 414.468786 -279.076077)
			(xy 414.426165 -279.05147) (xy 414.388044 -279.020345) (xy 414.355409 -278.983508) (xy 414.329106 -278.941912)
			(xy 414.309815 -278.896636) (xy 414.298038 -278.848852) (xy 414.294078 -278.799798) (xy 413.97682 -278.799798)
			(xy 413.976316 -278.825506) (xy 413.968273 -278.876288) (xy 413.952385 -278.925187) (xy 413.929042 -278.970999)
			(xy 413.898821 -279.012595) (xy 413.862465 -279.048951) (xy 413.820869 -279.079172) (xy 413.775057 -279.102515)
			(xy 413.726158 -279.118403) (xy 413.675376 -279.126446) (xy 413.62396 -279.126446) (xy 413.573178 -279.118403)
			(xy 413.524279 -279.102515) (xy 413.478467 -279.079172) (xy 413.436871 -279.048951) (xy 413.400515 -279.012595)
			(xy 413.370294 -278.970999) (xy 413.346951 -278.925187) (xy 413.331063 -278.876288) (xy 413.32302 -278.825506)
			(xy 413.004596 -278.825506) (xy 412.99688 -278.872982) (xy 412.981296 -278.919663) (xy 412.958425 -278.96324)
			(xy 412.92886 -279.002584) (xy 412.893367 -279.036676) (xy 412.852864 -279.064632) (xy 412.808402 -279.08573)
			(xy 412.761131 -279.099422) (xy 412.712276 -279.105354) (xy 412.663101 -279.103373) (xy 412.614882 -279.093529)
			(xy 412.568866 -279.076077) (xy 412.526245 -279.05147) (xy 412.488124 -279.020345) (xy 412.455489 -278.983508)
			(xy 412.429186 -278.941912) (xy 412.409895 -278.896636) (xy 412.398118 -278.848852) (xy 412.394158 -278.799798)
			(xy 412.0769 -278.799798) (xy 412.076396 -278.825506) (xy 412.068353 -278.876288) (xy 412.052465 -278.925187)
			(xy 412.029122 -278.970999) (xy 411.998901 -279.012595) (xy 411.962545 -279.048951) (xy 411.920949 -279.079172)
			(xy 411.875137 -279.102515) (xy 411.826238 -279.118403) (xy 411.775456 -279.126446) (xy 411.72404 -279.126446)
			(xy 411.673258 -279.118403) (xy 411.624359 -279.102515) (xy 411.578547 -279.079172) (xy 411.536951 -279.048951)
			(xy 411.500595 -279.012595) (xy 411.470374 -278.970999) (xy 411.447031 -278.925187) (xy 411.431143 -278.876288)
			(xy 411.4231 -278.825506) (xy 411.104422 -278.825506) (xy 411.096706 -278.872982) (xy 411.081122 -278.919663)
			(xy 411.058251 -278.96324) (xy 411.028686 -279.002584) (xy 410.993193 -279.036676) (xy 410.95269 -279.064632)
			(xy 410.908228 -279.08573) (xy 410.860957 -279.099422) (xy 410.812102 -279.105354) (xy 410.762927 -279.103373)
			(xy 410.714708 -279.093529) (xy 410.668692 -279.076077) (xy 410.626071 -279.05147) (xy 410.58795 -279.020345)
			(xy 410.555315 -278.983508) (xy 410.529012 -278.941912) (xy 410.509721 -278.896636) (xy 410.497944 -278.848852)
			(xy 410.493984 -278.799798) (xy 410.176726 -278.799798) (xy 410.176222 -278.825506) (xy 410.168179 -278.876288)
			(xy 410.152291 -278.925187) (xy 410.128948 -278.970999) (xy 410.098727 -279.012595) (xy 410.062371 -279.048951)
			(xy 410.020775 -279.079172) (xy 409.974963 -279.102515) (xy 409.926064 -279.118403) (xy 409.875282 -279.126446)
			(xy 409.823866 -279.126446) (xy 409.773084 -279.118403) (xy 409.724185 -279.102515) (xy 409.678373 -279.079172)
			(xy 409.636777 -279.048951) (xy 409.600421 -279.012595) (xy 409.5702 -278.970999) (xy 409.546857 -278.925187)
			(xy 409.530969 -278.876288) (xy 409.522926 -278.825506) (xy 409.204502 -278.825506) (xy 409.196786 -278.872982)
			(xy 409.181202 -278.919663) (xy 409.158331 -278.96324) (xy 409.128766 -279.002584) (xy 409.093273 -279.036676)
			(xy 409.05277 -279.064632) (xy 409.008308 -279.08573) (xy 408.961037 -279.099422) (xy 408.912182 -279.105354)
			(xy 408.863007 -279.103373) (xy 408.814788 -279.093529) (xy 408.768772 -279.076077) (xy 408.726151 -279.05147)
			(xy 408.68803 -279.020345) (xy 408.655395 -278.983508) (xy 408.629092 -278.941912) (xy 408.609801 -278.896636)
			(xy 408.598024 -278.848852) (xy 408.594064 -278.799798) (xy 408.276122 -278.799798) (xy 408.276122 -278.825492)
			(xy 408.268083 -278.876244) (xy 408.252203 -278.925113) (xy 408.228873 -278.970896) (xy 408.198667 -279.012466)
			(xy 408.16233 -279.048797) (xy 408.120757 -279.078997) (xy 408.074971 -279.10232) (xy 408.026099 -279.118194)
			(xy 407.975346 -279.126226) (xy 407.949654 -279.126696) (xy 407.941018 -279.126696) (xy 407.927302 -279.126442)
			(xy 407.915618 -279.132792) (xy 407.906982 -279.138634) (xy 407.903866 -279.141404) (xy 407.898499 -279.147783)
			(xy 407.896314 -279.151334) (xy 407.850594 -279.226772) (xy 407.847289 -279.232604) (xy 407.843566 -279.245477)
			(xy 407.843228 -279.252172) (xy 407.842974 -279.265634) (xy 407.849578 -279.277572) (xy 407.867208 -279.309979)
			(xy 407.8981 -279.37698) (xy 407.9113 -279.41143) (xy 407.915251 -279.420723) (xy 407.929058 -279.435435)
			(xy 407.947456 -279.443718) (xy 407.957528 -279.44445) (xy 407.981128 -279.445474) (xy 408.027607 -279.4539)
			(xy 408.072233 -279.469385) (xy 408.113941 -279.491559) (xy 408.151735 -279.519894) (xy 408.184713 -279.553713)
			(xy 408.212087 -279.592209) (xy 408.233204 -279.634462) (xy 408.247561 -279.679464) (xy 408.254813 -279.72614)
			(xy 408.255216 -279.749758) (xy 408.254691 -279.775212) (xy 408.57322 -279.775212) (xy 408.57322 -279.723796)
			(xy 408.581263 -279.673014) (xy 408.597151 -279.624115) (xy 408.620494 -279.578303) (xy 408.650715 -279.536707)
			(xy 408.687071 -279.500351) (xy 408.728667 -279.47013) (xy 408.774479 -279.446787) (xy 408.823378 -279.430899)
			(xy 408.87416 -279.422856) (xy 408.925576 -279.422856) (xy 408.976358 -279.430899) (xy 409.025257 -279.446787)
			(xy 409.071069 -279.47013) (xy 409.112665 -279.500351) (xy 409.149021 -279.536707) (xy 409.179242 -279.578303)
			(xy 409.202585 -279.624115) (xy 409.218473 -279.673014) (xy 409.226516 -279.723796) (xy 409.22702 -279.749504)
			(xy 409.227015 -279.749758) (xy 409.544024 -279.749758) (xy 409.547984 -279.700704) (xy 409.559761 -279.65292)
			(xy 409.579052 -279.607644) (xy 409.605355 -279.566048) (xy 409.63799 -279.529211) (xy 409.676111 -279.498086)
			(xy 409.718732 -279.473479) (xy 409.764748 -279.456027) (xy 409.812967 -279.446183) (xy 409.862142 -279.444202)
			(xy 409.910997 -279.450134) (xy 409.958268 -279.463826) (xy 410.00273 -279.484924) (xy 410.043233 -279.51288)
			(xy 410.078726 -279.546972) (xy 410.108291 -279.586316) (xy 410.131162 -279.629893) (xy 410.146746 -279.676574)
			(xy 410.154641 -279.725151) (xy 410.155136 -279.749758) (xy 410.154641 -279.774365) (xy 410.154503 -279.775212)
			(xy 410.47314 -279.775212) (xy 410.47314 -279.723796) (xy 410.481183 -279.673014) (xy 410.497071 -279.624115)
			(xy 410.520414 -279.578303) (xy 410.550635 -279.536707) (xy 410.586991 -279.500351) (xy 410.628587 -279.47013)
			(xy 410.674399 -279.446787) (xy 410.723298 -279.430899) (xy 410.77408 -279.422856) (xy 410.825496 -279.422856)
			(xy 410.876278 -279.430899) (xy 410.925177 -279.446787) (xy 410.970989 -279.47013) (xy 411.012585 -279.500351)
			(xy 411.048941 -279.536707) (xy 411.079162 -279.578303) (xy 411.102505 -279.624115) (xy 411.118393 -279.673014)
			(xy 411.126436 -279.723796) (xy 411.12694 -279.749504) (xy 411.126935 -279.749758) (xy 411.444198 -279.749758)
			(xy 411.448158 -279.700704) (xy 411.459935 -279.65292) (xy 411.479226 -279.607644) (xy 411.505529 -279.566048)
			(xy 411.538164 -279.529211) (xy 411.576285 -279.498086) (xy 411.618906 -279.473479) (xy 411.664922 -279.456027)
			(xy 411.713141 -279.446183) (xy 411.762316 -279.444202) (xy 411.811171 -279.450134) (xy 411.858442 -279.463826)
			(xy 411.902904 -279.484924) (xy 411.943407 -279.51288) (xy 411.9789 -279.546972) (xy 412.008465 -279.586316)
			(xy 412.031336 -279.629893) (xy 412.04692 -279.676574) (xy 412.054815 -279.725151) (xy 412.05531 -279.749758)
			(xy 412.054815 -279.774365) (xy 412.054677 -279.775212) (xy 412.373314 -279.775212) (xy 412.373314 -279.723796)
			(xy 412.381357 -279.673014) (xy 412.397245 -279.624115) (xy 412.420588 -279.578303) (xy 412.450809 -279.536707)
			(xy 412.487165 -279.500351) (xy 412.528761 -279.47013) (xy 412.574573 -279.446787) (xy 412.623472 -279.430899)
			(xy 412.674254 -279.422856) (xy 412.72567 -279.422856) (xy 412.776452 -279.430899) (xy 412.825351 -279.446787)
			(xy 412.871163 -279.47013) (xy 412.912759 -279.500351) (xy 412.949115 -279.536707) (xy 412.979336 -279.578303)
			(xy 413.002679 -279.624115) (xy 413.018567 -279.673014) (xy 413.02661 -279.723796) (xy 413.027114 -279.749504)
			(xy 413.027109 -279.749758) (xy 413.344118 -279.749758) (xy 413.348078 -279.700704) (xy 413.359855 -279.65292)
			(xy 413.379146 -279.607644) (xy 413.405449 -279.566048) (xy 413.438084 -279.529211) (xy 413.476205 -279.498086)
			(xy 413.518826 -279.473479) (xy 413.564842 -279.456027) (xy 413.613061 -279.446183) (xy 413.662236 -279.444202)
			(xy 413.711091 -279.450134) (xy 413.758362 -279.463826) (xy 413.802824 -279.484924) (xy 413.843327 -279.51288)
			(xy 413.87882 -279.546972) (xy 413.908385 -279.586316) (xy 413.931256 -279.629893) (xy 413.94684 -279.676574)
			(xy 413.954735 -279.725151) (xy 413.95523 -279.749758) (xy 413.954735 -279.774365) (xy 413.954597 -279.775212)
			(xy 414.273234 -279.775212) (xy 414.273234 -279.723796) (xy 414.281277 -279.673014) (xy 414.297165 -279.624115)
			(xy 414.320508 -279.578303) (xy 414.350729 -279.536707) (xy 414.387085 -279.500351) (xy 414.428681 -279.47013)
			(xy 414.474493 -279.446787) (xy 414.523392 -279.430899) (xy 414.574174 -279.422856) (xy 414.62559 -279.422856)
			(xy 414.676372 -279.430899) (xy 414.725271 -279.446787) (xy 414.771083 -279.47013) (xy 414.812679 -279.500351)
			(xy 414.849035 -279.536707) (xy 414.879256 -279.578303) (xy 414.902599 -279.624115) (xy 414.918487 -279.673014)
			(xy 414.92653 -279.723796) (xy 414.927034 -279.749504) (xy 414.927029 -279.749758) (xy 415.244038 -279.749758)
			(xy 415.247998 -279.700704) (xy 415.259775 -279.65292) (xy 415.279066 -279.607644) (xy 415.305369 -279.566048)
			(xy 415.338004 -279.529211) (xy 415.376125 -279.498086) (xy 415.418746 -279.473479) (xy 415.464762 -279.456027)
			(xy 415.512981 -279.446183) (xy 415.562156 -279.444202) (xy 415.611011 -279.450134) (xy 415.658282 -279.463826)
			(xy 415.702744 -279.484924) (xy 415.743247 -279.51288) (xy 415.77874 -279.546972) (xy 415.808305 -279.586316)
			(xy 415.831176 -279.629893) (xy 415.84676 -279.676574) (xy 415.854655 -279.725151) (xy 415.85515 -279.749758)
			(xy 415.854655 -279.774365) (xy 415.854517 -279.775212) (xy 416.173154 -279.775212) (xy 416.173154 -279.723796)
			(xy 416.181197 -279.673014) (xy 416.197085 -279.624115) (xy 416.220428 -279.578303) (xy 416.250649 -279.536707)
			(xy 416.287005 -279.500351) (xy 416.328601 -279.47013) (xy 416.374413 -279.446787) (xy 416.423312 -279.430899)
			(xy 416.474094 -279.422856) (xy 416.52551 -279.422856) (xy 416.576292 -279.430899) (xy 416.625191 -279.446787)
			(xy 416.671003 -279.47013) (xy 416.712599 -279.500351) (xy 416.748955 -279.536707) (xy 416.779176 -279.578303)
			(xy 416.802519 -279.624115) (xy 416.818407 -279.673014) (xy 416.82645 -279.723796) (xy 416.826954 -279.749504)
			(xy 416.826949 -279.749758) (xy 417.144212 -279.749758) (xy 417.148172 -279.700704) (xy 417.159949 -279.65292)
			(xy 417.17924 -279.607644) (xy 417.205543 -279.566048) (xy 417.238178 -279.529211) (xy 417.276299 -279.498086)
			(xy 417.31892 -279.473479) (xy 417.364936 -279.456027) (xy 417.413155 -279.446183) (xy 417.46233 -279.444202)
			(xy 417.511185 -279.450134) (xy 417.558456 -279.463826) (xy 417.602918 -279.484924) (xy 417.643421 -279.51288)
			(xy 417.678914 -279.546972) (xy 417.708479 -279.586316) (xy 417.73135 -279.629893) (xy 417.746934 -279.676574)
			(xy 417.754829 -279.725151) (xy 417.755324 -279.749758) (xy 417.754829 -279.774365) (xy 417.754691 -279.775212)
			(xy 418.073328 -279.775212) (xy 418.073328 -279.723796) (xy 418.081371 -279.673014) (xy 418.097259 -279.624115)
			(xy 418.120602 -279.578303) (xy 418.150823 -279.536707) (xy 418.187179 -279.500351) (xy 418.228775 -279.47013)
			(xy 418.274587 -279.446787) (xy 418.323486 -279.430899) (xy 418.374268 -279.422856) (xy 418.425684 -279.422856)
			(xy 418.476466 -279.430899) (xy 418.525365 -279.446787) (xy 418.571177 -279.47013) (xy 418.612773 -279.500351)
			(xy 418.649129 -279.536707) (xy 418.67935 -279.578303) (xy 418.702693 -279.624115) (xy 418.718581 -279.673014)
			(xy 418.726624 -279.723796) (xy 418.727128 -279.749504) (xy 418.727123 -279.749758) (xy 419.044132 -279.749758)
			(xy 419.048092 -279.700704) (xy 419.059869 -279.65292) (xy 419.07916 -279.607644) (xy 419.105463 -279.566048)
			(xy 419.138098 -279.529211) (xy 419.176219 -279.498086) (xy 419.21884 -279.473479) (xy 419.264856 -279.456027)
			(xy 419.313075 -279.446183) (xy 419.36225 -279.444202) (xy 419.411105 -279.450134) (xy 419.458376 -279.463826)
			(xy 419.502838 -279.484924) (xy 419.543341 -279.51288) (xy 419.578834 -279.546972) (xy 419.608399 -279.586316)
			(xy 419.63127 -279.629893) (xy 419.646854 -279.676574) (xy 419.654749 -279.725151) (xy 419.655244 -279.749758)
			(xy 419.654749 -279.774365) (xy 419.654611 -279.775212) (xy 419.973248 -279.775212) (xy 419.973248 -279.723796)
			(xy 419.981291 -279.673014) (xy 419.997179 -279.624115) (xy 420.020522 -279.578303) (xy 420.050743 -279.536707)
			(xy 420.087099 -279.500351) (xy 420.128695 -279.47013) (xy 420.174507 -279.446787) (xy 420.223406 -279.430899)
			(xy 420.274188 -279.422856) (xy 420.325604 -279.422856) (xy 420.376386 -279.430899) (xy 420.425285 -279.446787)
			(xy 420.471097 -279.47013) (xy 420.512693 -279.500351) (xy 420.549049 -279.536707) (xy 420.57927 -279.578303)
			(xy 420.602613 -279.624115) (xy 420.618501 -279.673014) (xy 420.626544 -279.723796) (xy 420.627048 -279.749504)
			(xy 420.627043 -279.749758) (xy 420.944052 -279.749758) (xy 420.948012 -279.700704) (xy 420.959789 -279.65292)
			(xy 420.97908 -279.607644) (xy 421.005383 -279.566048) (xy 421.038018 -279.529211) (xy 421.076139 -279.498086)
			(xy 421.11876 -279.473479) (xy 421.164776 -279.456027) (xy 421.212995 -279.446183) (xy 421.26217 -279.444202)
			(xy 421.311025 -279.450134) (xy 421.358296 -279.463826) (xy 421.402758 -279.484924) (xy 421.443261 -279.51288)
			(xy 421.478754 -279.546972) (xy 421.508319 -279.586316) (xy 421.53119 -279.629893) (xy 421.546774 -279.676574)
			(xy 421.554669 -279.725151) (xy 421.555164 -279.749758) (xy 421.554669 -279.774365) (xy 421.554531 -279.775212)
			(xy 421.873168 -279.775212) (xy 421.873168 -279.723796) (xy 421.881211 -279.673014) (xy 421.897099 -279.624115)
			(xy 421.920442 -279.578303) (xy 421.950663 -279.536707) (xy 421.987019 -279.500351) (xy 422.028615 -279.47013)
			(xy 422.074427 -279.446787) (xy 422.123326 -279.430899) (xy 422.174108 -279.422856) (xy 422.225524 -279.422856)
			(xy 422.276306 -279.430899) (xy 422.325205 -279.446787) (xy 422.371017 -279.47013) (xy 422.412613 -279.500351)
			(xy 422.448969 -279.536707) (xy 422.47919 -279.578303) (xy 422.502533 -279.624115) (xy 422.518421 -279.673014)
			(xy 422.526464 -279.723796) (xy 422.526968 -279.749504) (xy 422.526963 -279.749758) (xy 422.843972 -279.749758)
			(xy 422.847932 -279.700704) (xy 422.859709 -279.65292) (xy 422.879 -279.607644) (xy 422.905303 -279.566048)
			(xy 422.937938 -279.529211) (xy 422.976059 -279.498086) (xy 423.01868 -279.473479) (xy 423.064696 -279.456027)
			(xy 423.112915 -279.446183) (xy 423.16209 -279.444202) (xy 423.210945 -279.450134) (xy 423.258216 -279.463826)
			(xy 423.302678 -279.484924) (xy 423.343181 -279.51288) (xy 423.378674 -279.546972) (xy 423.408239 -279.586316)
			(xy 423.43111 -279.629893) (xy 423.446694 -279.676574) (xy 423.454589 -279.725151) (xy 423.455084 -279.749758)
			(xy 423.454589 -279.774365) (xy 423.454451 -279.775212) (xy 423.773342 -279.775212) (xy 423.773342 -279.723796)
			(xy 423.781385 -279.673014) (xy 423.797273 -279.624115) (xy 423.820616 -279.578303) (xy 423.850837 -279.536707)
			(xy 423.887193 -279.500351) (xy 423.928789 -279.47013) (xy 423.974601 -279.446787) (xy 424.0235 -279.430899)
			(xy 424.074282 -279.422856) (xy 424.125698 -279.422856) (xy 424.17648 -279.430899) (xy 424.225379 -279.446787)
			(xy 424.271191 -279.47013) (xy 424.312787 -279.500351) (xy 424.349143 -279.536707) (xy 424.379364 -279.578303)
			(xy 424.402707 -279.624115) (xy 424.418595 -279.673014) (xy 424.426638 -279.723796) (xy 424.427142 -279.749504)
			(xy 424.427137 -279.749758) (xy 424.744146 -279.749758) (xy 424.748106 -279.700704) (xy 424.759883 -279.65292)
			(xy 424.779174 -279.607644) (xy 424.805477 -279.566048) (xy 424.838112 -279.529211) (xy 424.876233 -279.498086)
			(xy 424.918854 -279.473479) (xy 424.96487 -279.456027) (xy 425.013089 -279.446183) (xy 425.062264 -279.444202)
			(xy 425.111119 -279.450134) (xy 425.15839 -279.463826) (xy 425.202852 -279.484924) (xy 425.243355 -279.51288)
			(xy 425.278848 -279.546972) (xy 425.308413 -279.586316) (xy 425.331284 -279.629893) (xy 425.346868 -279.676574)
			(xy 425.354763 -279.725151) (xy 425.355258 -279.749758) (xy 425.354763 -279.774365) (xy 425.354625 -279.775212)
			(xy 425.673262 -279.775212) (xy 425.673262 -279.723796) (xy 425.681305 -279.673014) (xy 425.697193 -279.624115)
			(xy 425.720536 -279.578303) (xy 425.750757 -279.536707) (xy 425.787113 -279.500351) (xy 425.828709 -279.47013)
			(xy 425.874521 -279.446787) (xy 425.92342 -279.430899) (xy 425.974202 -279.422856) (xy 426.025618 -279.422856)
			(xy 426.0764 -279.430899) (xy 426.125299 -279.446787) (xy 426.171111 -279.47013) (xy 426.212707 -279.500351)
			(xy 426.249063 -279.536707) (xy 426.279284 -279.578303) (xy 426.302627 -279.624115) (xy 426.318515 -279.673014)
			(xy 426.326558 -279.723796) (xy 426.327062 -279.749504) (xy 426.327057 -279.749758) (xy 426.644066 -279.749758)
			(xy 426.648026 -279.700704) (xy 426.659803 -279.65292) (xy 426.679094 -279.607644) (xy 426.705397 -279.566048)
			(xy 426.738032 -279.529211) (xy 426.776153 -279.498086) (xy 426.818774 -279.473479) (xy 426.86479 -279.456027)
			(xy 426.913009 -279.446183) (xy 426.962184 -279.444202) (xy 427.011039 -279.450134) (xy 427.05831 -279.463826)
			(xy 427.102772 -279.484924) (xy 427.143275 -279.51288) (xy 427.178768 -279.546972) (xy 427.208333 -279.586316)
			(xy 427.231204 -279.629893) (xy 427.246788 -279.676574) (xy 427.254683 -279.725151) (xy 427.255178 -279.749758)
			(xy 427.254683 -279.774365) (xy 427.254504 -279.775466) (xy 427.573182 -279.775466) (xy 427.573182 -279.72405)
			(xy 427.581225 -279.673268) (xy 427.597113 -279.624369) (xy 427.620456 -279.578557) (xy 427.650677 -279.536961)
			(xy 427.687033 -279.500605) (xy 427.728629 -279.470384) (xy 427.774441 -279.447041) (xy 427.82334 -279.431153)
			(xy 427.874122 -279.42311) (xy 427.925538 -279.42311) (xy 427.97632 -279.431153) (xy 428.025219 -279.447041)
			(xy 428.071031 -279.470384) (xy 428.112627 -279.500605) (xy 428.148983 -279.536961) (xy 428.179204 -279.578557)
			(xy 428.202547 -279.624369) (xy 428.218435 -279.673268) (xy 428.226478 -279.72405) (xy 428.226982 -279.749758)
			(xy 428.543986 -279.749758) (xy 428.547946 -279.700704) (xy 428.559723 -279.65292) (xy 428.579014 -279.607644)
			(xy 428.605317 -279.566048) (xy 428.637952 -279.529211) (xy 428.676073 -279.498086) (xy 428.718694 -279.473479)
			(xy 428.76471 -279.456027) (xy 428.812929 -279.446183) (xy 428.862104 -279.444202) (xy 428.910959 -279.450134)
			(xy 428.95823 -279.463826) (xy 429.002692 -279.484924) (xy 429.043195 -279.51288) (xy 429.078688 -279.546972)
			(xy 429.108253 -279.586316) (xy 429.131124 -279.629893) (xy 429.146708 -279.676574) (xy 429.154603 -279.725151)
			(xy 429.155098 -279.749758) (xy 429.154603 -279.774365) (xy 429.154424 -279.775466) (xy 429.473356 -279.775466)
			(xy 429.473356 -279.72405) (xy 429.481399 -279.673268) (xy 429.497287 -279.624369) (xy 429.52063 -279.578557)
			(xy 429.550851 -279.536961) (xy 429.587207 -279.500605) (xy 429.628803 -279.470384) (xy 429.674615 -279.447041)
			(xy 429.723514 -279.431153) (xy 429.774296 -279.42311) (xy 429.825712 -279.42311) (xy 429.876494 -279.431153)
			(xy 429.925393 -279.447041) (xy 429.971205 -279.470384) (xy 430.012801 -279.500605) (xy 430.049157 -279.536961)
			(xy 430.079378 -279.578557) (xy 430.102721 -279.624369) (xy 430.118609 -279.673268) (xy 430.126652 -279.72405)
			(xy 430.127156 -279.749758) (xy 430.126652 -279.775466) (xy 430.423316 -279.775466) (xy 430.423316 -279.72405)
			(xy 430.431359 -279.673268) (xy 430.447247 -279.624369) (xy 430.47059 -279.578557) (xy 430.500811 -279.536961)
			(xy 430.537167 -279.500605) (xy 430.578763 -279.470384) (xy 430.624575 -279.447041) (xy 430.673474 -279.431153)
			(xy 430.724256 -279.42311) (xy 430.775672 -279.42311) (xy 430.826454 -279.431153) (xy 430.875353 -279.447041)
			(xy 430.921165 -279.470384) (xy 430.962761 -279.500605) (xy 430.999117 -279.536961) (xy 431.029338 -279.578557)
			(xy 431.052681 -279.624369) (xy 431.068569 -279.673268) (xy 431.076612 -279.72405) (xy 431.077116 -279.749758)
			(xy 431.077111 -279.750012) (xy 431.394374 -279.750012) (xy 431.398334 -279.700958) (xy 431.410111 -279.653174)
			(xy 431.429402 -279.607898) (xy 431.455705 -279.566302) (xy 431.48834 -279.529465) (xy 431.526461 -279.49834)
			(xy 431.569082 -279.473733) (xy 431.615098 -279.456281) (xy 431.663317 -279.446437) (xy 431.712492 -279.444456)
			(xy 431.761347 -279.450388) (xy 431.808618 -279.46408) (xy 431.85308 -279.485178) (xy 431.893583 -279.513134)
			(xy 431.929076 -279.547226) (xy 431.958641 -279.58657) (xy 431.981512 -279.630147) (xy 431.997096 -279.676828)
			(xy 432.004991 -279.725405) (xy 432.005486 -279.750012) (xy 432.004991 -279.774619) (xy 431.997096 -279.823196)
			(xy 431.981512 -279.869877) (xy 431.970835 -279.89022) (xy 447.862958 -279.89022) (xy 447.867029 -279.834598)
			(xy 447.879155 -279.780161) (xy 447.899078 -279.72807) (xy 447.926374 -279.679435) (xy 447.96046 -279.635292)
			(xy 448.000609 -279.596583) (xy 448.045967 -279.564132) (xy 448.095567 -279.538631) (xy 448.148351 -279.520624)
			(xy 448.203194 -279.510494) (xy 448.258928 -279.508457) (xy 448.314365 -279.514557) (xy 448.368322 -279.528663)
			(xy 448.419651 -279.550475) (xy 448.467257 -279.579529) (xy 448.510125 -279.615204) (xy 448.547342 -279.656741)
			(xy 448.569895 -279.69083) (xy 461.074006 -279.69083) (xy 461.078077 -279.635208) (xy 461.090203 -279.580771)
			(xy 461.110126 -279.52868) (xy 461.137422 -279.480045) (xy 461.171508 -279.435902) (xy 461.211657 -279.397193)
			(xy 461.257015 -279.364742) (xy 461.306615 -279.339241) (xy 461.359399 -279.321234) (xy 461.414242 -279.311104)
			(xy 461.469976 -279.309067) (xy 461.525413 -279.315167) (xy 461.57937 -279.329273) (xy 461.630699 -279.351085)
			(xy 461.678305 -279.380139) (xy 461.721173 -279.415814) (xy 461.75839 -279.457351) (xy 461.789163 -279.503864)
			(xy 461.812835 -279.554361) (xy 461.828903 -279.607768) (xy 461.837023 -279.662944) (xy 461.837532 -279.69083)
			(xy 461.837023 -279.718716) (xy 461.828903 -279.773892) (xy 461.812835 -279.827299) (xy 461.789163 -279.877796)
			(xy 461.75839 -279.924309) (xy 461.721173 -279.965846) (xy 461.678305 -280.001521) (xy 461.630699 -280.030575)
			(xy 461.57937 -280.052387) (xy 461.525413 -280.066493) (xy 461.469976 -280.072593) (xy 461.414242 -280.070556)
			(xy 461.359399 -280.060426) (xy 461.306615 -280.042419) (xy 461.257015 -280.016918) (xy 461.211657 -279.984467)
			(xy 461.171508 -279.945758) (xy 461.137422 -279.901615) (xy 461.110126 -279.85298) (xy 461.090203 -279.800889)
			(xy 461.078077 -279.746452) (xy 461.074006 -279.69083) (xy 448.569895 -279.69083) (xy 448.578115 -279.703254)
			(xy 448.601787 -279.753751) (xy 448.617855 -279.807158) (xy 448.625975 -279.862334) (xy 448.626484 -279.89022)
			(xy 448.625975 -279.918106) (xy 448.617855 -279.973282) (xy 448.601787 -280.026689) (xy 448.578115 -280.077186)
			(xy 448.547342 -280.123699) (xy 448.510125 -280.165236) (xy 448.467257 -280.200911) (xy 448.428632 -280.224484)
			(xy 455.005184 -280.224484) (xy 455.009255 -280.168862) (xy 455.021381 -280.114425) (xy 455.041304 -280.062334)
			(xy 455.0686 -280.013699) (xy 455.102686 -279.969556) (xy 455.142835 -279.930847) (xy 455.188193 -279.898396)
			(xy 455.237793 -279.872895) (xy 455.290577 -279.854888) (xy 455.34542 -279.844758) (xy 455.401154 -279.842721)
			(xy 455.456591 -279.848821) (xy 455.510548 -279.862927) (xy 455.561877 -279.884739) (xy 455.609483 -279.913793)
			(xy 455.652351 -279.949468) (xy 455.689568 -279.991005) (xy 455.720341 -280.037518) (xy 455.744013 -280.088015)
			(xy 455.760081 -280.141422) (xy 455.768201 -280.196598) (xy 455.76871 -280.224484) (xy 457.024484 -280.224484)
			(xy 457.028555 -280.168862) (xy 457.040681 -280.114425) (xy 457.060604 -280.062334) (xy 457.0879 -280.013699)
			(xy 457.121986 -279.969556) (xy 457.162135 -279.930847) (xy 457.207493 -279.898396) (xy 457.257093 -279.872895)
			(xy 457.309877 -279.854888) (xy 457.36472 -279.844758) (xy 457.420454 -279.842721) (xy 457.475891 -279.848821)
			(xy 457.529848 -279.862927) (xy 457.581177 -279.884739) (xy 457.628783 -279.913793) (xy 457.671651 -279.949468)
			(xy 457.708868 -279.991005) (xy 457.739641 -280.037518) (xy 457.763313 -280.088015) (xy 457.779381 -280.141422)
			(xy 457.787501 -280.196598) (xy 457.78801 -280.224484) (xy 457.787501 -280.25237) (xy 457.779381 -280.307546)
			(xy 457.763313 -280.360953) (xy 457.739641 -280.41145) (xy 457.708868 -280.457963) (xy 457.671651 -280.4995)
			(xy 457.628783 -280.535175) (xy 457.581177 -280.564229) (xy 457.529848 -280.586041) (xy 457.475891 -280.600147)
			(xy 457.420454 -280.606247) (xy 457.36472 -280.60421) (xy 457.309877 -280.59408) (xy 457.257093 -280.576073)
			(xy 457.207493 -280.550572) (xy 457.162135 -280.518121) (xy 457.121986 -280.479412) (xy 457.0879 -280.435269)
			(xy 457.060604 -280.386634) (xy 457.040681 -280.334543) (xy 457.028555 -280.280106) (xy 457.024484 -280.224484)
			(xy 455.76871 -280.224484) (xy 455.768201 -280.25237) (xy 455.760081 -280.307546) (xy 455.744013 -280.360953)
			(xy 455.720341 -280.41145) (xy 455.689568 -280.457963) (xy 455.652351 -280.4995) (xy 455.609483 -280.535175)
			(xy 455.561877 -280.564229) (xy 455.510548 -280.586041) (xy 455.456591 -280.600147) (xy 455.401154 -280.606247)
			(xy 455.34542 -280.60421) (xy 455.290577 -280.59408) (xy 455.237793 -280.576073) (xy 455.188193 -280.550572)
			(xy 455.142835 -280.518121) (xy 455.102686 -280.479412) (xy 455.0686 -280.435269) (xy 455.041304 -280.386634)
			(xy 455.021381 -280.334543) (xy 455.009255 -280.280106) (xy 455.005184 -280.224484) (xy 448.428632 -280.224484)
			(xy 448.419651 -280.229965) (xy 448.368322 -280.251777) (xy 448.314365 -280.265883) (xy 448.258928 -280.271983)
			(xy 448.203194 -280.269946) (xy 448.148351 -280.259816) (xy 448.095567 -280.241809) (xy 448.045967 -280.216308)
			(xy 448.000609 -280.183857) (xy 447.96046 -280.145148) (xy 447.926374 -280.101005) (xy 447.899078 -280.05237)
			(xy 447.879155 -280.000279) (xy 447.867029 -279.945842) (xy 447.862958 -279.89022) (xy 431.970835 -279.89022)
			(xy 431.958641 -279.913454) (xy 431.929076 -279.952798) (xy 431.893583 -279.98689) (xy 431.85308 -280.014846)
			(xy 431.808618 -280.035944) (xy 431.761347 -280.049636) (xy 431.712492 -280.055568) (xy 431.663317 -280.053587)
			(xy 431.615098 -280.043743) (xy 431.569082 -280.026291) (xy 431.526461 -280.001684) (xy 431.48834 -279.970559)
			(xy 431.455705 -279.933722) (xy 431.429402 -279.892126) (xy 431.410111 -279.84685) (xy 431.398334 -279.799066)
			(xy 431.394374 -279.750012) (xy 431.077111 -279.750012) (xy 431.076612 -279.775466) (xy 431.068569 -279.826248)
			(xy 431.052681 -279.875147) (xy 431.029338 -279.920959) (xy 430.999117 -279.962555) (xy 430.962761 -279.998911)
			(xy 430.921165 -280.029132) (xy 430.875353 -280.052475) (xy 430.826454 -280.068363) (xy 430.775672 -280.076406)
			(xy 430.724256 -280.076406) (xy 430.673474 -280.068363) (xy 430.624575 -280.052475) (xy 430.578763 -280.029132)
			(xy 430.537167 -279.998911) (xy 430.500811 -279.962555) (xy 430.47059 -279.920959) (xy 430.447247 -279.875147)
			(xy 430.431359 -279.826248) (xy 430.423316 -279.775466) (xy 430.126652 -279.775466) (xy 430.118609 -279.826248)
			(xy 430.102721 -279.875147) (xy 430.079378 -279.920959) (xy 430.049157 -279.962555) (xy 430.012801 -279.998911)
			(xy 429.971205 -280.029132) (xy 429.925393 -280.052475) (xy 429.876494 -280.068363) (xy 429.825712 -280.076406)
			(xy 429.774296 -280.076406) (xy 429.723514 -280.068363) (xy 429.674615 -280.052475) (xy 429.628803 -280.029132)
			(xy 429.587207 -279.998911) (xy 429.550851 -279.962555) (xy 429.52063 -279.920959) (xy 429.497287 -279.875147)
			(xy 429.481399 -279.826248) (xy 429.473356 -279.775466) (xy 429.154424 -279.775466) (xy 429.146708 -279.822942)
			(xy 429.131124 -279.869623) (xy 429.108253 -279.9132) (xy 429.078688 -279.952544) (xy 429.043195 -279.986636)
			(xy 429.002692 -280.014592) (xy 428.95823 -280.03569) (xy 428.910959 -280.049382) (xy 428.862104 -280.055314)
			(xy 428.812929 -280.053333) (xy 428.76471 -280.043489) (xy 428.718694 -280.026037) (xy 428.676073 -280.00143)
			(xy 428.637952 -279.970305) (xy 428.605317 -279.933468) (xy 428.579014 -279.891872) (xy 428.559723 -279.846596)
			(xy 428.547946 -279.798812) (xy 428.543986 -279.749758) (xy 428.226982 -279.749758) (xy 428.226478 -279.775466)
			(xy 428.218435 -279.826248) (xy 428.202547 -279.875147) (xy 428.179204 -279.920959) (xy 428.148983 -279.962555)
			(xy 428.112627 -279.998911) (xy 428.071031 -280.029132) (xy 428.025219 -280.052475) (xy 427.97632 -280.068363)
			(xy 427.925538 -280.076406) (xy 427.874122 -280.076406) (xy 427.82334 -280.068363) (xy 427.774441 -280.052475)
			(xy 427.728629 -280.029132) (xy 427.687033 -279.998911) (xy 427.650677 -279.962555) (xy 427.620456 -279.920959)
			(xy 427.597113 -279.875147) (xy 427.581225 -279.826248) (xy 427.573182 -279.775466) (xy 427.254504 -279.775466)
			(xy 427.246788 -279.822942) (xy 427.231204 -279.869623) (xy 427.208333 -279.9132) (xy 427.178768 -279.952544)
			(xy 427.143275 -279.986636) (xy 427.102772 -280.014592) (xy 427.05831 -280.03569) (xy 427.011039 -280.049382)
			(xy 426.962184 -280.055314) (xy 426.913009 -280.053333) (xy 426.86479 -280.043489) (xy 426.818774 -280.026037)
			(xy 426.776153 -280.00143) (xy 426.738032 -279.970305) (xy 426.705397 -279.933468) (xy 426.679094 -279.891872)
			(xy 426.659803 -279.846596) (xy 426.648026 -279.798812) (xy 426.644066 -279.749758) (xy 426.327057 -279.749758)
			(xy 426.326558 -279.775212) (xy 426.318515 -279.825994) (xy 426.302627 -279.874893) (xy 426.279284 -279.920705)
			(xy 426.249063 -279.962301) (xy 426.212707 -279.998657) (xy 426.171111 -280.028878) (xy 426.125299 -280.052221)
			(xy 426.0764 -280.068109) (xy 426.025618 -280.076152) (xy 425.974202 -280.076152) (xy 425.92342 -280.068109)
			(xy 425.874521 -280.052221) (xy 425.828709 -280.028878) (xy 425.787113 -279.998657) (xy 425.750757 -279.962301)
			(xy 425.720536 -279.920705) (xy 425.697193 -279.874893) (xy 425.681305 -279.825994) (xy 425.673262 -279.775212)
			(xy 425.354625 -279.775212) (xy 425.346868 -279.822942) (xy 425.331284 -279.869623) (xy 425.308413 -279.9132)
			(xy 425.278848 -279.952544) (xy 425.243355 -279.986636) (xy 425.202852 -280.014592) (xy 425.15839 -280.03569)
			(xy 425.111119 -280.049382) (xy 425.062264 -280.055314) (xy 425.013089 -280.053333) (xy 424.96487 -280.043489)
			(xy 424.918854 -280.026037) (xy 424.876233 -280.00143) (xy 424.838112 -279.970305) (xy 424.805477 -279.933468)
			(xy 424.779174 -279.891872) (xy 424.759883 -279.846596) (xy 424.748106 -279.798812) (xy 424.744146 -279.749758)
			(xy 424.427137 -279.749758) (xy 424.426638 -279.775212) (xy 424.418595 -279.825994) (xy 424.402707 -279.874893)
			(xy 424.379364 -279.920705) (xy 424.349143 -279.962301) (xy 424.312787 -279.998657) (xy 424.271191 -280.028878)
			(xy 424.225379 -280.052221) (xy 424.17648 -280.068109) (xy 424.125698 -280.076152) (xy 424.074282 -280.076152)
			(xy 424.0235 -280.068109) (xy 423.974601 -280.052221) (xy 423.928789 -280.028878) (xy 423.887193 -279.998657)
			(xy 423.850837 -279.962301) (xy 423.820616 -279.920705) (xy 423.797273 -279.874893) (xy 423.781385 -279.825994)
			(xy 423.773342 -279.775212) (xy 423.454451 -279.775212) (xy 423.446694 -279.822942) (xy 423.43111 -279.869623)
			(xy 423.408239 -279.9132) (xy 423.378674 -279.952544) (xy 423.343181 -279.986636) (xy 423.302678 -280.014592)
			(xy 423.258216 -280.03569) (xy 423.210945 -280.049382) (xy 423.16209 -280.055314) (xy 423.112915 -280.053333)
			(xy 423.064696 -280.043489) (xy 423.01868 -280.026037) (xy 422.976059 -280.00143) (xy 422.937938 -279.970305)
			(xy 422.905303 -279.933468) (xy 422.879 -279.891872) (xy 422.859709 -279.846596) (xy 422.847932 -279.798812)
			(xy 422.843972 -279.749758) (xy 422.526963 -279.749758) (xy 422.526464 -279.775212) (xy 422.518421 -279.825994)
			(xy 422.502533 -279.874893) (xy 422.47919 -279.920705) (xy 422.448969 -279.962301) (xy 422.412613 -279.998657)
			(xy 422.371017 -280.028878) (xy 422.325205 -280.052221) (xy 422.276306 -280.068109) (xy 422.225524 -280.076152)
			(xy 422.174108 -280.076152) (xy 422.123326 -280.068109) (xy 422.074427 -280.052221) (xy 422.028615 -280.028878)
			(xy 421.987019 -279.998657) (xy 421.950663 -279.962301) (xy 421.920442 -279.920705) (xy 421.897099 -279.874893)
			(xy 421.881211 -279.825994) (xy 421.873168 -279.775212) (xy 421.554531 -279.775212) (xy 421.546774 -279.822942)
			(xy 421.53119 -279.869623) (xy 421.508319 -279.9132) (xy 421.478754 -279.952544) (xy 421.443261 -279.986636)
			(xy 421.402758 -280.014592) (xy 421.358296 -280.03569) (xy 421.311025 -280.049382) (xy 421.26217 -280.055314)
			(xy 421.212995 -280.053333) (xy 421.164776 -280.043489) (xy 421.11876 -280.026037) (xy 421.076139 -280.00143)
			(xy 421.038018 -279.970305) (xy 421.005383 -279.933468) (xy 420.97908 -279.891872) (xy 420.959789 -279.846596)
			(xy 420.948012 -279.798812) (xy 420.944052 -279.749758) (xy 420.627043 -279.749758) (xy 420.626544 -279.775212)
			(xy 420.618501 -279.825994) (xy 420.602613 -279.874893) (xy 420.57927 -279.920705) (xy 420.549049 -279.962301)
			(xy 420.512693 -279.998657) (xy 420.471097 -280.028878) (xy 420.425285 -280.052221) (xy 420.376386 -280.068109)
			(xy 420.325604 -280.076152) (xy 420.274188 -280.076152) (xy 420.223406 -280.068109) (xy 420.174507 -280.052221)
			(xy 420.128695 -280.028878) (xy 420.087099 -279.998657) (xy 420.050743 -279.962301) (xy 420.020522 -279.920705)
			(xy 419.997179 -279.874893) (xy 419.981291 -279.825994) (xy 419.973248 -279.775212) (xy 419.654611 -279.775212)
			(xy 419.646854 -279.822942) (xy 419.63127 -279.869623) (xy 419.608399 -279.9132) (xy 419.578834 -279.952544)
			(xy 419.543341 -279.986636) (xy 419.502838 -280.014592) (xy 419.458376 -280.03569) (xy 419.411105 -280.049382)
			(xy 419.36225 -280.055314) (xy 419.313075 -280.053333) (xy 419.264856 -280.043489) (xy 419.21884 -280.026037)
			(xy 419.176219 -280.00143) (xy 419.138098 -279.970305) (xy 419.105463 -279.933468) (xy 419.07916 -279.891872)
			(xy 419.059869 -279.846596) (xy 419.048092 -279.798812) (xy 419.044132 -279.749758) (xy 418.727123 -279.749758)
			(xy 418.726624 -279.775212) (xy 418.718581 -279.825994) (xy 418.702693 -279.874893) (xy 418.67935 -279.920705)
			(xy 418.649129 -279.962301) (xy 418.612773 -279.998657) (xy 418.571177 -280.028878) (xy 418.525365 -280.052221)
			(xy 418.476466 -280.068109) (xy 418.425684 -280.076152) (xy 418.374268 -280.076152) (xy 418.323486 -280.068109)
			(xy 418.274587 -280.052221) (xy 418.228775 -280.028878) (xy 418.187179 -279.998657) (xy 418.150823 -279.962301)
			(xy 418.120602 -279.920705) (xy 418.097259 -279.874893) (xy 418.081371 -279.825994) (xy 418.073328 -279.775212)
			(xy 417.754691 -279.775212) (xy 417.746934 -279.822942) (xy 417.73135 -279.869623) (xy 417.708479 -279.9132)
			(xy 417.678914 -279.952544) (xy 417.643421 -279.986636) (xy 417.602918 -280.014592) (xy 417.558456 -280.03569)
			(xy 417.511185 -280.049382) (xy 417.46233 -280.055314) (xy 417.413155 -280.053333) (xy 417.364936 -280.043489)
			(xy 417.31892 -280.026037) (xy 417.276299 -280.00143) (xy 417.238178 -279.970305) (xy 417.205543 -279.933468)
			(xy 417.17924 -279.891872) (xy 417.159949 -279.846596) (xy 417.148172 -279.798812) (xy 417.144212 -279.749758)
			(xy 416.826949 -279.749758) (xy 416.82645 -279.775212) (xy 416.818407 -279.825994) (xy 416.802519 -279.874893)
			(xy 416.779176 -279.920705) (xy 416.748955 -279.962301) (xy 416.712599 -279.998657) (xy 416.671003 -280.028878)
			(xy 416.625191 -280.052221) (xy 416.576292 -280.068109) (xy 416.52551 -280.076152) (xy 416.474094 -280.076152)
			(xy 416.423312 -280.068109) (xy 416.374413 -280.052221) (xy 416.328601 -280.028878) (xy 416.287005 -279.998657)
			(xy 416.250649 -279.962301) (xy 416.220428 -279.920705) (xy 416.197085 -279.874893) (xy 416.181197 -279.825994)
			(xy 416.173154 -279.775212) (xy 415.854517 -279.775212) (xy 415.84676 -279.822942) (xy 415.831176 -279.869623)
			(xy 415.808305 -279.9132) (xy 415.77874 -279.952544) (xy 415.743247 -279.986636) (xy 415.702744 -280.014592)
			(xy 415.658282 -280.03569) (xy 415.611011 -280.049382) (xy 415.562156 -280.055314) (xy 415.512981 -280.053333)
			(xy 415.464762 -280.043489) (xy 415.418746 -280.026037) (xy 415.376125 -280.00143) (xy 415.338004 -279.970305)
			(xy 415.305369 -279.933468) (xy 415.279066 -279.891872) (xy 415.259775 -279.846596) (xy 415.247998 -279.798812)
			(xy 415.244038 -279.749758) (xy 414.927029 -279.749758) (xy 414.92653 -279.775212) (xy 414.918487 -279.825994)
			(xy 414.902599 -279.874893) (xy 414.879256 -279.920705) (xy 414.849035 -279.962301) (xy 414.812679 -279.998657)
			(xy 414.771083 -280.028878) (xy 414.725271 -280.052221) (xy 414.676372 -280.068109) (xy 414.62559 -280.076152)
			(xy 414.574174 -280.076152) (xy 414.523392 -280.068109) (xy 414.474493 -280.052221) (xy 414.428681 -280.028878)
			(xy 414.387085 -279.998657) (xy 414.350729 -279.962301) (xy 414.320508 -279.920705) (xy 414.297165 -279.874893)
			(xy 414.281277 -279.825994) (xy 414.273234 -279.775212) (xy 413.954597 -279.775212) (xy 413.94684 -279.822942)
			(xy 413.931256 -279.869623) (xy 413.908385 -279.9132) (xy 413.87882 -279.952544) (xy 413.843327 -279.986636)
			(xy 413.802824 -280.014592) (xy 413.758362 -280.03569) (xy 413.711091 -280.049382) (xy 413.662236 -280.055314)
			(xy 413.613061 -280.053333) (xy 413.564842 -280.043489) (xy 413.518826 -280.026037) (xy 413.476205 -280.00143)
			(xy 413.438084 -279.970305) (xy 413.405449 -279.933468) (xy 413.379146 -279.891872) (xy 413.359855 -279.846596)
			(xy 413.348078 -279.798812) (xy 413.344118 -279.749758) (xy 413.027109 -279.749758) (xy 413.02661 -279.775212)
			(xy 413.018567 -279.825994) (xy 413.002679 -279.874893) (xy 412.979336 -279.920705) (xy 412.949115 -279.962301)
			(xy 412.912759 -279.998657) (xy 412.871163 -280.028878) (xy 412.825351 -280.052221) (xy 412.776452 -280.068109)
			(xy 412.72567 -280.076152) (xy 412.674254 -280.076152) (xy 412.623472 -280.068109) (xy 412.574573 -280.052221)
			(xy 412.528761 -280.028878) (xy 412.487165 -279.998657) (xy 412.450809 -279.962301) (xy 412.420588 -279.920705)
			(xy 412.397245 -279.874893) (xy 412.381357 -279.825994) (xy 412.373314 -279.775212) (xy 412.054677 -279.775212)
			(xy 412.04692 -279.822942) (xy 412.031336 -279.869623) (xy 412.008465 -279.9132) (xy 411.9789 -279.952544)
			(xy 411.943407 -279.986636) (xy 411.902904 -280.014592) (xy 411.858442 -280.03569) (xy 411.811171 -280.049382)
			(xy 411.762316 -280.055314) (xy 411.713141 -280.053333) (xy 411.664922 -280.043489) (xy 411.618906 -280.026037)
			(xy 411.576285 -280.00143) (xy 411.538164 -279.970305) (xy 411.505529 -279.933468) (xy 411.479226 -279.891872)
			(xy 411.459935 -279.846596) (xy 411.448158 -279.798812) (xy 411.444198 -279.749758) (xy 411.126935 -279.749758)
			(xy 411.126436 -279.775212) (xy 411.118393 -279.825994) (xy 411.102505 -279.874893) (xy 411.079162 -279.920705)
			(xy 411.048941 -279.962301) (xy 411.012585 -279.998657) (xy 410.970989 -280.028878) (xy 410.925177 -280.052221)
			(xy 410.876278 -280.068109) (xy 410.825496 -280.076152) (xy 410.77408 -280.076152) (xy 410.723298 -280.068109)
			(xy 410.674399 -280.052221) (xy 410.628587 -280.028878) (xy 410.586991 -279.998657) (xy 410.550635 -279.962301)
			(xy 410.520414 -279.920705) (xy 410.497071 -279.874893) (xy 410.481183 -279.825994) (xy 410.47314 -279.775212)
			(xy 410.154503 -279.775212) (xy 410.146746 -279.822942) (xy 410.131162 -279.869623) (xy 410.108291 -279.9132)
			(xy 410.078726 -279.952544) (xy 410.043233 -279.986636) (xy 410.00273 -280.014592) (xy 409.958268 -280.03569)
			(xy 409.910997 -280.049382) (xy 409.862142 -280.055314) (xy 409.812967 -280.053333) (xy 409.764748 -280.043489)
			(xy 409.718732 -280.026037) (xy 409.676111 -280.00143) (xy 409.63799 -279.970305) (xy 409.605355 -279.933468)
			(xy 409.579052 -279.891872) (xy 409.559761 -279.846596) (xy 409.547984 -279.798812) (xy 409.544024 -279.749758)
			(xy 409.227015 -279.749758) (xy 409.226516 -279.775212) (xy 409.218473 -279.825994) (xy 409.202585 -279.874893)
			(xy 409.179242 -279.920705) (xy 409.149021 -279.962301) (xy 409.112665 -279.998657) (xy 409.071069 -280.028878)
			(xy 409.025257 -280.052221) (xy 408.976358 -280.068109) (xy 408.925576 -280.076152) (xy 408.87416 -280.076152)
			(xy 408.823378 -280.068109) (xy 408.774479 -280.052221) (xy 408.728667 -280.028878) (xy 408.687071 -279.998657)
			(xy 408.650715 -279.962301) (xy 408.620494 -279.920705) (xy 408.597151 -279.874893) (xy 408.581263 -279.825994)
			(xy 408.57322 -279.775212) (xy 408.254691 -279.775212) (xy 408.254674 -279.776013) (xy 408.2457 -279.827751)
			(xy 408.228011 -279.877191) (xy 408.202126 -279.922878) (xy 408.16881 -279.963465) (xy 408.129043 -279.997756)
			(xy 408.083997 -280.02474) (xy 408.035 -280.043624) (xy 408.009344 -280.049224) (xy 407.99866 -280.051897)
			(xy 407.980859 -280.064824) (xy 407.97011 -280.08402) (xy 407.968704 -280.094944) (xy 407.96598 -280.124683)
			(xy 407.957338 -280.18378) (xy 407.951432 -280.213054) (xy 407.950924 -280.215086) (xy 407.95067 -280.216356)
			(xy 407.950061 -280.220525) (xy 407.950067 -280.22895) (xy 407.95067 -280.23312) (xy 407.950924 -280.23439)
			(xy 407.951432 -280.236422) (xy 407.957335 -280.265696) (xy 407.965978 -280.324793) (xy 407.968704 -280.354532)
			(xy 407.970128 -280.365447) (xy 407.980891 -280.384623) (xy 407.99867 -280.397563) (xy 408.009344 -280.400252)
			(xy 408.034987 -280.405899) (xy 408.083978 -280.424778) (xy 408.129019 -280.451758) (xy 408.168783 -280.486043)
			(xy 408.202097 -280.526623) (xy 408.227981 -280.572303) (xy 408.245671 -280.621736) (xy 408.254647 -280.673466)
			(xy 408.255216 -280.699718) (xy 408.254767 -280.723329) (xy 408.25444 -280.725426) (xy 408.57322 -280.725426)
			(xy 408.57322 -280.67401) (xy 408.581263 -280.623228) (xy 408.597151 -280.574329) (xy 408.620494 -280.528517)
			(xy 408.650715 -280.486921) (xy 408.687071 -280.450565) (xy 408.728667 -280.420344) (xy 408.774479 -280.397001)
			(xy 408.823378 -280.381113) (xy 408.87416 -280.37307) (xy 408.925576 -280.37307) (xy 408.976358 -280.381113)
			(xy 409.025257 -280.397001) (xy 409.071069 -280.420344) (xy 409.112665 -280.450565) (xy 409.149021 -280.486921)
			(xy 409.179242 -280.528517) (xy 409.202585 -280.574329) (xy 409.218473 -280.623228) (xy 409.226516 -280.67401)
			(xy 409.22702 -280.699718) (xy 409.544024 -280.699718) (xy 409.547984 -280.650664) (xy 409.559761 -280.60288)
			(xy 409.579052 -280.557604) (xy 409.605355 -280.516008) (xy 409.63799 -280.479171) (xy 409.676111 -280.448046)
			(xy 409.718732 -280.423439) (xy 409.764748 -280.405987) (xy 409.812967 -280.396143) (xy 409.862142 -280.394162)
			(xy 409.910997 -280.400094) (xy 409.958268 -280.413786) (xy 410.00273 -280.434884) (xy 410.043233 -280.46284)
			(xy 410.078726 -280.496932) (xy 410.108291 -280.536276) (xy 410.131162 -280.579853) (xy 410.146746 -280.626534)
			(xy 410.154641 -280.675111) (xy 410.155136 -280.699718) (xy 410.154641 -280.724325) (xy 410.154462 -280.725426)
			(xy 410.47314 -280.725426) (xy 410.47314 -280.67401) (xy 410.481183 -280.623228) (xy 410.497071 -280.574329)
			(xy 410.520414 -280.528517) (xy 410.550635 -280.486921) (xy 410.586991 -280.450565) (xy 410.628587 -280.420344)
			(xy 410.674399 -280.397001) (xy 410.723298 -280.381113) (xy 410.77408 -280.37307) (xy 410.825496 -280.37307)
			(xy 410.876278 -280.381113) (xy 410.925177 -280.397001) (xy 410.970989 -280.420344) (xy 411.012585 -280.450565)
			(xy 411.048941 -280.486921) (xy 411.079162 -280.528517) (xy 411.102505 -280.574329) (xy 411.118393 -280.623228)
			(xy 411.126436 -280.67401) (xy 411.12694 -280.699718) (xy 411.444198 -280.699718) (xy 411.448158 -280.650664)
			(xy 411.459935 -280.60288) (xy 411.479226 -280.557604) (xy 411.505529 -280.516008) (xy 411.538164 -280.479171)
			(xy 411.576285 -280.448046) (xy 411.618906 -280.423439) (xy 411.664922 -280.405987) (xy 411.713141 -280.396143)
			(xy 411.762316 -280.394162) (xy 411.811171 -280.400094) (xy 411.858442 -280.413786) (xy 411.902904 -280.434884)
			(xy 411.943407 -280.46284) (xy 411.9789 -280.496932) (xy 412.008465 -280.536276) (xy 412.031336 -280.579853)
			(xy 412.04692 -280.626534) (xy 412.054815 -280.675111) (xy 412.05531 -280.699718) (xy 412.054815 -280.724325)
			(xy 412.054636 -280.725426) (xy 412.373314 -280.725426) (xy 412.373314 -280.67401) (xy 412.381357 -280.623228)
			(xy 412.397245 -280.574329) (xy 412.420588 -280.528517) (xy 412.450809 -280.486921) (xy 412.487165 -280.450565)
			(xy 412.528761 -280.420344) (xy 412.574573 -280.397001) (xy 412.623472 -280.381113) (xy 412.674254 -280.37307)
			(xy 412.72567 -280.37307) (xy 412.776452 -280.381113) (xy 412.825351 -280.397001) (xy 412.871163 -280.420344)
			(xy 412.912759 -280.450565) (xy 412.949115 -280.486921) (xy 412.979336 -280.528517) (xy 413.002679 -280.574329)
			(xy 413.018567 -280.623228) (xy 413.02661 -280.67401) (xy 413.027114 -280.699718) (xy 413.344118 -280.699718)
			(xy 413.348078 -280.650664) (xy 413.359855 -280.60288) (xy 413.379146 -280.557604) (xy 413.405449 -280.516008)
			(xy 413.438084 -280.479171) (xy 413.476205 -280.448046) (xy 413.518826 -280.423439) (xy 413.564842 -280.405987)
			(xy 413.613061 -280.396143) (xy 413.662236 -280.394162) (xy 413.711091 -280.400094) (xy 413.758362 -280.413786)
			(xy 413.802824 -280.434884) (xy 413.843327 -280.46284) (xy 413.87882 -280.496932) (xy 413.908385 -280.536276)
			(xy 413.931256 -280.579853) (xy 413.94684 -280.626534) (xy 413.954735 -280.675111) (xy 413.95523 -280.699718)
			(xy 413.954735 -280.724325) (xy 413.954556 -280.725426) (xy 414.273234 -280.725426) (xy 414.273234 -280.67401)
			(xy 414.281277 -280.623228) (xy 414.297165 -280.574329) (xy 414.320508 -280.528517) (xy 414.350729 -280.486921)
			(xy 414.387085 -280.450565) (xy 414.428681 -280.420344) (xy 414.474493 -280.397001) (xy 414.523392 -280.381113)
			(xy 414.574174 -280.37307) (xy 414.62559 -280.37307) (xy 414.676372 -280.381113) (xy 414.725271 -280.397001)
			(xy 414.771083 -280.420344) (xy 414.812679 -280.450565) (xy 414.849035 -280.486921) (xy 414.879256 -280.528517)
			(xy 414.902599 -280.574329) (xy 414.918487 -280.623228) (xy 414.92653 -280.67401) (xy 414.927034 -280.699718)
			(xy 415.244038 -280.699718) (xy 415.247998 -280.650664) (xy 415.259775 -280.60288) (xy 415.279066 -280.557604)
			(xy 415.305369 -280.516008) (xy 415.338004 -280.479171) (xy 415.376125 -280.448046) (xy 415.418746 -280.423439)
			(xy 415.464762 -280.405987) (xy 415.512981 -280.396143) (xy 415.562156 -280.394162) (xy 415.611011 -280.400094)
			(xy 415.658282 -280.413786) (xy 415.702744 -280.434884) (xy 415.743247 -280.46284) (xy 415.77874 -280.496932)
			(xy 415.808305 -280.536276) (xy 415.831176 -280.579853) (xy 415.84676 -280.626534) (xy 415.854655 -280.675111)
			(xy 415.85515 -280.699718) (xy 415.854655 -280.724325) (xy 415.854476 -280.725426) (xy 416.173154 -280.725426)
			(xy 416.173154 -280.67401) (xy 416.181197 -280.623228) (xy 416.197085 -280.574329) (xy 416.220428 -280.528517)
			(xy 416.250649 -280.486921) (xy 416.287005 -280.450565) (xy 416.328601 -280.420344) (xy 416.374413 -280.397001)
			(xy 416.423312 -280.381113) (xy 416.474094 -280.37307) (xy 416.52551 -280.37307) (xy 416.576292 -280.381113)
			(xy 416.625191 -280.397001) (xy 416.671003 -280.420344) (xy 416.712599 -280.450565) (xy 416.748955 -280.486921)
			(xy 416.779176 -280.528517) (xy 416.802519 -280.574329) (xy 416.818407 -280.623228) (xy 416.82645 -280.67401)
			(xy 416.826954 -280.699718) (xy 417.144212 -280.699718) (xy 417.148172 -280.650664) (xy 417.159949 -280.60288)
			(xy 417.17924 -280.557604) (xy 417.205543 -280.516008) (xy 417.238178 -280.479171) (xy 417.276299 -280.448046)
			(xy 417.31892 -280.423439) (xy 417.364936 -280.405987) (xy 417.413155 -280.396143) (xy 417.46233 -280.394162)
			(xy 417.511185 -280.400094) (xy 417.558456 -280.413786) (xy 417.602918 -280.434884) (xy 417.643421 -280.46284)
			(xy 417.678914 -280.496932) (xy 417.708479 -280.536276) (xy 417.73135 -280.579853) (xy 417.746934 -280.626534)
			(xy 417.754829 -280.675111) (xy 417.755324 -280.699718) (xy 417.754829 -280.724325) (xy 417.75465 -280.725426)
			(xy 418.073328 -280.725426) (xy 418.073328 -280.67401) (xy 418.081371 -280.623228) (xy 418.097259 -280.574329)
			(xy 418.120602 -280.528517) (xy 418.150823 -280.486921) (xy 418.187179 -280.450565) (xy 418.228775 -280.420344)
			(xy 418.274587 -280.397001) (xy 418.323486 -280.381113) (xy 418.374268 -280.37307) (xy 418.425684 -280.37307)
			(xy 418.476466 -280.381113) (xy 418.525365 -280.397001) (xy 418.571177 -280.420344) (xy 418.612773 -280.450565)
			(xy 418.649129 -280.486921) (xy 418.67935 -280.528517) (xy 418.702693 -280.574329) (xy 418.718581 -280.623228)
			(xy 418.726624 -280.67401) (xy 418.727128 -280.699718) (xy 419.044132 -280.699718) (xy 419.048092 -280.650664)
			(xy 419.059869 -280.60288) (xy 419.07916 -280.557604) (xy 419.105463 -280.516008) (xy 419.138098 -280.479171)
			(xy 419.176219 -280.448046) (xy 419.21884 -280.423439) (xy 419.264856 -280.405987) (xy 419.313075 -280.396143)
			(xy 419.36225 -280.394162) (xy 419.411105 -280.400094) (xy 419.458376 -280.413786) (xy 419.502838 -280.434884)
			(xy 419.543341 -280.46284) (xy 419.578834 -280.496932) (xy 419.608399 -280.536276) (xy 419.63127 -280.579853)
			(xy 419.646854 -280.626534) (xy 419.654749 -280.675111) (xy 419.655244 -280.699718) (xy 419.654749 -280.724325)
			(xy 419.65457 -280.725426) (xy 419.973248 -280.725426) (xy 419.973248 -280.67401) (xy 419.981291 -280.623228)
			(xy 419.997179 -280.574329) (xy 420.020522 -280.528517) (xy 420.050743 -280.486921) (xy 420.087099 -280.450565)
			(xy 420.128695 -280.420344) (xy 420.174507 -280.397001) (xy 420.223406 -280.381113) (xy 420.274188 -280.37307)
			(xy 420.325604 -280.37307) (xy 420.376386 -280.381113) (xy 420.425285 -280.397001) (xy 420.471097 -280.420344)
			(xy 420.512693 -280.450565) (xy 420.549049 -280.486921) (xy 420.57927 -280.528517) (xy 420.602613 -280.574329)
			(xy 420.618501 -280.623228) (xy 420.626544 -280.67401) (xy 420.627048 -280.699718) (xy 420.944052 -280.699718)
			(xy 420.948012 -280.650664) (xy 420.959789 -280.60288) (xy 420.97908 -280.557604) (xy 421.005383 -280.516008)
			(xy 421.038018 -280.479171) (xy 421.076139 -280.448046) (xy 421.11876 -280.423439) (xy 421.164776 -280.405987)
			(xy 421.212995 -280.396143) (xy 421.26217 -280.394162) (xy 421.311025 -280.400094) (xy 421.358296 -280.413786)
			(xy 421.402758 -280.434884) (xy 421.443261 -280.46284) (xy 421.478754 -280.496932) (xy 421.508319 -280.536276)
			(xy 421.53119 -280.579853) (xy 421.546774 -280.626534) (xy 421.554669 -280.675111) (xy 421.555164 -280.699718)
			(xy 421.554669 -280.724325) (xy 421.55449 -280.725426) (xy 421.873168 -280.725426) (xy 421.873168 -280.67401)
			(xy 421.881211 -280.623228) (xy 421.897099 -280.574329) (xy 421.920442 -280.528517) (xy 421.950663 -280.486921)
			(xy 421.987019 -280.450565) (xy 422.028615 -280.420344) (xy 422.074427 -280.397001) (xy 422.123326 -280.381113)
			(xy 422.174108 -280.37307) (xy 422.225524 -280.37307) (xy 422.276306 -280.381113) (xy 422.325205 -280.397001)
			(xy 422.371017 -280.420344) (xy 422.412613 -280.450565) (xy 422.448969 -280.486921) (xy 422.47919 -280.528517)
			(xy 422.502533 -280.574329) (xy 422.518421 -280.623228) (xy 422.526464 -280.67401) (xy 422.526968 -280.699718)
			(xy 422.844226 -280.699718) (xy 422.848186 -280.650664) (xy 422.859963 -280.60288) (xy 422.879254 -280.557604)
			(xy 422.905557 -280.516008) (xy 422.938192 -280.479171) (xy 422.976313 -280.448046) (xy 423.018934 -280.423439)
			(xy 423.06495 -280.405987) (xy 423.113169 -280.396143) (xy 423.162344 -280.394162) (xy 423.211199 -280.400094)
			(xy 423.25847 -280.413786) (xy 423.302932 -280.434884) (xy 423.343435 -280.46284) (xy 423.378928 -280.496932)
			(xy 423.408493 -280.536276) (xy 423.431364 -280.579853) (xy 423.446948 -280.626534) (xy 423.454843 -280.675111)
			(xy 423.455338 -280.699718) (xy 423.454843 -280.724325) (xy 423.454664 -280.725426) (xy 423.773342 -280.725426)
			(xy 423.773342 -280.67401) (xy 423.781385 -280.623228) (xy 423.797273 -280.574329) (xy 423.820616 -280.528517)
			(xy 423.850837 -280.486921) (xy 423.887193 -280.450565) (xy 423.928789 -280.420344) (xy 423.974601 -280.397001)
			(xy 424.0235 -280.381113) (xy 424.074282 -280.37307) (xy 424.125698 -280.37307) (xy 424.17648 -280.381113)
			(xy 424.225379 -280.397001) (xy 424.271191 -280.420344) (xy 424.312787 -280.450565) (xy 424.349143 -280.486921)
			(xy 424.379364 -280.528517) (xy 424.402707 -280.574329) (xy 424.418595 -280.623228) (xy 424.426638 -280.67401)
			(xy 424.427142 -280.699718) (xy 424.744146 -280.699718) (xy 424.748106 -280.650664) (xy 424.759883 -280.60288)
			(xy 424.779174 -280.557604) (xy 424.805477 -280.516008) (xy 424.838112 -280.479171) (xy 424.876233 -280.448046)
			(xy 424.918854 -280.423439) (xy 424.96487 -280.405987) (xy 425.013089 -280.396143) (xy 425.062264 -280.394162)
			(xy 425.111119 -280.400094) (xy 425.15839 -280.413786) (xy 425.202852 -280.434884) (xy 425.243355 -280.46284)
			(xy 425.278848 -280.496932) (xy 425.308413 -280.536276) (xy 425.331284 -280.579853) (xy 425.346868 -280.626534)
			(xy 425.354763 -280.675111) (xy 425.355258 -280.699718) (xy 425.354763 -280.724325) (xy 425.354584 -280.725426)
			(xy 425.673262 -280.725426) (xy 425.673262 -280.67401) (xy 425.681305 -280.623228) (xy 425.697193 -280.574329)
			(xy 425.720536 -280.528517) (xy 425.750757 -280.486921) (xy 425.787113 -280.450565) (xy 425.828709 -280.420344)
			(xy 425.874521 -280.397001) (xy 425.92342 -280.381113) (xy 425.974202 -280.37307) (xy 426.025618 -280.37307)
			(xy 426.0764 -280.381113) (xy 426.125299 -280.397001) (xy 426.171111 -280.420344) (xy 426.212707 -280.450565)
			(xy 426.249063 -280.486921) (xy 426.279284 -280.528517) (xy 426.302627 -280.574329) (xy 426.318515 -280.623228)
			(xy 426.326558 -280.67401) (xy 426.327062 -280.699718) (xy 426.644066 -280.699718) (xy 426.648026 -280.650664)
			(xy 426.659803 -280.60288) (xy 426.679094 -280.557604) (xy 426.705397 -280.516008) (xy 426.738032 -280.479171)
			(xy 426.776153 -280.448046) (xy 426.818774 -280.423439) (xy 426.86479 -280.405987) (xy 426.913009 -280.396143)
			(xy 426.962184 -280.394162) (xy 427.011039 -280.400094) (xy 427.05831 -280.413786) (xy 427.102772 -280.434884)
			(xy 427.143275 -280.46284) (xy 427.178768 -280.496932) (xy 427.208333 -280.536276) (xy 427.231204 -280.579853)
			(xy 427.246788 -280.626534) (xy 427.254683 -280.675111) (xy 427.255178 -280.699718) (xy 427.254683 -280.724325)
			(xy 427.254504 -280.725426) (xy 427.573182 -280.725426) (xy 427.573182 -280.67401) (xy 427.581225 -280.623228)
			(xy 427.597113 -280.574329) (xy 427.620456 -280.528517) (xy 427.650677 -280.486921) (xy 427.687033 -280.450565)
			(xy 427.728629 -280.420344) (xy 427.774441 -280.397001) (xy 427.82334 -280.381113) (xy 427.874122 -280.37307)
			(xy 427.925538 -280.37307) (xy 427.97632 -280.381113) (xy 428.025219 -280.397001) (xy 428.071031 -280.420344)
			(xy 428.112627 -280.450565) (xy 428.148983 -280.486921) (xy 428.179204 -280.528517) (xy 428.202547 -280.574329)
			(xy 428.218435 -280.623228) (xy 428.226478 -280.67401) (xy 428.226982 -280.699718) (xy 428.54424 -280.699718)
			(xy 428.5482 -280.650664) (xy 428.559977 -280.60288) (xy 428.579268 -280.557604) (xy 428.605571 -280.516008)
			(xy 428.638206 -280.479171) (xy 428.676327 -280.448046) (xy 428.718948 -280.423439) (xy 428.764964 -280.405987)
			(xy 428.813183 -280.396143) (xy 428.862358 -280.394162) (xy 428.911213 -280.400094) (xy 428.958484 -280.413786)
			(xy 429.002946 -280.434884) (xy 429.043449 -280.46284) (xy 429.078942 -280.496932) (xy 429.108507 -280.536276)
			(xy 429.131378 -280.579853) (xy 429.146962 -280.626534) (xy 429.154857 -280.675111) (xy 429.155352 -280.699718)
			(xy 429.4942 -280.699718) (xy 429.49816 -280.650664) (xy 429.509937 -280.60288) (xy 429.529228 -280.557604)
			(xy 429.555531 -280.516008) (xy 429.588166 -280.479171) (xy 429.626287 -280.448046) (xy 429.668908 -280.423439)
			(xy 429.714924 -280.405987) (xy 429.763143 -280.396143) (xy 429.812318 -280.394162) (xy 429.861173 -280.400094)
			(xy 429.908444 -280.413786) (xy 429.952906 -280.434884) (xy 429.993409 -280.46284) (xy 430.028902 -280.496932)
			(xy 430.058467 -280.536276) (xy 430.081338 -280.579853) (xy 430.096922 -280.626534) (xy 430.104817 -280.675111)
			(xy 430.105312 -280.699718) (xy 430.44416 -280.699718) (xy 430.44812 -280.650664) (xy 430.459897 -280.60288)
			(xy 430.479188 -280.557604) (xy 430.505491 -280.516008) (xy 430.538126 -280.479171) (xy 430.576247 -280.448046)
			(xy 430.618868 -280.423439) (xy 430.664884 -280.405987) (xy 430.713103 -280.396143) (xy 430.762278 -280.394162)
			(xy 430.811133 -280.400094) (xy 430.858404 -280.413786) (xy 430.902866 -280.434884) (xy 430.943369 -280.46284)
			(xy 430.978862 -280.496932) (xy 431.008427 -280.536276) (xy 431.031298 -280.579853) (xy 431.046045 -280.624026)
			(xy 459.436722 -280.624026) (xy 459.440793 -280.568404) (xy 459.452919 -280.513967) (xy 459.472842 -280.461876)
			(xy 459.500138 -280.413241) (xy 459.534224 -280.369098) (xy 459.574373 -280.330389) (xy 459.619731 -280.297938)
			(xy 459.669331 -280.272437) (xy 459.722115 -280.25443) (xy 459.776958 -280.2443) (xy 459.832692 -280.242263)
			(xy 459.888129 -280.248363) (xy 459.942086 -280.262469) (xy 459.993415 -280.284281) (xy 460.041021 -280.313335)
			(xy 460.083889 -280.34901) (xy 460.121106 -280.390547) (xy 460.151879 -280.43706) (xy 460.175551 -280.487557)
			(xy 460.191619 -280.540964) (xy 460.199739 -280.59614) (xy 460.200248 -280.624026) (xy 460.199739 -280.651912)
			(xy 460.191619 -280.707088) (xy 460.175551 -280.760495) (xy 460.151879 -280.810992) (xy 460.121106 -280.857505)
			(xy 460.083889 -280.899042) (xy 460.041021 -280.934717) (xy 459.998234 -280.96083) (xy 463.093816 -280.96083)
			(xy 463.094349 -280.931755) (xy 463.103169 -280.874278) (xy 463.12061 -280.818806) (xy 463.146268 -280.766622)
			(xy 463.179547 -280.718937) (xy 463.219678 -280.676855) (xy 463.26573 -280.641351) (xy 463.29092 -280.62682)
			(xy 463.297016 -280.623518) (xy 463.306668 -280.614374) (xy 463.30997 -280.608786) (xy 463.313237 -280.60288)
			(xy 463.31684 -280.589877) (xy 463.317082 -280.583132) (xy 463.318098 -280.494486) (xy 463.318038 -280.49088)
			(xy 463.317016 -280.483741) (xy 463.316066 -280.480262) (xy 463.314542 -280.47442) (xy 463.31124 -280.468324)
			(xy 463.307726 -280.462686) (xy 463.298338 -280.453293) (xy 463.292698 -280.449782) (xy 463.292444 -280.449782)
			(xy 463.267877 -280.435063) (xy 463.223004 -280.399484) (xy 463.183955 -280.357596) (xy 463.151606 -280.310341)
			(xy 463.126686 -280.258782) (xy 463.109753 -280.204076) (xy 463.101189 -280.147453) (xy 463.100674 -280.11882)
			(xy 463.101216 -280.089868) (xy 463.10997 -280.032628) (xy 463.12728 -279.977371) (xy 463.152748 -279.925368)
			(xy 463.185787 -279.877814) (xy 463.205322 -279.856438) (xy 463.21218 -279.849072) (xy 463.215736 -279.840182)
			(xy 463.219038 -279.827228) (xy 463.219292 -279.820878) (xy 463.21853 -279.750266) (xy 463.218353 -279.745238)
			(xy 463.216309 -279.735389) (xy 463.214466 -279.730708) (xy 463.21091 -279.722326) (xy 463.203798 -279.71496)
			(xy 463.183324 -279.693399) (xy 463.148624 -279.645121) (xy 463.121836 -279.592044) (xy 463.103609 -279.535452)
			(xy 463.094384 -279.476717) (xy 463.093816 -279.44699) (xy 463.094267 -279.420526) (xy 463.101577 -279.368104)
			(xy 463.11607 -279.317198) (xy 463.137466 -279.268787) (xy 463.165354 -279.223802) (xy 463.199198 -279.183107)
			(xy 463.238346 -279.147486) (xy 463.282047 -279.117624) (xy 463.329458 -279.094095) (xy 463.35442 -279.085294)
			(xy 463.364834 -279.081738) (xy 463.372708 -279.074626) (xy 463.376513 -279.070893) (xy 463.382666 -279.062193)
			(xy 463.3849 -279.057354) (xy 463.414872 -278.987758) (xy 463.416853 -278.982785) (xy 463.41891 -278.972283)
			(xy 463.418936 -278.96693) (xy 463.418936 -278.956516) (xy 463.414364 -278.94661) (xy 463.403514 -278.92165)
			(xy 463.388153 -278.869439) (xy 463.380347 -278.815579) (xy 463.37982 -278.788368) (xy 463.37982 -278.787606)
			(xy 463.380261 -278.760352) (xy 463.388018 -278.706399) (xy 463.403375 -278.654099) (xy 463.426018 -278.604517)
			(xy 463.455488 -278.558662) (xy 463.491185 -278.517469) (xy 463.53238 -278.481775) (xy 463.578236 -278.452308)
			(xy 463.62782 -278.429667) (xy 463.68012 -278.414313) (xy 463.734074 -278.406559) (xy 463.761328 -278.406098)
			(xy 463.789236 -278.406582) (xy 463.844453 -278.41475) (xy 463.87131 -278.422354) (xy 463.882232 -278.425656)
			(xy 463.893408 -278.424132) (xy 463.898894 -278.423104) (xy 463.90927 -278.418997) (xy 463.913982 -278.416004)
			(xy 463.97926 -278.373078) (xy 463.982533 -278.370823) (xy 463.9884 -278.365463) (xy 463.990944 -278.36241)
			(xy 463.994754 -278.356822) (xy 464.000596 -278.34717) (xy 464.001612 -278.33574) (xy 464.005129 -278.30799)
			(xy 464.019083 -278.253827) (xy 464.040794 -278.202281) (xy 464.069795 -278.154456) (xy 464.105467 -278.111376)
			(xy 464.147045 -278.073964) (xy 464.193638 -278.043021) (xy 464.244248 -278.01921) (xy 464.297792 -278.003042)
			(xy 464.353122 -277.994862) (xy 464.381088 -277.994364) (xy 464.408339 -277.994882) (xy 464.462288 -278.002637)
			(xy 464.514583 -278.017991) (xy 464.564161 -278.040631) (xy 464.610012 -278.070097) (xy 464.651203 -278.105788)
			(xy 464.686896 -278.146978) (xy 464.716363 -278.192828) (xy 464.739004 -278.242406) (xy 464.75436 -278.294701)
			(xy 464.762117 -278.348649) (xy 464.762117 -278.403151) (xy 464.75436 -278.457099) (xy 464.739004 -278.509394)
			(xy 464.716363 -278.558972) (xy 464.686896 -278.604822) (xy 464.651203 -278.646012) (xy 464.610012 -278.681703)
			(xy 464.564161 -278.711169) (xy 464.514583 -278.733809) (xy 464.462288 -278.749163) (xy 464.408339 -278.756918)
			(xy 464.381088 -278.75738) (xy 464.35318 -278.75689) (xy 464.297964 -278.748725) (xy 464.271106 -278.741124)
			(xy 464.260184 -278.737822) (xy 464.249008 -278.739346) (xy 464.243524 -278.740381) (xy 464.233147 -278.744484)
			(xy 464.228434 -278.747474) (xy 464.163156 -278.7904) (xy 464.159887 -278.79266) (xy 464.154018 -278.798017)
			(xy 464.151472 -278.801068) (xy 464.147662 -278.806656) (xy 464.14182 -278.816308) (xy 464.140804 -278.827738)
			(xy 464.137448 -278.854793) (xy 464.124016 -278.90763) (xy 464.103203 -278.958018) (xy 464.075431 -279.004932)
			(xy 464.041267 -279.047417) (xy 464.001405 -279.084608) (xy 463.956657 -279.115748) (xy 463.907932 -279.140204)
			(xy 463.882232 -279.149302) (xy 463.871818 -279.152858) (xy 463.863944 -279.15997) (xy 463.860134 -279.163698)
			(xy 463.853985 -279.172402) (xy 463.851752 -279.177242) (xy 463.82178 -279.246838) (xy 463.819802 -279.251812)
			(xy 463.817743 -279.262314) (xy 463.817716 -279.267666) (xy 463.817716 -279.27808) (xy 463.822288 -279.287986)
			(xy 463.833134 -279.312948) (xy 463.848497 -279.365157) (xy 463.856305 -279.419017) (xy 463.856832 -279.446228)
			(xy 463.856832 -279.44699) (xy 463.856294 -279.475943) (xy 463.847539 -279.533182) (xy 463.830228 -279.588439)
			(xy 463.804759 -279.640443) (xy 463.771719 -279.687996) (xy 463.752184 -279.709372) (xy 463.745326 -279.716738)
			(xy 463.74177 -279.725628) (xy 463.738468 -279.738582) (xy 463.738214 -279.744932) (xy 463.738976 -279.815544)
			(xy 463.739149 -279.820572) (xy 463.741195 -279.830421) (xy 463.74304 -279.835102) (xy 463.746596 -279.843484)
			(xy 463.753708 -279.85085) (xy 463.774187 -279.872406) (xy 463.808887 -279.920685) (xy 463.835674 -279.973764)
			(xy 463.853899 -280.030357) (xy 463.863123 -280.089092) (xy 463.86369 -280.11882) (xy 463.863165 -280.147896)
			(xy 463.85435 -280.205375) (xy 463.836911 -280.260851) (xy 463.811253 -280.313036) (xy 463.777971 -280.360721)
			(xy 463.737836 -280.402802) (xy 463.691778 -280.438302) (xy 463.666586 -280.45283) (xy 463.66049 -280.456132)
			(xy 463.650838 -280.465276) (xy 463.647536 -280.470864) (xy 463.644287 -280.476779) (xy 463.640672 -280.489775)
			(xy 463.640424 -280.496518) (xy 463.639408 -280.585164) (xy 463.639482 -280.588769) (xy 463.640495 -280.595908)
			(xy 463.64144 -280.599388) (xy 463.642964 -280.60523) (xy 463.646266 -280.611326) (xy 463.649768 -280.616972)
			(xy 463.659165 -280.62636) (xy 463.664808 -280.629868) (xy 463.665062 -280.629868) (xy 463.689652 -280.644549)
			(xy 463.734525 -280.680135) (xy 463.773573 -280.722029) (xy 463.805919 -280.76929) (xy 463.830835 -280.820856)
			(xy 463.847763 -280.875568) (xy 463.85632 -280.932195) (xy 463.856832 -280.96083) (xy 463.856346 -280.988081)
			(xy 463.84859 -281.042029) (xy 463.833235 -281.094324) (xy 463.810593 -281.143901) (xy 463.781127 -281.189751)
			(xy 463.745436 -281.230942) (xy 463.704245 -281.266633) (xy 463.658395 -281.296099) (xy 463.608818 -281.318741)
			(xy 463.556523 -281.334096) (xy 463.502575 -281.341852) (xy 463.448073 -281.341852) (xy 463.394125 -281.334096)
			(xy 463.34183 -281.318741) (xy 463.292253 -281.296099) (xy 463.246403 -281.266633) (xy 463.205212 -281.230942)
			(xy 463.169521 -281.189751) (xy 463.140055 -281.143901) (xy 463.117413 -281.094324) (xy 463.102058 -281.042029)
			(xy 463.094302 -280.988081) (xy 463.093816 -280.96083) (xy 459.998234 -280.96083) (xy 459.993415 -280.963771)
			(xy 459.942086 -280.985583) (xy 459.888129 -280.999689) (xy 459.832692 -281.005789) (xy 459.776958 -281.003752)
			(xy 459.722115 -280.993622) (xy 459.669331 -280.975615) (xy 459.619731 -280.950114) (xy 459.574373 -280.917663)
			(xy 459.534224 -280.878954) (xy 459.500138 -280.834811) (xy 459.472842 -280.786176) (xy 459.452919 -280.734085)
			(xy 459.440793 -280.679648) (xy 459.436722 -280.624026) (xy 431.046045 -280.624026) (xy 431.046882 -280.626534)
			(xy 431.054777 -280.675111) (xy 431.055272 -280.699718) (xy 431.054777 -280.724325) (xy 431.046882 -280.772902)
			(xy 431.031298 -280.819583) (xy 431.008427 -280.86316) (xy 430.978862 -280.902504) (xy 430.943369 -280.936596)
			(xy 430.902866 -280.964552) (xy 430.858404 -280.98565) (xy 430.811133 -280.999342) (xy 430.762278 -281.005274)
			(xy 430.713103 -281.003293) (xy 430.664884 -280.993449) (xy 430.618868 -280.975997) (xy 430.576247 -280.95139)
			(xy 430.538126 -280.920265) (xy 430.505491 -280.883428) (xy 430.479188 -280.841832) (xy 430.459897 -280.796556)
			(xy 430.44812 -280.748772) (xy 430.44416 -280.699718) (xy 430.105312 -280.699718) (xy 430.104817 -280.724325)
			(xy 430.096922 -280.772902) (xy 430.081338 -280.819583) (xy 430.058467 -280.86316) (xy 430.028902 -280.902504)
			(xy 429.993409 -280.936596) (xy 429.952906 -280.964552) (xy 429.908444 -280.98565) (xy 429.861173 -280.999342)
			(xy 429.812318 -281.005274) (xy 429.763143 -281.003293) (xy 429.714924 -280.993449) (xy 429.668908 -280.975997)
			(xy 429.626287 -280.95139) (xy 429.588166 -280.920265) (xy 429.555531 -280.883428) (xy 429.529228 -280.841832)
			(xy 429.509937 -280.796556) (xy 429.49816 -280.748772) (xy 429.4942 -280.699718) (xy 429.155352 -280.699718)
			(xy 429.154857 -280.724325) (xy 429.146962 -280.772902) (xy 429.131378 -280.819583) (xy 429.108507 -280.86316)
			(xy 429.078942 -280.902504) (xy 429.043449 -280.936596) (xy 429.002946 -280.964552) (xy 428.958484 -280.98565)
			(xy 428.911213 -280.999342) (xy 428.862358 -281.005274) (xy 428.813183 -281.003293) (xy 428.764964 -280.993449)
			(xy 428.718948 -280.975997) (xy 428.676327 -280.95139) (xy 428.638206 -280.920265) (xy 428.605571 -280.883428)
			(xy 428.579268 -280.841832) (xy 428.559977 -280.796556) (xy 428.5482 -280.748772) (xy 428.54424 -280.699718)
			(xy 428.226982 -280.699718) (xy 428.226478 -280.725426) (xy 428.218435 -280.776208) (xy 428.202547 -280.825107)
			(xy 428.179204 -280.870919) (xy 428.148983 -280.912515) (xy 428.112627 -280.948871) (xy 428.071031 -280.979092)
			(xy 428.025219 -281.002435) (xy 427.97632 -281.018323) (xy 427.925538 -281.026366) (xy 427.874122 -281.026366)
			(xy 427.82334 -281.018323) (xy 427.774441 -281.002435) (xy 427.728629 -280.979092) (xy 427.687033 -280.948871)
			(xy 427.650677 -280.912515) (xy 427.620456 -280.870919) (xy 427.597113 -280.825107) (xy 427.581225 -280.776208)
			(xy 427.573182 -280.725426) (xy 427.254504 -280.725426) (xy 427.246788 -280.772902) (xy 427.231204 -280.819583)
			(xy 427.208333 -280.86316) (xy 427.178768 -280.902504) (xy 427.143275 -280.936596) (xy 427.102772 -280.964552)
			(xy 427.05831 -280.98565) (xy 427.011039 -280.999342) (xy 426.962184 -281.005274) (xy 426.913009 -281.003293)
			(xy 426.86479 -280.993449) (xy 426.818774 -280.975997) (xy 426.776153 -280.95139) (xy 426.738032 -280.920265)
			(xy 426.705397 -280.883428) (xy 426.679094 -280.841832) (xy 426.659803 -280.796556) (xy 426.648026 -280.748772)
			(xy 426.644066 -280.699718) (xy 426.327062 -280.699718) (xy 426.326558 -280.725426) (xy 426.318515 -280.776208)
			(xy 426.302627 -280.825107) (xy 426.279284 -280.870919) (xy 426.249063 -280.912515) (xy 426.212707 -280.948871)
			(xy 426.171111 -280.979092) (xy 426.125299 -281.002435) (xy 426.0764 -281.018323) (xy 426.025618 -281.026366)
			(xy 425.974202 -281.026366) (xy 425.92342 -281.018323) (xy 425.874521 -281.002435) (xy 425.828709 -280.979092)
			(xy 425.787113 -280.948871) (xy 425.750757 -280.912515) (xy 425.720536 -280.870919) (xy 425.697193 -280.825107)
			(xy 425.681305 -280.776208) (xy 425.673262 -280.725426) (xy 425.354584 -280.725426) (xy 425.346868 -280.772902)
			(xy 425.331284 -280.819583) (xy 425.308413 -280.86316) (xy 425.278848 -280.902504) (xy 425.243355 -280.936596)
			(xy 425.202852 -280.964552) (xy 425.15839 -280.98565) (xy 425.111119 -280.999342) (xy 425.062264 -281.005274)
			(xy 425.013089 -281.003293) (xy 424.96487 -280.993449) (xy 424.918854 -280.975997) (xy 424.876233 -280.95139)
			(xy 424.838112 -280.920265) (xy 424.805477 -280.883428) (xy 424.779174 -280.841832) (xy 424.759883 -280.796556)
			(xy 424.748106 -280.748772) (xy 424.744146 -280.699718) (xy 424.427142 -280.699718) (xy 424.426638 -280.725426)
			(xy 424.418595 -280.776208) (xy 424.402707 -280.825107) (xy 424.379364 -280.870919) (xy 424.349143 -280.912515)
			(xy 424.312787 -280.948871) (xy 424.271191 -280.979092) (xy 424.225379 -281.002435) (xy 424.17648 -281.018323)
			(xy 424.125698 -281.026366) (xy 424.074282 -281.026366) (xy 424.0235 -281.018323) (xy 423.974601 -281.002435)
			(xy 423.928789 -280.979092) (xy 423.887193 -280.948871) (xy 423.850837 -280.912515) (xy 423.820616 -280.870919)
			(xy 423.797273 -280.825107) (xy 423.781385 -280.776208) (xy 423.773342 -280.725426) (xy 423.454664 -280.725426)
			(xy 423.446948 -280.772902) (xy 423.431364 -280.819583) (xy 423.408493 -280.86316) (xy 423.378928 -280.902504)
			(xy 423.343435 -280.936596) (xy 423.302932 -280.964552) (xy 423.25847 -280.98565) (xy 423.211199 -280.999342)
			(xy 423.162344 -281.005274) (xy 423.113169 -281.003293) (xy 423.06495 -280.993449) (xy 423.018934 -280.975997)
			(xy 422.976313 -280.95139) (xy 422.938192 -280.920265) (xy 422.905557 -280.883428) (xy 422.879254 -280.841832)
			(xy 422.859963 -280.796556) (xy 422.848186 -280.748772) (xy 422.844226 -280.699718) (xy 422.526968 -280.699718)
			(xy 422.526464 -280.725426) (xy 422.518421 -280.776208) (xy 422.502533 -280.825107) (xy 422.47919 -280.870919)
			(xy 422.448969 -280.912515) (xy 422.412613 -280.948871) (xy 422.371017 -280.979092) (xy 422.325205 -281.002435)
			(xy 422.276306 -281.018323) (xy 422.225524 -281.026366) (xy 422.174108 -281.026366) (xy 422.123326 -281.018323)
			(xy 422.074427 -281.002435) (xy 422.028615 -280.979092) (xy 421.987019 -280.948871) (xy 421.950663 -280.912515)
			(xy 421.920442 -280.870919) (xy 421.897099 -280.825107) (xy 421.881211 -280.776208) (xy 421.873168 -280.725426)
			(xy 421.55449 -280.725426) (xy 421.546774 -280.772902) (xy 421.53119 -280.819583) (xy 421.508319 -280.86316)
			(xy 421.478754 -280.902504) (xy 421.443261 -280.936596) (xy 421.402758 -280.964552) (xy 421.358296 -280.98565)
			(xy 421.311025 -280.999342) (xy 421.26217 -281.005274) (xy 421.212995 -281.003293) (xy 421.164776 -280.993449)
			(xy 421.11876 -280.975997) (xy 421.076139 -280.95139) (xy 421.038018 -280.920265) (xy 421.005383 -280.883428)
			(xy 420.97908 -280.841832) (xy 420.959789 -280.796556) (xy 420.948012 -280.748772) (xy 420.944052 -280.699718)
			(xy 420.627048 -280.699718) (xy 420.626544 -280.725426) (xy 420.618501 -280.776208) (xy 420.602613 -280.825107)
			(xy 420.57927 -280.870919) (xy 420.549049 -280.912515) (xy 420.512693 -280.948871) (xy 420.471097 -280.979092)
			(xy 420.425285 -281.002435) (xy 420.376386 -281.018323) (xy 420.325604 -281.026366) (xy 420.274188 -281.026366)
			(xy 420.223406 -281.018323) (xy 420.174507 -281.002435) (xy 420.128695 -280.979092) (xy 420.087099 -280.948871)
			(xy 420.050743 -280.912515) (xy 420.020522 -280.870919) (xy 419.997179 -280.825107) (xy 419.981291 -280.776208)
			(xy 419.973248 -280.725426) (xy 419.65457 -280.725426) (xy 419.646854 -280.772902) (xy 419.63127 -280.819583)
			(xy 419.608399 -280.86316) (xy 419.578834 -280.902504) (xy 419.543341 -280.936596) (xy 419.502838 -280.964552)
			(xy 419.458376 -280.98565) (xy 419.411105 -280.999342) (xy 419.36225 -281.005274) (xy 419.313075 -281.003293)
			(xy 419.264856 -280.993449) (xy 419.21884 -280.975997) (xy 419.176219 -280.95139) (xy 419.138098 -280.920265)
			(xy 419.105463 -280.883428) (xy 419.07916 -280.841832) (xy 419.059869 -280.796556) (xy 419.048092 -280.748772)
			(xy 419.044132 -280.699718) (xy 418.727128 -280.699718) (xy 418.726624 -280.725426) (xy 418.718581 -280.776208)
			(xy 418.702693 -280.825107) (xy 418.67935 -280.870919) (xy 418.649129 -280.912515) (xy 418.612773 -280.948871)
			(xy 418.571177 -280.979092) (xy 418.525365 -281.002435) (xy 418.476466 -281.018323) (xy 418.425684 -281.026366)
			(xy 418.374268 -281.026366) (xy 418.323486 -281.018323) (xy 418.274587 -281.002435) (xy 418.228775 -280.979092)
			(xy 418.187179 -280.948871) (xy 418.150823 -280.912515) (xy 418.120602 -280.870919) (xy 418.097259 -280.825107)
			(xy 418.081371 -280.776208) (xy 418.073328 -280.725426) (xy 417.75465 -280.725426) (xy 417.746934 -280.772902)
			(xy 417.73135 -280.819583) (xy 417.708479 -280.86316) (xy 417.678914 -280.902504) (xy 417.643421 -280.936596)
			(xy 417.602918 -280.964552) (xy 417.558456 -280.98565) (xy 417.511185 -280.999342) (xy 417.46233 -281.005274)
			(xy 417.413155 -281.003293) (xy 417.364936 -280.993449) (xy 417.31892 -280.975997) (xy 417.276299 -280.95139)
			(xy 417.238178 -280.920265) (xy 417.205543 -280.883428) (xy 417.17924 -280.841832) (xy 417.159949 -280.796556)
			(xy 417.148172 -280.748772) (xy 417.144212 -280.699718) (xy 416.826954 -280.699718) (xy 416.82645 -280.725426)
			(xy 416.818407 -280.776208) (xy 416.802519 -280.825107) (xy 416.779176 -280.870919) (xy 416.748955 -280.912515)
			(xy 416.712599 -280.948871) (xy 416.671003 -280.979092) (xy 416.625191 -281.002435) (xy 416.576292 -281.018323)
			(xy 416.52551 -281.026366) (xy 416.474094 -281.026366) (xy 416.423312 -281.018323) (xy 416.374413 -281.002435)
			(xy 416.328601 -280.979092) (xy 416.287005 -280.948871) (xy 416.250649 -280.912515) (xy 416.220428 -280.870919)
			(xy 416.197085 -280.825107) (xy 416.181197 -280.776208) (xy 416.173154 -280.725426) (xy 415.854476 -280.725426)
			(xy 415.84676 -280.772902) (xy 415.831176 -280.819583) (xy 415.808305 -280.86316) (xy 415.77874 -280.902504)
			(xy 415.743247 -280.936596) (xy 415.702744 -280.964552) (xy 415.658282 -280.98565) (xy 415.611011 -280.999342)
			(xy 415.562156 -281.005274) (xy 415.512981 -281.003293) (xy 415.464762 -280.993449) (xy 415.418746 -280.975997)
			(xy 415.376125 -280.95139) (xy 415.338004 -280.920265) (xy 415.305369 -280.883428) (xy 415.279066 -280.841832)
			(xy 415.259775 -280.796556) (xy 415.247998 -280.748772) (xy 415.244038 -280.699718) (xy 414.927034 -280.699718)
			(xy 414.92653 -280.725426) (xy 414.918487 -280.776208) (xy 414.902599 -280.825107) (xy 414.879256 -280.870919)
			(xy 414.849035 -280.912515) (xy 414.812679 -280.948871) (xy 414.771083 -280.979092) (xy 414.725271 -281.002435)
			(xy 414.676372 -281.018323) (xy 414.62559 -281.026366) (xy 414.574174 -281.026366) (xy 414.523392 -281.018323)
			(xy 414.474493 -281.002435) (xy 414.428681 -280.979092) (xy 414.387085 -280.948871) (xy 414.350729 -280.912515)
			(xy 414.320508 -280.870919) (xy 414.297165 -280.825107) (xy 414.281277 -280.776208) (xy 414.273234 -280.725426)
			(xy 413.954556 -280.725426) (xy 413.94684 -280.772902) (xy 413.931256 -280.819583) (xy 413.908385 -280.86316)
			(xy 413.87882 -280.902504) (xy 413.843327 -280.936596) (xy 413.802824 -280.964552) (xy 413.758362 -280.98565)
			(xy 413.711091 -280.999342) (xy 413.662236 -281.005274) (xy 413.613061 -281.003293) (xy 413.564842 -280.993449)
			(xy 413.518826 -280.975997) (xy 413.476205 -280.95139) (xy 413.438084 -280.920265) (xy 413.405449 -280.883428)
			(xy 413.379146 -280.841832) (xy 413.359855 -280.796556) (xy 413.348078 -280.748772) (xy 413.344118 -280.699718)
			(xy 413.027114 -280.699718) (xy 413.02661 -280.725426) (xy 413.018567 -280.776208) (xy 413.002679 -280.825107)
			(xy 412.979336 -280.870919) (xy 412.949115 -280.912515) (xy 412.912759 -280.948871) (xy 412.871163 -280.979092)
			(xy 412.825351 -281.002435) (xy 412.776452 -281.018323) (xy 412.72567 -281.026366) (xy 412.674254 -281.026366)
			(xy 412.623472 -281.018323) (xy 412.574573 -281.002435) (xy 412.528761 -280.979092) (xy 412.487165 -280.948871)
			(xy 412.450809 -280.912515) (xy 412.420588 -280.870919) (xy 412.397245 -280.825107) (xy 412.381357 -280.776208)
			(xy 412.373314 -280.725426) (xy 412.054636 -280.725426) (xy 412.04692 -280.772902) (xy 412.031336 -280.819583)
			(xy 412.008465 -280.86316) (xy 411.9789 -280.902504) (xy 411.943407 -280.936596) (xy 411.902904 -280.964552)
			(xy 411.858442 -280.98565) (xy 411.811171 -280.999342) (xy 411.762316 -281.005274) (xy 411.713141 -281.003293)
			(xy 411.664922 -280.993449) (xy 411.618906 -280.975997) (xy 411.576285 -280.95139) (xy 411.538164 -280.920265)
			(xy 411.505529 -280.883428) (xy 411.479226 -280.841832) (xy 411.459935 -280.796556) (xy 411.448158 -280.748772)
			(xy 411.444198 -280.699718) (xy 411.12694 -280.699718) (xy 411.126436 -280.725426) (xy 411.118393 -280.776208)
			(xy 411.102505 -280.825107) (xy 411.079162 -280.870919) (xy 411.048941 -280.912515) (xy 411.012585 -280.948871)
			(xy 410.970989 -280.979092) (xy 410.925177 -281.002435) (xy 410.876278 -281.018323) (xy 410.825496 -281.026366)
			(xy 410.77408 -281.026366) (xy 410.723298 -281.018323) (xy 410.674399 -281.002435) (xy 410.628587 -280.979092)
			(xy 410.586991 -280.948871) (xy 410.550635 -280.912515) (xy 410.520414 -280.870919) (xy 410.497071 -280.825107)
			(xy 410.481183 -280.776208) (xy 410.47314 -280.725426) (xy 410.154462 -280.725426) (xy 410.146746 -280.772902)
			(xy 410.131162 -280.819583) (xy 410.108291 -280.86316) (xy 410.078726 -280.902504) (xy 410.043233 -280.936596)
			(xy 410.00273 -280.964552) (xy 409.958268 -280.98565) (xy 409.910997 -280.999342) (xy 409.862142 -281.005274)
			(xy 409.812967 -281.003293) (xy 409.764748 -280.993449) (xy 409.718732 -280.975997) (xy 409.676111 -280.95139)
			(xy 409.63799 -280.920265) (xy 409.605355 -280.883428) (xy 409.579052 -280.841832) (xy 409.559761 -280.796556)
			(xy 409.547984 -280.748772) (xy 409.544024 -280.699718) (xy 409.22702 -280.699718) (xy 409.226516 -280.725426)
			(xy 409.218473 -280.776208) (xy 409.202585 -280.825107) (xy 409.179242 -280.870919) (xy 409.149021 -280.912515)
			(xy 409.112665 -280.948871) (xy 409.071069 -280.979092) (xy 409.025257 -281.002435) (xy 408.976358 -281.018323)
			(xy 408.925576 -281.026366) (xy 408.87416 -281.026366) (xy 408.823378 -281.018323) (xy 408.774479 -281.002435)
			(xy 408.728667 -280.979092) (xy 408.687071 -280.948871) (xy 408.650715 -280.912515) (xy 408.620494 -280.870919)
			(xy 408.597151 -280.825107) (xy 408.581263 -280.776208) (xy 408.57322 -280.725426) (xy 408.25444 -280.725426)
			(xy 408.247483 -280.769985) (xy 408.233107 -280.814965) (xy 408.211982 -280.857198) (xy 408.18461 -280.895677)
			(xy 408.151643 -280.929487) (xy 408.113867 -280.957821) (xy 408.072181 -280.980006) (xy 408.027577 -280.995512)
			(xy 407.98112 -281.003971) (xy 407.957528 -281.005026) (xy 407.9474 -281.005671) (xy 407.92887 -281.013908)
			(xy 407.914998 -281.028698) (xy 407.911046 -281.038046) (xy 407.895762 -281.077947) (xy 407.859131 -281.155148)
			(xy 407.837894 -281.192224) (xy 407.83764 -281.192478) (xy 407.834379 -281.198583) (xy 407.830895 -281.211974)
			(xy 407.830782 -281.218894) (xy 407.830782 -281.232356) (xy 407.885138 -281.321256) (xy 407.888887 -281.327032)
			(xy 407.89894 -281.336437) (xy 407.90495 -281.339798) (xy 407.911046 -281.342846) (xy 407.924508 -281.34564)
			(xy 407.93162 -281.345132) (xy 407.949908 -281.344624) (xy 407.974726 -281.34511) (xy 408.023707 -281.353142)
			(xy 408.070743 -281.368991) (xy 408.114596 -281.392241) (xy 408.15411 -281.422279) (xy 408.188244 -281.458314)
			(xy 408.216099 -281.499397) (xy 408.23694 -281.544444) (xy 408.25022 -281.59227) (xy 408.255587 -281.641614)
			(xy 408.255136 -281.649932) (xy 408.594064 -281.649932) (xy 408.598024 -281.600878) (xy 408.609801 -281.553094)
			(xy 408.629092 -281.507818) (xy 408.655395 -281.466222) (xy 408.68803 -281.429385) (xy 408.726151 -281.39826)
			(xy 408.768772 -281.373653) (xy 408.814788 -281.356201) (xy 408.863007 -281.346357) (xy 408.912182 -281.344376)
			(xy 408.961037 -281.350308) (xy 409.008308 -281.364) (xy 409.05277 -281.385098) (xy 409.093273 -281.413054)
			(xy 409.128766 -281.447146) (xy 409.158331 -281.48649) (xy 409.181202 -281.530067) (xy 409.196786 -281.576748)
			(xy 409.204681 -281.625325) (xy 409.205176 -281.649932) (xy 409.544024 -281.649932) (xy 409.547984 -281.600878)
			(xy 409.559761 -281.553094) (xy 409.579052 -281.507818) (xy 409.605355 -281.466222) (xy 409.63799 -281.429385)
			(xy 409.676111 -281.39826) (xy 409.718732 -281.373653) (xy 409.764748 -281.356201) (xy 409.812967 -281.346357)
			(xy 409.862142 -281.344376) (xy 409.910997 -281.350308) (xy 409.958268 -281.364) (xy 410.00273 -281.385098)
			(xy 410.043233 -281.413054) (xy 410.078726 -281.447146) (xy 410.108291 -281.48649) (xy 410.131162 -281.530067)
			(xy 410.146746 -281.576748) (xy 410.154641 -281.625325) (xy 410.155136 -281.649932) (xy 410.493984 -281.649932)
			(xy 410.497944 -281.600878) (xy 410.509721 -281.553094) (xy 410.529012 -281.507818) (xy 410.555315 -281.466222)
			(xy 410.58795 -281.429385) (xy 410.626071 -281.39826) (xy 410.668692 -281.373653) (xy 410.714708 -281.356201)
			(xy 410.762927 -281.346357) (xy 410.812102 -281.344376) (xy 410.860957 -281.350308) (xy 410.908228 -281.364)
			(xy 410.95269 -281.385098) (xy 410.993193 -281.413054) (xy 411.028686 -281.447146) (xy 411.058251 -281.48649)
			(xy 411.081122 -281.530067) (xy 411.096706 -281.576748) (xy 411.104601 -281.625325) (xy 411.105096 -281.649932)
			(xy 411.444198 -281.649932) (xy 411.448158 -281.600878) (xy 411.459935 -281.553094) (xy 411.479226 -281.507818)
			(xy 411.505529 -281.466222) (xy 411.538164 -281.429385) (xy 411.576285 -281.39826) (xy 411.618906 -281.373653)
			(xy 411.664922 -281.356201) (xy 411.713141 -281.346357) (xy 411.762316 -281.344376) (xy 411.811171 -281.350308)
			(xy 411.858442 -281.364) (xy 411.902904 -281.385098) (xy 411.943407 -281.413054) (xy 411.9789 -281.447146)
			(xy 412.008465 -281.48649) (xy 412.031336 -281.530067) (xy 412.04692 -281.576748) (xy 412.054815 -281.625325)
			(xy 412.05531 -281.649932) (xy 412.394158 -281.649932) (xy 412.398118 -281.600878) (xy 412.409895 -281.553094)
			(xy 412.429186 -281.507818) (xy 412.455489 -281.466222) (xy 412.488124 -281.429385) (xy 412.526245 -281.39826)
			(xy 412.568866 -281.373653) (xy 412.614882 -281.356201) (xy 412.663101 -281.346357) (xy 412.712276 -281.344376)
			(xy 412.761131 -281.350308) (xy 412.808402 -281.364) (xy 412.852864 -281.385098) (xy 412.893367 -281.413054)
			(xy 412.92886 -281.447146) (xy 412.958425 -281.48649) (xy 412.981296 -281.530067) (xy 412.99688 -281.576748)
			(xy 413.004775 -281.625325) (xy 413.00527 -281.649932) (xy 413.344118 -281.649932) (xy 413.348078 -281.600878)
			(xy 413.359855 -281.553094) (xy 413.379146 -281.507818) (xy 413.405449 -281.466222) (xy 413.438084 -281.429385)
			(xy 413.476205 -281.39826) (xy 413.518826 -281.373653) (xy 413.564842 -281.356201) (xy 413.613061 -281.346357)
			(xy 413.662236 -281.344376) (xy 413.711091 -281.350308) (xy 413.758362 -281.364) (xy 413.802824 -281.385098)
			(xy 413.843327 -281.413054) (xy 413.87882 -281.447146) (xy 413.908385 -281.48649) (xy 413.931256 -281.530067)
			(xy 413.94684 -281.576748) (xy 413.954735 -281.625325) (xy 413.95523 -281.649932) (xy 414.294078 -281.649932)
			(xy 414.298038 -281.600878) (xy 414.309815 -281.553094) (xy 414.329106 -281.507818) (xy 414.355409 -281.466222)
			(xy 414.388044 -281.429385) (xy 414.426165 -281.39826) (xy 414.468786 -281.373653) (xy 414.514802 -281.356201)
			(xy 414.563021 -281.346357) (xy 414.612196 -281.344376) (xy 414.661051 -281.350308) (xy 414.708322 -281.364)
			(xy 414.752784 -281.385098) (xy 414.793287 -281.413054) (xy 414.82878 -281.447146) (xy 414.858345 -281.48649)
			(xy 414.881216 -281.530067) (xy 414.8968 -281.576748) (xy 414.904695 -281.625325) (xy 414.90519 -281.649932)
			(xy 415.244038 -281.649932) (xy 415.247998 -281.600878) (xy 415.259775 -281.553094) (xy 415.279066 -281.507818)
			(xy 415.305369 -281.466222) (xy 415.338004 -281.429385) (xy 415.376125 -281.39826) (xy 415.418746 -281.373653)
			(xy 415.464762 -281.356201) (xy 415.512981 -281.346357) (xy 415.562156 -281.344376) (xy 415.611011 -281.350308)
			(xy 415.658282 -281.364) (xy 415.702744 -281.385098) (xy 415.743247 -281.413054) (xy 415.77874 -281.447146)
			(xy 415.808305 -281.48649) (xy 415.831176 -281.530067) (xy 415.84676 -281.576748) (xy 415.854655 -281.625325)
			(xy 415.85515 -281.649932) (xy 416.193998 -281.649932) (xy 416.197958 -281.600878) (xy 416.209735 -281.553094)
			(xy 416.229026 -281.507818) (xy 416.255329 -281.466222) (xy 416.287964 -281.429385) (xy 416.326085 -281.39826)
			(xy 416.368706 -281.373653) (xy 416.414722 -281.356201) (xy 416.462941 -281.346357) (xy 416.512116 -281.344376)
			(xy 416.560971 -281.350308) (xy 416.608242 -281.364) (xy 416.652704 -281.385098) (xy 416.693207 -281.413054)
			(xy 416.7287 -281.447146) (xy 416.758265 -281.48649) (xy 416.781136 -281.530067) (xy 416.79672 -281.576748)
			(xy 416.804615 -281.625325) (xy 416.80511 -281.649932) (xy 417.144212 -281.649932) (xy 417.148172 -281.600878)
			(xy 417.159949 -281.553094) (xy 417.17924 -281.507818) (xy 417.205543 -281.466222) (xy 417.238178 -281.429385)
			(xy 417.276299 -281.39826) (xy 417.31892 -281.373653) (xy 417.364936 -281.356201) (xy 417.413155 -281.346357)
			(xy 417.46233 -281.344376) (xy 417.511185 -281.350308) (xy 417.558456 -281.364) (xy 417.602918 -281.385098)
			(xy 417.643421 -281.413054) (xy 417.678914 -281.447146) (xy 417.708479 -281.48649) (xy 417.73135 -281.530067)
			(xy 417.746934 -281.576748) (xy 417.754829 -281.625325) (xy 417.755324 -281.649932) (xy 418.094172 -281.649932)
			(xy 418.098132 -281.600878) (xy 418.109909 -281.553094) (xy 418.1292 -281.507818) (xy 418.155503 -281.466222)
			(xy 418.188138 -281.429385) (xy 418.226259 -281.39826) (xy 418.26888 -281.373653) (xy 418.314896 -281.356201)
			(xy 418.363115 -281.346357) (xy 418.41229 -281.344376) (xy 418.461145 -281.350308) (xy 418.508416 -281.364)
			(xy 418.552878 -281.385098) (xy 418.593381 -281.413054) (xy 418.628874 -281.447146) (xy 418.658439 -281.48649)
			(xy 418.68131 -281.530067) (xy 418.696894 -281.576748) (xy 418.704789 -281.625325) (xy 418.705284 -281.649932)
			(xy 419.044132 -281.649932) (xy 419.048092 -281.600878) (xy 419.059869 -281.553094) (xy 419.07916 -281.507818)
			(xy 419.105463 -281.466222) (xy 419.138098 -281.429385) (xy 419.176219 -281.39826) (xy 419.21884 -281.373653)
			(xy 419.264856 -281.356201) (xy 419.313075 -281.346357) (xy 419.36225 -281.344376) (xy 419.411105 -281.350308)
			(xy 419.458376 -281.364) (xy 419.502838 -281.385098) (xy 419.543341 -281.413054) (xy 419.578834 -281.447146)
			(xy 419.608399 -281.48649) (xy 419.63127 -281.530067) (xy 419.646854 -281.576748) (xy 419.654749 -281.625325)
			(xy 419.655244 -281.649932) (xy 419.994092 -281.649932) (xy 419.998052 -281.600878) (xy 420.009829 -281.553094)
			(xy 420.02912 -281.507818) (xy 420.055423 -281.466222) (xy 420.088058 -281.429385) (xy 420.126179 -281.39826)
			(xy 420.1688 -281.373653) (xy 420.214816 -281.356201) (xy 420.263035 -281.346357) (xy 420.31221 -281.344376)
			(xy 420.361065 -281.350308) (xy 420.408336 -281.364) (xy 420.452798 -281.385098) (xy 420.493301 -281.413054)
			(xy 420.528794 -281.447146) (xy 420.558359 -281.48649) (xy 420.58123 -281.530067) (xy 420.596814 -281.576748)
			(xy 420.604709 -281.625325) (xy 420.605204 -281.649932) (xy 420.944052 -281.649932) (xy 420.948012 -281.600878)
			(xy 420.959789 -281.553094) (xy 420.97908 -281.507818) (xy 421.005383 -281.466222) (xy 421.038018 -281.429385)
			(xy 421.076139 -281.39826) (xy 421.11876 -281.373653) (xy 421.164776 -281.356201) (xy 421.212995 -281.346357)
			(xy 421.26217 -281.344376) (xy 421.311025 -281.350308) (xy 421.358296 -281.364) (xy 421.402758 -281.385098)
			(xy 421.443261 -281.413054) (xy 421.478754 -281.447146) (xy 421.508319 -281.48649) (xy 421.53119 -281.530067)
			(xy 421.546774 -281.576748) (xy 421.554669 -281.625325) (xy 421.555164 -281.649932) (xy 421.894012 -281.649932)
			(xy 421.897972 -281.600878) (xy 421.909749 -281.553094) (xy 421.92904 -281.507818) (xy 421.955343 -281.466222)
			(xy 421.987978 -281.429385) (xy 422.026099 -281.39826) (xy 422.06872 -281.373653) (xy 422.114736 -281.356201)
			(xy 422.162955 -281.346357) (xy 422.21213 -281.344376) (xy 422.260985 -281.350308) (xy 422.308256 -281.364)
			(xy 422.352718 -281.385098) (xy 422.393221 -281.413054) (xy 422.428714 -281.447146) (xy 422.458279 -281.48649)
			(xy 422.48115 -281.530067) (xy 422.496734 -281.576748) (xy 422.504629 -281.625325) (xy 422.505124 -281.649932)
			(xy 422.844226 -281.649932) (xy 422.848186 -281.600878) (xy 422.859963 -281.553094) (xy 422.879254 -281.507818)
			(xy 422.905557 -281.466222) (xy 422.938192 -281.429385) (xy 422.976313 -281.39826) (xy 423.018934 -281.373653)
			(xy 423.06495 -281.356201) (xy 423.113169 -281.346357) (xy 423.162344 -281.344376) (xy 423.211199 -281.350308)
			(xy 423.25847 -281.364) (xy 423.302932 -281.385098) (xy 423.343435 -281.413054) (xy 423.378928 -281.447146)
			(xy 423.408493 -281.48649) (xy 423.431364 -281.530067) (xy 423.446948 -281.576748) (xy 423.454843 -281.625325)
			(xy 423.455338 -281.649932) (xy 423.794186 -281.649932) (xy 423.798146 -281.600878) (xy 423.809923 -281.553094)
			(xy 423.829214 -281.507818) (xy 423.855517 -281.466222) (xy 423.888152 -281.429385) (xy 423.926273 -281.39826)
			(xy 423.968894 -281.373653) (xy 424.01491 -281.356201) (xy 424.063129 -281.346357) (xy 424.112304 -281.344376)
			(xy 424.161159 -281.350308) (xy 424.20843 -281.364) (xy 424.252892 -281.385098) (xy 424.293395 -281.413054)
			(xy 424.328888 -281.447146) (xy 424.358453 -281.48649) (xy 424.381324 -281.530067) (xy 424.396908 -281.576748)
			(xy 424.404803 -281.625325) (xy 424.405298 -281.649932) (xy 424.744146 -281.649932) (xy 424.748106 -281.600878)
			(xy 424.759883 -281.553094) (xy 424.779174 -281.507818) (xy 424.805477 -281.466222) (xy 424.838112 -281.429385)
			(xy 424.876233 -281.39826) (xy 424.918854 -281.373653) (xy 424.96487 -281.356201) (xy 425.013089 -281.346357)
			(xy 425.062264 -281.344376) (xy 425.111119 -281.350308) (xy 425.15839 -281.364) (xy 425.202852 -281.385098)
			(xy 425.243355 -281.413054) (xy 425.278848 -281.447146) (xy 425.308413 -281.48649) (xy 425.331284 -281.530067)
			(xy 425.346868 -281.576748) (xy 425.354763 -281.625325) (xy 425.355253 -281.649678) (xy 425.693852 -281.649678)
			(xy 425.697812 -281.600624) (xy 425.709589 -281.55284) (xy 425.72888 -281.507564) (xy 425.755183 -281.465968)
			(xy 425.787818 -281.429131) (xy 425.825939 -281.398006) (xy 425.86856 -281.373399) (xy 425.914576 -281.355947)
			(xy 425.962795 -281.346103) (xy 426.01197 -281.344122) (xy 426.060825 -281.350054) (xy 426.108096 -281.363746)
			(xy 426.152558 -281.384844) (xy 426.193061 -281.4128) (xy 426.228554 -281.446892) (xy 426.258119 -281.486236)
			(xy 426.28099 -281.529813) (xy 426.296574 -281.576494) (xy 426.304469 -281.625071) (xy 426.304964 -281.649678)
			(xy 426.304959 -281.649932) (xy 426.643812 -281.649932) (xy 426.647772 -281.600878) (xy 426.659549 -281.553094)
			(xy 426.67884 -281.507818) (xy 426.705143 -281.466222) (xy 426.737778 -281.429385) (xy 426.775899 -281.39826)
			(xy 426.81852 -281.373653) (xy 426.864536 -281.356201) (xy 426.912755 -281.346357) (xy 426.96193 -281.344376)
			(xy 427.010785 -281.350308) (xy 427.058056 -281.364) (xy 427.102518 -281.385098) (xy 427.143021 -281.413054)
			(xy 427.178514 -281.447146) (xy 427.208079 -281.48649) (xy 427.23095 -281.530067) (xy 427.246534 -281.576748)
			(xy 427.254429 -281.625325) (xy 427.254924 -281.649932) (xy 427.594026 -281.649932) (xy 427.597986 -281.600878)
			(xy 427.609763 -281.553094) (xy 427.629054 -281.507818) (xy 427.655357 -281.466222) (xy 427.687992 -281.429385)
			(xy 427.726113 -281.39826) (xy 427.768734 -281.373653) (xy 427.81475 -281.356201) (xy 427.862969 -281.346357)
			(xy 427.912144 -281.344376) (xy 427.960999 -281.350308) (xy 428.00827 -281.364) (xy 428.052732 -281.385098)
			(xy 428.093235 -281.413054) (xy 428.128728 -281.447146) (xy 428.158293 -281.48649) (xy 428.181164 -281.530067)
			(xy 428.196748 -281.576748) (xy 428.204643 -281.625325) (xy 428.205138 -281.649932) (xy 428.543986 -281.649932)
			(xy 428.547946 -281.600878) (xy 428.559723 -281.553094) (xy 428.579014 -281.507818) (xy 428.605317 -281.466222)
			(xy 428.637952 -281.429385) (xy 428.676073 -281.39826) (xy 428.718694 -281.373653) (xy 428.76471 -281.356201)
			(xy 428.812929 -281.346357) (xy 428.862104 -281.344376) (xy 428.910959 -281.350308) (xy 428.95823 -281.364)
			(xy 429.002692 -281.385098) (xy 429.043195 -281.413054) (xy 429.078688 -281.447146) (xy 429.108253 -281.48649)
			(xy 429.131124 -281.530067) (xy 429.146708 -281.576748) (xy 429.154603 -281.625325) (xy 429.155098 -281.649932)
			(xy 429.154603 -281.674539) (xy 429.154424 -281.67564) (xy 429.473356 -281.67564) (xy 429.473356 -281.624224)
			(xy 429.481399 -281.573442) (xy 429.497287 -281.524543) (xy 429.52063 -281.478731) (xy 429.550851 -281.437135)
			(xy 429.587207 -281.400779) (xy 429.628803 -281.370558) (xy 429.674615 -281.347215) (xy 429.723514 -281.331327)
			(xy 429.774296 -281.323284) (xy 429.825712 -281.323284) (xy 429.876494 -281.331327) (xy 429.925393 -281.347215)
			(xy 429.971205 -281.370558) (xy 430.012801 -281.400779) (xy 430.049157 -281.437135) (xy 430.079378 -281.478731)
			(xy 430.102721 -281.524543) (xy 430.118609 -281.573442) (xy 430.126652 -281.624224) (xy 430.127156 -281.649932)
			(xy 430.126652 -281.67564) (xy 430.423316 -281.67564) (xy 430.423316 -281.624224) (xy 430.431359 -281.573442)
			(xy 430.447247 -281.524543) (xy 430.47059 -281.478731) (xy 430.500811 -281.437135) (xy 430.537167 -281.400779)
			(xy 430.578763 -281.370558) (xy 430.624575 -281.347215) (xy 430.673474 -281.331327) (xy 430.724256 -281.323284)
			(xy 430.775672 -281.323284) (xy 430.826454 -281.331327) (xy 430.875353 -281.347215) (xy 430.921165 -281.370558)
			(xy 430.962761 -281.400779) (xy 430.999117 -281.437135) (xy 431.029338 -281.478731) (xy 431.052681 -281.524543)
			(xy 431.068569 -281.573442) (xy 431.076612 -281.624224) (xy 431.077116 -281.649932) (xy 431.077111 -281.650186)
			(xy 431.394374 -281.650186) (xy 431.398334 -281.601132) (xy 431.410111 -281.553348) (xy 431.429402 -281.508072)
			(xy 431.455705 -281.466476) (xy 431.48834 -281.429639) (xy 431.526461 -281.398514) (xy 431.569082 -281.373907)
			(xy 431.615098 -281.356455) (xy 431.663317 -281.346611) (xy 431.712492 -281.34463) (xy 431.761347 -281.350562)
			(xy 431.808618 -281.364254) (xy 431.85308 -281.385352) (xy 431.893583 -281.413308) (xy 431.929076 -281.4474)
			(xy 431.958641 -281.486744) (xy 431.981512 -281.530321) (xy 431.997096 -281.577002) (xy 432.004991 -281.625579)
			(xy 432.005486 -281.650186) (xy 432.004991 -281.674793) (xy 431.997096 -281.72337) (xy 431.981512 -281.770051)
			(xy 431.958641 -281.813628) (xy 431.929076 -281.852972) (xy 431.893583 -281.887064) (xy 431.85308 -281.91502)
			(xy 431.808618 -281.936118) (xy 431.761347 -281.94981) (xy 431.712492 -281.955742) (xy 431.663317 -281.953761)
			(xy 431.615098 -281.943917) (xy 431.569082 -281.926465) (xy 431.526461 -281.901858) (xy 431.48834 -281.870733)
			(xy 431.455705 -281.833896) (xy 431.429402 -281.7923) (xy 431.410111 -281.747024) (xy 431.398334 -281.69924)
			(xy 431.394374 -281.650186) (xy 431.077111 -281.650186) (xy 431.076612 -281.67564) (xy 431.068569 -281.726422)
			(xy 431.052681 -281.775321) (xy 431.029338 -281.821133) (xy 430.999117 -281.862729) (xy 430.962761 -281.899085)
			(xy 430.921165 -281.929306) (xy 430.875353 -281.952649) (xy 430.826454 -281.968537) (xy 430.775672 -281.97658)
			(xy 430.724256 -281.97658) (xy 430.673474 -281.968537) (xy 430.624575 -281.952649) (xy 430.578763 -281.929306)
			(xy 430.537167 -281.899085) (xy 430.500811 -281.862729) (xy 430.47059 -281.821133) (xy 430.447247 -281.775321)
			(xy 430.431359 -281.726422) (xy 430.423316 -281.67564) (xy 430.126652 -281.67564) (xy 430.118609 -281.726422)
			(xy 430.102721 -281.775321) (xy 430.079378 -281.821133) (xy 430.049157 -281.862729) (xy 430.012801 -281.899085)
			(xy 429.971205 -281.929306) (xy 429.925393 -281.952649) (xy 429.876494 -281.968537) (xy 429.825712 -281.97658)
			(xy 429.774296 -281.97658) (xy 429.723514 -281.968537) (xy 429.674615 -281.952649) (xy 429.628803 -281.929306)
			(xy 429.587207 -281.899085) (xy 429.550851 -281.862729) (xy 429.52063 -281.821133) (xy 429.497287 -281.775321)
			(xy 429.481399 -281.726422) (xy 429.473356 -281.67564) (xy 429.154424 -281.67564) (xy 429.146708 -281.723116)
			(xy 429.131124 -281.769797) (xy 429.108253 -281.813374) (xy 429.078688 -281.852718) (xy 429.043195 -281.88681)
			(xy 429.002692 -281.914766) (xy 428.95823 -281.935864) (xy 428.910959 -281.949556) (xy 428.862104 -281.955488)
			(xy 428.812929 -281.953507) (xy 428.76471 -281.943663) (xy 428.718694 -281.926211) (xy 428.676073 -281.901604)
			(xy 428.637952 -281.870479) (xy 428.605317 -281.833642) (xy 428.579014 -281.792046) (xy 428.559723 -281.74677)
			(xy 428.547946 -281.698986) (xy 428.543986 -281.649932) (xy 428.205138 -281.649932) (xy 428.204643 -281.674539)
			(xy 428.196748 -281.723116) (xy 428.181164 -281.769797) (xy 428.158293 -281.813374) (xy 428.128728 -281.852718)
			(xy 428.093235 -281.88681) (xy 428.052732 -281.914766) (xy 428.00827 -281.935864) (xy 427.960999 -281.949556)
			(xy 427.912144 -281.955488) (xy 427.862969 -281.953507) (xy 427.81475 -281.943663) (xy 427.768734 -281.926211)
			(xy 427.726113 -281.901604) (xy 427.687992 -281.870479) (xy 427.655357 -281.833642) (xy 427.629054 -281.792046)
			(xy 427.609763 -281.74677) (xy 427.597986 -281.698986) (xy 427.594026 -281.649932) (xy 427.254924 -281.649932)
			(xy 427.254429 -281.674539) (xy 427.246534 -281.723116) (xy 427.23095 -281.769797) (xy 427.208079 -281.813374)
			(xy 427.178514 -281.852718) (xy 427.143021 -281.88681) (xy 427.102518 -281.914766) (xy 427.058056 -281.935864)
			(xy 427.010785 -281.949556) (xy 426.96193 -281.955488) (xy 426.912755 -281.953507) (xy 426.864536 -281.943663)
			(xy 426.81852 -281.926211) (xy 426.775899 -281.901604) (xy 426.737778 -281.870479) (xy 426.705143 -281.833642)
			(xy 426.67884 -281.792046) (xy 426.659549 -281.74677) (xy 426.647772 -281.698986) (xy 426.643812 -281.649932)
			(xy 426.304959 -281.649932) (xy 426.304469 -281.674285) (xy 426.296574 -281.722862) (xy 426.28099 -281.769543)
			(xy 426.258119 -281.81312) (xy 426.228554 -281.852464) (xy 426.193061 -281.886556) (xy 426.152558 -281.914512)
			(xy 426.108096 -281.93561) (xy 426.060825 -281.949302) (xy 426.01197 -281.955234) (xy 425.962795 -281.953253)
			(xy 425.914576 -281.943409) (xy 425.86856 -281.925957) (xy 425.825939 -281.90135) (xy 425.787818 -281.870225)
			(xy 425.755183 -281.833388) (xy 425.72888 -281.791792) (xy 425.709589 -281.746516) (xy 425.697812 -281.698732)
			(xy 425.693852 -281.649678) (xy 425.355253 -281.649678) (xy 425.355258 -281.649932) (xy 425.354763 -281.674539)
			(xy 425.346868 -281.723116) (xy 425.331284 -281.769797) (xy 425.308413 -281.813374) (xy 425.278848 -281.852718)
			(xy 425.243355 -281.88681) (xy 425.202852 -281.914766) (xy 425.15839 -281.935864) (xy 425.111119 -281.949556)
			(xy 425.062264 -281.955488) (xy 425.013089 -281.953507) (xy 424.96487 -281.943663) (xy 424.918854 -281.926211)
			(xy 424.876233 -281.901604) (xy 424.838112 -281.870479) (xy 424.805477 -281.833642) (xy 424.779174 -281.792046)
			(xy 424.759883 -281.74677) (xy 424.748106 -281.698986) (xy 424.744146 -281.649932) (xy 424.405298 -281.649932)
			(xy 424.404803 -281.674539) (xy 424.396908 -281.723116) (xy 424.381324 -281.769797) (xy 424.358453 -281.813374)
			(xy 424.328888 -281.852718) (xy 424.293395 -281.88681) (xy 424.252892 -281.914766) (xy 424.20843 -281.935864)
			(xy 424.161159 -281.949556) (xy 424.112304 -281.955488) (xy 424.063129 -281.953507) (xy 424.01491 -281.943663)
			(xy 423.968894 -281.926211) (xy 423.926273 -281.901604) (xy 423.888152 -281.870479) (xy 423.855517 -281.833642)
			(xy 423.829214 -281.792046) (xy 423.809923 -281.74677) (xy 423.798146 -281.698986) (xy 423.794186 -281.649932)
			(xy 423.455338 -281.649932) (xy 423.454843 -281.674539) (xy 423.446948 -281.723116) (xy 423.431364 -281.769797)
			(xy 423.408493 -281.813374) (xy 423.378928 -281.852718) (xy 423.343435 -281.88681) (xy 423.302932 -281.914766)
			(xy 423.25847 -281.935864) (xy 423.211199 -281.949556) (xy 423.162344 -281.955488) (xy 423.113169 -281.953507)
			(xy 423.06495 -281.943663) (xy 423.018934 -281.926211) (xy 422.976313 -281.901604) (xy 422.938192 -281.870479)
			(xy 422.905557 -281.833642) (xy 422.879254 -281.792046) (xy 422.859963 -281.74677) (xy 422.848186 -281.698986)
			(xy 422.844226 -281.649932) (xy 422.505124 -281.649932) (xy 422.504629 -281.674539) (xy 422.496734 -281.723116)
			(xy 422.48115 -281.769797) (xy 422.458279 -281.813374) (xy 422.428714 -281.852718) (xy 422.393221 -281.88681)
			(xy 422.352718 -281.914766) (xy 422.308256 -281.935864) (xy 422.260985 -281.949556) (xy 422.21213 -281.955488)
			(xy 422.162955 -281.953507) (xy 422.114736 -281.943663) (xy 422.06872 -281.926211) (xy 422.026099 -281.901604)
			(xy 421.987978 -281.870479) (xy 421.955343 -281.833642) (xy 421.92904 -281.792046) (xy 421.909749 -281.74677)
			(xy 421.897972 -281.698986) (xy 421.894012 -281.649932) (xy 421.555164 -281.649932) (xy 421.554669 -281.674539)
			(xy 421.546774 -281.723116) (xy 421.53119 -281.769797) (xy 421.508319 -281.813374) (xy 421.478754 -281.852718)
			(xy 421.443261 -281.88681) (xy 421.402758 -281.914766) (xy 421.358296 -281.935864) (xy 421.311025 -281.949556)
			(xy 421.26217 -281.955488) (xy 421.212995 -281.953507) (xy 421.164776 -281.943663) (xy 421.11876 -281.926211)
			(xy 421.076139 -281.901604) (xy 421.038018 -281.870479) (xy 421.005383 -281.833642) (xy 420.97908 -281.792046)
			(xy 420.959789 -281.74677) (xy 420.948012 -281.698986) (xy 420.944052 -281.649932) (xy 420.605204 -281.649932)
			(xy 420.604709 -281.674539) (xy 420.596814 -281.723116) (xy 420.58123 -281.769797) (xy 420.558359 -281.813374)
			(xy 420.528794 -281.852718) (xy 420.493301 -281.88681) (xy 420.452798 -281.914766) (xy 420.408336 -281.935864)
			(xy 420.361065 -281.949556) (xy 420.31221 -281.955488) (xy 420.263035 -281.953507) (xy 420.214816 -281.943663)
			(xy 420.1688 -281.926211) (xy 420.126179 -281.901604) (xy 420.088058 -281.870479) (xy 420.055423 -281.833642)
			(xy 420.02912 -281.792046) (xy 420.009829 -281.74677) (xy 419.998052 -281.698986) (xy 419.994092 -281.649932)
			(xy 419.655244 -281.649932) (xy 419.654749 -281.674539) (xy 419.646854 -281.723116) (xy 419.63127 -281.769797)
			(xy 419.608399 -281.813374) (xy 419.578834 -281.852718) (xy 419.543341 -281.88681) (xy 419.502838 -281.914766)
			(xy 419.458376 -281.935864) (xy 419.411105 -281.949556) (xy 419.36225 -281.955488) (xy 419.313075 -281.953507)
			(xy 419.264856 -281.943663) (xy 419.21884 -281.926211) (xy 419.176219 -281.901604) (xy 419.138098 -281.870479)
			(xy 419.105463 -281.833642) (xy 419.07916 -281.792046) (xy 419.059869 -281.74677) (xy 419.048092 -281.698986)
			(xy 419.044132 -281.649932) (xy 418.705284 -281.649932) (xy 418.704789 -281.674539) (xy 418.696894 -281.723116)
			(xy 418.68131 -281.769797) (xy 418.658439 -281.813374) (xy 418.628874 -281.852718) (xy 418.593381 -281.88681)
			(xy 418.552878 -281.914766) (xy 418.508416 -281.935864) (xy 418.461145 -281.949556) (xy 418.41229 -281.955488)
			(xy 418.363115 -281.953507) (xy 418.314896 -281.943663) (xy 418.26888 -281.926211) (xy 418.226259 -281.901604)
			(xy 418.188138 -281.870479) (xy 418.155503 -281.833642) (xy 418.1292 -281.792046) (xy 418.109909 -281.74677)
			(xy 418.098132 -281.698986) (xy 418.094172 -281.649932) (xy 417.755324 -281.649932) (xy 417.754829 -281.674539)
			(xy 417.746934 -281.723116) (xy 417.73135 -281.769797) (xy 417.708479 -281.813374) (xy 417.678914 -281.852718)
			(xy 417.643421 -281.88681) (xy 417.602918 -281.914766) (xy 417.558456 -281.935864) (xy 417.511185 -281.949556)
			(xy 417.46233 -281.955488) (xy 417.413155 -281.953507) (xy 417.364936 -281.943663) (xy 417.31892 -281.926211)
			(xy 417.276299 -281.901604) (xy 417.238178 -281.870479) (xy 417.205543 -281.833642) (xy 417.17924 -281.792046)
			(xy 417.159949 -281.74677) (xy 417.148172 -281.698986) (xy 417.144212 -281.649932) (xy 416.80511 -281.649932)
			(xy 416.804615 -281.674539) (xy 416.79672 -281.723116) (xy 416.781136 -281.769797) (xy 416.758265 -281.813374)
			(xy 416.7287 -281.852718) (xy 416.693207 -281.88681) (xy 416.652704 -281.914766) (xy 416.608242 -281.935864)
			(xy 416.560971 -281.949556) (xy 416.512116 -281.955488) (xy 416.462941 -281.953507) (xy 416.414722 -281.943663)
			(xy 416.368706 -281.926211) (xy 416.326085 -281.901604) (xy 416.287964 -281.870479) (xy 416.255329 -281.833642)
			(xy 416.229026 -281.792046) (xy 416.209735 -281.74677) (xy 416.197958 -281.698986) (xy 416.193998 -281.649932)
			(xy 415.85515 -281.649932) (xy 415.854655 -281.674539) (xy 415.84676 -281.723116) (xy 415.831176 -281.769797)
			(xy 415.808305 -281.813374) (xy 415.77874 -281.852718) (xy 415.743247 -281.88681) (xy 415.702744 -281.914766)
			(xy 415.658282 -281.935864) (xy 415.611011 -281.949556) (xy 415.562156 -281.955488) (xy 415.512981 -281.953507)
			(xy 415.464762 -281.943663) (xy 415.418746 -281.926211) (xy 415.376125 -281.901604) (xy 415.338004 -281.870479)
			(xy 415.305369 -281.833642) (xy 415.279066 -281.792046) (xy 415.259775 -281.74677) (xy 415.247998 -281.698986)
			(xy 415.244038 -281.649932) (xy 414.90519 -281.649932) (xy 414.904695 -281.674539) (xy 414.8968 -281.723116)
			(xy 414.881216 -281.769797) (xy 414.858345 -281.813374) (xy 414.82878 -281.852718) (xy 414.793287 -281.88681)
			(xy 414.752784 -281.914766) (xy 414.708322 -281.935864) (xy 414.661051 -281.949556) (xy 414.612196 -281.955488)
			(xy 414.563021 -281.953507) (xy 414.514802 -281.943663) (xy 414.468786 -281.926211) (xy 414.426165 -281.901604)
			(xy 414.388044 -281.870479) (xy 414.355409 -281.833642) (xy 414.329106 -281.792046) (xy 414.309815 -281.74677)
			(xy 414.298038 -281.698986) (xy 414.294078 -281.649932) (xy 413.95523 -281.649932) (xy 413.954735 -281.674539)
			(xy 413.94684 -281.723116) (xy 413.931256 -281.769797) (xy 413.908385 -281.813374) (xy 413.87882 -281.852718)
			(xy 413.843327 -281.88681) (xy 413.802824 -281.914766) (xy 413.758362 -281.935864) (xy 413.711091 -281.949556)
			(xy 413.662236 -281.955488) (xy 413.613061 -281.953507) (xy 413.564842 -281.943663) (xy 413.518826 -281.926211)
			(xy 413.476205 -281.901604) (xy 413.438084 -281.870479) (xy 413.405449 -281.833642) (xy 413.379146 -281.792046)
			(xy 413.359855 -281.74677) (xy 413.348078 -281.698986) (xy 413.344118 -281.649932) (xy 413.00527 -281.649932)
			(xy 413.004775 -281.674539) (xy 412.99688 -281.723116) (xy 412.981296 -281.769797) (xy 412.958425 -281.813374)
			(xy 412.92886 -281.852718) (xy 412.893367 -281.88681) (xy 412.852864 -281.914766) (xy 412.808402 -281.935864)
			(xy 412.761131 -281.949556) (xy 412.712276 -281.955488) (xy 412.663101 -281.953507) (xy 412.614882 -281.943663)
			(xy 412.568866 -281.926211) (xy 412.526245 -281.901604) (xy 412.488124 -281.870479) (xy 412.455489 -281.833642)
			(xy 412.429186 -281.792046) (xy 412.409895 -281.74677) (xy 412.398118 -281.698986) (xy 412.394158 -281.649932)
			(xy 412.05531 -281.649932) (xy 412.054815 -281.674539) (xy 412.04692 -281.723116) (xy 412.031336 -281.769797)
			(xy 412.008465 -281.813374) (xy 411.9789 -281.852718) (xy 411.943407 -281.88681) (xy 411.902904 -281.914766)
			(xy 411.858442 -281.935864) (xy 411.811171 -281.949556) (xy 411.762316 -281.955488) (xy 411.713141 -281.953507)
			(xy 411.664922 -281.943663) (xy 411.618906 -281.926211) (xy 411.576285 -281.901604) (xy 411.538164 -281.870479)
			(xy 411.505529 -281.833642) (xy 411.479226 -281.792046) (xy 411.459935 -281.74677) (xy 411.448158 -281.698986)
			(xy 411.444198 -281.649932) (xy 411.105096 -281.649932) (xy 411.104601 -281.674539) (xy 411.096706 -281.723116)
			(xy 411.081122 -281.769797) (xy 411.058251 -281.813374) (xy 411.028686 -281.852718) (xy 410.993193 -281.88681)
			(xy 410.95269 -281.914766) (xy 410.908228 -281.935864) (xy 410.860957 -281.949556) (xy 410.812102 -281.955488)
			(xy 410.762927 -281.953507) (xy 410.714708 -281.943663) (xy 410.668692 -281.926211) (xy 410.626071 -281.901604)
			(xy 410.58795 -281.870479) (xy 410.555315 -281.833642) (xy 410.529012 -281.792046) (xy 410.509721 -281.74677)
			(xy 410.497944 -281.698986) (xy 410.493984 -281.649932) (xy 410.155136 -281.649932) (xy 410.154641 -281.674539)
			(xy 410.146746 -281.723116) (xy 410.131162 -281.769797) (xy 410.108291 -281.813374) (xy 410.078726 -281.852718)
			(xy 410.043233 -281.88681) (xy 410.00273 -281.914766) (xy 409.958268 -281.935864) (xy 409.910997 -281.949556)
			(xy 409.862142 -281.955488) (xy 409.812967 -281.953507) (xy 409.764748 -281.943663) (xy 409.718732 -281.926211)
			(xy 409.676111 -281.901604) (xy 409.63799 -281.870479) (xy 409.605355 -281.833642) (xy 409.579052 -281.792046)
			(xy 409.559761 -281.74677) (xy 409.547984 -281.698986) (xy 409.544024 -281.649932) (xy 409.205176 -281.649932)
			(xy 409.204681 -281.674539) (xy 409.196786 -281.723116) (xy 409.181202 -281.769797) (xy 409.158331 -281.813374)
			(xy 409.128766 -281.852718) (xy 409.093273 -281.88681) (xy 409.05277 -281.914766) (xy 409.008308 -281.935864)
			(xy 408.961037 -281.949556) (xy 408.912182 -281.955488) (xy 408.863007 -281.953507) (xy 408.814788 -281.943663)
			(xy 408.768772 -281.926211) (xy 408.726151 -281.901604) (xy 408.68803 -281.870479) (xy 408.655395 -281.833642)
			(xy 408.629092 -281.792046) (xy 408.609801 -281.74677) (xy 408.598024 -281.698986) (xy 408.594064 -281.649932)
			(xy 408.255136 -281.649932) (xy 408.2529 -281.691176) (xy 408.242232 -281.739651) (xy 408.223861 -281.785762)
			(xy 408.198273 -281.828293) (xy 408.166141 -281.866124) (xy 408.128312 -281.898259) (xy 408.085783 -281.92385)
			(xy 408.039674 -281.942224) (xy 407.9912 -281.952897) (xy 407.941638 -281.955587) (xy 407.892294 -281.950224)
			(xy 407.844467 -281.936949) (xy 407.799418 -281.916111) (xy 407.758333 -281.888259) (xy 407.722295 -281.854128)
			(xy 407.692254 -281.814616) (xy 407.669 -281.770765) (xy 407.653147 -281.72373) (xy 407.645112 -281.67475)
			(xy 407.6446 -281.649932) (xy 407.645108 -281.63139) (xy 407.645616 -281.624532) (xy 407.642822 -281.610562)
			(xy 407.639774 -281.604974) (xy 407.636431 -281.599063) (xy 407.627162 -281.589144) (xy 407.621486 -281.585416)
			(xy 407.621232 -281.585162) (xy 407.54427 -281.538172) (xy 407.538328 -281.534772) (xy 407.525198 -281.530917)
			(xy 407.518362 -281.530552) (xy 407.504646 -281.530552) (xy 407.492454 -281.53741) (xy 407.491946 -281.537918)
			(xy 407.472683 -281.549053) (xy 407.433298 -281.569762) (xy 407.413206 -281.57932) (xy 407.406246 -281.582903)
			(xy 407.394733 -281.5935) (xy 407.3906 -281.600148) (xy 407.389584 -281.602434) (xy 407.389076 -281.603196)
			(xy 407.365816 -281.648627) (xy 407.311091 -281.734788) (xy 407.279856 -281.775154) (xy 407.274014 -281.784298)
			(xy 407.262459 -281.806709) (xy 407.233142 -281.847727) (xy 407.197489 -281.883375) (xy 407.156465 -281.912685)
			(xy 407.13406 -281.924252) (xy 407.124916 -281.930094) (xy 407.088568 -281.958261) (xy 407.011418 -282.008311)
			(xy 406.929851 -282.050785) (xy 406.887426 -282.068524) (xy 406.880514 -282.071631) (xy 406.868765 -282.081188)
			(xy 406.864312 -282.08732) (xy 406.859994 -282.093416) (xy 406.857708 -282.100782) (xy 406.856743 -282.104323)
			(xy 406.855725 -282.11159) (xy 406.855676 -282.11526) (xy 406.855676 -282.124912) (xy 406.855166 -282.150899)
			(xy 406.847036 -282.202234) (xy 406.846575 -282.203652) (xy 450.561456 -282.203652) (xy 450.561883 -282.178253)
			(xy 450.568618 -282.127905) (xy 450.581977 -282.078896) (xy 450.601722 -282.032094) (xy 450.627505 -281.988326)
			(xy 450.658869 -281.948369) (xy 450.676772 -281.930348) (xy 450.683884 -281.92349) (xy 450.687694 -281.9146)
			(xy 450.689546 -281.910179) (xy 450.691714 -281.900842) (xy 450.692012 -281.896058) (xy 450.694806 -281.825954)
			(xy 450.693282 -281.811984) (xy 450.691758 -281.80665) (xy 450.688456 -281.797506) (xy 450.681852 -281.79014)
			(xy 450.663878 -281.769091) (xy 450.633518 -281.722813) (xy 450.610173 -281.672629) (xy 450.594333 -281.619596)
			(xy 450.586332 -281.56483) (xy 450.58584 -281.537156) (xy 450.58584 -281.536902) (xy 450.586257 -281.509647)
			(xy 450.594015 -281.455692) (xy 450.609373 -281.40339) (xy 450.632019 -281.353807) (xy 450.661492 -281.307952)
			(xy 450.69719 -281.266758) (xy 450.738388 -281.231064) (xy 450.784247 -281.201597) (xy 450.833833 -281.178957)
			(xy 450.886137 -281.163605) (xy 450.940093 -281.155854) (xy 450.967348 -281.155394) (xy 450.996088 -281.15589)
			(xy 451.052916 -281.16452) (xy 451.107807 -281.181576) (xy 451.159519 -281.206674) (xy 451.20688 -281.239245)
			(xy 451.228206 -281.258518) (xy 451.235318 -281.265122) (xy 451.2437 -281.268424) (xy 451.248266 -281.270181)
			(xy 451.257859 -281.272098) (xy 451.26275 -281.272234) (xy 451.332346 -281.272234) (xy 451.337236 -281.272093)
			(xy 451.346829 -281.270177) (xy 451.351396 -281.268424) (xy 451.359778 -281.265122) (xy 451.36689 -281.258518)
			(xy 451.388217 -281.239248) (xy 451.43558 -281.206683) (xy 451.487291 -281.181592) (xy 451.542182 -281.164542)
			(xy 451.599009 -281.15592) (xy 451.656487 -281.15592) (xy 451.713314 -281.164542) (xy 451.768205 -281.181592)
			(xy 451.819916 -281.206683) (xy 451.867279 -281.239248) (xy 451.888606 -281.258518) (xy 451.895718 -281.265122)
			(xy 451.9041 -281.268424) (xy 451.908666 -281.270181) (xy 451.918259 -281.272098) (xy 451.92315 -281.272234)
			(xy 451.992746 -281.272234) (xy 451.997636 -281.272093) (xy 452.007229 -281.270177) (xy 452.011796 -281.268424)
			(xy 452.020178 -281.265122) (xy 452.02729 -281.258518) (xy 452.048617 -281.239248) (xy 452.09598 -281.206683)
			(xy 452.147691 -281.181592) (xy 452.202582 -281.164542) (xy 452.259409 -281.15592) (xy 452.316887 -281.15592)
			(xy 452.373714 -281.164542) (xy 452.428605 -281.181592) (xy 452.480316 -281.206683) (xy 452.527679 -281.239248)
			(xy 452.549006 -281.258518) (xy 452.556118 -281.265122) (xy 452.5645 -281.268424) (xy 452.569066 -281.270181)
			(xy 452.578659 -281.272098) (xy 452.58355 -281.272234) (xy 452.653146 -281.272234) (xy 452.658036 -281.272093)
			(xy 452.667629 -281.270177) (xy 452.672196 -281.268424) (xy 452.680578 -281.265122) (xy 452.68769 -281.258518)
			(xy 452.708994 -281.239221) (xy 452.756363 -281.206659) (xy 452.80808 -281.181572) (xy 452.862976 -281.164528)
			(xy 452.919807 -281.155911) (xy 452.948548 -281.155394) (xy 452.975801 -281.155833) (xy 453.02975 -281.163596)
			(xy 453.082046 -281.178958) (xy 453.131623 -281.201604) (xy 453.177474 -281.231076) (xy 453.218663 -281.266772)
			(xy 453.254354 -281.307967) (xy 453.28382 -281.353821) (xy 453.30646 -281.403401) (xy 453.321814 -281.455699)
			(xy 453.32957 -281.509649) (xy 453.330056 -281.536902) (xy 453.329661 -281.562302) (xy 453.322919 -281.612651)
			(xy 453.309553 -281.661661) (xy 453.289802 -281.708463) (xy 453.281187 -281.723084) (xy 464.670392 -281.723084)
			(xy 464.674463 -281.667462) (xy 464.686589 -281.613025) (xy 464.706512 -281.560934) (xy 464.733808 -281.512299)
			(xy 464.767894 -281.468156) (xy 464.808043 -281.429447) (xy 464.853401 -281.396996) (xy 464.903001 -281.371495)
			(xy 464.955785 -281.353488) (xy 465.010628 -281.343358) (xy 465.066362 -281.341321) (xy 465.121799 -281.347421)
			(xy 465.175756 -281.361527) (xy 465.227085 -281.383339) (xy 465.274691 -281.412393) (xy 465.317559 -281.448068)
			(xy 465.354776 -281.489605) (xy 465.385549 -281.536118) (xy 465.409221 -281.586615) (xy 465.425289 -281.640022)
			(xy 465.433409 -281.695198) (xy 465.433918 -281.723084) (xy 465.433409 -281.75097) (xy 465.425289 -281.806146)
			(xy 465.409221 -281.859553) (xy 465.385549 -281.91005) (xy 465.354776 -281.956563) (xy 465.317559 -281.9981)
			(xy 465.274691 -282.033775) (xy 465.227085 -282.062829) (xy 465.175756 -282.084641) (xy 465.121799 -282.098747)
			(xy 465.066362 -282.104847) (xy 465.010628 -282.10281) (xy 464.955785 -282.09268) (xy 464.903001 -282.074673)
			(xy 464.853401 -282.049172) (xy 464.808043 -282.016721) (xy 464.767894 -281.978012) (xy 464.733808 -281.933869)
			(xy 464.706512 -281.885234) (xy 464.686589 -281.833143) (xy 464.674463 -281.778706) (xy 464.670392 -281.723084)
			(xy 453.281187 -281.723084) (xy 453.264014 -281.752229) (xy 453.232645 -281.792186) (xy 453.21474 -281.810206)
			(xy 453.207628 -281.817064) (xy 453.203818 -281.825954) (xy 453.201974 -281.830378) (xy 453.199801 -281.839712)
			(xy 453.1995 -281.844496) (xy 453.196706 -281.9146) (xy 453.19823 -281.92857) (xy 453.199754 -281.933904)
			(xy 453.203056 -281.943048) (xy 453.20966 -281.950414) (xy 453.227661 -281.971441) (xy 453.258016 -282.017725)
			(xy 453.281356 -282.067914) (xy 453.29719 -282.120952) (xy 453.305184 -282.175723) (xy 453.305672 -282.203398)
			(xy 453.305672 -282.203652) (xy 453.3052 -282.230905) (xy 453.297449 -282.284858) (xy 453.282097 -282.337158)
			(xy 453.259457 -282.38674) (xy 453.229991 -282.432595) (xy 453.194298 -282.473789) (xy 453.153105 -282.509484)
			(xy 453.107251 -282.538951) (xy 453.057669 -282.561593) (xy 453.00537 -282.576946) (xy 452.951417 -282.584699)
			(xy 452.924164 -282.58516) (xy 452.895425 -282.584642) (xy 452.838598 -282.576016) (xy 452.783708 -282.558963)
			(xy 452.731996 -282.533871) (xy 452.684633 -282.501306) (xy 452.663306 -282.482036) (xy 452.656194 -282.475432)
			(xy 452.647812 -282.47213) (xy 452.643244 -282.470378) (xy 452.633652 -282.468458) (xy 452.628762 -282.46832)
			(xy 452.559166 -282.46832) (xy 452.554276 -282.468461) (xy 452.544683 -282.470377) (xy 452.540116 -282.47213)
			(xy 452.531734 -282.475432) (xy 452.524622 -282.482036) (xy 452.503295 -282.501306) (xy 452.455932 -282.533871)
			(xy 452.404221 -282.558962) (xy 452.34933 -282.576012) (xy 452.292503 -282.584634) (xy 452.235025 -282.584634)
			(xy 452.178198 -282.576012) (xy 452.123307 -282.558962) (xy 452.071596 -282.533871) (xy 452.024233 -282.501306)
			(xy 452.002906 -282.482036) (xy 451.995794 -282.475432) (xy 451.987412 -282.47213) (xy 451.982844 -282.470378)
			(xy 451.973252 -282.468458) (xy 451.968362 -282.46832) (xy 451.898766 -282.46832) (xy 451.893876 -282.468461)
			(xy 451.884283 -282.470377) (xy 451.879716 -282.47213) (xy 451.871334 -282.475432) (xy 451.864222 -282.482036)
			(xy 451.842895 -282.501306) (xy 451.795532 -282.533871) (xy 451.743821 -282.558962) (xy 451.68893 -282.576012)
			(xy 451.632103 -282.584634) (xy 451.574625 -282.584634) (xy 451.517798 -282.576012) (xy 451.462907 -282.558962)
			(xy 451.411196 -282.533871) (xy 451.363833 -282.501306) (xy 451.342506 -282.482036) (xy 451.335394 -282.475432)
			(xy 451.327012 -282.47213) (xy 451.322444 -282.470378) (xy 451.312852 -282.468458) (xy 451.307962 -282.46832)
			(xy 451.238366 -282.46832) (xy 451.233476 -282.468461) (xy 451.223883 -282.470377) (xy 451.219316 -282.47213)
			(xy 451.210934 -282.475432) (xy 451.203822 -282.482036) (xy 451.182506 -282.501319) (xy 451.135141 -282.533885)
			(xy 451.083427 -282.558975) (xy 451.028534 -282.576023) (xy 450.971704 -282.584642) (xy 450.942964 -282.58516)
			(xy 450.915708 -282.584778) (xy 450.861752 -282.577015) (xy 450.809449 -282.561652) (xy 450.759866 -282.539002)
			(xy 450.71401 -282.509526) (xy 450.672817 -282.473824) (xy 450.637124 -282.432622) (xy 450.607658 -282.38676)
			(xy 450.585018 -282.337172) (xy 450.569667 -282.284866) (xy 450.561916 -282.230908) (xy 450.561456 -282.203652)
			(xy 406.846575 -282.203652) (xy 406.830975 -282.251664) (xy 406.807379 -282.297974) (xy 406.776829 -282.340022)
			(xy 406.740078 -282.376773) (xy 406.69803 -282.407323) (xy 406.65172 -282.430919) (xy 406.60229 -282.44698)
			(xy 406.550955 -282.45511) (xy 406.498981 -282.45511) (xy 406.447646 -282.44698) (xy 406.398216 -282.430919)
			(xy 406.351906 -282.407323) (xy 406.309858 -282.376773) (xy 406.273107 -282.340022) (xy 406.242557 -282.297974)
			(xy 406.218961 -282.251664) (xy 406.2029 -282.202234) (xy 406.19477 -282.150899) (xy 406.19426 -282.124912)
			(xy 406.19426 -282.117038) (xy 406.194514 -282.109418) (xy 406.19045 -282.094432) (xy 406.186132 -282.088082)
			(xy 406.181705 -282.081712) (xy 406.169814 -282.07176) (xy 406.162764 -282.068524) (xy 406.16251 -282.068524)
			(xy 406.13531 -282.057245) (xy 406.082188 -282.031826) (xy 406.056338 -282.017724) (xy 406.050242 -282.014422)
			(xy 406.037034 -282.01112) (xy 406.030684 -282.01112) (xy 406.023982 -282.011555) (xy 406.011126 -282.015426)
			(xy 406.005284 -282.01874) (xy 405.929592 -282.065476) (xy 405.922141 -282.0705) (xy 405.911048 -282.084626)
			(xy 405.905478 -282.101702) (xy 405.905462 -282.110688) (xy 405.905716 -282.124912) (xy 405.905206 -282.150899)
			(xy 405.897076 -282.202234) (xy 405.881015 -282.251664) (xy 405.857419 -282.297974) (xy 405.826869 -282.340022)
			(xy 405.790118 -282.376773) (xy 405.74807 -282.407323) (xy 405.70176 -282.430919) (xy 405.65233 -282.44698)
			(xy 405.600995 -282.45511) (xy 405.549021 -282.45511) (xy 405.497686 -282.44698) (xy 405.448256 -282.430919)
			(xy 405.401946 -282.407323) (xy 405.359898 -282.376773) (xy 405.323147 -282.340022) (xy 405.292597 -282.297974)
			(xy 405.269001 -282.251664) (xy 405.25294 -282.202234) (xy 405.24481 -282.150899) (xy 405.2443 -282.124912)
			(xy 405.244554 -282.110434) (xy 405.245062 -282.099766) (xy 405.241252 -282.090114) (xy 405.239223 -282.085244)
			(xy 405.233462 -282.076407) (xy 405.229822 -282.072588) (xy 405.220424 -282.065222) (xy 405.145748 -282.018994)
			(xy 405.137906 -282.014574) (xy 405.120276 -282.010989) (xy 405.10249 -282.013695) (xy 405.09444 -282.017724)
			(xy 405.068345 -282.031857) (xy 405.014713 -282.057275) (xy 404.987252 -282.068524) (xy 404.986998 -282.068524)
			(xy 404.980182 -282.071612) (xy 404.968562 -282.081031) (xy 404.964138 -282.087066) (xy 404.95982 -282.093162)
			(xy 404.957534 -282.100528) (xy 404.956567 -282.104069) (xy 404.955542 -282.111336) (xy 404.955502 -282.115006)
			(xy 404.955502 -282.124912) (xy 404.954992 -282.150899) (xy 404.946862 -282.202234) (xy 404.930801 -282.251664)
			(xy 404.907205 -282.297974) (xy 404.876655 -282.340022) (xy 404.839904 -282.376773) (xy 404.797856 -282.407323)
			(xy 404.751546 -282.430919) (xy 404.702116 -282.44698) (xy 404.650781 -282.45511) (xy 404.598807 -282.45511)
			(xy 404.547472 -282.44698) (xy 404.498042 -282.430919) (xy 404.451732 -282.407323) (xy 404.409684 -282.376773)
			(xy 404.372933 -282.340022) (xy 404.342383 -282.297974) (xy 404.318787 -282.251664) (xy 404.302726 -282.202234)
			(xy 404.294596 -282.150899) (xy 404.294086 -282.124912) (xy 404.294086 -282.117038) (xy 404.29434 -282.109418)
			(xy 404.290276 -282.094432) (xy 404.285958 -282.088082) (xy 404.281533 -282.08171) (xy 404.269644 -282.071753)
			(xy 404.26259 -282.068524) (xy 404.262336 -282.068524) (xy 404.235135 -282.057246) (xy 404.182013 -282.031828)
			(xy 404.156164 -282.017724) (xy 404.150068 -282.014422) (xy 404.13686 -282.01112) (xy 404.13051 -282.01112)
			(xy 404.123807 -282.011552) (xy 404.110948 -282.015417) (xy 404.10511 -282.01874) (xy 404.029418 -282.065476)
			(xy 404.021964 -282.070498) (xy 404.010865 -282.084623) (xy 404.005292 -282.101701) (xy 404.005288 -282.110688)
			(xy 404.005542 -282.124912) (xy 404.005032 -282.1509) (xy 403.9969 -282.202235) (xy 403.980838 -282.251666)
			(xy 403.957242 -282.297976) (xy 403.926693 -282.340025) (xy 403.889942 -282.376778) (xy 403.847895 -282.407331)
			(xy 403.801586 -282.43093) (xy 403.752156 -282.446995) (xy 403.700822 -282.45513) (xy 403.674834 -282.45562)
			(xy 403.66118 -282.455458) (xy 403.633967 -282.453168) (xy 403.620478 -282.451048) (xy 403.60854 -282.449016)
			(xy 403.59711 -282.452572) (xy 403.592579 -282.454086) (xy 403.58414 -282.45856) (xy 403.580346 -282.461462)
			(xy 403.577298 -282.464256) (xy 403.51837 -282.520644) (xy 403.514135 -282.524871) (xy 403.507581 -282.534878)
			(xy 403.505416 -282.540456) (xy 403.501606 -282.551378) (xy 403.502876 -282.56357) (xy 403.503916 -282.572551)
			(xy 403.505059 -282.590597) (xy 403.505162 -282.599638) (xy 403.505162 -282.599892) (xy 422.843972 -282.599892)
			(xy 422.847932 -282.550838) (xy 422.859709 -282.503054) (xy 422.879 -282.457778) (xy 422.905303 -282.416182)
			(xy 422.937938 -282.379345) (xy 422.976059 -282.34822) (xy 423.01868 -282.323613) (xy 423.064696 -282.306161)
			(xy 423.112915 -282.296317) (xy 423.16209 -282.294336) (xy 423.210945 -282.300268) (xy 423.258216 -282.31396)
			(xy 423.302678 -282.335058) (xy 423.343181 -282.363014) (xy 423.378674 -282.397106) (xy 423.408239 -282.43645)
			(xy 423.43111 -282.480027) (xy 423.446694 -282.526708) (xy 423.454589 -282.575285) (xy 423.455084 -282.599892)
			(xy 423.794186 -282.599892) (xy 423.798146 -282.550838) (xy 423.809923 -282.503054) (xy 423.829214 -282.457778)
			(xy 423.855517 -282.416182) (xy 423.888152 -282.379345) (xy 423.926273 -282.34822) (xy 423.968894 -282.323613)
			(xy 424.01491 -282.306161) (xy 424.063129 -282.296317) (xy 424.112304 -282.294336) (xy 424.161159 -282.300268)
			(xy 424.20843 -282.31396) (xy 424.252892 -282.335058) (xy 424.293395 -282.363014) (xy 424.328888 -282.397106)
			(xy 424.358453 -282.43645) (xy 424.381324 -282.480027) (xy 424.396908 -282.526708) (xy 424.404803 -282.575285)
			(xy 424.405298 -282.599892) (xy 424.404803 -282.624499) (xy 424.404624 -282.6256) (xy 424.723302 -282.6256)
			(xy 424.723302 -282.574184) (xy 424.731345 -282.523402) (xy 424.747233 -282.474503) (xy 424.770576 -282.428691)
			(xy 424.800797 -282.387095) (xy 424.837153 -282.350739) (xy 424.878749 -282.320518) (xy 424.924561 -282.297175)
			(xy 424.97346 -282.281287) (xy 425.024242 -282.273244) (xy 425.075658 -282.273244) (xy 425.12644 -282.281287)
			(xy 425.175339 -282.297175) (xy 425.221151 -282.320518) (xy 425.262747 -282.350739) (xy 425.299103 -282.387095)
			(xy 425.329324 -282.428691) (xy 425.352667 -282.474503) (xy 425.368555 -282.523402) (xy 425.376598 -282.574184)
			(xy 425.377102 -282.599892) (xy 425.376598 -282.6256) (xy 425.673262 -282.6256) (xy 425.673262 -282.574184)
			(xy 425.681305 -282.523402) (xy 425.697193 -282.474503) (xy 425.720536 -282.428691) (xy 425.750757 -282.387095)
			(xy 425.787113 -282.350739) (xy 425.828709 -282.320518) (xy 425.874521 -282.297175) (xy 425.92342 -282.281287)
			(xy 425.974202 -282.273244) (xy 426.025618 -282.273244) (xy 426.0764 -282.281287) (xy 426.125299 -282.297175)
			(xy 426.171111 -282.320518) (xy 426.212707 -282.350739) (xy 426.249063 -282.387095) (xy 426.279284 -282.428691)
			(xy 426.302627 -282.474503) (xy 426.318515 -282.523402) (xy 426.326558 -282.574184) (xy 426.327062 -282.599892)
			(xy 426.644066 -282.599892) (xy 426.648026 -282.550838) (xy 426.659803 -282.503054) (xy 426.679094 -282.457778)
			(xy 426.705397 -282.416182) (xy 426.738032 -282.379345) (xy 426.776153 -282.34822) (xy 426.818774 -282.323613)
			(xy 426.86479 -282.306161) (xy 426.913009 -282.296317) (xy 426.962184 -282.294336) (xy 427.011039 -282.300268)
			(xy 427.05831 -282.31396) (xy 427.102772 -282.335058) (xy 427.143275 -282.363014) (xy 427.178768 -282.397106)
			(xy 427.208333 -282.43645) (xy 427.231204 -282.480027) (xy 427.246788 -282.526708) (xy 427.254683 -282.575285)
			(xy 427.255178 -282.599892) (xy 427.254683 -282.624499) (xy 427.254504 -282.6256) (xy 427.573182 -282.6256)
			(xy 427.573182 -282.574184) (xy 427.581225 -282.523402) (xy 427.597113 -282.474503) (xy 427.620456 -282.428691)
			(xy 427.650677 -282.387095) (xy 427.687033 -282.350739) (xy 427.728629 -282.320518) (xy 427.774441 -282.297175)
			(xy 427.82334 -282.281287) (xy 427.874122 -282.273244) (xy 427.925538 -282.273244) (xy 427.97632 -282.281287)
			(xy 428.025219 -282.297175) (xy 428.071031 -282.320518) (xy 428.112627 -282.350739) (xy 428.148983 -282.387095)
			(xy 428.179204 -282.428691) (xy 428.202547 -282.474503) (xy 428.218435 -282.523402) (xy 428.226478 -282.574184)
			(xy 428.226982 -282.599892) (xy 428.226478 -282.6256) (xy 428.523142 -282.6256) (xy 428.523142 -282.574184)
			(xy 428.531185 -282.523402) (xy 428.547073 -282.474503) (xy 428.570416 -282.428691) (xy 428.600637 -282.387095)
			(xy 428.636993 -282.350739) (xy 428.678589 -282.320518) (xy 428.724401 -282.297175) (xy 428.7733 -282.281287)
			(xy 428.824082 -282.273244) (xy 428.875498 -282.273244) (xy 428.92628 -282.281287) (xy 428.975179 -282.297175)
			(xy 429.020991 -282.320518) (xy 429.062587 -282.350739) (xy 429.098943 -282.387095) (xy 429.129164 -282.428691)
			(xy 429.152507 -282.474503) (xy 429.168395 -282.523402) (xy 429.176438 -282.574184) (xy 429.176942 -282.599892)
			(xy 429.4942 -282.599892) (xy 429.49816 -282.550838) (xy 429.509937 -282.503054) (xy 429.529228 -282.457778)
			(xy 429.555531 -282.416182) (xy 429.588166 -282.379345) (xy 429.626287 -282.34822) (xy 429.668908 -282.323613)
			(xy 429.714924 -282.306161) (xy 429.763143 -282.296317) (xy 429.812318 -282.294336) (xy 429.861173 -282.300268)
			(xy 429.908444 -282.31396) (xy 429.952906 -282.335058) (xy 429.993409 -282.363014) (xy 430.028902 -282.397106)
			(xy 430.058467 -282.43645) (xy 430.081338 -282.480027) (xy 430.096922 -282.526708) (xy 430.104817 -282.575285)
			(xy 430.105312 -282.599892) (xy 430.44416 -282.599892) (xy 430.44812 -282.550838) (xy 430.459897 -282.503054)
			(xy 430.479188 -282.457778) (xy 430.505491 -282.416182) (xy 430.538126 -282.379345) (xy 430.576247 -282.34822)
			(xy 430.618868 -282.323613) (xy 430.664884 -282.306161) (xy 430.713103 -282.296317) (xy 430.762278 -282.294336)
			(xy 430.811133 -282.300268) (xy 430.858404 -282.31396) (xy 430.902866 -282.335058) (xy 430.943369 -282.363014)
			(xy 430.978862 -282.397106) (xy 431.008427 -282.43645) (xy 431.031298 -282.480027) (xy 431.046882 -282.526708)
			(xy 431.054777 -282.575285) (xy 431.055272 -282.599892) (xy 431.054777 -282.624499) (xy 431.046882 -282.673076)
			(xy 431.031298 -282.719757) (xy 431.008427 -282.763334) (xy 430.978862 -282.802678) (xy 430.943369 -282.83677)
			(xy 430.902866 -282.864726) (xy 430.858404 -282.885824) (xy 430.811133 -282.899516) (xy 430.762278 -282.905448)
			(xy 430.713103 -282.903467) (xy 430.664884 -282.893623) (xy 430.618868 -282.876171) (xy 430.576247 -282.851564)
			(xy 430.538126 -282.820439) (xy 430.505491 -282.783602) (xy 430.479188 -282.742006) (xy 430.459897 -282.69673)
			(xy 430.44812 -282.648946) (xy 430.44416 -282.599892) (xy 430.105312 -282.599892) (xy 430.104817 -282.624499)
			(xy 430.096922 -282.673076) (xy 430.081338 -282.719757) (xy 430.058467 -282.763334) (xy 430.028902 -282.802678)
			(xy 429.993409 -282.83677) (xy 429.952906 -282.864726) (xy 429.908444 -282.885824) (xy 429.861173 -282.899516)
			(xy 429.812318 -282.905448) (xy 429.763143 -282.903467) (xy 429.714924 -282.893623) (xy 429.668908 -282.876171)
			(xy 429.626287 -282.851564) (xy 429.588166 -282.820439) (xy 429.555531 -282.783602) (xy 429.529228 -282.742006)
			(xy 429.509937 -282.69673) (xy 429.49816 -282.648946) (xy 429.4942 -282.599892) (xy 429.176942 -282.599892)
			(xy 429.176438 -282.6256) (xy 429.168395 -282.676382) (xy 429.152507 -282.725281) (xy 429.129164 -282.771093)
			(xy 429.098943 -282.812689) (xy 429.062587 -282.849045) (xy 429.020991 -282.879266) (xy 428.975179 -282.902609)
			(xy 428.92628 -282.918497) (xy 428.875498 -282.92654) (xy 428.824082 -282.92654) (xy 428.7733 -282.918497)
			(xy 428.724401 -282.902609) (xy 428.678589 -282.879266) (xy 428.636993 -282.849045) (xy 428.600637 -282.812689)
			(xy 428.570416 -282.771093) (xy 428.547073 -282.725281) (xy 428.531185 -282.676382) (xy 428.523142 -282.6256)
			(xy 428.226478 -282.6256) (xy 428.218435 -282.676382) (xy 428.202547 -282.725281) (xy 428.179204 -282.771093)
			(xy 428.148983 -282.812689) (xy 428.112627 -282.849045) (xy 428.071031 -282.879266) (xy 428.025219 -282.902609)
			(xy 427.97632 -282.918497) (xy 427.925538 -282.92654) (xy 427.874122 -282.92654) (xy 427.82334 -282.918497)
			(xy 427.774441 -282.902609) (xy 427.728629 -282.879266) (xy 427.687033 -282.849045) (xy 427.650677 -282.812689)
			(xy 427.620456 -282.771093) (xy 427.597113 -282.725281) (xy 427.581225 -282.676382) (xy 427.573182 -282.6256)
			(xy 427.254504 -282.6256) (xy 427.246788 -282.673076) (xy 427.231204 -282.719757) (xy 427.208333 -282.763334)
			(xy 427.178768 -282.802678) (xy 427.143275 -282.83677) (xy 427.102772 -282.864726) (xy 427.05831 -282.885824)
			(xy 427.011039 -282.899516) (xy 426.962184 -282.905448) (xy 426.913009 -282.903467) (xy 426.86479 -282.893623)
			(xy 426.818774 -282.876171) (xy 426.776153 -282.851564) (xy 426.738032 -282.820439) (xy 426.705397 -282.783602)
			(xy 426.679094 -282.742006) (xy 426.659803 -282.69673) (xy 426.648026 -282.648946) (xy 426.644066 -282.599892)
			(xy 426.327062 -282.599892) (xy 426.326558 -282.6256) (xy 426.318515 -282.676382) (xy 426.302627 -282.725281)
			(xy 426.279284 -282.771093) (xy 426.249063 -282.812689) (xy 426.212707 -282.849045) (xy 426.171111 -282.879266)
			(xy 426.125299 -282.902609) (xy 426.0764 -282.918497) (xy 426.025618 -282.92654) (xy 425.974202 -282.92654)
			(xy 425.92342 -282.918497) (xy 425.874521 -282.902609) (xy 425.828709 -282.879266) (xy 425.787113 -282.849045)
			(xy 425.750757 -282.812689) (xy 425.720536 -282.771093) (xy 425.697193 -282.725281) (xy 425.681305 -282.676382)
			(xy 425.673262 -282.6256) (xy 425.376598 -282.6256) (xy 425.368555 -282.676382) (xy 425.352667 -282.725281)
			(xy 425.329324 -282.771093) (xy 425.299103 -282.812689) (xy 425.262747 -282.849045) (xy 425.221151 -282.879266)
			(xy 425.175339 -282.902609) (xy 425.12644 -282.918497) (xy 425.075658 -282.92654) (xy 425.024242 -282.92654)
			(xy 424.97346 -282.918497) (xy 424.924561 -282.902609) (xy 424.878749 -282.879266) (xy 424.837153 -282.849045)
			(xy 424.800797 -282.812689) (xy 424.770576 -282.771093) (xy 424.747233 -282.725281) (xy 424.731345 -282.676382)
			(xy 424.723302 -282.6256) (xy 424.404624 -282.6256) (xy 424.396908 -282.673076) (xy 424.381324 -282.719757)
			(xy 424.358453 -282.763334) (xy 424.328888 -282.802678) (xy 424.293395 -282.83677) (xy 424.252892 -282.864726)
			(xy 424.20843 -282.885824) (xy 424.161159 -282.899516) (xy 424.112304 -282.905448) (xy 424.063129 -282.903467)
			(xy 424.01491 -282.893623) (xy 423.968894 -282.876171) (xy 423.926273 -282.851564) (xy 423.888152 -282.820439)
			(xy 423.855517 -282.783602) (xy 423.829214 -282.742006) (xy 423.809923 -282.69673) (xy 423.798146 -282.648946)
			(xy 423.794186 -282.599892) (xy 423.455084 -282.599892) (xy 423.454589 -282.624499) (xy 423.446694 -282.673076)
			(xy 423.43111 -282.719757) (xy 423.408239 -282.763334) (xy 423.378674 -282.802678) (xy 423.343181 -282.83677)
			(xy 423.302678 -282.864726) (xy 423.258216 -282.885824) (xy 423.210945 -282.899516) (xy 423.16209 -282.905448)
			(xy 423.112915 -282.903467) (xy 423.064696 -282.893623) (xy 423.01868 -282.876171) (xy 422.976059 -282.851564)
			(xy 422.937938 -282.820439) (xy 422.905303 -282.783602) (xy 422.879 -282.742006) (xy 422.859709 -282.69673)
			(xy 422.847932 -282.648946) (xy 422.843972 -282.599892) (xy 403.505162 -282.599892) (xy 403.505162 -282.600146)
			(xy 403.504962 -282.614265) (xy 403.50229 -282.642376) (xy 403.499828 -282.65628) (xy 403.497542 -282.668726)
			(xy 403.500844 -282.679902) (xy 403.502554 -282.684986) (xy 403.507807 -282.694337) (xy 403.511258 -282.698444)
			(xy 403.513798 -282.701238) (xy 403.573488 -282.760928) (xy 403.576282 -282.763468) (xy 403.580403 -282.766897)
			(xy 403.589753 -282.772141) (xy 403.594824 -282.773882) (xy 403.606 -282.777184) (xy 403.618446 -282.774898)
			(xy 403.632411 -282.772415) (xy 403.660651 -282.769746) (xy 403.674834 -282.769564) (xy 403.699657 -282.770053)
			(xy 403.748648 -282.77809) (xy 403.795694 -282.793947) (xy 403.839554 -282.817207) (xy 403.879074 -282.847255)
			(xy 403.913211 -282.883302) (xy 403.941068 -282.924396) (xy 403.961909 -282.969456) (xy 403.975185 -283.017294)
			(xy 403.980548 -283.06665) (xy 403.980101 -283.074872) (xy 404.319244 -283.074872) (xy 404.323204 -283.025818)
			(xy 404.334981 -282.978034) (xy 404.354272 -282.932758) (xy 404.380575 -282.891162) (xy 404.41321 -282.854325)
			(xy 404.451331 -282.8232) (xy 404.493952 -282.798593) (xy 404.539968 -282.781141) (xy 404.588187 -282.771297)
			(xy 404.637362 -282.769316) (xy 404.686217 -282.775248) (xy 404.733488 -282.78894) (xy 404.77795 -282.810038)
			(xy 404.818453 -282.837994) (xy 404.853946 -282.872086) (xy 404.883511 -282.91143) (xy 404.906382 -282.955007)
			(xy 404.921966 -283.001688) (xy 404.929861 -283.050265) (xy 404.930356 -283.074872) (xy 405.269204 -283.074872)
			(xy 405.273164 -283.025818) (xy 405.284941 -282.978034) (xy 405.304232 -282.932758) (xy 405.330535 -282.891162)
			(xy 405.36317 -282.854325) (xy 405.401291 -282.8232) (xy 405.443912 -282.798593) (xy 405.489928 -282.781141)
			(xy 405.538147 -282.771297) (xy 405.587322 -282.769316) (xy 405.636177 -282.775248) (xy 405.683448 -282.78894)
			(xy 405.72791 -282.810038) (xy 405.768413 -282.837994) (xy 405.803906 -282.872086) (xy 405.833471 -282.91143)
			(xy 405.856342 -282.955007) (xy 405.871926 -283.001688) (xy 405.879821 -283.050265) (xy 405.880316 -283.074872)
			(xy 406.219164 -283.074872) (xy 406.223124 -283.025818) (xy 406.234901 -282.978034) (xy 406.254192 -282.932758)
			(xy 406.280495 -282.891162) (xy 406.31313 -282.854325) (xy 406.351251 -282.8232) (xy 406.393872 -282.798593)
			(xy 406.439888 -282.781141) (xy 406.488107 -282.771297) (xy 406.537282 -282.769316) (xy 406.586137 -282.775248)
			(xy 406.633408 -282.78894) (xy 406.67787 -282.810038) (xy 406.718373 -282.837994) (xy 406.753866 -282.872086)
			(xy 406.783431 -282.91143) (xy 406.806302 -282.955007) (xy 406.821886 -283.001688) (xy 406.829781 -283.050265)
			(xy 406.830276 -283.074872) (xy 408.119084 -283.074872) (xy 408.123044 -283.025818) (xy 408.134821 -282.978034)
			(xy 408.154112 -282.932758) (xy 408.180415 -282.891162) (xy 408.21305 -282.854325) (xy 408.251171 -282.8232)
			(xy 408.293792 -282.798593) (xy 408.339808 -282.781141) (xy 408.388027 -282.771297) (xy 408.437202 -282.769316)
			(xy 408.486057 -282.775248) (xy 408.533328 -282.78894) (xy 408.57779 -282.810038) (xy 408.618293 -282.837994)
			(xy 408.653786 -282.872086) (xy 408.683351 -282.91143) (xy 408.706222 -282.955007) (xy 408.721806 -283.001688)
			(xy 408.729701 -283.050265) (xy 408.730196 -283.074872) (xy 409.069044 -283.074872) (xy 409.073004 -283.025818)
			(xy 409.084781 -282.978034) (xy 409.104072 -282.932758) (xy 409.130375 -282.891162) (xy 409.16301 -282.854325)
			(xy 409.201131 -282.8232) (xy 409.243752 -282.798593) (xy 409.289768 -282.781141) (xy 409.337987 -282.771297)
			(xy 409.387162 -282.769316) (xy 409.436017 -282.775248) (xy 409.483288 -282.78894) (xy 409.52775 -282.810038)
			(xy 409.568253 -282.837994) (xy 409.603746 -282.872086) (xy 409.633311 -282.91143) (xy 409.656182 -282.955007)
			(xy 409.671766 -283.001688) (xy 409.679661 -283.050265) (xy 409.680156 -283.074872) (xy 410.019004 -283.074872)
			(xy 410.022964 -283.025818) (xy 410.034741 -282.978034) (xy 410.054032 -282.932758) (xy 410.080335 -282.891162)
			(xy 410.11297 -282.854325) (xy 410.151091 -282.8232) (xy 410.193712 -282.798593) (xy 410.239728 -282.781141)
			(xy 410.287947 -282.771297) (xy 410.337122 -282.769316) (xy 410.385977 -282.775248) (xy 410.433248 -282.78894)
			(xy 410.47771 -282.810038) (xy 410.518213 -282.837994) (xy 410.553706 -282.872086) (xy 410.583271 -282.91143)
			(xy 410.606142 -282.955007) (xy 410.621726 -283.001688) (xy 410.629621 -283.050265) (xy 410.630116 -283.074872)
			(xy 410.969218 -283.074872) (xy 410.973178 -283.025818) (xy 410.984955 -282.978034) (xy 411.004246 -282.932758)
			(xy 411.030549 -282.891162) (xy 411.063184 -282.854325) (xy 411.101305 -282.8232) (xy 411.143926 -282.798593)
			(xy 411.189942 -282.781141) (xy 411.238161 -282.771297) (xy 411.287336 -282.769316) (xy 411.336191 -282.775248)
			(xy 411.383462 -282.78894) (xy 411.427924 -282.810038) (xy 411.468427 -282.837994) (xy 411.50392 -282.872086)
			(xy 411.533485 -282.91143) (xy 411.556356 -282.955007) (xy 411.57194 -283.001688) (xy 411.579835 -283.050265)
			(xy 411.58033 -283.074872) (xy 411.919178 -283.074872) (xy 411.923138 -283.025818) (xy 411.934915 -282.978034)
			(xy 411.954206 -282.932758) (xy 411.980509 -282.891162) (xy 412.013144 -282.854325) (xy 412.051265 -282.8232)
			(xy 412.093886 -282.798593) (xy 412.139902 -282.781141) (xy 412.188121 -282.771297) (xy 412.237296 -282.769316)
			(xy 412.286151 -282.775248) (xy 412.333422 -282.78894) (xy 412.377884 -282.810038) (xy 412.418387 -282.837994)
			(xy 412.45388 -282.872086) (xy 412.483445 -282.91143) (xy 412.506316 -282.955007) (xy 412.5219 -283.001688)
			(xy 412.529795 -283.050265) (xy 412.53029 -283.074872) (xy 412.869138 -283.074872) (xy 412.873098 -283.025818)
			(xy 412.884875 -282.978034) (xy 412.904166 -282.932758) (xy 412.930469 -282.891162) (xy 412.963104 -282.854325)
			(xy 413.001225 -282.8232) (xy 413.043846 -282.798593) (xy 413.089862 -282.781141) (xy 413.138081 -282.771297)
			(xy 413.187256 -282.769316) (xy 413.236111 -282.775248) (xy 413.283382 -282.78894) (xy 413.327844 -282.810038)
			(xy 413.368347 -282.837994) (xy 413.40384 -282.872086) (xy 413.433405 -282.91143) (xy 413.456276 -282.955007)
			(xy 413.47186 -283.001688) (xy 413.479755 -283.050265) (xy 413.48025 -283.074872) (xy 413.819098 -283.074872)
			(xy 413.823058 -283.025818) (xy 413.834835 -282.978034) (xy 413.854126 -282.932758) (xy 413.880429 -282.891162)
			(xy 413.913064 -282.854325) (xy 413.951185 -282.8232) (xy 413.993806 -282.798593) (xy 414.039822 -282.781141)
			(xy 414.088041 -282.771297) (xy 414.137216 -282.769316) (xy 414.186071 -282.775248) (xy 414.233342 -282.78894)
			(xy 414.277804 -282.810038) (xy 414.318307 -282.837994) (xy 414.3538 -282.872086) (xy 414.383365 -282.91143)
			(xy 414.406236 -282.955007) (xy 414.42182 -283.001688) (xy 414.429715 -283.050265) (xy 414.43021 -283.074872)
			(xy 414.769058 -283.074872) (xy 414.773018 -283.025818) (xy 414.784795 -282.978034) (xy 414.804086 -282.932758)
			(xy 414.830389 -282.891162) (xy 414.863024 -282.854325) (xy 414.901145 -282.8232) (xy 414.943766 -282.798593)
			(xy 414.989782 -282.781141) (xy 415.038001 -282.771297) (xy 415.087176 -282.769316) (xy 415.136031 -282.775248)
			(xy 415.183302 -282.78894) (xy 415.227764 -282.810038) (xy 415.268267 -282.837994) (xy 415.30376 -282.872086)
			(xy 415.333325 -282.91143) (xy 415.356196 -282.955007) (xy 415.37178 -283.001688) (xy 415.379675 -283.050265)
			(xy 415.38017 -283.074872) (xy 415.719018 -283.074872) (xy 415.722978 -283.025818) (xy 415.734755 -282.978034)
			(xy 415.754046 -282.932758) (xy 415.780349 -282.891162) (xy 415.812984 -282.854325) (xy 415.851105 -282.8232)
			(xy 415.893726 -282.798593) (xy 415.939742 -282.781141) (xy 415.987961 -282.771297) (xy 416.037136 -282.769316)
			(xy 416.085991 -282.775248) (xy 416.133262 -282.78894) (xy 416.177724 -282.810038) (xy 416.218227 -282.837994)
			(xy 416.25372 -282.872086) (xy 416.283285 -282.91143) (xy 416.306156 -282.955007) (xy 416.32174 -283.001688)
			(xy 416.329635 -283.050265) (xy 416.33013 -283.074872) (xy 416.668978 -283.074872) (xy 416.672938 -283.025818)
			(xy 416.684715 -282.978034) (xy 416.704006 -282.932758) (xy 416.730309 -282.891162) (xy 416.762944 -282.854325)
			(xy 416.801065 -282.8232) (xy 416.843686 -282.798593) (xy 416.889702 -282.781141) (xy 416.937921 -282.771297)
			(xy 416.987096 -282.769316) (xy 417.035951 -282.775248) (xy 417.083222 -282.78894) (xy 417.127684 -282.810038)
			(xy 417.168187 -282.837994) (xy 417.20368 -282.872086) (xy 417.233245 -282.91143) (xy 417.256116 -282.955007)
			(xy 417.2717 -283.001688) (xy 417.279595 -283.050265) (xy 417.28009 -283.074872) (xy 417.619192 -283.074872)
			(xy 417.623152 -283.025818) (xy 417.634929 -282.978034) (xy 417.65422 -282.932758) (xy 417.680523 -282.891162)
			(xy 417.713158 -282.854325) (xy 417.751279 -282.8232) (xy 417.7939 -282.798593) (xy 417.839916 -282.781141)
			(xy 417.888135 -282.771297) (xy 417.93731 -282.769316) (xy 417.986165 -282.775248) (xy 418.033436 -282.78894)
			(xy 418.077898 -282.810038) (xy 418.118401 -282.837994) (xy 418.153894 -282.872086) (xy 418.183459 -282.91143)
			(xy 418.20633 -282.955007) (xy 418.221914 -283.001688) (xy 418.229809 -283.050265) (xy 418.230304 -283.074872)
			(xy 418.569152 -283.074872) (xy 418.573112 -283.025818) (xy 418.584889 -282.978034) (xy 418.60418 -282.932758)
			(xy 418.630483 -282.891162) (xy 418.663118 -282.854325) (xy 418.701239 -282.8232) (xy 418.74386 -282.798593)
			(xy 418.789876 -282.781141) (xy 418.838095 -282.771297) (xy 418.88727 -282.769316) (xy 418.936125 -282.775248)
			(xy 418.983396 -282.78894) (xy 419.027858 -282.810038) (xy 419.068361 -282.837994) (xy 419.103854 -282.872086)
			(xy 419.133419 -282.91143) (xy 419.15629 -282.955007) (xy 419.171874 -283.001688) (xy 419.179769 -283.050265)
			(xy 419.180264 -283.074872) (xy 419.519112 -283.074872) (xy 419.523072 -283.025818) (xy 419.534849 -282.978034)
			(xy 419.55414 -282.932758) (xy 419.580443 -282.891162) (xy 419.613078 -282.854325) (xy 419.651199 -282.8232)
			(xy 419.69382 -282.798593) (xy 419.739836 -282.781141) (xy 419.788055 -282.771297) (xy 419.83723 -282.769316)
			(xy 419.886085 -282.775248) (xy 419.933356 -282.78894) (xy 419.977818 -282.810038) (xy 420.018321 -282.837994)
			(xy 420.053814 -282.872086) (xy 420.083379 -282.91143) (xy 420.10625 -282.955007) (xy 420.121834 -283.001688)
			(xy 420.129729 -283.050265) (xy 420.130224 -283.074872) (xy 420.469072 -283.074872) (xy 420.473032 -283.025818)
			(xy 420.484809 -282.978034) (xy 420.5041 -282.932758) (xy 420.530403 -282.891162) (xy 420.563038 -282.854325)
			(xy 420.601159 -282.8232) (xy 420.64378 -282.798593) (xy 420.689796 -282.781141) (xy 420.738015 -282.771297)
			(xy 420.78719 -282.769316) (xy 420.836045 -282.775248) (xy 420.883316 -282.78894) (xy 420.927778 -282.810038)
			(xy 420.968281 -282.837994) (xy 421.003774 -282.872086) (xy 421.033339 -282.91143) (xy 421.05621 -282.955007)
			(xy 421.071794 -283.001688) (xy 421.079689 -283.050265) (xy 421.080184 -283.074872) (xy 421.079689 -283.099479)
			(xy 421.074265 -283.132854) (xy 456.388661 -283.132854) (xy 456.388661 -283.078346) (xy 456.396419 -283.024394)
			(xy 456.411776 -282.972095) (xy 456.43442 -282.922514) (xy 456.46389 -282.876661) (xy 456.499585 -282.835468)
			(xy 456.54078 -282.799775) (xy 456.586636 -282.770308) (xy 456.636218 -282.747667) (xy 456.688518 -282.732314)
			(xy 456.74247 -282.72456) (xy 456.769724 -282.724098) (xy 456.798463 -282.724608) (xy 456.855291 -282.733234)
			(xy 456.910182 -282.750287) (xy 456.961894 -282.775382) (xy 457.009256 -282.80795) (xy 457.030582 -282.827222)
			(xy 457.037694 -282.833826) (xy 457.046076 -282.837128) (xy 457.050644 -282.838879) (xy 457.060236 -282.840799)
			(xy 457.065126 -282.840938) (xy 457.134722 -282.840938) (xy 457.139612 -282.84079) (xy 457.149204 -282.838879)
			(xy 457.153772 -282.837128) (xy 457.162154 -282.833826) (xy 457.169266 -282.827222) (xy 457.190593 -282.807952)
			(xy 457.237956 -282.775387) (xy 457.289667 -282.750296) (xy 457.344558 -282.733246) (xy 457.401385 -282.724624)
			(xy 457.458863 -282.724624) (xy 457.51569 -282.733246) (xy 457.570581 -282.750296) (xy 457.622292 -282.775387)
			(xy 457.669655 -282.807952) (xy 457.690982 -282.827222) (xy 457.698094 -282.833826) (xy 457.706476 -282.837128)
			(xy 457.711044 -282.838879) (xy 457.720636 -282.840799) (xy 457.725526 -282.840938) (xy 457.795122 -282.840938)
			(xy 457.800012 -282.84079) (xy 457.809604 -282.838879) (xy 457.814172 -282.837128) (xy 457.822554 -282.833826)
			(xy 457.829666 -282.827222) (xy 457.850981 -282.807937) (xy 457.898346 -282.775373) (xy 457.950061 -282.750284)
			(xy 458.004955 -282.733237) (xy 458.061784 -282.724617) (xy 458.090524 -282.724098) (xy 458.120649 -282.724639)
			(xy 458.180147 -282.734126) (xy 458.237416 -282.752843) (xy 458.291033 -282.780325) (xy 458.339665 -282.815891)
			(xy 458.361288 -282.836874) (xy 458.3684 -282.84424) (xy 458.378052 -282.84805) (xy 458.382624 -282.849791)
			(xy 458.392212 -282.851719) (xy 458.397102 -282.85186) (xy 458.469746 -282.85186) (xy 458.474637 -282.851724)
			(xy 458.484229 -282.849805) (xy 458.488796 -282.84805) (xy 458.498448 -282.84424) (xy 458.50556 -282.836874)
			(xy 458.527192 -282.815901) (xy 458.575817 -282.780329) (xy 458.629432 -282.752846) (xy 458.686701 -282.734137)
			(xy 458.7462 -282.724666) (xy 458.776324 -282.724098) (xy 458.803575 -282.724573) (xy 458.857521 -282.732333)
			(xy 458.909813 -282.74769) (xy 458.959388 -282.770333) (xy 459.005236 -282.799801) (xy 459.046424 -282.835493)
			(xy 459.082114 -282.876683) (xy 459.111578 -282.922533) (xy 459.134218 -282.972109) (xy 459.149572 -283.024403)
			(xy 459.157328 -283.078349) (xy 459.157328 -283.132851) (xy 459.157328 -283.132853) (xy 460.636061 -283.132853)
			(xy 460.636061 -283.078347) (xy 460.643819 -283.024396) (xy 460.659175 -282.972098) (xy 460.681818 -282.922518)
			(xy 460.711287 -282.876665) (xy 460.746981 -282.835472) (xy 460.788174 -282.799779) (xy 460.834028 -282.770312)
			(xy 460.883609 -282.747671) (xy 460.935908 -282.732316) (xy 460.989859 -282.724561) (xy 461.017112 -282.724098)
			(xy 461.045851 -282.724615) (xy 461.102679 -282.733239) (xy 461.15757 -282.750291) (xy 461.209281 -282.775384)
			(xy 461.256643 -282.807951) (xy 461.27797 -282.827222) (xy 461.285082 -282.833826) (xy 461.293464 -282.837128)
			(xy 461.298033 -282.838876) (xy 461.307624 -282.840798) (xy 461.312514 -282.840938) (xy 461.38211 -282.840938)
			(xy 461.387 -282.840786) (xy 461.396592 -282.838877) (xy 461.40116 -282.837128) (xy 461.409542 -282.833826)
			(xy 461.416654 -282.827222) (xy 461.437981 -282.807952) (xy 461.485344 -282.775387) (xy 461.537055 -282.750296)
			(xy 461.591946 -282.733246) (xy 461.648773 -282.724624) (xy 461.706251 -282.724624) (xy 461.763078 -282.733246)
			(xy 461.817969 -282.750296) (xy 461.86968 -282.775387) (xy 461.917043 -282.807952) (xy 461.93837 -282.827222)
			(xy 461.945482 -282.833826) (xy 461.953864 -282.837128) (xy 461.958433 -282.838876) (xy 461.968024 -282.840798)
			(xy 461.972914 -282.840938) (xy 462.04251 -282.840938) (xy 462.0474 -282.840786) (xy 462.056992 -282.838877)
			(xy 462.06156 -282.837128) (xy 462.069942 -282.833826) (xy 462.077054 -282.827222) (xy 462.098374 -282.807943)
			(xy 462.145738 -282.775378) (xy 462.197452 -282.750288) (xy 462.252344 -282.733239) (xy 462.309173 -282.724618)
			(xy 462.337912 -282.724098) (xy 462.368036 -282.724647) (xy 462.427534 -282.734131) (xy 462.484803 -282.752846)
			(xy 462.53842 -282.780328) (xy 462.587053 -282.815892) (xy 462.608676 -282.836874) (xy 462.615788 -282.84424)
			(xy 462.62544 -282.84805) (xy 462.630004 -282.849815) (xy 462.639599 -282.851727) (xy 462.64449 -282.85186)
			(xy 462.717134 -282.85186) (xy 462.722024 -282.85172) (xy 462.731617 -282.849804) (xy 462.736184 -282.84805)
			(xy 462.745836 -282.84424) (xy 462.752948 -282.836874) (xy 462.774585 -282.815907) (xy 462.823209 -282.780334)
			(xy 462.876822 -282.75285) (xy 462.93409 -282.734139) (xy 462.993588 -282.724667) (xy 463.023712 -282.724098)
			(xy 463.050963 -282.724573) (xy 463.10491 -282.732331) (xy 463.157205 -282.747687) (xy 463.206781 -282.770329)
			(xy 463.252631 -282.799796) (xy 463.29382 -282.835488) (xy 463.329511 -282.876679) (xy 463.358977 -282.92253)
			(xy 463.381617 -282.972107) (xy 463.396972 -283.024401) (xy 463.404728 -283.078349) (xy 463.404728 -283.132851)
			(xy 463.396972 -283.186799) (xy 463.381617 -283.239093) (xy 463.358977 -283.28867) (xy 463.329511 -283.334521)
			(xy 463.29382 -283.375712) (xy 463.252631 -283.411404) (xy 463.206781 -283.440871) (xy 463.157205 -283.463513)
			(xy 463.10491 -283.478869) (xy 463.050963 -283.486627) (xy 463.023712 -283.487114) (xy 462.993588 -283.486546)
			(xy 462.934091 -283.477066) (xy 462.876823 -283.458355) (xy 462.823206 -283.430878) (xy 462.774572 -283.395318)
			(xy 462.752948 -283.374338) (xy 462.745836 -283.366972) (xy 462.736184 -283.363162) (xy 462.73162 -283.3614)
			(xy 462.722025 -283.359487) (xy 462.717134 -283.359352) (xy 462.64449 -283.359352) (xy 462.6396 -283.359504)
			(xy 462.630008 -283.361413) (xy 462.62544 -283.363162) (xy 462.615788 -283.366972) (xy 462.608676 -283.374338)
			(xy 462.58703 -283.395296) (xy 462.538408 -283.43087) (xy 462.484797 -283.458355) (xy 462.427531 -283.477068)
			(xy 462.368035 -283.486544) (xy 462.337912 -283.487114) (xy 462.309174 -283.486579) (xy 462.252347 -283.477959)
			(xy 462.197456 -283.460911) (xy 462.145744 -283.435822) (xy 462.098381 -283.403259) (xy 462.077054 -283.38399)
			(xy 462.069942 -283.377386) (xy 462.06156 -283.374084) (xy 462.056997 -283.372316) (xy 462.047402 -283.370407)
			(xy 462.04251 -283.370274) (xy 461.972914 -283.370274) (xy 461.968023 -283.370404) (xy 461.958431 -283.372327)
			(xy 461.953864 -283.374084) (xy 461.945482 -283.377386) (xy 461.93837 -283.38399) (xy 461.917043 -283.40326)
			(xy 461.86968 -283.435825) (xy 461.817969 -283.460916) (xy 461.763078 -283.477966) (xy 461.706251 -283.486588)
			(xy 461.648773 -283.486588) (xy 461.591946 -283.477966) (xy 461.537055 -283.460916) (xy 461.485344 -283.435825)
			(xy 461.437981 -283.40326) (xy 461.416654 -283.38399) (xy 461.409542 -283.377386) (xy 461.40116 -283.374084)
			(xy 461.396597 -283.372316) (xy 461.387002 -283.370407) (xy 461.38211 -283.370274) (xy 461.312514 -283.370274)
			(xy 461.307623 -283.370404) (xy 461.298031 -283.372327) (xy 461.293464 -283.374084) (xy 461.285082 -283.377386)
			(xy 461.27797 -283.38399) (xy 461.256642 -283.40326) (xy 461.20928 -283.435825) (xy 461.157568 -283.460917)
			(xy 461.102678 -283.477968) (xy 461.045851 -283.486592) (xy 461.017112 -283.487114) (xy 460.989859 -283.486639)
			(xy 460.935908 -283.478884) (xy 460.883609 -283.463529) (xy 460.834028 -283.440888) (xy 460.788174 -283.411421)
			(xy 460.746981 -283.375728) (xy 460.711287 -283.334535) (xy 460.681818 -283.288682) (xy 460.659175 -283.239102)
			(xy 460.643819 -283.186804) (xy 460.636061 -283.132853) (xy 459.157328 -283.132853) (xy 459.149572 -283.186797)
			(xy 459.134218 -283.239091) (xy 459.111578 -283.288667) (xy 459.082114 -283.334517) (xy 459.046424 -283.375707)
			(xy 459.005236 -283.411399) (xy 458.959388 -283.440867) (xy 458.909813 -283.46351) (xy 458.857521 -283.478867)
			(xy 458.803575 -283.486627) (xy 458.776324 -283.487114) (xy 458.746201 -283.486538) (xy 458.686704 -283.47706)
			(xy 458.629436 -283.458351) (xy 458.575819 -283.430876) (xy 458.527185 -283.395317) (xy 458.50556 -283.374338)
			(xy 458.498448 -283.366972) (xy 458.488796 -283.363162) (xy 458.48423 -283.361403) (xy 458.474637 -283.359488)
			(xy 458.469746 -283.359352) (xy 458.397102 -283.359352) (xy 458.392211 -283.35948) (xy 458.382619 -283.361405)
			(xy 458.378052 -283.363162) (xy 458.3684 -283.366972) (xy 458.361288 -283.374338) (xy 458.339681 -283.395338)
			(xy 458.291049 -283.430906) (xy 458.237428 -283.458384) (xy 458.180153 -283.477087) (xy 458.12065 -283.486551)
			(xy 458.090524 -283.487114) (xy 458.061786 -283.486572) (xy 458.004959 -283.477953) (xy 457.950069 -283.460907)
			(xy 457.898357 -283.43582) (xy 457.850994 -283.403259) (xy 457.829666 -283.38399) (xy 457.822554 -283.377386)
			(xy 457.814172 -283.374084) (xy 457.809608 -283.37232) (xy 457.800013 -283.370408) (xy 457.795122 -283.370274)
			(xy 457.725526 -283.370274) (xy 457.720635 -283.370407) (xy 457.711043 -283.372328) (xy 457.706476 -283.374084)
			(xy 457.698094 -283.377386) (xy 457.690982 -283.38399) (xy 457.669655 -283.40326) (xy 457.622292 -283.435825)
			(xy 457.570581 -283.460916) (xy 457.51569 -283.477966) (xy 457.458863 -283.486588) (xy 457.401385 -283.486588)
			(xy 457.344558 -283.477966) (xy 457.289667 -283.460916) (xy 457.237956 -283.435825) (xy 457.190593 -283.40326)
			(xy 457.169266 -283.38399) (xy 457.162154 -283.377386) (xy 457.153772 -283.374084) (xy 457.149208 -283.37232)
			(xy 457.139613 -283.370408) (xy 457.134722 -283.370274) (xy 457.065126 -283.370274) (xy 457.060235 -283.370407)
			(xy 457.050643 -283.372328) (xy 457.046076 -283.374084) (xy 457.037694 -283.377386) (xy 457.030582 -283.38399)
			(xy 457.009249 -283.403254) (xy 456.961888 -283.43582) (xy 456.910178 -283.460913) (xy 456.855289 -283.477966)
			(xy 456.798463 -283.486591) (xy 456.769724 -283.487114) (xy 456.74247 -283.48664) (xy 456.688518 -283.478886)
			(xy 456.636218 -283.463533) (xy 456.586636 -283.440892) (xy 456.54078 -283.411425) (xy 456.499585 -283.375732)
			(xy 456.46389 -283.334539) (xy 456.43442 -283.288686) (xy 456.411776 -283.239105) (xy 456.396419 -283.186806)
			(xy 456.388661 -283.132854) (xy 421.074265 -283.132854) (xy 421.071794 -283.148056) (xy 421.05621 -283.194737)
			(xy 421.033339 -283.238314) (xy 421.003774 -283.277658) (xy 420.968281 -283.31175) (xy 420.927778 -283.339706)
			(xy 420.883316 -283.360804) (xy 420.836045 -283.374496) (xy 420.78719 -283.380428) (xy 420.738015 -283.378447)
			(xy 420.689796 -283.368603) (xy 420.64378 -283.351151) (xy 420.601159 -283.326544) (xy 420.563038 -283.295419)
			(xy 420.530403 -283.258582) (xy 420.5041 -283.216986) (xy 420.484809 -283.17171) (xy 420.473032 -283.123926)
			(xy 420.469072 -283.074872) (xy 420.130224 -283.074872) (xy 420.129729 -283.099479) (xy 420.121834 -283.148056)
			(xy 420.10625 -283.194737) (xy 420.083379 -283.238314) (xy 420.053814 -283.277658) (xy 420.018321 -283.31175)
			(xy 419.977818 -283.339706) (xy 419.933356 -283.360804) (xy 419.886085 -283.374496) (xy 419.83723 -283.380428)
			(xy 419.788055 -283.378447) (xy 419.739836 -283.368603) (xy 419.69382 -283.351151) (xy 419.651199 -283.326544)
			(xy 419.613078 -283.295419) (xy 419.580443 -283.258582) (xy 419.55414 -283.216986) (xy 419.534849 -283.17171)
			(xy 419.523072 -283.123926) (xy 419.519112 -283.074872) (xy 419.180264 -283.074872) (xy 419.179769 -283.099479)
			(xy 419.171874 -283.148056) (xy 419.15629 -283.194737) (xy 419.133419 -283.238314) (xy 419.103854 -283.277658)
			(xy 419.068361 -283.31175) (xy 419.027858 -283.339706) (xy 418.983396 -283.360804) (xy 418.936125 -283.374496)
			(xy 418.88727 -283.380428) (xy 418.838095 -283.378447) (xy 418.789876 -283.368603) (xy 418.74386 -283.351151)
			(xy 418.701239 -283.326544) (xy 418.663118 -283.295419) (xy 418.630483 -283.258582) (xy 418.60418 -283.216986)
			(xy 418.584889 -283.17171) (xy 418.573112 -283.123926) (xy 418.569152 -283.074872) (xy 418.230304 -283.074872)
			(xy 418.229809 -283.099479) (xy 418.221914 -283.148056) (xy 418.20633 -283.194737) (xy 418.183459 -283.238314)
			(xy 418.153894 -283.277658) (xy 418.118401 -283.31175) (xy 418.077898 -283.339706) (xy 418.033436 -283.360804)
			(xy 417.986165 -283.374496) (xy 417.93731 -283.380428) (xy 417.888135 -283.378447) (xy 417.839916 -283.368603)
			(xy 417.7939 -283.351151) (xy 417.751279 -283.326544) (xy 417.713158 -283.295419) (xy 417.680523 -283.258582)
			(xy 417.65422 -283.216986) (xy 417.634929 -283.17171) (xy 417.623152 -283.123926) (xy 417.619192 -283.074872)
			(xy 417.28009 -283.074872) (xy 417.279595 -283.099479) (xy 417.2717 -283.148056) (xy 417.256116 -283.194737)
			(xy 417.233245 -283.238314) (xy 417.20368 -283.277658) (xy 417.168187 -283.31175) (xy 417.127684 -283.339706)
			(xy 417.083222 -283.360804) (xy 417.035951 -283.374496) (xy 416.987096 -283.380428) (xy 416.937921 -283.378447)
			(xy 416.889702 -283.368603) (xy 416.843686 -283.351151) (xy 416.801065 -283.326544) (xy 416.762944 -283.295419)
			(xy 416.730309 -283.258582) (xy 416.704006 -283.216986) (xy 416.684715 -283.17171) (xy 416.672938 -283.123926)
			(xy 416.668978 -283.074872) (xy 416.33013 -283.074872) (xy 416.329635 -283.099479) (xy 416.32174 -283.148056)
			(xy 416.306156 -283.194737) (xy 416.283285 -283.238314) (xy 416.25372 -283.277658) (xy 416.218227 -283.31175)
			(xy 416.177724 -283.339706) (xy 416.133262 -283.360804) (xy 416.085991 -283.374496) (xy 416.037136 -283.380428)
			(xy 415.987961 -283.378447) (xy 415.939742 -283.368603) (xy 415.893726 -283.351151) (xy 415.851105 -283.326544)
			(xy 415.812984 -283.295419) (xy 415.780349 -283.258582) (xy 415.754046 -283.216986) (xy 415.734755 -283.17171)
			(xy 415.722978 -283.123926) (xy 415.719018 -283.074872) (xy 415.38017 -283.074872) (xy 415.379675 -283.099479)
			(xy 415.37178 -283.148056) (xy 415.356196 -283.194737) (xy 415.333325 -283.238314) (xy 415.30376 -283.277658)
			(xy 415.268267 -283.31175) (xy 415.227764 -283.339706) (xy 415.183302 -283.360804) (xy 415.136031 -283.374496)
			(xy 415.087176 -283.380428) (xy 415.038001 -283.378447) (xy 414.989782 -283.368603) (xy 414.943766 -283.351151)
			(xy 414.901145 -283.326544) (xy 414.863024 -283.295419) (xy 414.830389 -283.258582) (xy 414.804086 -283.216986)
			(xy 414.784795 -283.17171) (xy 414.773018 -283.123926) (xy 414.769058 -283.074872) (xy 414.43021 -283.074872)
			(xy 414.429715 -283.099479) (xy 414.42182 -283.148056) (xy 414.406236 -283.194737) (xy 414.383365 -283.238314)
			(xy 414.3538 -283.277658) (xy 414.318307 -283.31175) (xy 414.277804 -283.339706) (xy 414.233342 -283.360804)
			(xy 414.186071 -283.374496) (xy 414.137216 -283.380428) (xy 414.088041 -283.378447) (xy 414.039822 -283.368603)
			(xy 413.993806 -283.351151) (xy 413.951185 -283.326544) (xy 413.913064 -283.295419) (xy 413.880429 -283.258582)
			(xy 413.854126 -283.216986) (xy 413.834835 -283.17171) (xy 413.823058 -283.123926) (xy 413.819098 -283.074872)
			(xy 413.48025 -283.074872) (xy 413.479755 -283.099479) (xy 413.47186 -283.148056) (xy 413.456276 -283.194737)
			(xy 413.433405 -283.238314) (xy 413.40384 -283.277658) (xy 413.368347 -283.31175) (xy 413.327844 -283.339706)
			(xy 413.283382 -283.360804) (xy 413.236111 -283.374496) (xy 413.187256 -283.380428) (xy 413.138081 -283.378447)
			(xy 413.089862 -283.368603) (xy 413.043846 -283.351151) (xy 413.001225 -283.326544) (xy 412.963104 -283.295419)
			(xy 412.930469 -283.258582) (xy 412.904166 -283.216986) (xy 412.884875 -283.17171) (xy 412.873098 -283.123926)
			(xy 412.869138 -283.074872) (xy 412.53029 -283.074872) (xy 412.529795 -283.099479) (xy 412.5219 -283.148056)
			(xy 412.506316 -283.194737) (xy 412.483445 -283.238314) (xy 412.45388 -283.277658) (xy 412.418387 -283.31175)
			(xy 412.377884 -283.339706) (xy 412.333422 -283.360804) (xy 412.286151 -283.374496) (xy 412.237296 -283.380428)
			(xy 412.188121 -283.378447) (xy 412.139902 -283.368603) (xy 412.093886 -283.351151) (xy 412.051265 -283.326544)
			(xy 412.013144 -283.295419) (xy 411.980509 -283.258582) (xy 411.954206 -283.216986) (xy 411.934915 -283.17171)
			(xy 411.923138 -283.123926) (xy 411.919178 -283.074872) (xy 411.58033 -283.074872) (xy 411.579835 -283.099479)
			(xy 411.57194 -283.148056) (xy 411.556356 -283.194737) (xy 411.533485 -283.238314) (xy 411.50392 -283.277658)
			(xy 411.468427 -283.31175) (xy 411.427924 -283.339706) (xy 411.383462 -283.360804) (xy 411.336191 -283.374496)
			(xy 411.287336 -283.380428) (xy 411.238161 -283.378447) (xy 411.189942 -283.368603) (xy 411.143926 -283.351151)
			(xy 411.101305 -283.326544) (xy 411.063184 -283.295419) (xy 411.030549 -283.258582) (xy 411.004246 -283.216986)
			(xy 410.984955 -283.17171) (xy 410.973178 -283.123926) (xy 410.969218 -283.074872) (xy 410.630116 -283.074872)
			(xy 410.629621 -283.099479) (xy 410.621726 -283.148056) (xy 410.606142 -283.194737) (xy 410.583271 -283.238314)
			(xy 410.553706 -283.277658) (xy 410.518213 -283.31175) (xy 410.47771 -283.339706) (xy 410.433248 -283.360804)
			(xy 410.385977 -283.374496) (xy 410.337122 -283.380428) (xy 410.287947 -283.378447) (xy 410.239728 -283.368603)
			(xy 410.193712 -283.351151) (xy 410.151091 -283.326544) (xy 410.11297 -283.295419) (xy 410.080335 -283.258582)
			(xy 410.054032 -283.216986) (xy 410.034741 -283.17171) (xy 410.022964 -283.123926) (xy 410.019004 -283.074872)
			(xy 409.680156 -283.074872) (xy 409.679661 -283.099479) (xy 409.671766 -283.148056) (xy 409.656182 -283.194737)
			(xy 409.633311 -283.238314) (xy 409.603746 -283.277658) (xy 409.568253 -283.31175) (xy 409.52775 -283.339706)
			(xy 409.483288 -283.360804) (xy 409.436017 -283.374496) (xy 409.387162 -283.380428) (xy 409.337987 -283.378447)
			(xy 409.289768 -283.368603) (xy 409.243752 -283.351151) (xy 409.201131 -283.326544) (xy 409.16301 -283.295419)
			(xy 409.130375 -283.258582) (xy 409.104072 -283.216986) (xy 409.084781 -283.17171) (xy 409.073004 -283.123926)
			(xy 409.069044 -283.074872) (xy 408.730196 -283.074872) (xy 408.729701 -283.099479) (xy 408.721806 -283.148056)
			(xy 408.706222 -283.194737) (xy 408.683351 -283.238314) (xy 408.653786 -283.277658) (xy 408.618293 -283.31175)
			(xy 408.57779 -283.339706) (xy 408.533328 -283.360804) (xy 408.486057 -283.374496) (xy 408.437202 -283.380428)
			(xy 408.388027 -283.378447) (xy 408.339808 -283.368603) (xy 408.293792 -283.351151) (xy 408.251171 -283.326544)
			(xy 408.21305 -283.295419) (xy 408.180415 -283.258582) (xy 408.154112 -283.216986) (xy 408.134821 -283.17171)
			(xy 408.123044 -283.123926) (xy 408.119084 -283.074872) (xy 406.830276 -283.074872) (xy 406.829781 -283.099479)
			(xy 406.821886 -283.148056) (xy 406.806302 -283.194737) (xy 406.783431 -283.238314) (xy 406.753866 -283.277658)
			(xy 406.718373 -283.31175) (xy 406.67787 -283.339706) (xy 406.633408 -283.360804) (xy 406.586137 -283.374496)
			(xy 406.537282 -283.380428) (xy 406.488107 -283.378447) (xy 406.439888 -283.368603) (xy 406.393872 -283.351151)
			(xy 406.351251 -283.326544) (xy 406.31313 -283.295419) (xy 406.280495 -283.258582) (xy 406.254192 -283.216986)
			(xy 406.234901 -283.17171) (xy 406.223124 -283.123926) (xy 406.219164 -283.074872) (xy 405.880316 -283.074872)
			(xy 405.879821 -283.099479) (xy 405.871926 -283.148056) (xy 405.856342 -283.194737) (xy 405.833471 -283.238314)
			(xy 405.803906 -283.277658) (xy 405.768413 -283.31175) (xy 405.72791 -283.339706) (xy 405.683448 -283.360804)
			(xy 405.636177 -283.374496) (xy 405.587322 -283.380428) (xy 405.538147 -283.378447) (xy 405.489928 -283.368603)
			(xy 405.443912 -283.351151) (xy 405.401291 -283.326544) (xy 405.36317 -283.295419) (xy 405.330535 -283.258582)
			(xy 405.304232 -283.216986) (xy 405.284941 -283.17171) (xy 405.273164 -283.123926) (xy 405.269204 -283.074872)
			(xy 404.930356 -283.074872) (xy 404.929861 -283.099479) (xy 404.921966 -283.148056) (xy 404.906382 -283.194737)
			(xy 404.883511 -283.238314) (xy 404.853946 -283.277658) (xy 404.818453 -283.31175) (xy 404.77795 -283.339706)
			(xy 404.733488 -283.360804) (xy 404.686217 -283.374496) (xy 404.637362 -283.380428) (xy 404.588187 -283.378447)
			(xy 404.539968 -283.368603) (xy 404.493952 -283.351151) (xy 404.451331 -283.326544) (xy 404.41321 -283.295419)
			(xy 404.380575 -283.258582) (xy 404.354272 -283.216986) (xy 404.334981 -283.17171) (xy 404.323204 -283.123926)
			(xy 404.319244 -283.074872) (xy 403.980101 -283.074872) (xy 403.977855 -283.116223) (xy 403.967177 -283.164707)
			(xy 403.948797 -283.210825) (xy 403.923197 -283.253362) (xy 403.891053 -283.291197) (xy 403.853211 -283.323333)
			(xy 403.810669 -283.348924) (xy 403.764547 -283.367296) (xy 403.716061 -283.377963) (xy 403.666488 -283.380646)
			(xy 403.617133 -283.375274) (xy 403.569298 -283.361987) (xy 403.524242 -283.341137) (xy 403.483154 -283.313272)
			(xy 403.447114 -283.279127) (xy 403.417073 -283.239602) (xy 403.393823 -283.195737) (xy 403.377975 -283.148688)
			(xy 403.369948 -283.099695) (xy 403.369526 -283.074872) (xy 403.369709 -283.060689) (xy 403.372377 -283.032449)
			(xy 403.37486 -283.018484) (xy 403.377146 -283.006038) (xy 403.373844 -282.994862) (xy 403.372139 -282.989775)
			(xy 403.366894 -282.980417) (xy 403.36343 -282.97632) (xy 403.36089 -282.973526) (xy 403.3012 -282.913836)
			(xy 403.298406 -282.911296) (xy 403.294286 -282.907864) (xy 403.284938 -282.902617) (xy 403.279864 -282.900882)
			(xy 403.268688 -282.89758) (xy 403.256242 -282.899866) (xy 403.242277 -282.902349) (xy 403.214037 -282.905017)
			(xy 403.199854 -282.9052) (xy 403.185671 -282.905016) (xy 403.157431 -282.902347) (xy 403.143466 -282.899866)
			(xy 403.13102 -282.89758) (xy 403.119844 -282.900882) (xy 403.114758 -282.90259) (xy 403.105405 -282.907839)
			(xy 403.101302 -282.911296) (xy 403.098508 -282.913836) (xy 403.038818 -282.973526) (xy 403.036278 -282.97632)
			(xy 403.032841 -282.980437) (xy 403.027583 -282.989782) (xy 403.025864 -282.994862) (xy 403.022562 -283.006038)
			(xy 403.024848 -283.018484) (xy 403.027335 -283.032449) (xy 403.03001 -283.060689) (xy 403.030182 -283.074872)
			(xy 403.029698 -283.099691) (xy 403.021672 -283.148675) (xy 403.005827 -283.195716) (xy 402.982581 -283.239573)
			(xy 402.952545 -283.279092) (xy 402.916511 -283.313231) (xy 402.87543 -283.341091) (xy 402.830382 -283.361937)
			(xy 402.782554 -283.375221) (xy 402.733208 -283.380592) (xy 402.683643 -283.377909) (xy 402.635165 -283.367243)
			(xy 402.589052 -283.348874) (xy 402.546517 -283.323287) (xy 402.508682 -283.291156) (xy 402.476544 -283.253327)
			(xy 402.45095 -283.210797) (xy 402.432573 -283.164686) (xy 402.421898 -283.11621) (xy 402.419206 -283.066646)
			(xy 402.424569 -283.017299) (xy 402.437844 -282.969469) (xy 402.458683 -282.924418) (xy 402.486535 -282.883331)
			(xy 402.520668 -282.847291) (xy 402.560181 -282.817248) (xy 402.604034 -282.793994) (xy 402.651072 -282.778141)
			(xy 402.700055 -282.770106) (xy 402.724874 -282.769564) (xy 402.739057 -282.769749) (xy 402.767296 -282.77242)
			(xy 402.781262 -282.774898) (xy 402.793708 -282.777184) (xy 402.804884 -282.773882) (xy 402.809968 -282.772171)
			(xy 402.819315 -282.766914) (xy 402.823426 -282.763468) (xy 402.82622 -282.760928) (xy 402.88591 -282.701238)
			(xy 402.88845 -282.698444) (xy 402.891882 -282.694324) (xy 402.897132 -282.684977) (xy 402.898864 -282.679902)
			(xy 402.902166 -282.668726) (xy 402.89988 -282.65628) (xy 402.897404 -282.642378) (xy 402.894734 -282.614265)
			(xy 402.894546 -282.600146) (xy 402.894546 -282.599638) (xy 402.89465 -282.590597) (xy 402.895792 -282.572551)
			(xy 402.896832 -282.56357) (xy 402.898102 -282.551378) (xy 402.894292 -282.540456) (xy 402.892127 -282.534877)
			(xy 402.885581 -282.524864) (xy 402.881338 -282.520644) (xy 402.82241 -282.464256) (xy 402.819362 -282.461462)
			(xy 402.815567 -282.458561) (xy 402.807129 -282.454085) (xy 402.802598 -282.452572) (xy 402.791168 -282.449016)
			(xy 402.77923 -282.451048) (xy 402.765742 -282.453178) (xy 402.738528 -282.455463) (xy 402.724874 -282.45562)
			(xy 402.698888 -282.455109) (xy 402.647556 -282.446975) (xy 402.598128 -282.430912) (xy 402.551821 -282.407315)
			(xy 402.509776 -282.376765) (xy 402.473026 -282.340014) (xy 402.442478 -282.297967) (xy 402.418883 -282.251659)
			(xy 402.402822 -282.202231) (xy 402.39469 -282.150898) (xy 402.394166 -282.124912) (xy 402.394166 -282.117038)
			(xy 402.39442 -282.109418) (xy 402.390356 -282.094432) (xy 402.386038 -282.088082) (xy 402.381612 -282.081711)
			(xy 402.369721 -282.071758) (xy 402.36267 -282.068524) (xy 402.362416 -282.068524) (xy 402.335215 -282.057246)
			(xy 402.282094 -282.031826) (xy 402.256244 -282.017724) (xy 402.250148 -282.014422) (xy 402.23694 -282.01112)
			(xy 402.23059 -282.01112) (xy 402.223888 -282.011555) (xy 402.211031 -282.015424) (xy 402.20519 -282.01874)
			(xy 402.129498 -282.065476) (xy 402.122046 -282.0705) (xy 402.110952 -282.084626) (xy 402.105381 -282.101701)
			(xy 402.105368 -282.110688) (xy 402.105622 -282.124912) (xy 402.105112 -282.150899) (xy 402.096982 -282.202234)
			(xy 402.080921 -282.251664) (xy 402.057325 -282.297974) (xy 402.026775 -282.340022) (xy 401.990024 -282.376773)
			(xy 401.947976 -282.407323) (xy 401.901666 -282.430919) (xy 401.852236 -282.44698) (xy 401.800901 -282.45511)
			(xy 401.748927 -282.45511) (xy 401.697592 -282.44698) (xy 401.648162 -282.430919) (xy 401.601852 -282.407323)
			(xy 401.559804 -282.376773) (xy 401.523053 -282.340022) (xy 401.492503 -282.297974) (xy 401.468907 -282.251664)
			(xy 401.452846 -282.202234) (xy 401.444716 -282.150899) (xy 401.444206 -282.124912) (xy 401.44446 -282.110688)
			(xy 401.44447 -282.101695) (xy 401.438931 -282.084597) (xy 401.427799 -282.070487) (xy 401.42033 -282.065476)
			(xy 401.344638 -282.01874) (xy 401.338828 -282.015356) (xy 401.325952 -282.011496) (xy 401.319238 -282.01112)
			(xy 401.305776 -282.010866) (xy 401.293584 -282.017724) (xy 401.267742 -282.031842) (xy 401.214619 -282.057259)
			(xy 401.187412 -282.068524) (xy 401.180501 -282.071632) (xy 401.168755 -282.081191) (xy 401.164298 -282.08732)
			(xy 401.15998 -282.093416) (xy 401.157694 -282.100782) (xy 401.15673 -282.104323) (xy 401.155712 -282.11159)
			(xy 401.155662 -282.11526) (xy 401.155662 -282.124912) (xy 401.155152 -282.150899) (xy 401.147022 -282.202234)
			(xy 401.130961 -282.251664) (xy 401.107365 -282.297974) (xy 401.076815 -282.340022) (xy 401.040064 -282.376773)
			(xy 400.998016 -282.407323) (xy 400.951706 -282.430919) (xy 400.902276 -282.44698) (xy 400.850941 -282.45511)
			(xy 400.798967 -282.45511) (xy 400.747632 -282.44698) (xy 400.698202 -282.430919) (xy 400.651892 -282.407323)
			(xy 400.609844 -282.376773) (xy 400.573093 -282.340022) (xy 400.542543 -282.297974) (xy 400.518947 -282.251664)
			(xy 400.502886 -282.202234) (xy 400.494756 -282.150899) (xy 400.494246 -282.124912) (xy 400.494246 -282.117038)
			(xy 400.4945 -282.109418) (xy 400.490436 -282.094432) (xy 400.486118 -282.088082) (xy 400.481696 -282.081705)
			(xy 400.469813 -282.071735) (xy 400.46275 -282.068524) (xy 400.462496 -282.068524) (xy 400.435296 -282.057245)
			(xy 400.382174 -282.031825) (xy 400.356324 -282.017724) (xy 400.350228 -282.014422) (xy 400.33702 -282.01112)
			(xy 400.33067 -282.01112) (xy 400.323964 -282.011545) (xy 400.311098 -282.015397) (xy 400.30527 -282.01874)
			(xy 400.229578 -282.065476) (xy 400.222128 -282.070502) (xy 400.211039 -282.084628) (xy 400.20547 -282.101702)
			(xy 400.205448 -282.110688) (xy 400.205702 -282.124912) (xy 400.205192 -282.150899) (xy 400.197062 -282.202234)
			(xy 400.181001 -282.251664) (xy 400.157405 -282.297974) (xy 400.126855 -282.340022) (xy 400.090104 -282.376773)
			(xy 400.048056 -282.407323) (xy 400.001746 -282.430919) (xy 399.952316 -282.44698) (xy 399.900981 -282.45511)
			(xy 399.849007 -282.45511) (xy 399.797672 -282.44698) (xy 399.748242 -282.430919) (xy 399.701932 -282.407323)
			(xy 399.659884 -282.376773) (xy 399.623133 -282.340022) (xy 399.592583 -282.297974) (xy 399.568987 -282.251664)
			(xy 399.552926 -282.202234) (xy 399.544796 -282.150899) (xy 399.544286 -282.124912) (xy 399.54454 -282.110688)
			(xy 399.54455 -282.101695) (xy 399.539009 -282.084599) (xy 399.527875 -282.070493) (xy 399.52041 -282.065476)
			(xy 399.444718 -282.01874) (xy 399.438907 -282.015358) (xy 399.426031 -282.011504) (xy 399.419318 -282.01112)
			(xy 399.405856 -282.010866) (xy 399.393664 -282.017724) (xy 399.367822 -282.031841) (xy 399.314698 -282.057258)
			(xy 399.287492 -282.068524) (xy 399.280574 -282.071624) (xy 399.268812 -282.081173) (xy 399.264378 -282.08732)
			(xy 399.26006 -282.093416) (xy 399.257774 -282.100782) (xy 399.25681 -282.104323) (xy 399.255792 -282.11159)
			(xy 399.255742 -282.11526) (xy 399.255742 -282.124912) (xy 399.255232 -282.150899) (xy 399.247102 -282.202234)
			(xy 399.231041 -282.251664) (xy 399.207445 -282.297974) (xy 399.176895 -282.340022) (xy 399.140144 -282.376773)
			(xy 399.098096 -282.407323) (xy 399.051786 -282.430919) (xy 399.002356 -282.44698) (xy 398.951021 -282.45511)
			(xy 398.899047 -282.45511) (xy 398.847712 -282.44698) (xy 398.798282 -282.430919) (xy 398.751972 -282.407323)
			(xy 398.709924 -282.376773) (xy 398.673173 -282.340022) (xy 398.642623 -282.297974) (xy 398.619027 -282.251664)
			(xy 398.602966 -282.202234) (xy 398.594836 -282.150899) (xy 398.594326 -282.124912) (xy 398.594326 -282.117038)
			(xy 398.595596 -282.08097) (xy 398.559476 -282.067639) (xy 398.489287 -282.035979) (xy 398.455388 -282.017724)
			(xy 398.447345 -282.013663) (xy 398.429548 -282.01092) (xy 398.411908 -282.014533) (xy 398.40408 -282.018994)
			(xy 398.329404 -282.065222) (xy 398.324578 -282.068524) (xy 398.320006 -282.072588) (xy 398.31637 -282.076411)
			(xy 398.3106 -282.085242) (xy 398.308576 -282.090114) (xy 398.304766 -282.099766) (xy 398.305274 -282.110434)
			(xy 398.305528 -282.124912) (xy 398.305018 -282.150899) (xy 398.296888 -282.202234) (xy 398.280827 -282.251664)
			(xy 398.257231 -282.297974) (xy 398.226681 -282.340022) (xy 398.18993 -282.376773) (xy 398.147882 -282.407323)
			(xy 398.101572 -282.430919) (xy 398.052142 -282.44698) (xy 398.000807 -282.45511) (xy 397.948833 -282.45511)
			(xy 397.897498 -282.44698) (xy 397.848068 -282.430919) (xy 397.801758 -282.407323) (xy 397.75971 -282.376773)
			(xy 397.722959 -282.340022) (xy 397.692409 -282.297974) (xy 397.668813 -282.251664) (xy 397.652752 -282.202234)
			(xy 397.644622 -282.150899) (xy 397.644112 -282.124912) (xy 397.644366 -282.110688) (xy 397.644376 -282.101694)
			(xy 397.638838 -282.084596) (xy 397.627706 -282.070486) (xy 397.620236 -282.065476) (xy 397.544544 -282.01874)
			(xy 397.538734 -282.015355) (xy 397.525858 -282.011494) (xy 397.519144 -282.01112) (xy 397.505682 -282.010866)
			(xy 397.49349 -282.017724) (xy 397.467648 -282.031842) (xy 397.414525 -282.05726) (xy 397.387318 -282.068524)
			(xy 397.380407 -282.071631) (xy 397.368659 -282.08119) (xy 397.364204 -282.08732) (xy 397.359886 -282.093416)
			(xy 397.3576 -282.100782) (xy 397.356635 -282.104323) (xy 397.355617 -282.11159) (xy 397.355568 -282.11526)
			(xy 397.355568 -282.124912) (xy 397.355055 -282.151271) (xy 397.346694 -282.203321) (xy 397.330185 -282.253387)
			(xy 397.305946 -282.300202) (xy 397.27459 -282.342581) (xy 397.236911 -282.379451) (xy 397.193862 -282.409881)
			(xy 397.146533 -282.433099) (xy 397.096121 -282.448519) (xy 397.070072 -282.452572) (xy 397.066008 -282.45308)
			(xy 397.054578 -282.456636) (xy 397.05026 -282.457906) (xy 397.02613 -282.469082) (xy 397.019526 -282.476194)
			(xy 397.004794 -282.491688) (xy 396.996666 -282.502864) (xy 396.99397 -282.508395) (xy 396.991013 -282.520336)
			(xy 396.990824 -282.526486) (xy 396.990824 -282.673298) (xy 396.990997 -282.67945) (xy 396.993956 -282.691394)
			(xy 396.996666 -282.69692) (xy 397.004794 -282.708096) (xy 397.019526 -282.72359) (xy 397.02613 -282.730702)
			(xy 397.05026 -282.741878) (xy 397.054578 -282.743148) (xy 397.066008 -282.746704) (xy 397.070072 -282.747212)
			(xy 397.096119 -282.75132) (xy 397.146549 -282.766716) (xy 397.193898 -282.789916) (xy 397.236967 -282.820335)
			(xy 397.274666 -282.8572) (xy 397.306038 -282.899579) (xy 397.330291 -282.946398) (xy 397.346809 -282.996472)
			(xy 397.355174 -283.048532) (xy 397.355174 -283.074872) (xy 397.669016 -283.074872) (xy 397.672976 -283.025818)
			(xy 397.684753 -282.978034) (xy 397.704044 -282.932758) (xy 397.730347 -282.891162) (xy 397.762982 -282.854325)
			(xy 397.801103 -282.8232) (xy 397.843724 -282.798593) (xy 397.88974 -282.781141) (xy 397.937959 -282.771297)
			(xy 397.987134 -282.769316) (xy 398.035989 -282.775248) (xy 398.08326 -282.78894) (xy 398.127722 -282.810038)
			(xy 398.168225 -282.837994) (xy 398.203718 -282.872086) (xy 398.233283 -282.91143) (xy 398.256154 -282.955007)
			(xy 398.271738 -283.001688) (xy 398.279633 -283.050265) (xy 398.280128 -283.074872) (xy 398.61923 -283.074872)
			(xy 398.62319 -283.025818) (xy 398.634967 -282.978034) (xy 398.654258 -282.932758) (xy 398.680561 -282.891162)
			(xy 398.713196 -282.854325) (xy 398.751317 -282.8232) (xy 398.793938 -282.798593) (xy 398.839954 -282.781141)
			(xy 398.888173 -282.771297) (xy 398.937348 -282.769316) (xy 398.986203 -282.775248) (xy 399.033474 -282.78894)
			(xy 399.077936 -282.810038) (xy 399.118439 -282.837994) (xy 399.153932 -282.872086) (xy 399.183497 -282.91143)
			(xy 399.206368 -282.955007) (xy 399.221952 -283.001688) (xy 399.229847 -283.050265) (xy 399.230342 -283.074872)
			(xy 399.56919 -283.074872) (xy 399.57315 -283.025818) (xy 399.584927 -282.978034) (xy 399.604218 -282.932758)
			(xy 399.630521 -282.891162) (xy 399.663156 -282.854325) (xy 399.701277 -282.8232) (xy 399.743898 -282.798593)
			(xy 399.789914 -282.781141) (xy 399.838133 -282.771297) (xy 399.887308 -282.769316) (xy 399.936163 -282.775248)
			(xy 399.983434 -282.78894) (xy 400.027896 -282.810038) (xy 400.068399 -282.837994) (xy 400.103892 -282.872086)
			(xy 400.133457 -282.91143) (xy 400.156328 -282.955007) (xy 400.171912 -283.001688) (xy 400.179807 -283.050265)
			(xy 400.180302 -283.074872) (xy 400.51915 -283.074872) (xy 400.52311 -283.025818) (xy 400.534887 -282.978034)
			(xy 400.554178 -282.932758) (xy 400.580481 -282.891162) (xy 400.613116 -282.854325) (xy 400.651237 -282.8232)
			(xy 400.693858 -282.798593) (xy 400.739874 -282.781141) (xy 400.788093 -282.771297) (xy 400.837268 -282.769316)
			(xy 400.886123 -282.775248) (xy 400.933394 -282.78894) (xy 400.977856 -282.810038) (xy 401.018359 -282.837994)
			(xy 401.053852 -282.872086) (xy 401.083417 -282.91143) (xy 401.106288 -282.955007) (xy 401.121872 -283.001688)
			(xy 401.129767 -283.050265) (xy 401.130262 -283.074872) (xy 401.46911 -283.074872) (xy 401.47307 -283.025818)
			(xy 401.484847 -282.978034) (xy 401.504138 -282.932758) (xy 401.530441 -282.891162) (xy 401.563076 -282.854325)
			(xy 401.601197 -282.8232) (xy 401.643818 -282.798593) (xy 401.689834 -282.781141) (xy 401.738053 -282.771297)
			(xy 401.787228 -282.769316) (xy 401.836083 -282.775248) (xy 401.883354 -282.78894) (xy 401.927816 -282.810038)
			(xy 401.968319 -282.837994) (xy 402.003812 -282.872086) (xy 402.033377 -282.91143) (xy 402.056248 -282.955007)
			(xy 402.071832 -283.001688) (xy 402.079727 -283.050265) (xy 402.080222 -283.074872) (xy 402.079727 -283.099479)
			(xy 402.071832 -283.148056) (xy 402.056248 -283.194737) (xy 402.033377 -283.238314) (xy 402.003812 -283.277658)
			(xy 401.968319 -283.31175) (xy 401.927816 -283.339706) (xy 401.883354 -283.360804) (xy 401.836083 -283.374496)
			(xy 401.787228 -283.380428) (xy 401.738053 -283.378447) (xy 401.689834 -283.368603) (xy 401.643818 -283.351151)
			(xy 401.601197 -283.326544) (xy 401.563076 -283.295419) (xy 401.530441 -283.258582) (xy 401.504138 -283.216986)
			(xy 401.484847 -283.17171) (xy 401.47307 -283.123926) (xy 401.46911 -283.074872) (xy 401.130262 -283.074872)
			(xy 401.129767 -283.099479) (xy 401.121872 -283.148056) (xy 401.106288 -283.194737) (xy 401.083417 -283.238314)
			(xy 401.053852 -283.277658) (xy 401.018359 -283.31175) (xy 400.977856 -283.339706) (xy 400.933394 -283.360804)
			(xy 400.886123 -283.374496) (xy 400.837268 -283.380428) (xy 400.788093 -283.378447) (xy 400.739874 -283.368603)
			(xy 400.693858 -283.351151) (xy 400.651237 -283.326544) (xy 400.613116 -283.295419) (xy 400.580481 -283.258582)
			(xy 400.554178 -283.216986) (xy 400.534887 -283.17171) (xy 400.52311 -283.123926) (xy 400.51915 -283.074872)
			(xy 400.180302 -283.074872) (xy 400.179807 -283.099479) (xy 400.171912 -283.148056) (xy 400.156328 -283.194737)
			(xy 400.133457 -283.238314) (xy 400.103892 -283.277658) (xy 400.068399 -283.31175) (xy 400.027896 -283.339706)
			(xy 399.983434 -283.360804) (xy 399.936163 -283.374496) (xy 399.887308 -283.380428) (xy 399.838133 -283.378447)
			(xy 399.789914 -283.368603) (xy 399.743898 -283.351151) (xy 399.701277 -283.326544) (xy 399.663156 -283.295419)
			(xy 399.630521 -283.258582) (xy 399.604218 -283.216986) (xy 399.584927 -283.17171) (xy 399.57315 -283.123926)
			(xy 399.56919 -283.074872) (xy 399.230342 -283.074872) (xy 399.229847 -283.099479) (xy 399.221952 -283.148056)
			(xy 399.206368 -283.194737) (xy 399.183497 -283.238314) (xy 399.153932 -283.277658) (xy 399.118439 -283.31175)
			(xy 399.077936 -283.339706) (xy 399.033474 -283.360804) (xy 398.986203 -283.374496) (xy 398.937348 -283.380428)
			(xy 398.888173 -283.378447) (xy 398.839954 -283.368603) (xy 398.793938 -283.351151) (xy 398.751317 -283.326544)
			(xy 398.713196 -283.295419) (xy 398.680561 -283.258582) (xy 398.654258 -283.216986) (xy 398.634967 -283.17171)
			(xy 398.62319 -283.123926) (xy 398.61923 -283.074872) (xy 398.280128 -283.074872) (xy 398.279633 -283.099479)
			(xy 398.271738 -283.148056) (xy 398.256154 -283.194737) (xy 398.233283 -283.238314) (xy 398.203718 -283.277658)
			(xy 398.168225 -283.31175) (xy 398.127722 -283.339706) (xy 398.08326 -283.360804) (xy 398.035989 -283.374496)
			(xy 397.987134 -283.380428) (xy 397.937959 -283.378447) (xy 397.88974 -283.368603) (xy 397.843724 -283.351151)
			(xy 397.801103 -283.326544) (xy 397.762982 -283.295419) (xy 397.730347 -283.258582) (xy 397.704044 -283.216986)
			(xy 397.684753 -283.17171) (xy 397.672976 -283.123926) (xy 397.669016 -283.074872) (xy 397.355174 -283.074872)
			(xy 397.355175 -283.10126) (xy 397.346811 -283.15332) (xy 397.330294 -283.203394) (xy 397.306042 -283.250214)
			(xy 397.274671 -283.292594) (xy 397.236973 -283.32946) (xy 397.193905 -283.35988) (xy 397.146556 -283.383082)
			(xy 397.096126 -283.398478) (xy 397.070072 -283.402532) (xy 397.066008 -283.40304) (xy 397.054578 -283.406596)
			(xy 397.05026 -283.407866) (xy 397.02613 -283.419042) (xy 397.019526 -283.426154) (xy 397.004794 -283.441648)
			(xy 396.996666 -283.452824) (xy 396.993976 -283.458357) (xy 396.991034 -283.470297) (xy 396.990824 -283.476446)
			(xy 396.990824 -283.549852) (xy 421.894012 -283.549852) (xy 421.897972 -283.500798) (xy 421.909749 -283.453014)
			(xy 421.92904 -283.407738) (xy 421.955343 -283.366142) (xy 421.987978 -283.329305) (xy 422.026099 -283.29818)
			(xy 422.06872 -283.273573) (xy 422.114736 -283.256121) (xy 422.162955 -283.246277) (xy 422.21213 -283.244296)
			(xy 422.260985 -283.250228) (xy 422.308256 -283.26392) (xy 422.352718 -283.285018) (xy 422.393221 -283.312974)
			(xy 422.428714 -283.347066) (xy 422.458279 -283.38641) (xy 422.48115 -283.429987) (xy 422.496734 -283.476668)
			(xy 422.504629 -283.525245) (xy 422.505124 -283.549852) (xy 422.504629 -283.574459) (xy 422.50445 -283.57556)
			(xy 422.823128 -283.57556) (xy 422.823128 -283.524144) (xy 422.831171 -283.473362) (xy 422.847059 -283.424463)
			(xy 422.870402 -283.378651) (xy 422.900623 -283.337055) (xy 422.936979 -283.300699) (xy 422.978575 -283.270478)
			(xy 423.024387 -283.247135) (xy 423.073286 -283.231247) (xy 423.124068 -283.223204) (xy 423.175484 -283.223204)
			(xy 423.226266 -283.231247) (xy 423.275165 -283.247135) (xy 423.320977 -283.270478) (xy 423.362573 -283.300699)
			(xy 423.398929 -283.337055) (xy 423.42915 -283.378651) (xy 423.452493 -283.424463) (xy 423.468381 -283.473362)
			(xy 423.476424 -283.524144) (xy 423.476928 -283.549852) (xy 423.476424 -283.57556) (xy 423.773342 -283.57556)
			(xy 423.773342 -283.524144) (xy 423.781385 -283.473362) (xy 423.797273 -283.424463) (xy 423.820616 -283.378651)
			(xy 423.850837 -283.337055) (xy 423.887193 -283.300699) (xy 423.928789 -283.270478) (xy 423.974601 -283.247135)
			(xy 424.0235 -283.231247) (xy 424.074282 -283.223204) (xy 424.125698 -283.223204) (xy 424.17648 -283.231247)
			(xy 424.225379 -283.247135) (xy 424.271191 -283.270478) (xy 424.312787 -283.300699) (xy 424.349143 -283.337055)
			(xy 424.379364 -283.378651) (xy 424.402707 -283.424463) (xy 424.418595 -283.473362) (xy 424.426638 -283.524144)
			(xy 424.427142 -283.549852) (xy 424.744146 -283.549852) (xy 424.748106 -283.500798) (xy 424.759883 -283.453014)
			(xy 424.779174 -283.407738) (xy 424.805477 -283.366142) (xy 424.838112 -283.329305) (xy 424.876233 -283.29818)
			(xy 424.918854 -283.273573) (xy 424.96487 -283.256121) (xy 425.013089 -283.246277) (xy 425.062264 -283.244296)
			(xy 425.111119 -283.250228) (xy 425.15839 -283.26392) (xy 425.202852 -283.285018) (xy 425.243355 -283.312974)
			(xy 425.278848 -283.347066) (xy 425.308413 -283.38641) (xy 425.331284 -283.429987) (xy 425.346868 -283.476668)
			(xy 425.354763 -283.525245) (xy 425.355258 -283.549852) (xy 425.694106 -283.549852) (xy 425.698066 -283.500798)
			(xy 425.709843 -283.453014) (xy 425.729134 -283.407738) (xy 425.755437 -283.366142) (xy 425.788072 -283.329305)
			(xy 425.826193 -283.29818) (xy 425.868814 -283.273573) (xy 425.91483 -283.256121) (xy 425.963049 -283.246277)
			(xy 426.012224 -283.244296) (xy 426.061079 -283.250228) (xy 426.10835 -283.26392) (xy 426.152812 -283.285018)
			(xy 426.193315 -283.312974) (xy 426.228808 -283.347066) (xy 426.258373 -283.38641) (xy 426.281244 -283.429987)
			(xy 426.296828 -283.476668) (xy 426.304723 -283.525245) (xy 426.305218 -283.549852) (xy 426.644066 -283.549852)
			(xy 426.648026 -283.500798) (xy 426.659803 -283.453014) (xy 426.679094 -283.407738) (xy 426.705397 -283.366142)
			(xy 426.738032 -283.329305) (xy 426.776153 -283.29818) (xy 426.818774 -283.273573) (xy 426.86479 -283.256121)
			(xy 426.913009 -283.246277) (xy 426.962184 -283.244296) (xy 427.011039 -283.250228) (xy 427.05831 -283.26392)
			(xy 427.102772 -283.285018) (xy 427.143275 -283.312974) (xy 427.178768 -283.347066) (xy 427.208333 -283.38641)
			(xy 427.231204 -283.429987) (xy 427.246788 -283.476668) (xy 427.254683 -283.525245) (xy 427.255178 -283.549852)
			(xy 427.594026 -283.549852) (xy 427.597986 -283.500798) (xy 427.609763 -283.453014) (xy 427.629054 -283.407738)
			(xy 427.655357 -283.366142) (xy 427.687992 -283.329305) (xy 427.726113 -283.29818) (xy 427.768734 -283.273573)
			(xy 427.81475 -283.256121) (xy 427.862969 -283.246277) (xy 427.912144 -283.244296) (xy 427.960999 -283.250228)
			(xy 428.00827 -283.26392) (xy 428.052732 -283.285018) (xy 428.093235 -283.312974) (xy 428.128728 -283.347066)
			(xy 428.158293 -283.38641) (xy 428.181164 -283.429987) (xy 428.196748 -283.476668) (xy 428.204643 -283.525245)
			(xy 428.205138 -283.549852) (xy 428.543986 -283.549852) (xy 428.547946 -283.500798) (xy 428.559723 -283.453014)
			(xy 428.579014 -283.407738) (xy 428.605317 -283.366142) (xy 428.637952 -283.329305) (xy 428.676073 -283.29818)
			(xy 428.718694 -283.273573) (xy 428.76471 -283.256121) (xy 428.812929 -283.246277) (xy 428.862104 -283.244296)
			(xy 428.910959 -283.250228) (xy 428.95823 -283.26392) (xy 429.002692 -283.285018) (xy 429.043195 -283.312974)
			(xy 429.078688 -283.347066) (xy 429.108253 -283.38641) (xy 429.131124 -283.429987) (xy 429.146708 -283.476668)
			(xy 429.154603 -283.525245) (xy 429.155098 -283.549852) (xy 429.154603 -283.574459) (xy 429.154424 -283.57556)
			(xy 429.473356 -283.57556) (xy 429.473356 -283.524144) (xy 429.481399 -283.473362) (xy 429.497287 -283.424463)
			(xy 429.52063 -283.378651) (xy 429.550851 -283.337055) (xy 429.587207 -283.300699) (xy 429.628803 -283.270478)
			(xy 429.674615 -283.247135) (xy 429.723514 -283.231247) (xy 429.774296 -283.223204) (xy 429.825712 -283.223204)
			(xy 429.876494 -283.231247) (xy 429.925393 -283.247135) (xy 429.971205 -283.270478) (xy 430.012801 -283.300699)
			(xy 430.049157 -283.337055) (xy 430.079378 -283.378651) (xy 430.102721 -283.424463) (xy 430.118609 -283.473362)
			(xy 430.126652 -283.524144) (xy 430.127156 -283.549852) (xy 430.126652 -283.57556) (xy 430.423316 -283.57556)
			(xy 430.423316 -283.524144) (xy 430.431359 -283.473362) (xy 430.447247 -283.424463) (xy 430.47059 -283.378651)
			(xy 430.500811 -283.337055) (xy 430.537167 -283.300699) (xy 430.578763 -283.270478) (xy 430.624575 -283.247135)
			(xy 430.673474 -283.231247) (xy 430.724256 -283.223204) (xy 430.775672 -283.223204) (xy 430.826454 -283.231247)
			(xy 430.875353 -283.247135) (xy 430.921165 -283.270478) (xy 430.962761 -283.300699) (xy 430.999117 -283.337055)
			(xy 431.029338 -283.378651) (xy 431.052681 -283.424463) (xy 431.068569 -283.473362) (xy 431.076612 -283.524144)
			(xy 431.077116 -283.549852) (xy 431.077111 -283.550106) (xy 431.394374 -283.550106) (xy 431.398334 -283.501052)
			(xy 431.410111 -283.453268) (xy 431.429402 -283.407992) (xy 431.455705 -283.366396) (xy 431.48834 -283.329559)
			(xy 431.526461 -283.298434) (xy 431.569082 -283.273827) (xy 431.615098 -283.256375) (xy 431.663317 -283.246531)
			(xy 431.712492 -283.24455) (xy 431.761347 -283.250482) (xy 431.808618 -283.264174) (xy 431.85308 -283.285272)
			(xy 431.893583 -283.313228) (xy 431.929076 -283.34732) (xy 431.958641 -283.386664) (xy 431.981512 -283.430241)
			(xy 431.997096 -283.476922) (xy 432.004991 -283.525499) (xy 432.005036 -283.527754) (xy 442.093858 -283.527754)
			(xy 442.094335 -283.500503) (xy 442.102097 -283.446557) (xy 442.117456 -283.394264) (xy 442.1401 -283.344689)
			(xy 442.169568 -283.29884) (xy 442.20526 -283.257652) (xy 442.24645 -283.221961) (xy 442.292299 -283.192494)
			(xy 442.341875 -283.169852) (xy 442.394169 -283.154494) (xy 442.448115 -283.146734) (xy 442.475366 -283.146246)
			(xy 442.502736 -283.146721) (xy 442.556915 -283.154535) (xy 442.609419 -283.170021) (xy 442.659166 -283.192861)
			(xy 442.705132 -283.222585) (xy 442.726064 -283.240226) (xy 442.733176 -283.246322) (xy 442.741558 -283.24937)
			(xy 442.745846 -283.250889) (xy 442.75479 -283.252549) (xy 442.759338 -283.252672) (xy 442.826394 -283.252672)
			(xy 442.830942 -283.252546) (xy 442.839886 -283.250888) (xy 442.844174 -283.24937) (xy 442.852556 -283.246322)
			(xy 442.859668 -283.240226) (xy 442.880605 -283.222592) (xy 442.926576 -283.192879) (xy 442.976322 -283.170041)
			(xy 443.028822 -283.154549) (xy 443.082997 -283.14672) (xy 443.110366 -283.146246) (xy 443.137614 -283.14681)
			(xy 443.191557 -283.15456) (xy 443.243847 -283.169909) (xy 443.293421 -283.192543) (xy 443.33927 -283.222001)
			(xy 443.380459 -283.257684) (xy 443.416151 -283.298866) (xy 443.445619 -283.344709) (xy 443.468263 -283.394278)
			(xy 443.483623 -283.446565) (xy 443.491385 -283.500506) (xy 443.491874 -283.527754) (xy 443.49149 -283.554179)
			(xy 443.484188 -283.606523) (xy 443.469732 -283.657358) (xy 443.448398 -283.705712) (xy 443.420594 -283.750658)
			(xy 443.386853 -283.791337) (xy 443.34782 -283.826969) (xy 443.304244 -283.856874) (xy 443.256957 -283.880477)
			(xy 443.206864 -283.897328) (xy 443.180978 -283.902658) (xy 443.168786 -283.904944) (xy 443.159134 -283.91231)
			(xy 443.154508 -283.916189) (xy 443.147063 -283.925688) (xy 443.144402 -283.931106) (xy 443.104016 -284.017212)
			(xy 443.104524 -284.029404) (xy 443.104921 -284.035387) (xy 443.108119 -284.046939) (xy 443.110874 -284.052264)
			(xy 443.111128 -284.052518) (xy 443.122831 -284.074052) (xy 443.14127 -284.119461) (xy 443.153736 -284.166859)
			(xy 443.160023 -284.215465) (xy 443.160404 -284.23997) (xy 443.159918 -284.267221) (xy 443.152162 -284.321169)
			(xy 443.136807 -284.373464) (xy 443.114165 -284.423041) (xy 443.084699 -284.468891) (xy 443.049008 -284.510082)
			(xy 443.007817 -284.545773) (xy 442.961967 -284.575239) (xy 442.91239 -284.597881) (xy 442.860095 -284.613236)
			(xy 442.806147 -284.620992) (xy 442.751645 -284.620992) (xy 442.697697 -284.613236) (xy 442.645402 -284.597881)
			(xy 442.595825 -284.575239) (xy 442.549975 -284.545773) (xy 442.508784 -284.510082) (xy 442.473093 -284.468891)
			(xy 442.443627 -284.423041) (xy 442.420985 -284.373464) (xy 442.40563 -284.321169) (xy 442.397874 -284.267221)
			(xy 442.397388 -284.23997) (xy 442.397388 -284.239462) (xy 442.397785 -284.214404) (xy 442.404389 -284.164723)
			(xy 442.41744 -284.116334) (xy 442.436711 -284.07007) (xy 442.44895 -284.0482) (xy 442.4553 -284.037532)
			(xy 442.455808 -284.025848) (xy 442.456023 -284.02006) (xy 442.454091 -284.008643) (xy 442.451998 -284.003242)
			(xy 442.419994 -283.927804) (xy 442.416692 -283.9212) (xy 442.414378 -283.917632) (xy 442.40876 -283.911249)
			(xy 442.405516 -283.9085) (xy 442.397134 -283.901388) (xy 442.385196 -283.89834) (xy 442.35787 -283.891179)
			(xy 442.305548 -283.869885) (xy 442.256939 -283.841109) (xy 442.213106 -283.805478) (xy 442.175006 -283.763772)
			(xy 442.143474 -283.716903) (xy 442.119199 -283.665897) (xy 442.102711 -283.611868) (xy 442.094373 -283.555998)
			(xy 442.093858 -283.527754) (xy 432.005036 -283.527754) (xy 432.005486 -283.550106) (xy 432.004991 -283.574713)
			(xy 431.997096 -283.62329) (xy 431.981512 -283.669971) (xy 431.958641 -283.713548) (xy 431.929076 -283.752892)
			(xy 431.893583 -283.786984) (xy 431.85308 -283.81494) (xy 431.808618 -283.836038) (xy 431.761347 -283.84973)
			(xy 431.712492 -283.855662) (xy 431.663317 -283.853681) (xy 431.615098 -283.843837) (xy 431.569082 -283.826385)
			(xy 431.526461 -283.801778) (xy 431.48834 -283.770653) (xy 431.455705 -283.733816) (xy 431.429402 -283.69222)
			(xy 431.410111 -283.646944) (xy 431.398334 -283.59916) (xy 431.394374 -283.550106) (xy 431.077111 -283.550106)
			(xy 431.076612 -283.57556) (xy 431.068569 -283.626342) (xy 431.052681 -283.675241) (xy 431.029338 -283.721053)
			(xy 430.999117 -283.762649) (xy 430.962761 -283.799005) (xy 430.921165 -283.829226) (xy 430.875353 -283.852569)
			(xy 430.826454 -283.868457) (xy 430.775672 -283.8765) (xy 430.724256 -283.8765) (xy 430.673474 -283.868457)
			(xy 430.624575 -283.852569) (xy 430.578763 -283.829226) (xy 430.537167 -283.799005) (xy 430.500811 -283.762649)
			(xy 430.47059 -283.721053) (xy 430.447247 -283.675241) (xy 430.431359 -283.626342) (xy 430.423316 -283.57556)
			(xy 430.126652 -283.57556) (xy 430.118609 -283.626342) (xy 430.102721 -283.675241) (xy 430.079378 -283.721053)
			(xy 430.049157 -283.762649) (xy 430.012801 -283.799005) (xy 429.971205 -283.829226) (xy 429.925393 -283.852569)
			(xy 429.876494 -283.868457) (xy 429.825712 -283.8765) (xy 429.774296 -283.8765) (xy 429.723514 -283.868457)
			(xy 429.674615 -283.852569) (xy 429.628803 -283.829226) (xy 429.587207 -283.799005) (xy 429.550851 -283.762649)
			(xy 429.52063 -283.721053) (xy 429.497287 -283.675241) (xy 429.481399 -283.626342) (xy 429.473356 -283.57556)
			(xy 429.154424 -283.57556) (xy 429.146708 -283.623036) (xy 429.131124 -283.669717) (xy 429.108253 -283.713294)
			(xy 429.078688 -283.752638) (xy 429.043195 -283.78673) (xy 429.002692 -283.814686) (xy 428.95823 -283.835784)
			(xy 428.910959 -283.849476) (xy 428.862104 -283.855408) (xy 428.812929 -283.853427) (xy 428.76471 -283.843583)
			(xy 428.718694 -283.826131) (xy 428.676073 -283.801524) (xy 428.637952 -283.770399) (xy 428.605317 -283.733562)
			(xy 428.579014 -283.691966) (xy 428.559723 -283.64669) (xy 428.547946 -283.598906) (xy 428.543986 -283.549852)
			(xy 428.205138 -283.549852) (xy 428.204643 -283.574459) (xy 428.196748 -283.623036) (xy 428.181164 -283.669717)
			(xy 428.158293 -283.713294) (xy 428.128728 -283.752638) (xy 428.093235 -283.78673) (xy 428.052732 -283.814686)
			(xy 428.00827 -283.835784) (xy 427.960999 -283.849476) (xy 427.912144 -283.855408) (xy 427.862969 -283.853427)
			(xy 427.81475 -283.843583) (xy 427.768734 -283.826131) (xy 427.726113 -283.801524) (xy 427.687992 -283.770399)
			(xy 427.655357 -283.733562) (xy 427.629054 -283.691966) (xy 427.609763 -283.64669) (xy 427.597986 -283.598906)
			(xy 427.594026 -283.549852) (xy 427.255178 -283.549852) (xy 427.254683 -283.574459) (xy 427.246788 -283.623036)
			(xy 427.231204 -283.669717) (xy 427.208333 -283.713294) (xy 427.178768 -283.752638) (xy 427.143275 -283.78673)
			(xy 427.102772 -283.814686) (xy 427.05831 -283.835784) (xy 427.011039 -283.849476) (xy 426.962184 -283.855408)
			(xy 426.913009 -283.853427) (xy 426.86479 -283.843583) (xy 426.818774 -283.826131) (xy 426.776153 -283.801524)
			(xy 426.738032 -283.770399) (xy 426.705397 -283.733562) (xy 426.679094 -283.691966) (xy 426.659803 -283.64669)
			(xy 426.648026 -283.598906) (xy 426.644066 -283.549852) (xy 426.305218 -283.549852) (xy 426.304723 -283.574459)
			(xy 426.296828 -283.623036) (xy 426.281244 -283.669717) (xy 426.258373 -283.713294) (xy 426.228808 -283.752638)
			(xy 426.193315 -283.78673) (xy 426.152812 -283.814686) (xy 426.10835 -283.835784) (xy 426.061079 -283.849476)
			(xy 426.012224 -283.855408) (xy 425.963049 -283.853427) (xy 425.91483 -283.843583) (xy 425.868814 -283.826131)
			(xy 425.826193 -283.801524) (xy 425.788072 -283.770399) (xy 425.755437 -283.733562) (xy 425.729134 -283.691966)
			(xy 425.709843 -283.64669) (xy 425.698066 -283.598906) (xy 425.694106 -283.549852) (xy 425.355258 -283.549852)
			(xy 425.354763 -283.574459) (xy 425.346868 -283.623036) (xy 425.331284 -283.669717) (xy 425.308413 -283.713294)
			(xy 425.278848 -283.752638) (xy 425.243355 -283.78673) (xy 425.202852 -283.814686) (xy 425.15839 -283.835784)
			(xy 425.111119 -283.849476) (xy 425.062264 -283.855408) (xy 425.013089 -283.853427) (xy 424.96487 -283.843583)
			(xy 424.918854 -283.826131) (xy 424.876233 -283.801524) (xy 424.838112 -283.770399) (xy 424.805477 -283.733562)
			(xy 424.779174 -283.691966) (xy 424.759883 -283.64669) (xy 424.748106 -283.598906) (xy 424.744146 -283.549852)
			(xy 424.427142 -283.549852) (xy 424.426638 -283.57556) (xy 424.418595 -283.626342) (xy 424.402707 -283.675241)
			(xy 424.379364 -283.721053) (xy 424.349143 -283.762649) (xy 424.312787 -283.799005) (xy 424.271191 -283.829226)
			(xy 424.225379 -283.852569) (xy 424.17648 -283.868457) (xy 424.125698 -283.8765) (xy 424.074282 -283.8765)
			(xy 424.0235 -283.868457) (xy 423.974601 -283.852569) (xy 423.928789 -283.829226) (xy 423.887193 -283.799005)
			(xy 423.850837 -283.762649) (xy 423.820616 -283.721053) (xy 423.797273 -283.675241) (xy 423.781385 -283.626342)
			(xy 423.773342 -283.57556) (xy 423.476424 -283.57556) (xy 423.468381 -283.626342) (xy 423.452493 -283.675241)
			(xy 423.42915 -283.721053) (xy 423.398929 -283.762649) (xy 423.362573 -283.799005) (xy 423.320977 -283.829226)
			(xy 423.275165 -283.852569) (xy 423.226266 -283.868457) (xy 423.175484 -283.8765) (xy 423.124068 -283.8765)
			(xy 423.073286 -283.868457) (xy 423.024387 -283.852569) (xy 422.978575 -283.829226) (xy 422.936979 -283.799005)
			(xy 422.900623 -283.762649) (xy 422.870402 -283.721053) (xy 422.847059 -283.675241) (xy 422.831171 -283.626342)
			(xy 422.823128 -283.57556) (xy 422.50445 -283.57556) (xy 422.496734 -283.623036) (xy 422.48115 -283.669717)
			(xy 422.458279 -283.713294) (xy 422.428714 -283.752638) (xy 422.393221 -283.78673) (xy 422.352718 -283.814686)
			(xy 422.308256 -283.835784) (xy 422.260985 -283.849476) (xy 422.21213 -283.855408) (xy 422.162955 -283.853427)
			(xy 422.114736 -283.843583) (xy 422.06872 -283.826131) (xy 422.026099 -283.801524) (xy 421.987978 -283.770399)
			(xy 421.955343 -283.733562) (xy 421.92904 -283.691966) (xy 421.909749 -283.64669) (xy 421.897972 -283.598906)
			(xy 421.894012 -283.549852) (xy 396.990824 -283.549852) (xy 396.990824 -283.623258) (xy 396.990992 -283.629412)
			(xy 396.993943 -283.641359) (xy 396.996666 -283.64688) (xy 397.004794 -283.658056) (xy 397.019526 -283.67355)
			(xy 397.02613 -283.680662) (xy 397.05026 -283.691838) (xy 397.054578 -283.693108) (xy 397.066008 -283.696664)
			(xy 397.070072 -283.697172) (xy 397.096114 -283.70128) (xy 397.146535 -283.716674) (xy 397.193875 -283.739872)
			(xy 397.236936 -283.770286) (xy 397.274626 -283.807145) (xy 397.305992 -283.849518) (xy 397.330239 -283.896329)
			(xy 397.346753 -283.946394) (xy 397.355115 -283.998445) (xy 397.355115 -284.024832) (xy 397.669016 -284.024832)
			(xy 397.672976 -283.975778) (xy 397.684753 -283.927994) (xy 397.704044 -283.882718) (xy 397.730347 -283.841122)
			(xy 397.762982 -283.804285) (xy 397.801103 -283.77316) (xy 397.843724 -283.748553) (xy 397.88974 -283.731101)
			(xy 397.937959 -283.721257) (xy 397.987134 -283.719276) (xy 398.035989 -283.725208) (xy 398.08326 -283.7389)
			(xy 398.127722 -283.759998) (xy 398.168225 -283.787954) (xy 398.203718 -283.822046) (xy 398.233283 -283.86139)
			(xy 398.256154 -283.904967) (xy 398.271738 -283.951648) (xy 398.279633 -284.000225) (xy 398.280128 -284.024832)
			(xy 398.61923 -284.024832) (xy 398.62319 -283.975778) (xy 398.634967 -283.927994) (xy 398.654258 -283.882718)
			(xy 398.680561 -283.841122) (xy 398.713196 -283.804285) (xy 398.751317 -283.77316) (xy 398.793938 -283.748553)
			(xy 398.839954 -283.731101) (xy 398.888173 -283.721257) (xy 398.937348 -283.719276) (xy 398.986203 -283.725208)
			(xy 399.033474 -283.7389) (xy 399.077936 -283.759998) (xy 399.118439 -283.787954) (xy 399.153932 -283.822046)
			(xy 399.183497 -283.86139) (xy 399.206368 -283.904967) (xy 399.221952 -283.951648) (xy 399.229847 -284.000225)
			(xy 399.230342 -284.024832) (xy 399.56919 -284.024832) (xy 399.57315 -283.975778) (xy 399.584927 -283.927994)
			(xy 399.604218 -283.882718) (xy 399.630521 -283.841122) (xy 399.663156 -283.804285) (xy 399.701277 -283.77316)
			(xy 399.743898 -283.748553) (xy 399.789914 -283.731101) (xy 399.838133 -283.721257) (xy 399.887308 -283.719276)
			(xy 399.936163 -283.725208) (xy 399.983434 -283.7389) (xy 400.027896 -283.759998) (xy 400.068399 -283.787954)
			(xy 400.103892 -283.822046) (xy 400.133457 -283.86139) (xy 400.156328 -283.904967) (xy 400.171912 -283.951648)
			(xy 400.179807 -284.000225) (xy 400.180302 -284.024832) (xy 400.51915 -284.024832) (xy 400.52311 -283.975778)
			(xy 400.534887 -283.927994) (xy 400.554178 -283.882718) (xy 400.580481 -283.841122) (xy 400.613116 -283.804285)
			(xy 400.651237 -283.77316) (xy 400.693858 -283.748553) (xy 400.739874 -283.731101) (xy 400.788093 -283.721257)
			(xy 400.837268 -283.719276) (xy 400.886123 -283.725208) (xy 400.933394 -283.7389) (xy 400.977856 -283.759998)
			(xy 401.018359 -283.787954) (xy 401.053852 -283.822046) (xy 401.083417 -283.86139) (xy 401.106288 -283.904967)
			(xy 401.121872 -283.951648) (xy 401.129767 -284.000225) (xy 401.130262 -284.024832) (xy 401.46911 -284.024832)
			(xy 401.47307 -283.975778) (xy 401.484847 -283.927994) (xy 401.504138 -283.882718) (xy 401.530441 -283.841122)
			(xy 401.563076 -283.804285) (xy 401.601197 -283.77316) (xy 401.643818 -283.748553) (xy 401.689834 -283.731101)
			(xy 401.738053 -283.721257) (xy 401.787228 -283.719276) (xy 401.836083 -283.725208) (xy 401.883354 -283.7389)
			(xy 401.927816 -283.759998) (xy 401.968319 -283.787954) (xy 402.003812 -283.822046) (xy 402.033377 -283.86139)
			(xy 402.056248 -283.904967) (xy 402.071832 -283.951648) (xy 402.079727 -284.000225) (xy 402.080222 -284.024832)
			(xy 402.41907 -284.024832) (xy 402.42303 -283.975778) (xy 402.434807 -283.927994) (xy 402.454098 -283.882718)
			(xy 402.480401 -283.841122) (xy 402.513036 -283.804285) (xy 402.551157 -283.77316) (xy 402.593778 -283.748553)
			(xy 402.639794 -283.731101) (xy 402.688013 -283.721257) (xy 402.737188 -283.719276) (xy 402.786043 -283.725208)
			(xy 402.833314 -283.7389) (xy 402.877776 -283.759998) (xy 402.918279 -283.787954) (xy 402.953772 -283.822046)
			(xy 402.983337 -283.86139) (xy 403.006208 -283.904967) (xy 403.021792 -283.951648) (xy 403.029687 -284.000225)
			(xy 403.030182 -284.024832) (xy 403.36903 -284.024832) (xy 403.37299 -283.975778) (xy 403.384767 -283.927994)
			(xy 403.404058 -283.882718) (xy 403.430361 -283.841122) (xy 403.462996 -283.804285) (xy 403.501117 -283.77316)
			(xy 403.543738 -283.748553) (xy 403.589754 -283.731101) (xy 403.637973 -283.721257) (xy 403.687148 -283.719276)
			(xy 403.736003 -283.725208) (xy 403.783274 -283.7389) (xy 403.827736 -283.759998) (xy 403.868239 -283.787954)
			(xy 403.903732 -283.822046) (xy 403.933297 -283.86139) (xy 403.956168 -283.904967) (xy 403.971752 -283.951648)
			(xy 403.979647 -284.000225) (xy 403.980142 -284.024832) (xy 404.31899 -284.024832) (xy 404.32295 -283.975778)
			(xy 404.334727 -283.927994) (xy 404.354018 -283.882718) (xy 404.380321 -283.841122) (xy 404.412956 -283.804285)
			(xy 404.451077 -283.77316) (xy 404.493698 -283.748553) (xy 404.539714 -283.731101) (xy 404.587933 -283.721257)
			(xy 404.637108 -283.719276) (xy 404.685963 -283.725208) (xy 404.733234 -283.7389) (xy 404.777696 -283.759998)
			(xy 404.818199 -283.787954) (xy 404.853692 -283.822046) (xy 404.883257 -283.86139) (xy 404.906128 -283.904967)
			(xy 404.921712 -283.951648) (xy 404.929607 -284.000225) (xy 404.930102 -284.024832) (xy 405.269204 -284.024832)
			(xy 405.273164 -283.975778) (xy 405.284941 -283.927994) (xy 405.304232 -283.882718) (xy 405.330535 -283.841122)
			(xy 405.36317 -283.804285) (xy 405.401291 -283.77316) (xy 405.443912 -283.748553) (xy 405.489928 -283.731101)
			(xy 405.538147 -283.721257) (xy 405.587322 -283.719276) (xy 405.636177 -283.725208) (xy 405.683448 -283.7389)
			(xy 405.72791 -283.759998) (xy 405.768413 -283.787954) (xy 405.803906 -283.822046) (xy 405.833471 -283.86139)
			(xy 405.856342 -283.904967) (xy 405.871926 -283.951648) (xy 405.879821 -284.000225) (xy 405.880316 -284.024832)
			(xy 406.219164 -284.024832) (xy 406.223124 -283.975778) (xy 406.234901 -283.927994) (xy 406.254192 -283.882718)
			(xy 406.280495 -283.841122) (xy 406.31313 -283.804285) (xy 406.351251 -283.77316) (xy 406.393872 -283.748553)
			(xy 406.439888 -283.731101) (xy 406.488107 -283.721257) (xy 406.537282 -283.719276) (xy 406.586137 -283.725208)
			(xy 406.633408 -283.7389) (xy 406.67787 -283.759998) (xy 406.718373 -283.787954) (xy 406.753866 -283.822046)
			(xy 406.783431 -283.86139) (xy 406.806302 -283.904967) (xy 406.821886 -283.951648) (xy 406.829781 -284.000225)
			(xy 406.830276 -284.024832) (xy 408.119084 -284.024832) (xy 408.123044 -283.975778) (xy 408.134821 -283.927994)
			(xy 408.154112 -283.882718) (xy 408.180415 -283.841122) (xy 408.21305 -283.804285) (xy 408.251171 -283.77316)
			(xy 408.293792 -283.748553) (xy 408.339808 -283.731101) (xy 408.388027 -283.721257) (xy 408.437202 -283.719276)
			(xy 408.486057 -283.725208) (xy 408.533328 -283.7389) (xy 408.57779 -283.759998) (xy 408.618293 -283.787954)
			(xy 408.653786 -283.822046) (xy 408.683351 -283.86139) (xy 408.706222 -283.904967) (xy 408.721806 -283.951648)
			(xy 408.729701 -284.000225) (xy 408.730196 -284.024832) (xy 409.069044 -284.024832) (xy 409.073004 -283.975778)
			(xy 409.084781 -283.927994) (xy 409.104072 -283.882718) (xy 409.130375 -283.841122) (xy 409.16301 -283.804285)
			(xy 409.201131 -283.77316) (xy 409.243752 -283.748553) (xy 409.289768 -283.731101) (xy 409.337987 -283.721257)
			(xy 409.387162 -283.719276) (xy 409.436017 -283.725208) (xy 409.483288 -283.7389) (xy 409.52775 -283.759998)
			(xy 409.568253 -283.787954) (xy 409.603746 -283.822046) (xy 409.633311 -283.86139) (xy 409.656182 -283.904967)
			(xy 409.671766 -283.951648) (xy 409.679661 -284.000225) (xy 409.680156 -284.024832) (xy 410.019004 -284.024832)
			(xy 410.022964 -283.975778) (xy 410.034741 -283.927994) (xy 410.054032 -283.882718) (xy 410.080335 -283.841122)
			(xy 410.11297 -283.804285) (xy 410.151091 -283.77316) (xy 410.193712 -283.748553) (xy 410.239728 -283.731101)
			(xy 410.287947 -283.721257) (xy 410.337122 -283.719276) (xy 410.385977 -283.725208) (xy 410.433248 -283.7389)
			(xy 410.47771 -283.759998) (xy 410.518213 -283.787954) (xy 410.553706 -283.822046) (xy 410.583271 -283.86139)
			(xy 410.606142 -283.904967) (xy 410.621726 -283.951648) (xy 410.629621 -284.000225) (xy 410.630116 -284.024832)
			(xy 410.969218 -284.024832) (xy 410.973178 -283.975778) (xy 410.984955 -283.927994) (xy 411.004246 -283.882718)
			(xy 411.030549 -283.841122) (xy 411.063184 -283.804285) (xy 411.101305 -283.77316) (xy 411.143926 -283.748553)
			(xy 411.189942 -283.731101) (xy 411.238161 -283.721257) (xy 411.287336 -283.719276) (xy 411.336191 -283.725208)
			(xy 411.383462 -283.7389) (xy 411.427924 -283.759998) (xy 411.468427 -283.787954) (xy 411.50392 -283.822046)
			(xy 411.533485 -283.86139) (xy 411.556356 -283.904967) (xy 411.57194 -283.951648) (xy 411.579835 -284.000225)
			(xy 411.58033 -284.024832) (xy 411.919178 -284.024832) (xy 411.923138 -283.975778) (xy 411.934915 -283.927994)
			(xy 411.954206 -283.882718) (xy 411.980509 -283.841122) (xy 412.013144 -283.804285) (xy 412.051265 -283.77316)
			(xy 412.093886 -283.748553) (xy 412.139902 -283.731101) (xy 412.188121 -283.721257) (xy 412.237296 -283.719276)
			(xy 412.286151 -283.725208) (xy 412.333422 -283.7389) (xy 412.377884 -283.759998) (xy 412.418387 -283.787954)
			(xy 412.45388 -283.822046) (xy 412.483445 -283.86139) (xy 412.506316 -283.904967) (xy 412.5219 -283.951648)
			(xy 412.529795 -284.000225) (xy 412.53029 -284.024832) (xy 412.869138 -284.024832) (xy 412.873098 -283.975778)
			(xy 412.884875 -283.927994) (xy 412.904166 -283.882718) (xy 412.930469 -283.841122) (xy 412.963104 -283.804285)
			(xy 413.001225 -283.77316) (xy 413.043846 -283.748553) (xy 413.089862 -283.731101) (xy 413.138081 -283.721257)
			(xy 413.187256 -283.719276) (xy 413.236111 -283.725208) (xy 413.283382 -283.7389) (xy 413.327844 -283.759998)
			(xy 413.368347 -283.787954) (xy 413.40384 -283.822046) (xy 413.433405 -283.86139) (xy 413.456276 -283.904967)
			(xy 413.47186 -283.951648) (xy 413.479755 -284.000225) (xy 413.48025 -284.024832) (xy 413.819098 -284.024832)
			(xy 413.823058 -283.975778) (xy 413.834835 -283.927994) (xy 413.854126 -283.882718) (xy 413.880429 -283.841122)
			(xy 413.913064 -283.804285) (xy 413.951185 -283.77316) (xy 413.993806 -283.748553) (xy 414.039822 -283.731101)
			(xy 414.088041 -283.721257) (xy 414.137216 -283.719276) (xy 414.186071 -283.725208) (xy 414.233342 -283.7389)
			(xy 414.277804 -283.759998) (xy 414.318307 -283.787954) (xy 414.3538 -283.822046) (xy 414.383365 -283.86139)
			(xy 414.406236 -283.904967) (xy 414.42182 -283.951648) (xy 414.429715 -284.000225) (xy 414.43021 -284.024832)
			(xy 414.769058 -284.024832) (xy 414.773018 -283.975778) (xy 414.784795 -283.927994) (xy 414.804086 -283.882718)
			(xy 414.830389 -283.841122) (xy 414.863024 -283.804285) (xy 414.901145 -283.77316) (xy 414.943766 -283.748553)
			(xy 414.989782 -283.731101) (xy 415.038001 -283.721257) (xy 415.087176 -283.719276) (xy 415.136031 -283.725208)
			(xy 415.183302 -283.7389) (xy 415.227764 -283.759998) (xy 415.268267 -283.787954) (xy 415.30376 -283.822046)
			(xy 415.333325 -283.86139) (xy 415.356196 -283.904967) (xy 415.37178 -283.951648) (xy 415.379675 -284.000225)
			(xy 415.38017 -284.024832) (xy 415.719018 -284.024832) (xy 415.722978 -283.975778) (xy 415.734755 -283.927994)
			(xy 415.754046 -283.882718) (xy 415.780349 -283.841122) (xy 415.812984 -283.804285) (xy 415.851105 -283.77316)
			(xy 415.893726 -283.748553) (xy 415.939742 -283.731101) (xy 415.987961 -283.721257) (xy 416.037136 -283.719276)
			(xy 416.085991 -283.725208) (xy 416.133262 -283.7389) (xy 416.177724 -283.759998) (xy 416.218227 -283.787954)
			(xy 416.25372 -283.822046) (xy 416.283285 -283.86139) (xy 416.306156 -283.904967) (xy 416.32174 -283.951648)
			(xy 416.329635 -284.000225) (xy 416.33013 -284.024832) (xy 416.668978 -284.024832) (xy 416.672938 -283.975778)
			(xy 416.684715 -283.927994) (xy 416.704006 -283.882718) (xy 416.730309 -283.841122) (xy 416.762944 -283.804285)
			(xy 416.801065 -283.77316) (xy 416.843686 -283.748553) (xy 416.889702 -283.731101) (xy 416.937921 -283.721257)
			(xy 416.987096 -283.719276) (xy 417.035951 -283.725208) (xy 417.083222 -283.7389) (xy 417.127684 -283.759998)
			(xy 417.168187 -283.787954) (xy 417.20368 -283.822046) (xy 417.233245 -283.86139) (xy 417.256116 -283.904967)
			(xy 417.2717 -283.951648) (xy 417.279595 -284.000225) (xy 417.28009 -284.024832) (xy 417.619192 -284.024832)
			(xy 417.623152 -283.975778) (xy 417.634929 -283.927994) (xy 417.65422 -283.882718) (xy 417.680523 -283.841122)
			(xy 417.713158 -283.804285) (xy 417.751279 -283.77316) (xy 417.7939 -283.748553) (xy 417.839916 -283.731101)
			(xy 417.888135 -283.721257) (xy 417.93731 -283.719276) (xy 417.986165 -283.725208) (xy 418.033436 -283.7389)
			(xy 418.077898 -283.759998) (xy 418.118401 -283.787954) (xy 418.153894 -283.822046) (xy 418.183459 -283.86139)
			(xy 418.20633 -283.904967) (xy 418.221914 -283.951648) (xy 418.229809 -284.000225) (xy 418.230304 -284.024832)
			(xy 418.569152 -284.024832) (xy 418.573112 -283.975778) (xy 418.584889 -283.927994) (xy 418.60418 -283.882718)
			(xy 418.630483 -283.841122) (xy 418.663118 -283.804285) (xy 418.701239 -283.77316) (xy 418.74386 -283.748553)
			(xy 418.789876 -283.731101) (xy 418.838095 -283.721257) (xy 418.88727 -283.719276) (xy 418.936125 -283.725208)
			(xy 418.983396 -283.7389) (xy 419.027858 -283.759998) (xy 419.068361 -283.787954) (xy 419.103854 -283.822046)
			(xy 419.133419 -283.86139) (xy 419.15629 -283.904967) (xy 419.171874 -283.951648) (xy 419.179769 -284.000225)
			(xy 419.180264 -284.024832) (xy 419.519112 -284.024832) (xy 419.523072 -283.975778) (xy 419.534849 -283.927994)
			(xy 419.55414 -283.882718) (xy 419.580443 -283.841122) (xy 419.613078 -283.804285) (xy 419.651199 -283.77316)
			(xy 419.69382 -283.748553) (xy 419.739836 -283.731101) (xy 419.788055 -283.721257) (xy 419.83723 -283.719276)
			(xy 419.886085 -283.725208) (xy 419.933356 -283.7389) (xy 419.977818 -283.759998) (xy 420.018321 -283.787954)
			(xy 420.053814 -283.822046) (xy 420.083379 -283.86139) (xy 420.10625 -283.904967) (xy 420.121834 -283.951648)
			(xy 420.129729 -284.000225) (xy 420.130224 -284.024832) (xy 420.469072 -284.024832) (xy 420.473032 -283.975778)
			(xy 420.484809 -283.927994) (xy 420.5041 -283.882718) (xy 420.530403 -283.841122) (xy 420.563038 -283.804285)
			(xy 420.601159 -283.77316) (xy 420.64378 -283.748553) (xy 420.689796 -283.731101) (xy 420.738015 -283.721257)
			(xy 420.78719 -283.719276) (xy 420.836045 -283.725208) (xy 420.883316 -283.7389) (xy 420.927778 -283.759998)
			(xy 420.968281 -283.787954) (xy 421.003774 -283.822046) (xy 421.033339 -283.86139) (xy 421.05621 -283.904967)
			(xy 421.071794 -283.951648) (xy 421.079689 -284.000225) (xy 421.080184 -284.024832) (xy 421.079689 -284.049439)
			(xy 421.071794 -284.098016) (xy 421.05621 -284.144697) (xy 421.033339 -284.188274) (xy 421.003774 -284.227618)
			(xy 420.968281 -284.26171) (xy 420.927778 -284.289666) (xy 420.883316 -284.310764) (xy 420.836045 -284.324456)
			(xy 420.78719 -284.330388) (xy 420.738015 -284.328407) (xy 420.689796 -284.318563) (xy 420.64378 -284.301111)
			(xy 420.601159 -284.276504) (xy 420.563038 -284.245379) (xy 420.530403 -284.208542) (xy 420.5041 -284.166946)
			(xy 420.484809 -284.12167) (xy 420.473032 -284.073886) (xy 420.469072 -284.024832) (xy 420.130224 -284.024832)
			(xy 420.129729 -284.049439) (xy 420.121834 -284.098016) (xy 420.10625 -284.144697) (xy 420.083379 -284.188274)
			(xy 420.053814 -284.227618) (xy 420.018321 -284.26171) (xy 419.977818 -284.289666) (xy 419.933356 -284.310764)
			(xy 419.886085 -284.324456) (xy 419.83723 -284.330388) (xy 419.788055 -284.328407) (xy 419.739836 -284.318563)
			(xy 419.69382 -284.301111) (xy 419.651199 -284.276504) (xy 419.613078 -284.245379) (xy 419.580443 -284.208542)
			(xy 419.55414 -284.166946) (xy 419.534849 -284.12167) (xy 419.523072 -284.073886) (xy 419.519112 -284.024832)
			(xy 419.180264 -284.024832) (xy 419.179769 -284.049439) (xy 419.171874 -284.098016) (xy 419.15629 -284.144697)
			(xy 419.133419 -284.188274) (xy 419.103854 -284.227618) (xy 419.068361 -284.26171) (xy 419.027858 -284.289666)
			(xy 418.983396 -284.310764) (xy 418.936125 -284.324456) (xy 418.88727 -284.330388) (xy 418.838095 -284.328407)
			(xy 418.789876 -284.318563) (xy 418.74386 -284.301111) (xy 418.701239 -284.276504) (xy 418.663118 -284.245379)
			(xy 418.630483 -284.208542) (xy 418.60418 -284.166946) (xy 418.584889 -284.12167) (xy 418.573112 -284.073886)
			(xy 418.569152 -284.024832) (xy 418.230304 -284.024832) (xy 418.229809 -284.049439) (xy 418.221914 -284.098016)
			(xy 418.20633 -284.144697) (xy 418.183459 -284.188274) (xy 418.153894 -284.227618) (xy 418.118401 -284.26171)
			(xy 418.077898 -284.289666) (xy 418.033436 -284.310764) (xy 417.986165 -284.324456) (xy 417.93731 -284.330388)
			(xy 417.888135 -284.328407) (xy 417.839916 -284.318563) (xy 417.7939 -284.301111) (xy 417.751279 -284.276504)
			(xy 417.713158 -284.245379) (xy 417.680523 -284.208542) (xy 417.65422 -284.166946) (xy 417.634929 -284.12167)
			(xy 417.623152 -284.073886) (xy 417.619192 -284.024832) (xy 417.28009 -284.024832) (xy 417.279595 -284.049439)
			(xy 417.2717 -284.098016) (xy 417.256116 -284.144697) (xy 417.233245 -284.188274) (xy 417.20368 -284.227618)
			(xy 417.168187 -284.26171) (xy 417.127684 -284.289666) (xy 417.083222 -284.310764) (xy 417.035951 -284.324456)
			(xy 416.987096 -284.330388) (xy 416.937921 -284.328407) (xy 416.889702 -284.318563) (xy 416.843686 -284.301111)
			(xy 416.801065 -284.276504) (xy 416.762944 -284.245379) (xy 416.730309 -284.208542) (xy 416.704006 -284.166946)
			(xy 416.684715 -284.12167) (xy 416.672938 -284.073886) (xy 416.668978 -284.024832) (xy 416.33013 -284.024832)
			(xy 416.329635 -284.049439) (xy 416.32174 -284.098016) (xy 416.306156 -284.144697) (xy 416.283285 -284.188274)
			(xy 416.25372 -284.227618) (xy 416.218227 -284.26171) (xy 416.177724 -284.289666) (xy 416.133262 -284.310764)
			(xy 416.085991 -284.324456) (xy 416.037136 -284.330388) (xy 415.987961 -284.328407) (xy 415.939742 -284.318563)
			(xy 415.893726 -284.301111) (xy 415.851105 -284.276504) (xy 415.812984 -284.245379) (xy 415.780349 -284.208542)
			(xy 415.754046 -284.166946) (xy 415.734755 -284.12167) (xy 415.722978 -284.073886) (xy 415.719018 -284.024832)
			(xy 415.38017 -284.024832) (xy 415.379675 -284.049439) (xy 415.37178 -284.098016) (xy 415.356196 -284.144697)
			(xy 415.333325 -284.188274) (xy 415.30376 -284.227618) (xy 415.268267 -284.26171) (xy 415.227764 -284.289666)
			(xy 415.183302 -284.310764) (xy 415.136031 -284.324456) (xy 415.087176 -284.330388) (xy 415.038001 -284.328407)
			(xy 414.989782 -284.318563) (xy 414.943766 -284.301111) (xy 414.901145 -284.276504) (xy 414.863024 -284.245379)
			(xy 414.830389 -284.208542) (xy 414.804086 -284.166946) (xy 414.784795 -284.12167) (xy 414.773018 -284.073886)
			(xy 414.769058 -284.024832) (xy 414.43021 -284.024832) (xy 414.429715 -284.049439) (xy 414.42182 -284.098016)
			(xy 414.406236 -284.144697) (xy 414.383365 -284.188274) (xy 414.3538 -284.227618) (xy 414.318307 -284.26171)
			(xy 414.277804 -284.289666) (xy 414.233342 -284.310764) (xy 414.186071 -284.324456) (xy 414.137216 -284.330388)
			(xy 414.088041 -284.328407) (xy 414.039822 -284.318563) (xy 413.993806 -284.301111) (xy 413.951185 -284.276504)
			(xy 413.913064 -284.245379) (xy 413.880429 -284.208542) (xy 413.854126 -284.166946) (xy 413.834835 -284.12167)
			(xy 413.823058 -284.073886) (xy 413.819098 -284.024832) (xy 413.48025 -284.024832) (xy 413.479755 -284.049439)
			(xy 413.47186 -284.098016) (xy 413.456276 -284.144697) (xy 413.433405 -284.188274) (xy 413.40384 -284.227618)
			(xy 413.368347 -284.26171) (xy 413.327844 -284.289666) (xy 413.283382 -284.310764) (xy 413.236111 -284.324456)
			(xy 413.187256 -284.330388) (xy 413.138081 -284.328407) (xy 413.089862 -284.318563) (xy 413.043846 -284.301111)
			(xy 413.001225 -284.276504) (xy 412.963104 -284.245379) (xy 412.930469 -284.208542) (xy 412.904166 -284.166946)
			(xy 412.884875 -284.12167) (xy 412.873098 -284.073886) (xy 412.869138 -284.024832) (xy 412.53029 -284.024832)
			(xy 412.529795 -284.049439) (xy 412.5219 -284.098016) (xy 412.506316 -284.144697) (xy 412.483445 -284.188274)
			(xy 412.45388 -284.227618) (xy 412.418387 -284.26171) (xy 412.377884 -284.289666) (xy 412.333422 -284.310764)
			(xy 412.286151 -284.324456) (xy 412.237296 -284.330388) (xy 412.188121 -284.328407) (xy 412.139902 -284.318563)
			(xy 412.093886 -284.301111) (xy 412.051265 -284.276504) (xy 412.013144 -284.245379) (xy 411.980509 -284.208542)
			(xy 411.954206 -284.166946) (xy 411.934915 -284.12167) (xy 411.923138 -284.073886) (xy 411.919178 -284.024832)
			(xy 411.58033 -284.024832) (xy 411.579835 -284.049439) (xy 411.57194 -284.098016) (xy 411.556356 -284.144697)
			(xy 411.533485 -284.188274) (xy 411.50392 -284.227618) (xy 411.468427 -284.26171) (xy 411.427924 -284.289666)
			(xy 411.383462 -284.310764) (xy 411.336191 -284.324456) (xy 411.287336 -284.330388) (xy 411.238161 -284.328407)
			(xy 411.189942 -284.318563) (xy 411.143926 -284.301111) (xy 411.101305 -284.276504) (xy 411.063184 -284.245379)
			(xy 411.030549 -284.208542) (xy 411.004246 -284.166946) (xy 410.984955 -284.12167) (xy 410.973178 -284.073886)
			(xy 410.969218 -284.024832) (xy 410.630116 -284.024832) (xy 410.629621 -284.049439) (xy 410.621726 -284.098016)
			(xy 410.606142 -284.144697) (xy 410.583271 -284.188274) (xy 410.553706 -284.227618) (xy 410.518213 -284.26171)
			(xy 410.47771 -284.289666) (xy 410.433248 -284.310764) (xy 410.385977 -284.324456) (xy 410.337122 -284.330388)
			(xy 410.287947 -284.328407) (xy 410.239728 -284.318563) (xy 410.193712 -284.301111) (xy 410.151091 -284.276504)
			(xy 410.11297 -284.245379) (xy 410.080335 -284.208542) (xy 410.054032 -284.166946) (xy 410.034741 -284.12167)
			(xy 410.022964 -284.073886) (xy 410.019004 -284.024832) (xy 409.680156 -284.024832) (xy 409.679661 -284.049439)
			(xy 409.671766 -284.098016) (xy 409.656182 -284.144697) (xy 409.633311 -284.188274) (xy 409.603746 -284.227618)
			(xy 409.568253 -284.26171) (xy 409.52775 -284.289666) (xy 409.483288 -284.310764) (xy 409.436017 -284.324456)
			(xy 409.387162 -284.330388) (xy 409.337987 -284.328407) (xy 409.289768 -284.318563) (xy 409.243752 -284.301111)
			(xy 409.201131 -284.276504) (xy 409.16301 -284.245379) (xy 409.130375 -284.208542) (xy 409.104072 -284.166946)
			(xy 409.084781 -284.12167) (xy 409.073004 -284.073886) (xy 409.069044 -284.024832) (xy 408.730196 -284.024832)
			(xy 408.729701 -284.049439) (xy 408.721806 -284.098016) (xy 408.706222 -284.144697) (xy 408.683351 -284.188274)
			(xy 408.653786 -284.227618) (xy 408.618293 -284.26171) (xy 408.57779 -284.289666) (xy 408.533328 -284.310764)
			(xy 408.486057 -284.324456) (xy 408.437202 -284.330388) (xy 408.388027 -284.328407) (xy 408.339808 -284.318563)
			(xy 408.293792 -284.301111) (xy 408.251171 -284.276504) (xy 408.21305 -284.245379) (xy 408.180415 -284.208542)
			(xy 408.154112 -284.166946) (xy 408.134821 -284.12167) (xy 408.123044 -284.073886) (xy 408.119084 -284.024832)
			(xy 406.830276 -284.024832) (xy 406.829781 -284.049439) (xy 406.821886 -284.098016) (xy 406.806302 -284.144697)
			(xy 406.783431 -284.188274) (xy 406.753866 -284.227618) (xy 406.718373 -284.26171) (xy 406.67787 -284.289666)
			(xy 406.633408 -284.310764) (xy 406.586137 -284.324456) (xy 406.537282 -284.330388) (xy 406.488107 -284.328407)
			(xy 406.439888 -284.318563) (xy 406.393872 -284.301111) (xy 406.351251 -284.276504) (xy 406.31313 -284.245379)
			(xy 406.280495 -284.208542) (xy 406.254192 -284.166946) (xy 406.234901 -284.12167) (xy 406.223124 -284.073886)
			(xy 406.219164 -284.024832) (xy 405.880316 -284.024832) (xy 405.879821 -284.049439) (xy 405.871926 -284.098016)
			(xy 405.856342 -284.144697) (xy 405.833471 -284.188274) (xy 405.803906 -284.227618) (xy 405.768413 -284.26171)
			(xy 405.72791 -284.289666) (xy 405.683448 -284.310764) (xy 405.636177 -284.324456) (xy 405.587322 -284.330388)
			(xy 405.538147 -284.328407) (xy 405.489928 -284.318563) (xy 405.443912 -284.301111) (xy 405.401291 -284.276504)
			(xy 405.36317 -284.245379) (xy 405.330535 -284.208542) (xy 405.304232 -284.166946) (xy 405.284941 -284.12167)
			(xy 405.273164 -284.073886) (xy 405.269204 -284.024832) (xy 404.930102 -284.024832) (xy 404.929607 -284.049439)
			(xy 404.921712 -284.098016) (xy 404.906128 -284.144697) (xy 404.883257 -284.188274) (xy 404.853692 -284.227618)
			(xy 404.818199 -284.26171) (xy 404.777696 -284.289666) (xy 404.733234 -284.310764) (xy 404.685963 -284.324456)
			(xy 404.637108 -284.330388) (xy 404.587933 -284.328407) (xy 404.539714 -284.318563) (xy 404.493698 -284.301111)
			(xy 404.451077 -284.276504) (xy 404.412956 -284.245379) (xy 404.380321 -284.208542) (xy 404.354018 -284.166946)
			(xy 404.334727 -284.12167) (xy 404.32295 -284.073886) (xy 404.31899 -284.024832) (xy 403.980142 -284.024832)
			(xy 403.979647 -284.049439) (xy 403.971752 -284.098016) (xy 403.956168 -284.144697) (xy 403.933297 -284.188274)
			(xy 403.903732 -284.227618) (xy 403.868239 -284.26171) (xy 403.827736 -284.289666) (xy 403.783274 -284.310764)
			(xy 403.736003 -284.324456) (xy 403.687148 -284.330388) (xy 403.637973 -284.328407) (xy 403.589754 -284.318563)
			(xy 403.543738 -284.301111) (xy 403.501117 -284.276504) (xy 403.462996 -284.245379) (xy 403.430361 -284.208542)
			(xy 403.404058 -284.166946) (xy 403.384767 -284.12167) (xy 403.37299 -284.073886) (xy 403.36903 -284.024832)
			(xy 403.030182 -284.024832) (xy 403.029687 -284.049439) (xy 403.021792 -284.098016) (xy 403.006208 -284.144697)
			(xy 402.983337 -284.188274) (xy 402.953772 -284.227618) (xy 402.918279 -284.26171) (xy 402.877776 -284.289666)
			(xy 402.833314 -284.310764) (xy 402.786043 -284.324456) (xy 402.737188 -284.330388) (xy 402.688013 -284.328407)
			(xy 402.639794 -284.318563) (xy 402.593778 -284.301111) (xy 402.551157 -284.276504) (xy 402.513036 -284.245379)
			(xy 402.480401 -284.208542) (xy 402.454098 -284.166946) (xy 402.434807 -284.12167) (xy 402.42303 -284.073886)
			(xy 402.41907 -284.024832) (xy 402.080222 -284.024832) (xy 402.079727 -284.049439) (xy 402.071832 -284.098016)
			(xy 402.056248 -284.144697) (xy 402.033377 -284.188274) (xy 402.003812 -284.227618) (xy 401.968319 -284.26171)
			(xy 401.927816 -284.289666) (xy 401.883354 -284.310764) (xy 401.836083 -284.324456) (xy 401.787228 -284.330388)
			(xy 401.738053 -284.328407) (xy 401.689834 -284.318563) (xy 401.643818 -284.301111) (xy 401.601197 -284.276504)
			(xy 401.563076 -284.245379) (xy 401.530441 -284.208542) (xy 401.504138 -284.166946) (xy 401.484847 -284.12167)
			(xy 401.47307 -284.073886) (xy 401.46911 -284.024832) (xy 401.130262 -284.024832) (xy 401.129767 -284.049439)
			(xy 401.121872 -284.098016) (xy 401.106288 -284.144697) (xy 401.083417 -284.188274) (xy 401.053852 -284.227618)
			(xy 401.018359 -284.26171) (xy 400.977856 -284.289666) (xy 400.933394 -284.310764) (xy 400.886123 -284.324456)
			(xy 400.837268 -284.330388) (xy 400.788093 -284.328407) (xy 400.739874 -284.318563) (xy 400.693858 -284.301111)
			(xy 400.651237 -284.276504) (xy 400.613116 -284.245379) (xy 400.580481 -284.208542) (xy 400.554178 -284.166946)
			(xy 400.534887 -284.12167) (xy 400.52311 -284.073886) (xy 400.51915 -284.024832) (xy 400.180302 -284.024832)
			(xy 400.179807 -284.049439) (xy 400.171912 -284.098016) (xy 400.156328 -284.144697) (xy 400.133457 -284.188274)
			(xy 400.103892 -284.227618) (xy 400.068399 -284.26171) (xy 400.027896 -284.289666) (xy 399.983434 -284.310764)
			(xy 399.936163 -284.324456) (xy 399.887308 -284.330388) (xy 399.838133 -284.328407) (xy 399.789914 -284.318563)
			(xy 399.743898 -284.301111) (xy 399.701277 -284.276504) (xy 399.663156 -284.245379) (xy 399.630521 -284.208542)
			(xy 399.604218 -284.166946) (xy 399.584927 -284.12167) (xy 399.57315 -284.073886) (xy 399.56919 -284.024832)
			(xy 399.230342 -284.024832) (xy 399.229847 -284.049439) (xy 399.221952 -284.098016) (xy 399.206368 -284.144697)
			(xy 399.183497 -284.188274) (xy 399.153932 -284.227618) (xy 399.118439 -284.26171) (xy 399.077936 -284.289666)
			(xy 399.033474 -284.310764) (xy 398.986203 -284.324456) (xy 398.937348 -284.330388) (xy 398.888173 -284.328407)
			(xy 398.839954 -284.318563) (xy 398.793938 -284.301111) (xy 398.751317 -284.276504) (xy 398.713196 -284.245379)
			(xy 398.680561 -284.208542) (xy 398.654258 -284.166946) (xy 398.634967 -284.12167) (xy 398.62319 -284.073886)
			(xy 398.61923 -284.024832) (xy 398.280128 -284.024832) (xy 398.279633 -284.049439) (xy 398.271738 -284.098016)
			(xy 398.256154 -284.144697) (xy 398.233283 -284.188274) (xy 398.203718 -284.227618) (xy 398.168225 -284.26171)
			(xy 398.127722 -284.289666) (xy 398.08326 -284.310764) (xy 398.035989 -284.324456) (xy 397.987134 -284.330388)
			(xy 397.937959 -284.328407) (xy 397.88974 -284.318563) (xy 397.843724 -284.301111) (xy 397.801103 -284.276504)
			(xy 397.762982 -284.245379) (xy 397.730347 -284.208542) (xy 397.704044 -284.166946) (xy 397.684753 -284.12167)
			(xy 397.672976 -284.073886) (xy 397.669016 -284.024832) (xy 397.355115 -284.024832) (xy 397.355115 -284.051164)
			(xy 397.346751 -284.103214) (xy 397.330236 -284.153279) (xy 397.305988 -284.20009) (xy 397.274621 -284.242461)
			(xy 397.236929 -284.27932) (xy 397.193868 -284.309733) (xy 397.146527 -284.332929) (xy 397.096106 -284.348322)
			(xy 397.070072 -284.352492) (xy 397.066008 -284.353) (xy 397.054578 -284.356556) (xy 397.05026 -284.357826)
			(xy 397.02613 -284.369002) (xy 397.019526 -284.376114) (xy 397.004794 -284.391608) (xy 396.996666 -284.402784)
			(xy 396.993972 -284.408316) (xy 396.99102 -284.420256) (xy 396.990824 -284.426406) (xy 396.990824 -284.499812)
			(xy 421.894012 -284.499812) (xy 421.897972 -284.450758) (xy 421.909749 -284.402974) (xy 421.92904 -284.357698)
			(xy 421.955343 -284.316102) (xy 421.987978 -284.279265) (xy 422.026099 -284.24814) (xy 422.06872 -284.223533)
			(xy 422.114736 -284.206081) (xy 422.162955 -284.196237) (xy 422.21213 -284.194256) (xy 422.260985 -284.200188)
			(xy 422.308256 -284.21388) (xy 422.352718 -284.234978) (xy 422.393221 -284.262934) (xy 422.428714 -284.297026)
			(xy 422.458279 -284.33637) (xy 422.48115 -284.379947) (xy 422.496734 -284.426628) (xy 422.504629 -284.475205)
			(xy 422.505124 -284.499812) (xy 422.843972 -284.499812) (xy 422.847932 -284.450758) (xy 422.859709 -284.402974)
			(xy 422.879 -284.357698) (xy 422.905303 -284.316102) (xy 422.937938 -284.279265) (xy 422.976059 -284.24814)
			(xy 423.01868 -284.223533) (xy 423.064696 -284.206081) (xy 423.112915 -284.196237) (xy 423.16209 -284.194256)
			(xy 423.210945 -284.200188) (xy 423.258216 -284.21388) (xy 423.302678 -284.234978) (xy 423.343181 -284.262934)
			(xy 423.378674 -284.297026) (xy 423.408239 -284.33637) (xy 423.43111 -284.379947) (xy 423.446694 -284.426628)
			(xy 423.454589 -284.475205) (xy 423.455084 -284.499812) (xy 423.794186 -284.499812) (xy 423.798146 -284.450758)
			(xy 423.809923 -284.402974) (xy 423.829214 -284.357698) (xy 423.855517 -284.316102) (xy 423.888152 -284.279265)
			(xy 423.926273 -284.24814) (xy 423.968894 -284.223533) (xy 424.01491 -284.206081) (xy 424.063129 -284.196237)
			(xy 424.112304 -284.194256) (xy 424.161159 -284.200188) (xy 424.20843 -284.21388) (xy 424.252892 -284.234978)
			(xy 424.293395 -284.262934) (xy 424.328888 -284.297026) (xy 424.358453 -284.33637) (xy 424.381324 -284.379947)
			(xy 424.396908 -284.426628) (xy 424.404803 -284.475205) (xy 424.405298 -284.499812) (xy 424.404803 -284.524419)
			(xy 424.404624 -284.52552) (xy 424.723302 -284.52552) (xy 424.723302 -284.474104) (xy 424.731345 -284.423322)
			(xy 424.747233 -284.374423) (xy 424.770576 -284.328611) (xy 424.800797 -284.287015) (xy 424.837153 -284.250659)
			(xy 424.878749 -284.220438) (xy 424.924561 -284.197095) (xy 424.97346 -284.181207) (xy 425.024242 -284.173164)
			(xy 425.075658 -284.173164) (xy 425.12644 -284.181207) (xy 425.175339 -284.197095) (xy 425.221151 -284.220438)
			(xy 425.262747 -284.250659) (xy 425.299103 -284.287015) (xy 425.329324 -284.328611) (xy 425.352667 -284.374423)
			(xy 425.368555 -284.423322) (xy 425.376598 -284.474104) (xy 425.377102 -284.499812) (xy 425.376598 -284.52552)
			(xy 425.673262 -284.52552) (xy 425.673262 -284.474104) (xy 425.681305 -284.423322) (xy 425.697193 -284.374423)
			(xy 425.720536 -284.328611) (xy 425.750757 -284.287015) (xy 425.787113 -284.250659) (xy 425.828709 -284.220438)
			(xy 425.874521 -284.197095) (xy 425.92342 -284.181207) (xy 425.974202 -284.173164) (xy 426.025618 -284.173164)
			(xy 426.0764 -284.181207) (xy 426.125299 -284.197095) (xy 426.171111 -284.220438) (xy 426.212707 -284.250659)
			(xy 426.249063 -284.287015) (xy 426.279284 -284.328611) (xy 426.302627 -284.374423) (xy 426.318515 -284.423322)
			(xy 426.326558 -284.474104) (xy 426.327062 -284.499812) (xy 426.644066 -284.499812) (xy 426.648026 -284.450758)
			(xy 426.659803 -284.402974) (xy 426.679094 -284.357698) (xy 426.705397 -284.316102) (xy 426.738032 -284.279265)
			(xy 426.776153 -284.24814) (xy 426.818774 -284.223533) (xy 426.86479 -284.206081) (xy 426.913009 -284.196237)
			(xy 426.962184 -284.194256) (xy 427.011039 -284.200188) (xy 427.05831 -284.21388) (xy 427.102772 -284.234978)
			(xy 427.143275 -284.262934) (xy 427.178768 -284.297026) (xy 427.208333 -284.33637) (xy 427.231204 -284.379947)
			(xy 427.246788 -284.426628) (xy 427.254683 -284.475205) (xy 427.255178 -284.499812) (xy 427.254683 -284.524419)
			(xy 427.254504 -284.52552) (xy 427.573182 -284.52552) (xy 427.573182 -284.474104) (xy 427.581225 -284.423322)
			(xy 427.597113 -284.374423) (xy 427.620456 -284.328611) (xy 427.650677 -284.287015) (xy 427.687033 -284.250659)
			(xy 427.728629 -284.220438) (xy 427.774441 -284.197095) (xy 427.82334 -284.181207) (xy 427.874122 -284.173164)
			(xy 427.925538 -284.173164) (xy 427.97632 -284.181207) (xy 428.025219 -284.197095) (xy 428.071031 -284.220438)
			(xy 428.112627 -284.250659) (xy 428.148983 -284.287015) (xy 428.179204 -284.328611) (xy 428.202547 -284.374423)
			(xy 428.218435 -284.423322) (xy 428.226478 -284.474104) (xy 428.226982 -284.499812) (xy 428.226478 -284.52552)
			(xy 428.523142 -284.52552) (xy 428.523142 -284.474104) (xy 428.531185 -284.423322) (xy 428.547073 -284.374423)
			(xy 428.570416 -284.328611) (xy 428.600637 -284.287015) (xy 428.636993 -284.250659) (xy 428.678589 -284.220438)
			(xy 428.724401 -284.197095) (xy 428.7733 -284.181207) (xy 428.824082 -284.173164) (xy 428.875498 -284.173164)
			(xy 428.92628 -284.181207) (xy 428.975179 -284.197095) (xy 429.020991 -284.220438) (xy 429.062587 -284.250659)
			(xy 429.098943 -284.287015) (xy 429.129164 -284.328611) (xy 429.152507 -284.374423) (xy 429.168395 -284.423322)
			(xy 429.176438 -284.474104) (xy 429.176942 -284.499812) (xy 429.4942 -284.499812) (xy 429.49816 -284.450758)
			(xy 429.509937 -284.402974) (xy 429.529228 -284.357698) (xy 429.555531 -284.316102) (xy 429.588166 -284.279265)
			(xy 429.626287 -284.24814) (xy 429.668908 -284.223533) (xy 429.714924 -284.206081) (xy 429.763143 -284.196237)
			(xy 429.812318 -284.194256) (xy 429.861173 -284.200188) (xy 429.908444 -284.21388) (xy 429.952906 -284.234978)
			(xy 429.993409 -284.262934) (xy 430.028902 -284.297026) (xy 430.058467 -284.33637) (xy 430.081338 -284.379947)
			(xy 430.096922 -284.426628) (xy 430.104817 -284.475205) (xy 430.105312 -284.499812) (xy 430.44416 -284.499812)
			(xy 430.44812 -284.450758) (xy 430.459897 -284.402974) (xy 430.479188 -284.357698) (xy 430.505491 -284.316102)
			(xy 430.538126 -284.279265) (xy 430.576247 -284.24814) (xy 430.618868 -284.223533) (xy 430.664884 -284.206081)
			(xy 430.713103 -284.196237) (xy 430.762278 -284.194256) (xy 430.811133 -284.200188) (xy 430.858404 -284.21388)
			(xy 430.902866 -284.234978) (xy 430.943369 -284.262934) (xy 430.978862 -284.297026) (xy 431.008427 -284.33637)
			(xy 431.031298 -284.379947) (xy 431.046882 -284.426628) (xy 431.054777 -284.475205) (xy 431.055272 -284.499812)
			(xy 431.054777 -284.524419) (xy 431.046882 -284.572996) (xy 431.031298 -284.619677) (xy 431.008427 -284.663254)
			(xy 430.978862 -284.702598) (xy 430.943369 -284.73669) (xy 430.902866 -284.764646) (xy 430.858404 -284.785744)
			(xy 430.835922 -284.792256) (xy 448.411243 -284.792256) (xy 448.411243 -284.737744) (xy 448.419001 -284.683787)
			(xy 448.43436 -284.631484) (xy 448.457007 -284.581899) (xy 448.48648 -284.536043) (xy 448.52218 -284.494847)
			(xy 448.563379 -284.459153) (xy 448.60924 -284.429685) (xy 448.658827 -284.407044) (xy 448.711132 -284.391692)
			(xy 448.76509 -284.38394) (xy 448.792346 -284.38348) (xy 448.821086 -284.383981) (xy 448.877914 -284.39261)
			(xy 448.932805 -284.409666) (xy 448.984516 -284.434762) (xy 449.031878 -284.467331) (xy 449.053204 -284.486604)
			(xy 449.060316 -284.493208) (xy 449.077842 -284.50032) (xy 449.16725 -284.50032) (xy 449.184776 -284.493208)
			(xy 449.191888 -284.486604) (xy 449.213215 -284.467334) (xy 449.260578 -284.434769) (xy 449.312289 -284.409678)
			(xy 449.36718 -284.392628) (xy 449.424007 -284.384006) (xy 449.481485 -284.384006) (xy 449.538312 -284.392628)
			(xy 449.593203 -284.409678) (xy 449.644914 -284.434769) (xy 449.692277 -284.467334) (xy 449.713604 -284.486604)
			(xy 449.720716 -284.493208) (xy 449.738242 -284.50032) (xy 449.82765 -284.50032) (xy 449.845176 -284.493208)
			(xy 449.852288 -284.486604) (xy 449.873606 -284.467323) (xy 449.920969 -284.434756) (xy 449.972683 -284.409664)
			(xy 450.027576 -284.392616) (xy 450.084406 -284.383998) (xy 450.113146 -284.38348) (xy 450.143268 -284.384076)
			(xy 450.202764 -284.39355) (xy 450.260032 -284.412254) (xy 450.31365 -284.439725) (xy 450.362285 -284.475279)
			(xy 450.38391 -284.496256) (xy 450.391022 -284.503622) (xy 450.409818 -284.511242) (xy 450.502274 -284.511242)
			(xy 450.52107 -284.503622) (xy 450.528182 -284.496256) (xy 450.549801 -284.475269) (xy 450.59843 -284.439699)
			(xy 450.652048 -284.412219) (xy 450.70932 -284.393513) (xy 450.768821 -284.384046) (xy 450.798946 -284.38348)
			(xy 450.826194 -284.383993) (xy 450.880135 -284.391755) (xy 450.932423 -284.407114) (xy 450.981993 -284.429757)
			(xy 451.027836 -284.459223) (xy 451.069019 -284.494914) (xy 451.104704 -284.536101) (xy 451.134165 -284.581948)
			(xy 451.156803 -284.63152) (xy 451.172155 -284.68381) (xy 451.17991 -284.737752) (xy 451.17991 -284.792248)
			(xy 451.179909 -284.792255) (xy 453.090443 -284.792255) (xy 453.090443 -284.737745) (xy 453.098201 -284.683789)
			(xy 453.113559 -284.631487) (xy 453.136205 -284.581903) (xy 453.165677 -284.536047) (xy 453.201376 -284.494852)
			(xy 453.242574 -284.459157) (xy 453.288433 -284.429689) (xy 453.338019 -284.407047) (xy 453.390322 -284.391694)
			(xy 453.444279 -284.383941) (xy 453.471534 -284.38348) (xy 453.500273 -284.383988) (xy 453.557101 -284.392616)
			(xy 453.611992 -284.409669) (xy 453.663703 -284.434764) (xy 453.711065 -284.467332) (xy 453.732392 -284.486604)
			(xy 453.739504 -284.493208) (xy 453.75703 -284.50032) (xy 453.846438 -284.50032) (xy 453.863964 -284.493208)
			(xy 453.871076 -284.486604) (xy 453.892403 -284.467334) (xy 453.939766 -284.434769) (xy 453.991477 -284.409678)
			(xy 454.046368 -284.392628) (xy 454.103195 -284.384006) (xy 454.160673 -284.384006) (xy 454.2175 -284.392628)
			(xy 454.272391 -284.409678) (xy 454.324102 -284.434769) (xy 454.371465 -284.467334) (xy 454.392792 -284.486604)
			(xy 454.399904 -284.493208) (xy 454.41743 -284.50032) (xy 454.506838 -284.50032) (xy 454.524364 -284.493208)
			(xy 454.531476 -284.486604) (xy 454.552799 -284.467328) (xy 454.600161 -284.43476) (xy 454.651873 -284.409668)
			(xy 454.706766 -284.392619) (xy 454.763595 -284.383999) (xy 454.792334 -284.38348) (xy 454.822459 -284.38402)
			(xy 454.881957 -284.393508) (xy 454.939226 -284.412225) (xy 454.992842 -284.439708) (xy 455.041475 -284.475274)
			(xy 455.063098 -284.496256) (xy 455.07021 -284.503622) (xy 455.089006 -284.511242) (xy 455.181462 -284.511242)
			(xy 455.200258 -284.503622) (xy 455.20737 -284.496256) (xy 455.228994 -284.475275) (xy 455.277622 -284.439704)
			(xy 455.331239 -284.412223) (xy 455.388509 -284.393516) (xy 455.44801 -284.384047) (xy 455.478134 -284.38348)
			(xy 455.505383 -284.383993) (xy 455.559325 -284.391753) (xy 455.611614 -284.40711) (xy 455.661185 -284.429753)
			(xy 455.70703 -284.459219) (xy 455.748215 -284.494909) (xy 455.783901 -284.536097) (xy 455.813364 -284.581945)
			(xy 455.836002 -284.631518) (xy 455.851354 -284.683808) (xy 455.85911 -284.737751) (xy 455.85911 -284.792249)
			(xy 455.851354 -284.846192) (xy 455.836002 -284.898482) (xy 455.813364 -284.948055) (xy 455.783901 -284.993903)
			(xy 455.748215 -285.035091) (xy 455.70703 -285.070781) (xy 455.661185 -285.100247) (xy 455.611614 -285.12289)
			(xy 455.559325 -285.138247) (xy 455.505383 -285.146007) (xy 455.478134 -285.146496) (xy 455.448011 -285.145919)
			(xy 455.388514 -285.136442) (xy 455.331245 -285.117733) (xy 455.277628 -285.090258) (xy 455.228994 -285.054699)
			(xy 455.20737 -285.03372) (xy 455.200258 -285.026354) (xy 455.181462 -285.018734) (xy 455.089006 -285.018734)
			(xy 455.07021 -285.026354) (xy 455.063098 -285.03372) (xy 455.041501 -285.05473) (xy 454.992864 -285.090293)
			(xy 454.939241 -285.117768) (xy 454.881964 -285.136469) (xy 454.82246 -285.145932) (xy 454.792334 -285.146496)
			(xy 454.763594 -285.146013) (xy 454.706764 -285.137381) (xy 454.651873 -285.120321) (xy 454.600162 -285.095221)
			(xy 454.552801 -285.062647) (xy 454.531476 -285.043372) (xy 454.524364 -285.036768) (xy 454.506838 -285.029656)
			(xy 454.41743 -285.029656) (xy 454.399904 -285.036768) (xy 454.392792 -285.043372) (xy 454.371465 -285.062642)
			(xy 454.324102 -285.095207) (xy 454.272391 -285.120298) (xy 454.2175 -285.137348) (xy 454.160673 -285.14597)
			(xy 454.103195 -285.14597) (xy 454.046368 -285.137348) (xy 453.991477 -285.120298) (xy 453.939766 -285.095207)
			(xy 453.892403 -285.062642) (xy 453.871076 -285.043372) (xy 453.863964 -285.036768) (xy 453.846438 -285.029656)
			(xy 453.75703 -285.029656) (xy 453.739504 -285.036768) (xy 453.732392 -285.043372) (xy 453.711052 -285.062628)
			(xy 453.663694 -285.095196) (xy 453.611985 -285.120291) (xy 453.557097 -285.137345) (xy 453.500272 -285.145973)
			(xy 453.471534 -285.146496) (xy 453.444279 -285.146059) (xy 453.390322 -285.138306) (xy 453.338019 -285.122953)
			(xy 453.288433 -285.100311) (xy 453.242574 -285.070843) (xy 453.201376 -285.035148) (xy 453.165677 -284.993953)
			(xy 453.136205 -284.948097) (xy 453.113559 -284.898513) (xy 453.098201 -284.846211) (xy 453.090443 -284.792255)
			(xy 451.179909 -284.792255) (xy 451.172155 -284.84619) (xy 451.156803 -284.89848) (xy 451.134165 -284.948052)
			(xy 451.104704 -284.993899) (xy 451.069019 -285.035086) (xy 451.027836 -285.070777) (xy 450.981993 -285.100243)
			(xy 450.932423 -285.122886) (xy 450.880135 -285.138245) (xy 450.826194 -285.146007) (xy 450.798946 -285.146496)
			(xy 450.768823 -285.145912) (xy 450.709327 -285.136436) (xy 450.652058 -285.117729) (xy 450.598441 -285.090256)
			(xy 450.549807 -285.054699) (xy 450.528182 -285.03372) (xy 450.52107 -285.026354) (xy 450.502274 -285.018734)
			(xy 450.409818 -285.018734) (xy 450.391022 -285.026354) (xy 450.38391 -285.03372) (xy 450.362307 -285.054724)
			(xy 450.313672 -285.090288) (xy 450.26005 -285.117764) (xy 450.202775 -285.136466) (xy 450.143272 -285.145931)
			(xy 450.113146 -285.146496) (xy 450.084406 -285.146006) (xy 450.027577 -285.137375) (xy 449.972686 -285.120318)
			(xy 449.920975 -285.095218) (xy 449.873614 -285.062646) (xy 449.852288 -285.043372) (xy 449.845176 -285.036768)
			(xy 449.82765 -285.029656) (xy 449.738242 -285.029656) (xy 449.720716 -285.036768) (xy 449.713604 -285.043372)
			(xy 449.692277 -285.062642) (xy 449.644914 -285.095207) (xy 449.593203 -285.120298) (xy 449.538312 -285.137348)
			(xy 449.481485 -285.14597) (xy 449.424007 -285.14597) (xy 449.36718 -285.137348) (xy 449.312289 -285.120298)
			(xy 449.260578 -285.095207) (xy 449.213215 -285.062642) (xy 449.191888 -285.043372) (xy 449.184776 -285.036768)
			(xy 449.16725 -285.029656) (xy 449.077842 -285.029656) (xy 449.060316 -285.036768) (xy 449.053204 -285.043372)
			(xy 449.031901 -285.06267) (xy 448.984532 -285.095232) (xy 448.932814 -285.120319) (xy 448.877918 -285.137363)
			(xy 448.821087 -285.145979) (xy 448.792346 -285.146496) (xy 448.76509 -285.14606) (xy 448.711132 -285.138308)
			(xy 448.658827 -285.122956) (xy 448.60924 -285.100315) (xy 448.563379 -285.070847) (xy 448.52218 -285.035153)
			(xy 448.48648 -284.993957) (xy 448.457007 -284.948101) (xy 448.43436 -284.898516) (xy 448.419001 -284.846213)
			(xy 448.411243 -284.792256) (xy 430.835922 -284.792256) (xy 430.811133 -284.799436) (xy 430.762278 -284.805368)
			(xy 430.713103 -284.803387) (xy 430.664884 -284.793543) (xy 430.618868 -284.776091) (xy 430.576247 -284.751484)
			(xy 430.538126 -284.720359) (xy 430.505491 -284.683522) (xy 430.479188 -284.641926) (xy 430.459897 -284.59665)
			(xy 430.44812 -284.548866) (xy 430.44416 -284.499812) (xy 430.105312 -284.499812) (xy 430.104817 -284.524419)
			(xy 430.096922 -284.572996) (xy 430.081338 -284.619677) (xy 430.058467 -284.663254) (xy 430.028902 -284.702598)
			(xy 429.993409 -284.73669) (xy 429.952906 -284.764646) (xy 429.908444 -284.785744) (xy 429.861173 -284.799436)
			(xy 429.812318 -284.805368) (xy 429.763143 -284.803387) (xy 429.714924 -284.793543) (xy 429.668908 -284.776091)
			(xy 429.626287 -284.751484) (xy 429.588166 -284.720359) (xy 429.555531 -284.683522) (xy 429.529228 -284.641926)
			(xy 429.509937 -284.59665) (xy 429.49816 -284.548866) (xy 429.4942 -284.499812) (xy 429.176942 -284.499812)
			(xy 429.176438 -284.52552) (xy 429.168395 -284.576302) (xy 429.152507 -284.625201) (xy 429.129164 -284.671013)
			(xy 429.098943 -284.712609) (xy 429.062587 -284.748965) (xy 429.020991 -284.779186) (xy 428.975179 -284.802529)
			(xy 428.92628 -284.818417) (xy 428.875498 -284.82646) (xy 428.824082 -284.82646) (xy 428.7733 -284.818417)
			(xy 428.724401 -284.802529) (xy 428.678589 -284.779186) (xy 428.636993 -284.748965) (xy 428.600637 -284.712609)
			(xy 428.570416 -284.671013) (xy 428.547073 -284.625201) (xy 428.531185 -284.576302) (xy 428.523142 -284.52552)
			(xy 428.226478 -284.52552) (xy 428.218435 -284.576302) (xy 428.202547 -284.625201) (xy 428.179204 -284.671013)
			(xy 428.148983 -284.712609) (xy 428.112627 -284.748965) (xy 428.071031 -284.779186) (xy 428.025219 -284.802529)
			(xy 427.97632 -284.818417) (xy 427.925538 -284.82646) (xy 427.874122 -284.82646) (xy 427.82334 -284.818417)
			(xy 427.774441 -284.802529) (xy 427.728629 -284.779186) (xy 427.687033 -284.748965) (xy 427.650677 -284.712609)
			(xy 427.620456 -284.671013) (xy 427.597113 -284.625201) (xy 427.581225 -284.576302) (xy 427.573182 -284.52552)
			(xy 427.254504 -284.52552) (xy 427.246788 -284.572996) (xy 427.231204 -284.619677) (xy 427.208333 -284.663254)
			(xy 427.178768 -284.702598) (xy 427.143275 -284.73669) (xy 427.102772 -284.764646) (xy 427.05831 -284.785744)
			(xy 427.011039 -284.799436) (xy 426.962184 -284.805368) (xy 426.913009 -284.803387) (xy 426.86479 -284.793543)
			(xy 426.818774 -284.776091) (xy 426.776153 -284.751484) (xy 426.738032 -284.720359) (xy 426.705397 -284.683522)
			(xy 426.679094 -284.641926) (xy 426.659803 -284.59665) (xy 426.648026 -284.548866) (xy 426.644066 -284.499812)
			(xy 426.327062 -284.499812) (xy 426.326558 -284.52552) (xy 426.318515 -284.576302) (xy 426.302627 -284.625201)
			(xy 426.279284 -284.671013) (xy 426.249063 -284.712609) (xy 426.212707 -284.748965) (xy 426.171111 -284.779186)
			(xy 426.125299 -284.802529) (xy 426.0764 -284.818417) (xy 426.025618 -284.82646) (xy 425.974202 -284.82646)
			(xy 425.92342 -284.818417) (xy 425.874521 -284.802529) (xy 425.828709 -284.779186) (xy 425.787113 -284.748965)
			(xy 425.750757 -284.712609) (xy 425.720536 -284.671013) (xy 425.697193 -284.625201) (xy 425.681305 -284.576302)
			(xy 425.673262 -284.52552) (xy 425.376598 -284.52552) (xy 425.368555 -284.576302) (xy 425.352667 -284.625201)
			(xy 425.329324 -284.671013) (xy 425.299103 -284.712609) (xy 425.262747 -284.748965) (xy 425.221151 -284.779186)
			(xy 425.175339 -284.802529) (xy 425.12644 -284.818417) (xy 425.075658 -284.82646) (xy 425.024242 -284.82646)
			(xy 424.97346 -284.818417) (xy 424.924561 -284.802529) (xy 424.878749 -284.779186) (xy 424.837153 -284.748965)
			(xy 424.800797 -284.712609) (xy 424.770576 -284.671013) (xy 424.747233 -284.625201) (xy 424.731345 -284.576302)
			(xy 424.723302 -284.52552) (xy 424.404624 -284.52552) (xy 424.396908 -284.572996) (xy 424.381324 -284.619677)
			(xy 424.358453 -284.663254) (xy 424.328888 -284.702598) (xy 424.293395 -284.73669) (xy 424.252892 -284.764646)
			(xy 424.20843 -284.785744) (xy 424.161159 -284.799436) (xy 424.112304 -284.805368) (xy 424.063129 -284.803387)
			(xy 424.01491 -284.793543) (xy 423.968894 -284.776091) (xy 423.926273 -284.751484) (xy 423.888152 -284.720359)
			(xy 423.855517 -284.683522) (xy 423.829214 -284.641926) (xy 423.809923 -284.59665) (xy 423.798146 -284.548866)
			(xy 423.794186 -284.499812) (xy 423.455084 -284.499812) (xy 423.454589 -284.524419) (xy 423.446694 -284.572996)
			(xy 423.43111 -284.619677) (xy 423.408239 -284.663254) (xy 423.378674 -284.702598) (xy 423.343181 -284.73669)
			(xy 423.302678 -284.764646) (xy 423.258216 -284.785744) (xy 423.210945 -284.799436) (xy 423.16209 -284.805368)
			(xy 423.112915 -284.803387) (xy 423.064696 -284.793543) (xy 423.01868 -284.776091) (xy 422.976059 -284.751484)
			(xy 422.937938 -284.720359) (xy 422.905303 -284.683522) (xy 422.879 -284.641926) (xy 422.859709 -284.59665)
			(xy 422.847932 -284.548866) (xy 422.843972 -284.499812) (xy 422.505124 -284.499812) (xy 422.504629 -284.524419)
			(xy 422.496734 -284.572996) (xy 422.48115 -284.619677) (xy 422.458279 -284.663254) (xy 422.428714 -284.702598)
			(xy 422.393221 -284.73669) (xy 422.352718 -284.764646) (xy 422.308256 -284.785744) (xy 422.260985 -284.799436)
			(xy 422.21213 -284.805368) (xy 422.162955 -284.803387) (xy 422.114736 -284.793543) (xy 422.06872 -284.776091)
			(xy 422.026099 -284.751484) (xy 421.987978 -284.720359) (xy 421.955343 -284.683522) (xy 421.92904 -284.641926)
			(xy 421.909749 -284.59665) (xy 421.897972 -284.548866) (xy 421.894012 -284.499812) (xy 396.990824 -284.499812)
			(xy 396.990824 -284.573218) (xy 396.990999 -284.57937) (xy 396.993963 -284.591311) (xy 396.996666 -284.59684)
			(xy 397.004794 -284.608016) (xy 397.019526 -284.62351) (xy 397.02613 -284.630622) (xy 397.05026 -284.641798)
			(xy 397.054578 -284.643068) (xy 397.066008 -284.646624) (xy 397.070072 -284.647132) (xy 397.096117 -284.65124)
			(xy 397.146544 -284.666635) (xy 397.193891 -284.689835) (xy 397.236957 -284.720252) (xy 397.274653 -284.757115)
			(xy 397.306023 -284.799492) (xy 397.330274 -284.846309) (xy 397.34679 -284.89638) (xy 397.355154 -284.948437)
			(xy 397.355154 -284.974792) (xy 397.669016 -284.974792) (xy 397.672976 -284.925738) (xy 397.684753 -284.877954)
			(xy 397.704044 -284.832678) (xy 397.730347 -284.791082) (xy 397.762982 -284.754245) (xy 397.801103 -284.72312)
			(xy 397.843724 -284.698513) (xy 397.88974 -284.681061) (xy 397.937959 -284.671217) (xy 397.987134 -284.669236)
			(xy 398.035989 -284.675168) (xy 398.08326 -284.68886) (xy 398.127722 -284.709958) (xy 398.168225 -284.737914)
			(xy 398.203718 -284.772006) (xy 398.233283 -284.81135) (xy 398.256154 -284.854927) (xy 398.271738 -284.901608)
			(xy 398.279633 -284.950185) (xy 398.280128 -284.974792) (xy 398.61923 -284.974792) (xy 398.62319 -284.925738)
			(xy 398.634967 -284.877954) (xy 398.654258 -284.832678) (xy 398.680561 -284.791082) (xy 398.713196 -284.754245)
			(xy 398.751317 -284.72312) (xy 398.793938 -284.698513) (xy 398.839954 -284.681061) (xy 398.888173 -284.671217)
			(xy 398.937348 -284.669236) (xy 398.986203 -284.675168) (xy 399.033474 -284.68886) (xy 399.077936 -284.709958)
			(xy 399.118439 -284.737914) (xy 399.153932 -284.772006) (xy 399.183497 -284.81135) (xy 399.206368 -284.854927)
			(xy 399.221952 -284.901608) (xy 399.229847 -284.950185) (xy 399.230342 -284.974792) (xy 399.56919 -284.974792)
			(xy 399.57315 -284.925738) (xy 399.584927 -284.877954) (xy 399.604218 -284.832678) (xy 399.630521 -284.791082)
			(xy 399.663156 -284.754245) (xy 399.701277 -284.72312) (xy 399.743898 -284.698513) (xy 399.789914 -284.681061)
			(xy 399.838133 -284.671217) (xy 399.887308 -284.669236) (xy 399.936163 -284.675168) (xy 399.983434 -284.68886)
			(xy 400.027896 -284.709958) (xy 400.068399 -284.737914) (xy 400.103892 -284.772006) (xy 400.133457 -284.81135)
			(xy 400.156328 -284.854927) (xy 400.171912 -284.901608) (xy 400.179807 -284.950185) (xy 400.180302 -284.974792)
			(xy 400.51915 -284.974792) (xy 400.52311 -284.925738) (xy 400.534887 -284.877954) (xy 400.554178 -284.832678)
			(xy 400.580481 -284.791082) (xy 400.613116 -284.754245) (xy 400.651237 -284.72312) (xy 400.693858 -284.698513)
			(xy 400.739874 -284.681061) (xy 400.788093 -284.671217) (xy 400.837268 -284.669236) (xy 400.886123 -284.675168)
			(xy 400.933394 -284.68886) (xy 400.977856 -284.709958) (xy 401.018359 -284.737914) (xy 401.053852 -284.772006)
			(xy 401.083417 -284.81135) (xy 401.106288 -284.854927) (xy 401.121872 -284.901608) (xy 401.129767 -284.950185)
			(xy 401.130262 -284.974792) (xy 401.46911 -284.974792) (xy 401.47307 -284.925738) (xy 401.484847 -284.877954)
			(xy 401.504138 -284.832678) (xy 401.530441 -284.791082) (xy 401.563076 -284.754245) (xy 401.601197 -284.72312)
			(xy 401.643818 -284.698513) (xy 401.689834 -284.681061) (xy 401.738053 -284.671217) (xy 401.787228 -284.669236)
			(xy 401.836083 -284.675168) (xy 401.883354 -284.68886) (xy 401.927816 -284.709958) (xy 401.968319 -284.737914)
			(xy 402.003812 -284.772006) (xy 402.033377 -284.81135) (xy 402.056248 -284.854927) (xy 402.071832 -284.901608)
			(xy 402.079727 -284.950185) (xy 402.080222 -284.974792) (xy 402.41907 -284.974792) (xy 402.42303 -284.925738)
			(xy 402.434807 -284.877954) (xy 402.454098 -284.832678) (xy 402.480401 -284.791082) (xy 402.513036 -284.754245)
			(xy 402.551157 -284.72312) (xy 402.593778 -284.698513) (xy 402.639794 -284.681061) (xy 402.688013 -284.671217)
			(xy 402.737188 -284.669236) (xy 402.786043 -284.675168) (xy 402.833314 -284.68886) (xy 402.877776 -284.709958)
			(xy 402.918279 -284.737914) (xy 402.953772 -284.772006) (xy 402.983337 -284.81135) (xy 403.006208 -284.854927)
			(xy 403.021792 -284.901608) (xy 403.029687 -284.950185) (xy 403.030182 -284.974792) (xy 403.36903 -284.974792)
			(xy 403.37299 -284.925738) (xy 403.384767 -284.877954) (xy 403.404058 -284.832678) (xy 403.430361 -284.791082)
			(xy 403.462996 -284.754245) (xy 403.501117 -284.72312) (xy 403.543738 -284.698513) (xy 403.589754 -284.681061)
			(xy 403.637973 -284.671217) (xy 403.687148 -284.669236) (xy 403.736003 -284.675168) (xy 403.783274 -284.68886)
			(xy 403.827736 -284.709958) (xy 403.868239 -284.737914) (xy 403.903732 -284.772006) (xy 403.933297 -284.81135)
			(xy 403.956168 -284.854927) (xy 403.971752 -284.901608) (xy 403.979647 -284.950185) (xy 403.980142 -284.974792)
			(xy 404.31899 -284.974792) (xy 404.32295 -284.925738) (xy 404.334727 -284.877954) (xy 404.354018 -284.832678)
			(xy 404.380321 -284.791082) (xy 404.412956 -284.754245) (xy 404.451077 -284.72312) (xy 404.493698 -284.698513)
			(xy 404.539714 -284.681061) (xy 404.587933 -284.671217) (xy 404.637108 -284.669236) (xy 404.685963 -284.675168)
			(xy 404.733234 -284.68886) (xy 404.777696 -284.709958) (xy 404.818199 -284.737914) (xy 404.853692 -284.772006)
			(xy 404.883257 -284.81135) (xy 404.906128 -284.854927) (xy 404.921712 -284.901608) (xy 404.929607 -284.950185)
			(xy 404.930102 -284.974792) (xy 405.269204 -284.974792) (xy 405.273164 -284.925738) (xy 405.284941 -284.877954)
			(xy 405.304232 -284.832678) (xy 405.330535 -284.791082) (xy 405.36317 -284.754245) (xy 405.401291 -284.72312)
			(xy 405.443912 -284.698513) (xy 405.489928 -284.681061) (xy 405.538147 -284.671217) (xy 405.587322 -284.669236)
			(xy 405.636177 -284.675168) (xy 405.683448 -284.68886) (xy 405.72791 -284.709958) (xy 405.768413 -284.737914)
			(xy 405.803906 -284.772006) (xy 405.833471 -284.81135) (xy 405.856342 -284.854927) (xy 405.871926 -284.901608)
			(xy 405.879821 -284.950185) (xy 405.880316 -284.974792) (xy 406.219164 -284.974792) (xy 406.223124 -284.925738)
			(xy 406.234901 -284.877954) (xy 406.254192 -284.832678) (xy 406.280495 -284.791082) (xy 406.31313 -284.754245)
			(xy 406.351251 -284.72312) (xy 406.393872 -284.698513) (xy 406.439888 -284.681061) (xy 406.488107 -284.671217)
			(xy 406.537282 -284.669236) (xy 406.586137 -284.675168) (xy 406.633408 -284.68886) (xy 406.67787 -284.709958)
			(xy 406.718373 -284.737914) (xy 406.753866 -284.772006) (xy 406.783431 -284.81135) (xy 406.806302 -284.854927)
			(xy 406.821886 -284.901608) (xy 406.829781 -284.950185) (xy 406.830276 -284.974792) (xy 408.119084 -284.974792)
			(xy 408.123044 -284.925738) (xy 408.134821 -284.877954) (xy 408.154112 -284.832678) (xy 408.180415 -284.791082)
			(xy 408.21305 -284.754245) (xy 408.251171 -284.72312) (xy 408.293792 -284.698513) (xy 408.339808 -284.681061)
			(xy 408.388027 -284.671217) (xy 408.437202 -284.669236) (xy 408.486057 -284.675168) (xy 408.533328 -284.68886)
			(xy 408.57779 -284.709958) (xy 408.618293 -284.737914) (xy 408.653786 -284.772006) (xy 408.683351 -284.81135)
			(xy 408.706222 -284.854927) (xy 408.721806 -284.901608) (xy 408.729701 -284.950185) (xy 408.730196 -284.974792)
			(xy 409.069044 -284.974792) (xy 409.073004 -284.925738) (xy 409.084781 -284.877954) (xy 409.104072 -284.832678)
			(xy 409.130375 -284.791082) (xy 409.16301 -284.754245) (xy 409.201131 -284.72312) (xy 409.243752 -284.698513)
			(xy 409.289768 -284.681061) (xy 409.337987 -284.671217) (xy 409.387162 -284.669236) (xy 409.436017 -284.675168)
			(xy 409.483288 -284.68886) (xy 409.52775 -284.709958) (xy 409.568253 -284.737914) (xy 409.603746 -284.772006)
			(xy 409.633311 -284.81135) (xy 409.656182 -284.854927) (xy 409.671766 -284.901608) (xy 409.679661 -284.950185)
			(xy 409.680156 -284.974792) (xy 410.019004 -284.974792) (xy 410.022964 -284.925738) (xy 410.034741 -284.877954)
			(xy 410.054032 -284.832678) (xy 410.080335 -284.791082) (xy 410.11297 -284.754245) (xy 410.151091 -284.72312)
			(xy 410.193712 -284.698513) (xy 410.239728 -284.681061) (xy 410.287947 -284.671217) (xy 410.337122 -284.669236)
			(xy 410.385977 -284.675168) (xy 410.433248 -284.68886) (xy 410.47771 -284.709958) (xy 410.518213 -284.737914)
			(xy 410.553706 -284.772006) (xy 410.583271 -284.81135) (xy 410.606142 -284.854927) (xy 410.621726 -284.901608)
			(xy 410.629621 -284.950185) (xy 410.630116 -284.974792) (xy 410.969218 -284.974792) (xy 410.973178 -284.925738)
			(xy 410.984955 -284.877954) (xy 411.004246 -284.832678) (xy 411.030549 -284.791082) (xy 411.063184 -284.754245)
			(xy 411.101305 -284.72312) (xy 411.143926 -284.698513) (xy 411.189942 -284.681061) (xy 411.238161 -284.671217)
			(xy 411.287336 -284.669236) (xy 411.336191 -284.675168) (xy 411.383462 -284.68886) (xy 411.427924 -284.709958)
			(xy 411.468427 -284.737914) (xy 411.50392 -284.772006) (xy 411.533485 -284.81135) (xy 411.556356 -284.854927)
			(xy 411.57194 -284.901608) (xy 411.579835 -284.950185) (xy 411.58033 -284.974792) (xy 411.919178 -284.974792)
			(xy 411.923138 -284.925738) (xy 411.934915 -284.877954) (xy 411.954206 -284.832678) (xy 411.980509 -284.791082)
			(xy 412.013144 -284.754245) (xy 412.051265 -284.72312) (xy 412.093886 -284.698513) (xy 412.139902 -284.681061)
			(xy 412.188121 -284.671217) (xy 412.237296 -284.669236) (xy 412.286151 -284.675168) (xy 412.333422 -284.68886)
			(xy 412.377884 -284.709958) (xy 412.418387 -284.737914) (xy 412.45388 -284.772006) (xy 412.483445 -284.81135)
			(xy 412.506316 -284.854927) (xy 412.5219 -284.901608) (xy 412.529795 -284.950185) (xy 412.53029 -284.974792)
			(xy 412.869138 -284.974792) (xy 412.873098 -284.925738) (xy 412.884875 -284.877954) (xy 412.904166 -284.832678)
			(xy 412.930469 -284.791082) (xy 412.963104 -284.754245) (xy 413.001225 -284.72312) (xy 413.043846 -284.698513)
			(xy 413.089862 -284.681061) (xy 413.138081 -284.671217) (xy 413.187256 -284.669236) (xy 413.236111 -284.675168)
			(xy 413.283382 -284.68886) (xy 413.327844 -284.709958) (xy 413.368347 -284.737914) (xy 413.40384 -284.772006)
			(xy 413.433405 -284.81135) (xy 413.456276 -284.854927) (xy 413.47186 -284.901608) (xy 413.479755 -284.950185)
			(xy 413.48025 -284.974792) (xy 413.819098 -284.974792) (xy 413.823058 -284.925738) (xy 413.834835 -284.877954)
			(xy 413.854126 -284.832678) (xy 413.880429 -284.791082) (xy 413.913064 -284.754245) (xy 413.951185 -284.72312)
			(xy 413.993806 -284.698513) (xy 414.039822 -284.681061) (xy 414.088041 -284.671217) (xy 414.137216 -284.669236)
			(xy 414.186071 -284.675168) (xy 414.233342 -284.68886) (xy 414.277804 -284.709958) (xy 414.318307 -284.737914)
			(xy 414.3538 -284.772006) (xy 414.383365 -284.81135) (xy 414.406236 -284.854927) (xy 414.42182 -284.901608)
			(xy 414.429715 -284.950185) (xy 414.43021 -284.974792) (xy 414.769058 -284.974792) (xy 414.773018 -284.925738)
			(xy 414.784795 -284.877954) (xy 414.804086 -284.832678) (xy 414.830389 -284.791082) (xy 414.863024 -284.754245)
			(xy 414.901145 -284.72312) (xy 414.943766 -284.698513) (xy 414.989782 -284.681061) (xy 415.038001 -284.671217)
			(xy 415.087176 -284.669236) (xy 415.136031 -284.675168) (xy 415.183302 -284.68886) (xy 415.227764 -284.709958)
			(xy 415.268267 -284.737914) (xy 415.30376 -284.772006) (xy 415.333325 -284.81135) (xy 415.356196 -284.854927)
			(xy 415.37178 -284.901608) (xy 415.379675 -284.950185) (xy 415.38017 -284.974792) (xy 415.719018 -284.974792)
			(xy 415.722978 -284.925738) (xy 415.734755 -284.877954) (xy 415.754046 -284.832678) (xy 415.780349 -284.791082)
			(xy 415.812984 -284.754245) (xy 415.851105 -284.72312) (xy 415.893726 -284.698513) (xy 415.939742 -284.681061)
			(xy 415.987961 -284.671217) (xy 416.037136 -284.669236) (xy 416.085991 -284.675168) (xy 416.133262 -284.68886)
			(xy 416.177724 -284.709958) (xy 416.218227 -284.737914) (xy 416.25372 -284.772006) (xy 416.283285 -284.81135)
			(xy 416.306156 -284.854927) (xy 416.32174 -284.901608) (xy 416.329635 -284.950185) (xy 416.33013 -284.974792)
			(xy 416.668978 -284.974792) (xy 416.672938 -284.925738) (xy 416.684715 -284.877954) (xy 416.704006 -284.832678)
			(xy 416.730309 -284.791082) (xy 416.762944 -284.754245) (xy 416.801065 -284.72312) (xy 416.843686 -284.698513)
			(xy 416.889702 -284.681061) (xy 416.937921 -284.671217) (xy 416.987096 -284.669236) (xy 417.035951 -284.675168)
			(xy 417.083222 -284.68886) (xy 417.127684 -284.709958) (xy 417.168187 -284.737914) (xy 417.20368 -284.772006)
			(xy 417.233245 -284.81135) (xy 417.256116 -284.854927) (xy 417.2717 -284.901608) (xy 417.279595 -284.950185)
			(xy 417.28009 -284.974792) (xy 417.619192 -284.974792) (xy 417.623152 -284.925738) (xy 417.634929 -284.877954)
			(xy 417.65422 -284.832678) (xy 417.680523 -284.791082) (xy 417.713158 -284.754245) (xy 417.751279 -284.72312)
			(xy 417.7939 -284.698513) (xy 417.839916 -284.681061) (xy 417.888135 -284.671217) (xy 417.93731 -284.669236)
			(xy 417.986165 -284.675168) (xy 418.033436 -284.68886) (xy 418.077898 -284.709958) (xy 418.118401 -284.737914)
			(xy 418.153894 -284.772006) (xy 418.183459 -284.81135) (xy 418.20633 -284.854927) (xy 418.221914 -284.901608)
			(xy 418.229809 -284.950185) (xy 418.230304 -284.974792) (xy 418.569152 -284.974792) (xy 418.573112 -284.925738)
			(xy 418.584889 -284.877954) (xy 418.60418 -284.832678) (xy 418.630483 -284.791082) (xy 418.663118 -284.754245)
			(xy 418.701239 -284.72312) (xy 418.74386 -284.698513) (xy 418.789876 -284.681061) (xy 418.838095 -284.671217)
			(xy 418.88727 -284.669236) (xy 418.936125 -284.675168) (xy 418.983396 -284.68886) (xy 419.027858 -284.709958)
			(xy 419.068361 -284.737914) (xy 419.103854 -284.772006) (xy 419.133419 -284.81135) (xy 419.15629 -284.854927)
			(xy 419.171874 -284.901608) (xy 419.179769 -284.950185) (xy 419.180264 -284.974792) (xy 419.179769 -284.999399)
			(xy 419.171874 -285.047976) (xy 419.15629 -285.094657) (xy 419.133419 -285.138234) (xy 419.103854 -285.177578)
			(xy 419.068361 -285.21167) (xy 419.027858 -285.239626) (xy 418.983396 -285.260724) (xy 418.936125 -285.274416)
			(xy 418.88727 -285.280348) (xy 418.838095 -285.278367) (xy 418.789876 -285.268523) (xy 418.74386 -285.251071)
			(xy 418.701239 -285.226464) (xy 418.663118 -285.195339) (xy 418.630483 -285.158502) (xy 418.60418 -285.116906)
			(xy 418.584889 -285.07163) (xy 418.573112 -285.023846) (xy 418.569152 -284.974792) (xy 418.230304 -284.974792)
			(xy 418.229809 -284.999399) (xy 418.221914 -285.047976) (xy 418.20633 -285.094657) (xy 418.183459 -285.138234)
			(xy 418.153894 -285.177578) (xy 418.118401 -285.21167) (xy 418.077898 -285.239626) (xy 418.033436 -285.260724)
			(xy 417.986165 -285.274416) (xy 417.93731 -285.280348) (xy 417.888135 -285.278367) (xy 417.839916 -285.268523)
			(xy 417.7939 -285.251071) (xy 417.751279 -285.226464) (xy 417.713158 -285.195339) (xy 417.680523 -285.158502)
			(xy 417.65422 -285.116906) (xy 417.634929 -285.07163) (xy 417.623152 -285.023846) (xy 417.619192 -284.974792)
			(xy 417.28009 -284.974792) (xy 417.279595 -284.999399) (xy 417.2717 -285.047976) (xy 417.256116 -285.094657)
			(xy 417.233245 -285.138234) (xy 417.20368 -285.177578) (xy 417.168187 -285.21167) (xy 417.127684 -285.239626)
			(xy 417.083222 -285.260724) (xy 417.035951 -285.274416) (xy 416.987096 -285.280348) (xy 416.937921 -285.278367)
			(xy 416.889702 -285.268523) (xy 416.843686 -285.251071) (xy 416.801065 -285.226464) (xy 416.762944 -285.195339)
			(xy 416.730309 -285.158502) (xy 416.704006 -285.116906) (xy 416.684715 -285.07163) (xy 416.672938 -285.023846)
			(xy 416.668978 -284.974792) (xy 416.33013 -284.974792) (xy 416.329635 -284.999399) (xy 416.32174 -285.047976)
			(xy 416.306156 -285.094657) (xy 416.283285 -285.138234) (xy 416.25372 -285.177578) (xy 416.218227 -285.21167)
			(xy 416.177724 -285.239626) (xy 416.133262 -285.260724) (xy 416.085991 -285.274416) (xy 416.037136 -285.280348)
			(xy 415.987961 -285.278367) (xy 415.939742 -285.268523) (xy 415.893726 -285.251071) (xy 415.851105 -285.226464)
			(xy 415.812984 -285.195339) (xy 415.780349 -285.158502) (xy 415.754046 -285.116906) (xy 415.734755 -285.07163)
			(xy 415.722978 -285.023846) (xy 415.719018 -284.974792) (xy 415.38017 -284.974792) (xy 415.379675 -284.999399)
			(xy 415.37178 -285.047976) (xy 415.356196 -285.094657) (xy 415.333325 -285.138234) (xy 415.30376 -285.177578)
			(xy 415.268267 -285.21167) (xy 415.227764 -285.239626) (xy 415.183302 -285.260724) (xy 415.136031 -285.274416)
			(xy 415.087176 -285.280348) (xy 415.038001 -285.278367) (xy 414.989782 -285.268523) (xy 414.943766 -285.251071)
			(xy 414.901145 -285.226464) (xy 414.863024 -285.195339) (xy 414.830389 -285.158502) (xy 414.804086 -285.116906)
			(xy 414.784795 -285.07163) (xy 414.773018 -285.023846) (xy 414.769058 -284.974792) (xy 414.43021 -284.974792)
			(xy 414.429715 -284.999399) (xy 414.42182 -285.047976) (xy 414.406236 -285.094657) (xy 414.383365 -285.138234)
			(xy 414.3538 -285.177578) (xy 414.318307 -285.21167) (xy 414.277804 -285.239626) (xy 414.233342 -285.260724)
			(xy 414.186071 -285.274416) (xy 414.137216 -285.280348) (xy 414.088041 -285.278367) (xy 414.039822 -285.268523)
			(xy 413.993806 -285.251071) (xy 413.951185 -285.226464) (xy 413.913064 -285.195339) (xy 413.880429 -285.158502)
			(xy 413.854126 -285.116906) (xy 413.834835 -285.07163) (xy 413.823058 -285.023846) (xy 413.819098 -284.974792)
			(xy 413.48025 -284.974792) (xy 413.479755 -284.999399) (xy 413.47186 -285.047976) (xy 413.456276 -285.094657)
			(xy 413.433405 -285.138234) (xy 413.40384 -285.177578) (xy 413.368347 -285.21167) (xy 413.327844 -285.239626)
			(xy 413.283382 -285.260724) (xy 413.236111 -285.274416) (xy 413.187256 -285.280348) (xy 413.138081 -285.278367)
			(xy 413.089862 -285.268523) (xy 413.043846 -285.251071) (xy 413.001225 -285.226464) (xy 412.963104 -285.195339)
			(xy 412.930469 -285.158502) (xy 412.904166 -285.116906) (xy 412.884875 -285.07163) (xy 412.873098 -285.023846)
			(xy 412.869138 -284.974792) (xy 412.53029 -284.974792) (xy 412.529795 -284.999399) (xy 412.5219 -285.047976)
			(xy 412.506316 -285.094657) (xy 412.483445 -285.138234) (xy 412.45388 -285.177578) (xy 412.418387 -285.21167)
			(xy 412.377884 -285.239626) (xy 412.333422 -285.260724) (xy 412.286151 -285.274416) (xy 412.237296 -285.280348)
			(xy 412.188121 -285.278367) (xy 412.139902 -285.268523) (xy 412.093886 -285.251071) (xy 412.051265 -285.226464)
			(xy 412.013144 -285.195339) (xy 411.980509 -285.158502) (xy 411.954206 -285.116906) (xy 411.934915 -285.07163)
			(xy 411.923138 -285.023846) (xy 411.919178 -284.974792) (xy 411.58033 -284.974792) (xy 411.579835 -284.999399)
			(xy 411.57194 -285.047976) (xy 411.556356 -285.094657) (xy 411.533485 -285.138234) (xy 411.50392 -285.177578)
			(xy 411.468427 -285.21167) (xy 411.427924 -285.239626) (xy 411.383462 -285.260724) (xy 411.336191 -285.274416)
			(xy 411.287336 -285.280348) (xy 411.238161 -285.278367) (xy 411.189942 -285.268523) (xy 411.143926 -285.251071)
			(xy 411.101305 -285.226464) (xy 411.063184 -285.195339) (xy 411.030549 -285.158502) (xy 411.004246 -285.116906)
			(xy 410.984955 -285.07163) (xy 410.973178 -285.023846) (xy 410.969218 -284.974792) (xy 410.630116 -284.974792)
			(xy 410.629621 -284.999399) (xy 410.621726 -285.047976) (xy 410.606142 -285.094657) (xy 410.583271 -285.138234)
			(xy 410.553706 -285.177578) (xy 410.518213 -285.21167) (xy 410.47771 -285.239626) (xy 410.433248 -285.260724)
			(xy 410.385977 -285.274416) (xy 410.337122 -285.280348) (xy 410.287947 -285.278367) (xy 410.239728 -285.268523)
			(xy 410.193712 -285.251071) (xy 410.151091 -285.226464) (xy 410.11297 -285.195339) (xy 410.080335 -285.158502)
			(xy 410.054032 -285.116906) (xy 410.034741 -285.07163) (xy 410.022964 -285.023846) (xy 410.019004 -284.974792)
			(xy 409.680156 -284.974792) (xy 409.679661 -284.999399) (xy 409.671766 -285.047976) (xy 409.656182 -285.094657)
			(xy 409.633311 -285.138234) (xy 409.603746 -285.177578) (xy 409.568253 -285.21167) (xy 409.52775 -285.239626)
			(xy 409.483288 -285.260724) (xy 409.436017 -285.274416) (xy 409.387162 -285.280348) (xy 409.337987 -285.278367)
			(xy 409.289768 -285.268523) (xy 409.243752 -285.251071) (xy 409.201131 -285.226464) (xy 409.16301 -285.195339)
			(xy 409.130375 -285.158502) (xy 409.104072 -285.116906) (xy 409.084781 -285.07163) (xy 409.073004 -285.023846)
			(xy 409.069044 -284.974792) (xy 408.730196 -284.974792) (xy 408.729701 -284.999399) (xy 408.721806 -285.047976)
			(xy 408.706222 -285.094657) (xy 408.683351 -285.138234) (xy 408.653786 -285.177578) (xy 408.618293 -285.21167)
			(xy 408.57779 -285.239626) (xy 408.533328 -285.260724) (xy 408.486057 -285.274416) (xy 408.437202 -285.280348)
			(xy 408.388027 -285.278367) (xy 408.339808 -285.268523) (xy 408.293792 -285.251071) (xy 408.251171 -285.226464)
			(xy 408.21305 -285.195339) (xy 408.180415 -285.158502) (xy 408.154112 -285.116906) (xy 408.134821 -285.07163)
			(xy 408.123044 -285.023846) (xy 408.119084 -284.974792) (xy 406.830276 -284.974792) (xy 406.829781 -284.999399)
			(xy 406.821886 -285.047976) (xy 406.806302 -285.094657) (xy 406.783431 -285.138234) (xy 406.753866 -285.177578)
			(xy 406.718373 -285.21167) (xy 406.67787 -285.239626) (xy 406.633408 -285.260724) (xy 406.586137 -285.274416)
			(xy 406.537282 -285.280348) (xy 406.488107 -285.278367) (xy 406.439888 -285.268523) (xy 406.393872 -285.251071)
			(xy 406.351251 -285.226464) (xy 406.31313 -285.195339) (xy 406.280495 -285.158502) (xy 406.254192 -285.116906)
			(xy 406.234901 -285.07163) (xy 406.223124 -285.023846) (xy 406.219164 -284.974792) (xy 405.880316 -284.974792)
			(xy 405.879821 -284.999399) (xy 405.871926 -285.047976) (xy 405.856342 -285.094657) (xy 405.833471 -285.138234)
			(xy 405.803906 -285.177578) (xy 405.768413 -285.21167) (xy 405.72791 -285.239626) (xy 405.683448 -285.260724)
			(xy 405.636177 -285.274416) (xy 405.587322 -285.280348) (xy 405.538147 -285.278367) (xy 405.489928 -285.268523)
			(xy 405.443912 -285.251071) (xy 405.401291 -285.226464) (xy 405.36317 -285.195339) (xy 405.330535 -285.158502)
			(xy 405.304232 -285.116906) (xy 405.284941 -285.07163) (xy 405.273164 -285.023846) (xy 405.269204 -284.974792)
			(xy 404.930102 -284.974792) (xy 404.929607 -284.999399) (xy 404.921712 -285.047976) (xy 404.906128 -285.094657)
			(xy 404.883257 -285.138234) (xy 404.853692 -285.177578) (xy 404.818199 -285.21167) (xy 404.777696 -285.239626)
			(xy 404.733234 -285.260724) (xy 404.685963 -285.274416) (xy 404.637108 -285.280348) (xy 404.587933 -285.278367)
			(xy 404.539714 -285.268523) (xy 404.493698 -285.251071) (xy 404.451077 -285.226464) (xy 404.412956 -285.195339)
			(xy 404.380321 -285.158502) (xy 404.354018 -285.116906) (xy 404.334727 -285.07163) (xy 404.32295 -285.023846)
			(xy 404.31899 -284.974792) (xy 403.980142 -284.974792) (xy 403.979647 -284.999399) (xy 403.971752 -285.047976)
			(xy 403.956168 -285.094657) (xy 403.933297 -285.138234) (xy 403.903732 -285.177578) (xy 403.868239 -285.21167)
			(xy 403.827736 -285.239626) (xy 403.783274 -285.260724) (xy 403.736003 -285.274416) (xy 403.687148 -285.280348)
			(xy 403.637973 -285.278367) (xy 403.589754 -285.268523) (xy 403.543738 -285.251071) (xy 403.501117 -285.226464)
			(xy 403.462996 -285.195339) (xy 403.430361 -285.158502) (xy 403.404058 -285.116906) (xy 403.384767 -285.07163)
			(xy 403.37299 -285.023846) (xy 403.36903 -284.974792) (xy 403.030182 -284.974792) (xy 403.029687 -284.999399)
			(xy 403.021792 -285.047976) (xy 403.006208 -285.094657) (xy 402.983337 -285.138234) (xy 402.953772 -285.177578)
			(xy 402.918279 -285.21167) (xy 402.877776 -285.239626) (xy 402.833314 -285.260724) (xy 402.786043 -285.274416)
			(xy 402.737188 -285.280348) (xy 402.688013 -285.278367) (xy 402.639794 -285.268523) (xy 402.593778 -285.251071)
			(xy 402.551157 -285.226464) (xy 402.513036 -285.195339) (xy 402.480401 -285.158502) (xy 402.454098 -285.116906)
			(xy 402.434807 -285.07163) (xy 402.42303 -285.023846) (xy 402.41907 -284.974792) (xy 402.080222 -284.974792)
			(xy 402.079727 -284.999399) (xy 402.071832 -285.047976) (xy 402.056248 -285.094657) (xy 402.033377 -285.138234)
			(xy 402.003812 -285.177578) (xy 401.968319 -285.21167) (xy 401.927816 -285.239626) (xy 401.883354 -285.260724)
			(xy 401.836083 -285.274416) (xy 401.787228 -285.280348) (xy 401.738053 -285.278367) (xy 401.689834 -285.268523)
			(xy 401.643818 -285.251071) (xy 401.601197 -285.226464) (xy 401.563076 -285.195339) (xy 401.530441 -285.158502)
			(xy 401.504138 -285.116906) (xy 401.484847 -285.07163) (xy 401.47307 -285.023846) (xy 401.46911 -284.974792)
			(xy 401.130262 -284.974792) (xy 401.129767 -284.999399) (xy 401.121872 -285.047976) (xy 401.106288 -285.094657)
			(xy 401.083417 -285.138234) (xy 401.053852 -285.177578) (xy 401.018359 -285.21167) (xy 400.977856 -285.239626)
			(xy 400.933394 -285.260724) (xy 400.886123 -285.274416) (xy 400.837268 -285.280348) (xy 400.788093 -285.278367)
			(xy 400.739874 -285.268523) (xy 400.693858 -285.251071) (xy 400.651237 -285.226464) (xy 400.613116 -285.195339)
			(xy 400.580481 -285.158502) (xy 400.554178 -285.116906) (xy 400.534887 -285.07163) (xy 400.52311 -285.023846)
			(xy 400.51915 -284.974792) (xy 400.180302 -284.974792) (xy 400.179807 -284.999399) (xy 400.171912 -285.047976)
			(xy 400.156328 -285.094657) (xy 400.133457 -285.138234) (xy 400.103892 -285.177578) (xy 400.068399 -285.21167)
			(xy 400.027896 -285.239626) (xy 399.983434 -285.260724) (xy 399.936163 -285.274416) (xy 399.887308 -285.280348)
			(xy 399.838133 -285.278367) (xy 399.789914 -285.268523) (xy 399.743898 -285.251071) (xy 399.701277 -285.226464)
			(xy 399.663156 -285.195339) (xy 399.630521 -285.158502) (xy 399.604218 -285.116906) (xy 399.584927 -285.07163)
			(xy 399.57315 -285.023846) (xy 399.56919 -284.974792) (xy 399.230342 -284.974792) (xy 399.229847 -284.999399)
			(xy 399.221952 -285.047976) (xy 399.206368 -285.094657) (xy 399.183497 -285.138234) (xy 399.153932 -285.177578)
			(xy 399.118439 -285.21167) (xy 399.077936 -285.239626) (xy 399.033474 -285.260724) (xy 398.986203 -285.274416)
			(xy 398.937348 -285.280348) (xy 398.888173 -285.278367) (xy 398.839954 -285.268523) (xy 398.793938 -285.251071)
			(xy 398.751317 -285.226464) (xy 398.713196 -285.195339) (xy 398.680561 -285.158502) (xy 398.654258 -285.116906)
			(xy 398.634967 -285.07163) (xy 398.62319 -285.023846) (xy 398.61923 -284.974792) (xy 398.280128 -284.974792)
			(xy 398.279633 -284.999399) (xy 398.271738 -285.047976) (xy 398.256154 -285.094657) (xy 398.233283 -285.138234)
			(xy 398.203718 -285.177578) (xy 398.168225 -285.21167) (xy 398.127722 -285.239626) (xy 398.08326 -285.260724)
			(xy 398.035989 -285.274416) (xy 397.987134 -285.280348) (xy 397.937959 -285.278367) (xy 397.88974 -285.268523)
			(xy 397.843724 -285.251071) (xy 397.801103 -285.226464) (xy 397.762982 -285.195339) (xy 397.730347 -285.158502)
			(xy 397.704044 -285.116906) (xy 397.684753 -285.07163) (xy 397.672976 -285.023846) (xy 397.669016 -284.974792)
			(xy 397.355154 -284.974792) (xy 397.355155 -285.001161) (xy 397.346791 -285.053218) (xy 397.330274 -285.103289)
			(xy 397.306024 -285.150106) (xy 397.274654 -285.192483) (xy 397.236959 -285.229347) (xy 397.193892 -285.259764)
			(xy 397.146546 -285.282964) (xy 397.096119 -285.29836) (xy 397.070072 -285.302452) (xy 397.066008 -285.30296)
			(xy 397.054578 -285.306516) (xy 397.05026 -285.307786) (xy 397.02613 -285.318962) (xy 397.019526 -285.326074)
			(xy 397.004794 -285.341568) (xy 396.996666 -285.352744) (xy 396.993968 -285.358275) (xy 396.991006 -285.370215)
			(xy 396.990824 -285.376366) (xy 396.990824 -285.449772) (xy 421.894012 -285.449772) (xy 421.897972 -285.400718)
			(xy 421.909749 -285.352934) (xy 421.92904 -285.307658) (xy 421.955343 -285.266062) (xy 421.987978 -285.229225)
			(xy 422.026099 -285.1981) (xy 422.06872 -285.173493) (xy 422.114736 -285.156041) (xy 422.162955 -285.146197)
			(xy 422.21213 -285.144216) (xy 422.260985 -285.150148) (xy 422.308256 -285.16384) (xy 422.352718 -285.184938)
			(xy 422.393221 -285.212894) (xy 422.428714 -285.246986) (xy 422.458279 -285.28633) (xy 422.48115 -285.329907)
			(xy 422.496734 -285.376588) (xy 422.504629 -285.425165) (xy 422.505124 -285.449772) (xy 422.504629 -285.474379)
			(xy 422.50445 -285.47548) (xy 422.823128 -285.47548) (xy 422.823128 -285.424064) (xy 422.831171 -285.373282)
			(xy 422.847059 -285.324383) (xy 422.870402 -285.278571) (xy 422.900623 -285.236975) (xy 422.936979 -285.200619)
			(xy 422.978575 -285.170398) (xy 423.024387 -285.147055) (xy 423.073286 -285.131167) (xy 423.124068 -285.123124)
			(xy 423.175484 -285.123124) (xy 423.226266 -285.131167) (xy 423.275165 -285.147055) (xy 423.320977 -285.170398)
			(xy 423.362573 -285.200619) (xy 423.398929 -285.236975) (xy 423.42915 -285.278571) (xy 423.452493 -285.324383)
			(xy 423.468381 -285.373282) (xy 423.476424 -285.424064) (xy 423.476928 -285.449772) (xy 423.476424 -285.47548)
			(xy 423.773342 -285.47548) (xy 423.773342 -285.424064) (xy 423.781385 -285.373282) (xy 423.797273 -285.324383)
			(xy 423.820616 -285.278571) (xy 423.850837 -285.236975) (xy 423.887193 -285.200619) (xy 423.928789 -285.170398)
			(xy 423.974601 -285.147055) (xy 424.0235 -285.131167) (xy 424.074282 -285.123124) (xy 424.125698 -285.123124)
			(xy 424.17648 -285.131167) (xy 424.225379 -285.147055) (xy 424.271191 -285.170398) (xy 424.312787 -285.200619)
			(xy 424.349143 -285.236975) (xy 424.379364 -285.278571) (xy 424.402707 -285.324383) (xy 424.418595 -285.373282)
			(xy 424.426638 -285.424064) (xy 424.427142 -285.449772) (xy 424.744146 -285.449772) (xy 424.748106 -285.400718)
			(xy 424.759883 -285.352934) (xy 424.779174 -285.307658) (xy 424.805477 -285.266062) (xy 424.838112 -285.229225)
			(xy 424.876233 -285.1981) (xy 424.918854 -285.173493) (xy 424.96487 -285.156041) (xy 425.013089 -285.146197)
			(xy 425.062264 -285.144216) (xy 425.111119 -285.150148) (xy 425.15839 -285.16384) (xy 425.202852 -285.184938)
			(xy 425.243355 -285.212894) (xy 425.278848 -285.246986) (xy 425.308413 -285.28633) (xy 425.331284 -285.329907)
			(xy 425.346868 -285.376588) (xy 425.354763 -285.425165) (xy 425.355258 -285.449772) (xy 425.694106 -285.449772)
			(xy 425.698066 -285.400718) (xy 425.709843 -285.352934) (xy 425.729134 -285.307658) (xy 425.755437 -285.266062)
			(xy 425.788072 -285.229225) (xy 425.826193 -285.1981) (xy 425.868814 -285.173493) (xy 425.91483 -285.156041)
			(xy 425.963049 -285.146197) (xy 426.012224 -285.144216) (xy 426.061079 -285.150148) (xy 426.10835 -285.16384)
			(xy 426.152812 -285.184938) (xy 426.193315 -285.212894) (xy 426.228808 -285.246986) (xy 426.258373 -285.28633)
			(xy 426.281244 -285.329907) (xy 426.296828 -285.376588) (xy 426.304723 -285.425165) (xy 426.305218 -285.449772)
			(xy 426.644066 -285.449772) (xy 426.648026 -285.400718) (xy 426.659803 -285.352934) (xy 426.679094 -285.307658)
			(xy 426.705397 -285.266062) (xy 426.738032 -285.229225) (xy 426.776153 -285.1981) (xy 426.818774 -285.173493)
			(xy 426.86479 -285.156041) (xy 426.913009 -285.146197) (xy 426.962184 -285.144216) (xy 427.011039 -285.150148)
			(xy 427.05831 -285.16384) (xy 427.102772 -285.184938) (xy 427.143275 -285.212894) (xy 427.178768 -285.246986)
			(xy 427.208333 -285.28633) (xy 427.231204 -285.329907) (xy 427.246788 -285.376588) (xy 427.254683 -285.425165)
			(xy 427.255178 -285.449772) (xy 427.594026 -285.449772) (xy 427.597986 -285.400718) (xy 427.609763 -285.352934)
			(xy 427.629054 -285.307658) (xy 427.655357 -285.266062) (xy 427.687992 -285.229225) (xy 427.726113 -285.1981)
			(xy 427.768734 -285.173493) (xy 427.81475 -285.156041) (xy 427.862969 -285.146197) (xy 427.912144 -285.144216)
			(xy 427.960999 -285.150148) (xy 428.00827 -285.16384) (xy 428.052732 -285.184938) (xy 428.093235 -285.212894)
			(xy 428.128728 -285.246986) (xy 428.158293 -285.28633) (xy 428.181164 -285.329907) (xy 428.196748 -285.376588)
			(xy 428.204643 -285.425165) (xy 428.205138 -285.449772) (xy 428.543986 -285.449772) (xy 428.547946 -285.400718)
			(xy 428.559723 -285.352934) (xy 428.579014 -285.307658) (xy 428.605317 -285.266062) (xy 428.637952 -285.229225)
			(xy 428.676073 -285.1981) (xy 428.718694 -285.173493) (xy 428.76471 -285.156041) (xy 428.812929 -285.146197)
			(xy 428.862104 -285.144216) (xy 428.910959 -285.150148) (xy 428.95823 -285.16384) (xy 429.002692 -285.184938)
			(xy 429.043195 -285.212894) (xy 429.078688 -285.246986) (xy 429.108253 -285.28633) (xy 429.131124 -285.329907)
			(xy 429.146708 -285.376588) (xy 429.154603 -285.425165) (xy 429.155098 -285.449772) (xy 429.154603 -285.474379)
			(xy 429.154424 -285.47548) (xy 429.473356 -285.47548) (xy 429.473356 -285.424064) (xy 429.481399 -285.373282)
			(xy 429.497287 -285.324383) (xy 429.52063 -285.278571) (xy 429.550851 -285.236975) (xy 429.587207 -285.200619)
			(xy 429.628803 -285.170398) (xy 429.674615 -285.147055) (xy 429.723514 -285.131167) (xy 429.774296 -285.123124)
			(xy 429.825712 -285.123124) (xy 429.876494 -285.131167) (xy 429.925393 -285.147055) (xy 429.971205 -285.170398)
			(xy 430.012801 -285.200619) (xy 430.049157 -285.236975) (xy 430.079378 -285.278571) (xy 430.102721 -285.324383)
			(xy 430.118609 -285.373282) (xy 430.126652 -285.424064) (xy 430.127156 -285.449772) (xy 430.126652 -285.47548)
			(xy 430.423316 -285.47548) (xy 430.423316 -285.424064) (xy 430.431359 -285.373282) (xy 430.447247 -285.324383)
			(xy 430.47059 -285.278571) (xy 430.500811 -285.236975) (xy 430.537167 -285.200619) (xy 430.578763 -285.170398)
			(xy 430.624575 -285.147055) (xy 430.673474 -285.131167) (xy 430.724256 -285.123124) (xy 430.775672 -285.123124)
			(xy 430.826454 -285.131167) (xy 430.875353 -285.147055) (xy 430.921165 -285.170398) (xy 430.962761 -285.200619)
			(xy 430.999117 -285.236975) (xy 431.029338 -285.278571) (xy 431.052681 -285.324383) (xy 431.068569 -285.373282)
			(xy 431.076612 -285.424064) (xy 431.077116 -285.449772) (xy 431.077111 -285.450026) (xy 431.394374 -285.450026)
			(xy 431.398334 -285.400972) (xy 431.410111 -285.353188) (xy 431.429402 -285.307912) (xy 431.455705 -285.266316)
			(xy 431.48834 -285.229479) (xy 431.526461 -285.198354) (xy 431.569082 -285.173747) (xy 431.615098 -285.156295)
			(xy 431.663317 -285.146451) (xy 431.712492 -285.14447) (xy 431.761347 -285.150402) (xy 431.808618 -285.164094)
			(xy 431.85308 -285.185192) (xy 431.893583 -285.213148) (xy 431.929076 -285.24724) (xy 431.958641 -285.286584)
			(xy 431.981512 -285.330161) (xy 431.997096 -285.376842) (xy 432.004991 -285.425419) (xy 432.005486 -285.450026)
			(xy 432.004991 -285.474633) (xy 431.997096 -285.52321) (xy 431.981512 -285.569891) (xy 431.962271 -285.606552)
			(xy 456.489267 -285.606552) (xy 456.489267 -285.552048) (xy 456.497024 -285.498098) (xy 456.51238 -285.445801)
			(xy 456.535023 -285.396222) (xy 456.56449 -285.35037) (xy 456.600184 -285.309178) (xy 456.641376 -285.273486)
			(xy 456.687229 -285.244019) (xy 456.736808 -285.221377) (xy 456.789106 -285.206023) (xy 456.843056 -285.198267)
			(xy 456.870308 -285.197804) (xy 456.899047 -285.198322) (xy 456.955875 -285.206946) (xy 457.010766 -285.223997)
			(xy 457.062477 -285.24909) (xy 457.109839 -285.281657) (xy 457.131166 -285.300928) (xy 457.138278 -285.307532)
			(xy 457.155804 -285.314644) (xy 457.245212 -285.314644) (xy 457.262738 -285.307532) (xy 457.26985 -285.300928)
			(xy 457.291177 -285.281658) (xy 457.33854 -285.249093) (xy 457.390251 -285.224002) (xy 457.445142 -285.206952)
			(xy 457.501969 -285.19833) (xy 457.559447 -285.19833) (xy 457.616274 -285.206952) (xy 457.671165 -285.224002)
			(xy 457.722876 -285.249093) (xy 457.770239 -285.281658) (xy 457.791566 -285.300928) (xy 457.798678 -285.307532)
			(xy 457.816204 -285.314644) (xy 457.905612 -285.314644) (xy 457.923138 -285.307532) (xy 457.93025 -285.300928)
			(xy 457.951572 -285.281652) (xy 457.998936 -285.249087) (xy 458.050649 -285.223995) (xy 458.10554 -285.206946)
			(xy 458.162369 -285.198324) (xy 458.191108 -285.197804) (xy 458.221232 -285.198354) (xy 458.280731 -285.207838)
			(xy 458.337999 -285.226552) (xy 458.391616 -285.254033) (xy 458.440249 -285.289598) (xy 458.461872 -285.31058)
			(xy 458.468984 -285.317946) (xy 458.48778 -285.325566) (xy 458.580236 -285.325566) (xy 458.599032 -285.317946)
			(xy 458.606144 -285.31058) (xy 458.627767 -285.289598) (xy 458.676397 -285.254031) (xy 458.730014 -285.226551)
			(xy 458.787284 -285.207844) (xy 458.846784 -285.198372) (xy 458.876908 -285.197804) (xy 458.90416 -285.198266)
			(xy 458.958108 -285.206024) (xy 459.010404 -285.22138) (xy 459.059982 -285.244023) (xy 459.105832 -285.27349)
			(xy 459.147023 -285.309183) (xy 459.182715 -285.350374) (xy 459.212181 -285.396226) (xy 459.234822 -285.445804)
			(xy 459.250178 -285.4981) (xy 459.257934 -285.552048) (xy 459.257934 -285.596653) (xy 460.661461 -285.596653)
			(xy 460.661461 -285.542147) (xy 460.669219 -285.488196) (xy 460.684575 -285.435898) (xy 460.707218 -285.386318)
			(xy 460.736687 -285.340465) (xy 460.772381 -285.299272) (xy 460.813574 -285.263579) (xy 460.859428 -285.234112)
			(xy 460.909009 -285.211471) (xy 460.961308 -285.196116) (xy 461.015259 -285.188361) (xy 461.042512 -285.187898)
			(xy 461.071251 -285.188415) (xy 461.128079 -285.197039) (xy 461.18297 -285.214091) (xy 461.234681 -285.239184)
			(xy 461.282043 -285.271751) (xy 461.30337 -285.291022) (xy 461.310482 -285.297626) (xy 461.328008 -285.304738)
			(xy 461.417416 -285.304738) (xy 461.434942 -285.297626) (xy 461.442054 -285.291022) (xy 461.463381 -285.271752)
			(xy 461.510744 -285.239187) (xy 461.562455 -285.214096) (xy 461.617346 -285.197046) (xy 461.674173 -285.188424)
			(xy 461.731651 -285.188424) (xy 461.788478 -285.197046) (xy 461.843369 -285.214096) (xy 461.89508 -285.239187)
			(xy 461.942443 -285.271752) (xy 461.96377 -285.291022) (xy 461.970882 -285.297626) (xy 461.988408 -285.304738)
			(xy 462.077816 -285.304738) (xy 462.095342 -285.297626) (xy 462.102454 -285.291022) (xy 462.123774 -285.271743)
			(xy 462.171138 -285.239178) (xy 462.222852 -285.214088) (xy 462.277744 -285.197039) (xy 462.334573 -285.188418)
			(xy 462.363312 -285.187898) (xy 462.393436 -285.188447) (xy 462.452934 -285.197931) (xy 462.510203 -285.216646)
			(xy 462.56382 -285.244128) (xy 462.612453 -285.279692) (xy 462.634076 -285.300674) (xy 462.641188 -285.30804)
			(xy 462.659984 -285.31566) (xy 462.75244 -285.31566) (xy 462.771236 -285.30804) (xy 462.778348 -285.300674)
			(xy 462.799985 -285.279707) (xy 462.848609 -285.244134) (xy 462.902222 -285.21665) (xy 462.95949 -285.197939)
			(xy 463.018988 -285.188467) (xy 463.049112 -285.187898) (xy 463.076363 -285.188373) (xy 463.13031 -285.196131)
			(xy 463.182605 -285.211487) (xy 463.232181 -285.234129) (xy 463.278031 -285.263596) (xy 463.31922 -285.299288)
			(xy 463.354911 -285.340479) (xy 463.384377 -285.38633) (xy 463.407017 -285.435907) (xy 463.422372 -285.488201)
			(xy 463.430128 -285.542149) (xy 463.430128 -285.596651) (xy 463.422372 -285.650599) (xy 463.407017 -285.702893)
			(xy 463.384377 -285.75247) (xy 463.354911 -285.798321) (xy 463.31922 -285.839512) (xy 463.278031 -285.875204)
			(xy 463.232181 -285.904671) (xy 463.182605 -285.927313) (xy 463.13031 -285.942669) (xy 463.076363 -285.950427)
			(xy 463.049112 -285.950914) (xy 463.018988 -285.950346) (xy 462.959491 -285.940866) (xy 462.902223 -285.922155)
			(xy 462.848606 -285.894678) (xy 462.799972 -285.859118) (xy 462.778348 -285.838138) (xy 462.771236 -285.830772)
			(xy 462.75244 -285.823152) (xy 462.659984 -285.823152) (xy 462.641188 -285.830772) (xy 462.634076 -285.838138)
			(xy 462.61243 -285.859096) (xy 462.563808 -285.89467) (xy 462.510197 -285.922155) (xy 462.452931 -285.940868)
			(xy 462.393435 -285.950344) (xy 462.363312 -285.950914) (xy 462.334574 -285.950379) (xy 462.277747 -285.941759)
			(xy 462.222856 -285.924711) (xy 462.171144 -285.899622) (xy 462.123781 -285.867059) (xy 462.102454 -285.84779)
			(xy 462.095342 -285.841186) (xy 462.077816 -285.834074) (xy 461.988408 -285.834074) (xy 461.970882 -285.841186)
			(xy 461.96377 -285.84779) (xy 461.942443 -285.86706) (xy 461.89508 -285.899625) (xy 461.843369 -285.924716)
			(xy 461.788478 -285.941766) (xy 461.731651 -285.950388) (xy 461.674173 -285.950388) (xy 461.617346 -285.941766)
			(xy 461.562455 -285.924716) (xy 461.510744 -285.899625) (xy 461.463381 -285.86706) (xy 461.442054 -285.84779)
			(xy 461.434942 -285.841186) (xy 461.417416 -285.834074) (xy 461.328008 -285.834074) (xy 461.310482 -285.841186)
			(xy 461.30337 -285.84779) (xy 461.282042 -285.86706) (xy 461.23468 -285.899625) (xy 461.182968 -285.924717)
			(xy 461.128078 -285.941768) (xy 461.071251 -285.950392) (xy 461.042512 -285.950914) (xy 461.015259 -285.950439)
			(xy 460.961308 -285.942684) (xy 460.909009 -285.927329) (xy 460.859428 -285.904688) (xy 460.813574 -285.875221)
			(xy 460.772381 -285.839528) (xy 460.736687 -285.798335) (xy 460.707218 -285.752482) (xy 460.684575 -285.702902)
			(xy 460.669219 -285.650604) (xy 460.661461 -285.596653) (xy 459.257934 -285.596653) (xy 459.257934 -285.606552)
			(xy 459.250178 -285.6605) (xy 459.234822 -285.712796) (xy 459.212181 -285.762374) (xy 459.182715 -285.808226)
			(xy 459.147023 -285.849417) (xy 459.105832 -285.88511) (xy 459.059982 -285.914577) (xy 459.010404 -285.93722)
			(xy 458.958108 -285.952576) (xy 458.90416 -285.960334) (xy 458.876908 -285.96082) (xy 458.846784 -285.960253)
			(xy 458.787287 -285.950772) (xy 458.730019 -285.932061) (xy 458.676402 -285.904584) (xy 458.627768 -285.869024)
			(xy 458.606144 -285.848044) (xy 458.599032 -285.840678) (xy 458.580236 -285.833058) (xy 458.48778 -285.833058)
			(xy 458.468984 -285.840678) (xy 458.461872 -285.848044) (xy 458.440229 -285.869005) (xy 458.391606 -285.904578)
			(xy 458.337995 -285.932063) (xy 458.280728 -285.950775) (xy 458.221231 -285.96025) (xy 458.191108 -285.96082)
			(xy 458.16237 -285.960286) (xy 458.105543 -285.951665) (xy 458.050652 -285.934617) (xy 457.998941 -285.909528)
			(xy 457.951577 -285.876965) (xy 457.93025 -285.857696) (xy 457.923138 -285.851092) (xy 457.905612 -285.84398)
			(xy 457.816204 -285.84398) (xy 457.798678 -285.851092) (xy 457.791566 -285.857696) (xy 457.770239 -285.876966)
			(xy 457.722876 -285.909531) (xy 457.671165 -285.934622) (xy 457.616274 -285.951672) (xy 457.559447 -285.960294)
			(xy 457.501969 -285.960294) (xy 457.445142 -285.951672) (xy 457.390251 -285.934622) (xy 457.33854 -285.909531)
			(xy 457.291177 -285.876966) (xy 457.26985 -285.857696) (xy 457.262738 -285.851092) (xy 457.245212 -285.84398)
			(xy 457.155804 -285.84398) (xy 457.138278 -285.851092) (xy 457.131166 -285.857696) (xy 457.109826 -285.876952)
			(xy 457.062468 -285.909522) (xy 457.01076 -285.934619) (xy 456.955872 -285.951673) (xy 456.899046 -285.960298)
			(xy 456.870308 -285.96082) (xy 456.843056 -285.960333) (xy 456.789106 -285.952577) (xy 456.736808 -285.937223)
			(xy 456.687229 -285.914581) (xy 456.641376 -285.885114) (xy 456.600184 -285.849422) (xy 456.56449 -285.80823)
			(xy 456.535023 -285.762378) (xy 456.51238 -285.712799) (xy 456.497024 -285.660502) (xy 456.489267 -285.606552)
			(xy 431.962271 -285.606552) (xy 431.958641 -285.613468) (xy 431.929076 -285.652812) (xy 431.893583 -285.686904)
			(xy 431.85308 -285.71486) (xy 431.808618 -285.735958) (xy 431.761347 -285.74965) (xy 431.712492 -285.755582)
			(xy 431.663317 -285.753601) (xy 431.615098 -285.743757) (xy 431.569082 -285.726305) (xy 431.526461 -285.701698)
			(xy 431.48834 -285.670573) (xy 431.455705 -285.633736) (xy 431.429402 -285.59214) (xy 431.410111 -285.546864)
			(xy 431.398334 -285.49908) (xy 431.394374 -285.450026) (xy 431.077111 -285.450026) (xy 431.076612 -285.47548)
			(xy 431.068569 -285.526262) (xy 431.052681 -285.575161) (xy 431.029338 -285.620973) (xy 430.999117 -285.662569)
			(xy 430.962761 -285.698925) (xy 430.921165 -285.729146) (xy 430.875353 -285.752489) (xy 430.826454 -285.768377)
			(xy 430.775672 -285.77642) (xy 430.724256 -285.77642) (xy 430.673474 -285.768377) (xy 430.624575 -285.752489)
			(xy 430.578763 -285.729146) (xy 430.537167 -285.698925) (xy 430.500811 -285.662569) (xy 430.47059 -285.620973)
			(xy 430.447247 -285.575161) (xy 430.431359 -285.526262) (xy 430.423316 -285.47548) (xy 430.126652 -285.47548)
			(xy 430.118609 -285.526262) (xy 430.102721 -285.575161) (xy 430.079378 -285.620973) (xy 430.049157 -285.662569)
			(xy 430.012801 -285.698925) (xy 429.971205 -285.729146) (xy 429.925393 -285.752489) (xy 429.876494 -285.768377)
			(xy 429.825712 -285.77642) (xy 429.774296 -285.77642) (xy 429.723514 -285.768377) (xy 429.674615 -285.752489)
			(xy 429.628803 -285.729146) (xy 429.587207 -285.698925) (xy 429.550851 -285.662569) (xy 429.52063 -285.620973)
			(xy 429.497287 -285.575161) (xy 429.481399 -285.526262) (xy 429.473356 -285.47548) (xy 429.154424 -285.47548)
			(xy 429.146708 -285.522956) (xy 429.131124 -285.569637) (xy 429.108253 -285.613214) (xy 429.078688 -285.652558)
			(xy 429.043195 -285.68665) (xy 429.002692 -285.714606) (xy 428.95823 -285.735704) (xy 428.910959 -285.749396)
			(xy 428.862104 -285.755328) (xy 428.812929 -285.753347) (xy 428.76471 -285.743503) (xy 428.718694 -285.726051)
			(xy 428.676073 -285.701444) (xy 428.637952 -285.670319) (xy 428.605317 -285.633482) (xy 428.579014 -285.591886)
			(xy 428.559723 -285.54661) (xy 428.547946 -285.498826) (xy 428.543986 -285.449772) (xy 428.205138 -285.449772)
			(xy 428.204643 -285.474379) (xy 428.196748 -285.522956) (xy 428.181164 -285.569637) (xy 428.158293 -285.613214)
			(xy 428.128728 -285.652558) (xy 428.093235 -285.68665) (xy 428.052732 -285.714606) (xy 428.00827 -285.735704)
			(xy 427.960999 -285.749396) (xy 427.912144 -285.755328) (xy 427.862969 -285.753347) (xy 427.81475 -285.743503)
			(xy 427.768734 -285.726051) (xy 427.726113 -285.701444) (xy 427.687992 -285.670319) (xy 427.655357 -285.633482)
			(xy 427.629054 -285.591886) (xy 427.609763 -285.54661) (xy 427.597986 -285.498826) (xy 427.594026 -285.449772)
			(xy 427.255178 -285.449772) (xy 427.254683 -285.474379) (xy 427.246788 -285.522956) (xy 427.231204 -285.569637)
			(xy 427.208333 -285.613214) (xy 427.178768 -285.652558) (xy 427.143275 -285.68665) (xy 427.102772 -285.714606)
			(xy 427.05831 -285.735704) (xy 427.011039 -285.749396) (xy 426.962184 -285.755328) (xy 426.913009 -285.753347)
			(xy 426.86479 -285.743503) (xy 426.818774 -285.726051) (xy 426.776153 -285.701444) (xy 426.738032 -285.670319)
			(xy 426.705397 -285.633482) (xy 426.679094 -285.591886) (xy 426.659803 -285.54661) (xy 426.648026 -285.498826)
			(xy 426.644066 -285.449772) (xy 426.305218 -285.449772) (xy 426.304723 -285.474379) (xy 426.296828 -285.522956)
			(xy 426.281244 -285.569637) (xy 426.258373 -285.613214) (xy 426.228808 -285.652558) (xy 426.193315 -285.68665)
			(xy 426.152812 -285.714606) (xy 426.10835 -285.735704) (xy 426.061079 -285.749396) (xy 426.012224 -285.755328)
			(xy 425.963049 -285.753347) (xy 425.91483 -285.743503) (xy 425.868814 -285.726051) (xy 425.826193 -285.701444)
			(xy 425.788072 -285.670319) (xy 425.755437 -285.633482) (xy 425.729134 -285.591886) (xy 425.709843 -285.54661)
			(xy 425.698066 -285.498826) (xy 425.694106 -285.449772) (xy 425.355258 -285.449772) (xy 425.354763 -285.474379)
			(xy 425.346868 -285.522956) (xy 425.331284 -285.569637) (xy 425.308413 -285.613214) (xy 425.278848 -285.652558)
			(xy 425.243355 -285.68665) (xy 425.202852 -285.714606) (xy 425.15839 -285.735704) (xy 425.111119 -285.749396)
			(xy 425.062264 -285.755328) (xy 425.013089 -285.753347) (xy 424.96487 -285.743503) (xy 424.918854 -285.726051)
			(xy 424.876233 -285.701444) (xy 424.838112 -285.670319) (xy 424.805477 -285.633482) (xy 424.779174 -285.591886)
			(xy 424.759883 -285.54661) (xy 424.748106 -285.498826) (xy 424.744146 -285.449772) (xy 424.427142 -285.449772)
			(xy 424.426638 -285.47548) (xy 424.418595 -285.526262) (xy 424.402707 -285.575161) (xy 424.379364 -285.620973)
			(xy 424.349143 -285.662569) (xy 424.312787 -285.698925) (xy 424.271191 -285.729146) (xy 424.225379 -285.752489)
			(xy 424.17648 -285.768377) (xy 424.125698 -285.77642) (xy 424.074282 -285.77642) (xy 424.0235 -285.768377)
			(xy 423.974601 -285.752489) (xy 423.928789 -285.729146) (xy 423.887193 -285.698925) (xy 423.850837 -285.662569)
			(xy 423.820616 -285.620973) (xy 423.797273 -285.575161) (xy 423.781385 -285.526262) (xy 423.773342 -285.47548)
			(xy 423.476424 -285.47548) (xy 423.468381 -285.526262) (xy 423.452493 -285.575161) (xy 423.42915 -285.620973)
			(xy 423.398929 -285.662569) (xy 423.362573 -285.698925) (xy 423.320977 -285.729146) (xy 423.275165 -285.752489)
			(xy 423.226266 -285.768377) (xy 423.175484 -285.77642) (xy 423.124068 -285.77642) (xy 423.073286 -285.768377)
			(xy 423.024387 -285.752489) (xy 422.978575 -285.729146) (xy 422.936979 -285.698925) (xy 422.900623 -285.662569)
			(xy 422.870402 -285.620973) (xy 422.847059 -285.575161) (xy 422.831171 -285.526262) (xy 422.823128 -285.47548)
			(xy 422.50445 -285.47548) (xy 422.496734 -285.522956) (xy 422.48115 -285.569637) (xy 422.458279 -285.613214)
			(xy 422.428714 -285.652558) (xy 422.393221 -285.68665) (xy 422.352718 -285.714606) (xy 422.308256 -285.735704)
			(xy 422.260985 -285.749396) (xy 422.21213 -285.755328) (xy 422.162955 -285.753347) (xy 422.114736 -285.743503)
			(xy 422.06872 -285.726051) (xy 422.026099 -285.701444) (xy 421.987978 -285.670319) (xy 421.955343 -285.633482)
			(xy 421.92904 -285.591886) (xy 421.909749 -285.54661) (xy 421.897972 -285.498826) (xy 421.894012 -285.449772)
			(xy 396.990824 -285.449772) (xy 396.990824 -285.523178) (xy 396.990994 -285.529331) (xy 396.99395 -285.541277)
			(xy 396.996666 -285.5468) (xy 397.004794 -285.557976) (xy 397.019526 -285.57347) (xy 397.02613 -285.580582)
			(xy 397.05026 -285.591758) (xy 397.054578 -285.593028) (xy 397.066008 -285.596584) (xy 397.070072 -285.597092)
			(xy 397.096121 -285.6012) (xy 397.146554 -285.616596) (xy 397.193906 -285.639798) (xy 397.236978 -285.670218)
			(xy 397.274679 -285.707085) (xy 397.306054 -285.749466) (xy 397.330308 -285.796288) (xy 397.346827 -285.846365)
			(xy 397.355193 -285.898428) (xy 397.355194 -285.924752) (xy 397.669016 -285.924752) (xy 397.672976 -285.875698)
			(xy 397.684753 -285.827914) (xy 397.704044 -285.782638) (xy 397.730347 -285.741042) (xy 397.762982 -285.704205)
			(xy 397.801103 -285.67308) (xy 397.843724 -285.648473) (xy 397.88974 -285.631021) (xy 397.937959 -285.621177)
			(xy 397.987134 -285.619196) (xy 398.035989 -285.625128) (xy 398.08326 -285.63882) (xy 398.127722 -285.659918)
			(xy 398.168225 -285.687874) (xy 398.203718 -285.721966) (xy 398.233283 -285.76131) (xy 398.256154 -285.804887)
			(xy 398.271738 -285.851568) (xy 398.279633 -285.900145) (xy 398.280128 -285.924752) (xy 398.61923 -285.924752)
			(xy 398.62319 -285.875698) (xy 398.634967 -285.827914) (xy 398.654258 -285.782638) (xy 398.680561 -285.741042)
			(xy 398.713196 -285.704205) (xy 398.751317 -285.67308) (xy 398.793938 -285.648473) (xy 398.839954 -285.631021)
			(xy 398.888173 -285.621177) (xy 398.937348 -285.619196) (xy 398.986203 -285.625128) (xy 399.033474 -285.63882)
			(xy 399.077936 -285.659918) (xy 399.118439 -285.687874) (xy 399.153932 -285.721966) (xy 399.183497 -285.76131)
			(xy 399.206368 -285.804887) (xy 399.221952 -285.851568) (xy 399.229847 -285.900145) (xy 399.230342 -285.924752)
			(xy 399.56919 -285.924752) (xy 399.57315 -285.875698) (xy 399.584927 -285.827914) (xy 399.604218 -285.782638)
			(xy 399.630521 -285.741042) (xy 399.663156 -285.704205) (xy 399.701277 -285.67308) (xy 399.743898 -285.648473)
			(xy 399.789914 -285.631021) (xy 399.838133 -285.621177) (xy 399.887308 -285.619196) (xy 399.936163 -285.625128)
			(xy 399.983434 -285.63882) (xy 400.027896 -285.659918) (xy 400.068399 -285.687874) (xy 400.103892 -285.721966)
			(xy 400.133457 -285.76131) (xy 400.156328 -285.804887) (xy 400.171912 -285.851568) (xy 400.179807 -285.900145)
			(xy 400.180302 -285.924752) (xy 400.51915 -285.924752) (xy 400.52311 -285.875698) (xy 400.534887 -285.827914)
			(xy 400.554178 -285.782638) (xy 400.580481 -285.741042) (xy 400.613116 -285.704205) (xy 400.651237 -285.67308)
			(xy 400.693858 -285.648473) (xy 400.739874 -285.631021) (xy 400.788093 -285.621177) (xy 400.837268 -285.619196)
			(xy 400.886123 -285.625128) (xy 400.933394 -285.63882) (xy 400.977856 -285.659918) (xy 401.018359 -285.687874)
			(xy 401.053852 -285.721966) (xy 401.083417 -285.76131) (xy 401.106288 -285.804887) (xy 401.121872 -285.851568)
			(xy 401.129767 -285.900145) (xy 401.130262 -285.924752) (xy 401.46911 -285.924752) (xy 401.47307 -285.875698)
			(xy 401.484847 -285.827914) (xy 401.504138 -285.782638) (xy 401.530441 -285.741042) (xy 401.563076 -285.704205)
			(xy 401.601197 -285.67308) (xy 401.643818 -285.648473) (xy 401.689834 -285.631021) (xy 401.738053 -285.621177)
			(xy 401.787228 -285.619196) (xy 401.836083 -285.625128) (xy 401.883354 -285.63882) (xy 401.927816 -285.659918)
			(xy 401.968319 -285.687874) (xy 402.003812 -285.721966) (xy 402.033377 -285.76131) (xy 402.056248 -285.804887)
			(xy 402.071832 -285.851568) (xy 402.079727 -285.900145) (xy 402.080222 -285.924752) (xy 402.41907 -285.924752)
			(xy 402.42303 -285.875698) (xy 402.434807 -285.827914) (xy 402.454098 -285.782638) (xy 402.480401 -285.741042)
			(xy 402.513036 -285.704205) (xy 402.551157 -285.67308) (xy 402.593778 -285.648473) (xy 402.639794 -285.631021)
			(xy 402.688013 -285.621177) (xy 402.737188 -285.619196) (xy 402.786043 -285.625128) (xy 402.833314 -285.63882)
			(xy 402.877776 -285.659918) (xy 402.918279 -285.687874) (xy 402.953772 -285.721966) (xy 402.983337 -285.76131)
			(xy 403.006208 -285.804887) (xy 403.021792 -285.851568) (xy 403.029687 -285.900145) (xy 403.030182 -285.924752)
			(xy 403.36903 -285.924752) (xy 403.37299 -285.875698) (xy 403.384767 -285.827914) (xy 403.404058 -285.782638)
			(xy 403.430361 -285.741042) (xy 403.462996 -285.704205) (xy 403.501117 -285.67308) (xy 403.543738 -285.648473)
			(xy 403.589754 -285.631021) (xy 403.637973 -285.621177) (xy 403.687148 -285.619196) (xy 403.736003 -285.625128)
			(xy 403.783274 -285.63882) (xy 403.827736 -285.659918) (xy 403.868239 -285.687874) (xy 403.903732 -285.721966)
			(xy 403.933297 -285.76131) (xy 403.956168 -285.804887) (xy 403.971752 -285.851568) (xy 403.979647 -285.900145)
			(xy 403.980142 -285.924752) (xy 404.31899 -285.924752) (xy 404.32295 -285.875698) (xy 404.334727 -285.827914)
			(xy 404.354018 -285.782638) (xy 404.380321 -285.741042) (xy 404.412956 -285.704205) (xy 404.451077 -285.67308)
			(xy 404.493698 -285.648473) (xy 404.539714 -285.631021) (xy 404.587933 -285.621177) (xy 404.637108 -285.619196)
			(xy 404.685963 -285.625128) (xy 404.733234 -285.63882) (xy 404.777696 -285.659918) (xy 404.818199 -285.687874)
			(xy 404.853692 -285.721966) (xy 404.883257 -285.76131) (xy 404.906128 -285.804887) (xy 404.921712 -285.851568)
			(xy 404.929607 -285.900145) (xy 404.930102 -285.924752) (xy 405.269204 -285.924752) (xy 405.273164 -285.875698)
			(xy 405.284941 -285.827914) (xy 405.304232 -285.782638) (xy 405.330535 -285.741042) (xy 405.36317 -285.704205)
			(xy 405.401291 -285.67308) (xy 405.443912 -285.648473) (xy 405.489928 -285.631021) (xy 405.538147 -285.621177)
			(xy 405.587322 -285.619196) (xy 405.636177 -285.625128) (xy 405.683448 -285.63882) (xy 405.72791 -285.659918)
			(xy 405.768413 -285.687874) (xy 405.803906 -285.721966) (xy 405.833471 -285.76131) (xy 405.856342 -285.804887)
			(xy 405.871926 -285.851568) (xy 405.879821 -285.900145) (xy 405.880316 -285.924752) (xy 406.219164 -285.924752)
			(xy 406.223124 -285.875698) (xy 406.234901 -285.827914) (xy 406.254192 -285.782638) (xy 406.280495 -285.741042)
			(xy 406.31313 -285.704205) (xy 406.351251 -285.67308) (xy 406.393872 -285.648473) (xy 406.439888 -285.631021)
			(xy 406.488107 -285.621177) (xy 406.537282 -285.619196) (xy 406.586137 -285.625128) (xy 406.633408 -285.63882)
			(xy 406.67787 -285.659918) (xy 406.718373 -285.687874) (xy 406.753866 -285.721966) (xy 406.783431 -285.76131)
			(xy 406.806302 -285.804887) (xy 406.821886 -285.851568) (xy 406.829781 -285.900145) (xy 406.830276 -285.924752)
			(xy 408.119084 -285.924752) (xy 408.123044 -285.875698) (xy 408.134821 -285.827914) (xy 408.154112 -285.782638)
			(xy 408.180415 -285.741042) (xy 408.21305 -285.704205) (xy 408.251171 -285.67308) (xy 408.293792 -285.648473)
			(xy 408.339808 -285.631021) (xy 408.388027 -285.621177) (xy 408.437202 -285.619196) (xy 408.486057 -285.625128)
			(xy 408.533328 -285.63882) (xy 408.57779 -285.659918) (xy 408.618293 -285.687874) (xy 408.653786 -285.721966)
			(xy 408.683351 -285.76131) (xy 408.706222 -285.804887) (xy 408.721806 -285.851568) (xy 408.729701 -285.900145)
			(xy 408.730196 -285.924752) (xy 409.069044 -285.924752) (xy 409.073004 -285.875698) (xy 409.084781 -285.827914)
			(xy 409.104072 -285.782638) (xy 409.130375 -285.741042) (xy 409.16301 -285.704205) (xy 409.201131 -285.67308)
			(xy 409.243752 -285.648473) (xy 409.289768 -285.631021) (xy 409.337987 -285.621177) (xy 409.387162 -285.619196)
			(xy 409.436017 -285.625128) (xy 409.483288 -285.63882) (xy 409.52775 -285.659918) (xy 409.568253 -285.687874)
			(xy 409.603746 -285.721966) (xy 409.633311 -285.76131) (xy 409.656182 -285.804887) (xy 409.671766 -285.851568)
			(xy 409.679661 -285.900145) (xy 409.680156 -285.924752) (xy 410.019004 -285.924752) (xy 410.022964 -285.875698)
			(xy 410.034741 -285.827914) (xy 410.054032 -285.782638) (xy 410.080335 -285.741042) (xy 410.11297 -285.704205)
			(xy 410.151091 -285.67308) (xy 410.193712 -285.648473) (xy 410.239728 -285.631021) (xy 410.287947 -285.621177)
			(xy 410.337122 -285.619196) (xy 410.385977 -285.625128) (xy 410.433248 -285.63882) (xy 410.47771 -285.659918)
			(xy 410.518213 -285.687874) (xy 410.553706 -285.721966) (xy 410.583271 -285.76131) (xy 410.606142 -285.804887)
			(xy 410.621726 -285.851568) (xy 410.629621 -285.900145) (xy 410.630116 -285.924752) (xy 410.969218 -285.924752)
			(xy 410.973178 -285.875698) (xy 410.984955 -285.827914) (xy 411.004246 -285.782638) (xy 411.030549 -285.741042)
			(xy 411.063184 -285.704205) (xy 411.101305 -285.67308) (xy 411.143926 -285.648473) (xy 411.189942 -285.631021)
			(xy 411.238161 -285.621177) (xy 411.287336 -285.619196) (xy 411.336191 -285.625128) (xy 411.383462 -285.63882)
			(xy 411.427924 -285.659918) (xy 411.468427 -285.687874) (xy 411.50392 -285.721966) (xy 411.533485 -285.76131)
			(xy 411.556356 -285.804887) (xy 411.57194 -285.851568) (xy 411.579835 -285.900145) (xy 411.58033 -285.924752)
			(xy 411.919178 -285.924752) (xy 411.923138 -285.875698) (xy 411.934915 -285.827914) (xy 411.954206 -285.782638)
			(xy 411.980509 -285.741042) (xy 412.013144 -285.704205) (xy 412.051265 -285.67308) (xy 412.093886 -285.648473)
			(xy 412.139902 -285.631021) (xy 412.188121 -285.621177) (xy 412.237296 -285.619196) (xy 412.286151 -285.625128)
			(xy 412.333422 -285.63882) (xy 412.377884 -285.659918) (xy 412.418387 -285.687874) (xy 412.45388 -285.721966)
			(xy 412.483445 -285.76131) (xy 412.506316 -285.804887) (xy 412.5219 -285.851568) (xy 412.529795 -285.900145)
			(xy 412.53029 -285.924752) (xy 412.869138 -285.924752) (xy 412.873098 -285.875698) (xy 412.884875 -285.827914)
			(xy 412.904166 -285.782638) (xy 412.930469 -285.741042) (xy 412.963104 -285.704205) (xy 413.001225 -285.67308)
			(xy 413.043846 -285.648473) (xy 413.089862 -285.631021) (xy 413.138081 -285.621177) (xy 413.187256 -285.619196)
			(xy 413.236111 -285.625128) (xy 413.283382 -285.63882) (xy 413.327844 -285.659918) (xy 413.368347 -285.687874)
			(xy 413.40384 -285.721966) (xy 413.433405 -285.76131) (xy 413.456276 -285.804887) (xy 413.47186 -285.851568)
			(xy 413.479755 -285.900145) (xy 413.48025 -285.924752) (xy 413.819098 -285.924752) (xy 413.823058 -285.875698)
			(xy 413.834835 -285.827914) (xy 413.854126 -285.782638) (xy 413.880429 -285.741042) (xy 413.913064 -285.704205)
			(xy 413.951185 -285.67308) (xy 413.993806 -285.648473) (xy 414.039822 -285.631021) (xy 414.088041 -285.621177)
			(xy 414.137216 -285.619196) (xy 414.186071 -285.625128) (xy 414.233342 -285.63882) (xy 414.277804 -285.659918)
			(xy 414.318307 -285.687874) (xy 414.3538 -285.721966) (xy 414.383365 -285.76131) (xy 414.406236 -285.804887)
			(xy 414.42182 -285.851568) (xy 414.429715 -285.900145) (xy 414.43021 -285.924752) (xy 414.769058 -285.924752)
			(xy 414.773018 -285.875698) (xy 414.784795 -285.827914) (xy 414.804086 -285.782638) (xy 414.830389 -285.741042)
			(xy 414.863024 -285.704205) (xy 414.901145 -285.67308) (xy 414.943766 -285.648473) (xy 414.989782 -285.631021)
			(xy 415.038001 -285.621177) (xy 415.087176 -285.619196) (xy 415.136031 -285.625128) (xy 415.183302 -285.63882)
			(xy 415.227764 -285.659918) (xy 415.268267 -285.687874) (xy 415.30376 -285.721966) (xy 415.333325 -285.76131)
			(xy 415.356196 -285.804887) (xy 415.37178 -285.851568) (xy 415.379675 -285.900145) (xy 415.38017 -285.924752)
			(xy 415.719018 -285.924752) (xy 415.722978 -285.875698) (xy 415.734755 -285.827914) (xy 415.754046 -285.782638)
			(xy 415.780349 -285.741042) (xy 415.812984 -285.704205) (xy 415.851105 -285.67308) (xy 415.893726 -285.648473)
			(xy 415.939742 -285.631021) (xy 415.987961 -285.621177) (xy 416.037136 -285.619196) (xy 416.085991 -285.625128)
			(xy 416.133262 -285.63882) (xy 416.177724 -285.659918) (xy 416.218227 -285.687874) (xy 416.25372 -285.721966)
			(xy 416.283285 -285.76131) (xy 416.306156 -285.804887) (xy 416.32174 -285.851568) (xy 416.329635 -285.900145)
			(xy 416.33013 -285.924752) (xy 416.668978 -285.924752) (xy 416.672938 -285.875698) (xy 416.684715 -285.827914)
			(xy 416.704006 -285.782638) (xy 416.730309 -285.741042) (xy 416.762944 -285.704205) (xy 416.801065 -285.67308)
			(xy 416.843686 -285.648473) (xy 416.889702 -285.631021) (xy 416.937921 -285.621177) (xy 416.987096 -285.619196)
			(xy 417.035951 -285.625128) (xy 417.083222 -285.63882) (xy 417.127684 -285.659918) (xy 417.168187 -285.687874)
			(xy 417.20368 -285.721966) (xy 417.233245 -285.76131) (xy 417.256116 -285.804887) (xy 417.2717 -285.851568)
			(xy 417.279595 -285.900145) (xy 417.28009 -285.924752) (xy 417.619192 -285.924752) (xy 417.623152 -285.875698)
			(xy 417.634929 -285.827914) (xy 417.65422 -285.782638) (xy 417.680523 -285.741042) (xy 417.713158 -285.704205)
			(xy 417.751279 -285.67308) (xy 417.7939 -285.648473) (xy 417.839916 -285.631021) (xy 417.888135 -285.621177)
			(xy 417.93731 -285.619196) (xy 417.986165 -285.625128) (xy 418.033436 -285.63882) (xy 418.077898 -285.659918)
			(xy 418.118401 -285.687874) (xy 418.153894 -285.721966) (xy 418.183459 -285.76131) (xy 418.20633 -285.804887)
			(xy 418.221914 -285.851568) (xy 418.229809 -285.900145) (xy 418.230304 -285.924752) (xy 418.569152 -285.924752)
			(xy 418.573112 -285.875698) (xy 418.584889 -285.827914) (xy 418.60418 -285.782638) (xy 418.630483 -285.741042)
			(xy 418.663118 -285.704205) (xy 418.701239 -285.67308) (xy 418.74386 -285.648473) (xy 418.789876 -285.631021)
			(xy 418.838095 -285.621177) (xy 418.88727 -285.619196) (xy 418.936125 -285.625128) (xy 418.983396 -285.63882)
			(xy 419.027858 -285.659918) (xy 419.068361 -285.687874) (xy 419.103854 -285.721966) (xy 419.133419 -285.76131)
			(xy 419.15629 -285.804887) (xy 419.171874 -285.851568) (xy 419.179769 -285.900145) (xy 419.180264 -285.924752)
			(xy 419.179769 -285.949359) (xy 419.171874 -285.997936) (xy 419.15629 -286.044617) (xy 419.133419 -286.088194)
			(xy 419.103854 -286.127538) (xy 419.068361 -286.16163) (xy 419.027858 -286.189586) (xy 418.983396 -286.210684)
			(xy 418.936125 -286.224376) (xy 418.88727 -286.230308) (xy 418.838095 -286.228327) (xy 418.789876 -286.218483)
			(xy 418.74386 -286.201031) (xy 418.701239 -286.176424) (xy 418.663118 -286.145299) (xy 418.630483 -286.108462)
			(xy 418.60418 -286.066866) (xy 418.584889 -286.02159) (xy 418.573112 -285.973806) (xy 418.569152 -285.924752)
			(xy 418.230304 -285.924752) (xy 418.229809 -285.949359) (xy 418.221914 -285.997936) (xy 418.20633 -286.044617)
			(xy 418.183459 -286.088194) (xy 418.153894 -286.127538) (xy 418.118401 -286.16163) (xy 418.077898 -286.189586)
			(xy 418.033436 -286.210684) (xy 417.986165 -286.224376) (xy 417.93731 -286.230308) (xy 417.888135 -286.228327)
			(xy 417.839916 -286.218483) (xy 417.7939 -286.201031) (xy 417.751279 -286.176424) (xy 417.713158 -286.145299)
			(xy 417.680523 -286.108462) (xy 417.65422 -286.066866) (xy 417.634929 -286.02159) (xy 417.623152 -285.973806)
			(xy 417.619192 -285.924752) (xy 417.28009 -285.924752) (xy 417.279595 -285.949359) (xy 417.2717 -285.997936)
			(xy 417.256116 -286.044617) (xy 417.233245 -286.088194) (xy 417.20368 -286.127538) (xy 417.168187 -286.16163)
			(xy 417.127684 -286.189586) (xy 417.083222 -286.210684) (xy 417.035951 -286.224376) (xy 416.987096 -286.230308)
			(xy 416.937921 -286.228327) (xy 416.889702 -286.218483) (xy 416.843686 -286.201031) (xy 416.801065 -286.176424)
			(xy 416.762944 -286.145299) (xy 416.730309 -286.108462) (xy 416.704006 -286.066866) (xy 416.684715 -286.02159)
			(xy 416.672938 -285.973806) (xy 416.668978 -285.924752) (xy 416.33013 -285.924752) (xy 416.329635 -285.949359)
			(xy 416.32174 -285.997936) (xy 416.306156 -286.044617) (xy 416.283285 -286.088194) (xy 416.25372 -286.127538)
			(xy 416.218227 -286.16163) (xy 416.177724 -286.189586) (xy 416.133262 -286.210684) (xy 416.085991 -286.224376)
			(xy 416.037136 -286.230308) (xy 415.987961 -286.228327) (xy 415.939742 -286.218483) (xy 415.893726 -286.201031)
			(xy 415.851105 -286.176424) (xy 415.812984 -286.145299) (xy 415.780349 -286.108462) (xy 415.754046 -286.066866)
			(xy 415.734755 -286.02159) (xy 415.722978 -285.973806) (xy 415.719018 -285.924752) (xy 415.38017 -285.924752)
			(xy 415.379675 -285.949359) (xy 415.37178 -285.997936) (xy 415.356196 -286.044617) (xy 415.333325 -286.088194)
			(xy 415.30376 -286.127538) (xy 415.268267 -286.16163) (xy 415.227764 -286.189586) (xy 415.183302 -286.210684)
			(xy 415.136031 -286.224376) (xy 415.087176 -286.230308) (xy 415.038001 -286.228327) (xy 414.989782 -286.218483)
			(xy 414.943766 -286.201031) (xy 414.901145 -286.176424) (xy 414.863024 -286.145299) (xy 414.830389 -286.108462)
			(xy 414.804086 -286.066866) (xy 414.784795 -286.02159) (xy 414.773018 -285.973806) (xy 414.769058 -285.924752)
			(xy 414.43021 -285.924752) (xy 414.429715 -285.949359) (xy 414.42182 -285.997936) (xy 414.406236 -286.044617)
			(xy 414.383365 -286.088194) (xy 414.3538 -286.127538) (xy 414.318307 -286.16163) (xy 414.277804 -286.189586)
			(xy 414.233342 -286.210684) (xy 414.186071 -286.224376) (xy 414.137216 -286.230308) (xy 414.088041 -286.228327)
			(xy 414.039822 -286.218483) (xy 413.993806 -286.201031) (xy 413.951185 -286.176424) (xy 413.913064 -286.145299)
			(xy 413.880429 -286.108462) (xy 413.854126 -286.066866) (xy 413.834835 -286.02159) (xy 413.823058 -285.973806)
			(xy 413.819098 -285.924752) (xy 413.48025 -285.924752) (xy 413.479755 -285.949359) (xy 413.47186 -285.997936)
			(xy 413.456276 -286.044617) (xy 413.433405 -286.088194) (xy 413.40384 -286.127538) (xy 413.368347 -286.16163)
			(xy 413.327844 -286.189586) (xy 413.283382 -286.210684) (xy 413.236111 -286.224376) (xy 413.187256 -286.230308)
			(xy 413.138081 -286.228327) (xy 413.089862 -286.218483) (xy 413.043846 -286.201031) (xy 413.001225 -286.176424)
			(xy 412.963104 -286.145299) (xy 412.930469 -286.108462) (xy 412.904166 -286.066866) (xy 412.884875 -286.02159)
			(xy 412.873098 -285.973806) (xy 412.869138 -285.924752) (xy 412.53029 -285.924752) (xy 412.529795 -285.949359)
			(xy 412.5219 -285.997936) (xy 412.506316 -286.044617) (xy 412.483445 -286.088194) (xy 412.45388 -286.127538)
			(xy 412.418387 -286.16163) (xy 412.377884 -286.189586) (xy 412.333422 -286.210684) (xy 412.286151 -286.224376)
			(xy 412.237296 -286.230308) (xy 412.188121 -286.228327) (xy 412.139902 -286.218483) (xy 412.093886 -286.201031)
			(xy 412.051265 -286.176424) (xy 412.013144 -286.145299) (xy 411.980509 -286.108462) (xy 411.954206 -286.066866)
			(xy 411.934915 -286.02159) (xy 411.923138 -285.973806) (xy 411.919178 -285.924752) (xy 411.58033 -285.924752)
			(xy 411.579835 -285.949359) (xy 411.57194 -285.997936) (xy 411.556356 -286.044617) (xy 411.533485 -286.088194)
			(xy 411.50392 -286.127538) (xy 411.468427 -286.16163) (xy 411.427924 -286.189586) (xy 411.383462 -286.210684)
			(xy 411.336191 -286.224376) (xy 411.287336 -286.230308) (xy 411.238161 -286.228327) (xy 411.189942 -286.218483)
			(xy 411.143926 -286.201031) (xy 411.101305 -286.176424) (xy 411.063184 -286.145299) (xy 411.030549 -286.108462)
			(xy 411.004246 -286.066866) (xy 410.984955 -286.02159) (xy 410.973178 -285.973806) (xy 410.969218 -285.924752)
			(xy 410.630116 -285.924752) (xy 410.629621 -285.949359) (xy 410.621726 -285.997936) (xy 410.606142 -286.044617)
			(xy 410.583271 -286.088194) (xy 410.553706 -286.127538) (xy 410.518213 -286.16163) (xy 410.47771 -286.189586)
			(xy 410.433248 -286.210684) (xy 410.385977 -286.224376) (xy 410.337122 -286.230308) (xy 410.287947 -286.228327)
			(xy 410.239728 -286.218483) (xy 410.193712 -286.201031) (xy 410.151091 -286.176424) (xy 410.11297 -286.145299)
			(xy 410.080335 -286.108462) (xy 410.054032 -286.066866) (xy 410.034741 -286.02159) (xy 410.022964 -285.973806)
			(xy 410.019004 -285.924752) (xy 409.680156 -285.924752) (xy 409.679661 -285.949359) (xy 409.671766 -285.997936)
			(xy 409.656182 -286.044617) (xy 409.633311 -286.088194) (xy 409.603746 -286.127538) (xy 409.568253 -286.16163)
			(xy 409.52775 -286.189586) (xy 409.483288 -286.210684) (xy 409.436017 -286.224376) (xy 409.387162 -286.230308)
			(xy 409.337987 -286.228327) (xy 409.289768 -286.218483) (xy 409.243752 -286.201031) (xy 409.201131 -286.176424)
			(xy 409.16301 -286.145299) (xy 409.130375 -286.108462) (xy 409.104072 -286.066866) (xy 409.084781 -286.02159)
			(xy 409.073004 -285.973806) (xy 409.069044 -285.924752) (xy 408.730196 -285.924752) (xy 408.729701 -285.949359)
			(xy 408.721806 -285.997936) (xy 408.706222 -286.044617) (xy 408.683351 -286.088194) (xy 408.653786 -286.127538)
			(xy 408.618293 -286.16163) (xy 408.57779 -286.189586) (xy 408.533328 -286.210684) (xy 408.486057 -286.224376)
			(xy 408.437202 -286.230308) (xy 408.388027 -286.228327) (xy 408.339808 -286.218483) (xy 408.293792 -286.201031)
			(xy 408.251171 -286.176424) (xy 408.21305 -286.145299) (xy 408.180415 -286.108462) (xy 408.154112 -286.066866)
			(xy 408.134821 -286.02159) (xy 408.123044 -285.973806) (xy 408.119084 -285.924752) (xy 406.830276 -285.924752)
			(xy 406.829781 -285.949359) (xy 406.821886 -285.997936) (xy 406.806302 -286.044617) (xy 406.783431 -286.088194)
			(xy 406.753866 -286.127538) (xy 406.718373 -286.16163) (xy 406.67787 -286.189586) (xy 406.633408 -286.210684)
			(xy 406.586137 -286.224376) (xy 406.537282 -286.230308) (xy 406.488107 -286.228327) (xy 406.439888 -286.218483)
			(xy 406.393872 -286.201031) (xy 406.351251 -286.176424) (xy 406.31313 -286.145299) (xy 406.280495 -286.108462)
			(xy 406.254192 -286.066866) (xy 406.234901 -286.02159) (xy 406.223124 -285.973806) (xy 406.219164 -285.924752)
			(xy 405.880316 -285.924752) (xy 405.879821 -285.949359) (xy 405.871926 -285.997936) (xy 405.856342 -286.044617)
			(xy 405.833471 -286.088194) (xy 405.803906 -286.127538) (xy 405.768413 -286.16163) (xy 405.72791 -286.189586)
			(xy 405.683448 -286.210684) (xy 405.636177 -286.224376) (xy 405.587322 -286.230308) (xy 405.538147 -286.228327)
			(xy 405.489928 -286.218483) (xy 405.443912 -286.201031) (xy 405.401291 -286.176424) (xy 405.36317 -286.145299)
			(xy 405.330535 -286.108462) (xy 405.304232 -286.066866) (xy 405.284941 -286.02159) (xy 405.273164 -285.973806)
			(xy 405.269204 -285.924752) (xy 404.930102 -285.924752) (xy 404.929607 -285.949359) (xy 404.921712 -285.997936)
			(xy 404.906128 -286.044617) (xy 404.883257 -286.088194) (xy 404.853692 -286.127538) (xy 404.818199 -286.16163)
			(xy 404.777696 -286.189586) (xy 404.733234 -286.210684) (xy 404.685963 -286.224376) (xy 404.637108 -286.230308)
			(xy 404.587933 -286.228327) (xy 404.539714 -286.218483) (xy 404.493698 -286.201031) (xy 404.451077 -286.176424)
			(xy 404.412956 -286.145299) (xy 404.380321 -286.108462) (xy 404.354018 -286.066866) (xy 404.334727 -286.02159)
			(xy 404.32295 -285.973806) (xy 404.31899 -285.924752) (xy 403.980142 -285.924752) (xy 403.979647 -285.949359)
			(xy 403.971752 -285.997936) (xy 403.956168 -286.044617) (xy 403.933297 -286.088194) (xy 403.903732 -286.127538)
			(xy 403.868239 -286.16163) (xy 403.827736 -286.189586) (xy 403.783274 -286.210684) (xy 403.736003 -286.224376)
			(xy 403.687148 -286.230308) (xy 403.637973 -286.228327) (xy 403.589754 -286.218483) (xy 403.543738 -286.201031)
			(xy 403.501117 -286.176424) (xy 403.462996 -286.145299) (xy 403.430361 -286.108462) (xy 403.404058 -286.066866)
			(xy 403.384767 -286.02159) (xy 403.37299 -285.973806) (xy 403.36903 -285.924752) (xy 403.030182 -285.924752)
			(xy 403.029687 -285.949359) (xy 403.021792 -285.997936) (xy 403.006208 -286.044617) (xy 402.983337 -286.088194)
			(xy 402.953772 -286.127538) (xy 402.918279 -286.16163) (xy 402.877776 -286.189586) (xy 402.833314 -286.210684)
			(xy 402.786043 -286.224376) (xy 402.737188 -286.230308) (xy 402.688013 -286.228327) (xy 402.639794 -286.218483)
			(xy 402.593778 -286.201031) (xy 402.551157 -286.176424) (xy 402.513036 -286.145299) (xy 402.480401 -286.108462)
			(xy 402.454098 -286.066866) (xy 402.434807 -286.02159) (xy 402.42303 -285.973806) (xy 402.41907 -285.924752)
			(xy 402.080222 -285.924752) (xy 402.079727 -285.949359) (xy 402.071832 -285.997936) (xy 402.056248 -286.044617)
			(xy 402.033377 -286.088194) (xy 402.003812 -286.127538) (xy 401.968319 -286.16163) (xy 401.927816 -286.189586)
			(xy 401.883354 -286.210684) (xy 401.836083 -286.224376) (xy 401.787228 -286.230308) (xy 401.738053 -286.228327)
			(xy 401.689834 -286.218483) (xy 401.643818 -286.201031) (xy 401.601197 -286.176424) (xy 401.563076 -286.145299)
			(xy 401.530441 -286.108462) (xy 401.504138 -286.066866) (xy 401.484847 -286.02159) (xy 401.47307 -285.973806)
			(xy 401.46911 -285.924752) (xy 401.130262 -285.924752) (xy 401.129767 -285.949359) (xy 401.121872 -285.997936)
			(xy 401.106288 -286.044617) (xy 401.083417 -286.088194) (xy 401.053852 -286.127538) (xy 401.018359 -286.16163)
			(xy 400.977856 -286.189586) (xy 400.933394 -286.210684) (xy 400.886123 -286.224376) (xy 400.837268 -286.230308)
			(xy 400.788093 -286.228327) (xy 400.739874 -286.218483) (xy 400.693858 -286.201031) (xy 400.651237 -286.176424)
			(xy 400.613116 -286.145299) (xy 400.580481 -286.108462) (xy 400.554178 -286.066866) (xy 400.534887 -286.02159)
			(xy 400.52311 -285.973806) (xy 400.51915 -285.924752) (xy 400.180302 -285.924752) (xy 400.179807 -285.949359)
			(xy 400.171912 -285.997936) (xy 400.156328 -286.044617) (xy 400.133457 -286.088194) (xy 400.103892 -286.127538)
			(xy 400.068399 -286.16163) (xy 400.027896 -286.189586) (xy 399.983434 -286.210684) (xy 399.936163 -286.224376)
			(xy 399.887308 -286.230308) (xy 399.838133 -286.228327) (xy 399.789914 -286.218483) (xy 399.743898 -286.201031)
			(xy 399.701277 -286.176424) (xy 399.663156 -286.145299) (xy 399.630521 -286.108462) (xy 399.604218 -286.066866)
			(xy 399.584927 -286.02159) (xy 399.57315 -285.973806) (xy 399.56919 -285.924752) (xy 399.230342 -285.924752)
			(xy 399.229847 -285.949359) (xy 399.221952 -285.997936) (xy 399.206368 -286.044617) (xy 399.183497 -286.088194)
			(xy 399.153932 -286.127538) (xy 399.118439 -286.16163) (xy 399.077936 -286.189586) (xy 399.033474 -286.210684)
			(xy 398.986203 -286.224376) (xy 398.937348 -286.230308) (xy 398.888173 -286.228327) (xy 398.839954 -286.218483)
			(xy 398.793938 -286.201031) (xy 398.751317 -286.176424) (xy 398.713196 -286.145299) (xy 398.680561 -286.108462)
			(xy 398.654258 -286.066866) (xy 398.634967 -286.02159) (xy 398.62319 -285.973806) (xy 398.61923 -285.924752)
			(xy 398.280128 -285.924752) (xy 398.279633 -285.949359) (xy 398.271738 -285.997936) (xy 398.256154 -286.044617)
			(xy 398.233283 -286.088194) (xy 398.203718 -286.127538) (xy 398.168225 -286.16163) (xy 398.127722 -286.189586)
			(xy 398.08326 -286.210684) (xy 398.035989 -286.224376) (xy 397.987134 -286.230308) (xy 397.937959 -286.228327)
			(xy 397.88974 -286.218483) (xy 397.843724 -286.201031) (xy 397.801103 -286.176424) (xy 397.762982 -286.145299)
			(xy 397.730347 -286.108462) (xy 397.704044 -286.066866) (xy 397.684753 -286.02159) (xy 397.672976 -285.973806)
			(xy 397.669016 -285.924752) (xy 397.355194 -285.924752) (xy 397.355195 -285.951159) (xy 397.34683 -286.003222)
			(xy 397.330313 -286.0533) (xy 397.306061 -286.100122) (xy 397.274687 -286.142505) (xy 397.236988 -286.179374)
			(xy 397.193917 -286.209795) (xy 397.146566 -286.232999) (xy 397.096133 -286.248397) (xy 397.070072 -286.252412)
			(xy 397.066008 -286.25292) (xy 397.054578 -286.256476) (xy 397.05026 -286.257746) (xy 397.02613 -286.268922)
			(xy 397.019526 -286.276034) (xy 397.004794 -286.291528) (xy 396.996666 -286.302704) (xy 396.993974 -286.308236)
			(xy 396.991027 -286.320177) (xy 396.990824 -286.326326) (xy 396.990824 -286.399732) (xy 421.894012 -286.399732)
			(xy 421.897972 -286.350678) (xy 421.909749 -286.302894) (xy 421.92904 -286.257618) (xy 421.955343 -286.216022)
			(xy 421.987978 -286.179185) (xy 422.026099 -286.14806) (xy 422.06872 -286.123453) (xy 422.114736 -286.106001)
			(xy 422.162955 -286.096157) (xy 422.21213 -286.094176) (xy 422.260985 -286.100108) (xy 422.308256 -286.1138)
			(xy 422.352718 -286.134898) (xy 422.393221 -286.162854) (xy 422.428714 -286.196946) (xy 422.458279 -286.23629)
			(xy 422.48115 -286.279867) (xy 422.496734 -286.326548) (xy 422.504629 -286.375125) (xy 422.505124 -286.399732)
			(xy 422.844226 -286.399732) (xy 422.848186 -286.350678) (xy 422.859963 -286.302894) (xy 422.879254 -286.257618)
			(xy 422.905557 -286.216022) (xy 422.938192 -286.179185) (xy 422.976313 -286.14806) (xy 423.018934 -286.123453)
			(xy 423.06495 -286.106001) (xy 423.113169 -286.096157) (xy 423.162344 -286.094176) (xy 423.211199 -286.100108)
			(xy 423.25847 -286.1138) (xy 423.302932 -286.134898) (xy 423.343435 -286.162854) (xy 423.378928 -286.196946)
			(xy 423.408493 -286.23629) (xy 423.431364 -286.279867) (xy 423.446948 -286.326548) (xy 423.454843 -286.375125)
			(xy 423.455338 -286.399732) (xy 423.794186 -286.399732) (xy 423.798146 -286.350678) (xy 423.809923 -286.302894)
			(xy 423.829214 -286.257618) (xy 423.855517 -286.216022) (xy 423.888152 -286.179185) (xy 423.926273 -286.14806)
			(xy 423.968894 -286.123453) (xy 424.01491 -286.106001) (xy 424.063129 -286.096157) (xy 424.112304 -286.094176)
			(xy 424.161159 -286.100108) (xy 424.20843 -286.1138) (xy 424.252892 -286.134898) (xy 424.293395 -286.162854)
			(xy 424.328888 -286.196946) (xy 424.358453 -286.23629) (xy 424.381324 -286.279867) (xy 424.396908 -286.326548)
			(xy 424.404803 -286.375125) (xy 424.405298 -286.399732) (xy 424.404803 -286.424339) (xy 424.404583 -286.425694)
			(xy 424.723302 -286.425694) (xy 424.723302 -286.374278) (xy 424.731345 -286.323496) (xy 424.747233 -286.274597)
			(xy 424.770576 -286.228785) (xy 424.800797 -286.187189) (xy 424.837153 -286.150833) (xy 424.878749 -286.120612)
			(xy 424.924561 -286.097269) (xy 424.97346 -286.081381) (xy 425.024242 -286.073338) (xy 425.075658 -286.073338)
			(xy 425.12644 -286.081381) (xy 425.175339 -286.097269) (xy 425.221151 -286.120612) (xy 425.262747 -286.150833)
			(xy 425.299103 -286.187189) (xy 425.329324 -286.228785) (xy 425.352667 -286.274597) (xy 425.368555 -286.323496)
			(xy 425.376598 -286.374278) (xy 425.377102 -286.399986) (xy 425.376598 -286.425694) (xy 425.673262 -286.425694)
			(xy 425.673262 -286.374278) (xy 425.681305 -286.323496) (xy 425.697193 -286.274597) (xy 425.720536 -286.228785)
			(xy 425.750757 -286.187189) (xy 425.787113 -286.150833) (xy 425.828709 -286.120612) (xy 425.874521 -286.097269)
			(xy 425.92342 -286.081381) (xy 425.974202 -286.073338) (xy 426.025618 -286.073338) (xy 426.0764 -286.081381)
			(xy 426.125299 -286.097269) (xy 426.171111 -286.120612) (xy 426.212707 -286.150833) (xy 426.249063 -286.187189)
			(xy 426.279284 -286.228785) (xy 426.302627 -286.274597) (xy 426.318515 -286.323496) (xy 426.326558 -286.374278)
			(xy 426.327057 -286.399732) (xy 426.644066 -286.399732) (xy 426.648026 -286.350678) (xy 426.659803 -286.302894)
			(xy 426.679094 -286.257618) (xy 426.705397 -286.216022) (xy 426.738032 -286.179185) (xy 426.776153 -286.14806)
			(xy 426.818774 -286.123453) (xy 426.86479 -286.106001) (xy 426.913009 -286.096157) (xy 426.962184 -286.094176)
			(xy 427.011039 -286.100108) (xy 427.05831 -286.1138) (xy 427.102772 -286.134898) (xy 427.143275 -286.162854)
			(xy 427.178768 -286.196946) (xy 427.208333 -286.23629) (xy 427.231204 -286.279867) (xy 427.246788 -286.326548)
			(xy 427.254683 -286.375125) (xy 427.255178 -286.399732) (xy 427.254683 -286.424339) (xy 427.254504 -286.42544)
			(xy 427.573182 -286.42544) (xy 427.573182 -286.374024) (xy 427.581225 -286.323242) (xy 427.597113 -286.274343)
			(xy 427.620456 -286.228531) (xy 427.650677 -286.186935) (xy 427.687033 -286.150579) (xy 427.728629 -286.120358)
			(xy 427.774441 -286.097015) (xy 427.82334 -286.081127) (xy 427.874122 -286.073084) (xy 427.925538 -286.073084)
			(xy 427.97632 -286.081127) (xy 428.025219 -286.097015) (xy 428.071031 -286.120358) (xy 428.112627 -286.150579)
			(xy 428.148983 -286.186935) (xy 428.179204 -286.228531) (xy 428.202547 -286.274343) (xy 428.218435 -286.323242)
			(xy 428.226478 -286.374024) (xy 428.226982 -286.399732) (xy 428.226478 -286.42544) (xy 428.523142 -286.42544)
			(xy 428.523142 -286.374024) (xy 428.531185 -286.323242) (xy 428.547073 -286.274343) (xy 428.570416 -286.228531)
			(xy 428.600637 -286.186935) (xy 428.636993 -286.150579) (xy 428.678589 -286.120358) (xy 428.724401 -286.097015)
			(xy 428.7733 -286.081127) (xy 428.824082 -286.073084) (xy 428.875498 -286.073084) (xy 428.92628 -286.081127)
			(xy 428.975179 -286.097015) (xy 429.020991 -286.120358) (xy 429.062587 -286.150579) (xy 429.098943 -286.186935)
			(xy 429.129164 -286.228531) (xy 429.152507 -286.274343) (xy 429.168395 -286.323242) (xy 429.176438 -286.374024)
			(xy 429.176942 -286.399732) (xy 429.4942 -286.399732) (xy 429.49816 -286.350678) (xy 429.509937 -286.302894)
			(xy 429.529228 -286.257618) (xy 429.555531 -286.216022) (xy 429.588166 -286.179185) (xy 429.626287 -286.14806)
			(xy 429.668908 -286.123453) (xy 429.714924 -286.106001) (xy 429.763143 -286.096157) (xy 429.812318 -286.094176)
			(xy 429.861173 -286.100108) (xy 429.908444 -286.1138) (xy 429.952906 -286.134898) (xy 429.993409 -286.162854)
			(xy 430.028902 -286.196946) (xy 430.058467 -286.23629) (xy 430.081338 -286.279867) (xy 430.096922 -286.326548)
			(xy 430.104817 -286.375125) (xy 430.105312 -286.399732) (xy 430.44416 -286.399732) (xy 430.44812 -286.350678)
			(xy 430.459897 -286.302894) (xy 430.479188 -286.257618) (xy 430.505491 -286.216022) (xy 430.538126 -286.179185)
			(xy 430.576247 -286.14806) (xy 430.618868 -286.123453) (xy 430.664884 -286.106001) (xy 430.713103 -286.096157)
			(xy 430.762278 -286.094176) (xy 430.811133 -286.100108) (xy 430.858404 -286.1138) (xy 430.902866 -286.134898)
			(xy 430.943369 -286.162854) (xy 430.978862 -286.196946) (xy 431.008427 -286.23629) (xy 431.031298 -286.279867)
			(xy 431.046882 -286.326548) (xy 431.054777 -286.375125) (xy 431.055272 -286.399732) (xy 431.054777 -286.424339)
			(xy 431.046882 -286.472916) (xy 431.031298 -286.519597) (xy 431.008427 -286.563174) (xy 430.978862 -286.602518)
			(xy 430.943369 -286.63661) (xy 430.902866 -286.664566) (xy 430.858404 -286.685664) (xy 430.811133 -286.699356)
			(xy 430.762278 -286.705288) (xy 430.713103 -286.703307) (xy 430.664884 -286.693463) (xy 430.618868 -286.676011)
			(xy 430.576247 -286.651404) (xy 430.538126 -286.620279) (xy 430.505491 -286.583442) (xy 430.479188 -286.541846)
			(xy 430.459897 -286.49657) (xy 430.44812 -286.448786) (xy 430.44416 -286.399732) (xy 430.105312 -286.399732)
			(xy 430.104817 -286.424339) (xy 430.096922 -286.472916) (xy 430.081338 -286.519597) (xy 430.058467 -286.563174)
			(xy 430.028902 -286.602518) (xy 429.993409 -286.63661) (xy 429.952906 -286.664566) (xy 429.908444 -286.685664)
			(xy 429.861173 -286.699356) (xy 429.812318 -286.705288) (xy 429.763143 -286.703307) (xy 429.714924 -286.693463)
			(xy 429.668908 -286.676011) (xy 429.626287 -286.651404) (xy 429.588166 -286.620279) (xy 429.555531 -286.583442)
			(xy 429.529228 -286.541846) (xy 429.509937 -286.49657) (xy 429.49816 -286.448786) (xy 429.4942 -286.399732)
			(xy 429.176942 -286.399732) (xy 429.176438 -286.42544) (xy 429.168395 -286.476222) (xy 429.152507 -286.525121)
			(xy 429.129164 -286.570933) (xy 429.098943 -286.612529) (xy 429.062587 -286.648885) (xy 429.020991 -286.679106)
			(xy 428.975179 -286.702449) (xy 428.92628 -286.718337) (xy 428.875498 -286.72638) (xy 428.824082 -286.72638)
			(xy 428.7733 -286.718337) (xy 428.724401 -286.702449) (xy 428.678589 -286.679106) (xy 428.636993 -286.648885)
			(xy 428.600637 -286.612529) (xy 428.570416 -286.570933) (xy 428.547073 -286.525121) (xy 428.531185 -286.476222)
			(xy 428.523142 -286.42544) (xy 428.226478 -286.42544) (xy 428.218435 -286.476222) (xy 428.202547 -286.525121)
			(xy 428.179204 -286.570933) (xy 428.148983 -286.612529) (xy 428.112627 -286.648885) (xy 428.071031 -286.679106)
			(xy 428.025219 -286.702449) (xy 427.97632 -286.718337) (xy 427.925538 -286.72638) (xy 427.874122 -286.72638)
			(xy 427.82334 -286.718337) (xy 427.774441 -286.702449) (xy 427.728629 -286.679106) (xy 427.687033 -286.648885)
			(xy 427.650677 -286.612529) (xy 427.620456 -286.570933) (xy 427.597113 -286.525121) (xy 427.581225 -286.476222)
			(xy 427.573182 -286.42544) (xy 427.254504 -286.42544) (xy 427.246788 -286.472916) (xy 427.231204 -286.519597)
			(xy 427.208333 -286.563174) (xy 427.178768 -286.602518) (xy 427.143275 -286.63661) (xy 427.102772 -286.664566)
			(xy 427.05831 -286.685664) (xy 427.011039 -286.699356) (xy 426.962184 -286.705288) (xy 426.913009 -286.703307)
			(xy 426.86479 -286.693463) (xy 426.818774 -286.676011) (xy 426.776153 -286.651404) (xy 426.738032 -286.620279)
			(xy 426.705397 -286.583442) (xy 426.679094 -286.541846) (xy 426.659803 -286.49657) (xy 426.648026 -286.448786)
			(xy 426.644066 -286.399732) (xy 426.327057 -286.399732) (xy 426.327062 -286.399986) (xy 426.326558 -286.425694)
			(xy 426.318515 -286.476476) (xy 426.302627 -286.525375) (xy 426.279284 -286.571187) (xy 426.249063 -286.612783)
			(xy 426.212707 -286.649139) (xy 426.171111 -286.67936) (xy 426.125299 -286.702703) (xy 426.0764 -286.718591)
			(xy 426.025618 -286.726634) (xy 425.974202 -286.726634) (xy 425.92342 -286.718591) (xy 425.874521 -286.702703)
			(xy 425.828709 -286.67936) (xy 425.787113 -286.649139) (xy 425.750757 -286.612783) (xy 425.720536 -286.571187)
			(xy 425.697193 -286.525375) (xy 425.681305 -286.476476) (xy 425.673262 -286.425694) (xy 425.376598 -286.425694)
			(xy 425.368555 -286.476476) (xy 425.352667 -286.525375) (xy 425.329324 -286.571187) (xy 425.299103 -286.612783)
			(xy 425.262747 -286.649139) (xy 425.221151 -286.67936) (xy 425.175339 -286.702703) (xy 425.12644 -286.718591)
			(xy 425.075658 -286.726634) (xy 425.024242 -286.726634) (xy 424.97346 -286.718591) (xy 424.924561 -286.702703)
			(xy 424.878749 -286.67936) (xy 424.837153 -286.649139) (xy 424.800797 -286.612783) (xy 424.770576 -286.571187)
			(xy 424.747233 -286.525375) (xy 424.731345 -286.476476) (xy 424.723302 -286.425694) (xy 424.404583 -286.425694)
			(xy 424.396908 -286.472916) (xy 424.381324 -286.519597) (xy 424.358453 -286.563174) (xy 424.328888 -286.602518)
			(xy 424.293395 -286.63661) (xy 424.252892 -286.664566) (xy 424.20843 -286.685664) (xy 424.161159 -286.699356)
			(xy 424.112304 -286.705288) (xy 424.063129 -286.703307) (xy 424.01491 -286.693463) (xy 423.968894 -286.676011)
			(xy 423.926273 -286.651404) (xy 423.888152 -286.620279) (xy 423.855517 -286.583442) (xy 423.829214 -286.541846)
			(xy 423.809923 -286.49657) (xy 423.798146 -286.448786) (xy 423.794186 -286.399732) (xy 423.455338 -286.399732)
			(xy 423.454843 -286.424339) (xy 423.446948 -286.472916) (xy 423.431364 -286.519597) (xy 423.408493 -286.563174)
			(xy 423.378928 -286.602518) (xy 423.343435 -286.63661) (xy 423.302932 -286.664566) (xy 423.25847 -286.685664)
			(xy 423.211199 -286.699356) (xy 423.162344 -286.705288) (xy 423.113169 -286.703307) (xy 423.06495 -286.693463)
			(xy 423.018934 -286.676011) (xy 422.976313 -286.651404) (xy 422.938192 -286.620279) (xy 422.905557 -286.583442)
			(xy 422.879254 -286.541846) (xy 422.859963 -286.49657) (xy 422.848186 -286.448786) (xy 422.844226 -286.399732)
			(xy 422.505124 -286.399732) (xy 422.504629 -286.424339) (xy 422.496734 -286.472916) (xy 422.48115 -286.519597)
			(xy 422.458279 -286.563174) (xy 422.428714 -286.602518) (xy 422.393221 -286.63661) (xy 422.352718 -286.664566)
			(xy 422.308256 -286.685664) (xy 422.260985 -286.699356) (xy 422.21213 -286.705288) (xy 422.162955 -286.703307)
			(xy 422.114736 -286.693463) (xy 422.06872 -286.676011) (xy 422.026099 -286.651404) (xy 421.987978 -286.620279)
			(xy 421.955343 -286.583442) (xy 421.92904 -286.541846) (xy 421.909749 -286.49657) (xy 421.897972 -286.448786)
			(xy 421.894012 -286.399732) (xy 396.990824 -286.399732) (xy 396.990824 -286.473392) (xy 396.990996 -286.479544)
			(xy 396.993954 -286.491489) (xy 396.996666 -286.497014) (xy 397.004794 -286.50819) (xy 397.019526 -286.523684)
			(xy 397.02613 -286.530796) (xy 397.05026 -286.541972) (xy 397.054578 -286.543242) (xy 397.066008 -286.546798)
			(xy 397.070072 -286.547306) (xy 397.096119 -286.551414) (xy 397.146551 -286.56681) (xy 397.193901 -286.590011)
			(xy 397.236971 -286.62043) (xy 397.27467 -286.657296) (xy 397.306043 -286.699675) (xy 397.330296 -286.746495)
			(xy 397.346814 -286.79657) (xy 397.35518 -286.848631) (xy 397.35518 -286.874966) (xy 397.669016 -286.874966)
			(xy 397.672976 -286.825912) (xy 397.684753 -286.778128) (xy 397.704044 -286.732852) (xy 397.730347 -286.691256)
			(xy 397.762982 -286.654419) (xy 397.801103 -286.623294) (xy 397.843724 -286.598687) (xy 397.88974 -286.581235)
			(xy 397.937959 -286.571391) (xy 397.987134 -286.56941) (xy 398.035989 -286.575342) (xy 398.08326 -286.589034)
			(xy 398.127722 -286.610132) (xy 398.168225 -286.638088) (xy 398.203718 -286.67218) (xy 398.233283 -286.711524)
			(xy 398.256154 -286.755101) (xy 398.271738 -286.801782) (xy 398.279633 -286.850359) (xy 398.280128 -286.874966)
			(xy 398.61923 -286.874966) (xy 398.62319 -286.825912) (xy 398.634967 -286.778128) (xy 398.654258 -286.732852)
			(xy 398.680561 -286.691256) (xy 398.713196 -286.654419) (xy 398.751317 -286.623294) (xy 398.793938 -286.598687)
			(xy 398.839954 -286.581235) (xy 398.888173 -286.571391) (xy 398.937348 -286.56941) (xy 398.986203 -286.575342)
			(xy 399.033474 -286.589034) (xy 399.077936 -286.610132) (xy 399.118439 -286.638088) (xy 399.153932 -286.67218)
			(xy 399.183497 -286.711524) (xy 399.206368 -286.755101) (xy 399.221952 -286.801782) (xy 399.229847 -286.850359)
			(xy 399.230342 -286.874966) (xy 399.56919 -286.874966) (xy 399.57315 -286.825912) (xy 399.584927 -286.778128)
			(xy 399.604218 -286.732852) (xy 399.630521 -286.691256) (xy 399.663156 -286.654419) (xy 399.701277 -286.623294)
			(xy 399.743898 -286.598687) (xy 399.789914 -286.581235) (xy 399.838133 -286.571391) (xy 399.887308 -286.56941)
			(xy 399.936163 -286.575342) (xy 399.983434 -286.589034) (xy 400.027896 -286.610132) (xy 400.068399 -286.638088)
			(xy 400.103892 -286.67218) (xy 400.133457 -286.711524) (xy 400.156328 -286.755101) (xy 400.171912 -286.801782)
			(xy 400.179807 -286.850359) (xy 400.180302 -286.874966) (xy 400.51915 -286.874966) (xy 400.52311 -286.825912)
			(xy 400.534887 -286.778128) (xy 400.554178 -286.732852) (xy 400.580481 -286.691256) (xy 400.613116 -286.654419)
			(xy 400.651237 -286.623294) (xy 400.693858 -286.598687) (xy 400.739874 -286.581235) (xy 400.788093 -286.571391)
			(xy 400.837268 -286.56941) (xy 400.886123 -286.575342) (xy 400.933394 -286.589034) (xy 400.977856 -286.610132)
			(xy 401.018359 -286.638088) (xy 401.053852 -286.67218) (xy 401.083417 -286.711524) (xy 401.106288 -286.755101)
			(xy 401.121872 -286.801782) (xy 401.129767 -286.850359) (xy 401.130262 -286.874966) (xy 401.46911 -286.874966)
			(xy 401.47307 -286.825912) (xy 401.484847 -286.778128) (xy 401.504138 -286.732852) (xy 401.530441 -286.691256)
			(xy 401.563076 -286.654419) (xy 401.601197 -286.623294) (xy 401.643818 -286.598687) (xy 401.689834 -286.581235)
			(xy 401.738053 -286.571391) (xy 401.787228 -286.56941) (xy 401.836083 -286.575342) (xy 401.883354 -286.589034)
			(xy 401.927816 -286.610132) (xy 401.968319 -286.638088) (xy 402.003812 -286.67218) (xy 402.033377 -286.711524)
			(xy 402.056248 -286.755101) (xy 402.071832 -286.801782) (xy 402.079727 -286.850359) (xy 402.080222 -286.874966)
			(xy 402.41907 -286.874966) (xy 402.42303 -286.825912) (xy 402.434807 -286.778128) (xy 402.454098 -286.732852)
			(xy 402.480401 -286.691256) (xy 402.513036 -286.654419) (xy 402.551157 -286.623294) (xy 402.593778 -286.598687)
			(xy 402.639794 -286.581235) (xy 402.688013 -286.571391) (xy 402.737188 -286.56941) (xy 402.786043 -286.575342)
			(xy 402.833314 -286.589034) (xy 402.877776 -286.610132) (xy 402.918279 -286.638088) (xy 402.953772 -286.67218)
			(xy 402.983337 -286.711524) (xy 403.006208 -286.755101) (xy 403.021792 -286.801782) (xy 403.029687 -286.850359)
			(xy 403.030182 -286.874966) (xy 403.36903 -286.874966) (xy 403.37299 -286.825912) (xy 403.384767 -286.778128)
			(xy 403.404058 -286.732852) (xy 403.430361 -286.691256) (xy 403.462996 -286.654419) (xy 403.501117 -286.623294)
			(xy 403.543738 -286.598687) (xy 403.589754 -286.581235) (xy 403.637973 -286.571391) (xy 403.687148 -286.56941)
			(xy 403.736003 -286.575342) (xy 403.783274 -286.589034) (xy 403.827736 -286.610132) (xy 403.868239 -286.638088)
			(xy 403.903732 -286.67218) (xy 403.933297 -286.711524) (xy 403.956168 -286.755101) (xy 403.971752 -286.801782)
			(xy 403.979647 -286.850359) (xy 403.980142 -286.874966) (xy 404.31899 -286.874966) (xy 404.32295 -286.825912)
			(xy 404.334727 -286.778128) (xy 404.354018 -286.732852) (xy 404.380321 -286.691256) (xy 404.412956 -286.654419)
			(xy 404.451077 -286.623294) (xy 404.493698 -286.598687) (xy 404.539714 -286.581235) (xy 404.587933 -286.571391)
			(xy 404.637108 -286.56941) (xy 404.685963 -286.575342) (xy 404.733234 -286.589034) (xy 404.777696 -286.610132)
			(xy 404.818199 -286.638088) (xy 404.853692 -286.67218) (xy 404.883257 -286.711524) (xy 404.906128 -286.755101)
			(xy 404.921712 -286.801782) (xy 404.929607 -286.850359) (xy 404.930102 -286.874966) (xy 405.269204 -286.874966)
			(xy 405.273164 -286.825912) (xy 405.284941 -286.778128) (xy 405.304232 -286.732852) (xy 405.330535 -286.691256)
			(xy 405.36317 -286.654419) (xy 405.401291 -286.623294) (xy 405.443912 -286.598687) (xy 405.489928 -286.581235)
			(xy 405.538147 -286.571391) (xy 405.587322 -286.56941) (xy 405.636177 -286.575342) (xy 405.683448 -286.589034)
			(xy 405.72791 -286.610132) (xy 405.768413 -286.638088) (xy 405.803906 -286.67218) (xy 405.833471 -286.711524)
			(xy 405.856342 -286.755101) (xy 405.871926 -286.801782) (xy 405.879821 -286.850359) (xy 405.880316 -286.874966)
			(xy 406.219164 -286.874966) (xy 406.223124 -286.825912) (xy 406.234901 -286.778128) (xy 406.254192 -286.732852)
			(xy 406.280495 -286.691256) (xy 406.31313 -286.654419) (xy 406.351251 -286.623294) (xy 406.393872 -286.598687)
			(xy 406.439888 -286.581235) (xy 406.488107 -286.571391) (xy 406.537282 -286.56941) (xy 406.586137 -286.575342)
			(xy 406.633408 -286.589034) (xy 406.67787 -286.610132) (xy 406.718373 -286.638088) (xy 406.753866 -286.67218)
			(xy 406.783431 -286.711524) (xy 406.806302 -286.755101) (xy 406.821886 -286.801782) (xy 406.829781 -286.850359)
			(xy 406.830276 -286.874966) (xy 408.119084 -286.874966) (xy 408.123044 -286.825912) (xy 408.134821 -286.778128)
			(xy 408.154112 -286.732852) (xy 408.180415 -286.691256) (xy 408.21305 -286.654419) (xy 408.251171 -286.623294)
			(xy 408.293792 -286.598687) (xy 408.339808 -286.581235) (xy 408.388027 -286.571391) (xy 408.437202 -286.56941)
			(xy 408.486057 -286.575342) (xy 408.533328 -286.589034) (xy 408.57779 -286.610132) (xy 408.618293 -286.638088)
			(xy 408.653786 -286.67218) (xy 408.683351 -286.711524) (xy 408.706222 -286.755101) (xy 408.721806 -286.801782)
			(xy 408.729701 -286.850359) (xy 408.730196 -286.874966) (xy 409.069044 -286.874966) (xy 409.073004 -286.825912)
			(xy 409.084781 -286.778128) (xy 409.104072 -286.732852) (xy 409.130375 -286.691256) (xy 409.16301 -286.654419)
			(xy 409.201131 -286.623294) (xy 409.243752 -286.598687) (xy 409.289768 -286.581235) (xy 409.337987 -286.571391)
			(xy 409.387162 -286.56941) (xy 409.436017 -286.575342) (xy 409.483288 -286.589034) (xy 409.52775 -286.610132)
			(xy 409.568253 -286.638088) (xy 409.603746 -286.67218) (xy 409.633311 -286.711524) (xy 409.656182 -286.755101)
			(xy 409.671766 -286.801782) (xy 409.679661 -286.850359) (xy 409.680156 -286.874966) (xy 410.019004 -286.874966)
			(xy 410.022964 -286.825912) (xy 410.034741 -286.778128) (xy 410.054032 -286.732852) (xy 410.080335 -286.691256)
			(xy 410.11297 -286.654419) (xy 410.151091 -286.623294) (xy 410.193712 -286.598687) (xy 410.239728 -286.581235)
			(xy 410.287947 -286.571391) (xy 410.337122 -286.56941) (xy 410.385977 -286.575342) (xy 410.433248 -286.589034)
			(xy 410.47771 -286.610132) (xy 410.518213 -286.638088) (xy 410.553706 -286.67218) (xy 410.583271 -286.711524)
			(xy 410.606142 -286.755101) (xy 410.621726 -286.801782) (xy 410.629621 -286.850359) (xy 410.630116 -286.874966)
			(xy 410.969218 -286.874966) (xy 410.973178 -286.825912) (xy 410.984955 -286.778128) (xy 411.004246 -286.732852)
			(xy 411.030549 -286.691256) (xy 411.063184 -286.654419) (xy 411.101305 -286.623294) (xy 411.143926 -286.598687)
			(xy 411.189942 -286.581235) (xy 411.238161 -286.571391) (xy 411.287336 -286.56941) (xy 411.336191 -286.575342)
			(xy 411.383462 -286.589034) (xy 411.427924 -286.610132) (xy 411.468427 -286.638088) (xy 411.50392 -286.67218)
			(xy 411.533485 -286.711524) (xy 411.556356 -286.755101) (xy 411.57194 -286.801782) (xy 411.579835 -286.850359)
			(xy 411.58033 -286.874966) (xy 411.919178 -286.874966) (xy 411.923138 -286.825912) (xy 411.934915 -286.778128)
			(xy 411.954206 -286.732852) (xy 411.980509 -286.691256) (xy 412.013144 -286.654419) (xy 412.051265 -286.623294)
			(xy 412.093886 -286.598687) (xy 412.139902 -286.581235) (xy 412.188121 -286.571391) (xy 412.237296 -286.56941)
			(xy 412.286151 -286.575342) (xy 412.333422 -286.589034) (xy 412.377884 -286.610132) (xy 412.418387 -286.638088)
			(xy 412.45388 -286.67218) (xy 412.483445 -286.711524) (xy 412.506316 -286.755101) (xy 412.5219 -286.801782)
			(xy 412.529795 -286.850359) (xy 412.53029 -286.874966) (xy 412.869138 -286.874966) (xy 412.873098 -286.825912)
			(xy 412.884875 -286.778128) (xy 412.904166 -286.732852) (xy 412.930469 -286.691256) (xy 412.963104 -286.654419)
			(xy 413.001225 -286.623294) (xy 413.043846 -286.598687) (xy 413.089862 -286.581235) (xy 413.138081 -286.571391)
			(xy 413.187256 -286.56941) (xy 413.236111 -286.575342) (xy 413.283382 -286.589034) (xy 413.327844 -286.610132)
			(xy 413.368347 -286.638088) (xy 413.40384 -286.67218) (xy 413.433405 -286.711524) (xy 413.456276 -286.755101)
			(xy 413.47186 -286.801782) (xy 413.479755 -286.850359) (xy 413.48025 -286.874966) (xy 413.819098 -286.874966)
			(xy 413.823058 -286.825912) (xy 413.834835 -286.778128) (xy 413.854126 -286.732852) (xy 413.880429 -286.691256)
			(xy 413.913064 -286.654419) (xy 413.951185 -286.623294) (xy 413.993806 -286.598687) (xy 414.039822 -286.581235)
			(xy 414.088041 -286.571391) (xy 414.137216 -286.56941) (xy 414.186071 -286.575342) (xy 414.233342 -286.589034)
			(xy 414.277804 -286.610132) (xy 414.318307 -286.638088) (xy 414.3538 -286.67218) (xy 414.383365 -286.711524)
			(xy 414.406236 -286.755101) (xy 414.42182 -286.801782) (xy 414.429715 -286.850359) (xy 414.43021 -286.874966)
			(xy 414.769058 -286.874966) (xy 414.773018 -286.825912) (xy 414.784795 -286.778128) (xy 414.804086 -286.732852)
			(xy 414.830389 -286.691256) (xy 414.863024 -286.654419) (xy 414.901145 -286.623294) (xy 414.943766 -286.598687)
			(xy 414.989782 -286.581235) (xy 415.038001 -286.571391) (xy 415.087176 -286.56941) (xy 415.136031 -286.575342)
			(xy 415.183302 -286.589034) (xy 415.227764 -286.610132) (xy 415.268267 -286.638088) (xy 415.30376 -286.67218)
			(xy 415.333325 -286.711524) (xy 415.356196 -286.755101) (xy 415.37178 -286.801782) (xy 415.379675 -286.850359)
			(xy 415.38017 -286.874966) (xy 415.719018 -286.874966) (xy 415.722978 -286.825912) (xy 415.734755 -286.778128)
			(xy 415.754046 -286.732852) (xy 415.780349 -286.691256) (xy 415.812984 -286.654419) (xy 415.851105 -286.623294)
			(xy 415.893726 -286.598687) (xy 415.939742 -286.581235) (xy 415.987961 -286.571391) (xy 416.037136 -286.56941)
			(xy 416.085991 -286.575342) (xy 416.133262 -286.589034) (xy 416.177724 -286.610132) (xy 416.218227 -286.638088)
			(xy 416.25372 -286.67218) (xy 416.283285 -286.711524) (xy 416.306156 -286.755101) (xy 416.32174 -286.801782)
			(xy 416.329635 -286.850359) (xy 416.33013 -286.874966) (xy 416.668978 -286.874966) (xy 416.672938 -286.825912)
			(xy 416.684715 -286.778128) (xy 416.704006 -286.732852) (xy 416.730309 -286.691256) (xy 416.762944 -286.654419)
			(xy 416.801065 -286.623294) (xy 416.843686 -286.598687) (xy 416.889702 -286.581235) (xy 416.937921 -286.571391)
			(xy 416.987096 -286.56941) (xy 417.035951 -286.575342) (xy 417.083222 -286.589034) (xy 417.127684 -286.610132)
			(xy 417.168187 -286.638088) (xy 417.20368 -286.67218) (xy 417.233245 -286.711524) (xy 417.256116 -286.755101)
			(xy 417.2717 -286.801782) (xy 417.279595 -286.850359) (xy 417.28009 -286.874966) (xy 417.619192 -286.874966)
			(xy 417.623152 -286.825912) (xy 417.634929 -286.778128) (xy 417.65422 -286.732852) (xy 417.680523 -286.691256)
			(xy 417.713158 -286.654419) (xy 417.751279 -286.623294) (xy 417.7939 -286.598687) (xy 417.839916 -286.581235)
			(xy 417.888135 -286.571391) (xy 417.93731 -286.56941) (xy 417.986165 -286.575342) (xy 418.033436 -286.589034)
			(xy 418.077898 -286.610132) (xy 418.118401 -286.638088) (xy 418.153894 -286.67218) (xy 418.183459 -286.711524)
			(xy 418.20633 -286.755101) (xy 418.221914 -286.801782) (xy 418.229809 -286.850359) (xy 418.230304 -286.874966)
			(xy 418.569152 -286.874966) (xy 418.573112 -286.825912) (xy 418.584889 -286.778128) (xy 418.60418 -286.732852)
			(xy 418.630483 -286.691256) (xy 418.663118 -286.654419) (xy 418.701239 -286.623294) (xy 418.74386 -286.598687)
			(xy 418.789876 -286.581235) (xy 418.838095 -286.571391) (xy 418.88727 -286.56941) (xy 418.936125 -286.575342)
			(xy 418.983396 -286.589034) (xy 419.027858 -286.610132) (xy 419.068361 -286.638088) (xy 419.103854 -286.67218)
			(xy 419.133419 -286.711524) (xy 419.15629 -286.755101) (xy 419.171874 -286.801782) (xy 419.179769 -286.850359)
			(xy 419.180264 -286.874966) (xy 419.179769 -286.899573) (xy 419.171874 -286.94815) (xy 419.15629 -286.994831)
			(xy 419.133419 -287.038408) (xy 419.103854 -287.077752) (xy 419.068361 -287.111844) (xy 419.027858 -287.1398)
			(xy 418.983396 -287.160898) (xy 418.936125 -287.17459) (xy 418.88727 -287.180522) (xy 418.838095 -287.178541)
			(xy 418.789876 -287.168697) (xy 418.74386 -287.151245) (xy 418.701239 -287.126638) (xy 418.663118 -287.095513)
			(xy 418.630483 -287.058676) (xy 418.60418 -287.01708) (xy 418.584889 -286.971804) (xy 418.573112 -286.92402)
			(xy 418.569152 -286.874966) (xy 418.230304 -286.874966) (xy 418.229809 -286.899573) (xy 418.221914 -286.94815)
			(xy 418.20633 -286.994831) (xy 418.183459 -287.038408) (xy 418.153894 -287.077752) (xy 418.118401 -287.111844)
			(xy 418.077898 -287.1398) (xy 418.033436 -287.160898) (xy 417.986165 -287.17459) (xy 417.93731 -287.180522)
			(xy 417.888135 -287.178541) (xy 417.839916 -287.168697) (xy 417.7939 -287.151245) (xy 417.751279 -287.126638)
			(xy 417.713158 -287.095513) (xy 417.680523 -287.058676) (xy 417.65422 -287.01708) (xy 417.634929 -286.971804)
			(xy 417.623152 -286.92402) (xy 417.619192 -286.874966) (xy 417.28009 -286.874966) (xy 417.279595 -286.899573)
			(xy 417.2717 -286.94815) (xy 417.256116 -286.994831) (xy 417.233245 -287.038408) (xy 417.20368 -287.077752)
			(xy 417.168187 -287.111844) (xy 417.127684 -287.1398) (xy 417.083222 -287.160898) (xy 417.035951 -287.17459)
			(xy 416.987096 -287.180522) (xy 416.937921 -287.178541) (xy 416.889702 -287.168697) (xy 416.843686 -287.151245)
			(xy 416.801065 -287.126638) (xy 416.762944 -287.095513) (xy 416.730309 -287.058676) (xy 416.704006 -287.01708)
			(xy 416.684715 -286.971804) (xy 416.672938 -286.92402) (xy 416.668978 -286.874966) (xy 416.33013 -286.874966)
			(xy 416.329635 -286.899573) (xy 416.32174 -286.94815) (xy 416.306156 -286.994831) (xy 416.283285 -287.038408)
			(xy 416.25372 -287.077752) (xy 416.218227 -287.111844) (xy 416.177724 -287.1398) (xy 416.133262 -287.160898)
			(xy 416.085991 -287.17459) (xy 416.037136 -287.180522) (xy 415.987961 -287.178541) (xy 415.939742 -287.168697)
			(xy 415.893726 -287.151245) (xy 415.851105 -287.126638) (xy 415.812984 -287.095513) (xy 415.780349 -287.058676)
			(xy 415.754046 -287.01708) (xy 415.734755 -286.971804) (xy 415.722978 -286.92402) (xy 415.719018 -286.874966)
			(xy 415.38017 -286.874966) (xy 415.379675 -286.899573) (xy 415.37178 -286.94815) (xy 415.356196 -286.994831)
			(xy 415.333325 -287.038408) (xy 415.30376 -287.077752) (xy 415.268267 -287.111844) (xy 415.227764 -287.1398)
			(xy 415.183302 -287.160898) (xy 415.136031 -287.17459) (xy 415.087176 -287.180522) (xy 415.038001 -287.178541)
			(xy 414.989782 -287.168697) (xy 414.943766 -287.151245) (xy 414.901145 -287.126638) (xy 414.863024 -287.095513)
			(xy 414.830389 -287.058676) (xy 414.804086 -287.01708) (xy 414.784795 -286.971804) (xy 414.773018 -286.92402)
			(xy 414.769058 -286.874966) (xy 414.43021 -286.874966) (xy 414.429715 -286.899573) (xy 414.42182 -286.94815)
			(xy 414.406236 -286.994831) (xy 414.383365 -287.038408) (xy 414.3538 -287.077752) (xy 414.318307 -287.111844)
			(xy 414.277804 -287.1398) (xy 414.233342 -287.160898) (xy 414.186071 -287.17459) (xy 414.137216 -287.180522)
			(xy 414.088041 -287.178541) (xy 414.039822 -287.168697) (xy 413.993806 -287.151245) (xy 413.951185 -287.126638)
			(xy 413.913064 -287.095513) (xy 413.880429 -287.058676) (xy 413.854126 -287.01708) (xy 413.834835 -286.971804)
			(xy 413.823058 -286.92402) (xy 413.819098 -286.874966) (xy 413.48025 -286.874966) (xy 413.479755 -286.899573)
			(xy 413.47186 -286.94815) (xy 413.456276 -286.994831) (xy 413.433405 -287.038408) (xy 413.40384 -287.077752)
			(xy 413.368347 -287.111844) (xy 413.327844 -287.1398) (xy 413.283382 -287.160898) (xy 413.236111 -287.17459)
			(xy 413.187256 -287.180522) (xy 413.138081 -287.178541) (xy 413.089862 -287.168697) (xy 413.043846 -287.151245)
			(xy 413.001225 -287.126638) (xy 412.963104 -287.095513) (xy 412.930469 -287.058676) (xy 412.904166 -287.01708)
			(xy 412.884875 -286.971804) (xy 412.873098 -286.92402) (xy 412.869138 -286.874966) (xy 412.53029 -286.874966)
			(xy 412.529795 -286.899573) (xy 412.5219 -286.94815) (xy 412.506316 -286.994831) (xy 412.483445 -287.038408)
			(xy 412.45388 -287.077752) (xy 412.418387 -287.111844) (xy 412.377884 -287.1398) (xy 412.333422 -287.160898)
			(xy 412.286151 -287.17459) (xy 412.237296 -287.180522) (xy 412.188121 -287.178541) (xy 412.139902 -287.168697)
			(xy 412.093886 -287.151245) (xy 412.051265 -287.126638) (xy 412.013144 -287.095513) (xy 411.980509 -287.058676)
			(xy 411.954206 -287.01708) (xy 411.934915 -286.971804) (xy 411.923138 -286.92402) (xy 411.919178 -286.874966)
			(xy 411.58033 -286.874966) (xy 411.579835 -286.899573) (xy 411.57194 -286.94815) (xy 411.556356 -286.994831)
			(xy 411.533485 -287.038408) (xy 411.50392 -287.077752) (xy 411.468427 -287.111844) (xy 411.427924 -287.1398)
			(xy 411.383462 -287.160898) (xy 411.336191 -287.17459) (xy 411.287336 -287.180522) (xy 411.238161 -287.178541)
			(xy 411.189942 -287.168697) (xy 411.143926 -287.151245) (xy 411.101305 -287.126638) (xy 411.063184 -287.095513)
			(xy 411.030549 -287.058676) (xy 411.004246 -287.01708) (xy 410.984955 -286.971804) (xy 410.973178 -286.92402)
			(xy 410.969218 -286.874966) (xy 410.630116 -286.874966) (xy 410.629621 -286.899573) (xy 410.621726 -286.94815)
			(xy 410.606142 -286.994831) (xy 410.583271 -287.038408) (xy 410.553706 -287.077752) (xy 410.518213 -287.111844)
			(xy 410.47771 -287.1398) (xy 410.433248 -287.160898) (xy 410.385977 -287.17459) (xy 410.337122 -287.180522)
			(xy 410.287947 -287.178541) (xy 410.239728 -287.168697) (xy 410.193712 -287.151245) (xy 410.151091 -287.126638)
			(xy 410.11297 -287.095513) (xy 410.080335 -287.058676) (xy 410.054032 -287.01708) (xy 410.034741 -286.971804)
			(xy 410.022964 -286.92402) (xy 410.019004 -286.874966) (xy 409.680156 -286.874966) (xy 409.679661 -286.899573)
			(xy 409.671766 -286.94815) (xy 409.656182 -286.994831) (xy 409.633311 -287.038408) (xy 409.603746 -287.077752)
			(xy 409.568253 -287.111844) (xy 409.52775 -287.1398) (xy 409.483288 -287.160898) (xy 409.436017 -287.17459)
			(xy 409.387162 -287.180522) (xy 409.337987 -287.178541) (xy 409.289768 -287.168697) (xy 409.243752 -287.151245)
			(xy 409.201131 -287.126638) (xy 409.16301 -287.095513) (xy 409.130375 -287.058676) (xy 409.104072 -287.01708)
			(xy 409.084781 -286.971804) (xy 409.073004 -286.92402) (xy 409.069044 -286.874966) (xy 408.730196 -286.874966)
			(xy 408.729701 -286.899573) (xy 408.721806 -286.94815) (xy 408.706222 -286.994831) (xy 408.683351 -287.038408)
			(xy 408.653786 -287.077752) (xy 408.618293 -287.111844) (xy 408.57779 -287.1398) (xy 408.533328 -287.160898)
			(xy 408.486057 -287.17459) (xy 408.437202 -287.180522) (xy 408.388027 -287.178541) (xy 408.339808 -287.168697)
			(xy 408.293792 -287.151245) (xy 408.251171 -287.126638) (xy 408.21305 -287.095513) (xy 408.180415 -287.058676)
			(xy 408.154112 -287.01708) (xy 408.134821 -286.971804) (xy 408.123044 -286.92402) (xy 408.119084 -286.874966)
			(xy 406.830276 -286.874966) (xy 406.829781 -286.899573) (xy 406.821886 -286.94815) (xy 406.806302 -286.994831)
			(xy 406.783431 -287.038408) (xy 406.753866 -287.077752) (xy 406.718373 -287.111844) (xy 406.67787 -287.1398)
			(xy 406.633408 -287.160898) (xy 406.586137 -287.17459) (xy 406.537282 -287.180522) (xy 406.488107 -287.178541)
			(xy 406.439888 -287.168697) (xy 406.393872 -287.151245) (xy 406.351251 -287.126638) (xy 406.31313 -287.095513)
			(xy 406.280495 -287.058676) (xy 406.254192 -287.01708) (xy 406.234901 -286.971804) (xy 406.223124 -286.92402)
			(xy 406.219164 -286.874966) (xy 405.880316 -286.874966) (xy 405.879821 -286.899573) (xy 405.871926 -286.94815)
			(xy 405.856342 -286.994831) (xy 405.833471 -287.038408) (xy 405.803906 -287.077752) (xy 405.768413 -287.111844)
			(xy 405.72791 -287.1398) (xy 405.683448 -287.160898) (xy 405.636177 -287.17459) (xy 405.587322 -287.180522)
			(xy 405.538147 -287.178541) (xy 405.489928 -287.168697) (xy 405.443912 -287.151245) (xy 405.401291 -287.126638)
			(xy 405.36317 -287.095513) (xy 405.330535 -287.058676) (xy 405.304232 -287.01708) (xy 405.284941 -286.971804)
			(xy 405.273164 -286.92402) (xy 405.269204 -286.874966) (xy 404.930102 -286.874966) (xy 404.929607 -286.899573)
			(xy 404.921712 -286.94815) (xy 404.906128 -286.994831) (xy 404.883257 -287.038408) (xy 404.853692 -287.077752)
			(xy 404.818199 -287.111844) (xy 404.777696 -287.1398) (xy 404.733234 -287.160898) (xy 404.685963 -287.17459)
			(xy 404.637108 -287.180522) (xy 404.587933 -287.178541) (xy 404.539714 -287.168697) (xy 404.493698 -287.151245)
			(xy 404.451077 -287.126638) (xy 404.412956 -287.095513) (xy 404.380321 -287.058676) (xy 404.354018 -287.01708)
			(xy 404.334727 -286.971804) (xy 404.32295 -286.92402) (xy 404.31899 -286.874966) (xy 403.980142 -286.874966)
			(xy 403.979647 -286.899573) (xy 403.971752 -286.94815) (xy 403.956168 -286.994831) (xy 403.933297 -287.038408)
			(xy 403.903732 -287.077752) (xy 403.868239 -287.111844) (xy 403.827736 -287.1398) (xy 403.783274 -287.160898)
			(xy 403.736003 -287.17459) (xy 403.687148 -287.180522) (xy 403.637973 -287.178541) (xy 403.589754 -287.168697)
			(xy 403.543738 -287.151245) (xy 403.501117 -287.126638) (xy 403.462996 -287.095513) (xy 403.430361 -287.058676)
			(xy 403.404058 -287.01708) (xy 403.384767 -286.971804) (xy 403.37299 -286.92402) (xy 403.36903 -286.874966)
			(xy 403.030182 -286.874966) (xy 403.029687 -286.899573) (xy 403.021792 -286.94815) (xy 403.006208 -286.994831)
			(xy 402.983337 -287.038408) (xy 402.953772 -287.077752) (xy 402.918279 -287.111844) (xy 402.877776 -287.1398)
			(xy 402.833314 -287.160898) (xy 402.786043 -287.17459) (xy 402.737188 -287.180522) (xy 402.688013 -287.178541)
			(xy 402.639794 -287.168697) (xy 402.593778 -287.151245) (xy 402.551157 -287.126638) (xy 402.513036 -287.095513)
			(xy 402.480401 -287.058676) (xy 402.454098 -287.01708) (xy 402.434807 -286.971804) (xy 402.42303 -286.92402)
			(xy 402.41907 -286.874966) (xy 402.080222 -286.874966) (xy 402.079727 -286.899573) (xy 402.071832 -286.94815)
			(xy 402.056248 -286.994831) (xy 402.033377 -287.038408) (xy 402.003812 -287.077752) (xy 401.968319 -287.111844)
			(xy 401.927816 -287.1398) (xy 401.883354 -287.160898) (xy 401.836083 -287.17459) (xy 401.787228 -287.180522)
			(xy 401.738053 -287.178541) (xy 401.689834 -287.168697) (xy 401.643818 -287.151245) (xy 401.601197 -287.126638)
			(xy 401.563076 -287.095513) (xy 401.530441 -287.058676) (xy 401.504138 -287.01708) (xy 401.484847 -286.971804)
			(xy 401.47307 -286.92402) (xy 401.46911 -286.874966) (xy 401.130262 -286.874966) (xy 401.129767 -286.899573)
			(xy 401.121872 -286.94815) (xy 401.106288 -286.994831) (xy 401.083417 -287.038408) (xy 401.053852 -287.077752)
			(xy 401.018359 -287.111844) (xy 400.977856 -287.1398) (xy 400.933394 -287.160898) (xy 400.886123 -287.17459)
			(xy 400.837268 -287.180522) (xy 400.788093 -287.178541) (xy 400.739874 -287.168697) (xy 400.693858 -287.151245)
			(xy 400.651237 -287.126638) (xy 400.613116 -287.095513) (xy 400.580481 -287.058676) (xy 400.554178 -287.01708)
			(xy 400.534887 -286.971804) (xy 400.52311 -286.92402) (xy 400.51915 -286.874966) (xy 400.180302 -286.874966)
			(xy 400.179807 -286.899573) (xy 400.171912 -286.94815) (xy 400.156328 -286.994831) (xy 400.133457 -287.038408)
			(xy 400.103892 -287.077752) (xy 400.068399 -287.111844) (xy 400.027896 -287.1398) (xy 399.983434 -287.160898)
			(xy 399.936163 -287.17459) (xy 399.887308 -287.180522) (xy 399.838133 -287.178541) (xy 399.789914 -287.168697)
			(xy 399.743898 -287.151245) (xy 399.701277 -287.126638) (xy 399.663156 -287.095513) (xy 399.630521 -287.058676)
			(xy 399.604218 -287.01708) (xy 399.584927 -286.971804) (xy 399.57315 -286.92402) (xy 399.56919 -286.874966)
			(xy 399.230342 -286.874966) (xy 399.229847 -286.899573) (xy 399.221952 -286.94815) (xy 399.206368 -286.994831)
			(xy 399.183497 -287.038408) (xy 399.153932 -287.077752) (xy 399.118439 -287.111844) (xy 399.077936 -287.1398)
			(xy 399.033474 -287.160898) (xy 398.986203 -287.17459) (xy 398.937348 -287.180522) (xy 398.888173 -287.178541)
			(xy 398.839954 -287.168697) (xy 398.793938 -287.151245) (xy 398.751317 -287.126638) (xy 398.713196 -287.095513)
			(xy 398.680561 -287.058676) (xy 398.654258 -287.01708) (xy 398.634967 -286.971804) (xy 398.62319 -286.92402)
			(xy 398.61923 -286.874966) (xy 398.280128 -286.874966) (xy 398.279633 -286.899573) (xy 398.271738 -286.94815)
			(xy 398.256154 -286.994831) (xy 398.233283 -287.038408) (xy 398.203718 -287.077752) (xy 398.168225 -287.111844)
			(xy 398.127722 -287.1398) (xy 398.08326 -287.160898) (xy 398.035989 -287.17459) (xy 397.987134 -287.180522)
			(xy 397.937959 -287.178541) (xy 397.88974 -287.168697) (xy 397.843724 -287.151245) (xy 397.801103 -287.126638)
			(xy 397.762982 -287.095513) (xy 397.730347 -287.058676) (xy 397.704044 -287.01708) (xy 397.684753 -286.971804)
			(xy 397.672976 -286.92402) (xy 397.669016 -286.874966) (xy 397.35518 -286.874966) (xy 397.355181 -286.90136)
			(xy 397.346817 -286.953421) (xy 397.3303 -287.003496) (xy 397.306048 -287.050317) (xy 397.274676 -287.092697)
			(xy 397.236978 -287.129565) (xy 397.193909 -287.159984) (xy 397.146559 -287.183187) (xy 397.096129 -287.198584)
			(xy 397.070072 -287.202626) (xy 397.066008 -287.203134) (xy 397.054578 -287.20669) (xy 397.05026 -287.20796)
			(xy 397.02613 -287.219136) (xy 397.019526 -287.226248) (xy 397.004794 -287.241742) (xy 396.996666 -287.252918)
			(xy 396.993976 -287.25845) (xy 396.991032 -287.270391) (xy 396.990824 -287.27654) (xy 396.990824 -287.349946)
			(xy 421.894012 -287.349946) (xy 421.897972 -287.300892) (xy 421.909749 -287.253108) (xy 421.92904 -287.207832)
			(xy 421.955343 -287.166236) (xy 421.987978 -287.129399) (xy 422.026099 -287.098274) (xy 422.06872 -287.073667)
			(xy 422.114736 -287.056215) (xy 422.162955 -287.046371) (xy 422.21213 -287.04439) (xy 422.260985 -287.050322)
			(xy 422.308256 -287.064014) (xy 422.352718 -287.085112) (xy 422.393221 -287.113068) (xy 422.428714 -287.14716)
			(xy 422.458279 -287.186504) (xy 422.48115 -287.230081) (xy 422.496734 -287.276762) (xy 422.504629 -287.325339)
			(xy 422.505124 -287.349946) (xy 422.504629 -287.374553) (xy 422.50445 -287.375654) (xy 422.823128 -287.375654)
			(xy 422.823128 -287.324238) (xy 422.831171 -287.273456) (xy 422.847059 -287.224557) (xy 422.870402 -287.178745)
			(xy 422.900623 -287.137149) (xy 422.936979 -287.100793) (xy 422.978575 -287.070572) (xy 423.024387 -287.047229)
			(xy 423.073286 -287.031341) (xy 423.124068 -287.023298) (xy 423.175484 -287.023298) (xy 423.226266 -287.031341)
			(xy 423.275165 -287.047229) (xy 423.320977 -287.070572) (xy 423.362573 -287.100793) (xy 423.398929 -287.137149)
			(xy 423.42915 -287.178745) (xy 423.452493 -287.224557) (xy 423.468381 -287.273456) (xy 423.476424 -287.324238)
			(xy 423.476928 -287.349946) (xy 423.476424 -287.375654) (xy 423.773342 -287.375654) (xy 423.773342 -287.324238)
			(xy 423.781385 -287.273456) (xy 423.797273 -287.224557) (xy 423.820616 -287.178745) (xy 423.850837 -287.137149)
			(xy 423.887193 -287.100793) (xy 423.928789 -287.070572) (xy 423.974601 -287.047229) (xy 424.0235 -287.031341)
			(xy 424.074282 -287.023298) (xy 424.125698 -287.023298) (xy 424.17648 -287.031341) (xy 424.225379 -287.047229)
			(xy 424.271191 -287.070572) (xy 424.312787 -287.100793) (xy 424.349143 -287.137149) (xy 424.379364 -287.178745)
			(xy 424.402707 -287.224557) (xy 424.418595 -287.273456) (xy 424.426638 -287.324238) (xy 424.427142 -287.349946)
			(xy 424.744146 -287.349946) (xy 424.748106 -287.300892) (xy 424.759883 -287.253108) (xy 424.779174 -287.207832)
			(xy 424.805477 -287.166236) (xy 424.838112 -287.129399) (xy 424.876233 -287.098274) (xy 424.918854 -287.073667)
			(xy 424.96487 -287.056215) (xy 425.013089 -287.046371) (xy 425.062264 -287.04439) (xy 425.111119 -287.050322)
			(xy 425.15839 -287.064014) (xy 425.202852 -287.085112) (xy 425.243355 -287.113068) (xy 425.278848 -287.14716)
			(xy 425.308413 -287.186504) (xy 425.331284 -287.230081) (xy 425.346868 -287.276762) (xy 425.354763 -287.325339)
			(xy 425.355258 -287.349946) (xy 425.694106 -287.349946) (xy 425.698066 -287.300892) (xy 425.709843 -287.253108)
			(xy 425.729134 -287.207832) (xy 425.755437 -287.166236) (xy 425.788072 -287.129399) (xy 425.826193 -287.098274)
			(xy 425.868814 -287.073667) (xy 425.91483 -287.056215) (xy 425.963049 -287.046371) (xy 426.012224 -287.04439)
			(xy 426.061079 -287.050322) (xy 426.10835 -287.064014) (xy 426.152812 -287.085112) (xy 426.193315 -287.113068)
			(xy 426.228808 -287.14716) (xy 426.258373 -287.186504) (xy 426.281244 -287.230081) (xy 426.296828 -287.276762)
			(xy 426.304723 -287.325339) (xy 426.305218 -287.349946) (xy 426.644066 -287.349946) (xy 426.648026 -287.300892)
			(xy 426.659803 -287.253108) (xy 426.679094 -287.207832) (xy 426.705397 -287.166236) (xy 426.738032 -287.129399)
			(xy 426.776153 -287.098274) (xy 426.818774 -287.073667) (xy 426.86479 -287.056215) (xy 426.913009 -287.046371)
			(xy 426.962184 -287.04439) (xy 427.011039 -287.050322) (xy 427.05831 -287.064014) (xy 427.102772 -287.085112)
			(xy 427.143275 -287.113068) (xy 427.178768 -287.14716) (xy 427.208333 -287.186504) (xy 427.231204 -287.230081)
			(xy 427.246788 -287.276762) (xy 427.254683 -287.325339) (xy 427.255178 -287.349946) (xy 427.593772 -287.349946)
			(xy 427.597732 -287.300892) (xy 427.609509 -287.253108) (xy 427.6288 -287.207832) (xy 427.655103 -287.166236)
			(xy 427.687738 -287.129399) (xy 427.725859 -287.098274) (xy 427.76848 -287.073667) (xy 427.814496 -287.056215)
			(xy 427.862715 -287.046371) (xy 427.91189 -287.04439) (xy 427.960745 -287.050322) (xy 428.008016 -287.064014)
			(xy 428.052478 -287.085112) (xy 428.092981 -287.113068) (xy 428.128474 -287.14716) (xy 428.158039 -287.186504)
			(xy 428.18091 -287.230081) (xy 428.196494 -287.276762) (xy 428.204389 -287.325339) (xy 428.204884 -287.349946)
			(xy 428.543986 -287.349946) (xy 428.547946 -287.300892) (xy 428.559723 -287.253108) (xy 428.579014 -287.207832)
			(xy 428.605317 -287.166236) (xy 428.637952 -287.129399) (xy 428.676073 -287.098274) (xy 428.718694 -287.073667)
			(xy 428.76471 -287.056215) (xy 428.812929 -287.046371) (xy 428.862104 -287.04439) (xy 428.910959 -287.050322)
			(xy 428.95823 -287.064014) (xy 429.002692 -287.085112) (xy 429.043195 -287.113068) (xy 429.078688 -287.14716)
			(xy 429.108253 -287.186504) (xy 429.131124 -287.230081) (xy 429.146708 -287.276762) (xy 429.154603 -287.325339)
			(xy 429.155098 -287.349946) (xy 429.154603 -287.374553) (xy 429.154424 -287.375654) (xy 429.473356 -287.375654)
			(xy 429.473356 -287.324238) (xy 429.481399 -287.273456) (xy 429.497287 -287.224557) (xy 429.52063 -287.178745)
			(xy 429.550851 -287.137149) (xy 429.587207 -287.100793) (xy 429.628803 -287.070572) (xy 429.674615 -287.047229)
			(xy 429.723514 -287.031341) (xy 429.774296 -287.023298) (xy 429.825712 -287.023298) (xy 429.876494 -287.031341)
			(xy 429.925393 -287.047229) (xy 429.971205 -287.070572) (xy 430.012801 -287.100793) (xy 430.049157 -287.137149)
			(xy 430.079378 -287.178745) (xy 430.102721 -287.224557) (xy 430.118609 -287.273456) (xy 430.126652 -287.324238)
			(xy 430.127156 -287.349946) (xy 430.126652 -287.375654) (xy 430.423316 -287.375654) (xy 430.423316 -287.324238)
			(xy 430.431359 -287.273456) (xy 430.447247 -287.224557) (xy 430.47059 -287.178745) (xy 430.500811 -287.137149)
			(xy 430.537167 -287.100793) (xy 430.578763 -287.070572) (xy 430.624575 -287.047229) (xy 430.673474 -287.031341)
			(xy 430.724256 -287.023298) (xy 430.775672 -287.023298) (xy 430.826454 -287.031341) (xy 430.875353 -287.047229)
			(xy 430.921165 -287.070572) (xy 430.962761 -287.100793) (xy 430.999117 -287.137149) (xy 431.029338 -287.178745)
			(xy 431.052681 -287.224557) (xy 431.068569 -287.273456) (xy 431.076612 -287.324238) (xy 431.077116 -287.349946)
			(xy 431.077111 -287.3502) (xy 431.394374 -287.3502) (xy 431.398334 -287.301146) (xy 431.410111 -287.253362)
			(xy 431.429402 -287.208086) (xy 431.455705 -287.16649) (xy 431.48834 -287.129653) (xy 431.526461 -287.098528)
			(xy 431.569082 -287.073921) (xy 431.615098 -287.056469) (xy 431.663317 -287.046625) (xy 431.712492 -287.044644)
			(xy 431.761347 -287.050576) (xy 431.808618 -287.064268) (xy 431.85308 -287.085366) (xy 431.893583 -287.113322)
			(xy 431.929076 -287.147414) (xy 431.958641 -287.186758) (xy 431.981512 -287.230335) (xy 431.997096 -287.277016)
			(xy 432.004991 -287.325593) (xy 432.005486 -287.3502) (xy 432.004991 -287.374807) (xy 431.997096 -287.423384)
			(xy 431.981512 -287.470065) (xy 431.958641 -287.513642) (xy 431.929076 -287.552986) (xy 431.893583 -287.587078)
			(xy 431.85308 -287.615034) (xy 431.808618 -287.636132) (xy 431.761347 -287.649824) (xy 431.712492 -287.655756)
			(xy 431.663317 -287.653775) (xy 431.615098 -287.643931) (xy 431.569082 -287.626479) (xy 431.526461 -287.601872)
			(xy 431.48834 -287.570747) (xy 431.455705 -287.53391) (xy 431.429402 -287.492314) (xy 431.410111 -287.447038)
			(xy 431.398334 -287.399254) (xy 431.394374 -287.3502) (xy 431.077111 -287.3502) (xy 431.076612 -287.375654)
			(xy 431.068569 -287.426436) (xy 431.052681 -287.475335) (xy 431.029338 -287.521147) (xy 430.999117 -287.562743)
			(xy 430.962761 -287.599099) (xy 430.921165 -287.62932) (xy 430.875353 -287.652663) (xy 430.826454 -287.668551)
			(xy 430.775672 -287.676594) (xy 430.724256 -287.676594) (xy 430.673474 -287.668551) (xy 430.624575 -287.652663)
			(xy 430.578763 -287.62932) (xy 430.537167 -287.599099) (xy 430.500811 -287.562743) (xy 430.47059 -287.521147)
			(xy 430.447247 -287.475335) (xy 430.431359 -287.426436) (xy 430.423316 -287.375654) (xy 430.126652 -287.375654)
			(xy 430.118609 -287.426436) (xy 430.102721 -287.475335) (xy 430.079378 -287.521147) (xy 430.049157 -287.562743)
			(xy 430.012801 -287.599099) (xy 429.971205 -287.62932) (xy 429.925393 -287.652663) (xy 429.876494 -287.668551)
			(xy 429.825712 -287.676594) (xy 429.774296 -287.676594) (xy 429.723514 -287.668551) (xy 429.674615 -287.652663)
			(xy 429.628803 -287.62932) (xy 429.587207 -287.599099) (xy 429.550851 -287.562743) (xy 429.52063 -287.521147)
			(xy 429.497287 -287.475335) (xy 429.481399 -287.426436) (xy 429.473356 -287.375654) (xy 429.154424 -287.375654)
			(xy 429.146708 -287.42313) (xy 429.131124 -287.469811) (xy 429.108253 -287.513388) (xy 429.078688 -287.552732)
			(xy 429.043195 -287.586824) (xy 429.002692 -287.61478) (xy 428.95823 -287.635878) (xy 428.910959 -287.64957)
			(xy 428.862104 -287.655502) (xy 428.812929 -287.653521) (xy 428.76471 -287.643677) (xy 428.718694 -287.626225)
			(xy 428.676073 -287.601618) (xy 428.637952 -287.570493) (xy 428.605317 -287.533656) (xy 428.579014 -287.49206)
			(xy 428.559723 -287.446784) (xy 428.547946 -287.399) (xy 428.543986 -287.349946) (xy 428.204884 -287.349946)
			(xy 428.204389 -287.374553) (xy 428.196494 -287.42313) (xy 428.18091 -287.469811) (xy 428.158039 -287.513388)
			(xy 428.128474 -287.552732) (xy 428.092981 -287.586824) (xy 428.052478 -287.61478) (xy 428.008016 -287.635878)
			(xy 427.960745 -287.64957) (xy 427.91189 -287.655502) (xy 427.862715 -287.653521) (xy 427.814496 -287.643677)
			(xy 427.76848 -287.626225) (xy 427.725859 -287.601618) (xy 427.687738 -287.570493) (xy 427.655103 -287.533656)
			(xy 427.6288 -287.49206) (xy 427.609509 -287.446784) (xy 427.597732 -287.399) (xy 427.593772 -287.349946)
			(xy 427.255178 -287.349946) (xy 427.254683 -287.374553) (xy 427.246788 -287.42313) (xy 427.231204 -287.469811)
			(xy 427.208333 -287.513388) (xy 427.178768 -287.552732) (xy 427.143275 -287.586824) (xy 427.102772 -287.61478)
			(xy 427.05831 -287.635878) (xy 427.011039 -287.64957) (xy 426.962184 -287.655502) (xy 426.913009 -287.653521)
			(xy 426.86479 -287.643677) (xy 426.818774 -287.626225) (xy 426.776153 -287.601618) (xy 426.738032 -287.570493)
			(xy 426.705397 -287.533656) (xy 426.679094 -287.49206) (xy 426.659803 -287.446784) (xy 426.648026 -287.399)
			(xy 426.644066 -287.349946) (xy 426.305218 -287.349946) (xy 426.304723 -287.374553) (xy 426.296828 -287.42313)
			(xy 426.281244 -287.469811) (xy 426.258373 -287.513388) (xy 426.228808 -287.552732) (xy 426.193315 -287.586824)
			(xy 426.152812 -287.61478) (xy 426.10835 -287.635878) (xy 426.061079 -287.64957) (xy 426.012224 -287.655502)
			(xy 425.963049 -287.653521) (xy 425.91483 -287.643677) (xy 425.868814 -287.626225) (xy 425.826193 -287.601618)
			(xy 425.788072 -287.570493) (xy 425.755437 -287.533656) (xy 425.729134 -287.49206) (xy 425.709843 -287.446784)
			(xy 425.698066 -287.399) (xy 425.694106 -287.349946) (xy 425.355258 -287.349946) (xy 425.354763 -287.374553)
			(xy 425.346868 -287.42313) (xy 425.331284 -287.469811) (xy 425.308413 -287.513388) (xy 425.278848 -287.552732)
			(xy 425.243355 -287.586824) (xy 425.202852 -287.61478) (xy 425.15839 -287.635878) (xy 425.111119 -287.64957)
			(xy 425.062264 -287.655502) (xy 425.013089 -287.653521) (xy 424.96487 -287.643677) (xy 424.918854 -287.626225)
			(xy 424.876233 -287.601618) (xy 424.838112 -287.570493) (xy 424.805477 -287.533656) (xy 424.779174 -287.49206)
			(xy 424.759883 -287.446784) (xy 424.748106 -287.399) (xy 424.744146 -287.349946) (xy 424.427142 -287.349946)
			(xy 424.426638 -287.375654) (xy 424.418595 -287.426436) (xy 424.402707 -287.475335) (xy 424.379364 -287.521147)
			(xy 424.349143 -287.562743) (xy 424.312787 -287.599099) (xy 424.271191 -287.62932) (xy 424.225379 -287.652663)
			(xy 424.17648 -287.668551) (xy 424.125698 -287.676594) (xy 424.074282 -287.676594) (xy 424.0235 -287.668551)
			(xy 423.974601 -287.652663) (xy 423.928789 -287.62932) (xy 423.887193 -287.599099) (xy 423.850837 -287.562743)
			(xy 423.820616 -287.521147) (xy 423.797273 -287.475335) (xy 423.781385 -287.426436) (xy 423.773342 -287.375654)
			(xy 423.476424 -287.375654) (xy 423.468381 -287.426436) (xy 423.452493 -287.475335) (xy 423.42915 -287.521147)
			(xy 423.398929 -287.562743) (xy 423.362573 -287.599099) (xy 423.320977 -287.62932) (xy 423.275165 -287.652663)
			(xy 423.226266 -287.668551) (xy 423.175484 -287.676594) (xy 423.124068 -287.676594) (xy 423.073286 -287.668551)
			(xy 423.024387 -287.652663) (xy 422.978575 -287.62932) (xy 422.936979 -287.599099) (xy 422.900623 -287.562743)
			(xy 422.870402 -287.521147) (xy 422.847059 -287.475335) (xy 422.831171 -287.426436) (xy 422.823128 -287.375654)
			(xy 422.50445 -287.375654) (xy 422.496734 -287.42313) (xy 422.48115 -287.469811) (xy 422.458279 -287.513388)
			(xy 422.428714 -287.552732) (xy 422.393221 -287.586824) (xy 422.352718 -287.61478) (xy 422.308256 -287.635878)
			(xy 422.260985 -287.64957) (xy 422.21213 -287.655502) (xy 422.162955 -287.653521) (xy 422.114736 -287.643677)
			(xy 422.06872 -287.626225) (xy 422.026099 -287.601618) (xy 421.987978 -287.570493) (xy 421.955343 -287.533656)
			(xy 421.92904 -287.49206) (xy 421.909749 -287.446784) (xy 421.897972 -287.399) (xy 421.894012 -287.349946)
			(xy 396.990824 -287.349946) (xy 396.990824 -287.423352) (xy 396.990991 -287.429506) (xy 396.993941 -287.441454)
			(xy 396.996666 -287.446974) (xy 397.004794 -287.45815) (xy 397.019526 -287.473644) (xy 397.02613 -287.480756)
			(xy 397.05026 -287.491932) (xy 397.054578 -287.493202) (xy 397.066008 -287.496758) (xy 397.070072 -287.497266)
			(xy 397.096115 -287.501374) (xy 397.146536 -287.516768) (xy 397.193877 -287.539966) (xy 397.236939 -287.57038)
			(xy 397.27463 -287.607241) (xy 397.305997 -287.649614) (xy 397.330244 -287.696426) (xy 397.346759 -287.746492)
			(xy 397.355121 -287.798544) (xy 397.355121 -287.824926) (xy 397.669016 -287.824926) (xy 397.672976 -287.775872)
			(xy 397.684753 -287.728088) (xy 397.704044 -287.682812) (xy 397.730347 -287.641216) (xy 397.762982 -287.604379)
			(xy 397.801103 -287.573254) (xy 397.843724 -287.548647) (xy 397.88974 -287.531195) (xy 397.937959 -287.521351)
			(xy 397.987134 -287.51937) (xy 398.035989 -287.525302) (xy 398.08326 -287.538994) (xy 398.127722 -287.560092)
			(xy 398.168225 -287.588048) (xy 398.203718 -287.62214) (xy 398.233283 -287.661484) (xy 398.256154 -287.705061)
			(xy 398.271738 -287.751742) (xy 398.279633 -287.800319) (xy 398.280128 -287.824926) (xy 398.61923 -287.824926)
			(xy 398.62319 -287.775872) (xy 398.634967 -287.728088) (xy 398.654258 -287.682812) (xy 398.680561 -287.641216)
			(xy 398.713196 -287.604379) (xy 398.751317 -287.573254) (xy 398.793938 -287.548647) (xy 398.839954 -287.531195)
			(xy 398.888173 -287.521351) (xy 398.937348 -287.51937) (xy 398.986203 -287.525302) (xy 399.033474 -287.538994)
			(xy 399.077936 -287.560092) (xy 399.118439 -287.588048) (xy 399.153932 -287.62214) (xy 399.183497 -287.661484)
			(xy 399.206368 -287.705061) (xy 399.221952 -287.751742) (xy 399.229847 -287.800319) (xy 399.230342 -287.824926)
			(xy 399.56919 -287.824926) (xy 399.57315 -287.775872) (xy 399.584927 -287.728088) (xy 399.604218 -287.682812)
			(xy 399.630521 -287.641216) (xy 399.663156 -287.604379) (xy 399.701277 -287.573254) (xy 399.743898 -287.548647)
			(xy 399.789914 -287.531195) (xy 399.838133 -287.521351) (xy 399.887308 -287.51937) (xy 399.936163 -287.525302)
			(xy 399.983434 -287.538994) (xy 400.027896 -287.560092) (xy 400.068399 -287.588048) (xy 400.103892 -287.62214)
			(xy 400.133457 -287.661484) (xy 400.156328 -287.705061) (xy 400.171912 -287.751742) (xy 400.179807 -287.800319)
			(xy 400.180302 -287.824926) (xy 400.51915 -287.824926) (xy 400.52311 -287.775872) (xy 400.534887 -287.728088)
			(xy 400.554178 -287.682812) (xy 400.580481 -287.641216) (xy 400.613116 -287.604379) (xy 400.651237 -287.573254)
			(xy 400.693858 -287.548647) (xy 400.739874 -287.531195) (xy 400.788093 -287.521351) (xy 400.837268 -287.51937)
			(xy 400.886123 -287.525302) (xy 400.933394 -287.538994) (xy 400.977856 -287.560092) (xy 401.018359 -287.588048)
			(xy 401.053852 -287.62214) (xy 401.083417 -287.661484) (xy 401.106288 -287.705061) (xy 401.121872 -287.751742)
			(xy 401.129767 -287.800319) (xy 401.130262 -287.824926) (xy 401.46911 -287.824926) (xy 401.47307 -287.775872)
			(xy 401.484847 -287.728088) (xy 401.504138 -287.682812) (xy 401.530441 -287.641216) (xy 401.563076 -287.604379)
			(xy 401.601197 -287.573254) (xy 401.643818 -287.548647) (xy 401.689834 -287.531195) (xy 401.738053 -287.521351)
			(xy 401.787228 -287.51937) (xy 401.836083 -287.525302) (xy 401.883354 -287.538994) (xy 401.927816 -287.560092)
			(xy 401.968319 -287.588048) (xy 402.003812 -287.62214) (xy 402.033377 -287.661484) (xy 402.056248 -287.705061)
			(xy 402.071832 -287.751742) (xy 402.079727 -287.800319) (xy 402.080222 -287.824926) (xy 402.41907 -287.824926)
			(xy 402.42303 -287.775872) (xy 402.434807 -287.728088) (xy 402.454098 -287.682812) (xy 402.480401 -287.641216)
			(xy 402.513036 -287.604379) (xy 402.551157 -287.573254) (xy 402.593778 -287.548647) (xy 402.639794 -287.531195)
			(xy 402.688013 -287.521351) (xy 402.737188 -287.51937) (xy 402.786043 -287.525302) (xy 402.833314 -287.538994)
			(xy 402.877776 -287.560092) (xy 402.918279 -287.588048) (xy 402.953772 -287.62214) (xy 402.983337 -287.661484)
			(xy 403.006208 -287.705061) (xy 403.021792 -287.751742) (xy 403.029687 -287.800319) (xy 403.030182 -287.824926)
			(xy 403.36903 -287.824926) (xy 403.37299 -287.775872) (xy 403.384767 -287.728088) (xy 403.404058 -287.682812)
			(xy 403.430361 -287.641216) (xy 403.462996 -287.604379) (xy 403.501117 -287.573254) (xy 403.543738 -287.548647)
			(xy 403.589754 -287.531195) (xy 403.637973 -287.521351) (xy 403.687148 -287.51937) (xy 403.736003 -287.525302)
			(xy 403.783274 -287.538994) (xy 403.827736 -287.560092) (xy 403.868239 -287.588048) (xy 403.903732 -287.62214)
			(xy 403.933297 -287.661484) (xy 403.956168 -287.705061) (xy 403.971752 -287.751742) (xy 403.979647 -287.800319)
			(xy 403.980142 -287.824926) (xy 404.31899 -287.824926) (xy 404.32295 -287.775872) (xy 404.334727 -287.728088)
			(xy 404.354018 -287.682812) (xy 404.380321 -287.641216) (xy 404.412956 -287.604379) (xy 404.451077 -287.573254)
			(xy 404.493698 -287.548647) (xy 404.539714 -287.531195) (xy 404.587933 -287.521351) (xy 404.637108 -287.51937)
			(xy 404.685963 -287.525302) (xy 404.733234 -287.538994) (xy 404.777696 -287.560092) (xy 404.818199 -287.588048)
			(xy 404.853692 -287.62214) (xy 404.883257 -287.661484) (xy 404.906128 -287.705061) (xy 404.921712 -287.751742)
			(xy 404.929607 -287.800319) (xy 404.930102 -287.824926) (xy 405.269204 -287.824926) (xy 405.273164 -287.775872)
			(xy 405.284941 -287.728088) (xy 405.304232 -287.682812) (xy 405.330535 -287.641216) (xy 405.36317 -287.604379)
			(xy 405.401291 -287.573254) (xy 405.443912 -287.548647) (xy 405.489928 -287.531195) (xy 405.538147 -287.521351)
			(xy 405.587322 -287.51937) (xy 405.636177 -287.525302) (xy 405.683448 -287.538994) (xy 405.72791 -287.560092)
			(xy 405.768413 -287.588048) (xy 405.803906 -287.62214) (xy 405.833471 -287.661484) (xy 405.853664 -287.699958)
			(xy 406.244056 -287.699958) (xy 406.248016 -287.650904) (xy 406.259793 -287.60312) (xy 406.279084 -287.557844)
			(xy 406.305387 -287.516248) (xy 406.338022 -287.479411) (xy 406.376143 -287.448286) (xy 406.418764 -287.423679)
			(xy 406.46478 -287.406227) (xy 406.512999 -287.396383) (xy 406.562174 -287.394402) (xy 406.611029 -287.400334)
			(xy 406.6583 -287.414026) (xy 406.702762 -287.435124) (xy 406.743265 -287.46308) (xy 406.778758 -287.497172)
			(xy 406.808323 -287.536516) (xy 406.831194 -287.580093) (xy 406.846778 -287.626774) (xy 406.854673 -287.675351)
			(xy 406.855168 -287.699958) (xy 406.854673 -287.724565) (xy 406.846778 -287.773142) (xy 406.831194 -287.819823)
			(xy 406.808323 -287.8634) (xy 406.780928 -287.899856) (xy 408.119084 -287.899856) (xy 408.123044 -287.850802)
			(xy 408.134821 -287.803018) (xy 408.154112 -287.757742) (xy 408.180415 -287.716146) (xy 408.21305 -287.679309)
			(xy 408.251171 -287.648184) (xy 408.293792 -287.623577) (xy 408.339808 -287.606125) (xy 408.388027 -287.596281)
			(xy 408.437202 -287.5943) (xy 408.486057 -287.600232) (xy 408.533328 -287.613924) (xy 408.57779 -287.635022)
			(xy 408.618293 -287.662978) (xy 408.653786 -287.69707) (xy 408.683351 -287.736414) (xy 408.706222 -287.779991)
			(xy 408.721223 -287.824926) (xy 409.069044 -287.824926) (xy 409.073004 -287.775872) (xy 409.084781 -287.728088)
			(xy 409.104072 -287.682812) (xy 409.130375 -287.641216) (xy 409.16301 -287.604379) (xy 409.201131 -287.573254)
			(xy 409.243752 -287.548647) (xy 409.289768 -287.531195) (xy 409.337987 -287.521351) (xy 409.387162 -287.51937)
			(xy 409.436017 -287.525302) (xy 409.483288 -287.538994) (xy 409.52775 -287.560092) (xy 409.568253 -287.588048)
			(xy 409.603746 -287.62214) (xy 409.633311 -287.661484) (xy 409.656182 -287.705061) (xy 409.671766 -287.751742)
			(xy 409.679661 -287.800319) (xy 409.680156 -287.824926) (xy 410.019004 -287.824926) (xy 410.022964 -287.775872)
			(xy 410.034741 -287.728088) (xy 410.054032 -287.682812) (xy 410.080335 -287.641216) (xy 410.11297 -287.604379)
			(xy 410.151091 -287.573254) (xy 410.193712 -287.548647) (xy 410.239728 -287.531195) (xy 410.287947 -287.521351)
			(xy 410.337122 -287.51937) (xy 410.385977 -287.525302) (xy 410.433248 -287.538994) (xy 410.47771 -287.560092)
			(xy 410.518213 -287.588048) (xy 410.553706 -287.62214) (xy 410.583271 -287.661484) (xy 410.606142 -287.705061)
			(xy 410.621726 -287.751742) (xy 410.629621 -287.800319) (xy 410.630116 -287.824926) (xy 410.969218 -287.824926)
			(xy 410.973178 -287.775872) (xy 410.984955 -287.728088) (xy 411.004246 -287.682812) (xy 411.030549 -287.641216)
			(xy 411.063184 -287.604379) (xy 411.101305 -287.573254) (xy 411.143926 -287.548647) (xy 411.189942 -287.531195)
			(xy 411.238161 -287.521351) (xy 411.287336 -287.51937) (xy 411.336191 -287.525302) (xy 411.383462 -287.538994)
			(xy 411.427924 -287.560092) (xy 411.468427 -287.588048) (xy 411.50392 -287.62214) (xy 411.533485 -287.661484)
			(xy 411.556356 -287.705061) (xy 411.57194 -287.751742) (xy 411.579835 -287.800319) (xy 411.58033 -287.824926)
			(xy 411.919178 -287.824926) (xy 411.923138 -287.775872) (xy 411.934915 -287.728088) (xy 411.954206 -287.682812)
			(xy 411.980509 -287.641216) (xy 412.013144 -287.604379) (xy 412.051265 -287.573254) (xy 412.093886 -287.548647)
			(xy 412.139902 -287.531195) (xy 412.188121 -287.521351) (xy 412.237296 -287.51937) (xy 412.286151 -287.525302)
			(xy 412.333422 -287.538994) (xy 412.377884 -287.560092) (xy 412.418387 -287.588048) (xy 412.45388 -287.62214)
			(xy 412.483445 -287.661484) (xy 412.506316 -287.705061) (xy 412.5219 -287.751742) (xy 412.529795 -287.800319)
			(xy 412.53029 -287.824926) (xy 412.869138 -287.824926) (xy 412.873098 -287.775872) (xy 412.884875 -287.728088)
			(xy 412.904166 -287.682812) (xy 412.930469 -287.641216) (xy 412.963104 -287.604379) (xy 413.001225 -287.573254)
			(xy 413.043846 -287.548647) (xy 413.089862 -287.531195) (xy 413.138081 -287.521351) (xy 413.187256 -287.51937)
			(xy 413.236111 -287.525302) (xy 413.283382 -287.538994) (xy 413.327844 -287.560092) (xy 413.368347 -287.588048)
			(xy 413.40384 -287.62214) (xy 413.433405 -287.661484) (xy 413.456276 -287.705061) (xy 413.47186 -287.751742)
			(xy 413.479755 -287.800319) (xy 413.48025 -287.824926) (xy 413.819098 -287.824926) (xy 413.823058 -287.775872)
			(xy 413.834835 -287.728088) (xy 413.854126 -287.682812) (xy 413.880429 -287.641216) (xy 413.913064 -287.604379)
			(xy 413.951185 -287.573254) (xy 413.993806 -287.548647) (xy 414.039822 -287.531195) (xy 414.088041 -287.521351)
			(xy 414.137216 -287.51937) (xy 414.186071 -287.525302) (xy 414.233342 -287.538994) (xy 414.277804 -287.560092)
			(xy 414.318307 -287.588048) (xy 414.3538 -287.62214) (xy 414.383365 -287.661484) (xy 414.406236 -287.705061)
			(xy 414.42182 -287.751742) (xy 414.429715 -287.800319) (xy 414.43021 -287.824926) (xy 414.769058 -287.824926)
			(xy 414.773018 -287.775872) (xy 414.784795 -287.728088) (xy 414.804086 -287.682812) (xy 414.830389 -287.641216)
			(xy 414.863024 -287.604379) (xy 414.901145 -287.573254) (xy 414.943766 -287.548647) (xy 414.989782 -287.531195)
			(xy 415.038001 -287.521351) (xy 415.087176 -287.51937) (xy 415.136031 -287.525302) (xy 415.183302 -287.538994)
			(xy 415.227764 -287.560092) (xy 415.268267 -287.588048) (xy 415.30376 -287.62214) (xy 415.333325 -287.661484)
			(xy 415.356196 -287.705061) (xy 415.37178 -287.751742) (xy 415.379675 -287.800319) (xy 415.38017 -287.824926)
			(xy 415.719018 -287.824926) (xy 415.722978 -287.775872) (xy 415.734755 -287.728088) (xy 415.754046 -287.682812)
			(xy 415.780349 -287.641216) (xy 415.812984 -287.604379) (xy 415.851105 -287.573254) (xy 415.893726 -287.548647)
			(xy 415.939742 -287.531195) (xy 415.987961 -287.521351) (xy 416.037136 -287.51937) (xy 416.085991 -287.525302)
			(xy 416.133262 -287.538994) (xy 416.177724 -287.560092) (xy 416.218227 -287.588048) (xy 416.25372 -287.62214)
			(xy 416.283285 -287.661484) (xy 416.306156 -287.705061) (xy 416.32174 -287.751742) (xy 416.329635 -287.800319)
			(xy 416.33013 -287.824926) (xy 416.668978 -287.824926) (xy 416.672938 -287.775872) (xy 416.684715 -287.728088)
			(xy 416.704006 -287.682812) (xy 416.730309 -287.641216) (xy 416.762944 -287.604379) (xy 416.801065 -287.573254)
			(xy 416.843686 -287.548647) (xy 416.889702 -287.531195) (xy 416.937921 -287.521351) (xy 416.987096 -287.51937)
			(xy 417.035951 -287.525302) (xy 417.083222 -287.538994) (xy 417.127684 -287.560092) (xy 417.168187 -287.588048)
			(xy 417.20368 -287.62214) (xy 417.233245 -287.661484) (xy 417.256116 -287.705061) (xy 417.2717 -287.751742)
			(xy 417.279595 -287.800319) (xy 417.28009 -287.824926) (xy 418.569152 -287.824926) (xy 418.573112 -287.775872)
			(xy 418.584889 -287.728088) (xy 418.60418 -287.682812) (xy 418.630483 -287.641216) (xy 418.663118 -287.604379)
			(xy 418.701239 -287.573254) (xy 418.74386 -287.548647) (xy 418.789876 -287.531195) (xy 418.838095 -287.521351)
			(xy 418.88727 -287.51937) (xy 418.936125 -287.525302) (xy 418.983396 -287.538994) (xy 419.027858 -287.560092)
			(xy 419.068361 -287.588048) (xy 419.103854 -287.62214) (xy 419.133419 -287.661484) (xy 419.15629 -287.705061)
			(xy 419.171874 -287.751742) (xy 419.179769 -287.800319) (xy 419.180264 -287.824926) (xy 420.469072 -287.824926)
			(xy 420.473032 -287.775872) (xy 420.484809 -287.728088) (xy 420.5041 -287.682812) (xy 420.530403 -287.641216)
			(xy 420.563038 -287.604379) (xy 420.601159 -287.573254) (xy 420.64378 -287.548647) (xy 420.689796 -287.531195)
			(xy 420.738015 -287.521351) (xy 420.78719 -287.51937) (xy 420.836045 -287.525302) (xy 420.883316 -287.538994)
			(xy 420.927778 -287.560092) (xy 420.968281 -287.588048) (xy 421.003774 -287.62214) (xy 421.033339 -287.661484)
			(xy 421.05621 -287.705061) (xy 421.071794 -287.751742) (xy 421.079689 -287.800319) (xy 421.080184 -287.824926)
			(xy 421.079689 -287.849533) (xy 421.071794 -287.89811) (xy 421.05621 -287.944791) (xy 421.033339 -287.988368)
			(xy 421.003774 -288.027712) (xy 420.968281 -288.061804) (xy 420.927778 -288.08976) (xy 420.883316 -288.110858)
			(xy 420.836045 -288.12455) (xy 420.78719 -288.130482) (xy 420.738015 -288.128501) (xy 420.689796 -288.118657)
			(xy 420.64378 -288.101205) (xy 420.601159 -288.076598) (xy 420.563038 -288.045473) (xy 420.530403 -288.008636)
			(xy 420.5041 -287.96704) (xy 420.484809 -287.921764) (xy 420.473032 -287.87398) (xy 420.469072 -287.824926)
			(xy 419.180264 -287.824926) (xy 419.179769 -287.849533) (xy 419.171874 -287.89811) (xy 419.15629 -287.944791)
			(xy 419.133419 -287.988368) (xy 419.103854 -288.027712) (xy 419.068361 -288.061804) (xy 419.027858 -288.08976)
			(xy 418.983396 -288.110858) (xy 418.936125 -288.12455) (xy 418.88727 -288.130482) (xy 418.838095 -288.128501)
			(xy 418.789876 -288.118657) (xy 418.74386 -288.101205) (xy 418.701239 -288.076598) (xy 418.663118 -288.045473)
			(xy 418.630483 -288.008636) (xy 418.60418 -287.96704) (xy 418.584889 -287.921764) (xy 418.573112 -287.87398)
			(xy 418.569152 -287.824926) (xy 417.28009 -287.824926) (xy 417.279595 -287.849533) (xy 417.2717 -287.89811)
			(xy 417.256116 -287.944791) (xy 417.233245 -287.988368) (xy 417.20368 -288.027712) (xy 417.168187 -288.061804)
			(xy 417.127684 -288.08976) (xy 417.083222 -288.110858) (xy 417.035951 -288.12455) (xy 416.987096 -288.130482)
			(xy 416.937921 -288.128501) (xy 416.889702 -288.118657) (xy 416.843686 -288.101205) (xy 416.801065 -288.076598)
			(xy 416.762944 -288.045473) (xy 416.730309 -288.008636) (xy 416.704006 -287.96704) (xy 416.684715 -287.921764)
			(xy 416.672938 -287.87398) (xy 416.668978 -287.824926) (xy 416.33013 -287.824926) (xy 416.329635 -287.849533)
			(xy 416.32174 -287.89811) (xy 416.306156 -287.944791) (xy 416.283285 -287.988368) (xy 416.25372 -288.027712)
			(xy 416.218227 -288.061804) (xy 416.177724 -288.08976) (xy 416.133262 -288.110858) (xy 416.085991 -288.12455)
			(xy 416.037136 -288.130482) (xy 415.987961 -288.128501) (xy 415.939742 -288.118657) (xy 415.893726 -288.101205)
			(xy 415.851105 -288.076598) (xy 415.812984 -288.045473) (xy 415.780349 -288.008636) (xy 415.754046 -287.96704)
			(xy 415.734755 -287.921764) (xy 415.722978 -287.87398) (xy 415.719018 -287.824926) (xy 415.38017 -287.824926)
			(xy 415.379675 -287.849533) (xy 415.37178 -287.89811) (xy 415.356196 -287.944791) (xy 415.333325 -287.988368)
			(xy 415.30376 -288.027712) (xy 415.268267 -288.061804) (xy 415.227764 -288.08976) (xy 415.183302 -288.110858)
			(xy 415.136031 -288.12455) (xy 415.087176 -288.130482) (xy 415.038001 -288.128501) (xy 414.989782 -288.118657)
			(xy 414.943766 -288.101205) (xy 414.901145 -288.076598) (xy 414.863024 -288.045473) (xy 414.830389 -288.008636)
			(xy 414.804086 -287.96704) (xy 414.784795 -287.921764) (xy 414.773018 -287.87398) (xy 414.769058 -287.824926)
			(xy 414.43021 -287.824926) (xy 414.429715 -287.849533) (xy 414.42182 -287.89811) (xy 414.406236 -287.944791)
			(xy 414.383365 -287.988368) (xy 414.3538 -288.027712) (xy 414.318307 -288.061804) (xy 414.277804 -288.08976)
			(xy 414.233342 -288.110858) (xy 414.186071 -288.12455) (xy 414.137216 -288.130482) (xy 414.088041 -288.128501)
			(xy 414.039822 -288.118657) (xy 413.993806 -288.101205) (xy 413.951185 -288.076598) (xy 413.913064 -288.045473)
			(xy 413.880429 -288.008636) (xy 413.854126 -287.96704) (xy 413.834835 -287.921764) (xy 413.823058 -287.87398)
			(xy 413.819098 -287.824926) (xy 413.48025 -287.824926) (xy 413.479755 -287.849533) (xy 413.47186 -287.89811)
			(xy 413.456276 -287.944791) (xy 413.433405 -287.988368) (xy 413.40384 -288.027712) (xy 413.368347 -288.061804)
			(xy 413.327844 -288.08976) (xy 413.283382 -288.110858) (xy 413.236111 -288.12455) (xy 413.187256 -288.130482)
			(xy 413.138081 -288.128501) (xy 413.089862 -288.118657) (xy 413.043846 -288.101205) (xy 413.001225 -288.076598)
			(xy 412.963104 -288.045473) (xy 412.930469 -288.008636) (xy 412.904166 -287.96704) (xy 412.884875 -287.921764)
			(xy 412.873098 -287.87398) (xy 412.869138 -287.824926) (xy 412.53029 -287.824926) (xy 412.529795 -287.849533)
			(xy 412.5219 -287.89811) (xy 412.506316 -287.944791) (xy 412.483445 -287.988368) (xy 412.45388 -288.027712)
			(xy 412.418387 -288.061804) (xy 412.377884 -288.08976) (xy 412.333422 -288.110858) (xy 412.286151 -288.12455)
			(xy 412.237296 -288.130482) (xy 412.188121 -288.128501) (xy 412.139902 -288.118657) (xy 412.093886 -288.101205)
			(xy 412.051265 -288.076598) (xy 412.013144 -288.045473) (xy 411.980509 -288.008636) (xy 411.954206 -287.96704)
			(xy 411.934915 -287.921764) (xy 411.923138 -287.87398) (xy 411.919178 -287.824926) (xy 411.58033 -287.824926)
			(xy 411.579835 -287.849533) (xy 411.57194 -287.89811) (xy 411.556356 -287.944791) (xy 411.533485 -287.988368)
			(xy 411.50392 -288.027712) (xy 411.468427 -288.061804) (xy 411.427924 -288.08976) (xy 411.383462 -288.110858)
			(xy 411.336191 -288.12455) (xy 411.287336 -288.130482) (xy 411.238161 -288.128501) (xy 411.189942 -288.118657)
			(xy 411.143926 -288.101205) (xy 411.101305 -288.076598) (xy 411.063184 -288.045473) (xy 411.030549 -288.008636)
			(xy 411.004246 -287.96704) (xy 410.984955 -287.921764) (xy 410.973178 -287.87398) (xy 410.969218 -287.824926)
			(xy 410.630116 -287.824926) (xy 410.629621 -287.849533) (xy 410.621726 -287.89811) (xy 410.606142 -287.944791)
			(xy 410.583271 -287.988368) (xy 410.553706 -288.027712) (xy 410.518213 -288.061804) (xy 410.47771 -288.08976)
			(xy 410.433248 -288.110858) (xy 410.385977 -288.12455) (xy 410.337122 -288.130482) (xy 410.287947 -288.128501)
			(xy 410.239728 -288.118657) (xy 410.193712 -288.101205) (xy 410.151091 -288.076598) (xy 410.11297 -288.045473)
			(xy 410.080335 -288.008636) (xy 410.054032 -287.96704) (xy 410.034741 -287.921764) (xy 410.022964 -287.87398)
			(xy 410.019004 -287.824926) (xy 409.680156 -287.824926) (xy 409.679661 -287.849533) (xy 409.671766 -287.89811)
			(xy 409.656182 -287.944791) (xy 409.633311 -287.988368) (xy 409.603746 -288.027712) (xy 409.568253 -288.061804)
			(xy 409.52775 -288.08976) (xy 409.483288 -288.110858) (xy 409.436017 -288.12455) (xy 409.387162 -288.130482)
			(xy 409.337987 -288.128501) (xy 409.289768 -288.118657) (xy 409.243752 -288.101205) (xy 409.201131 -288.076598)
			(xy 409.16301 -288.045473) (xy 409.130375 -288.008636) (xy 409.104072 -287.96704) (xy 409.084781 -287.921764)
			(xy 409.073004 -287.87398) (xy 409.069044 -287.824926) (xy 408.721223 -287.824926) (xy 408.721806 -287.826672)
			(xy 408.729701 -287.875249) (xy 408.730196 -287.899856) (xy 408.729701 -287.924463) (xy 408.721806 -287.97304)
			(xy 408.706222 -288.019721) (xy 408.683351 -288.063298) (xy 408.653786 -288.102642) (xy 408.618293 -288.136734)
			(xy 408.57779 -288.16469) (xy 408.533328 -288.185788) (xy 408.486057 -288.19948) (xy 408.437202 -288.205412)
			(xy 408.388027 -288.203431) (xy 408.339808 -288.193587) (xy 408.293792 -288.176135) (xy 408.251171 -288.151528)
			(xy 408.21305 -288.120403) (xy 408.180415 -288.083566) (xy 408.154112 -288.04197) (xy 408.134821 -287.996694)
			(xy 408.123044 -287.94891) (xy 408.119084 -287.899856) (xy 406.780928 -287.899856) (xy 406.778758 -287.902744)
			(xy 406.743265 -287.936836) (xy 406.702762 -287.964792) (xy 406.6583 -287.98589) (xy 406.611029 -287.999582)
			(xy 406.562174 -288.005514) (xy 406.512999 -288.003533) (xy 406.46478 -287.993689) (xy 406.418764 -287.976237)
			(xy 406.376143 -287.95163) (xy 406.338022 -287.920505) (xy 406.305387 -287.883668) (xy 406.279084 -287.842072)
			(xy 406.259793 -287.796796) (xy 406.248016 -287.749012) (xy 406.244056 -287.699958) (xy 405.853664 -287.699958)
			(xy 405.856342 -287.705061) (xy 405.871926 -287.751742) (xy 405.879821 -287.800319) (xy 405.880316 -287.824926)
			(xy 405.879821 -287.849533) (xy 405.871926 -287.89811) (xy 405.856342 -287.944791) (xy 405.833471 -287.988368)
			(xy 405.803906 -288.027712) (xy 405.768413 -288.061804) (xy 405.72791 -288.08976) (xy 405.683448 -288.110858)
			(xy 405.636177 -288.12455) (xy 405.587322 -288.130482) (xy 405.538147 -288.128501) (xy 405.489928 -288.118657)
			(xy 405.443912 -288.101205) (xy 405.401291 -288.076598) (xy 405.36317 -288.045473) (xy 405.330535 -288.008636)
			(xy 405.304232 -287.96704) (xy 405.284941 -287.921764) (xy 405.273164 -287.87398) (xy 405.269204 -287.824926)
			(xy 404.930102 -287.824926) (xy 404.929607 -287.849533) (xy 404.921712 -287.89811) (xy 404.906128 -287.944791)
			(xy 404.883257 -287.988368) (xy 404.853692 -288.027712) (xy 404.818199 -288.061804) (xy 404.777696 -288.08976)
			(xy 404.733234 -288.110858) (xy 404.685963 -288.12455) (xy 404.637108 -288.130482) (xy 404.587933 -288.128501)
			(xy 404.539714 -288.118657) (xy 404.493698 -288.101205) (xy 404.451077 -288.076598) (xy 404.412956 -288.045473)
			(xy 404.380321 -288.008636) (xy 404.354018 -287.96704) (xy 404.334727 -287.921764) (xy 404.32295 -287.87398)
			(xy 404.31899 -287.824926) (xy 403.980142 -287.824926) (xy 403.979647 -287.849533) (xy 403.971752 -287.89811)
			(xy 403.956168 -287.944791) (xy 403.933297 -287.988368) (xy 403.903732 -288.027712) (xy 403.868239 -288.061804)
			(xy 403.827736 -288.08976) (xy 403.783274 -288.110858) (xy 403.736003 -288.12455) (xy 403.687148 -288.130482)
			(xy 403.637973 -288.128501) (xy 403.589754 -288.118657) (xy 403.543738 -288.101205) (xy 403.501117 -288.076598)
			(xy 403.462996 -288.045473) (xy 403.430361 -288.008636) (xy 403.404058 -287.96704) (xy 403.384767 -287.921764)
			(xy 403.37299 -287.87398) (xy 403.36903 -287.824926) (xy 403.030182 -287.824926) (xy 403.029687 -287.849533)
			(xy 403.021792 -287.89811) (xy 403.006208 -287.944791) (xy 402.983337 -287.988368) (xy 402.953772 -288.027712)
			(xy 402.918279 -288.061804) (xy 402.877776 -288.08976) (xy 402.833314 -288.110858) (xy 402.786043 -288.12455)
			(xy 402.737188 -288.130482) (xy 402.688013 -288.128501) (xy 402.639794 -288.118657) (xy 402.593778 -288.101205)
			(xy 402.551157 -288.076598) (xy 402.513036 -288.045473) (xy 402.480401 -288.008636) (xy 402.454098 -287.96704)
			(xy 402.434807 -287.921764) (xy 402.42303 -287.87398) (xy 402.41907 -287.824926) (xy 402.080222 -287.824926)
			(xy 402.079727 -287.849533) (xy 402.071832 -287.89811) (xy 402.056248 -287.944791) (xy 402.033377 -287.988368)
			(xy 402.003812 -288.027712) (xy 401.968319 -288.061804) (xy 401.927816 -288.08976) (xy 401.883354 -288.110858)
			(xy 401.836083 -288.12455) (xy 401.787228 -288.130482) (xy 401.738053 -288.128501) (xy 401.689834 -288.118657)
			(xy 401.643818 -288.101205) (xy 401.601197 -288.076598) (xy 401.563076 -288.045473) (xy 401.530441 -288.008636)
			(xy 401.504138 -287.96704) (xy 401.484847 -287.921764) (xy 401.47307 -287.87398) (xy 401.46911 -287.824926)
			(xy 401.130262 -287.824926) (xy 401.129767 -287.849533) (xy 401.121872 -287.89811) (xy 401.106288 -287.944791)
			(xy 401.083417 -287.988368) (xy 401.053852 -288.027712) (xy 401.018359 -288.061804) (xy 400.977856 -288.08976)
			(xy 400.933394 -288.110858) (xy 400.886123 -288.12455) (xy 400.837268 -288.130482) (xy 400.788093 -288.128501)
			(xy 400.739874 -288.118657) (xy 400.693858 -288.101205) (xy 400.651237 -288.076598) (xy 400.613116 -288.045473)
			(xy 400.580481 -288.008636) (xy 400.554178 -287.96704) (xy 400.534887 -287.921764) (xy 400.52311 -287.87398)
			(xy 400.51915 -287.824926) (xy 400.180302 -287.824926) (xy 400.179807 -287.849533) (xy 400.171912 -287.89811)
			(xy 400.156328 -287.944791) (xy 400.133457 -287.988368) (xy 400.103892 -288.027712) (xy 400.068399 -288.061804)
			(xy 400.027896 -288.08976) (xy 399.983434 -288.110858) (xy 399.936163 -288.12455) (xy 399.887308 -288.130482)
			(xy 399.838133 -288.128501) (xy 399.789914 -288.118657) (xy 399.743898 -288.101205) (xy 399.701277 -288.076598)
			(xy 399.663156 -288.045473) (xy 399.630521 -288.008636) (xy 399.604218 -287.96704) (xy 399.584927 -287.921764)
			(xy 399.57315 -287.87398) (xy 399.56919 -287.824926) (xy 399.230342 -287.824926) (xy 399.229847 -287.849533)
			(xy 399.221952 -287.89811) (xy 399.206368 -287.944791) (xy 399.183497 -287.988368) (xy 399.153932 -288.027712)
			(xy 399.118439 -288.061804) (xy 399.077936 -288.08976) (xy 399.033474 -288.110858) (xy 398.986203 -288.12455)
			(xy 398.937348 -288.130482) (xy 398.888173 -288.128501) (xy 398.839954 -288.118657) (xy 398.793938 -288.101205)
			(xy 398.751317 -288.076598) (xy 398.713196 -288.045473) (xy 398.680561 -288.008636) (xy 398.654258 -287.96704)
			(xy 398.634967 -287.921764) (xy 398.62319 -287.87398) (xy 398.61923 -287.824926) (xy 398.280128 -287.824926)
			(xy 398.279633 -287.849533) (xy 398.271738 -287.89811) (xy 398.256154 -287.944791) (xy 398.233283 -287.988368)
			(xy 398.203718 -288.027712) (xy 398.168225 -288.061804) (xy 398.127722 -288.08976) (xy 398.08326 -288.110858)
			(xy 398.035989 -288.12455) (xy 397.987134 -288.130482) (xy 397.937959 -288.128501) (xy 397.88974 -288.118657)
			(xy 397.843724 -288.101205) (xy 397.801103 -288.076598) (xy 397.762982 -288.045473) (xy 397.730347 -288.008636)
			(xy 397.704044 -287.96704) (xy 397.684753 -287.921764) (xy 397.672976 -287.87398) (xy 397.669016 -287.824926)
			(xy 397.355121 -287.824926) (xy 397.355121 -287.851263) (xy 397.346757 -287.903315) (xy 397.330242 -287.953381)
			(xy 397.305993 -288.000192) (xy 397.274626 -288.042565) (xy 397.236933 -288.079424) (xy 397.193871 -288.109838)
			(xy 397.14653 -288.133035) (xy 397.096108 -288.148428) (xy 397.070072 -288.152586) (xy 397.066008 -288.153094)
			(xy 397.054578 -288.15665) (xy 397.05026 -288.15792) (xy 397.02613 -288.169096) (xy 397.019526 -288.176208)
			(xy 397.004794 -288.191702) (xy 396.996666 -288.202878) (xy 396.993971 -288.20841) (xy 396.991018 -288.22035)
			(xy 396.990824 -288.2265) (xy 396.990824 -288.299906) (xy 421.894012 -288.299906) (xy 421.897972 -288.250852)
			(xy 421.909749 -288.203068) (xy 421.92904 -288.157792) (xy 421.955343 -288.116196) (xy 421.987978 -288.079359)
			(xy 422.026099 -288.048234) (xy 422.06872 -288.023627) (xy 422.114736 -288.006175) (xy 422.162955 -287.996331)
			(xy 422.21213 -287.99435) (xy 422.260985 -288.000282) (xy 422.308256 -288.013974) (xy 422.352718 -288.035072)
			(xy 422.393221 -288.063028) (xy 422.428714 -288.09712) (xy 422.458279 -288.136464) (xy 422.48115 -288.180041)
			(xy 422.496734 -288.226722) (xy 422.504629 -288.275299) (xy 422.505124 -288.299906) (xy 422.844226 -288.299906)
			(xy 422.848186 -288.250852) (xy 422.859963 -288.203068) (xy 422.879254 -288.157792) (xy 422.905557 -288.116196)
			(xy 422.938192 -288.079359) (xy 422.976313 -288.048234) (xy 423.018934 -288.023627) (xy 423.06495 -288.006175)
			(xy 423.113169 -287.996331) (xy 423.162344 -287.99435) (xy 423.211199 -288.000282) (xy 423.25847 -288.013974)
			(xy 423.302932 -288.035072) (xy 423.343435 -288.063028) (xy 423.378928 -288.09712) (xy 423.408493 -288.136464)
			(xy 423.431364 -288.180041) (xy 423.446948 -288.226722) (xy 423.454843 -288.275299) (xy 423.455338 -288.299906)
			(xy 423.455172 -288.308173) (xy 423.794291 -288.308173) (xy 423.79698 -288.258606) (xy 423.807652 -288.210127)
			(xy 423.826027 -288.164013) (xy 423.85162 -288.121479) (xy 423.883758 -288.083646) (xy 423.921592 -288.051511)
			(xy 423.964127 -288.02592) (xy 424.010242 -288.007548) (xy 424.058722 -287.996878) (xy 424.108289 -287.994191)
			(xy 424.157638 -287.99956) (xy 424.205468 -288.012841) (xy 424.250519 -288.033685) (xy 424.291605 -288.061543)
			(xy 424.327643 -288.095681) (xy 424.357683 -288.1352) (xy 424.380934 -288.179058) (xy 424.396783 -288.2261)
			(xy 424.404813 -288.275086) (xy 424.405298 -288.299906) (xy 424.405122 -288.314089) (xy 424.40245 -288.342329)
			(xy 424.399964 -288.356294) (xy 424.397678 -288.36874) (xy 424.405044 -288.392362) (xy 424.482514 -288.469832)
			(xy 424.506136 -288.477198) (xy 424.518582 -288.474912) (xy 424.532547 -288.472428) (xy 424.560787 -288.469761)
			(xy 424.57497 -288.469578) (xy 424.584841 -288.469654) (xy 424.604542 -288.470923) (xy 424.61434 -288.472118)
			(xy 424.626278 -288.473642) (xy 424.648884 -288.465768) (xy 424.722544 -288.389314) (xy 424.729402 -288.366454)
			(xy 424.727624 -288.354516) (xy 424.725467 -288.340967) (xy 424.72318 -288.313625) (xy 424.723052 -288.299906)
			(xy 424.723573 -288.274215) (xy 424.731611 -288.223465) (xy 424.747489 -288.174597) (xy 424.770816 -288.128815)
			(xy 424.801018 -288.087246) (xy 424.837351 -288.050913) (xy 424.878921 -288.020712) (xy 424.924703 -287.997386)
			(xy 424.973571 -287.981509) (xy 425.024321 -287.973473) (xy 425.075704 -287.973475) (xy 425.126453 -287.981515)
			(xy 425.17532 -287.997396) (xy 425.221101 -288.020725) (xy 425.262668 -288.05093) (xy 425.298999 -288.087265)
			(xy 425.329198 -288.128837) (xy 425.352521 -288.174621) (xy 425.368395 -288.223489) (xy 425.376429 -288.27424)
			(xy 425.376424 -288.325614) (xy 425.673262 -288.325614) (xy 425.673262 -288.274198) (xy 425.681305 -288.223416)
			(xy 425.697193 -288.174517) (xy 425.720536 -288.128705) (xy 425.750757 -288.087109) (xy 425.787113 -288.050753)
			(xy 425.828709 -288.020532) (xy 425.874521 -287.997189) (xy 425.92342 -287.981301) (xy 425.974202 -287.973258)
			(xy 426.025618 -287.973258) (xy 426.0764 -287.981301) (xy 426.125299 -287.997189) (xy 426.171111 -288.020532)
			(xy 426.212707 -288.050753) (xy 426.249063 -288.087109) (xy 426.279284 -288.128705) (xy 426.302627 -288.174517)
			(xy 426.318515 -288.223416) (xy 426.326558 -288.274198) (xy 426.327062 -288.299906) (xy 426.3269 -288.308159)
			(xy 426.644211 -288.308159) (xy 426.646901 -288.258596) (xy 426.657575 -288.210121) (xy 426.67595 -288.164011)
			(xy 426.701543 -288.121482) (xy 426.733679 -288.083653) (xy 426.771511 -288.051522) (xy 426.814044 -288.025934)
			(xy 426.860155 -288.007564) (xy 426.908631 -287.996896) (xy 426.958195 -287.994212) (xy 427.00754 -287.99958)
			(xy 427.055366 -288.012861) (xy 427.100413 -288.033705) (xy 427.141496 -288.061561) (xy 427.17753 -288.095697)
			(xy 427.207567 -288.135213) (xy 427.230816 -288.179068) (xy 427.246664 -288.226106) (xy 427.254693 -288.275088)
			(xy 427.255178 -288.299906) (xy 427.255003 -288.314089) (xy 427.25233 -288.342329) (xy 427.249844 -288.356294)
			(xy 427.247558 -288.36874) (xy 427.254924 -288.392362) (xy 427.332394 -288.469832) (xy 427.356016 -288.477198)
			(xy 427.368462 -288.474912) (xy 427.382427 -288.472431) (xy 427.410667 -288.469762) (xy 427.42485 -288.469578)
			(xy 427.434721 -288.469655) (xy 427.454421 -288.470924) (xy 427.46422 -288.472118) (xy 427.476158 -288.473642)
			(xy 427.498764 -288.465768) (xy 427.572424 -288.389314) (xy 427.579282 -288.366454) (xy 427.577504 -288.354516)
			(xy 427.575348 -288.340967) (xy 427.57306 -288.313625) (xy 427.572932 -288.299906) (xy 427.573436 -288.274218)
			(xy 427.581473 -288.223475) (xy 427.597349 -288.174614) (xy 427.620673 -288.128838) (xy 427.65087 -288.087274)
			(xy 427.687198 -288.050946) (xy 427.728762 -288.020749) (xy 427.774538 -287.997425) (xy 427.823399 -287.981549)
			(xy 427.874142 -287.973512) (xy 427.925518 -287.973512) (xy 427.976261 -287.981549) (xy 428.025122 -287.997425)
			(xy 428.070898 -288.020749) (xy 428.112462 -288.050946) (xy 428.14879 -288.087274) (xy 428.178987 -288.128838)
			(xy 428.202311 -288.174614) (xy 428.218187 -288.223475) (xy 428.226224 -288.274218) (xy 428.226728 -288.299906)
			(xy 428.226581 -288.313624) (xy 428.224293 -288.340965) (xy 428.222156 -288.354516) (xy 428.220378 -288.366454)
			(xy 428.227236 -288.389314) (xy 428.300896 -288.465768) (xy 428.323502 -288.473642) (xy 428.33544 -288.472118)
			(xy 428.345239 -288.470931) (xy 428.364939 -288.469659) (xy 428.37481 -288.469578) (xy 428.384681 -288.46965)
			(xy 428.404382 -288.470922) (xy 428.41418 -288.472118) (xy 428.426118 -288.473642) (xy 428.448724 -288.465768)
			(xy 428.522384 -288.389314) (xy 428.529242 -288.366454) (xy 428.527464 -288.354516) (xy 428.525308 -288.340967)
			(xy 428.52302 -288.313625) (xy 428.522892 -288.299906) (xy 428.523396 -288.274218) (xy 428.531433 -288.223475)
			(xy 428.547309 -288.174614) (xy 428.570633 -288.128838) (xy 428.60083 -288.087274) (xy 428.637158 -288.050946)
			(xy 428.678722 -288.020749) (xy 428.724498 -287.997425) (xy 428.773359 -287.981549) (xy 428.824102 -287.973512)
			(xy 428.875478 -287.973512) (xy 428.926221 -287.981549) (xy 428.975082 -287.997425) (xy 429.020858 -288.020749)
			(xy 429.062422 -288.050946) (xy 429.09875 -288.087274) (xy 429.128947 -288.128838) (xy 429.152271 -288.174614)
			(xy 429.168147 -288.223475) (xy 429.176184 -288.274218) (xy 429.176688 -288.299906) (xy 429.176541 -288.313624)
			(xy 429.174253 -288.340965) (xy 429.172116 -288.354516) (xy 429.170084 -288.366454) (xy 429.177196 -288.389314)
			(xy 429.250856 -288.465768) (xy 429.273462 -288.473642) (xy 429.285654 -288.472118) (xy 429.295453 -288.47093)
			(xy 429.315153 -288.469658) (xy 429.325024 -288.469578) (xy 429.339207 -288.469752) (xy 429.367447 -288.472426)
			(xy 429.381412 -288.474912) (xy 429.393858 -288.477198) (xy 429.41748 -288.469832) (xy 429.49495 -288.392362)
			(xy 429.502316 -288.36874) (xy 429.50003 -288.356294) (xy 429.497557 -288.342328) (xy 429.494883 -288.314088)
			(xy 429.494696 -288.299906) (xy 429.495218 -288.274651) (xy 429.503531 -288.224829) (xy 429.519932 -288.177055)
			(xy 429.543973 -288.132632) (xy 429.574997 -288.092772) (xy 429.612159 -288.058562) (xy 429.654445 -288.030936)
			(xy 429.700701 -288.010646) (xy 429.749666 -287.998246) (xy 429.800004 -287.994075) (xy 429.850342 -287.998246)
			(xy 429.899307 -288.010646) (xy 429.945563 -288.030936) (xy 429.987849 -288.058562) (xy 430.025011 -288.092772)
			(xy 430.056035 -288.132632) (xy 430.080076 -288.177055) (xy 430.096477 -288.224829) (xy 430.10479 -288.274651)
			(xy 430.105312 -288.299906) (xy 430.105136 -288.314089) (xy 430.102464 -288.342329) (xy 430.099978 -288.356294)
			(xy 430.097692 -288.36874) (xy 430.105058 -288.392362) (xy 430.182528 -288.469832) (xy 430.20615 -288.477198)
			(xy 430.218596 -288.474912) (xy 430.232563 -288.47244) (xy 430.260802 -288.469765) (xy 430.274984 -288.469578)
			(xy 430.289167 -288.469757) (xy 430.317407 -288.472428) (xy 430.331372 -288.474912) (xy 430.343818 -288.477198)
			(xy 430.36744 -288.469832) (xy 430.44491 -288.392362) (xy 430.452276 -288.36874) (xy 430.44999 -288.356294)
			(xy 430.447516 -288.342328) (xy 430.444843 -288.314088) (xy 430.444656 -288.299906) (xy 430.445178 -288.274651)
			(xy 430.453491 -288.224829) (xy 430.469892 -288.177055) (xy 430.493933 -288.132632) (xy 430.524957 -288.092772)
			(xy 430.562119 -288.058562) (xy 430.604405 -288.030936) (xy 430.650661 -288.010646) (xy 430.699626 -287.998246)
			(xy 430.749964 -287.994075) (xy 430.800302 -287.998246) (xy 430.849267 -288.010646) (xy 430.895523 -288.030936)
			(xy 430.937809 -288.058562) (xy 430.974971 -288.092772) (xy 431.005995 -288.132632) (xy 431.030036 -288.177055)
			(xy 431.046437 -288.224829) (xy 431.050379 -288.248455) (xy 435.895921 -288.248455) (xy 435.895921 -288.193945)
			(xy 435.903679 -288.139988) (xy 435.919036 -288.087685) (xy 435.941681 -288.038101) (xy 435.971152 -287.992243)
			(xy 436.00685 -287.951047) (xy 436.048046 -287.91535) (xy 436.093904 -287.885879) (xy 436.143489 -287.863235)
			(xy 436.195792 -287.847878) (xy 436.249749 -287.840121) (xy 436.277004 -287.839658) (xy 436.30312 -287.84011)
			(xy 436.354864 -287.847248) (xy 436.40515 -287.861376) (xy 436.453039 -287.88223) (xy 436.497637 -287.909421)
			(xy 436.53811 -287.94244) (xy 436.573701 -287.98067) (xy 436.603746 -288.023397) (xy 436.616094 -288.046414)
			(xy 436.622861 -288.058628) (xy 436.641864 -288.079074) (xy 436.66569 -288.093616) (xy 436.692561 -288.101168)
			(xy 436.720475 -288.101168) (xy 436.747346 -288.093616) (xy 436.771172 -288.079074) (xy 436.790175 -288.058628)
			(xy 436.796942 -288.046414) (xy 436.809302 -288.023401) (xy 436.839331 -287.980658) (xy 436.874913 -287.942414)
			(xy 436.915382 -287.909384) (xy 436.95998 -287.882187) (xy 437.007873 -287.861333) (xy 437.058165 -287.84721)
			(xy 437.109914 -287.840085) (xy 437.136032 -287.839658) (xy 437.163279 -287.840214) (xy 437.217219 -287.847974)
			(xy 437.269505 -287.86333) (xy 437.319074 -287.885971) (xy 437.364916 -287.915436) (xy 437.406099 -287.951124)
			(xy 437.441783 -287.99231) (xy 437.471244 -288.038155) (xy 437.493881 -288.087725) (xy 437.509233 -288.140013)
			(xy 437.516988 -288.193953) (xy 437.516988 -288.224712) (xy 437.77102 -288.224712) (xy 437.771025 -288.170216)
			(xy 437.778785 -288.116276) (xy 437.794143 -288.063989) (xy 437.816786 -288.01442) (xy 437.846253 -287.968578)
			(xy 437.881944 -287.927396) (xy 437.923132 -287.891712) (xy 437.96898 -287.862254) (xy 438.018553 -287.83962)
			(xy 438.070842 -287.824271) (xy 438.124784 -287.81652) (xy 438.152032 -287.816036) (xy 438.172098 -287.816544)
			(xy 438.184036 -287.817306) (xy 438.205626 -287.807908) (xy 438.273444 -287.72739) (xy 438.279032 -287.70453)
			(xy 438.276492 -287.692846) (xy 438.272095 -287.672171) (xy 438.267389 -287.630162) (xy 438.267094 -287.609026)
			(xy 438.26758 -287.581775) (xy 438.275336 -287.527827) (xy 438.290691 -287.475532) (xy 438.313333 -287.425955)
			(xy 438.342799 -287.380105) (xy 438.37849 -287.338914) (xy 438.419681 -287.303223) (xy 438.465531 -287.273757)
			(xy 438.515108 -287.251115) (xy 438.567403 -287.23576) (xy 438.621351 -287.228004) (xy 438.675853 -287.228004)
			(xy 438.729801 -287.23576) (xy 438.782096 -287.251115) (xy 438.831673 -287.273757) (xy 438.877523 -287.303223)
			(xy 438.918714 -287.338914) (xy 438.954405 -287.380105) (xy 438.983871 -287.425955) (xy 439.006513 -287.475532)
			(xy 439.021868 -287.527827) (xy 439.029624 -287.581775) (xy 439.03011 -287.609026) (xy 439.029679 -287.63547)
			(xy 439.022416 -287.687857) (xy 439.015632 -287.71342) (xy 439.012076 -287.725866) (xy 439.01741 -287.75025)
			(xy 439.08853 -287.834324) (xy 439.111898 -287.843468) (xy 439.124852 -287.842198) (xy 439.13298 -287.841182)
			(xy 439.144156 -287.840166) (xy 439.163206 -287.829244) (xy 439.220864 -287.747456) (xy 439.224674 -287.725612)
			(xy 439.22188 -287.71469) (xy 439.216292 -287.69134) (xy 439.210305 -287.643701) (xy 439.209942 -287.619694)
			(xy 439.210428 -287.592443) (xy 439.218184 -287.538495) (xy 439.233539 -287.4862) (xy 439.256181 -287.436623)
			(xy 439.285647 -287.390773) (xy 439.321338 -287.349582) (xy 439.362529 -287.313891) (xy 439.408379 -287.284425)
			(xy 439.457956 -287.261783) (xy 439.510251 -287.246428) (xy 439.564199 -287.238672) (xy 439.618701 -287.238672)
			(xy 439.672649 -287.246428) (xy 439.705439 -287.256056) (xy 448.436643 -287.256056) (xy 448.436643 -287.201544)
			(xy 448.444401 -287.147587) (xy 448.45976 -287.095284) (xy 448.482407 -287.045699) (xy 448.51188 -286.999843)
			(xy 448.54758 -286.958647) (xy 448.588779 -286.922953) (xy 448.63464 -286.893485) (xy 448.684227 -286.870844)
			(xy 448.736532 -286.855492) (xy 448.79049 -286.84774) (xy 448.817746 -286.84728) (xy 448.846486 -286.847781)
			(xy 448.903314 -286.85641) (xy 448.958205 -286.873466) (xy 449.009916 -286.898562) (xy 449.057278 -286.931131)
			(xy 449.078604 -286.950404) (xy 449.085716 -286.957008) (xy 449.103242 -286.96412) (xy 449.19265 -286.96412)
			(xy 449.210176 -286.957008) (xy 449.217288 -286.950404) (xy 449.238615 -286.931134) (xy 449.285978 -286.898569)
			(xy 449.337689 -286.873478) (xy 449.39258 -286.856428) (xy 449.449407 -286.847806) (xy 449.506885 -286.847806)
			(xy 449.563712 -286.856428) (xy 449.618603 -286.873478) (xy 449.670314 -286.898569) (xy 449.717677 -286.931134)
			(xy 449.739004 -286.950404) (xy 449.746116 -286.957008) (xy 449.763642 -286.96412) (xy 449.85305 -286.96412)
			(xy 449.870576 -286.957008) (xy 449.877688 -286.950404) (xy 449.899006 -286.931123) (xy 449.946369 -286.898556)
			(xy 449.998083 -286.873464) (xy 450.052976 -286.856416) (xy 450.109806 -286.847798) (xy 450.138546 -286.84728)
			(xy 450.168668 -286.847876) (xy 450.228164 -286.85735) (xy 450.285432 -286.876054) (xy 450.33905 -286.903525)
			(xy 450.387685 -286.939079) (xy 450.40931 -286.960056) (xy 450.416422 -286.967422) (xy 450.435218 -286.975042)
			(xy 450.527674 -286.975042) (xy 450.54647 -286.967422) (xy 450.553582 -286.960056) (xy 450.575201 -286.939069)
			(xy 450.62383 -286.903499) (xy 450.677448 -286.876019) (xy 450.73472 -286.857313) (xy 450.794221 -286.847846)
			(xy 450.824346 -286.84728) (xy 450.851594 -286.847793) (xy 450.905535 -286.855555) (xy 450.957823 -286.870914)
			(xy 451.007393 -286.893557) (xy 451.053236 -286.923023) (xy 451.094419 -286.958714) (xy 451.130104 -286.999901)
			(xy 451.159565 -287.045748) (xy 451.182203 -287.09532) (xy 451.197555 -287.14761) (xy 451.20531 -287.201552)
			(xy 451.20531 -287.256048) (xy 451.205309 -287.256055) (xy 453.090443 -287.256055) (xy 453.090443 -287.201545)
			(xy 453.098201 -287.147589) (xy 453.113559 -287.095287) (xy 453.136205 -287.045703) (xy 453.165677 -286.999847)
			(xy 453.201376 -286.958652) (xy 453.242574 -286.922957) (xy 453.288433 -286.893489) (xy 453.338019 -286.870847)
			(xy 453.390322 -286.855494) (xy 453.444279 -286.847741) (xy 453.471534 -286.84728) (xy 453.500273 -286.847788)
			(xy 453.557101 -286.856416) (xy 453.611992 -286.873469) (xy 453.663703 -286.898564) (xy 453.711065 -286.931132)
			(xy 453.732392 -286.950404) (xy 453.739504 -286.957008) (xy 453.75703 -286.96412) (xy 453.846438 -286.96412)
			(xy 453.863964 -286.957008) (xy 453.871076 -286.950404) (xy 453.892403 -286.931134) (xy 453.939766 -286.898569)
			(xy 453.991477 -286.873478) (xy 454.046368 -286.856428) (xy 454.103195 -286.847806) (xy 454.160673 -286.847806)
			(xy 454.2175 -286.856428) (xy 454.272391 -286.873478) (xy 454.324102 -286.898569) (xy 454.371465 -286.931134)
			(xy 454.392792 -286.950404) (xy 454.399904 -286.957008) (xy 454.41743 -286.96412) (xy 454.506838 -286.96412)
			(xy 454.524364 -286.957008) (xy 454.531476 -286.950404) (xy 454.552799 -286.931128) (xy 454.600161 -286.89856)
			(xy 454.651873 -286.873468) (xy 454.706766 -286.856419) (xy 454.763595 -286.847799) (xy 454.792334 -286.84728)
			(xy 454.822459 -286.84782) (xy 454.881957 -286.857308) (xy 454.939226 -286.876025) (xy 454.992842 -286.903508)
			(xy 455.041475 -286.939074) (xy 455.063098 -286.960056) (xy 455.07021 -286.967422) (xy 455.089006 -286.975042)
			(xy 455.181462 -286.975042) (xy 455.200258 -286.967422) (xy 455.20737 -286.960056) (xy 455.228994 -286.939075)
			(xy 455.277622 -286.903504) (xy 455.331239 -286.876023) (xy 455.388509 -286.857316) (xy 455.44801 -286.847847)
			(xy 455.478134 -286.84728) (xy 455.505383 -286.847793) (xy 455.559325 -286.855553) (xy 455.611614 -286.87091)
			(xy 455.661185 -286.893553) (xy 455.70703 -286.923019) (xy 455.748215 -286.958709) (xy 455.783901 -286.999897)
			(xy 455.813364 -287.045745) (xy 455.836002 -287.095318) (xy 455.851354 -287.147608) (xy 455.85911 -287.201551)
			(xy 455.85911 -287.256049) (xy 455.851354 -287.309992) (xy 455.836002 -287.362282) (xy 455.813364 -287.411855)
			(xy 455.783901 -287.457703) (xy 455.748215 -287.498891) (xy 455.70703 -287.534581) (xy 455.661185 -287.564047)
			(xy 455.611614 -287.58669) (xy 455.559325 -287.602047) (xy 455.505383 -287.609807) (xy 455.478134 -287.610296)
			(xy 455.448011 -287.609719) (xy 455.388514 -287.600242) (xy 455.331245 -287.581533) (xy 455.277628 -287.554058)
			(xy 455.228994 -287.518499) (xy 455.20737 -287.49752) (xy 455.200258 -287.490154) (xy 455.181462 -287.482534)
			(xy 455.089006 -287.482534) (xy 455.07021 -287.490154) (xy 455.063098 -287.49752) (xy 455.041501 -287.51853)
			(xy 454.992864 -287.554093) (xy 454.939241 -287.581568) (xy 454.881964 -287.600269) (xy 454.82246 -287.609732)
			(xy 454.792334 -287.610296) (xy 454.763594 -287.609813) (xy 454.706764 -287.601181) (xy 454.651873 -287.584121)
			(xy 454.600162 -287.559021) (xy 454.552801 -287.526447) (xy 454.531476 -287.507172) (xy 454.524364 -287.500568)
			(xy 454.506838 -287.493456) (xy 454.41743 -287.493456) (xy 454.399904 -287.500568) (xy 454.392792 -287.507172)
			(xy 454.371465 -287.526442) (xy 454.324102 -287.559007) (xy 454.272391 -287.584098) (xy 454.2175 -287.601148)
			(xy 454.160673 -287.60977) (xy 454.103195 -287.60977) (xy 454.046368 -287.601148) (xy 453.991477 -287.584098)
			(xy 453.939766 -287.559007) (xy 453.892403 -287.526442) (xy 453.871076 -287.507172) (xy 453.863964 -287.500568)
			(xy 453.846438 -287.493456) (xy 453.75703 -287.493456) (xy 453.739504 -287.500568) (xy 453.732392 -287.507172)
			(xy 453.711052 -287.526428) (xy 453.663694 -287.558996) (xy 453.611985 -287.584091) (xy 453.557097 -287.601145)
			(xy 453.500272 -287.609773) (xy 453.471534 -287.610296) (xy 453.444279 -287.609859) (xy 453.390322 -287.602106)
			(xy 453.338019 -287.586753) (xy 453.288433 -287.564111) (xy 453.242574 -287.534643) (xy 453.201376 -287.498948)
			(xy 453.165677 -287.457753) (xy 453.136205 -287.411897) (xy 453.113559 -287.362313) (xy 453.098201 -287.310011)
			(xy 453.090443 -287.256055) (xy 451.205309 -287.256055) (xy 451.197555 -287.30999) (xy 451.182203 -287.36228)
			(xy 451.159565 -287.411852) (xy 451.130104 -287.457699) (xy 451.094419 -287.498886) (xy 451.053236 -287.534577)
			(xy 451.007393 -287.564043) (xy 450.957823 -287.586686) (xy 450.905535 -287.602045) (xy 450.851594 -287.609807)
			(xy 450.824346 -287.610296) (xy 450.794223 -287.609712) (xy 450.734727 -287.600236) (xy 450.677458 -287.581529)
			(xy 450.623841 -287.554056) (xy 450.575207 -287.518499) (xy 450.553582 -287.49752) (xy 450.54647 -287.490154)
			(xy 450.527674 -287.482534) (xy 450.435218 -287.482534) (xy 450.416422 -287.490154) (xy 450.40931 -287.49752)
			(xy 450.387707 -287.518524) (xy 450.339072 -287.554088) (xy 450.28545 -287.581564) (xy 450.228175 -287.600266)
			(xy 450.168672 -287.609731) (xy 450.138546 -287.610296) (xy 450.109806 -287.609806) (xy 450.052977 -287.601175)
			(xy 449.998086 -287.584118) (xy 449.946375 -287.559018) (xy 449.899014 -287.526446) (xy 449.877688 -287.507172)
			(xy 449.870576 -287.500568) (xy 449.85305 -287.493456) (xy 449.763642 -287.493456) (xy 449.746116 -287.500568)
			(xy 449.739004 -287.507172) (xy 449.717677 -287.526442) (xy 449.670314 -287.559007) (xy 449.618603 -287.584098)
			(xy 449.563712 -287.601148) (xy 449.506885 -287.60977) (xy 449.449407 -287.60977) (xy 449.39258 -287.601148)
			(xy 449.337689 -287.584098) (xy 449.285978 -287.559007) (xy 449.238615 -287.526442) (xy 449.217288 -287.507172)
			(xy 449.210176 -287.500568) (xy 449.19265 -287.493456) (xy 449.103242 -287.493456) (xy 449.085716 -287.500568)
			(xy 449.078604 -287.507172) (xy 449.057301 -287.52647) (xy 449.009932 -287.559032) (xy 448.958214 -287.584119)
			(xy 448.903318 -287.601163) (xy 448.846487 -287.609779) (xy 448.817746 -287.610296) (xy 448.79049 -287.60986)
			(xy 448.736532 -287.602108) (xy 448.684227 -287.586756) (xy 448.63464 -287.564115) (xy 448.588779 -287.534647)
			(xy 448.54758 -287.498953) (xy 448.51188 -287.457757) (xy 448.482407 -287.411901) (xy 448.45976 -287.362316)
			(xy 448.444401 -287.310013) (xy 448.436643 -287.256056) (xy 439.705439 -287.256056) (xy 439.724944 -287.261783)
			(xy 439.774521 -287.284425) (xy 439.820371 -287.313891) (xy 439.861562 -287.349582) (xy 439.897253 -287.390773)
			(xy 439.926719 -287.436623) (xy 439.949361 -287.4862) (xy 439.964716 -287.538495) (xy 439.972472 -287.592443)
			(xy 439.972958 -287.619694) (xy 439.972595 -287.645215) (xy 439.965836 -287.695808) (xy 439.959496 -287.720532)
			(xy 439.95594 -287.733486) (xy 439.962036 -287.758886) (xy 440.039252 -287.84169) (xy 440.064144 -287.849564)
			(xy 440.077098 -287.847024) (xy 440.095574 -287.843576) (xy 440.13298 -287.83989) (xy 440.151774 -287.839658)
			(xy 440.17903 -287.840127) (xy 440.232987 -287.847881) (xy 440.285291 -287.863236) (xy 440.334877 -287.885878)
			(xy 440.356312 -287.899652) (xy 457.970079 -287.899652) (xy 457.970079 -287.845148) (xy 457.977837 -287.791198)
			(xy 457.993193 -287.738901) (xy 458.015836 -287.689322) (xy 458.045305 -287.64347) (xy 458.080999 -287.60228)
			(xy 458.122193 -287.566588) (xy 458.168047 -287.537123) (xy 458.217627 -287.514483) (xy 458.269925 -287.499131)
			(xy 458.323876 -287.491377) (xy 458.351128 -287.490916) (xy 458.381252 -287.491479) (xy 458.440748 -287.500963)
			(xy 458.498016 -287.519677) (xy 458.551632 -287.547154) (xy 458.600267 -287.582713) (xy 458.621892 -287.603692)
			(xy 458.629004 -287.611058) (xy 458.6478 -287.618678) (xy 458.740256 -287.618678) (xy 458.759052 -287.611058)
			(xy 458.766164 -287.603692) (xy 458.78778 -287.582702) (xy 458.836412 -287.547136) (xy 458.89003 -287.519658)
			(xy 458.947302 -287.500952) (xy 459.006803 -287.491483) (xy 459.036928 -287.490916) (xy 459.06418 -287.491356)
			(xy 459.118128 -287.499116) (xy 459.170422 -287.514475) (xy 459.219999 -287.537119) (xy 459.265849 -287.566588)
			(xy 459.307038 -287.602281) (xy 459.342729 -287.643473) (xy 459.372195 -287.689325) (xy 459.394835 -287.738904)
			(xy 459.41019 -287.7912) (xy 459.417946 -287.845148) (xy 459.417946 -287.872424) (xy 460.847692 -287.872424)
			(xy 460.851763 -287.816802) (xy 460.863889 -287.762365) (xy 460.883812 -287.710274) (xy 460.911108 -287.661639)
			(xy 460.945194 -287.617496) (xy 460.985343 -287.578787) (xy 461.030701 -287.546336) (xy 461.080301 -287.520835)
			(xy 461.133085 -287.502828) (xy 461.187928 -287.492698) (xy 461.243662 -287.490661) (xy 461.299099 -287.496761)
			(xy 461.353056 -287.510867) (xy 461.404385 -287.532679) (xy 461.451991 -287.561733) (xy 461.494859 -287.597408)
			(xy 461.532076 -287.638945) (xy 461.562849 -287.685458) (xy 461.586521 -287.735955) (xy 461.602589 -287.789362)
			(xy 461.610709 -287.844538) (xy 461.611218 -287.872424) (xy 461.610709 -287.90031) (xy 461.602589 -287.955486)
			(xy 461.586521 -288.008893) (xy 461.562849 -288.05939) (xy 461.532076 -288.105903) (xy 461.494859 -288.14744)
			(xy 461.451991 -288.183115) (xy 461.404385 -288.212169) (xy 461.353056 -288.233981) (xy 461.299099 -288.248087)
			(xy 461.243662 -288.254187) (xy 461.187928 -288.25215) (xy 461.133085 -288.24202) (xy 461.080301 -288.224013)
			(xy 461.030701 -288.198512) (xy 460.985343 -288.166061) (xy 460.945194 -288.127352) (xy 460.911108 -288.083209)
			(xy 460.883812 -288.034574) (xy 460.863889 -287.982483) (xy 460.851763 -287.928046) (xy 460.847692 -287.872424)
			(xy 459.417946 -287.872424) (xy 459.417946 -287.899652) (xy 459.41019 -287.9536) (xy 459.394835 -288.005896)
			(xy 459.372195 -288.055475) (xy 459.342729 -288.101327) (xy 459.307038 -288.142519) (xy 459.265849 -288.178212)
			(xy 459.219999 -288.207681) (xy 459.170422 -288.230325) (xy 459.118128 -288.245684) (xy 459.06418 -288.253444)
			(xy 459.036928 -288.253932) (xy 459.006805 -288.253349) (xy 458.947309 -288.243872) (xy 458.890041 -288.225164)
			(xy 458.836424 -288.197691) (xy 458.787789 -288.162134) (xy 458.766164 -288.141156) (xy 458.759052 -288.13379)
			(xy 458.740256 -288.12617) (xy 458.6478 -288.12617) (xy 458.629004 -288.13379) (xy 458.621892 -288.141156)
			(xy 458.600287 -288.162158) (xy 458.551653 -288.197725) (xy 458.498032 -288.225202) (xy 458.440757 -288.243905)
			(xy 458.381254 -288.253368) (xy 458.351128 -288.253932) (xy 458.323876 -288.253423) (xy 458.269925 -288.245669)
			(xy 458.217627 -288.230317) (xy 458.168047 -288.207677) (xy 458.122193 -288.178212) (xy 458.080999 -288.14252)
			(xy 458.045305 -288.10133) (xy 458.015836 -288.055478) (xy 457.993193 -288.005899) (xy 457.977837 -287.953602)
			(xy 457.970079 -287.899652) (xy 440.356312 -287.899652) (xy 440.380736 -287.915347) (xy 440.421935 -287.951042)
			(xy 440.457634 -287.992238) (xy 440.487106 -288.038095) (xy 440.509753 -288.087679) (xy 440.525112 -288.139982)
			(xy 440.532871 -288.193938) (xy 440.532871 -288.24845) (xy 440.525114 -288.302406) (xy 440.509757 -288.35471)
			(xy 440.487112 -288.404295) (xy 440.457641 -288.450152) (xy 440.421943 -288.491349) (xy 440.380746 -288.527046)
			(xy 440.334888 -288.556516) (xy 440.285302 -288.57916) (xy 440.232998 -288.594516) (xy 440.179042 -288.602272)
			(xy 440.12453 -288.60227) (xy 440.070574 -288.59451) (xy 440.018272 -288.57915) (xy 439.968688 -288.556503)
			(xy 439.922831 -288.527029) (xy 439.881637 -288.491329) (xy 439.845942 -288.45013) (xy 439.816474 -288.40427)
			(xy 439.793833 -288.354683) (xy 439.77848 -288.302379) (xy 439.770727 -288.248422) (xy 439.770266 -288.221166)
			(xy 439.77064 -288.195645) (xy 439.777392 -288.145053) (xy 439.783728 -288.120328) (xy 439.787284 -288.107374)
			(xy 439.781188 -288.081974) (xy 439.703972 -287.99917) (xy 439.67908 -287.991296) (xy 439.666126 -287.993836)
			(xy 439.656292 -287.99575) (xy 439.63647 -287.998672) (xy 439.626502 -287.999678) (xy 439.615326 -288.000694)
			(xy 439.596276 -288.011616) (xy 439.538618 -288.093404) (xy 439.534808 -288.115248) (xy 439.537602 -288.12617)
			(xy 439.543182 -288.149522) (xy 439.549175 -288.197159) (xy 439.54954 -288.221166) (xy 439.549054 -288.248417)
			(xy 439.541298 -288.302365) (xy 439.525943 -288.35466) (xy 439.503301 -288.404237) (xy 439.473835 -288.450087)
			(xy 439.438144 -288.491278) (xy 439.396953 -288.526969) (xy 439.351103 -288.556435) (xy 439.301526 -288.579077)
			(xy 439.249231 -288.594432) (xy 439.195283 -288.602188) (xy 439.140781 -288.602188) (xy 439.086833 -288.594432)
			(xy 439.034538 -288.579077) (xy 438.984961 -288.556435) (xy 438.939111 -288.526969) (xy 438.89792 -288.491278)
			(xy 438.862229 -288.450087) (xy 438.832763 -288.404237) (xy 438.810121 -288.35466) (xy 438.794766 -288.302365)
			(xy 438.78701 -288.248417) (xy 438.786524 -288.221166) (xy 438.786952 -288.194722) (xy 438.794217 -288.142335)
			(xy 438.801002 -288.116772) (xy 438.804558 -288.104326) (xy 438.799224 -288.079942) (xy 438.728104 -287.995868)
			(xy 438.704736 -287.986724) (xy 438.691782 -287.987994) (xy 438.681025 -287.989162) (xy 438.659422 -287.990435)
			(xy 438.648602 -287.990534) (xy 438.628536 -287.990026) (xy 438.616598 -287.989264) (xy 438.595008 -287.998662)
			(xy 438.52719 -288.07918) (xy 438.521602 -288.10204) (xy 438.524142 -288.113724) (xy 438.528534 -288.1344)
			(xy 438.533243 -288.176408) (xy 438.53354 -288.197544) (xy 438.532975 -288.224792) (xy 438.525213 -288.278732)
			(xy 438.509854 -288.331019) (xy 438.48721 -288.380587) (xy 438.457742 -288.426429) (xy 438.42205 -288.46761)
			(xy 438.380861 -288.503293) (xy 438.335013 -288.53275) (xy 438.28544 -288.555383) (xy 438.23315 -288.570731)
			(xy 438.179208 -288.578481) (xy 438.124712 -288.578475) (xy 438.070772 -288.570714) (xy 438.018485 -288.555355)
			(xy 437.968916 -288.532712) (xy 437.923075 -288.503245) (xy 437.881893 -288.467553) (xy 437.84621 -288.426365)
			(xy 437.816752 -288.380517) (xy 437.794118 -288.330944) (xy 437.77877 -288.278654) (xy 437.77102 -288.224712)
			(xy 437.516988 -288.224712) (xy 437.516988 -288.248447) (xy 437.509233 -288.302387) (xy 437.493881 -288.354675)
			(xy 437.471244 -288.404245) (xy 437.441783 -288.45009) (xy 437.406099 -288.491276) (xy 437.364916 -288.526964)
			(xy 437.319074 -288.556429) (xy 437.269505 -288.57907) (xy 437.217219 -288.594426) (xy 437.163279 -288.602186)
			(xy 437.136032 -288.602674) (xy 437.109915 -288.602229) (xy 437.05817 -288.595095) (xy 437.007882 -288.580969)
			(xy 436.959991 -288.560115) (xy 436.915392 -288.532923) (xy 436.87492 -288.499901) (xy 436.83933 -288.461668)
			(xy 436.809288 -288.418937) (xy 436.796942 -288.395918) (xy 436.790175 -288.383704) (xy 436.771172 -288.363258)
			(xy 436.747346 -288.348716) (xy 436.720475 -288.341164) (xy 436.692561 -288.341164) (xy 436.66569 -288.348716)
			(xy 436.641864 -288.363258) (xy 436.622861 -288.383704) (xy 436.616094 -288.395918) (xy 436.603721 -288.418923)
			(xy 436.573692 -288.461665) (xy 436.538111 -288.499908) (xy 436.497644 -288.532937) (xy 436.453048 -288.560134)
			(xy 436.405157 -288.58099) (xy 436.354868 -288.595115) (xy 436.303122 -288.602245) (xy 436.277004 -288.602674)
			(xy 436.249749 -288.602279) (xy 436.195792 -288.594522) (xy 436.143489 -288.579165) (xy 436.093904 -288.556521)
			(xy 436.048046 -288.52705) (xy 436.00685 -288.491353) (xy 435.971152 -288.450157) (xy 435.941681 -288.404299)
			(xy 435.919036 -288.354715) (xy 435.903679 -288.302412) (xy 435.895921 -288.248455) (xy 431.050379 -288.248455)
			(xy 431.05475 -288.274651) (xy 431.055272 -288.299906) (xy 431.055097 -288.314089) (xy 431.052424 -288.342329)
			(xy 431.049938 -288.356294) (xy 431.047652 -288.36874) (xy 431.055018 -288.392362) (xy 431.132488 -288.469832)
			(xy 431.15611 -288.477198) (xy 431.168556 -288.474912) (xy 431.182521 -288.472432) (xy 431.210761 -288.469763)
			(xy 431.224944 -288.469578) (xy 431.247727 -288.469994) (xy 431.292784 -288.476778) (xy 431.336336 -288.490174)
			(xy 431.377417 -288.509885) (xy 431.415118 -288.535475) (xy 431.448604 -288.566377) (xy 431.463196 -288.583878)
			(xy 431.470763 -288.592476) (xy 431.491379 -288.6024) (xy 431.50282 -288.602928) (xy 431.582068 -288.602928)
			(xy 431.593481 -288.602268) (xy 431.614058 -288.592386) (xy 431.621692 -288.583878) (xy 431.636289 -288.566379)
			(xy 431.669762 -288.535462) (xy 431.707459 -288.509862) (xy 431.748542 -288.49015) (xy 431.792098 -288.476762)
			(xy 431.83716 -288.469997) (xy 431.859944 -288.469578) (xy 431.885196 -288.470131) (xy 431.93501 -288.47845)
			(xy 431.982775 -288.494854) (xy 432.027189 -288.518895) (xy 432.067041 -288.549919) (xy 432.101244 -288.587078)
			(xy 432.128865 -288.629359) (xy 432.14915 -288.67561) (xy 432.161547 -288.724569) (xy 432.165717 -288.7749)
			(xy 432.161547 -288.825231) (xy 432.14915 -288.87419) (xy 432.128865 -288.920441) (xy 432.101244 -288.962722)
			(xy 432.067041 -288.999881) (xy 432.027189 -289.030905) (xy 431.982775 -289.054946) (xy 431.93501 -289.07135)
			(xy 431.885196 -289.079669) (xy 431.859944 -289.080194) (xy 431.837161 -289.079797) (xy 431.792102 -289.07301)
			(xy 431.748549 -289.059612) (xy 431.707468 -289.039897) (xy 431.669767 -289.014303) (xy 431.636283 -288.983397)
			(xy 431.621692 -288.965894) (xy 431.614135 -288.957286) (xy 431.593511 -288.947368) (xy 431.582068 -288.946844)
			(xy 431.50282 -288.946844) (xy 431.491408 -288.947506) (xy 431.470831 -288.957388) (xy 431.463196 -288.965894)
			(xy 431.448623 -288.983414) (xy 431.415143 -289.014326) (xy 431.37744 -289.039921) (xy 431.336353 -289.059629)
			(xy 431.292793 -289.073013) (xy 431.247729 -289.079776) (xy 431.224944 -289.080194) (xy 431.200951 -289.079721)
			(xy 431.153556 -289.072221) (xy 431.107918 -289.057397) (xy 431.065161 -289.035616) (xy 431.026338 -289.007414)
			(xy 430.992406 -288.973485) (xy 430.9642 -288.934665) (xy 430.942414 -288.89191) (xy 430.927586 -288.846273)
			(xy 430.920081 -288.798879) (xy 430.919636 -288.774886) (xy 430.91981 -288.760703) (xy 430.922484 -288.732463)
			(xy 430.92497 -288.718498) (xy 430.927256 -288.706052) (xy 430.91989 -288.68243) (xy 430.84242 -288.60496)
			(xy 430.818798 -288.597594) (xy 430.806352 -288.59988) (xy 430.792387 -288.602359) (xy 430.764147 -288.605029)
			(xy 430.749964 -288.605214) (xy 430.735781 -288.605042) (xy 430.707541 -288.602367) (xy 430.693576 -288.59988)
			(xy 430.68113 -288.597594) (xy 430.657508 -288.60496) (xy 430.580038 -288.68243) (xy 430.572672 -288.706052)
			(xy 430.574958 -288.718498) (xy 430.57743 -288.732465) (xy 430.580105 -288.760704) (xy 430.580292 -288.774886)
			(xy 430.57977 -288.800141) (xy 430.571457 -288.849963) (xy 430.555056 -288.897737) (xy 430.531015 -288.94216)
			(xy 430.499991 -288.98202) (xy 430.462829 -289.01623) (xy 430.420543 -289.043856) (xy 430.374287 -289.064146)
			(xy 430.325322 -289.076546) (xy 430.274984 -289.080717) (xy 430.224646 -289.076546) (xy 430.175681 -289.064146)
			(xy 430.129425 -289.043856) (xy 430.087139 -289.01623) (xy 430.049977 -288.98202) (xy 430.018953 -288.94216)
			(xy 429.994912 -288.897737) (xy 429.978511 -288.849963) (xy 429.970198 -288.800141) (xy 429.969676 -288.774886)
			(xy 429.969851 -288.760703) (xy 429.972524 -288.732463) (xy 429.97501 -288.718498) (xy 429.977296 -288.706052)
			(xy 429.96993 -288.68243) (xy 429.89246 -288.60496) (xy 429.868838 -288.597594) (xy 429.856392 -288.59988)
			(xy 429.842426 -288.602353) (xy 429.814186 -288.605027) (xy 429.800004 -288.605214) (xy 429.785821 -288.605037)
			(xy 429.757581 -288.602365) (xy 429.743616 -288.59988) (xy 429.73117 -288.597594) (xy 429.707548 -288.60496)
			(xy 429.630078 -288.68243) (xy 429.622712 -288.706052) (xy 429.624998 -288.718498) (xy 429.62747 -288.732465)
			(xy 429.630145 -288.760704) (xy 429.630332 -288.774886) (xy 429.62981 -288.800141) (xy 429.621497 -288.849963)
			(xy 429.605096 -288.897737) (xy 429.581055 -288.94216) (xy 429.550031 -288.98202) (xy 429.512869 -289.01623)
			(xy 429.470583 -289.043856) (xy 429.424327 -289.064146) (xy 429.375362 -289.076546) (xy 429.325024 -289.080717)
			(xy 429.274686 -289.076546) (xy 429.225721 -289.064146) (xy 429.179465 -289.043856) (xy 429.137179 -289.01623)
			(xy 429.100017 -288.98202) (xy 429.068993 -288.94216) (xy 429.044952 -288.897737) (xy 429.028551 -288.849963)
			(xy 429.020238 -288.800141) (xy 429.019716 -288.774886) (xy 429.019787 -288.765015) (xy 429.021059 -288.745314)
			(xy 429.022256 -288.735516) (xy 429.02378 -288.723578) (xy 429.015906 -288.700718) (xy 428.939452 -288.627312)
			(xy 428.916592 -288.6202) (xy 428.9044 -288.622232) (xy 428.890851 -288.62439) (xy 428.863509 -288.626677)
			(xy 428.84979 -288.626804) (xy 428.836072 -288.626658) (xy 428.808731 -288.62437) (xy 428.79518 -288.622232)
			(xy 428.783242 -288.620454) (xy 428.760382 -288.627312) (xy 428.683928 -288.700972) (xy 428.676054 -288.723578)
			(xy 428.677578 -288.735516) (xy 428.678763 -288.745316) (xy 428.680036 -288.765015) (xy 428.680118 -288.774886)
			(xy 428.679596 -288.800141) (xy 428.671283 -288.849963) (xy 428.654882 -288.897737) (xy 428.630841 -288.94216)
			(xy 428.599817 -288.98202) (xy 428.562655 -289.01623) (xy 428.520369 -289.043856) (xy 428.474113 -289.064146)
			(xy 428.425148 -289.076546) (xy 428.37481 -289.080717) (xy 428.324472 -289.076546) (xy 428.275507 -289.064146)
			(xy 428.229251 -289.043856) (xy 428.186965 -289.01623) (xy 428.149803 -288.98202) (xy 428.118779 -288.94216)
			(xy 428.094738 -288.897737) (xy 428.078337 -288.849963) (xy 428.070024 -288.800141) (xy 428.069502 -288.774886)
			(xy 428.069573 -288.765015) (xy 428.070845 -288.745314) (xy 428.072042 -288.735516) (xy 428.073566 -288.723578)
			(xy 428.065692 -288.700972) (xy 427.989238 -288.627312) (xy 427.966378 -288.620454) (xy 427.95444 -288.622232)
			(xy 427.940891 -288.624385) (xy 427.913549 -288.626675) (xy 427.89983 -288.626804) (xy 427.886112 -288.626653)
			(xy 427.858771 -288.624368) (xy 427.84522 -288.622232) (xy 427.833282 -288.620454) (xy 427.810422 -288.627312)
			(xy 427.733968 -288.700972) (xy 427.726094 -288.723578) (xy 427.727618 -288.735516) (xy 427.728803 -288.745316)
			(xy 427.730076 -288.765015) (xy 427.730158 -288.774886) (xy 427.729636 -288.800141) (xy 427.721323 -288.849963)
			(xy 427.704922 -288.897737) (xy 427.680881 -288.94216) (xy 427.649857 -288.98202) (xy 427.612695 -289.01623)
			(xy 427.570409 -289.043856) (xy 427.524153 -289.064146) (xy 427.475188 -289.076546) (xy 427.42485 -289.080717)
			(xy 427.374512 -289.076546) (xy 427.325547 -289.064146) (xy 427.279291 -289.043856) (xy 427.237005 -289.01623)
			(xy 427.199843 -288.98202) (xy 427.168819 -288.94216) (xy 427.144778 -288.897737) (xy 427.128377 -288.849963)
			(xy 427.120064 -288.800141) (xy 427.119542 -288.774886) (xy 427.119716 -288.760703) (xy 427.12239 -288.732463)
			(xy 427.124876 -288.718498) (xy 427.127162 -288.706052) (xy 427.119796 -288.68243) (xy 427.042326 -288.60496)
			(xy 427.018704 -288.597594) (xy 427.006258 -288.59988) (xy 426.992292 -288.602358) (xy 426.964053 -288.605029)
			(xy 426.94987 -288.605214) (xy 426.925052 -288.60469) (xy 426.876071 -288.596655) (xy 426.829034 -288.580802)
			(xy 426.785183 -288.557548) (xy 426.74567 -288.527506) (xy 426.711539 -288.491468) (xy 426.683687 -288.450382)
			(xy 426.662849 -288.405332) (xy 426.649573 -288.357504) (xy 426.644211 -288.308159) (xy 426.3269 -288.308159)
			(xy 426.326558 -288.325614) (xy 426.318515 -288.376396) (xy 426.302627 -288.425295) (xy 426.279284 -288.471107)
			(xy 426.249063 -288.512703) (xy 426.212707 -288.549059) (xy 426.171111 -288.57928) (xy 426.125299 -288.602623)
			(xy 426.0764 -288.618511) (xy 426.025618 -288.626554) (xy 425.974202 -288.626554) (xy 425.92342 -288.618511)
			(xy 425.874521 -288.602623) (xy 425.828709 -288.57928) (xy 425.787113 -288.549059) (xy 425.750757 -288.512703)
			(xy 425.720536 -288.471107) (xy 425.697193 -288.425295) (xy 425.681305 -288.376396) (xy 425.673262 -288.325614)
			(xy 425.376424 -288.325614) (xy 425.376424 -288.325623) (xy 425.36838 -288.376372) (xy 425.352497 -288.425237)
			(xy 425.329165 -288.471017) (xy 425.298958 -288.512583) (xy 425.262621 -288.548911) (xy 425.221047 -288.579107)
			(xy 425.175262 -288.602428) (xy 425.126392 -288.618299) (xy 425.075641 -288.62633) (xy 425.04995 -288.626804)
			(xy 425.036232 -288.626663) (xy 425.008891 -288.624371) (xy 424.99534 -288.622232) (xy 424.983402 -288.620454)
			(xy 424.960542 -288.627312) (xy 424.884088 -288.700972) (xy 424.876214 -288.723578) (xy 424.877738 -288.735516)
			(xy 424.878923 -288.745316) (xy 424.880196 -288.765015) (xy 424.880278 -288.774886) (xy 424.879756 -288.800141)
			(xy 424.871443 -288.849963) (xy 424.855042 -288.897737) (xy 424.831001 -288.94216) (xy 424.799977 -288.98202)
			(xy 424.762815 -289.01623) (xy 424.720529 -289.043856) (xy 424.674273 -289.064146) (xy 424.625308 -289.076546)
			(xy 424.57497 -289.080717) (xy 424.524632 -289.076546) (xy 424.475667 -289.064146) (xy 424.429411 -289.043856)
			(xy 424.387125 -289.01623) (xy 424.349963 -288.98202) (xy 424.318939 -288.94216) (xy 424.294898 -288.897737)
			(xy 424.278497 -288.849963) (xy 424.270184 -288.800141) (xy 424.269662 -288.774886) (xy 424.269837 -288.760703)
			(xy 424.27251 -288.732463) (xy 424.274996 -288.718498) (xy 424.277282 -288.706052) (xy 424.269916 -288.68243)
			(xy 424.192446 -288.60496) (xy 424.168824 -288.597594) (xy 424.156378 -288.59988) (xy 424.142412 -288.602355)
			(xy 424.114172 -288.605028) (xy 424.09999 -288.605214) (xy 424.07517 -288.604711) (xy 424.026184 -288.596679)
			(xy 423.979143 -288.580827) (xy 423.935287 -288.557574) (xy 423.895769 -288.527532) (xy 423.861633 -288.491493)
			(xy 423.833777 -288.450405) (xy 423.812935 -288.405353) (xy 423.799657 -288.357522) (xy 423.794291 -288.308173)
			(xy 423.455172 -288.308173) (xy 423.454843 -288.324513) (xy 423.446948 -288.37309) (xy 423.431364 -288.419771)
			(xy 423.408493 -288.463348) (xy 423.378928 -288.502692) (xy 423.343435 -288.536784) (xy 423.302932 -288.56474)
			(xy 423.25847 -288.585838) (xy 423.211199 -288.59953) (xy 423.162344 -288.605462) (xy 423.113169 -288.603481)
			(xy 423.06495 -288.593637) (xy 423.018934 -288.576185) (xy 422.976313 -288.551578) (xy 422.938192 -288.520453)
			(xy 422.905557 -288.483616) (xy 422.879254 -288.44202) (xy 422.859963 -288.396744) (xy 422.848186 -288.34896)
			(xy 422.844226 -288.299906) (xy 422.505124 -288.299906) (xy 422.504629 -288.324513) (xy 422.496734 -288.37309)
			(xy 422.48115 -288.419771) (xy 422.458279 -288.463348) (xy 422.428714 -288.502692) (xy 422.393221 -288.536784)
			(xy 422.352718 -288.56474) (xy 422.308256 -288.585838) (xy 422.260985 -288.59953) (xy 422.21213 -288.605462)
			(xy 422.162955 -288.603481) (xy 422.114736 -288.593637) (xy 422.06872 -288.576185) (xy 422.026099 -288.551578)
			(xy 421.987978 -288.520453) (xy 421.955343 -288.483616) (xy 421.92904 -288.44202) (xy 421.909749 -288.396744)
			(xy 421.897972 -288.34896) (xy 421.894012 -288.299906) (xy 396.990824 -288.299906) (xy 396.990824 -288.373312)
			(xy 396.990998 -288.379464) (xy 396.993961 -288.391406) (xy 396.996666 -288.396934) (xy 397.004794 -288.40811)
			(xy 397.019526 -288.423604) (xy 397.02613 -288.430716) (xy 397.05026 -288.441892) (xy 397.054578 -288.443162)
			(xy 397.066008 -288.446718) (xy 397.070072 -288.447226) (xy 397.096118 -288.451334) (xy 397.146546 -288.466729)
			(xy 397.193893 -288.489929) (xy 397.23696 -288.520346) (xy 397.274657 -288.557211) (xy 397.306028 -288.599588)
			(xy 397.330279 -288.646406) (xy 397.346796 -288.696477) (xy 397.35516 -288.748535) (xy 397.35516 -288.774886)
			(xy 397.669016 -288.774886) (xy 397.672976 -288.725832) (xy 397.684753 -288.678048) (xy 397.704044 -288.632772)
			(xy 397.730347 -288.591176) (xy 397.762982 -288.554339) (xy 397.801103 -288.523214) (xy 397.843724 -288.498607)
			(xy 397.88974 -288.481155) (xy 397.937959 -288.471311) (xy 397.987134 -288.46933) (xy 398.035989 -288.475262)
			(xy 398.08326 -288.488954) (xy 398.127722 -288.510052) (xy 398.168225 -288.538008) (xy 398.203718 -288.5721)
			(xy 398.233283 -288.611444) (xy 398.256154 -288.655021) (xy 398.271738 -288.701702) (xy 398.279633 -288.750279)
			(xy 398.280128 -288.774886) (xy 416.668978 -288.774886) (xy 416.672938 -288.725832) (xy 416.684715 -288.678048)
			(xy 416.704006 -288.632772) (xy 416.730309 -288.591176) (xy 416.762944 -288.554339) (xy 416.801065 -288.523214)
			(xy 416.843686 -288.498607) (xy 416.889702 -288.481155) (xy 416.937921 -288.471311) (xy 416.987096 -288.46933)
			(xy 417.035951 -288.475262) (xy 417.083222 -288.488954) (xy 417.127684 -288.510052) (xy 417.168187 -288.538008)
			(xy 417.20368 -288.5721) (xy 417.233245 -288.611444) (xy 417.256116 -288.655021) (xy 417.2717 -288.701702)
			(xy 417.279595 -288.750279) (xy 417.28009 -288.774886) (xy 417.619192 -288.774886) (xy 417.623152 -288.725832)
			(xy 417.634929 -288.678048) (xy 417.65422 -288.632772) (xy 417.680523 -288.591176) (xy 417.713158 -288.554339)
			(xy 417.751279 -288.523214) (xy 417.7939 -288.498607) (xy 417.839916 -288.481155) (xy 417.888135 -288.471311)
			(xy 417.93731 -288.46933) (xy 417.986165 -288.475262) (xy 418.033436 -288.488954) (xy 418.077898 -288.510052)
			(xy 418.118401 -288.538008) (xy 418.153894 -288.5721) (xy 418.183459 -288.611444) (xy 418.20633 -288.655021)
			(xy 418.221914 -288.701702) (xy 418.229809 -288.750279) (xy 418.230304 -288.774886) (xy 418.569152 -288.774886)
			(xy 418.573112 -288.725832) (xy 418.584889 -288.678048) (xy 418.60418 -288.632772) (xy 418.630483 -288.591176)
			(xy 418.663118 -288.554339) (xy 418.701239 -288.523214) (xy 418.74386 -288.498607) (xy 418.789876 -288.481155)
			(xy 418.838095 -288.471311) (xy 418.88727 -288.46933) (xy 418.936125 -288.475262) (xy 418.983396 -288.488954)
			(xy 419.027858 -288.510052) (xy 419.068361 -288.538008) (xy 419.103854 -288.5721) (xy 419.133419 -288.611444)
			(xy 419.15629 -288.655021) (xy 419.171874 -288.701702) (xy 419.179769 -288.750279) (xy 419.180264 -288.774886)
			(xy 419.519112 -288.774886) (xy 419.523072 -288.725832) (xy 419.534849 -288.678048) (xy 419.55414 -288.632772)
			(xy 419.580443 -288.591176) (xy 419.613078 -288.554339) (xy 419.651199 -288.523214) (xy 419.69382 -288.498607)
			(xy 419.739836 -288.481155) (xy 419.788055 -288.471311) (xy 419.83723 -288.46933) (xy 419.886085 -288.475262)
			(xy 419.933356 -288.488954) (xy 419.977818 -288.510052) (xy 420.018321 -288.538008) (xy 420.053814 -288.5721)
			(xy 420.083379 -288.611444) (xy 420.10625 -288.655021) (xy 420.121834 -288.701702) (xy 420.129729 -288.750279)
			(xy 420.130224 -288.774886) (xy 420.469072 -288.774886) (xy 420.473032 -288.725832) (xy 420.484809 -288.678048)
			(xy 420.5041 -288.632772) (xy 420.530403 -288.591176) (xy 420.563038 -288.554339) (xy 420.601159 -288.523214)
			(xy 420.64378 -288.498607) (xy 420.689796 -288.481155) (xy 420.738015 -288.471311) (xy 420.78719 -288.46933)
			(xy 420.836045 -288.475262) (xy 420.883316 -288.488954) (xy 420.927778 -288.510052) (xy 420.968281 -288.538008)
			(xy 421.003774 -288.5721) (xy 421.033339 -288.611444) (xy 421.05621 -288.655021) (xy 421.071794 -288.701702)
			(xy 421.079689 -288.750279) (xy 421.080184 -288.774886) (xy 421.079689 -288.799493) (xy 421.071794 -288.84807)
			(xy 421.05621 -288.894751) (xy 421.033339 -288.938328) (xy 421.003774 -288.977672) (xy 420.968281 -289.011764)
			(xy 420.927778 -289.03972) (xy 420.883316 -289.060818) (xy 420.836045 -289.07451) (xy 420.78719 -289.080442)
			(xy 420.738015 -289.078461) (xy 420.689796 -289.068617) (xy 420.64378 -289.051165) (xy 420.601159 -289.026558)
			(xy 420.563038 -288.995433) (xy 420.530403 -288.958596) (xy 420.5041 -288.917) (xy 420.484809 -288.871724)
			(xy 420.473032 -288.82394) (xy 420.469072 -288.774886) (xy 420.130224 -288.774886) (xy 420.129729 -288.799493)
			(xy 420.121834 -288.84807) (xy 420.10625 -288.894751) (xy 420.083379 -288.938328) (xy 420.053814 -288.977672)
			(xy 420.018321 -289.011764) (xy 419.977818 -289.03972) (xy 419.933356 -289.060818) (xy 419.886085 -289.07451)
			(xy 419.83723 -289.080442) (xy 419.788055 -289.078461) (xy 419.739836 -289.068617) (xy 419.69382 -289.051165)
			(xy 419.651199 -289.026558) (xy 419.613078 -288.995433) (xy 419.580443 -288.958596) (xy 419.55414 -288.917)
			(xy 419.534849 -288.871724) (xy 419.523072 -288.82394) (xy 419.519112 -288.774886) (xy 419.180264 -288.774886)
			(xy 419.179769 -288.799493) (xy 419.171874 -288.84807) (xy 419.15629 -288.894751) (xy 419.133419 -288.938328)
			(xy 419.103854 -288.977672) (xy 419.068361 -289.011764) (xy 419.027858 -289.03972) (xy 418.983396 -289.060818)
			(xy 418.936125 -289.07451) (xy 418.88727 -289.080442) (xy 418.838095 -289.078461) (xy 418.789876 -289.068617)
			(xy 418.74386 -289.051165) (xy 418.701239 -289.026558) (xy 418.663118 -288.995433) (xy 418.630483 -288.958596)
			(xy 418.60418 -288.917) (xy 418.584889 -288.871724) (xy 418.573112 -288.82394) (xy 418.569152 -288.774886)
			(xy 418.230304 -288.774886) (xy 418.229809 -288.799493) (xy 418.221914 -288.84807) (xy 418.20633 -288.894751)
			(xy 418.183459 -288.938328) (xy 418.153894 -288.977672) (xy 418.118401 -289.011764) (xy 418.077898 -289.03972)
			(xy 418.033436 -289.060818) (xy 417.986165 -289.07451) (xy 417.93731 -289.080442) (xy 417.888135 -289.078461)
			(xy 417.839916 -289.068617) (xy 417.7939 -289.051165) (xy 417.751279 -289.026558) (xy 417.713158 -288.995433)
			(xy 417.680523 -288.958596) (xy 417.65422 -288.917) (xy 417.634929 -288.871724) (xy 417.623152 -288.82394)
			(xy 417.619192 -288.774886) (xy 417.28009 -288.774886) (xy 417.279595 -288.799493) (xy 417.2717 -288.84807)
			(xy 417.256116 -288.894751) (xy 417.233245 -288.938328) (xy 417.20368 -288.977672) (xy 417.168187 -289.011764)
			(xy 417.127684 -289.03972) (xy 417.083222 -289.060818) (xy 417.035951 -289.07451) (xy 416.987096 -289.080442)
			(xy 416.937921 -289.078461) (xy 416.889702 -289.068617) (xy 416.843686 -289.051165) (xy 416.801065 -289.026558)
			(xy 416.762944 -288.995433) (xy 416.730309 -288.958596) (xy 416.704006 -288.917) (xy 416.684715 -288.871724)
			(xy 416.672938 -288.82394) (xy 416.668978 -288.774886) (xy 398.280128 -288.774886) (xy 398.279633 -288.799493)
			(xy 398.271738 -288.84807) (xy 398.256154 -288.894751) (xy 398.233283 -288.938328) (xy 398.203718 -288.977672)
			(xy 398.168225 -289.011764) (xy 398.127722 -289.03972) (xy 398.08326 -289.060818) (xy 398.035989 -289.07451)
			(xy 397.987134 -289.080442) (xy 397.937959 -289.078461) (xy 397.88974 -289.068617) (xy 397.843724 -289.051165)
			(xy 397.801103 -289.026558) (xy 397.762982 -288.995433) (xy 397.730347 -288.958596) (xy 397.704044 -288.917)
			(xy 397.684753 -288.871724) (xy 397.672976 -288.82394) (xy 397.669016 -288.774886) (xy 397.35516 -288.774886)
			(xy 397.355161 -288.801261) (xy 397.346797 -288.853319) (xy 397.33028 -288.903391) (xy 397.30603 -288.950209)
			(xy 397.274659 -288.992586) (xy 397.236963 -289.029451) (xy 397.193896 -289.059869) (xy 397.146549 -289.083069)
			(xy 397.096122 -289.098465) (xy 397.070072 -289.102546) (xy 397.066008 -289.103054) (xy 397.054578 -289.10661)
			(xy 397.05026 -289.10788) (xy 397.02613 -289.119056) (xy 397.019526 -289.126168) (xy 397.004794 -289.141662)
			(xy 396.996666 -289.152838) (xy 396.993967 -289.158369) (xy 396.991004 -289.170309) (xy 396.990824 -289.17646)
			(xy 396.990824 -289.323272) (xy 396.990994 -289.329425) (xy 396.993948 -289.341371) (xy 396.996666 -289.346894)
			(xy 397.004794 -289.35807) (xy 397.019526 -289.373564) (xy 397.02613 -289.380676) (xy 397.05026 -289.391852)
			(xy 397.054578 -289.393122) (xy 397.066008 -289.396678) (xy 397.070072 -289.397186) (xy 397.096113 -289.401294)
			(xy 397.146532 -289.416687) (xy 397.19387 -289.439885) (xy 397.236928 -289.470297) (xy 397.274617 -289.507156)
			(xy 397.305981 -289.549527) (xy 397.330227 -289.596336) (xy 397.34674 -289.646399) (xy 397.355102 -289.698448)
			(xy 397.355101 -289.724846) (xy 397.669016 -289.724846) (xy 397.672976 -289.675792) (xy 397.684753 -289.628008)
			(xy 397.704044 -289.582732) (xy 397.730347 -289.541136) (xy 397.762982 -289.504299) (xy 397.801103 -289.473174)
			(xy 397.843724 -289.448567) (xy 397.88974 -289.431115) (xy 397.937959 -289.421271) (xy 397.987134 -289.41929)
			(xy 398.035989 -289.425222) (xy 398.08326 -289.438914) (xy 398.127722 -289.460012) (xy 398.168225 -289.487968)
			(xy 398.203718 -289.52206) (xy 398.233283 -289.561404) (xy 398.256154 -289.604981) (xy 398.271738 -289.651662)
			(xy 398.279633 -289.700239) (xy 398.280128 -289.724846) (xy 398.61923 -289.724846) (xy 398.62319 -289.675792)
			(xy 398.634967 -289.628008) (xy 398.654258 -289.582732) (xy 398.680561 -289.541136) (xy 398.713196 -289.504299)
			(xy 398.751317 -289.473174) (xy 398.793938 -289.448567) (xy 398.839954 -289.431115) (xy 398.888173 -289.421271)
			(xy 398.937348 -289.41929) (xy 398.986203 -289.425222) (xy 399.033474 -289.438914) (xy 399.077936 -289.460012)
			(xy 399.118439 -289.487968) (xy 399.153932 -289.52206) (xy 399.183497 -289.561404) (xy 399.206368 -289.604981)
			(xy 399.221952 -289.651662) (xy 399.229847 -289.700239) (xy 399.230342 -289.724846) (xy 399.56919 -289.724846)
			(xy 399.57315 -289.675792) (xy 399.584927 -289.628008) (xy 399.604218 -289.582732) (xy 399.630521 -289.541136)
			(xy 399.663156 -289.504299) (xy 399.701277 -289.473174) (xy 399.743898 -289.448567) (xy 399.789914 -289.431115)
			(xy 399.838133 -289.421271) (xy 399.887308 -289.41929) (xy 399.936163 -289.425222) (xy 399.983434 -289.438914)
			(xy 400.027896 -289.460012) (xy 400.068399 -289.487968) (xy 400.103892 -289.52206) (xy 400.133457 -289.561404)
			(xy 400.156328 -289.604981) (xy 400.171912 -289.651662) (xy 400.179807 -289.700239) (xy 400.180302 -289.724846)
			(xy 400.51915 -289.724846) (xy 400.52311 -289.675792) (xy 400.534887 -289.628008) (xy 400.554178 -289.582732)
			(xy 400.580481 -289.541136) (xy 400.613116 -289.504299) (xy 400.651237 -289.473174) (xy 400.693858 -289.448567)
			(xy 400.739874 -289.431115) (xy 400.788093 -289.421271) (xy 400.837268 -289.41929) (xy 400.886123 -289.425222)
			(xy 400.933394 -289.438914) (xy 400.977856 -289.460012) (xy 401.018359 -289.487968) (xy 401.053852 -289.52206)
			(xy 401.083417 -289.561404) (xy 401.106288 -289.604981) (xy 401.121872 -289.651662) (xy 401.129767 -289.700239)
			(xy 401.130262 -289.724846) (xy 401.46911 -289.724846) (xy 401.47307 -289.675792) (xy 401.484847 -289.628008)
			(xy 401.504138 -289.582732) (xy 401.530441 -289.541136) (xy 401.563076 -289.504299) (xy 401.601197 -289.473174)
			(xy 401.643818 -289.448567) (xy 401.689834 -289.431115) (xy 401.738053 -289.421271) (xy 401.787228 -289.41929)
			(xy 401.836083 -289.425222) (xy 401.883354 -289.438914) (xy 401.927816 -289.460012) (xy 401.968319 -289.487968)
			(xy 402.003812 -289.52206) (xy 402.033377 -289.561404) (xy 402.056248 -289.604981) (xy 402.071832 -289.651662)
			(xy 402.079727 -289.700239) (xy 402.080222 -289.724846) (xy 402.41907 -289.724846) (xy 402.42303 -289.675792)
			(xy 402.434807 -289.628008) (xy 402.454098 -289.582732) (xy 402.480401 -289.541136) (xy 402.513036 -289.504299)
			(xy 402.551157 -289.473174) (xy 402.593778 -289.448567) (xy 402.639794 -289.431115) (xy 402.688013 -289.421271)
			(xy 402.737188 -289.41929) (xy 402.786043 -289.425222) (xy 402.833314 -289.438914) (xy 402.877776 -289.460012)
			(xy 402.918279 -289.487968) (xy 402.953772 -289.52206) (xy 402.983337 -289.561404) (xy 403.006208 -289.604981)
			(xy 403.021792 -289.651662) (xy 403.029687 -289.700239) (xy 403.030182 -289.724846) (xy 403.36903 -289.724846)
			(xy 403.37299 -289.675792) (xy 403.384767 -289.628008) (xy 403.404058 -289.582732) (xy 403.430361 -289.541136)
			(xy 403.462996 -289.504299) (xy 403.501117 -289.473174) (xy 403.543738 -289.448567) (xy 403.589754 -289.431115)
			(xy 403.637973 -289.421271) (xy 403.687148 -289.41929) (xy 403.736003 -289.425222) (xy 403.783274 -289.438914)
			(xy 403.827736 -289.460012) (xy 403.868239 -289.487968) (xy 403.903732 -289.52206) (xy 403.933297 -289.561404)
			(xy 403.956168 -289.604981) (xy 403.971752 -289.651662) (xy 403.979647 -289.700239) (xy 403.980142 -289.724846)
			(xy 404.31899 -289.724846) (xy 404.32295 -289.675792) (xy 404.334727 -289.628008) (xy 404.354018 -289.582732)
			(xy 404.380321 -289.541136) (xy 404.412956 -289.504299) (xy 404.451077 -289.473174) (xy 404.493698 -289.448567)
			(xy 404.539714 -289.431115) (xy 404.587933 -289.421271) (xy 404.637108 -289.41929) (xy 404.685963 -289.425222)
			(xy 404.733234 -289.438914) (xy 404.777696 -289.460012) (xy 404.818199 -289.487968) (xy 404.853692 -289.52206)
			(xy 404.883257 -289.561404) (xy 404.906128 -289.604981) (xy 404.921712 -289.651662) (xy 404.929607 -289.700239)
			(xy 404.930102 -289.724846) (xy 405.269204 -289.724846) (xy 405.273164 -289.675792) (xy 405.284941 -289.628008)
			(xy 405.304232 -289.582732) (xy 405.330535 -289.541136) (xy 405.36317 -289.504299) (xy 405.401291 -289.473174)
			(xy 405.443912 -289.448567) (xy 405.489928 -289.431115) (xy 405.538147 -289.421271) (xy 405.587322 -289.41929)
			(xy 405.636177 -289.425222) (xy 405.683448 -289.438914) (xy 405.72791 -289.460012) (xy 405.768413 -289.487968)
			(xy 405.803906 -289.52206) (xy 405.833471 -289.561404) (xy 405.856342 -289.604981) (xy 405.871926 -289.651662)
			(xy 405.879821 -289.700239) (xy 405.880316 -289.724846) (xy 406.219164 -289.724846) (xy 406.223124 -289.675792)
			(xy 406.234901 -289.628008) (xy 406.254192 -289.582732) (xy 406.280495 -289.541136) (xy 406.31313 -289.504299)
			(xy 406.351251 -289.473174) (xy 406.393872 -289.448567) (xy 406.439888 -289.431115) (xy 406.488107 -289.421271)
			(xy 406.537282 -289.41929) (xy 406.586137 -289.425222) (xy 406.633408 -289.438914) (xy 406.67787 -289.460012)
			(xy 406.718373 -289.487968) (xy 406.753866 -289.52206) (xy 406.783431 -289.561404) (xy 406.806302 -289.604981)
			(xy 406.821886 -289.651662) (xy 406.829781 -289.700239) (xy 406.830276 -289.724846) (xy 408.119084 -289.724846)
			(xy 408.123044 -289.675792) (xy 408.134821 -289.628008) (xy 408.154112 -289.582732) (xy 408.180415 -289.541136)
			(xy 408.21305 -289.504299) (xy 408.251171 -289.473174) (xy 408.293792 -289.448567) (xy 408.339808 -289.431115)
			(xy 408.388027 -289.421271) (xy 408.437202 -289.41929) (xy 408.486057 -289.425222) (xy 408.533328 -289.438914)
			(xy 408.57779 -289.460012) (xy 408.618293 -289.487968) (xy 408.653786 -289.52206) (xy 408.683351 -289.561404)
			(xy 408.706222 -289.604981) (xy 408.721806 -289.651662) (xy 408.729701 -289.700239) (xy 408.730196 -289.724846)
			(xy 409.069044 -289.724846) (xy 409.073004 -289.675792) (xy 409.084781 -289.628008) (xy 409.104072 -289.582732)
			(xy 409.130375 -289.541136) (xy 409.16301 -289.504299) (xy 409.201131 -289.473174) (xy 409.243752 -289.448567)
			(xy 409.289768 -289.431115) (xy 409.337987 -289.421271) (xy 409.387162 -289.41929) (xy 409.436017 -289.425222)
			(xy 409.483288 -289.438914) (xy 409.52775 -289.460012) (xy 409.568253 -289.487968) (xy 409.603746 -289.52206)
			(xy 409.633311 -289.561404) (xy 409.656182 -289.604981) (xy 409.671766 -289.651662) (xy 409.679661 -289.700239)
			(xy 409.680156 -289.724846) (xy 410.019004 -289.724846) (xy 410.022964 -289.675792) (xy 410.034741 -289.628008)
			(xy 410.054032 -289.582732) (xy 410.080335 -289.541136) (xy 410.11297 -289.504299) (xy 410.151091 -289.473174)
			(xy 410.193712 -289.448567) (xy 410.239728 -289.431115) (xy 410.287947 -289.421271) (xy 410.337122 -289.41929)
			(xy 410.385977 -289.425222) (xy 410.433248 -289.438914) (xy 410.47771 -289.460012) (xy 410.518213 -289.487968)
			(xy 410.553706 -289.52206) (xy 410.583271 -289.561404) (xy 410.606142 -289.604981) (xy 410.621726 -289.651662)
			(xy 410.629621 -289.700239) (xy 410.630116 -289.724846) (xy 410.969218 -289.724846) (xy 410.973178 -289.675792)
			(xy 410.984955 -289.628008) (xy 411.004246 -289.582732) (xy 411.030549 -289.541136) (xy 411.063184 -289.504299)
			(xy 411.101305 -289.473174) (xy 411.143926 -289.448567) (xy 411.189942 -289.431115) (xy 411.238161 -289.421271)
			(xy 411.287336 -289.41929) (xy 411.336191 -289.425222) (xy 411.383462 -289.438914) (xy 411.427924 -289.460012)
			(xy 411.468427 -289.487968) (xy 411.50392 -289.52206) (xy 411.533485 -289.561404) (xy 411.556356 -289.604981)
			(xy 411.57194 -289.651662) (xy 411.579835 -289.700239) (xy 411.58033 -289.724846) (xy 411.919178 -289.724846)
			(xy 411.923138 -289.675792) (xy 411.934915 -289.628008) (xy 411.954206 -289.582732) (xy 411.980509 -289.541136)
			(xy 412.013144 -289.504299) (xy 412.051265 -289.473174) (xy 412.093886 -289.448567) (xy 412.139902 -289.431115)
			(xy 412.188121 -289.421271) (xy 412.237296 -289.41929) (xy 412.286151 -289.425222) (xy 412.333422 -289.438914)
			(xy 412.377884 -289.460012) (xy 412.418387 -289.487968) (xy 412.45388 -289.52206) (xy 412.483445 -289.561404)
			(xy 412.506316 -289.604981) (xy 412.5219 -289.651662) (xy 412.529795 -289.700239) (xy 412.53029 -289.724846)
			(xy 412.869138 -289.724846) (xy 412.873098 -289.675792) (xy 412.884875 -289.628008) (xy 412.904166 -289.582732)
			(xy 412.930469 -289.541136) (xy 412.963104 -289.504299) (xy 413.001225 -289.473174) (xy 413.043846 -289.448567)
			(xy 413.089862 -289.431115) (xy 413.138081 -289.421271) (xy 413.187256 -289.41929) (xy 413.236111 -289.425222)
			(xy 413.283382 -289.438914) (xy 413.327844 -289.460012) (xy 413.368347 -289.487968) (xy 413.40384 -289.52206)
			(xy 413.433405 -289.561404) (xy 413.456276 -289.604981) (xy 413.47186 -289.651662) (xy 413.479755 -289.700239)
			(xy 413.48025 -289.724846) (xy 413.819098 -289.724846) (xy 413.823058 -289.675792) (xy 413.834835 -289.628008)
			(xy 413.854126 -289.582732) (xy 413.880429 -289.541136) (xy 413.913064 -289.504299) (xy 413.951185 -289.473174)
			(xy 413.993806 -289.448567) (xy 414.039822 -289.431115) (xy 414.088041 -289.421271) (xy 414.137216 -289.41929)
			(xy 414.186071 -289.425222) (xy 414.233342 -289.438914) (xy 414.277804 -289.460012) (xy 414.318307 -289.487968)
			(xy 414.3538 -289.52206) (xy 414.383365 -289.561404) (xy 414.406236 -289.604981) (xy 414.42182 -289.651662)
			(xy 414.429715 -289.700239) (xy 414.43021 -289.724846) (xy 414.769058 -289.724846) (xy 414.773018 -289.675792)
			(xy 414.784795 -289.628008) (xy 414.804086 -289.582732) (xy 414.830389 -289.541136) (xy 414.863024 -289.504299)
			(xy 414.901145 -289.473174) (xy 414.943766 -289.448567) (xy 414.989782 -289.431115) (xy 415.038001 -289.421271)
			(xy 415.087176 -289.41929) (xy 415.136031 -289.425222) (xy 415.183302 -289.438914) (xy 415.227764 -289.460012)
			(xy 415.268267 -289.487968) (xy 415.30376 -289.52206) (xy 415.333325 -289.561404) (xy 415.356196 -289.604981)
			(xy 415.37178 -289.651662) (xy 415.379675 -289.700239) (xy 415.38017 -289.724846) (xy 415.719018 -289.724846)
			(xy 415.722978 -289.675792) (xy 415.734755 -289.628008) (xy 415.754046 -289.582732) (xy 415.780349 -289.541136)
			(xy 415.812984 -289.504299) (xy 415.851105 -289.473174) (xy 415.893726 -289.448567) (xy 415.939742 -289.431115)
			(xy 415.987961 -289.421271) (xy 416.037136 -289.41929) (xy 416.085991 -289.425222) (xy 416.133262 -289.438914)
			(xy 416.177724 -289.460012) (xy 416.218227 -289.487968) (xy 416.25372 -289.52206) (xy 416.283285 -289.561404)
			(xy 416.306156 -289.604981) (xy 416.32174 -289.651662) (xy 416.329635 -289.700239) (xy 416.33013 -289.724846)
			(xy 416.668978 -289.724846) (xy 416.672938 -289.675792) (xy 416.684715 -289.628008) (xy 416.704006 -289.582732)
			(xy 416.730309 -289.541136) (xy 416.762944 -289.504299) (xy 416.801065 -289.473174) (xy 416.843686 -289.448567)
			(xy 416.889702 -289.431115) (xy 416.937921 -289.421271) (xy 416.987096 -289.41929) (xy 417.035951 -289.425222)
			(xy 417.083222 -289.438914) (xy 417.127684 -289.460012) (xy 417.168187 -289.487968) (xy 417.20368 -289.52206)
			(xy 417.233245 -289.561404) (xy 417.256116 -289.604981) (xy 417.2717 -289.651662) (xy 417.279595 -289.700239)
			(xy 417.28009 -289.724846) (xy 417.619192 -289.724846) (xy 417.623152 -289.675792) (xy 417.634929 -289.628008)
			(xy 417.65422 -289.582732) (xy 417.680523 -289.541136) (xy 417.713158 -289.504299) (xy 417.751279 -289.473174)
			(xy 417.7939 -289.448567) (xy 417.839916 -289.431115) (xy 417.888135 -289.421271) (xy 417.93731 -289.41929)
			(xy 417.986165 -289.425222) (xy 418.033436 -289.438914) (xy 418.077898 -289.460012) (xy 418.118401 -289.487968)
			(xy 418.153894 -289.52206) (xy 418.183459 -289.561404) (xy 418.20633 -289.604981) (xy 418.221914 -289.651662)
			(xy 418.229809 -289.700239) (xy 418.230304 -289.724846) (xy 418.569152 -289.724846) (xy 418.573112 -289.675792)
			(xy 418.584889 -289.628008) (xy 418.60418 -289.582732) (xy 418.630483 -289.541136) (xy 418.663118 -289.504299)
			(xy 418.701239 -289.473174) (xy 418.74386 -289.448567) (xy 418.789876 -289.431115) (xy 418.838095 -289.421271)
			(xy 418.88727 -289.41929) (xy 418.936125 -289.425222) (xy 418.983396 -289.438914) (xy 419.027858 -289.460012)
			(xy 419.068361 -289.487968) (xy 419.103854 -289.52206) (xy 419.133419 -289.561404) (xy 419.15629 -289.604981)
			(xy 419.171874 -289.651662) (xy 419.179769 -289.700239) (xy 419.180264 -289.724846) (xy 419.519112 -289.724846)
			(xy 419.523072 -289.675792) (xy 419.534849 -289.628008) (xy 419.55414 -289.582732) (xy 419.580443 -289.541136)
			(xy 419.613078 -289.504299) (xy 419.651199 -289.473174) (xy 419.69382 -289.448567) (xy 419.739836 -289.431115)
			(xy 419.788055 -289.421271) (xy 419.83723 -289.41929) (xy 419.886085 -289.425222) (xy 419.933356 -289.438914)
			(xy 419.977818 -289.460012) (xy 420.018321 -289.487968) (xy 420.053814 -289.52206) (xy 420.083379 -289.561404)
			(xy 420.10625 -289.604981) (xy 420.121834 -289.651662) (xy 420.129729 -289.700239) (xy 420.130224 -289.724846)
			(xy 420.469072 -289.724846) (xy 420.473032 -289.675792) (xy 420.484809 -289.628008) (xy 420.5041 -289.582732)
			(xy 420.530403 -289.541136) (xy 420.563038 -289.504299) (xy 420.601159 -289.473174) (xy 420.64378 -289.448567)
			(xy 420.689796 -289.431115) (xy 420.738015 -289.421271) (xy 420.78719 -289.41929) (xy 420.836045 -289.425222)
			(xy 420.883316 -289.438914) (xy 420.927778 -289.460012) (xy 420.968281 -289.487968) (xy 421.003774 -289.52206)
			(xy 421.033339 -289.561404) (xy 421.05621 -289.604981) (xy 421.071794 -289.651662) (xy 421.079689 -289.700239)
			(xy 421.080016 -289.71648) (xy 421.419128 -289.71648) (xy 421.424501 -289.667138) (xy 421.437785 -289.619315)
			(xy 421.458632 -289.574271) (xy 421.486491 -289.533193) (xy 421.520629 -289.497163) (xy 421.560145 -289.467131)
			(xy 421.604 -289.443887) (xy 421.651038 -289.428045) (xy 421.700019 -289.420021) (xy 421.724836 -289.419538)
			(xy 421.739019 -289.419709) (xy 421.767259 -289.422385) (xy 421.781224 -289.424872) (xy 421.79367 -289.427158)
			(xy 421.817292 -289.419792) (xy 421.894762 -289.342322) (xy 421.902128 -289.3187) (xy 421.899842 -289.306254)
			(xy 421.897364 -289.292288) (xy 421.894693 -289.264049) (xy 421.894508 -289.249866) (xy 421.89503 -289.224611)
			(xy 421.903343 -289.174789) (xy 421.919744 -289.127015) (xy 421.943785 -289.082592) (xy 421.974809 -289.042732)
			(xy 422.011971 -289.008522) (xy 422.054257 -288.980896) (xy 422.100513 -288.960606) (xy 422.149478 -288.948206)
			(xy 422.199816 -288.944035) (xy 422.250154 -288.948206) (xy 422.299119 -288.960606) (xy 422.345375 -288.980896)
			(xy 422.387661 -289.008522) (xy 422.424823 -289.042732) (xy 422.455847 -289.082592) (xy 422.457161 -289.08502)
			(xy 434.087776 -289.08502) (xy 434.091847 -289.029398) (xy 434.103973 -288.974961) (xy 434.123896 -288.92287)
			(xy 434.151192 -288.874235) (xy 434.185278 -288.830092) (xy 434.225427 -288.791383) (xy 434.270785 -288.758932)
			(xy 434.320385 -288.733431) (xy 434.373169 -288.715424) (xy 434.428012 -288.705294) (xy 434.483746 -288.703257)
			(xy 434.539183 -288.709357) (xy 434.59314 -288.723463) (xy 434.644469 -288.745275) (xy 434.692075 -288.774329)
			(xy 434.734943 -288.810004) (xy 434.753546 -288.830766) (xy 441.453014 -288.830766) (xy 441.457085 -288.775144)
			(xy 441.469211 -288.720707) (xy 441.489134 -288.668616) (xy 441.51643 -288.619981) (xy 441.550516 -288.575838)
			(xy 441.590665 -288.537129) (xy 441.636023 -288.504678) (xy 441.685623 -288.479177) (xy 441.738407 -288.46117)
			(xy 441.79325 -288.45104) (xy 441.848984 -288.449003) (xy 441.904421 -288.455103) (xy 441.958378 -288.469209)
			(xy 442.009707 -288.491021) (xy 442.057313 -288.520075) (xy 442.100181 -288.55575) (xy 442.137398 -288.597287)
			(xy 442.168171 -288.6438) (xy 442.191843 -288.694297) (xy 442.207911 -288.747704) (xy 442.216026 -288.802847)
			(xy 458.605926 -288.802847) (xy 458.605926 -288.748353) (xy 458.613681 -288.694413) (xy 458.629034 -288.642125)
			(xy 458.651672 -288.592555) (xy 458.681133 -288.546711) (xy 458.716819 -288.505526) (xy 458.758003 -288.469839)
			(xy 458.803846 -288.440376) (xy 458.853416 -288.417738) (xy 458.905703 -288.402384) (xy 458.959643 -288.394627)
			(xy 458.98689 -288.39414) (xy 459.01426 -288.394602) (xy 459.06844 -288.402419) (xy 459.120944 -288.417909)
			(xy 459.17069 -288.440752) (xy 459.216657 -288.470478) (xy 459.237588 -288.48812) (xy 459.2447 -288.494216)
			(xy 459.261718 -288.500566) (xy 459.347062 -288.500566) (xy 459.36408 -288.494216) (xy 459.371192 -288.48812)
			(xy 459.392119 -288.470474) (xy 459.438093 -288.440763) (xy 459.487842 -288.417928) (xy 459.540344 -288.402438)
			(xy 459.59452 -288.394613) (xy 459.62189 -288.39414) (xy 459.649147 -288.394506) (xy 459.703106 -288.402263)
			(xy 459.755411 -288.41762) (xy 459.804999 -288.440265) (xy 459.850859 -288.469736) (xy 459.892058 -288.505435)
			(xy 459.927758 -288.546633) (xy 459.95723 -288.592492) (xy 459.979876 -288.642079) (xy 459.995235 -288.694385)
			(xy 460.002993 -288.748343) (xy 460.002993 -288.802847) (xy 460.345826 -288.802847) (xy 460.345826 -288.748353)
			(xy 460.353581 -288.694413) (xy 460.368934 -288.642125) (xy 460.391572 -288.592555) (xy 460.421033 -288.546711)
			(xy 460.456719 -288.505526) (xy 460.497903 -288.469839) (xy 460.543746 -288.440376) (xy 460.593316 -288.417738)
			(xy 460.645603 -288.402384) (xy 460.699543 -288.394627) (xy 460.72679 -288.39414) (xy 460.75416 -288.394602)
			(xy 460.80834 -288.402419) (xy 460.860844 -288.417909) (xy 460.91059 -288.440752) (xy 460.956557 -288.470478)
			(xy 460.977488 -288.48812) (xy 460.9846 -288.494216) (xy 461.001618 -288.500566) (xy 461.086962 -288.500566)
			(xy 461.10398 -288.494216) (xy 461.111092 -288.48812) (xy 461.132019 -288.470474) (xy 461.177993 -288.440763)
			(xy 461.227742 -288.417928) (xy 461.280244 -288.402438) (xy 461.33442 -288.394613) (xy 461.36179 -288.39414)
			(xy 461.389047 -288.394506) (xy 461.443006 -288.402263) (xy 461.495311 -288.41762) (xy 461.544899 -288.440265)
			(xy 461.590759 -288.469736) (xy 461.631958 -288.505435) (xy 461.667658 -288.546633) (xy 461.69713 -288.592492)
			(xy 461.719776 -288.642079) (xy 461.735135 -288.694385) (xy 461.742893 -288.748343) (xy 461.742893 -288.802857)
			(xy 461.735135 -288.856815) (xy 461.719776 -288.909121) (xy 461.69713 -288.958708) (xy 461.667658 -289.004567)
			(xy 461.631958 -289.045765) (xy 461.590759 -289.081464) (xy 461.544899 -289.110935) (xy 461.495311 -289.13358)
			(xy 461.443006 -289.148937) (xy 461.389047 -289.156694) (xy 461.36179 -289.157156) (xy 461.334419 -289.156707)
			(xy 461.280239 -289.148886) (xy 461.227735 -289.133394) (xy 461.177988 -289.110548) (xy 461.132023 -289.080819)
			(xy 461.111092 -289.063176) (xy 461.10398 -289.05708) (xy 461.086962 -289.05073) (xy 461.001618 -289.05073)
			(xy 460.9846 -289.05708) (xy 460.977488 -289.063176) (xy 460.95653 -289.080784) (xy 460.910565 -289.110501)
			(xy 460.860824 -289.133343) (xy 460.808329 -289.148842) (xy 460.754157 -289.156678) (xy 460.72679 -289.157156)
			(xy 460.699543 -289.156573) (xy 460.645603 -289.148816) (xy 460.593316 -289.133462) (xy 460.543746 -289.110824)
			(xy 460.497903 -289.081361) (xy 460.456719 -289.045674) (xy 460.421033 -289.004489) (xy 460.391572 -288.958645)
			(xy 460.368934 -288.909075) (xy 460.353581 -288.856787) (xy 460.345826 -288.802847) (xy 460.002993 -288.802847)
			(xy 460.002993 -288.802857) (xy 459.995235 -288.856815) (xy 459.979876 -288.909121) (xy 459.95723 -288.958708)
			(xy 459.927758 -289.004567) (xy 459.892058 -289.045765) (xy 459.850859 -289.081464) (xy 459.804999 -289.110935)
			(xy 459.755411 -289.13358) (xy 459.703106 -289.148937) (xy 459.649147 -289.156694) (xy 459.62189 -289.157156)
			(xy 459.594519 -289.156707) (xy 459.540339 -289.148886) (xy 459.487835 -289.133394) (xy 459.438088 -289.110548)
			(xy 459.392123 -289.080819) (xy 459.371192 -289.063176) (xy 459.36408 -289.05708) (xy 459.347062 -289.05073)
			(xy 459.261718 -289.05073) (xy 459.2447 -289.05708) (xy 459.237588 -289.063176) (xy 459.21663 -289.080784)
			(xy 459.170665 -289.110501) (xy 459.120924 -289.133343) (xy 459.068429 -289.148842) (xy 459.014257 -289.156678)
			(xy 458.98689 -289.157156) (xy 458.959643 -289.156573) (xy 458.905703 -289.148816) (xy 458.853416 -289.133462)
			(xy 458.803846 -289.110824) (xy 458.758003 -289.081361) (xy 458.716819 -289.045674) (xy 458.681133 -289.004489)
			(xy 458.651672 -288.958645) (xy 458.629034 -288.909075) (xy 458.613681 -288.856787) (xy 458.605926 -288.802847)
			(xy 442.216026 -288.802847) (xy 442.216031 -288.80288) (xy 442.21654 -288.830766) (xy 442.216031 -288.858652)
			(xy 442.207911 -288.913828) (xy 442.191843 -288.967235) (xy 442.168171 -289.017732) (xy 442.137398 -289.064245)
			(xy 442.100181 -289.105782) (xy 442.057313 -289.141457) (xy 442.009707 -289.170511) (xy 441.958378 -289.192323)
			(xy 441.904421 -289.206429) (xy 441.848984 -289.212529) (xy 441.79325 -289.210492) (xy 441.738407 -289.200362)
			(xy 441.685623 -289.182355) (xy 441.636023 -289.156854) (xy 441.590665 -289.124403) (xy 441.550516 -289.085694)
			(xy 441.51643 -289.041551) (xy 441.489134 -288.992916) (xy 441.469211 -288.940825) (xy 441.457085 -288.886388)
			(xy 441.453014 -288.830766) (xy 434.753546 -288.830766) (xy 434.77216 -288.851541) (xy 434.802933 -288.898054)
			(xy 434.826605 -288.948551) (xy 434.842673 -289.001958) (xy 434.850793 -289.057134) (xy 434.851302 -289.08502)
			(xy 434.850793 -289.112906) (xy 434.842673 -289.168082) (xy 434.826605 -289.221489) (xy 434.802933 -289.271986)
			(xy 434.77216 -289.318499) (xy 434.734943 -289.360036) (xy 434.692075 -289.395711) (xy 434.644469 -289.424765)
			(xy 434.59314 -289.446577) (xy 434.539183 -289.460683) (xy 434.483746 -289.466783) (xy 434.428012 -289.464746)
			(xy 434.373169 -289.454616) (xy 434.320385 -289.436609) (xy 434.270785 -289.411108) (xy 434.225427 -289.378657)
			(xy 434.185278 -289.339948) (xy 434.151192 -289.295805) (xy 434.123896 -289.24717) (xy 434.103973 -289.195079)
			(xy 434.091847 -289.140642) (xy 434.087776 -289.08502) (xy 422.457161 -289.08502) (xy 422.479888 -289.127015)
			(xy 422.496289 -289.174789) (xy 422.504602 -289.224611) (xy 422.505124 -289.249866) (xy 422.504942 -289.264049)
			(xy 422.502274 -289.292289) (xy 422.49979 -289.306254) (xy 422.497504 -289.3187) (xy 422.50487 -289.342576)
			(xy 422.582086 -289.419792) (xy 422.606216 -289.427158) (xy 422.618408 -289.424872) (xy 422.632437 -289.422389)
			(xy 422.660804 -289.419716) (xy 422.67505 -289.419538) (xy 422.699865 -289.420032) (xy 422.74884 -289.428068)
			(xy 422.79587 -289.443922) (xy 422.839716 -289.467175) (xy 422.879223 -289.497215) (xy 422.91335 -289.53325)
			(xy 422.941198 -289.574331) (xy 422.962033 -289.619376) (xy 422.975307 -289.667199) (xy 422.980669 -289.716538)
			(xy 422.980218 -289.724846) (xy 424.269166 -289.724846) (xy 424.273126 -289.675792) (xy 424.284903 -289.628008)
			(xy 424.304194 -289.582732) (xy 424.330497 -289.541136) (xy 424.363132 -289.504299) (xy 424.401253 -289.473174)
			(xy 424.443874 -289.448567) (xy 424.48989 -289.431115) (xy 424.538109 -289.421271) (xy 424.587284 -289.41929)
			(xy 424.636139 -289.425222) (xy 424.68341 -289.438914) (xy 424.727872 -289.460012) (xy 424.768375 -289.487968)
			(xy 424.803868 -289.52206) (xy 424.833433 -289.561404) (xy 424.856304 -289.604981) (xy 424.871888 -289.651662)
			(xy 424.879783 -289.700239) (xy 424.880278 -289.724846) (xy 425.219126 -289.724846) (xy 425.223086 -289.675792)
			(xy 425.234863 -289.628008) (xy 425.254154 -289.582732) (xy 425.280457 -289.541136) (xy 425.313092 -289.504299)
			(xy 425.351213 -289.473174) (xy 425.393834 -289.448567) (xy 425.43985 -289.431115) (xy 425.488069 -289.421271)
			(xy 425.537244 -289.41929) (xy 425.586099 -289.425222) (xy 425.63337 -289.438914) (xy 425.677832 -289.460012)
			(xy 425.718335 -289.487968) (xy 425.753828 -289.52206) (xy 425.783393 -289.561404) (xy 425.806264 -289.604981)
			(xy 425.821848 -289.651662) (xy 425.829743 -289.700239) (xy 425.830238 -289.724846) (xy 426.169086 -289.724846)
			(xy 426.173046 -289.675792) (xy 426.184823 -289.628008) (xy 426.204114 -289.582732) (xy 426.230417 -289.541136)
			(xy 426.263052 -289.504299) (xy 426.301173 -289.473174) (xy 426.343794 -289.448567) (xy 426.38981 -289.431115)
			(xy 426.438029 -289.421271) (xy 426.487204 -289.41929) (xy 426.536059 -289.425222) (xy 426.58333 -289.438914)
			(xy 426.627792 -289.460012) (xy 426.668295 -289.487968) (xy 426.703788 -289.52206) (xy 426.733353 -289.561404)
			(xy 426.756224 -289.604981) (xy 426.771808 -289.651662) (xy 426.779703 -289.700239) (xy 426.780198 -289.724846)
			(xy 427.119046 -289.724846) (xy 427.123006 -289.675792) (xy 427.134783 -289.628008) (xy 427.154074 -289.582732)
			(xy 427.180377 -289.541136) (xy 427.213012 -289.504299) (xy 427.251133 -289.473174) (xy 427.293754 -289.448567)
			(xy 427.33977 -289.431115) (xy 427.387989 -289.421271) (xy 427.437164 -289.41929) (xy 427.486019 -289.425222)
			(xy 427.53329 -289.438914) (xy 427.577752 -289.460012) (xy 427.618255 -289.487968) (xy 427.653748 -289.52206)
			(xy 427.683313 -289.561404) (xy 427.706184 -289.604981) (xy 427.721768 -289.651662) (xy 427.729663 -289.700239)
			(xy 427.730158 -289.724846) (xy 428.069006 -289.724846) (xy 428.072966 -289.675792) (xy 428.084743 -289.628008)
			(xy 428.104034 -289.582732) (xy 428.130337 -289.541136) (xy 428.162972 -289.504299) (xy 428.201093 -289.473174)
			(xy 428.243714 -289.448567) (xy 428.28973 -289.431115) (xy 428.337949 -289.421271) (xy 428.387124 -289.41929)
			(xy 428.435979 -289.425222) (xy 428.48325 -289.438914) (xy 428.527712 -289.460012) (xy 428.568215 -289.487968)
			(xy 428.603708 -289.52206) (xy 428.633273 -289.561404) (xy 428.656144 -289.604981) (xy 428.671728 -289.651662)
			(xy 428.679623 -289.700239) (xy 428.680118 -289.724846) (xy 429.01922 -289.724846) (xy 429.02318 -289.675792)
			(xy 429.034957 -289.628008) (xy 429.054248 -289.582732) (xy 429.080551 -289.541136) (xy 429.113186 -289.504299)
			(xy 429.151307 -289.473174) (xy 429.193928 -289.448567) (xy 429.239944 -289.431115) (xy 429.288163 -289.421271)
			(xy 429.337338 -289.41929) (xy 429.386193 -289.425222) (xy 429.433464 -289.438914) (xy 429.477926 -289.460012)
			(xy 429.518429 -289.487968) (xy 429.553922 -289.52206) (xy 429.583487 -289.561404) (xy 429.606358 -289.604981)
			(xy 429.621942 -289.651662) (xy 429.629837 -289.700239) (xy 429.630332 -289.724846) (xy 429.96918 -289.724846)
			(xy 429.97314 -289.675792) (xy 429.984917 -289.628008) (xy 430.004208 -289.582732) (xy 430.030511 -289.541136)
			(xy 430.063146 -289.504299) (xy 430.101267 -289.473174) (xy 430.143888 -289.448567) (xy 430.189904 -289.431115)
			(xy 430.238123 -289.421271) (xy 430.287298 -289.41929) (xy 430.336153 -289.425222) (xy 430.383424 -289.438914)
			(xy 430.427886 -289.460012) (xy 430.468389 -289.487968) (xy 430.503882 -289.52206) (xy 430.533447 -289.561404)
			(xy 430.556318 -289.604981) (xy 430.571902 -289.651662) (xy 430.579797 -289.700239) (xy 430.580292 -289.724846)
			(xy 430.91914 -289.724846) (xy 430.9231 -289.675792) (xy 430.934877 -289.628008) (xy 430.954168 -289.582732)
			(xy 430.980471 -289.541136) (xy 431.013106 -289.504299) (xy 431.051227 -289.473174) (xy 431.093848 -289.448567)
			(xy 431.139864 -289.431115) (xy 431.188083 -289.421271) (xy 431.237258 -289.41929) (xy 431.286113 -289.425222)
			(xy 431.333384 -289.438914) (xy 431.377846 -289.460012) (xy 431.418349 -289.487968) (xy 431.453842 -289.52206)
			(xy 431.468868 -289.542056) (xy 450.443243 -289.542056) (xy 450.443243 -289.487544) (xy 450.451001 -289.433587)
			(xy 450.46636 -289.381284) (xy 450.489007 -289.331699) (xy 450.51848 -289.285843) (xy 450.55418 -289.244647)
			(xy 450.595379 -289.208953) (xy 450.64124 -289.179485) (xy 450.690827 -289.156844) (xy 450.743132 -289.141492)
			(xy 450.79709 -289.13374) (xy 450.824346 -289.13328) (xy 450.851716 -289.133758) (xy 450.905895 -289.14157)
			(xy 450.958399 -289.157055) (xy 451.008146 -289.179895) (xy 451.054113 -289.209619) (xy 451.075044 -289.22726)
			(xy 451.082156 -289.233356) (xy 451.099174 -289.239706) (xy 451.184518 -289.239706) (xy 451.201536 -289.233356)
			(xy 451.208648 -289.22726) (xy 451.229583 -289.209625) (xy 451.275556 -289.179914) (xy 451.325303 -289.157078)
			(xy 451.377802 -289.141585) (xy 451.431977 -289.133755) (xy 451.459346 -289.13328) (xy 451.486594 -289.133793)
			(xy 451.540535 -289.141555) (xy 451.592823 -289.156914) (xy 451.642393 -289.179557) (xy 451.688236 -289.209023)
			(xy 451.729419 -289.244714) (xy 451.765104 -289.285901) (xy 451.794565 -289.331748) (xy 451.817203 -289.38132)
			(xy 451.832555 -289.43361) (xy 451.84031 -289.487552) (xy 451.84031 -289.542048) (xy 451.840309 -289.542052)
			(xy 452.214966 -289.542052) (xy 452.214966 -289.487548) (xy 452.222722 -289.433599) (xy 452.238078 -289.381303)
			(xy 452.260719 -289.331724) (xy 452.290186 -289.285873) (xy 452.325878 -289.244681) (xy 452.36707 -289.208989)
			(xy 452.412921 -289.179521) (xy 452.462499 -289.156879) (xy 452.514795 -289.141523) (xy 452.568744 -289.133766)
			(xy 452.595996 -289.13328) (xy 452.623367 -289.133729) (xy 452.677548 -289.141548) (xy 452.730052 -289.15704)
			(xy 452.779798 -289.179886) (xy 452.825764 -289.209616) (xy 452.846694 -289.22726) (xy 452.853806 -289.233356)
			(xy 452.870824 -289.239706) (xy 452.956168 -289.239706) (xy 452.973186 -289.233356) (xy 452.980298 -289.22726)
			(xy 453.001215 -289.209602) (xy 453.047192 -289.179894) (xy 453.096944 -289.157062) (xy 453.149448 -289.141576)
			(xy 453.203626 -289.133751) (xy 453.230996 -289.13328) (xy 453.258248 -289.133767) (xy 453.312198 -289.141523)
			(xy 453.364495 -289.156879) (xy 453.414074 -289.17952) (xy 453.459926 -289.208987) (xy 453.501118 -289.24468)
			(xy 453.536811 -289.285871) (xy 453.566278 -289.331723) (xy 453.58892 -289.381302) (xy 453.604276 -289.433598)
			(xy 453.612033 -289.487548) (xy 453.612033 -289.542052) (xy 453.604276 -289.596002) (xy 453.58892 -289.648298)
			(xy 453.566278 -289.697877) (xy 453.536811 -289.743729) (xy 453.501118 -289.78492) (xy 453.459926 -289.820613)
			(xy 453.414074 -289.85008) (xy 453.364495 -289.872721) (xy 453.312198 -289.888077) (xy 453.258248 -289.895833)
			(xy 453.230996 -289.896296) (xy 453.203626 -289.895833) (xy 453.149446 -289.888015) (xy 453.096943 -289.872525)
			(xy 453.047196 -289.849683) (xy 453.00123 -289.819957) (xy 452.980298 -289.802316) (xy 452.973186 -289.79622)
			(xy 452.956168 -289.78987) (xy 452.870824 -289.78987) (xy 452.853806 -289.79622) (xy 452.846694 -289.802316)
			(xy 452.825777 -289.819974) (xy 452.7798 -289.849682) (xy 452.730048 -289.872514) (xy 452.677545 -289.888001)
			(xy 452.623366 -289.895825) (xy 452.595996 -289.896296) (xy 452.568744 -289.895834) (xy 452.514795 -289.888077)
			(xy 452.462499 -289.872721) (xy 452.412921 -289.850079) (xy 452.36707 -289.820611) (xy 452.325878 -289.784919)
			(xy 452.290186 -289.743727) (xy 452.260719 -289.697876) (xy 452.238078 -289.648297) (xy 452.222722 -289.596001)
			(xy 452.214966 -289.542052) (xy 451.840309 -289.542052) (xy 451.832555 -289.59599) (xy 451.817203 -289.64828)
			(xy 451.794565 -289.697852) (xy 451.765104 -289.743699) (xy 451.729419 -289.784886) (xy 451.688236 -289.820577)
			(xy 451.642393 -289.850043) (xy 451.592823 -289.872686) (xy 451.540535 -289.888045) (xy 451.486594 -289.895807)
			(xy 451.459346 -289.896296) (xy 451.431977 -289.895804) (xy 451.377799 -289.887993) (xy 451.325296 -289.87251)
			(xy 451.275549 -289.849674) (xy 451.229581 -289.819955) (xy 451.208648 -289.802316) (xy 451.201536 -289.79622)
			(xy 451.184518 -289.78987) (xy 451.099174 -289.78987) (xy 451.082156 -289.79622) (xy 451.075044 -289.802316)
			(xy 451.054108 -289.81995) (xy 451.008136 -289.849662) (xy 450.95839 -289.872499) (xy 450.90589 -289.887991)
			(xy 450.851715 -289.895821) (xy 450.824346 -289.896296) (xy 450.79709 -289.89586) (xy 450.743132 -289.888108)
			(xy 450.690827 -289.872756) (xy 450.64124 -289.850115) (xy 450.595379 -289.820647) (xy 450.55418 -289.784953)
			(xy 450.51848 -289.743757) (xy 450.489007 -289.697901) (xy 450.46636 -289.648316) (xy 450.451001 -289.596013)
			(xy 450.443243 -289.542056) (xy 431.468868 -289.542056) (xy 431.483407 -289.561404) (xy 431.506278 -289.604981)
			(xy 431.521862 -289.651662) (xy 431.529757 -289.700239) (xy 431.530252 -289.724846) (xy 431.529757 -289.749453)
			(xy 431.521862 -289.79803) (xy 431.506278 -289.844711) (xy 431.483407 -289.888288) (xy 431.453842 -289.927632)
			(xy 431.418349 -289.961724) (xy 431.377846 -289.98968) (xy 431.333384 -290.010778) (xy 431.286113 -290.02447)
			(xy 431.237258 -290.030402) (xy 431.188083 -290.028421) (xy 431.139864 -290.018577) (xy 431.093848 -290.001125)
			(xy 431.051227 -289.976518) (xy 431.013106 -289.945393) (xy 430.980471 -289.908556) (xy 430.954168 -289.86696)
			(xy 430.934877 -289.821684) (xy 430.9231 -289.7739) (xy 430.91914 -289.724846) (xy 430.580292 -289.724846)
			(xy 430.579797 -289.749453) (xy 430.571902 -289.79803) (xy 430.556318 -289.844711) (xy 430.533447 -289.888288)
			(xy 430.503882 -289.927632) (xy 430.468389 -289.961724) (xy 430.427886 -289.98968) (xy 430.383424 -290.010778)
			(xy 430.336153 -290.02447) (xy 430.287298 -290.030402) (xy 430.238123 -290.028421) (xy 430.189904 -290.018577)
			(xy 430.143888 -290.001125) (xy 430.101267 -289.976518) (xy 430.063146 -289.945393) (xy 430.030511 -289.908556)
			(xy 430.004208 -289.86696) (xy 429.984917 -289.821684) (xy 429.97314 -289.7739) (xy 429.96918 -289.724846)
			(xy 429.630332 -289.724846) (xy 429.629837 -289.749453) (xy 429.621942 -289.79803) (xy 429.606358 -289.844711)
			(xy 429.583487 -289.888288) (xy 429.553922 -289.927632) (xy 429.518429 -289.961724) (xy 429.477926 -289.98968)
			(xy 429.433464 -290.010778) (xy 429.386193 -290.02447) (xy 429.337338 -290.030402) (xy 429.288163 -290.028421)
			(xy 429.239944 -290.018577) (xy 429.193928 -290.001125) (xy 429.151307 -289.976518) (xy 429.113186 -289.945393)
			(xy 429.080551 -289.908556) (xy 429.054248 -289.86696) (xy 429.034957 -289.821684) (xy 429.02318 -289.7739)
			(xy 429.01922 -289.724846) (xy 428.680118 -289.724846) (xy 428.679623 -289.749453) (xy 428.671728 -289.79803)
			(xy 428.656144 -289.844711) (xy 428.633273 -289.888288) (xy 428.603708 -289.927632) (xy 428.568215 -289.961724)
			(xy 428.527712 -289.98968) (xy 428.48325 -290.010778) (xy 428.435979 -290.02447) (xy 428.387124 -290.030402)
			(xy 428.337949 -290.028421) (xy 428.28973 -290.018577) (xy 428.243714 -290.001125) (xy 428.201093 -289.976518)
			(xy 428.162972 -289.945393) (xy 428.130337 -289.908556) (xy 428.104034 -289.86696) (xy 428.084743 -289.821684)
			(xy 428.072966 -289.7739) (xy 428.069006 -289.724846) (xy 427.730158 -289.724846) (xy 427.729663 -289.749453)
			(xy 427.721768 -289.79803) (xy 427.706184 -289.844711) (xy 427.683313 -289.888288) (xy 427.653748 -289.927632)
			(xy 427.618255 -289.961724) (xy 427.577752 -289.98968) (xy 427.53329 -290.010778) (xy 427.486019 -290.02447)
			(xy 427.437164 -290.030402) (xy 427.387989 -290.028421) (xy 427.33977 -290.018577) (xy 427.293754 -290.001125)
			(xy 427.251133 -289.976518) (xy 427.213012 -289.945393) (xy 427.180377 -289.908556) (xy 427.154074 -289.86696)
			(xy 427.134783 -289.821684) (xy 427.123006 -289.7739) (xy 427.119046 -289.724846) (xy 426.780198 -289.724846)
			(xy 426.779703 -289.749453) (xy 426.771808 -289.79803) (xy 426.756224 -289.844711) (xy 426.733353 -289.888288)
			(xy 426.703788 -289.927632) (xy 426.668295 -289.961724) (xy 426.627792 -289.98968) (xy 426.58333 -290.010778)
			(xy 426.536059 -290.02447) (xy 426.487204 -290.030402) (xy 426.438029 -290.028421) (xy 426.38981 -290.018577)
			(xy 426.343794 -290.001125) (xy 426.301173 -289.976518) (xy 426.263052 -289.945393) (xy 426.230417 -289.908556)
			(xy 426.204114 -289.86696) (xy 426.184823 -289.821684) (xy 426.173046 -289.7739) (xy 426.169086 -289.724846)
			(xy 425.830238 -289.724846) (xy 425.829743 -289.749453) (xy 425.821848 -289.79803) (xy 425.806264 -289.844711)
			(xy 425.783393 -289.888288) (xy 425.753828 -289.927632) (xy 425.718335 -289.961724) (xy 425.677832 -289.98968)
			(xy 425.63337 -290.010778) (xy 425.586099 -290.02447) (xy 425.537244 -290.030402) (xy 425.488069 -290.028421)
			(xy 425.43985 -290.018577) (xy 425.393834 -290.001125) (xy 425.351213 -289.976518) (xy 425.313092 -289.945393)
			(xy 425.280457 -289.908556) (xy 425.254154 -289.86696) (xy 425.234863 -289.821684) (xy 425.223086 -289.7739)
			(xy 425.219126 -289.724846) (xy 424.880278 -289.724846) (xy 424.879783 -289.749453) (xy 424.871888 -289.79803)
			(xy 424.856304 -289.844711) (xy 424.833433 -289.888288) (xy 424.803868 -289.927632) (xy 424.768375 -289.961724)
			(xy 424.727872 -289.98968) (xy 424.68341 -290.010778) (xy 424.636139 -290.02447) (xy 424.587284 -290.030402)
			(xy 424.538109 -290.028421) (xy 424.48989 -290.018577) (xy 424.443874 -290.001125) (xy 424.401253 -289.976518)
			(xy 424.363132 -289.945393) (xy 424.330497 -289.908556) (xy 424.304194 -289.86696) (xy 424.284903 -289.821684)
			(xy 424.273126 -289.7739) (xy 424.269166 -289.724846) (xy 422.980218 -289.724846) (xy 422.97798 -289.766096)
			(xy 422.967308 -289.814565) (xy 422.948937 -289.86067) (xy 422.923349 -289.903195) (xy 422.891218 -289.941021)
			(xy 422.853392 -289.973151) (xy 422.810866 -289.998739) (xy 422.764761 -290.01711) (xy 422.716292 -290.02778)
			(xy 422.666734 -290.030469) (xy 422.617395 -290.025106) (xy 422.569572 -290.011831) (xy 422.524528 -289.990996)
			(xy 422.483447 -289.963147) (xy 422.447412 -289.92902) (xy 422.417373 -289.889513) (xy 422.394121 -289.845667)
			(xy 422.378267 -289.798636) (xy 422.370231 -289.749661) (xy 422.369742 -289.724846) (xy 422.369924 -289.710663)
			(xy 422.372592 -289.682423) (xy 422.375076 -289.668458) (xy 422.377362 -289.656012) (xy 422.369996 -289.632136)
			(xy 422.29278 -289.55492) (xy 422.26865 -289.547554) (xy 422.256458 -289.54984) (xy 422.24243 -289.552328)
			(xy 422.214062 -289.554998) (xy 422.199816 -289.555174) (xy 422.185633 -289.554996) (xy 422.157393 -289.552325)
			(xy 422.143428 -289.54984) (xy 422.130982 -289.547554) (xy 422.10736 -289.55492) (xy 422.02989 -289.63239)
			(xy 422.022524 -289.656012) (xy 422.02481 -289.668458) (xy 422.027291 -289.682423) (xy 422.02996 -289.710663)
			(xy 422.030144 -289.724846) (xy 422.029573 -289.749663) (xy 422.021535 -289.798642) (xy 422.00568 -289.845675)
			(xy 421.982425 -289.889524) (xy 421.952382 -289.929033) (xy 421.916343 -289.963161) (xy 421.875257 -289.991009)
			(xy 421.830208 -290.011843) (xy 421.782381 -290.025115) (xy 421.733038 -290.030474) (xy 421.683477 -290.02778)
			(xy 421.635005 -290.017103) (xy 421.588899 -289.998726) (xy 421.546373 -289.973131) (xy 421.508548 -289.940994)
			(xy 421.476421 -289.90316) (xy 421.450838 -289.860628) (xy 421.432472 -289.814517) (xy 421.421809 -289.766042)
			(xy 421.419128 -289.71648) (xy 421.080016 -289.71648) (xy 421.080184 -289.724846) (xy 421.079689 -289.749453)
			(xy 421.071794 -289.79803) (xy 421.05621 -289.844711) (xy 421.033339 -289.888288) (xy 421.003774 -289.927632)
			(xy 420.968281 -289.961724) (xy 420.927778 -289.98968) (xy 420.883316 -290.010778) (xy 420.836045 -290.02447)
			(xy 420.78719 -290.030402) (xy 420.738015 -290.028421) (xy 420.689796 -290.018577) (xy 420.64378 -290.001125)
			(xy 420.601159 -289.976518) (xy 420.563038 -289.945393) (xy 420.530403 -289.908556) (xy 420.5041 -289.86696)
			(xy 420.484809 -289.821684) (xy 420.473032 -289.7739) (xy 420.469072 -289.724846) (xy 420.130224 -289.724846)
			(xy 420.129729 -289.749453) (xy 420.121834 -289.79803) (xy 420.10625 -289.844711) (xy 420.083379 -289.888288)
			(xy 420.053814 -289.927632) (xy 420.018321 -289.961724) (xy 419.977818 -289.98968) (xy 419.933356 -290.010778)
			(xy 419.886085 -290.02447) (xy 419.83723 -290.030402) (xy 419.788055 -290.028421) (xy 419.739836 -290.018577)
			(xy 419.69382 -290.001125) (xy 419.651199 -289.976518) (xy 419.613078 -289.945393) (xy 419.580443 -289.908556)
			(xy 419.55414 -289.86696) (xy 419.534849 -289.821684) (xy 419.523072 -289.7739) (xy 419.519112 -289.724846)
			(xy 419.180264 -289.724846) (xy 419.179769 -289.749453) (xy 419.171874 -289.79803) (xy 419.15629 -289.844711)
			(xy 419.133419 -289.888288) (xy 419.103854 -289.927632) (xy 419.068361 -289.961724) (xy 419.027858 -289.98968)
			(xy 418.983396 -290.010778) (xy 418.936125 -290.02447) (xy 418.88727 -290.030402) (xy 418.838095 -290.028421)
			(xy 418.789876 -290.018577) (xy 418.74386 -290.001125) (xy 418.701239 -289.976518) (xy 418.663118 -289.945393)
			(xy 418.630483 -289.908556) (xy 418.60418 -289.86696) (xy 418.584889 -289.821684) (xy 418.573112 -289.7739)
			(xy 418.569152 -289.724846) (xy 418.230304 -289.724846) (xy 418.229809 -289.749453) (xy 418.221914 -289.79803)
			(xy 418.20633 -289.844711) (xy 418.183459 -289.888288) (xy 418.153894 -289.927632) (xy 418.118401 -289.961724)
			(xy 418.077898 -289.98968) (xy 418.033436 -290.010778) (xy 417.986165 -290.02447) (xy 417.93731 -290.030402)
			(xy 417.888135 -290.028421) (xy 417.839916 -290.018577) (xy 417.7939 -290.001125) (xy 417.751279 -289.976518)
			(xy 417.713158 -289.945393) (xy 417.680523 -289.908556) (xy 417.65422 -289.86696) (xy 417.634929 -289.821684)
			(xy 417.623152 -289.7739) (xy 417.619192 -289.724846) (xy 417.28009 -289.724846) (xy 417.279595 -289.749453)
			(xy 417.2717 -289.79803) (xy 417.256116 -289.844711) (xy 417.233245 -289.888288) (xy 417.20368 -289.927632)
			(xy 417.168187 -289.961724) (xy 417.127684 -289.98968) (xy 417.083222 -290.010778) (xy 417.035951 -290.02447)
			(xy 416.987096 -290.030402) (xy 416.937921 -290.028421) (xy 416.889702 -290.018577) (xy 416.843686 -290.001125)
			(xy 416.801065 -289.976518) (xy 416.762944 -289.945393) (xy 416.730309 -289.908556) (xy 416.704006 -289.86696)
			(xy 416.684715 -289.821684) (xy 416.672938 -289.7739) (xy 416.668978 -289.724846) (xy 416.33013 -289.724846)
			(xy 416.329635 -289.749453) (xy 416.32174 -289.79803) (xy 416.306156 -289.844711) (xy 416.283285 -289.888288)
			(xy 416.25372 -289.927632) (xy 416.218227 -289.961724) (xy 416.177724 -289.98968) (xy 416.133262 -290.010778)
			(xy 416.085991 -290.02447) (xy 416.037136 -290.030402) (xy 415.987961 -290.028421) (xy 415.939742 -290.018577)
			(xy 415.893726 -290.001125) (xy 415.851105 -289.976518) (xy 415.812984 -289.945393) (xy 415.780349 -289.908556)
			(xy 415.754046 -289.86696) (xy 415.734755 -289.821684) (xy 415.722978 -289.7739) (xy 415.719018 -289.724846)
			(xy 415.38017 -289.724846) (xy 415.379675 -289.749453) (xy 415.37178 -289.79803) (xy 415.356196 -289.844711)
			(xy 415.333325 -289.888288) (xy 415.30376 -289.927632) (xy 415.268267 -289.961724) (xy 415.227764 -289.98968)
			(xy 415.183302 -290.010778) (xy 415.136031 -290.02447) (xy 415.087176 -290.030402) (xy 415.038001 -290.028421)
			(xy 414.989782 -290.018577) (xy 414.943766 -290.001125) (xy 414.901145 -289.976518) (xy 414.863024 -289.945393)
			(xy 414.830389 -289.908556) (xy 414.804086 -289.86696) (xy 414.784795 -289.821684) (xy 414.773018 -289.7739)
			(xy 414.769058 -289.724846) (xy 414.43021 -289.724846) (xy 414.429715 -289.749453) (xy 414.42182 -289.79803)
			(xy 414.406236 -289.844711) (xy 414.383365 -289.888288) (xy 414.3538 -289.927632) (xy 414.318307 -289.961724)
			(xy 414.277804 -289.98968) (xy 414.233342 -290.010778) (xy 414.186071 -290.02447) (xy 414.137216 -290.030402)
			(xy 414.088041 -290.028421) (xy 414.039822 -290.018577) (xy 413.993806 -290.001125) (xy 413.951185 -289.976518)
			(xy 413.913064 -289.945393) (xy 413.880429 -289.908556) (xy 413.854126 -289.86696) (xy 413.834835 -289.821684)
			(xy 413.823058 -289.7739) (xy 413.819098 -289.724846) (xy 413.48025 -289.724846) (xy 413.479755 -289.749453)
			(xy 413.47186 -289.79803) (xy 413.456276 -289.844711) (xy 413.433405 -289.888288) (xy 413.40384 -289.927632)
			(xy 413.368347 -289.961724) (xy 413.327844 -289.98968) (xy 413.283382 -290.010778) (xy 413.236111 -290.02447)
			(xy 413.187256 -290.030402) (xy 413.138081 -290.028421) (xy 413.089862 -290.018577) (xy 413.043846 -290.001125)
			(xy 413.001225 -289.976518) (xy 412.963104 -289.945393) (xy 412.930469 -289.908556) (xy 412.904166 -289.86696)
			(xy 412.884875 -289.821684) (xy 412.873098 -289.7739) (xy 412.869138 -289.724846) (xy 412.53029 -289.724846)
			(xy 412.529795 -289.749453) (xy 412.5219 -289.79803) (xy 412.506316 -289.844711) (xy 412.483445 -289.888288)
			(xy 412.45388 -289.927632) (xy 412.418387 -289.961724) (xy 412.377884 -289.98968) (xy 412.333422 -290.010778)
			(xy 412.286151 -290.02447) (xy 412.237296 -290.030402) (xy 412.188121 -290.028421) (xy 412.139902 -290.018577)
			(xy 412.093886 -290.001125) (xy 412.051265 -289.976518) (xy 412.013144 -289.945393) (xy 411.980509 -289.908556)
			(xy 411.954206 -289.86696) (xy 411.934915 -289.821684) (xy 411.923138 -289.7739) (xy 411.919178 -289.724846)
			(xy 411.58033 -289.724846) (xy 411.579835 -289.749453) (xy 411.57194 -289.79803) (xy 411.556356 -289.844711)
			(xy 411.533485 -289.888288) (xy 411.50392 -289.927632) (xy 411.468427 -289.961724) (xy 411.427924 -289.98968)
			(xy 411.383462 -290.010778) (xy 411.336191 -290.02447) (xy 411.287336 -290.030402) (xy 411.238161 -290.028421)
			(xy 411.189942 -290.018577) (xy 411.143926 -290.001125) (xy 411.101305 -289.976518) (xy 411.063184 -289.945393)
			(xy 411.030549 -289.908556) (xy 411.004246 -289.86696) (xy 410.984955 -289.821684) (xy 410.973178 -289.7739)
			(xy 410.969218 -289.724846) (xy 410.630116 -289.724846) (xy 410.629621 -289.749453) (xy 410.621726 -289.79803)
			(xy 410.606142 -289.844711) (xy 410.583271 -289.888288) (xy 410.553706 -289.927632) (xy 410.518213 -289.961724)
			(xy 410.47771 -289.98968) (xy 410.433248 -290.010778) (xy 410.385977 -290.02447) (xy 410.337122 -290.030402)
			(xy 410.287947 -290.028421) (xy 410.239728 -290.018577) (xy 410.193712 -290.001125) (xy 410.151091 -289.976518)
			(xy 410.11297 -289.945393) (xy 410.080335 -289.908556) (xy 410.054032 -289.86696) (xy 410.034741 -289.821684)
			(xy 410.022964 -289.7739) (xy 410.019004 -289.724846) (xy 409.680156 -289.724846) (xy 409.679661 -289.749453)
			(xy 409.671766 -289.79803) (xy 409.656182 -289.844711) (xy 409.633311 -289.888288) (xy 409.603746 -289.927632)
			(xy 409.568253 -289.961724) (xy 409.52775 -289.98968) (xy 409.483288 -290.010778) (xy 409.436017 -290.02447)
			(xy 409.387162 -290.030402) (xy 409.337987 -290.028421) (xy 409.289768 -290.018577) (xy 409.243752 -290.001125)
			(xy 409.201131 -289.976518) (xy 409.16301 -289.945393) (xy 409.130375 -289.908556) (xy 409.104072 -289.86696)
			(xy 409.084781 -289.821684) (xy 409.073004 -289.7739) (xy 409.069044 -289.724846) (xy 408.730196 -289.724846)
			(xy 408.729701 -289.749453) (xy 408.721806 -289.79803) (xy 408.706222 -289.844711) (xy 408.683351 -289.888288)
			(xy 408.653786 -289.927632) (xy 408.618293 -289.961724) (xy 408.57779 -289.98968) (xy 408.533328 -290.010778)
			(xy 408.486057 -290.02447) (xy 408.437202 -290.030402) (xy 408.388027 -290.028421) (xy 408.339808 -290.018577)
			(xy 408.293792 -290.001125) (xy 408.251171 -289.976518) (xy 408.21305 -289.945393) (xy 408.180415 -289.908556)
			(xy 408.154112 -289.86696) (xy 408.134821 -289.821684) (xy 408.123044 -289.7739) (xy 408.119084 -289.724846)
			(xy 406.830276 -289.724846) (xy 406.829781 -289.749453) (xy 406.821886 -289.79803) (xy 406.806302 -289.844711)
			(xy 406.783431 -289.888288) (xy 406.753866 -289.927632) (xy 406.718373 -289.961724) (xy 406.67787 -289.98968)
			(xy 406.633408 -290.010778) (xy 406.586137 -290.02447) (xy 406.537282 -290.030402) (xy 406.488107 -290.028421)
			(xy 406.439888 -290.018577) (xy 406.393872 -290.001125) (xy 406.351251 -289.976518) (xy 406.31313 -289.945393)
			(xy 406.280495 -289.908556) (xy 406.254192 -289.86696) (xy 406.234901 -289.821684) (xy 406.223124 -289.7739)
			(xy 406.219164 -289.724846) (xy 405.880316 -289.724846) (xy 405.879821 -289.749453) (xy 405.871926 -289.79803)
			(xy 405.856342 -289.844711) (xy 405.833471 -289.888288) (xy 405.803906 -289.927632) (xy 405.768413 -289.961724)
			(xy 405.72791 -289.98968) (xy 405.683448 -290.010778) (xy 405.636177 -290.02447) (xy 405.587322 -290.030402)
			(xy 405.538147 -290.028421) (xy 405.489928 -290.018577) (xy 405.443912 -290.001125) (xy 405.401291 -289.976518)
			(xy 405.36317 -289.945393) (xy 405.330535 -289.908556) (xy 405.304232 -289.86696) (xy 405.284941 -289.821684)
			(xy 405.273164 -289.7739) (xy 405.269204 -289.724846) (xy 404.930102 -289.724846) (xy 404.929607 -289.749453)
			(xy 404.921712 -289.79803) (xy 404.906128 -289.844711) (xy 404.883257 -289.888288) (xy 404.853692 -289.927632)
			(xy 404.818199 -289.961724) (xy 404.777696 -289.98968) (xy 404.733234 -290.010778) (xy 404.685963 -290.02447)
			(xy 404.637108 -290.030402) (xy 404.587933 -290.028421) (xy 404.539714 -290.018577) (xy 404.493698 -290.001125)
			(xy 404.451077 -289.976518) (xy 404.412956 -289.945393) (xy 404.380321 -289.908556) (xy 404.354018 -289.86696)
			(xy 404.334727 -289.821684) (xy 404.32295 -289.7739) (xy 404.31899 -289.724846) (xy 403.980142 -289.724846)
			(xy 403.979647 -289.749453) (xy 403.971752 -289.79803) (xy 403.956168 -289.844711) (xy 403.933297 -289.888288)
			(xy 403.903732 -289.927632) (xy 403.868239 -289.961724) (xy 403.827736 -289.98968) (xy 403.783274 -290.010778)
			(xy 403.736003 -290.02447) (xy 403.687148 -290.030402) (xy 403.637973 -290.028421) (xy 403.589754 -290.018577)
			(xy 403.543738 -290.001125) (xy 403.501117 -289.976518) (xy 403.462996 -289.945393) (xy 403.430361 -289.908556)
			(xy 403.404058 -289.86696) (xy 403.384767 -289.821684) (xy 403.37299 -289.7739) (xy 403.36903 -289.724846)
			(xy 403.030182 -289.724846) (xy 403.029687 -289.749453) (xy 403.021792 -289.79803) (xy 403.006208 -289.844711)
			(xy 402.983337 -289.888288) (xy 402.953772 -289.927632) (xy 402.918279 -289.961724) (xy 402.877776 -289.98968)
			(xy 402.833314 -290.010778) (xy 402.786043 -290.02447) (xy 402.737188 -290.030402) (xy 402.688013 -290.028421)
			(xy 402.639794 -290.018577) (xy 402.593778 -290.001125) (xy 402.551157 -289.976518) (xy 402.513036 -289.945393)
			(xy 402.480401 -289.908556) (xy 402.454098 -289.86696) (xy 402.434807 -289.821684) (xy 402.42303 -289.7739)
			(xy 402.41907 -289.724846) (xy 402.080222 -289.724846) (xy 402.079727 -289.749453) (xy 402.071832 -289.79803)
			(xy 402.056248 -289.844711) (xy 402.033377 -289.888288) (xy 402.003812 -289.927632) (xy 401.968319 -289.961724)
			(xy 401.927816 -289.98968) (xy 401.883354 -290.010778) (xy 401.836083 -290.02447) (xy 401.787228 -290.030402)
			(xy 401.738053 -290.028421) (xy 401.689834 -290.018577) (xy 401.643818 -290.001125) (xy 401.601197 -289.976518)
			(xy 401.563076 -289.945393) (xy 401.530441 -289.908556) (xy 401.504138 -289.86696) (xy 401.484847 -289.821684)
			(xy 401.47307 -289.7739) (xy 401.46911 -289.724846) (xy 401.130262 -289.724846) (xy 401.129767 -289.749453)
			(xy 401.121872 -289.79803) (xy 401.106288 -289.844711) (xy 401.083417 -289.888288) (xy 401.053852 -289.927632)
			(xy 401.018359 -289.961724) (xy 400.977856 -289.98968) (xy 400.933394 -290.010778) (xy 400.886123 -290.02447)
			(xy 400.837268 -290.030402) (xy 400.788093 -290.028421) (xy 400.739874 -290.018577) (xy 400.693858 -290.001125)
			(xy 400.651237 -289.976518) (xy 400.613116 -289.945393) (xy 400.580481 -289.908556) (xy 400.554178 -289.86696)
			(xy 400.534887 -289.821684) (xy 400.52311 -289.7739) (xy 400.51915 -289.724846) (xy 400.180302 -289.724846)
			(xy 400.179807 -289.749453) (xy 400.171912 -289.79803) (xy 400.156328 -289.844711) (xy 400.133457 -289.888288)
			(xy 400.103892 -289.927632) (xy 400.068399 -289.961724) (xy 400.027896 -289.98968) (xy 399.983434 -290.010778)
			(xy 399.936163 -290.02447) (xy 399.887308 -290.030402) (xy 399.838133 -290.028421) (xy 399.789914 -290.018577)
			(xy 399.743898 -290.001125) (xy 399.701277 -289.976518) (xy 399.663156 -289.945393) (xy 399.630521 -289.908556)
			(xy 399.604218 -289.86696) (xy 399.584927 -289.821684) (xy 399.57315 -289.7739) (xy 399.56919 -289.724846)
			(xy 399.230342 -289.724846) (xy 399.229847 -289.749453) (xy 399.221952 -289.79803) (xy 399.206368 -289.844711)
			(xy 399.183497 -289.888288) (xy 399.153932 -289.927632) (xy 399.118439 -289.961724) (xy 399.077936 -289.98968)
			(xy 399.033474 -290.010778) (xy 398.986203 -290.02447) (xy 398.937348 -290.030402) (xy 398.888173 -290.028421)
			(xy 398.839954 -290.018577) (xy 398.793938 -290.001125) (xy 398.751317 -289.976518) (xy 398.713196 -289.945393)
			(xy 398.680561 -289.908556) (xy 398.654258 -289.86696) (xy 398.634967 -289.821684) (xy 398.62319 -289.7739)
			(xy 398.61923 -289.724846) (xy 398.280128 -289.724846) (xy 398.279633 -289.749453) (xy 398.271738 -289.79803)
			(xy 398.256154 -289.844711) (xy 398.233283 -289.888288) (xy 398.203718 -289.927632) (xy 398.168225 -289.961724)
			(xy 398.127722 -289.98968) (xy 398.08326 -290.010778) (xy 398.035989 -290.02447) (xy 397.987134 -290.030402)
			(xy 397.937959 -290.028421) (xy 397.88974 -290.018577) (xy 397.843724 -290.001125) (xy 397.801103 -289.976518)
			(xy 397.762982 -289.945393) (xy 397.730347 -289.908556) (xy 397.704044 -289.86696) (xy 397.684753 -289.821684)
			(xy 397.672976 -289.7739) (xy 397.669016 -289.724846) (xy 397.355101 -289.724846) (xy 397.355101 -289.751164)
			(xy 397.346737 -289.803213) (xy 397.330222 -289.853275) (xy 397.305975 -289.900084) (xy 397.274609 -289.942454)
			(xy 397.236919 -289.979311) (xy 397.193859 -290.009722) (xy 397.14652 -290.032917) (xy 397.096101 -290.048309)
			(xy 397.070072 -290.052506) (xy 397.066008 -290.053014) (xy 397.054578 -290.05657) (xy 397.05026 -290.05784)
			(xy 397.02613 -290.069016) (xy 397.019526 -290.076128) (xy 397.004794 -290.091622) (xy 396.996666 -290.102798)
			(xy 396.993974 -290.10833) (xy 396.991025 -290.120271) (xy 396.990824 -290.12642) (xy 396.990824 -290.2458)
			(xy 433.453792 -290.2458) (xy 433.457863 -290.190178) (xy 433.469989 -290.135741) (xy 433.489912 -290.08365)
			(xy 433.517208 -290.035015) (xy 433.551294 -289.990872) (xy 433.591443 -289.952163) (xy 433.636801 -289.919712)
			(xy 433.686401 -289.894211) (xy 433.739185 -289.876204) (xy 433.794028 -289.866074) (xy 433.849762 -289.864037)
			(xy 433.905199 -289.870137) (xy 433.959156 -289.884243) (xy 434.010485 -289.906055) (xy 434.058091 -289.935109)
			(xy 434.100959 -289.970784) (xy 434.138176 -290.012321) (xy 434.168949 -290.058834) (xy 434.192621 -290.109331)
			(xy 434.208689 -290.162738) (xy 434.216809 -290.217914) (xy 434.21716 -290.237164) (xy 437.464452 -290.237164)
			(xy 437.468523 -290.181542) (xy 437.480649 -290.127105) (xy 437.500572 -290.075014) (xy 437.527868 -290.026379)
			(xy 437.561954 -289.982236) (xy 437.602103 -289.943527) (xy 437.647461 -289.911076) (xy 437.697061 -289.885575)
			(xy 437.749845 -289.867568) (xy 437.804688 -289.857438) (xy 437.860422 -289.855401) (xy 437.915859 -289.861501)
			(xy 437.969816 -289.875607) (xy 438.021145 -289.897419) (xy 438.068751 -289.926473) (xy 438.111619 -289.962148)
			(xy 438.148836 -290.003685) (xy 438.179609 -290.050198) (xy 438.203281 -290.100695) (xy 438.219349 -290.154102)
			(xy 438.227469 -290.209278) (xy 438.227978 -290.237164) (xy 438.227469 -290.26505) (xy 438.219349 -290.320226)
			(xy 438.203281 -290.373633) (xy 438.179609 -290.42413) (xy 438.148836 -290.470643) (xy 438.111619 -290.51218)
			(xy 438.068751 -290.547855) (xy 438.021145 -290.576909) (xy 437.969816 -290.598721) (xy 437.915859 -290.612827)
			(xy 437.860422 -290.618927) (xy 437.804688 -290.61689) (xy 437.749845 -290.60676) (xy 437.697061 -290.588753)
			(xy 437.647461 -290.563252) (xy 437.602103 -290.530801) (xy 437.561954 -290.492092) (xy 437.527868 -290.447949)
			(xy 437.500572 -290.399314) (xy 437.480649 -290.347223) (xy 437.468523 -290.292786) (xy 437.464452 -290.237164)
			(xy 434.21716 -290.237164) (xy 434.217318 -290.2458) (xy 434.216809 -290.273686) (xy 434.208689 -290.328862)
			(xy 434.192621 -290.382269) (xy 434.168949 -290.432766) (xy 434.138176 -290.479279) (xy 434.100959 -290.520816)
			(xy 434.058091 -290.556491) (xy 434.010485 -290.585545) (xy 433.959156 -290.607357) (xy 433.905199 -290.621463)
			(xy 433.849762 -290.627563) (xy 433.794028 -290.625526) (xy 433.739185 -290.615396) (xy 433.686401 -290.597389)
			(xy 433.636801 -290.571888) (xy 433.591443 -290.539437) (xy 433.551294 -290.500728) (xy 433.517208 -290.456585)
			(xy 433.489912 -290.40795) (xy 433.469989 -290.355859) (xy 433.457863 -290.301422) (xy 433.453792 -290.2458)
			(xy 396.990824 -290.2458) (xy 396.990824 -290.273232) (xy 396.990989 -290.279386) (xy 396.993935 -290.291337)
			(xy 396.996666 -290.296854) (xy 397.004794 -290.30803) (xy 397.019526 -290.323524) (xy 397.02613 -290.330636)
			(xy 397.05026 -290.341812) (xy 397.054578 -290.343082) (xy 397.066008 -290.346638) (xy 397.070072 -290.347146)
			(xy 397.096116 -290.351254) (xy 397.146541 -290.366649) (xy 397.193885 -290.389848) (xy 397.236949 -290.420263)
			(xy 397.274643 -290.457126) (xy 397.306012 -290.499501) (xy 397.330262 -290.546316) (xy 397.346777 -290.596385)
			(xy 397.355141 -290.64844) (xy 397.355141 -290.674806) (xy 397.669016 -290.674806) (xy 397.672976 -290.625752)
			(xy 397.684753 -290.577968) (xy 397.704044 -290.532692) (xy 397.730347 -290.491096) (xy 397.762982 -290.454259)
			(xy 397.801103 -290.423134) (xy 397.843724 -290.398527) (xy 397.88974 -290.381075) (xy 397.937959 -290.371231)
			(xy 397.987134 -290.36925) (xy 398.035989 -290.375182) (xy 398.08326 -290.388874) (xy 398.127722 -290.409972)
			(xy 398.168225 -290.437928) (xy 398.203718 -290.47202) (xy 398.233283 -290.511364) (xy 398.256154 -290.554941)
			(xy 398.271738 -290.601622) (xy 398.279633 -290.650199) (xy 398.280128 -290.674806) (xy 398.61923 -290.674806)
			(xy 398.62319 -290.625752) (xy 398.634967 -290.577968) (xy 398.654258 -290.532692) (xy 398.680561 -290.491096)
			(xy 398.713196 -290.454259) (xy 398.751317 -290.423134) (xy 398.793938 -290.398527) (xy 398.839954 -290.381075)
			(xy 398.888173 -290.371231) (xy 398.937348 -290.36925) (xy 398.986203 -290.375182) (xy 399.033474 -290.388874)
			(xy 399.077936 -290.409972) (xy 399.118439 -290.437928) (xy 399.153932 -290.47202) (xy 399.183497 -290.511364)
			(xy 399.206368 -290.554941) (xy 399.221952 -290.601622) (xy 399.229847 -290.650199) (xy 399.230342 -290.674806)
			(xy 399.56919 -290.674806) (xy 399.57315 -290.625752) (xy 399.584927 -290.577968) (xy 399.604218 -290.532692)
			(xy 399.630521 -290.491096) (xy 399.663156 -290.454259) (xy 399.701277 -290.423134) (xy 399.743898 -290.398527)
			(xy 399.789914 -290.381075) (xy 399.838133 -290.371231) (xy 399.887308 -290.36925) (xy 399.936163 -290.375182)
			(xy 399.983434 -290.388874) (xy 400.027896 -290.409972) (xy 400.068399 -290.437928) (xy 400.103892 -290.47202)
			(xy 400.133457 -290.511364) (xy 400.156328 -290.554941) (xy 400.171912 -290.601622) (xy 400.179807 -290.650199)
			(xy 400.180302 -290.674806) (xy 400.51915 -290.674806) (xy 400.52311 -290.625752) (xy 400.534887 -290.577968)
			(xy 400.554178 -290.532692) (xy 400.580481 -290.491096) (xy 400.613116 -290.454259) (xy 400.651237 -290.423134)
			(xy 400.693858 -290.398527) (xy 400.739874 -290.381075) (xy 400.788093 -290.371231) (xy 400.837268 -290.36925)
			(xy 400.886123 -290.375182) (xy 400.933394 -290.388874) (xy 400.977856 -290.409972) (xy 401.018359 -290.437928)
			(xy 401.053852 -290.47202) (xy 401.083417 -290.511364) (xy 401.106288 -290.554941) (xy 401.121872 -290.601622)
			(xy 401.129767 -290.650199) (xy 401.130262 -290.674806) (xy 401.46911 -290.674806) (xy 401.47307 -290.625752)
			(xy 401.484847 -290.577968) (xy 401.504138 -290.532692) (xy 401.530441 -290.491096) (xy 401.563076 -290.454259)
			(xy 401.601197 -290.423134) (xy 401.643818 -290.398527) (xy 401.689834 -290.381075) (xy 401.738053 -290.371231)
			(xy 401.787228 -290.36925) (xy 401.836083 -290.375182) (xy 401.883354 -290.388874) (xy 401.927816 -290.409972)
			(xy 401.968319 -290.437928) (xy 402.003812 -290.47202) (xy 402.033377 -290.511364) (xy 402.056248 -290.554941)
			(xy 402.071832 -290.601622) (xy 402.079727 -290.650199) (xy 402.080222 -290.674806) (xy 402.41907 -290.674806)
			(xy 402.42303 -290.625752) (xy 402.434807 -290.577968) (xy 402.454098 -290.532692) (xy 402.480401 -290.491096)
			(xy 402.513036 -290.454259) (xy 402.551157 -290.423134) (xy 402.593778 -290.398527) (xy 402.639794 -290.381075)
			(xy 402.688013 -290.371231) (xy 402.737188 -290.36925) (xy 402.786043 -290.375182) (xy 402.833314 -290.388874)
			(xy 402.877776 -290.409972) (xy 402.918279 -290.437928) (xy 402.953772 -290.47202) (xy 402.983337 -290.511364)
			(xy 403.006208 -290.554941) (xy 403.021792 -290.601622) (xy 403.029687 -290.650199) (xy 403.030182 -290.674806)
			(xy 403.36903 -290.674806) (xy 403.37299 -290.625752) (xy 403.384767 -290.577968) (xy 403.404058 -290.532692)
			(xy 403.430361 -290.491096) (xy 403.462996 -290.454259) (xy 403.501117 -290.423134) (xy 403.543738 -290.398527)
			(xy 403.589754 -290.381075) (xy 403.637973 -290.371231) (xy 403.687148 -290.36925) (xy 403.736003 -290.375182)
			(xy 403.783274 -290.388874) (xy 403.827736 -290.409972) (xy 403.868239 -290.437928) (xy 403.903732 -290.47202)
			(xy 403.933297 -290.511364) (xy 403.956168 -290.554941) (xy 403.971752 -290.601622) (xy 403.979647 -290.650199)
			(xy 403.980142 -290.674806) (xy 404.31899 -290.674806) (xy 404.32295 -290.625752) (xy 404.334727 -290.577968)
			(xy 404.354018 -290.532692) (xy 404.380321 -290.491096) (xy 404.412956 -290.454259) (xy 404.451077 -290.423134)
			(xy 404.493698 -290.398527) (xy 404.539714 -290.381075) (xy 404.587933 -290.371231) (xy 404.637108 -290.36925)
			(xy 404.685963 -290.375182) (xy 404.733234 -290.388874) (xy 404.777696 -290.409972) (xy 404.818199 -290.437928)
			(xy 404.853692 -290.47202) (xy 404.883257 -290.511364) (xy 404.906128 -290.554941) (xy 404.921712 -290.601622)
			(xy 404.929607 -290.650199) (xy 404.930102 -290.674806) (xy 405.269204 -290.674806) (xy 405.273164 -290.625752)
			(xy 405.284941 -290.577968) (xy 405.304232 -290.532692) (xy 405.330535 -290.491096) (xy 405.36317 -290.454259)
			(xy 405.401291 -290.423134) (xy 405.443912 -290.398527) (xy 405.489928 -290.381075) (xy 405.538147 -290.371231)
			(xy 405.587322 -290.36925) (xy 405.636177 -290.375182) (xy 405.683448 -290.388874) (xy 405.72791 -290.409972)
			(xy 405.768413 -290.437928) (xy 405.803906 -290.47202) (xy 405.833471 -290.511364) (xy 405.856342 -290.554941)
			(xy 405.871926 -290.601622) (xy 405.879821 -290.650199) (xy 405.880316 -290.674806) (xy 406.219164 -290.674806)
			(xy 406.223124 -290.625752) (xy 406.234901 -290.577968) (xy 406.254192 -290.532692) (xy 406.280495 -290.491096)
			(xy 406.31313 -290.454259) (xy 406.351251 -290.423134) (xy 406.393872 -290.398527) (xy 406.439888 -290.381075)
			(xy 406.488107 -290.371231) (xy 406.537282 -290.36925) (xy 406.586137 -290.375182) (xy 406.633408 -290.388874)
			(xy 406.67787 -290.409972) (xy 406.718373 -290.437928) (xy 406.753866 -290.47202) (xy 406.783431 -290.511364)
			(xy 406.806302 -290.554941) (xy 406.821886 -290.601622) (xy 406.829781 -290.650199) (xy 406.830276 -290.674806)
			(xy 408.119084 -290.674806) (xy 408.123044 -290.625752) (xy 408.134821 -290.577968) (xy 408.154112 -290.532692)
			(xy 408.180415 -290.491096) (xy 408.21305 -290.454259) (xy 408.251171 -290.423134) (xy 408.293792 -290.398527)
			(xy 408.339808 -290.381075) (xy 408.388027 -290.371231) (xy 408.437202 -290.36925) (xy 408.486057 -290.375182)
			(xy 408.533328 -290.388874) (xy 408.57779 -290.409972) (xy 408.618293 -290.437928) (xy 408.653786 -290.47202)
			(xy 408.683351 -290.511364) (xy 408.706222 -290.554941) (xy 408.721806 -290.601622) (xy 408.729701 -290.650199)
			(xy 408.730196 -290.674806) (xy 409.069044 -290.674806) (xy 409.073004 -290.625752) (xy 409.084781 -290.577968)
			(xy 409.104072 -290.532692) (xy 409.130375 -290.491096) (xy 409.16301 -290.454259) (xy 409.201131 -290.423134)
			(xy 409.243752 -290.398527) (xy 409.289768 -290.381075) (xy 409.337987 -290.371231) (xy 409.387162 -290.36925)
			(xy 409.436017 -290.375182) (xy 409.483288 -290.388874) (xy 409.52775 -290.409972) (xy 409.568253 -290.437928)
			(xy 409.603746 -290.47202) (xy 409.633311 -290.511364) (xy 409.656182 -290.554941) (xy 409.671766 -290.601622)
			(xy 409.679661 -290.650199) (xy 409.680156 -290.674806) (xy 410.019004 -290.674806) (xy 410.022964 -290.625752)
			(xy 410.034741 -290.577968) (xy 410.054032 -290.532692) (xy 410.080335 -290.491096) (xy 410.11297 -290.454259)
			(xy 410.151091 -290.423134) (xy 410.193712 -290.398527) (xy 410.239728 -290.381075) (xy 410.287947 -290.371231)
			(xy 410.337122 -290.36925) (xy 410.385977 -290.375182) (xy 410.433248 -290.388874) (xy 410.47771 -290.409972)
			(xy 410.518213 -290.437928) (xy 410.553706 -290.47202) (xy 410.583271 -290.511364) (xy 410.606142 -290.554941)
			(xy 410.621726 -290.601622) (xy 410.629621 -290.650199) (xy 410.630116 -290.674806) (xy 410.969218 -290.674806)
			(xy 410.973178 -290.625752) (xy 410.984955 -290.577968) (xy 411.004246 -290.532692) (xy 411.030549 -290.491096)
			(xy 411.063184 -290.454259) (xy 411.101305 -290.423134) (xy 411.143926 -290.398527) (xy 411.189942 -290.381075)
			(xy 411.238161 -290.371231) (xy 411.287336 -290.36925) (xy 411.336191 -290.375182) (xy 411.383462 -290.388874)
			(xy 411.427924 -290.409972) (xy 411.468427 -290.437928) (xy 411.50392 -290.47202) (xy 411.533485 -290.511364)
			(xy 411.556356 -290.554941) (xy 411.57194 -290.601622) (xy 411.579835 -290.650199) (xy 411.58033 -290.674806)
			(xy 411.919178 -290.674806) (xy 411.923138 -290.625752) (xy 411.934915 -290.577968) (xy 411.954206 -290.532692)
			(xy 411.980509 -290.491096) (xy 412.013144 -290.454259) (xy 412.051265 -290.423134) (xy 412.093886 -290.398527)
			(xy 412.139902 -290.381075) (xy 412.188121 -290.371231) (xy 412.237296 -290.36925) (xy 412.286151 -290.375182)
			(xy 412.333422 -290.388874) (xy 412.377884 -290.409972) (xy 412.418387 -290.437928) (xy 412.45388 -290.47202)
			(xy 412.483445 -290.511364) (xy 412.506316 -290.554941) (xy 412.5219 -290.601622) (xy 412.529795 -290.650199)
			(xy 412.53029 -290.674806) (xy 412.869138 -290.674806) (xy 412.873098 -290.625752) (xy 412.884875 -290.577968)
			(xy 412.904166 -290.532692) (xy 412.930469 -290.491096) (xy 412.963104 -290.454259) (xy 413.001225 -290.423134)
			(xy 413.043846 -290.398527) (xy 413.089862 -290.381075) (xy 413.138081 -290.371231) (xy 413.187256 -290.36925)
			(xy 413.236111 -290.375182) (xy 413.283382 -290.388874) (xy 413.327844 -290.409972) (xy 413.368347 -290.437928)
			(xy 413.40384 -290.47202) (xy 413.433405 -290.511364) (xy 413.456276 -290.554941) (xy 413.47186 -290.601622)
			(xy 413.479755 -290.650199) (xy 413.48025 -290.674806) (xy 413.819098 -290.674806) (xy 413.823058 -290.625752)
			(xy 413.834835 -290.577968) (xy 413.854126 -290.532692) (xy 413.880429 -290.491096) (xy 413.913064 -290.454259)
			(xy 413.951185 -290.423134) (xy 413.993806 -290.398527) (xy 414.039822 -290.381075) (xy 414.088041 -290.371231)
			(xy 414.137216 -290.36925) (xy 414.186071 -290.375182) (xy 414.233342 -290.388874) (xy 414.277804 -290.409972)
			(xy 414.318307 -290.437928) (xy 414.3538 -290.47202) (xy 414.383365 -290.511364) (xy 414.406236 -290.554941)
			(xy 414.42182 -290.601622) (xy 414.429715 -290.650199) (xy 414.43021 -290.674806) (xy 414.769058 -290.674806)
			(xy 414.773018 -290.625752) (xy 414.784795 -290.577968) (xy 414.804086 -290.532692) (xy 414.830389 -290.491096)
			(xy 414.863024 -290.454259) (xy 414.901145 -290.423134) (xy 414.943766 -290.398527) (xy 414.989782 -290.381075)
			(xy 415.038001 -290.371231) (xy 415.087176 -290.36925) (xy 415.136031 -290.375182) (xy 415.183302 -290.388874)
			(xy 415.227764 -290.409972) (xy 415.268267 -290.437928) (xy 415.30376 -290.47202) (xy 415.333325 -290.511364)
			(xy 415.356196 -290.554941) (xy 415.37178 -290.601622) (xy 415.379675 -290.650199) (xy 415.38017 -290.674806)
			(xy 415.719018 -290.674806) (xy 415.722978 -290.625752) (xy 415.734755 -290.577968) (xy 415.754046 -290.532692)
			(xy 415.780349 -290.491096) (xy 415.812984 -290.454259) (xy 415.851105 -290.423134) (xy 415.893726 -290.398527)
			(xy 415.939742 -290.381075) (xy 415.987961 -290.371231) (xy 416.037136 -290.36925) (xy 416.085991 -290.375182)
			(xy 416.133262 -290.388874) (xy 416.177724 -290.409972) (xy 416.218227 -290.437928) (xy 416.25372 -290.47202)
			(xy 416.283285 -290.511364) (xy 416.306156 -290.554941) (xy 416.32174 -290.601622) (xy 416.329635 -290.650199)
			(xy 416.33013 -290.674806) (xy 416.668978 -290.674806) (xy 416.672938 -290.625752) (xy 416.684715 -290.577968)
			(xy 416.704006 -290.532692) (xy 416.730309 -290.491096) (xy 416.762944 -290.454259) (xy 416.801065 -290.423134)
			(xy 416.843686 -290.398527) (xy 416.889702 -290.381075) (xy 416.937921 -290.371231) (xy 416.987096 -290.36925)
			(xy 417.035951 -290.375182) (xy 417.083222 -290.388874) (xy 417.127684 -290.409972) (xy 417.168187 -290.437928)
			(xy 417.20368 -290.47202) (xy 417.233245 -290.511364) (xy 417.256116 -290.554941) (xy 417.2717 -290.601622)
			(xy 417.279595 -290.650199) (xy 417.28009 -290.674806) (xy 417.619192 -290.674806) (xy 417.623152 -290.625752)
			(xy 417.634929 -290.577968) (xy 417.65422 -290.532692) (xy 417.680523 -290.491096) (xy 417.713158 -290.454259)
			(xy 417.751279 -290.423134) (xy 417.7939 -290.398527) (xy 417.839916 -290.381075) (xy 417.888135 -290.371231)
			(xy 417.93731 -290.36925) (xy 417.986165 -290.375182) (xy 418.033436 -290.388874) (xy 418.077898 -290.409972)
			(xy 418.118401 -290.437928) (xy 418.153894 -290.47202) (xy 418.183459 -290.511364) (xy 418.20633 -290.554941)
			(xy 418.221914 -290.601622) (xy 418.229809 -290.650199) (xy 418.230304 -290.674806) (xy 418.569152 -290.674806)
			(xy 418.573112 -290.625752) (xy 418.584889 -290.577968) (xy 418.60418 -290.532692) (xy 418.630483 -290.491096)
			(xy 418.663118 -290.454259) (xy 418.701239 -290.423134) (xy 418.74386 -290.398527) (xy 418.789876 -290.381075)
			(xy 418.838095 -290.371231) (xy 418.88727 -290.36925) (xy 418.936125 -290.375182) (xy 418.983396 -290.388874)
			(xy 419.027858 -290.409972) (xy 419.068361 -290.437928) (xy 419.103854 -290.47202) (xy 419.133419 -290.511364)
			(xy 419.15629 -290.554941) (xy 419.171874 -290.601622) (xy 419.179769 -290.650199) (xy 419.180264 -290.674806)
			(xy 419.519112 -290.674806) (xy 419.523072 -290.625752) (xy 419.534849 -290.577968) (xy 419.55414 -290.532692)
			(xy 419.580443 -290.491096) (xy 419.613078 -290.454259) (xy 419.651199 -290.423134) (xy 419.69382 -290.398527)
			(xy 419.739836 -290.381075) (xy 419.788055 -290.371231) (xy 419.83723 -290.36925) (xy 419.886085 -290.375182)
			(xy 419.933356 -290.388874) (xy 419.977818 -290.409972) (xy 420.018321 -290.437928) (xy 420.053814 -290.47202)
			(xy 420.083379 -290.511364) (xy 420.10625 -290.554941) (xy 420.121834 -290.601622) (xy 420.129729 -290.650199)
			(xy 420.130224 -290.674806) (xy 420.469072 -290.674806) (xy 420.473032 -290.625752) (xy 420.484809 -290.577968)
			(xy 420.5041 -290.532692) (xy 420.530403 -290.491096) (xy 420.563038 -290.454259) (xy 420.601159 -290.423134)
			(xy 420.64378 -290.398527) (xy 420.689796 -290.381075) (xy 420.738015 -290.371231) (xy 420.78719 -290.36925)
			(xy 420.836045 -290.375182) (xy 420.883316 -290.388874) (xy 420.927778 -290.409972) (xy 420.968281 -290.437928)
			(xy 421.003774 -290.47202) (xy 421.033339 -290.511364) (xy 421.05621 -290.554941) (xy 421.071794 -290.601622)
			(xy 421.079689 -290.650199) (xy 421.080184 -290.674806) (xy 421.419032 -290.674806) (xy 421.422992 -290.625752)
			(xy 421.434769 -290.577968) (xy 421.45406 -290.532692) (xy 421.480363 -290.491096) (xy 421.512998 -290.454259)
			(xy 421.551119 -290.423134) (xy 421.59374 -290.398527) (xy 421.639756 -290.381075) (xy 421.687975 -290.371231)
			(xy 421.73715 -290.36925) (xy 421.786005 -290.375182) (xy 421.833276 -290.388874) (xy 421.877738 -290.409972)
			(xy 421.918241 -290.437928) (xy 421.953734 -290.47202) (xy 421.983299 -290.511364) (xy 422.00617 -290.554941)
			(xy 422.021754 -290.601622) (xy 422.029649 -290.650199) (xy 422.030144 -290.674806) (xy 422.368992 -290.674806)
			(xy 422.372952 -290.625752) (xy 422.384729 -290.577968) (xy 422.40402 -290.532692) (xy 422.430323 -290.491096)
			(xy 422.462958 -290.454259) (xy 422.501079 -290.423134) (xy 422.5437 -290.398527) (xy 422.589716 -290.381075)
			(xy 422.637935 -290.371231) (xy 422.68711 -290.36925) (xy 422.735965 -290.375182) (xy 422.783236 -290.388874)
			(xy 422.827698 -290.409972) (xy 422.868201 -290.437928) (xy 422.903694 -290.47202) (xy 422.933259 -290.511364)
			(xy 422.95613 -290.554941) (xy 422.971714 -290.601622) (xy 422.979609 -290.650199) (xy 422.980104 -290.674806)
			(xy 423.319206 -290.674806) (xy 423.323166 -290.625752) (xy 423.334943 -290.577968) (xy 423.354234 -290.532692)
			(xy 423.380537 -290.491096) (xy 423.413172 -290.454259) (xy 423.451293 -290.423134) (xy 423.493914 -290.398527)
			(xy 423.53993 -290.381075) (xy 423.588149 -290.371231) (xy 423.637324 -290.36925) (xy 423.686179 -290.375182)
			(xy 423.73345 -290.388874) (xy 423.777912 -290.409972) (xy 423.818415 -290.437928) (xy 423.853908 -290.47202)
			(xy 423.883473 -290.511364) (xy 423.906344 -290.554941) (xy 423.921928 -290.601622) (xy 423.929823 -290.650199)
			(xy 423.930318 -290.674806) (xy 424.269166 -290.674806) (xy 424.273126 -290.625752) (xy 424.284903 -290.577968)
			(xy 424.304194 -290.532692) (xy 424.330497 -290.491096) (xy 424.363132 -290.454259) (xy 424.401253 -290.423134)
			(xy 424.443874 -290.398527) (xy 424.48989 -290.381075) (xy 424.538109 -290.371231) (xy 424.587284 -290.36925)
			(xy 424.636139 -290.375182) (xy 424.68341 -290.388874) (xy 424.727872 -290.409972) (xy 424.768375 -290.437928)
			(xy 424.803868 -290.47202) (xy 424.833433 -290.511364) (xy 424.856304 -290.554941) (xy 424.871888 -290.601622)
			(xy 424.879783 -290.650199) (xy 424.880278 -290.674806) (xy 425.219126 -290.674806) (xy 425.223086 -290.625752)
			(xy 425.234863 -290.577968) (xy 425.254154 -290.532692) (xy 425.280457 -290.491096) (xy 425.313092 -290.454259)
			(xy 425.351213 -290.423134) (xy 425.393834 -290.398527) (xy 425.43985 -290.381075) (xy 425.488069 -290.371231)
			(xy 425.537244 -290.36925) (xy 425.586099 -290.375182) (xy 425.63337 -290.388874) (xy 425.677832 -290.409972)
			(xy 425.718335 -290.437928) (xy 425.753828 -290.47202) (xy 425.783393 -290.511364) (xy 425.806264 -290.554941)
			(xy 425.821848 -290.601622) (xy 425.829743 -290.650199) (xy 425.830238 -290.674806) (xy 426.169086 -290.674806)
			(xy 426.173046 -290.625752) (xy 426.184823 -290.577968) (xy 426.204114 -290.532692) (xy 426.230417 -290.491096)
			(xy 426.263052 -290.454259) (xy 426.301173 -290.423134) (xy 426.343794 -290.398527) (xy 426.38981 -290.381075)
			(xy 426.438029 -290.371231) (xy 426.487204 -290.36925) (xy 426.536059 -290.375182) (xy 426.58333 -290.388874)
			(xy 426.627792 -290.409972) (xy 426.668295 -290.437928) (xy 426.703788 -290.47202) (xy 426.733353 -290.511364)
			(xy 426.756224 -290.554941) (xy 426.771808 -290.601622) (xy 426.779703 -290.650199) (xy 426.780198 -290.674806)
			(xy 427.119046 -290.674806) (xy 427.123006 -290.625752) (xy 427.134783 -290.577968) (xy 427.154074 -290.532692)
			(xy 427.180377 -290.491096) (xy 427.213012 -290.454259) (xy 427.251133 -290.423134) (xy 427.293754 -290.398527)
			(xy 427.33977 -290.381075) (xy 427.387989 -290.371231) (xy 427.437164 -290.36925) (xy 427.486019 -290.375182)
			(xy 427.53329 -290.388874) (xy 427.577752 -290.409972) (xy 427.618255 -290.437928) (xy 427.653748 -290.47202)
			(xy 427.683313 -290.511364) (xy 427.706184 -290.554941) (xy 427.721768 -290.601622) (xy 427.729663 -290.650199)
			(xy 427.730158 -290.674806) (xy 428.069006 -290.674806) (xy 428.072966 -290.625752) (xy 428.084743 -290.577968)
			(xy 428.104034 -290.532692) (xy 428.130337 -290.491096) (xy 428.162972 -290.454259) (xy 428.201093 -290.423134)
			(xy 428.243714 -290.398527) (xy 428.28973 -290.381075) (xy 428.337949 -290.371231) (xy 428.387124 -290.36925)
			(xy 428.435979 -290.375182) (xy 428.48325 -290.388874) (xy 428.527712 -290.409972) (xy 428.568215 -290.437928)
			(xy 428.603708 -290.47202) (xy 428.633273 -290.511364) (xy 428.656144 -290.554941) (xy 428.671728 -290.601622)
			(xy 428.679623 -290.650199) (xy 428.680118 -290.674806) (xy 429.01922 -290.674806) (xy 429.02318 -290.625752)
			(xy 429.034957 -290.577968) (xy 429.054248 -290.532692) (xy 429.080551 -290.491096) (xy 429.113186 -290.454259)
			(xy 429.151307 -290.423134) (xy 429.193928 -290.398527) (xy 429.239944 -290.381075) (xy 429.288163 -290.371231)
			(xy 429.337338 -290.36925) (xy 429.386193 -290.375182) (xy 429.433464 -290.388874) (xy 429.477926 -290.409972)
			(xy 429.518429 -290.437928) (xy 429.553922 -290.47202) (xy 429.583487 -290.511364) (xy 429.606358 -290.554941)
			(xy 429.621942 -290.601622) (xy 429.629837 -290.650199) (xy 429.630332 -290.674806) (xy 429.96918 -290.674806)
			(xy 429.97314 -290.625752) (xy 429.984917 -290.577968) (xy 430.004208 -290.532692) (xy 430.030511 -290.491096)
			(xy 430.063146 -290.454259) (xy 430.101267 -290.423134) (xy 430.143888 -290.398527) (xy 430.189904 -290.381075)
			(xy 430.238123 -290.371231) (xy 430.287298 -290.36925) (xy 430.336153 -290.375182) (xy 430.383424 -290.388874)
			(xy 430.427886 -290.409972) (xy 430.468389 -290.437928) (xy 430.503882 -290.47202) (xy 430.533447 -290.511364)
			(xy 430.556318 -290.554941) (xy 430.571902 -290.601622) (xy 430.579797 -290.650199) (xy 430.580292 -290.674806)
			(xy 430.91914 -290.674806) (xy 430.9231 -290.625752) (xy 430.934877 -290.577968) (xy 430.954168 -290.532692)
			(xy 430.980471 -290.491096) (xy 431.013106 -290.454259) (xy 431.051227 -290.423134) (xy 431.093848 -290.398527)
			(xy 431.139864 -290.381075) (xy 431.188083 -290.371231) (xy 431.237258 -290.36925) (xy 431.286113 -290.375182)
			(xy 431.333384 -290.388874) (xy 431.377846 -290.409972) (xy 431.418349 -290.437928) (xy 431.453842 -290.47202)
			(xy 431.483407 -290.511364) (xy 431.506278 -290.554941) (xy 431.521862 -290.601622) (xy 431.529757 -290.650199)
			(xy 431.530252 -290.674806) (xy 431.529757 -290.699413) (xy 431.521862 -290.74799) (xy 431.506278 -290.794671)
			(xy 431.485192 -290.834847) (xy 458.605926 -290.834847) (xy 458.605926 -290.780353) (xy 458.613681 -290.726413)
			(xy 458.629034 -290.674125) (xy 458.651672 -290.624555) (xy 458.681133 -290.578711) (xy 458.716819 -290.537526)
			(xy 458.758003 -290.501839) (xy 458.803846 -290.472376) (xy 458.853416 -290.449738) (xy 458.905703 -290.434384)
			(xy 458.959643 -290.426627) (xy 458.98689 -290.42614) (xy 459.01426 -290.426602) (xy 459.06844 -290.434419)
			(xy 459.120944 -290.449909) (xy 459.17069 -290.472752) (xy 459.216657 -290.502478) (xy 459.237588 -290.52012)
			(xy 459.2447 -290.526216) (xy 459.261718 -290.532566) (xy 459.347062 -290.532566) (xy 459.36408 -290.526216)
			(xy 459.371192 -290.52012) (xy 459.392119 -290.502474) (xy 459.438093 -290.472763) (xy 459.487842 -290.449928)
			(xy 459.540344 -290.434438) (xy 459.59452 -290.426613) (xy 459.62189 -290.42614) (xy 459.649147 -290.426506)
			(xy 459.703106 -290.434263) (xy 459.755411 -290.44962) (xy 459.804999 -290.472265) (xy 459.850859 -290.501736)
			(xy 459.892058 -290.537435) (xy 459.927758 -290.578633) (xy 459.95723 -290.624492) (xy 459.979876 -290.674079)
			(xy 459.995235 -290.726385) (xy 460.002993 -290.780343) (xy 460.002993 -290.834847) (xy 460.345826 -290.834847)
			(xy 460.345826 -290.780353) (xy 460.353581 -290.726413) (xy 460.368934 -290.674125) (xy 460.391572 -290.624555)
			(xy 460.421033 -290.578711) (xy 460.456719 -290.537526) (xy 460.497903 -290.501839) (xy 460.543746 -290.472376)
			(xy 460.593316 -290.449738) (xy 460.645603 -290.434384) (xy 460.699543 -290.426627) (xy 460.72679 -290.42614)
			(xy 460.75416 -290.426602) (xy 460.80834 -290.434419) (xy 460.860844 -290.449909) (xy 460.91059 -290.472752)
			(xy 460.956557 -290.502478) (xy 460.977488 -290.52012) (xy 460.9846 -290.526216) (xy 461.001618 -290.532566)
			(xy 461.086962 -290.532566) (xy 461.10398 -290.526216) (xy 461.111092 -290.52012) (xy 461.132019 -290.502474)
			(xy 461.177993 -290.472763) (xy 461.227742 -290.449928) (xy 461.280244 -290.434438) (xy 461.33442 -290.426613)
			(xy 461.36179 -290.42614) (xy 461.389047 -290.426506) (xy 461.443006 -290.434263) (xy 461.495311 -290.44962)
			(xy 461.544899 -290.472265) (xy 461.590759 -290.501736) (xy 461.631958 -290.537435) (xy 461.667658 -290.578633)
			(xy 461.69713 -290.624492) (xy 461.719776 -290.674079) (xy 461.735135 -290.726385) (xy 461.742893 -290.780343)
			(xy 461.742893 -290.834857) (xy 461.735135 -290.888815) (xy 461.719776 -290.941121) (xy 461.69713 -290.990708)
			(xy 461.667658 -291.036567) (xy 461.631958 -291.077765) (xy 461.590759 -291.113464) (xy 461.544899 -291.142935)
			(xy 461.495311 -291.16558) (xy 461.443006 -291.180937) (xy 461.389047 -291.188694) (xy 461.36179 -291.189156)
			(xy 461.334419 -291.188707) (xy 461.280239 -291.180886) (xy 461.227735 -291.165394) (xy 461.177988 -291.142548)
			(xy 461.132023 -291.112819) (xy 461.111092 -291.095176) (xy 461.10398 -291.08908) (xy 461.086962 -291.08273)
			(xy 461.001618 -291.08273) (xy 460.9846 -291.08908) (xy 460.977488 -291.095176) (xy 460.95653 -291.112784)
			(xy 460.910565 -291.142501) (xy 460.860824 -291.165343) (xy 460.808329 -291.180842) (xy 460.754157 -291.188678)
			(xy 460.72679 -291.189156) (xy 460.699543 -291.188573) (xy 460.645603 -291.180816) (xy 460.593316 -291.165462)
			(xy 460.543746 -291.142824) (xy 460.497903 -291.113361) (xy 460.456719 -291.077674) (xy 460.421033 -291.036489)
			(xy 460.391572 -290.990645) (xy 460.368934 -290.941075) (xy 460.353581 -290.888787) (xy 460.345826 -290.834847)
			(xy 460.002993 -290.834847) (xy 460.002993 -290.834857) (xy 459.995235 -290.888815) (xy 459.979876 -290.941121)
			(xy 459.95723 -290.990708) (xy 459.927758 -291.036567) (xy 459.892058 -291.077765) (xy 459.850859 -291.113464)
			(xy 459.804999 -291.142935) (xy 459.755411 -291.16558) (xy 459.703106 -291.180937) (xy 459.649147 -291.188694)
			(xy 459.62189 -291.189156) (xy 459.594519 -291.188707) (xy 459.540339 -291.180886) (xy 459.487835 -291.165394)
			(xy 459.438088 -291.142548) (xy 459.392123 -291.112819) (xy 459.371192 -291.095176) (xy 459.36408 -291.08908)
			(xy 459.347062 -291.08273) (xy 459.261718 -291.08273) (xy 459.2447 -291.08908) (xy 459.237588 -291.095176)
			(xy 459.21663 -291.112784) (xy 459.170665 -291.142501) (xy 459.120924 -291.165343) (xy 459.068429 -291.180842)
			(xy 459.014257 -291.188678) (xy 458.98689 -291.189156) (xy 458.959643 -291.188573) (xy 458.905703 -291.180816)
			(xy 458.853416 -291.165462) (xy 458.803846 -291.142824) (xy 458.758003 -291.113361) (xy 458.716819 -291.077674)
			(xy 458.681133 -291.036489) (xy 458.651672 -290.990645) (xy 458.629034 -290.941075) (xy 458.613681 -290.888787)
			(xy 458.605926 -290.834847) (xy 431.485192 -290.834847) (xy 431.483407 -290.838248) (xy 431.453842 -290.877592)
			(xy 431.418349 -290.911684) (xy 431.377846 -290.93964) (xy 431.333384 -290.960738) (xy 431.286113 -290.97443)
			(xy 431.237258 -290.980362) (xy 431.188083 -290.978381) (xy 431.139864 -290.968537) (xy 431.093848 -290.951085)
			(xy 431.051227 -290.926478) (xy 431.013106 -290.895353) (xy 430.980471 -290.858516) (xy 430.954168 -290.81692)
			(xy 430.934877 -290.771644) (xy 430.9231 -290.72386) (xy 430.91914 -290.674806) (xy 430.580292 -290.674806)
			(xy 430.579797 -290.699413) (xy 430.571902 -290.74799) (xy 430.556318 -290.794671) (xy 430.533447 -290.838248)
			(xy 430.503882 -290.877592) (xy 430.468389 -290.911684) (xy 430.427886 -290.93964) (xy 430.383424 -290.960738)
			(xy 430.336153 -290.97443) (xy 430.287298 -290.980362) (xy 430.238123 -290.978381) (xy 430.189904 -290.968537)
			(xy 430.143888 -290.951085) (xy 430.101267 -290.926478) (xy 430.063146 -290.895353) (xy 430.030511 -290.858516)
			(xy 430.004208 -290.81692) (xy 429.984917 -290.771644) (xy 429.97314 -290.72386) (xy 429.96918 -290.674806)
			(xy 429.630332 -290.674806) (xy 429.629837 -290.699413) (xy 429.621942 -290.74799) (xy 429.606358 -290.794671)
			(xy 429.583487 -290.838248) (xy 429.553922 -290.877592) (xy 429.518429 -290.911684) (xy 429.477926 -290.93964)
			(xy 429.433464 -290.960738) (xy 429.386193 -290.97443) (xy 429.337338 -290.980362) (xy 429.288163 -290.978381)
			(xy 429.239944 -290.968537) (xy 429.193928 -290.951085) (xy 429.151307 -290.926478) (xy 429.113186 -290.895353)
			(xy 429.080551 -290.858516) (xy 429.054248 -290.81692) (xy 429.034957 -290.771644) (xy 429.02318 -290.72386)
			(xy 429.01922 -290.674806) (xy 428.680118 -290.674806) (xy 428.679623 -290.699413) (xy 428.671728 -290.74799)
			(xy 428.656144 -290.794671) (xy 428.633273 -290.838248) (xy 428.603708 -290.877592) (xy 428.568215 -290.911684)
			(xy 428.527712 -290.93964) (xy 428.48325 -290.960738) (xy 428.435979 -290.97443) (xy 428.387124 -290.980362)
			(xy 428.337949 -290.978381) (xy 428.28973 -290.968537) (xy 428.243714 -290.951085) (xy 428.201093 -290.926478)
			(xy 428.162972 -290.895353) (xy 428.130337 -290.858516) (xy 428.104034 -290.81692) (xy 428.084743 -290.771644)
			(xy 428.072966 -290.72386) (xy 428.069006 -290.674806) (xy 427.730158 -290.674806) (xy 427.729663 -290.699413)
			(xy 427.721768 -290.74799) (xy 427.706184 -290.794671) (xy 427.683313 -290.838248) (xy 427.653748 -290.877592)
			(xy 427.618255 -290.911684) (xy 427.577752 -290.93964) (xy 427.53329 -290.960738) (xy 427.486019 -290.97443)
			(xy 427.437164 -290.980362) (xy 427.387989 -290.978381) (xy 427.33977 -290.968537) (xy 427.293754 -290.951085)
			(xy 427.251133 -290.926478) (xy 427.213012 -290.895353) (xy 427.180377 -290.858516) (xy 427.154074 -290.81692)
			(xy 427.134783 -290.771644) (xy 427.123006 -290.72386) (xy 427.119046 -290.674806) (xy 426.780198 -290.674806)
			(xy 426.779703 -290.699413) (xy 426.771808 -290.74799) (xy 426.756224 -290.794671) (xy 426.733353 -290.838248)
			(xy 426.703788 -290.877592) (xy 426.668295 -290.911684) (xy 426.627792 -290.93964) (xy 426.58333 -290.960738)
			(xy 426.536059 -290.97443) (xy 426.487204 -290.980362) (xy 426.438029 -290.978381) (xy 426.38981 -290.968537)
			(xy 426.343794 -290.951085) (xy 426.301173 -290.926478) (xy 426.263052 -290.895353) (xy 426.230417 -290.858516)
			(xy 426.204114 -290.81692) (xy 426.184823 -290.771644) (xy 426.173046 -290.72386) (xy 426.169086 -290.674806)
			(xy 425.830238 -290.674806) (xy 425.829743 -290.699413) (xy 425.821848 -290.74799) (xy 425.806264 -290.794671)
			(xy 425.783393 -290.838248) (xy 425.753828 -290.877592) (xy 425.718335 -290.911684) (xy 425.677832 -290.93964)
			(xy 425.63337 -290.960738) (xy 425.586099 -290.97443) (xy 425.537244 -290.980362) (xy 425.488069 -290.978381)
			(xy 425.43985 -290.968537) (xy 425.393834 -290.951085) (xy 425.351213 -290.926478) (xy 425.313092 -290.895353)
			(xy 425.280457 -290.858516) (xy 425.254154 -290.81692) (xy 425.234863 -290.771644) (xy 425.223086 -290.72386)
			(xy 425.219126 -290.674806) (xy 424.880278 -290.674806) (xy 424.879783 -290.699413) (xy 424.871888 -290.74799)
			(xy 424.856304 -290.794671) (xy 424.833433 -290.838248) (xy 424.803868 -290.877592) (xy 424.768375 -290.911684)
			(xy 424.727872 -290.93964) (xy 424.68341 -290.960738) (xy 424.636139 -290.97443) (xy 424.587284 -290.980362)
			(xy 424.538109 -290.978381) (xy 424.48989 -290.968537) (xy 424.443874 -290.951085) (xy 424.401253 -290.926478)
			(xy 424.363132 -290.895353) (xy 424.330497 -290.858516) (xy 424.304194 -290.81692) (xy 424.284903 -290.771644)
			(xy 424.273126 -290.72386) (xy 424.269166 -290.674806) (xy 423.930318 -290.674806) (xy 423.929823 -290.699413)
			(xy 423.921928 -290.74799) (xy 423.906344 -290.794671) (xy 423.883473 -290.838248) (xy 423.853908 -290.877592)
			(xy 423.818415 -290.911684) (xy 423.777912 -290.93964) (xy 423.73345 -290.960738) (xy 423.686179 -290.97443)
			(xy 423.637324 -290.980362) (xy 423.588149 -290.978381) (xy 423.53993 -290.968537) (xy 423.493914 -290.951085)
			(xy 423.451293 -290.926478) (xy 423.413172 -290.895353) (xy 423.380537 -290.858516) (xy 423.354234 -290.81692)
			(xy 423.334943 -290.771644) (xy 423.323166 -290.72386) (xy 423.319206 -290.674806) (xy 422.980104 -290.674806)
			(xy 422.979609 -290.699413) (xy 422.971714 -290.74799) (xy 422.95613 -290.794671) (xy 422.933259 -290.838248)
			(xy 422.903694 -290.877592) (xy 422.868201 -290.911684) (xy 422.827698 -290.93964) (xy 422.783236 -290.960738)
			(xy 422.735965 -290.97443) (xy 422.68711 -290.980362) (xy 422.637935 -290.978381) (xy 422.589716 -290.968537)
			(xy 422.5437 -290.951085) (xy 422.501079 -290.926478) (xy 422.462958 -290.895353) (xy 422.430323 -290.858516)
			(xy 422.40402 -290.81692) (xy 422.384729 -290.771644) (xy 422.372952 -290.72386) (xy 422.368992 -290.674806)
			(xy 422.030144 -290.674806) (xy 422.029649 -290.699413) (xy 422.021754 -290.74799) (xy 422.00617 -290.794671)
			(xy 421.983299 -290.838248) (xy 421.953734 -290.877592) (xy 421.918241 -290.911684) (xy 421.877738 -290.93964)
			(xy 421.833276 -290.960738) (xy 421.786005 -290.97443) (xy 421.73715 -290.980362) (xy 421.687975 -290.978381)
			(xy 421.639756 -290.968537) (xy 421.59374 -290.951085) (xy 421.551119 -290.926478) (xy 421.512998 -290.895353)
			(xy 421.480363 -290.858516) (xy 421.45406 -290.81692) (xy 421.434769 -290.771644) (xy 421.422992 -290.72386)
			(xy 421.419032 -290.674806) (xy 421.080184 -290.674806) (xy 421.079689 -290.699413) (xy 421.071794 -290.74799)
			(xy 421.05621 -290.794671) (xy 421.033339 -290.838248) (xy 421.003774 -290.877592) (xy 420.968281 -290.911684)
			(xy 420.927778 -290.93964) (xy 420.883316 -290.960738) (xy 420.836045 -290.97443) (xy 420.78719 -290.980362)
			(xy 420.738015 -290.978381) (xy 420.689796 -290.968537) (xy 420.64378 -290.951085) (xy 420.601159 -290.926478)
			(xy 420.563038 -290.895353) (xy 420.530403 -290.858516) (xy 420.5041 -290.81692) (xy 420.484809 -290.771644)
			(xy 420.473032 -290.72386) (xy 420.469072 -290.674806) (xy 420.130224 -290.674806) (xy 420.129729 -290.699413)
			(xy 420.121834 -290.74799) (xy 420.10625 -290.794671) (xy 420.083379 -290.838248) (xy 420.053814 -290.877592)
			(xy 420.018321 -290.911684) (xy 419.977818 -290.93964) (xy 419.933356 -290.960738) (xy 419.886085 -290.97443)
			(xy 419.83723 -290.980362) (xy 419.788055 -290.978381) (xy 419.739836 -290.968537) (xy 419.69382 -290.951085)
			(xy 419.651199 -290.926478) (xy 419.613078 -290.895353) (xy 419.580443 -290.858516) (xy 419.55414 -290.81692)
			(xy 419.534849 -290.771644) (xy 419.523072 -290.72386) (xy 419.519112 -290.674806) (xy 419.180264 -290.674806)
			(xy 419.179769 -290.699413) (xy 419.171874 -290.74799) (xy 419.15629 -290.794671) (xy 419.133419 -290.838248)
			(xy 419.103854 -290.877592) (xy 419.068361 -290.911684) (xy 419.027858 -290.93964) (xy 418.983396 -290.960738)
			(xy 418.936125 -290.97443) (xy 418.88727 -290.980362) (xy 418.838095 -290.978381) (xy 418.789876 -290.968537)
			(xy 418.74386 -290.951085) (xy 418.701239 -290.926478) (xy 418.663118 -290.895353) (xy 418.630483 -290.858516)
			(xy 418.60418 -290.81692) (xy 418.584889 -290.771644) (xy 418.573112 -290.72386) (xy 418.569152 -290.674806)
			(xy 418.230304 -290.674806) (xy 418.229809 -290.699413) (xy 418.221914 -290.74799) (xy 418.20633 -290.794671)
			(xy 418.183459 -290.838248) (xy 418.153894 -290.877592) (xy 418.118401 -290.911684) (xy 418.077898 -290.93964)
			(xy 418.033436 -290.960738) (xy 417.986165 -290.97443) (xy 417.93731 -290.980362) (xy 417.888135 -290.978381)
			(xy 417.839916 -290.968537) (xy 417.7939 -290.951085) (xy 417.751279 -290.926478) (xy 417.713158 -290.895353)
			(xy 417.680523 -290.858516) (xy 417.65422 -290.81692) (xy 417.634929 -290.771644) (xy 417.623152 -290.72386)
			(xy 417.619192 -290.674806) (xy 417.28009 -290.674806) (xy 417.279595 -290.699413) (xy 417.2717 -290.74799)
			(xy 417.256116 -290.794671) (xy 417.233245 -290.838248) (xy 417.20368 -290.877592) (xy 417.168187 -290.911684)
			(xy 417.127684 -290.93964) (xy 417.083222 -290.960738) (xy 417.035951 -290.97443) (xy 416.987096 -290.980362)
			(xy 416.937921 -290.978381) (xy 416.889702 -290.968537) (xy 416.843686 -290.951085) (xy 416.801065 -290.926478)
			(xy 416.762944 -290.895353) (xy 416.730309 -290.858516) (xy 416.704006 -290.81692) (xy 416.684715 -290.771644)
			(xy 416.672938 -290.72386) (xy 416.668978 -290.674806) (xy 416.33013 -290.674806) (xy 416.329635 -290.699413)
			(xy 416.32174 -290.74799) (xy 416.306156 -290.794671) (xy 416.283285 -290.838248) (xy 416.25372 -290.877592)
			(xy 416.218227 -290.911684) (xy 416.177724 -290.93964) (xy 416.133262 -290.960738) (xy 416.085991 -290.97443)
			(xy 416.037136 -290.980362) (xy 415.987961 -290.978381) (xy 415.939742 -290.968537) (xy 415.893726 -290.951085)
			(xy 415.851105 -290.926478) (xy 415.812984 -290.895353) (xy 415.780349 -290.858516) (xy 415.754046 -290.81692)
			(xy 415.734755 -290.771644) (xy 415.722978 -290.72386) (xy 415.719018 -290.674806) (xy 415.38017 -290.674806)
			(xy 415.379675 -290.699413) (xy 415.37178 -290.74799) (xy 415.356196 -290.794671) (xy 415.333325 -290.838248)
			(xy 415.30376 -290.877592) (xy 415.268267 -290.911684) (xy 415.227764 -290.93964) (xy 415.183302 -290.960738)
			(xy 415.136031 -290.97443) (xy 415.087176 -290.980362) (xy 415.038001 -290.978381) (xy 414.989782 -290.968537)
			(xy 414.943766 -290.951085) (xy 414.901145 -290.926478) (xy 414.863024 -290.895353) (xy 414.830389 -290.858516)
			(xy 414.804086 -290.81692) (xy 414.784795 -290.771644) (xy 414.773018 -290.72386) (xy 414.769058 -290.674806)
			(xy 414.43021 -290.674806) (xy 414.429715 -290.699413) (xy 414.42182 -290.74799) (xy 414.406236 -290.794671)
			(xy 414.383365 -290.838248) (xy 414.3538 -290.877592) (xy 414.318307 -290.911684) (xy 414.277804 -290.93964)
			(xy 414.233342 -290.960738) (xy 414.186071 -290.97443) (xy 414.137216 -290.980362) (xy 414.088041 -290.978381)
			(xy 414.039822 -290.968537) (xy 413.993806 -290.951085) (xy 413.951185 -290.926478) (xy 413.913064 -290.895353)
			(xy 413.880429 -290.858516) (xy 413.854126 -290.81692) (xy 413.834835 -290.771644) (xy 413.823058 -290.72386)
			(xy 413.819098 -290.674806) (xy 413.48025 -290.674806) (xy 413.479755 -290.699413) (xy 413.47186 -290.74799)
			(xy 413.456276 -290.794671) (xy 413.433405 -290.838248) (xy 413.40384 -290.877592) (xy 413.368347 -290.911684)
			(xy 413.327844 -290.93964) (xy 413.283382 -290.960738) (xy 413.236111 -290.97443) (xy 413.187256 -290.980362)
			(xy 413.138081 -290.978381) (xy 413.089862 -290.968537) (xy 413.043846 -290.951085) (xy 413.001225 -290.926478)
			(xy 412.963104 -290.895353) (xy 412.930469 -290.858516) (xy 412.904166 -290.81692) (xy 412.884875 -290.771644)
			(xy 412.873098 -290.72386) (xy 412.869138 -290.674806) (xy 412.53029 -290.674806) (xy 412.529795 -290.699413)
			(xy 412.5219 -290.74799) (xy 412.506316 -290.794671) (xy 412.483445 -290.838248) (xy 412.45388 -290.877592)
			(xy 412.418387 -290.911684) (xy 412.377884 -290.93964) (xy 412.333422 -290.960738) (xy 412.286151 -290.97443)
			(xy 412.237296 -290.980362) (xy 412.188121 -290.978381) (xy 412.139902 -290.968537) (xy 412.093886 -290.951085)
			(xy 412.051265 -290.926478) (xy 412.013144 -290.895353) (xy 411.980509 -290.858516) (xy 411.954206 -290.81692)
			(xy 411.934915 -290.771644) (xy 411.923138 -290.72386) (xy 411.919178 -290.674806) (xy 411.58033 -290.674806)
			(xy 411.579835 -290.699413) (xy 411.57194 -290.74799) (xy 411.556356 -290.794671) (xy 411.533485 -290.838248)
			(xy 411.50392 -290.877592) (xy 411.468427 -290.911684) (xy 411.427924 -290.93964) (xy 411.383462 -290.960738)
			(xy 411.336191 -290.97443) (xy 411.287336 -290.980362) (xy 411.238161 -290.978381) (xy 411.189942 -290.968537)
			(xy 411.143926 -290.951085) (xy 411.101305 -290.926478) (xy 411.063184 -290.895353) (xy 411.030549 -290.858516)
			(xy 411.004246 -290.81692) (xy 410.984955 -290.771644) (xy 410.973178 -290.72386) (xy 410.969218 -290.674806)
			(xy 410.630116 -290.674806) (xy 410.629621 -290.699413) (xy 410.621726 -290.74799) (xy 410.606142 -290.794671)
			(xy 410.583271 -290.838248) (xy 410.553706 -290.877592) (xy 410.518213 -290.911684) (xy 410.47771 -290.93964)
			(xy 410.433248 -290.960738) (xy 410.385977 -290.97443) (xy 410.337122 -290.980362) (xy 410.287947 -290.978381)
			(xy 410.239728 -290.968537) (xy 410.193712 -290.951085) (xy 410.151091 -290.926478) (xy 410.11297 -290.895353)
			(xy 410.080335 -290.858516) (xy 410.054032 -290.81692) (xy 410.034741 -290.771644) (xy 410.022964 -290.72386)
			(xy 410.019004 -290.674806) (xy 409.680156 -290.674806) (xy 409.679661 -290.699413) (xy 409.671766 -290.74799)
			(xy 409.656182 -290.794671) (xy 409.633311 -290.838248) (xy 409.603746 -290.877592) (xy 409.568253 -290.911684)
			(xy 409.52775 -290.93964) (xy 409.483288 -290.960738) (xy 409.436017 -290.97443) (xy 409.387162 -290.980362)
			(xy 409.337987 -290.978381) (xy 409.289768 -290.968537) (xy 409.243752 -290.951085) (xy 409.201131 -290.926478)
			(xy 409.16301 -290.895353) (xy 409.130375 -290.858516) (xy 409.104072 -290.81692) (xy 409.084781 -290.771644)
			(xy 409.073004 -290.72386) (xy 409.069044 -290.674806) (xy 408.730196 -290.674806) (xy 408.729701 -290.699413)
			(xy 408.721806 -290.74799) (xy 408.706222 -290.794671) (xy 408.683351 -290.838248) (xy 408.653786 -290.877592)
			(xy 408.618293 -290.911684) (xy 408.57779 -290.93964) (xy 408.533328 -290.960738) (xy 408.486057 -290.97443)
			(xy 408.437202 -290.980362) (xy 408.388027 -290.978381) (xy 408.339808 -290.968537) (xy 408.293792 -290.951085)
			(xy 408.251171 -290.926478) (xy 408.21305 -290.895353) (xy 408.180415 -290.858516) (xy 408.154112 -290.81692)
			(xy 408.134821 -290.771644) (xy 408.123044 -290.72386) (xy 408.119084 -290.674806) (xy 406.830276 -290.674806)
			(xy 406.829781 -290.699413) (xy 406.821886 -290.74799) (xy 406.806302 -290.794671) (xy 406.783431 -290.838248)
			(xy 406.753866 -290.877592) (xy 406.718373 -290.911684) (xy 406.67787 -290.93964) (xy 406.633408 -290.960738)
			(xy 406.586137 -290.97443) (xy 406.537282 -290.980362) (xy 406.488107 -290.978381) (xy 406.439888 -290.968537)
			(xy 406.393872 -290.951085) (xy 406.351251 -290.926478) (xy 406.31313 -290.895353) (xy 406.280495 -290.858516)
			(xy 406.254192 -290.81692) (xy 406.234901 -290.771644) (xy 406.223124 -290.72386) (xy 406.219164 -290.674806)
			(xy 405.880316 -290.674806) (xy 405.879821 -290.699413) (xy 405.871926 -290.74799) (xy 405.856342 -290.794671)
			(xy 405.833471 -290.838248) (xy 405.803906 -290.877592) (xy 405.768413 -290.911684) (xy 405.72791 -290.93964)
			(xy 405.683448 -290.960738) (xy 405.636177 -290.97443) (xy 405.587322 -290.980362) (xy 405.538147 -290.978381)
			(xy 405.489928 -290.968537) (xy 405.443912 -290.951085) (xy 405.401291 -290.926478) (xy 405.36317 -290.895353)
			(xy 405.330535 -290.858516) (xy 405.304232 -290.81692) (xy 405.284941 -290.771644) (xy 405.273164 -290.72386)
			(xy 405.269204 -290.674806) (xy 404.930102 -290.674806) (xy 404.929607 -290.699413) (xy 404.921712 -290.74799)
			(xy 404.906128 -290.794671) (xy 404.883257 -290.838248) (xy 404.853692 -290.877592) (xy 404.818199 -290.911684)
			(xy 404.777696 -290.93964) (xy 404.733234 -290.960738) (xy 404.685963 -290.97443) (xy 404.637108 -290.980362)
			(xy 404.587933 -290.978381) (xy 404.539714 -290.968537) (xy 404.493698 -290.951085) (xy 404.451077 -290.926478)
			(xy 404.412956 -290.895353) (xy 404.380321 -290.858516) (xy 404.354018 -290.81692) (xy 404.334727 -290.771644)
			(xy 404.32295 -290.72386) (xy 404.31899 -290.674806) (xy 403.980142 -290.674806) (xy 403.979647 -290.699413)
			(xy 403.971752 -290.74799) (xy 403.956168 -290.794671) (xy 403.933297 -290.838248) (xy 403.903732 -290.877592)
			(xy 403.868239 -290.911684) (xy 403.827736 -290.93964) (xy 403.783274 -290.960738) (xy 403.736003 -290.97443)
			(xy 403.687148 -290.980362) (xy 403.637973 -290.978381) (xy 403.589754 -290.968537) (xy 403.543738 -290.951085)
			(xy 403.501117 -290.926478) (xy 403.462996 -290.895353) (xy 403.430361 -290.858516) (xy 403.404058 -290.81692)
			(xy 403.384767 -290.771644) (xy 403.37299 -290.72386) (xy 403.36903 -290.674806) (xy 403.030182 -290.674806)
			(xy 403.029687 -290.699413) (xy 403.021792 -290.74799) (xy 403.006208 -290.794671) (xy 402.983337 -290.838248)
			(xy 402.953772 -290.877592) (xy 402.918279 -290.911684) (xy 402.877776 -290.93964) (xy 402.833314 -290.960738)
			(xy 402.786043 -290.97443) (xy 402.737188 -290.980362) (xy 402.688013 -290.978381) (xy 402.639794 -290.968537)
			(xy 402.593778 -290.951085) (xy 402.551157 -290.926478) (xy 402.513036 -290.895353) (xy 402.480401 -290.858516)
			(xy 402.454098 -290.81692) (xy 402.434807 -290.771644) (xy 402.42303 -290.72386) (xy 402.41907 -290.674806)
			(xy 402.080222 -290.674806) (xy 402.079727 -290.699413) (xy 402.071832 -290.74799) (xy 402.056248 -290.794671)
			(xy 402.033377 -290.838248) (xy 402.003812 -290.877592) (xy 401.968319 -290.911684) (xy 401.927816 -290.93964)
			(xy 401.883354 -290.960738) (xy 401.836083 -290.97443) (xy 401.787228 -290.980362) (xy 401.738053 -290.978381)
			(xy 401.689834 -290.968537) (xy 401.643818 -290.951085) (xy 401.601197 -290.926478) (xy 401.563076 -290.895353)
			(xy 401.530441 -290.858516) (xy 401.504138 -290.81692) (xy 401.484847 -290.771644) (xy 401.47307 -290.72386)
			(xy 401.46911 -290.674806) (xy 401.130262 -290.674806) (xy 401.129767 -290.699413) (xy 401.121872 -290.74799)
			(xy 401.106288 -290.794671) (xy 401.083417 -290.838248) (xy 401.053852 -290.877592) (xy 401.018359 -290.911684)
			(xy 400.977856 -290.93964) (xy 400.933394 -290.960738) (xy 400.886123 -290.97443) (xy 400.837268 -290.980362)
			(xy 400.788093 -290.978381) (xy 400.739874 -290.968537) (xy 400.693858 -290.951085) (xy 400.651237 -290.926478)
			(xy 400.613116 -290.895353) (xy 400.580481 -290.858516) (xy 400.554178 -290.81692) (xy 400.534887 -290.771644)
			(xy 400.52311 -290.72386) (xy 400.51915 -290.674806) (xy 400.180302 -290.674806) (xy 400.179807 -290.699413)
			(xy 400.171912 -290.74799) (xy 400.156328 -290.794671) (xy 400.133457 -290.838248) (xy 400.103892 -290.877592)
			(xy 400.068399 -290.911684) (xy 400.027896 -290.93964) (xy 399.983434 -290.960738) (xy 399.936163 -290.97443)
			(xy 399.887308 -290.980362) (xy 399.838133 -290.978381) (xy 399.789914 -290.968537) (xy 399.743898 -290.951085)
			(xy 399.701277 -290.926478) (xy 399.663156 -290.895353) (xy 399.630521 -290.858516) (xy 399.604218 -290.81692)
			(xy 399.584927 -290.771644) (xy 399.57315 -290.72386) (xy 399.56919 -290.674806) (xy 399.230342 -290.674806)
			(xy 399.229847 -290.699413) (xy 399.221952 -290.74799) (xy 399.206368 -290.794671) (xy 399.183497 -290.838248)
			(xy 399.153932 -290.877592) (xy 399.118439 -290.911684) (xy 399.077936 -290.93964) (xy 399.033474 -290.960738)
			(xy 398.986203 -290.97443) (xy 398.937348 -290.980362) (xy 398.888173 -290.978381) (xy 398.839954 -290.968537)
			(xy 398.793938 -290.951085) (xy 398.751317 -290.926478) (xy 398.713196 -290.895353) (xy 398.680561 -290.858516)
			(xy 398.654258 -290.81692) (xy 398.634967 -290.771644) (xy 398.62319 -290.72386) (xy 398.61923 -290.674806)
			(xy 398.280128 -290.674806) (xy 398.279633 -290.699413) (xy 398.271738 -290.74799) (xy 398.256154 -290.794671)
			(xy 398.233283 -290.838248) (xy 398.203718 -290.877592) (xy 398.168225 -290.911684) (xy 398.127722 -290.93964)
			(xy 398.08326 -290.960738) (xy 398.035989 -290.97443) (xy 397.987134 -290.980362) (xy 397.937959 -290.978381)
			(xy 397.88974 -290.968537) (xy 397.843724 -290.951085) (xy 397.801103 -290.926478) (xy 397.762982 -290.895353)
			(xy 397.730347 -290.858516) (xy 397.704044 -290.81692) (xy 397.684753 -290.771644) (xy 397.672976 -290.72386)
			(xy 397.669016 -290.674806) (xy 397.355141 -290.674806) (xy 397.355141 -290.701162) (xy 397.346777 -290.753217)
			(xy 397.330261 -290.803286) (xy 397.306011 -290.8501) (xy 397.274642 -290.892475) (xy 397.236948 -290.929338)
			(xy 397.193884 -290.959753) (xy 397.14654 -290.982952) (xy 397.096115 -290.998346) (xy 397.070072 -291.002466)
			(xy 397.066008 -291.002974) (xy 397.054578 -291.00653) (xy 397.05026 -291.0078) (xy 397.02613 -291.018976)
			(xy 397.019526 -291.026088) (xy 397.004794 -291.041582) (xy 396.996666 -291.052758) (xy 396.993969 -291.058289)
			(xy 396.991011 -291.07023) (xy 396.990824 -291.07638) (xy 396.990824 -291.223192) (xy 396.990996 -291.229344)
			(xy 396.993309 -291.238686) (xy 434.296564 -291.238686) (xy 434.300635 -291.183064) (xy 434.312761 -291.128627)
			(xy 434.332684 -291.076536) (xy 434.35998 -291.027901) (xy 434.394066 -290.983758) (xy 434.434215 -290.945049)
			(xy 434.479573 -290.912598) (xy 434.529173 -290.887097) (xy 434.581957 -290.86909) (xy 434.6368 -290.85896)
			(xy 434.692534 -290.856923) (xy 434.747971 -290.863023) (xy 434.801928 -290.877129) (xy 434.853257 -290.898941)
			(xy 434.900863 -290.927995) (xy 434.943731 -290.96367) (xy 434.980948 -291.005207) (xy 435.011721 -291.05172)
			(xy 435.035393 -291.102217) (xy 435.051461 -291.155624) (xy 435.059581 -291.2108) (xy 435.06009 -291.238686)
			(xy 435.059581 -291.266572) (xy 435.051461 -291.321748) (xy 435.035393 -291.375155) (xy 435.011721 -291.425652)
			(xy 434.980948 -291.472165) (xy 434.943731 -291.513702) (xy 434.900863 -291.549377) (xy 434.853257 -291.578431)
			(xy 434.821326 -291.592) (xy 436.741822 -291.592) (xy 436.745893 -291.536378) (xy 436.758019 -291.481941)
			(xy 436.777942 -291.42985) (xy 436.805238 -291.381215) (xy 436.839324 -291.337072) (xy 436.879473 -291.298363)
			(xy 436.924831 -291.265912) (xy 436.974431 -291.240411) (xy 437.027215 -291.222404) (xy 437.082058 -291.212274)
			(xy 437.137792 -291.210237) (xy 437.193229 -291.216337) (xy 437.247186 -291.230443) (xy 437.298515 -291.252255)
			(xy 437.346121 -291.281309) (xy 437.388989 -291.316984) (xy 437.426206 -291.358521) (xy 437.456979 -291.405034)
			(xy 437.480651 -291.455531) (xy 437.496719 -291.508938) (xy 437.504839 -291.564114) (xy 437.505348 -291.592)
			(xy 437.504839 -291.619886) (xy 437.496719 -291.675062) (xy 437.480651 -291.728469) (xy 437.456979 -291.778966)
			(xy 437.426206 -291.825479) (xy 437.388989 -291.867016) (xy 437.346121 -291.902691) (xy 437.298515 -291.931745)
			(xy 437.247186 -291.953557) (xy 437.193229 -291.967663) (xy 437.137792 -291.973763) (xy 437.082058 -291.971726)
			(xy 437.027215 -291.961596) (xy 436.974431 -291.943589) (xy 436.924831 -291.918088) (xy 436.879473 -291.885637)
			(xy 436.839324 -291.846928) (xy 436.805238 -291.802785) (xy 436.777942 -291.75415) (xy 436.758019 -291.702059)
			(xy 436.745893 -291.647622) (xy 436.741822 -291.592) (xy 434.821326 -291.592) (xy 434.801928 -291.600243)
			(xy 434.747971 -291.614349) (xy 434.692534 -291.620449) (xy 434.6368 -291.618412) (xy 434.581957 -291.608282)
			(xy 434.529173 -291.590275) (xy 434.479573 -291.564774) (xy 434.434215 -291.532323) (xy 434.394066 -291.493614)
			(xy 434.35998 -291.449471) (xy 434.332684 -291.400836) (xy 434.312761 -291.348745) (xy 434.300635 -291.294308)
			(xy 434.296564 -291.238686) (xy 396.993309 -291.238686) (xy 396.993954 -291.241289) (xy 396.996666 -291.246814)
			(xy 397.004794 -291.25799) (xy 397.019526 -291.273484) (xy 397.02613 -291.280596) (xy 397.05026 -291.291772)
			(xy 397.054578 -291.293042) (xy 397.066008 -291.296598) (xy 397.070072 -291.297106) (xy 397.096119 -291.301214)
			(xy 397.146551 -291.31661) (xy 397.193901 -291.339811) (xy 397.236971 -291.37023) (xy 397.27467 -291.407096)
			(xy 397.306043 -291.449475) (xy 397.330296 -291.496295) (xy 397.346814 -291.54637) (xy 397.35518 -291.598431)
			(xy 397.35518 -291.624766) (xy 397.669016 -291.624766) (xy 397.672976 -291.575712) (xy 397.684753 -291.527928)
			(xy 397.704044 -291.482652) (xy 397.730347 -291.441056) (xy 397.762982 -291.404219) (xy 397.801103 -291.373094)
			(xy 397.843724 -291.348487) (xy 397.88974 -291.331035) (xy 397.937959 -291.321191) (xy 397.987134 -291.31921)
			(xy 398.035989 -291.325142) (xy 398.08326 -291.338834) (xy 398.127722 -291.359932) (xy 398.168225 -291.387888)
			(xy 398.203718 -291.42198) (xy 398.233283 -291.461324) (xy 398.256154 -291.504901) (xy 398.271738 -291.551582)
			(xy 398.279633 -291.600159) (xy 398.280128 -291.624766) (xy 398.61923 -291.624766) (xy 398.62319 -291.575712)
			(xy 398.634967 -291.527928) (xy 398.654258 -291.482652) (xy 398.680561 -291.441056) (xy 398.713196 -291.404219)
			(xy 398.751317 -291.373094) (xy 398.793938 -291.348487) (xy 398.839954 -291.331035) (xy 398.888173 -291.321191)
			(xy 398.937348 -291.31921) (xy 398.986203 -291.325142) (xy 399.033474 -291.338834) (xy 399.077936 -291.359932)
			(xy 399.118439 -291.387888) (xy 399.153932 -291.42198) (xy 399.183497 -291.461324) (xy 399.206368 -291.504901)
			(xy 399.221952 -291.551582) (xy 399.229847 -291.600159) (xy 399.230342 -291.624766) (xy 399.56919 -291.624766)
			(xy 399.57315 -291.575712) (xy 399.584927 -291.527928) (xy 399.604218 -291.482652) (xy 399.630521 -291.441056)
			(xy 399.663156 -291.404219) (xy 399.701277 -291.373094) (xy 399.743898 -291.348487) (xy 399.789914 -291.331035)
			(xy 399.838133 -291.321191) (xy 399.887308 -291.31921) (xy 399.936163 -291.325142) (xy 399.983434 -291.338834)
			(xy 400.027896 -291.359932) (xy 400.068399 -291.387888) (xy 400.103892 -291.42198) (xy 400.133457 -291.461324)
			(xy 400.156328 -291.504901) (xy 400.171912 -291.551582) (xy 400.179807 -291.600159) (xy 400.180302 -291.624766)
			(xy 400.51915 -291.624766) (xy 400.52311 -291.575712) (xy 400.534887 -291.527928) (xy 400.554178 -291.482652)
			(xy 400.580481 -291.441056) (xy 400.613116 -291.404219) (xy 400.651237 -291.373094) (xy 400.693858 -291.348487)
			(xy 400.739874 -291.331035) (xy 400.788093 -291.321191) (xy 400.837268 -291.31921) (xy 400.886123 -291.325142)
			(xy 400.933394 -291.338834) (xy 400.977856 -291.359932) (xy 401.018359 -291.387888) (xy 401.053852 -291.42198)
			(xy 401.083417 -291.461324) (xy 401.106288 -291.504901) (xy 401.121872 -291.551582) (xy 401.129767 -291.600159)
			(xy 401.130262 -291.624766) (xy 401.46911 -291.624766) (xy 401.47307 -291.575712) (xy 401.484847 -291.527928)
			(xy 401.504138 -291.482652) (xy 401.530441 -291.441056) (xy 401.563076 -291.404219) (xy 401.601197 -291.373094)
			(xy 401.643818 -291.348487) (xy 401.689834 -291.331035) (xy 401.738053 -291.321191) (xy 401.787228 -291.31921)
			(xy 401.836083 -291.325142) (xy 401.883354 -291.338834) (xy 401.927816 -291.359932) (xy 401.968319 -291.387888)
			(xy 402.003812 -291.42198) (xy 402.033377 -291.461324) (xy 402.056248 -291.504901) (xy 402.071832 -291.551582)
			(xy 402.079727 -291.600159) (xy 402.080222 -291.624766) (xy 402.41907 -291.624766) (xy 402.42303 -291.575712)
			(xy 402.434807 -291.527928) (xy 402.454098 -291.482652) (xy 402.480401 -291.441056) (xy 402.513036 -291.404219)
			(xy 402.551157 -291.373094) (xy 402.593778 -291.348487) (xy 402.639794 -291.331035) (xy 402.688013 -291.321191)
			(xy 402.737188 -291.31921) (xy 402.786043 -291.325142) (xy 402.833314 -291.338834) (xy 402.877776 -291.359932)
			(xy 402.918279 -291.387888) (xy 402.953772 -291.42198) (xy 402.983337 -291.461324) (xy 403.006208 -291.504901)
			(xy 403.021792 -291.551582) (xy 403.029687 -291.600159) (xy 403.030182 -291.624766) (xy 403.36903 -291.624766)
			(xy 403.37299 -291.575712) (xy 403.384767 -291.527928) (xy 403.404058 -291.482652) (xy 403.430361 -291.441056)
			(xy 403.462996 -291.404219) (xy 403.501117 -291.373094) (xy 403.543738 -291.348487) (xy 403.589754 -291.331035)
			(xy 403.637973 -291.321191) (xy 403.687148 -291.31921) (xy 403.736003 -291.325142) (xy 403.783274 -291.338834)
			(xy 403.827736 -291.359932) (xy 403.868239 -291.387888) (xy 403.903732 -291.42198) (xy 403.933297 -291.461324)
			(xy 403.956168 -291.504901) (xy 403.971752 -291.551582) (xy 403.979647 -291.600159) (xy 403.980142 -291.624766)
			(xy 404.31899 -291.624766) (xy 404.32295 -291.575712) (xy 404.334727 -291.527928) (xy 404.354018 -291.482652)
			(xy 404.380321 -291.441056) (xy 404.412956 -291.404219) (xy 404.451077 -291.373094) (xy 404.493698 -291.348487)
			(xy 404.539714 -291.331035) (xy 404.587933 -291.321191) (xy 404.637108 -291.31921) (xy 404.685963 -291.325142)
			(xy 404.733234 -291.338834) (xy 404.777696 -291.359932) (xy 404.818199 -291.387888) (xy 404.853692 -291.42198)
			(xy 404.883257 -291.461324) (xy 404.906128 -291.504901) (xy 404.921712 -291.551582) (xy 404.929607 -291.600159)
			(xy 404.930102 -291.624766) (xy 405.269204 -291.624766) (xy 405.273164 -291.575712) (xy 405.284941 -291.527928)
			(xy 405.304232 -291.482652) (xy 405.330535 -291.441056) (xy 405.36317 -291.404219) (xy 405.401291 -291.373094)
			(xy 405.443912 -291.348487) (xy 405.489928 -291.331035) (xy 405.538147 -291.321191) (xy 405.587322 -291.31921)
			(xy 405.636177 -291.325142) (xy 405.683448 -291.338834) (xy 405.72791 -291.359932) (xy 405.768413 -291.387888)
			(xy 405.803906 -291.42198) (xy 405.833471 -291.461324) (xy 405.856342 -291.504901) (xy 405.871926 -291.551582)
			(xy 405.879821 -291.600159) (xy 405.880316 -291.624766) (xy 406.219164 -291.624766) (xy 406.223124 -291.575712)
			(xy 406.234901 -291.527928) (xy 406.254192 -291.482652) (xy 406.280495 -291.441056) (xy 406.31313 -291.404219)
			(xy 406.351251 -291.373094) (xy 406.393872 -291.348487) (xy 406.439888 -291.331035) (xy 406.488107 -291.321191)
			(xy 406.537282 -291.31921) (xy 406.586137 -291.325142) (xy 406.633408 -291.338834) (xy 406.67787 -291.359932)
			(xy 406.718373 -291.387888) (xy 406.753866 -291.42198) (xy 406.783431 -291.461324) (xy 406.806302 -291.504901)
			(xy 406.821886 -291.551582) (xy 406.829781 -291.600159) (xy 406.830276 -291.624766) (xy 408.119084 -291.624766)
			(xy 408.123044 -291.575712) (xy 408.134821 -291.527928) (xy 408.154112 -291.482652) (xy 408.180415 -291.441056)
			(xy 408.21305 -291.404219) (xy 408.251171 -291.373094) (xy 408.293792 -291.348487) (xy 408.339808 -291.331035)
			(xy 408.388027 -291.321191) (xy 408.437202 -291.31921) (xy 408.486057 -291.325142) (xy 408.533328 -291.338834)
			(xy 408.57779 -291.359932) (xy 408.618293 -291.387888) (xy 408.653786 -291.42198) (xy 408.683351 -291.461324)
			(xy 408.706222 -291.504901) (xy 408.721806 -291.551582) (xy 408.729701 -291.600159) (xy 408.730196 -291.624766)
			(xy 409.069044 -291.624766) (xy 409.073004 -291.575712) (xy 409.084781 -291.527928) (xy 409.104072 -291.482652)
			(xy 409.130375 -291.441056) (xy 409.16301 -291.404219) (xy 409.201131 -291.373094) (xy 409.243752 -291.348487)
			(xy 409.289768 -291.331035) (xy 409.337987 -291.321191) (xy 409.387162 -291.31921) (xy 409.436017 -291.325142)
			(xy 409.483288 -291.338834) (xy 409.52775 -291.359932) (xy 409.568253 -291.387888) (xy 409.603746 -291.42198)
			(xy 409.633311 -291.461324) (xy 409.656182 -291.504901) (xy 409.671766 -291.551582) (xy 409.679661 -291.600159)
			(xy 409.680156 -291.624766) (xy 410.019004 -291.624766) (xy 410.022964 -291.575712) (xy 410.034741 -291.527928)
			(xy 410.054032 -291.482652) (xy 410.080335 -291.441056) (xy 410.11297 -291.404219) (xy 410.151091 -291.373094)
			(xy 410.193712 -291.348487) (xy 410.239728 -291.331035) (xy 410.287947 -291.321191) (xy 410.337122 -291.31921)
			(xy 410.385977 -291.325142) (xy 410.433248 -291.338834) (xy 410.47771 -291.359932) (xy 410.518213 -291.387888)
			(xy 410.553706 -291.42198) (xy 410.583271 -291.461324) (xy 410.606142 -291.504901) (xy 410.621726 -291.551582)
			(xy 410.629621 -291.600159) (xy 410.630116 -291.624766) (xy 410.969218 -291.624766) (xy 410.973178 -291.575712)
			(xy 410.984955 -291.527928) (xy 411.004246 -291.482652) (xy 411.030549 -291.441056) (xy 411.063184 -291.404219)
			(xy 411.101305 -291.373094) (xy 411.143926 -291.348487) (xy 411.189942 -291.331035) (xy 411.238161 -291.321191)
			(xy 411.287336 -291.31921) (xy 411.336191 -291.325142) (xy 411.383462 -291.338834) (xy 411.427924 -291.359932)
			(xy 411.468427 -291.387888) (xy 411.50392 -291.42198) (xy 411.533485 -291.461324) (xy 411.556356 -291.504901)
			(xy 411.57194 -291.551582) (xy 411.579835 -291.600159) (xy 411.58033 -291.624766) (xy 411.919178 -291.624766)
			(xy 411.923138 -291.575712) (xy 411.934915 -291.527928) (xy 411.954206 -291.482652) (xy 411.980509 -291.441056)
			(xy 412.013144 -291.404219) (xy 412.051265 -291.373094) (xy 412.093886 -291.348487) (xy 412.139902 -291.331035)
			(xy 412.188121 -291.321191) (xy 412.237296 -291.31921) (xy 412.286151 -291.325142) (xy 412.333422 -291.338834)
			(xy 412.377884 -291.359932) (xy 412.418387 -291.387888) (xy 412.45388 -291.42198) (xy 412.483445 -291.461324)
			(xy 412.506316 -291.504901) (xy 412.5219 -291.551582) (xy 412.529795 -291.600159) (xy 412.53029 -291.624766)
			(xy 412.869138 -291.624766) (xy 412.873098 -291.575712) (xy 412.884875 -291.527928) (xy 412.904166 -291.482652)
			(xy 412.930469 -291.441056) (xy 412.963104 -291.404219) (xy 413.001225 -291.373094) (xy 413.043846 -291.348487)
			(xy 413.089862 -291.331035) (xy 413.138081 -291.321191) (xy 413.187256 -291.31921) (xy 413.236111 -291.325142)
			(xy 413.283382 -291.338834) (xy 413.327844 -291.359932) (xy 413.368347 -291.387888) (xy 413.40384 -291.42198)
			(xy 413.433405 -291.461324) (xy 413.456276 -291.504901) (xy 413.47186 -291.551582) (xy 413.479755 -291.600159)
			(xy 413.48025 -291.624766) (xy 413.819098 -291.624766) (xy 413.823058 -291.575712) (xy 413.834835 -291.527928)
			(xy 413.854126 -291.482652) (xy 413.880429 -291.441056) (xy 413.913064 -291.404219) (xy 413.951185 -291.373094)
			(xy 413.993806 -291.348487) (xy 414.039822 -291.331035) (xy 414.088041 -291.321191) (xy 414.137216 -291.31921)
			(xy 414.186071 -291.325142) (xy 414.233342 -291.338834) (xy 414.277804 -291.359932) (xy 414.318307 -291.387888)
			(xy 414.3538 -291.42198) (xy 414.383365 -291.461324) (xy 414.406236 -291.504901) (xy 414.42182 -291.551582)
			(xy 414.429715 -291.600159) (xy 414.43021 -291.624766) (xy 414.769058 -291.624766) (xy 414.773018 -291.575712)
			(xy 414.784795 -291.527928) (xy 414.804086 -291.482652) (xy 414.830389 -291.441056) (xy 414.863024 -291.404219)
			(xy 414.901145 -291.373094) (xy 414.943766 -291.348487) (xy 414.989782 -291.331035) (xy 415.038001 -291.321191)
			(xy 415.087176 -291.31921) (xy 415.136031 -291.325142) (xy 415.183302 -291.338834) (xy 415.227764 -291.359932)
			(xy 415.268267 -291.387888) (xy 415.30376 -291.42198) (xy 415.333325 -291.461324) (xy 415.356196 -291.504901)
			(xy 415.37178 -291.551582) (xy 415.379675 -291.600159) (xy 415.38017 -291.624766) (xy 415.719018 -291.624766)
			(xy 415.722978 -291.575712) (xy 415.734755 -291.527928) (xy 415.754046 -291.482652) (xy 415.780349 -291.441056)
			(xy 415.812984 -291.404219) (xy 415.851105 -291.373094) (xy 415.893726 -291.348487) (xy 415.939742 -291.331035)
			(xy 415.987961 -291.321191) (xy 416.037136 -291.31921) (xy 416.085991 -291.325142) (xy 416.133262 -291.338834)
			(xy 416.177724 -291.359932) (xy 416.218227 -291.387888) (xy 416.25372 -291.42198) (xy 416.283285 -291.461324)
			(xy 416.306156 -291.504901) (xy 416.32174 -291.551582) (xy 416.329635 -291.600159) (xy 416.33013 -291.624766)
			(xy 416.668978 -291.624766) (xy 416.672938 -291.575712) (xy 416.684715 -291.527928) (xy 416.704006 -291.482652)
			(xy 416.730309 -291.441056) (xy 416.762944 -291.404219) (xy 416.801065 -291.373094) (xy 416.843686 -291.348487)
			(xy 416.889702 -291.331035) (xy 416.937921 -291.321191) (xy 416.987096 -291.31921) (xy 417.035951 -291.325142)
			(xy 417.083222 -291.338834) (xy 417.127684 -291.359932) (xy 417.168187 -291.387888) (xy 417.20368 -291.42198)
			(xy 417.233245 -291.461324) (xy 417.256116 -291.504901) (xy 417.2717 -291.551582) (xy 417.279595 -291.600159)
			(xy 417.28009 -291.624766) (xy 417.619192 -291.624766) (xy 417.623152 -291.575712) (xy 417.634929 -291.527928)
			(xy 417.65422 -291.482652) (xy 417.680523 -291.441056) (xy 417.713158 -291.404219) (xy 417.751279 -291.373094)
			(xy 417.7939 -291.348487) (xy 417.839916 -291.331035) (xy 417.888135 -291.321191) (xy 417.93731 -291.31921)
			(xy 417.986165 -291.325142) (xy 418.033436 -291.338834) (xy 418.077898 -291.359932) (xy 418.118401 -291.387888)
			(xy 418.153894 -291.42198) (xy 418.183459 -291.461324) (xy 418.20633 -291.504901) (xy 418.221914 -291.551582)
			(xy 418.229809 -291.600159) (xy 418.230304 -291.624766) (xy 418.569152 -291.624766) (xy 418.573112 -291.575712)
			(xy 418.584889 -291.527928) (xy 418.60418 -291.482652) (xy 418.630483 -291.441056) (xy 418.663118 -291.404219)
			(xy 418.701239 -291.373094) (xy 418.74386 -291.348487) (xy 418.789876 -291.331035) (xy 418.838095 -291.321191)
			(xy 418.88727 -291.31921) (xy 418.936125 -291.325142) (xy 418.983396 -291.338834) (xy 419.027858 -291.359932)
			(xy 419.068361 -291.387888) (xy 419.103854 -291.42198) (xy 419.133419 -291.461324) (xy 419.15629 -291.504901)
			(xy 419.171874 -291.551582) (xy 419.179769 -291.600159) (xy 419.180264 -291.624766) (xy 419.519112 -291.624766)
			(xy 419.523072 -291.575712) (xy 419.534849 -291.527928) (xy 419.55414 -291.482652) (xy 419.580443 -291.441056)
			(xy 419.613078 -291.404219) (xy 419.651199 -291.373094) (xy 419.69382 -291.348487) (xy 419.739836 -291.331035)
			(xy 419.788055 -291.321191) (xy 419.83723 -291.31921) (xy 419.886085 -291.325142) (xy 419.933356 -291.338834)
			(xy 419.977818 -291.359932) (xy 420.018321 -291.387888) (xy 420.053814 -291.42198) (xy 420.083379 -291.461324)
			(xy 420.10625 -291.504901) (xy 420.121834 -291.551582) (xy 420.129729 -291.600159) (xy 420.130224 -291.624766)
			(xy 420.469072 -291.624766) (xy 420.473032 -291.575712) (xy 420.484809 -291.527928) (xy 420.5041 -291.482652)
			(xy 420.530403 -291.441056) (xy 420.563038 -291.404219) (xy 420.601159 -291.373094) (xy 420.64378 -291.348487)
			(xy 420.689796 -291.331035) (xy 420.738015 -291.321191) (xy 420.78719 -291.31921) (xy 420.836045 -291.325142)
			(xy 420.883316 -291.338834) (xy 420.927778 -291.359932) (xy 420.968281 -291.387888) (xy 421.003774 -291.42198)
			(xy 421.033339 -291.461324) (xy 421.05621 -291.504901) (xy 421.071794 -291.551582) (xy 421.079689 -291.600159)
			(xy 421.080184 -291.624766) (xy 421.419032 -291.624766) (xy 421.422992 -291.575712) (xy 421.434769 -291.527928)
			(xy 421.45406 -291.482652) (xy 421.480363 -291.441056) (xy 421.512998 -291.404219) (xy 421.551119 -291.373094)
			(xy 421.59374 -291.348487) (xy 421.639756 -291.331035) (xy 421.687975 -291.321191) (xy 421.73715 -291.31921)
			(xy 421.786005 -291.325142) (xy 421.833276 -291.338834) (xy 421.877738 -291.359932) (xy 421.918241 -291.387888)
			(xy 421.953734 -291.42198) (xy 421.983299 -291.461324) (xy 422.00617 -291.504901) (xy 422.021754 -291.551582)
			(xy 422.029649 -291.600159) (xy 422.030144 -291.624766) (xy 422.369246 -291.624766) (xy 422.373206 -291.575712)
			(xy 422.384983 -291.527928) (xy 422.404274 -291.482652) (xy 422.430577 -291.441056) (xy 422.463212 -291.404219)
			(xy 422.501333 -291.373094) (xy 422.543954 -291.348487) (xy 422.58997 -291.331035) (xy 422.638189 -291.321191)
			(xy 422.687364 -291.31921) (xy 422.736219 -291.325142) (xy 422.78349 -291.338834) (xy 422.827952 -291.359932)
			(xy 422.868455 -291.387888) (xy 422.903948 -291.42198) (xy 422.933513 -291.461324) (xy 422.956384 -291.504901)
			(xy 422.971968 -291.551582) (xy 422.979863 -291.600159) (xy 422.980358 -291.624766) (xy 424.269166 -291.624766)
			(xy 424.273126 -291.575712) (xy 424.284903 -291.527928) (xy 424.304194 -291.482652) (xy 424.330497 -291.441056)
			(xy 424.363132 -291.404219) (xy 424.401253 -291.373094) (xy 424.443874 -291.348487) (xy 424.48989 -291.331035)
			(xy 424.538109 -291.321191) (xy 424.587284 -291.31921) (xy 424.636139 -291.325142) (xy 424.68341 -291.338834)
			(xy 424.727872 -291.359932) (xy 424.768375 -291.387888) (xy 424.803868 -291.42198) (xy 424.833433 -291.461324)
			(xy 424.856304 -291.504901) (xy 424.871888 -291.551582) (xy 424.879783 -291.600159) (xy 424.880278 -291.624766)
			(xy 425.219126 -291.624766) (xy 425.223086 -291.575712) (xy 425.234863 -291.527928) (xy 425.254154 -291.482652)
			(xy 425.280457 -291.441056) (xy 425.313092 -291.404219) (xy 425.351213 -291.373094) (xy 425.393834 -291.348487)
			(xy 425.43985 -291.331035) (xy 425.488069 -291.321191) (xy 425.537244 -291.31921) (xy 425.586099 -291.325142)
			(xy 425.63337 -291.338834) (xy 425.677832 -291.359932) (xy 425.718335 -291.387888) (xy 425.753828 -291.42198)
			(xy 425.783393 -291.461324) (xy 425.806264 -291.504901) (xy 425.821848 -291.551582) (xy 425.829743 -291.600159)
			(xy 425.830238 -291.624766) (xy 426.169086 -291.624766) (xy 426.173046 -291.575712) (xy 426.184823 -291.527928)
			(xy 426.204114 -291.482652) (xy 426.230417 -291.441056) (xy 426.263052 -291.404219) (xy 426.301173 -291.373094)
			(xy 426.343794 -291.348487) (xy 426.38981 -291.331035) (xy 426.438029 -291.321191) (xy 426.487204 -291.31921)
			(xy 426.536059 -291.325142) (xy 426.58333 -291.338834) (xy 426.627792 -291.359932) (xy 426.668295 -291.387888)
			(xy 426.703788 -291.42198) (xy 426.733353 -291.461324) (xy 426.756224 -291.504901) (xy 426.771808 -291.551582)
			(xy 426.779703 -291.600159) (xy 426.780198 -291.624766) (xy 427.119046 -291.624766) (xy 427.123006 -291.575712)
			(xy 427.134783 -291.527928) (xy 427.154074 -291.482652) (xy 427.180377 -291.441056) (xy 427.213012 -291.404219)
			(xy 427.251133 -291.373094) (xy 427.293754 -291.348487) (xy 427.33977 -291.331035) (xy 427.387989 -291.321191)
			(xy 427.437164 -291.31921) (xy 427.486019 -291.325142) (xy 427.53329 -291.338834) (xy 427.577752 -291.359932)
			(xy 427.618255 -291.387888) (xy 427.653748 -291.42198) (xy 427.683313 -291.461324) (xy 427.706184 -291.504901)
			(xy 427.721768 -291.551582) (xy 427.729663 -291.600159) (xy 427.730158 -291.624766) (xy 428.069006 -291.624766)
			(xy 428.072966 -291.575712) (xy 428.084743 -291.527928) (xy 428.104034 -291.482652) (xy 428.130337 -291.441056)
			(xy 428.162972 -291.404219) (xy 428.201093 -291.373094) (xy 428.243714 -291.348487) (xy 428.28973 -291.331035)
			(xy 428.337949 -291.321191) (xy 428.387124 -291.31921) (xy 428.435979 -291.325142) (xy 428.48325 -291.338834)
			(xy 428.527712 -291.359932) (xy 428.568215 -291.387888) (xy 428.603708 -291.42198) (xy 428.633273 -291.461324)
			(xy 428.656144 -291.504901) (xy 428.671728 -291.551582) (xy 428.679623 -291.600159) (xy 428.680118 -291.624766)
			(xy 429.01922 -291.624766) (xy 429.02318 -291.575712) (xy 429.034957 -291.527928) (xy 429.054248 -291.482652)
			(xy 429.080551 -291.441056) (xy 429.113186 -291.404219) (xy 429.151307 -291.373094) (xy 429.193928 -291.348487)
			(xy 429.239944 -291.331035) (xy 429.288163 -291.321191) (xy 429.337338 -291.31921) (xy 429.386193 -291.325142)
			(xy 429.433464 -291.338834) (xy 429.477926 -291.359932) (xy 429.518429 -291.387888) (xy 429.553922 -291.42198)
			(xy 429.583487 -291.461324) (xy 429.606358 -291.504901) (xy 429.621942 -291.551582) (xy 429.629837 -291.600159)
			(xy 429.630332 -291.624766) (xy 429.96918 -291.624766) (xy 429.97314 -291.575712) (xy 429.984917 -291.527928)
			(xy 430.004208 -291.482652) (xy 430.030511 -291.441056) (xy 430.063146 -291.404219) (xy 430.101267 -291.373094)
			(xy 430.143888 -291.348487) (xy 430.189904 -291.331035) (xy 430.238123 -291.321191) (xy 430.287298 -291.31921)
			(xy 430.336153 -291.325142) (xy 430.383424 -291.338834) (xy 430.427886 -291.359932) (xy 430.468389 -291.387888)
			(xy 430.503882 -291.42198) (xy 430.533447 -291.461324) (xy 430.556318 -291.504901) (xy 430.571902 -291.551582)
			(xy 430.579797 -291.600159) (xy 430.580292 -291.624766) (xy 430.91914 -291.624766) (xy 430.9231 -291.575712)
			(xy 430.934877 -291.527928) (xy 430.954168 -291.482652) (xy 430.980471 -291.441056) (xy 431.013106 -291.404219)
			(xy 431.051227 -291.373094) (xy 431.093848 -291.348487) (xy 431.139864 -291.331035) (xy 431.188083 -291.321191)
			(xy 431.237258 -291.31921) (xy 431.286113 -291.325142) (xy 431.333384 -291.338834) (xy 431.377846 -291.359932)
			(xy 431.418349 -291.387888) (xy 431.453842 -291.42198) (xy 431.483407 -291.461324) (xy 431.506278 -291.504901)
			(xy 431.521862 -291.551582) (xy 431.529757 -291.600159) (xy 431.530252 -291.624766) (xy 431.529757 -291.649373)
			(xy 431.521862 -291.69795) (xy 431.506278 -291.744631) (xy 431.483407 -291.788208) (xy 431.453842 -291.827552)
			(xy 431.418349 -291.861644) (xy 431.377846 -291.8896) (xy 431.333384 -291.910698) (xy 431.286113 -291.92439)
			(xy 431.237258 -291.930322) (xy 431.188083 -291.928341) (xy 431.139864 -291.918497) (xy 431.093848 -291.901045)
			(xy 431.051227 -291.876438) (xy 431.013106 -291.845313) (xy 430.980471 -291.808476) (xy 430.954168 -291.76688)
			(xy 430.934877 -291.721604) (xy 430.9231 -291.67382) (xy 430.91914 -291.624766) (xy 430.580292 -291.624766)
			(xy 430.579797 -291.649373) (xy 430.571902 -291.69795) (xy 430.556318 -291.744631) (xy 430.533447 -291.788208)
			(xy 430.503882 -291.827552) (xy 430.468389 -291.861644) (xy 430.427886 -291.8896) (xy 430.383424 -291.910698)
			(xy 430.336153 -291.92439) (xy 430.287298 -291.930322) (xy 430.238123 -291.928341) (xy 430.189904 -291.918497)
			(xy 430.143888 -291.901045) (xy 430.101267 -291.876438) (xy 430.063146 -291.845313) (xy 430.030511 -291.808476)
			(xy 430.004208 -291.76688) (xy 429.984917 -291.721604) (xy 429.97314 -291.67382) (xy 429.96918 -291.624766)
			(xy 429.630332 -291.624766) (xy 429.629837 -291.649373) (xy 429.621942 -291.69795) (xy 429.606358 -291.744631)
			(xy 429.583487 -291.788208) (xy 429.553922 -291.827552) (xy 429.518429 -291.861644) (xy 429.477926 -291.8896)
			(xy 429.433464 -291.910698) (xy 429.386193 -291.92439) (xy 429.337338 -291.930322) (xy 429.288163 -291.928341)
			(xy 429.239944 -291.918497) (xy 429.193928 -291.901045) (xy 429.151307 -291.876438) (xy 429.113186 -291.845313)
			(xy 429.080551 -291.808476) (xy 429.054248 -291.76688) (xy 429.034957 -291.721604) (xy 429.02318 -291.67382)
			(xy 429.01922 -291.624766) (xy 428.680118 -291.624766) (xy 428.679623 -291.649373) (xy 428.671728 -291.69795)
			(xy 428.656144 -291.744631) (xy 428.633273 -291.788208) (xy 428.603708 -291.827552) (xy 428.568215 -291.861644)
			(xy 428.527712 -291.8896) (xy 428.48325 -291.910698) (xy 428.435979 -291.92439) (xy 428.387124 -291.930322)
			(xy 428.337949 -291.928341) (xy 428.28973 -291.918497) (xy 428.243714 -291.901045) (xy 428.201093 -291.876438)
			(xy 428.162972 -291.845313) (xy 428.130337 -291.808476) (xy 428.104034 -291.76688) (xy 428.084743 -291.721604)
			(xy 428.072966 -291.67382) (xy 428.069006 -291.624766) (xy 427.730158 -291.624766) (xy 427.729663 -291.649373)
			(xy 427.721768 -291.69795) (xy 427.706184 -291.744631) (xy 427.683313 -291.788208) (xy 427.653748 -291.827552)
			(xy 427.618255 -291.861644) (xy 427.577752 -291.8896) (xy 427.53329 -291.910698) (xy 427.486019 -291.92439)
			(xy 427.437164 -291.930322) (xy 427.387989 -291.928341) (xy 427.33977 -291.918497) (xy 427.293754 -291.901045)
			(xy 427.251133 -291.876438) (xy 427.213012 -291.845313) (xy 427.180377 -291.808476) (xy 427.154074 -291.76688)
			(xy 427.134783 -291.721604) (xy 427.123006 -291.67382) (xy 427.119046 -291.624766) (xy 426.780198 -291.624766)
			(xy 426.779703 -291.649373) (xy 426.771808 -291.69795) (xy 426.756224 -291.744631) (xy 426.733353 -291.788208)
			(xy 426.703788 -291.827552) (xy 426.668295 -291.861644) (xy 426.627792 -291.8896) (xy 426.58333 -291.910698)
			(xy 426.536059 -291.92439) (xy 426.487204 -291.930322) (xy 426.438029 -291.928341) (xy 426.38981 -291.918497)
			(xy 426.343794 -291.901045) (xy 426.301173 -291.876438) (xy 426.263052 -291.845313) (xy 426.230417 -291.808476)
			(xy 426.204114 -291.76688) (xy 426.184823 -291.721604) (xy 426.173046 -291.67382) (xy 426.169086 -291.624766)
			(xy 425.830238 -291.624766) (xy 425.829743 -291.649373) (xy 425.821848 -291.69795) (xy 425.806264 -291.744631)
			(xy 425.783393 -291.788208) (xy 425.753828 -291.827552) (xy 425.718335 -291.861644) (xy 425.677832 -291.8896)
			(xy 425.63337 -291.910698) (xy 425.586099 -291.92439) (xy 425.537244 -291.930322) (xy 425.488069 -291.928341)
			(xy 425.43985 -291.918497) (xy 425.393834 -291.901045) (xy 425.351213 -291.876438) (xy 425.313092 -291.845313)
			(xy 425.280457 -291.808476) (xy 425.254154 -291.76688) (xy 425.234863 -291.721604) (xy 425.223086 -291.67382)
			(xy 425.219126 -291.624766) (xy 424.880278 -291.624766) (xy 424.879783 -291.649373) (xy 424.871888 -291.69795)
			(xy 424.856304 -291.744631) (xy 424.833433 -291.788208) (xy 424.803868 -291.827552) (xy 424.768375 -291.861644)
			(xy 424.727872 -291.8896) (xy 424.68341 -291.910698) (xy 424.636139 -291.92439) (xy 424.587284 -291.930322)
			(xy 424.538109 -291.928341) (xy 424.48989 -291.918497) (xy 424.443874 -291.901045) (xy 424.401253 -291.876438)
			(xy 424.363132 -291.845313) (xy 424.330497 -291.808476) (xy 424.304194 -291.76688) (xy 424.284903 -291.721604)
			(xy 424.273126 -291.67382) (xy 424.269166 -291.624766) (xy 422.980358 -291.624766) (xy 422.979863 -291.649373)
			(xy 422.971968 -291.69795) (xy 422.956384 -291.744631) (xy 422.933513 -291.788208) (xy 422.903948 -291.827552)
			(xy 422.868455 -291.861644) (xy 422.827952 -291.8896) (xy 422.78349 -291.910698) (xy 422.736219 -291.92439)
			(xy 422.687364 -291.930322) (xy 422.638189 -291.928341) (xy 422.58997 -291.918497) (xy 422.543954 -291.901045)
			(xy 422.501333 -291.876438) (xy 422.463212 -291.845313) (xy 422.430577 -291.808476) (xy 422.404274 -291.76688)
			(xy 422.384983 -291.721604) (xy 422.373206 -291.67382) (xy 422.369246 -291.624766) (xy 422.030144 -291.624766)
			(xy 422.029649 -291.649373) (xy 422.021754 -291.69795) (xy 422.00617 -291.744631) (xy 421.983299 -291.788208)
			(xy 421.953734 -291.827552) (xy 421.918241 -291.861644) (xy 421.877738 -291.8896) (xy 421.833276 -291.910698)
			(xy 421.786005 -291.92439) (xy 421.73715 -291.930322) (xy 421.687975 -291.928341) (xy 421.639756 -291.918497)
			(xy 421.59374 -291.901045) (xy 421.551119 -291.876438) (xy 421.512998 -291.845313) (xy 421.480363 -291.808476)
			(xy 421.45406 -291.76688) (xy 421.434769 -291.721604) (xy 421.422992 -291.67382) (xy 421.419032 -291.624766)
			(xy 421.080184 -291.624766) (xy 421.079689 -291.649373) (xy 421.071794 -291.69795) (xy 421.05621 -291.744631)
			(xy 421.033339 -291.788208) (xy 421.003774 -291.827552) (xy 420.968281 -291.861644) (xy 420.927778 -291.8896)
			(xy 420.883316 -291.910698) (xy 420.836045 -291.92439) (xy 420.78719 -291.930322) (xy 420.738015 -291.928341)
			(xy 420.689796 -291.918497) (xy 420.64378 -291.901045) (xy 420.601159 -291.876438) (xy 420.563038 -291.845313)
			(xy 420.530403 -291.808476) (xy 420.5041 -291.76688) (xy 420.484809 -291.721604) (xy 420.473032 -291.67382)
			(xy 420.469072 -291.624766) (xy 420.130224 -291.624766) (xy 420.129729 -291.649373) (xy 420.121834 -291.69795)
			(xy 420.10625 -291.744631) (xy 420.083379 -291.788208) (xy 420.053814 -291.827552) (xy 420.018321 -291.861644)
			(xy 419.977818 -291.8896) (xy 419.933356 -291.910698) (xy 419.886085 -291.92439) (xy 419.83723 -291.930322)
			(xy 419.788055 -291.928341) (xy 419.739836 -291.918497) (xy 419.69382 -291.901045) (xy 419.651199 -291.876438)
			(xy 419.613078 -291.845313) (xy 419.580443 -291.808476) (xy 419.55414 -291.76688) (xy 419.534849 -291.721604)
			(xy 419.523072 -291.67382) (xy 419.519112 -291.624766) (xy 419.180264 -291.624766) (xy 419.179769 -291.649373)
			(xy 419.171874 -291.69795) (xy 419.15629 -291.744631) (xy 419.133419 -291.788208) (xy 419.103854 -291.827552)
			(xy 419.068361 -291.861644) (xy 419.027858 -291.8896) (xy 418.983396 -291.910698) (xy 418.936125 -291.92439)
			(xy 418.88727 -291.930322) (xy 418.838095 -291.928341) (xy 418.789876 -291.918497) (xy 418.74386 -291.901045)
			(xy 418.701239 -291.876438) (xy 418.663118 -291.845313) (xy 418.630483 -291.808476) (xy 418.60418 -291.76688)
			(xy 418.584889 -291.721604) (xy 418.573112 -291.67382) (xy 418.569152 -291.624766) (xy 418.230304 -291.624766)
			(xy 418.229809 -291.649373) (xy 418.221914 -291.69795) (xy 418.20633 -291.744631) (xy 418.183459 -291.788208)
			(xy 418.153894 -291.827552) (xy 418.118401 -291.861644) (xy 418.077898 -291.8896) (xy 418.033436 -291.910698)
			(xy 417.986165 -291.92439) (xy 417.93731 -291.930322) (xy 417.888135 -291.928341) (xy 417.839916 -291.918497)
			(xy 417.7939 -291.901045) (xy 417.751279 -291.876438) (xy 417.713158 -291.845313) (xy 417.680523 -291.808476)
			(xy 417.65422 -291.76688) (xy 417.634929 -291.721604) (xy 417.623152 -291.67382) (xy 417.619192 -291.624766)
			(xy 417.28009 -291.624766) (xy 417.279595 -291.649373) (xy 417.2717 -291.69795) (xy 417.256116 -291.744631)
			(xy 417.233245 -291.788208) (xy 417.20368 -291.827552) (xy 417.168187 -291.861644) (xy 417.127684 -291.8896)
			(xy 417.083222 -291.910698) (xy 417.035951 -291.92439) (xy 416.987096 -291.930322) (xy 416.937921 -291.928341)
			(xy 416.889702 -291.918497) (xy 416.843686 -291.901045) (xy 416.801065 -291.876438) (xy 416.762944 -291.845313)
			(xy 416.730309 -291.808476) (xy 416.704006 -291.76688) (xy 416.684715 -291.721604) (xy 416.672938 -291.67382)
			(xy 416.668978 -291.624766) (xy 416.33013 -291.624766) (xy 416.329635 -291.649373) (xy 416.32174 -291.69795)
			(xy 416.306156 -291.744631) (xy 416.283285 -291.788208) (xy 416.25372 -291.827552) (xy 416.218227 -291.861644)
			(xy 416.177724 -291.8896) (xy 416.133262 -291.910698) (xy 416.085991 -291.92439) (xy 416.037136 -291.930322)
			(xy 415.987961 -291.928341) (xy 415.939742 -291.918497) (xy 415.893726 -291.901045) (xy 415.851105 -291.876438)
			(xy 415.812984 -291.845313) (xy 415.780349 -291.808476) (xy 415.754046 -291.76688) (xy 415.734755 -291.721604)
			(xy 415.722978 -291.67382) (xy 415.719018 -291.624766) (xy 415.38017 -291.624766) (xy 415.379675 -291.649373)
			(xy 415.37178 -291.69795) (xy 415.356196 -291.744631) (xy 415.333325 -291.788208) (xy 415.30376 -291.827552)
			(xy 415.268267 -291.861644) (xy 415.227764 -291.8896) (xy 415.183302 -291.910698) (xy 415.136031 -291.92439)
			(xy 415.087176 -291.930322) (xy 415.038001 -291.928341) (xy 414.989782 -291.918497) (xy 414.943766 -291.901045)
			(xy 414.901145 -291.876438) (xy 414.863024 -291.845313) (xy 414.830389 -291.808476) (xy 414.804086 -291.76688)
			(xy 414.784795 -291.721604) (xy 414.773018 -291.67382) (xy 414.769058 -291.624766) (xy 414.43021 -291.624766)
			(xy 414.429715 -291.649373) (xy 414.42182 -291.69795) (xy 414.406236 -291.744631) (xy 414.383365 -291.788208)
			(xy 414.3538 -291.827552) (xy 414.318307 -291.861644) (xy 414.277804 -291.8896) (xy 414.233342 -291.910698)
			(xy 414.186071 -291.92439) (xy 414.137216 -291.930322) (xy 414.088041 -291.928341) (xy 414.039822 -291.918497)
			(xy 413.993806 -291.901045) (xy 413.951185 -291.876438) (xy 413.913064 -291.845313) (xy 413.880429 -291.808476)
			(xy 413.854126 -291.76688) (xy 413.834835 -291.721604) (xy 413.823058 -291.67382) (xy 413.819098 -291.624766)
			(xy 413.48025 -291.624766) (xy 413.479755 -291.649373) (xy 413.47186 -291.69795) (xy 413.456276 -291.744631)
			(xy 413.433405 -291.788208) (xy 413.40384 -291.827552) (xy 413.368347 -291.861644) (xy 413.327844 -291.8896)
			(xy 413.283382 -291.910698) (xy 413.236111 -291.92439) (xy 413.187256 -291.930322) (xy 413.138081 -291.928341)
			(xy 413.089862 -291.918497) (xy 413.043846 -291.901045) (xy 413.001225 -291.876438) (xy 412.963104 -291.845313)
			(xy 412.930469 -291.808476) (xy 412.904166 -291.76688) (xy 412.884875 -291.721604) (xy 412.873098 -291.67382)
			(xy 412.869138 -291.624766) (xy 412.53029 -291.624766) (xy 412.529795 -291.649373) (xy 412.5219 -291.69795)
			(xy 412.506316 -291.744631) (xy 412.483445 -291.788208) (xy 412.45388 -291.827552) (xy 412.418387 -291.861644)
			(xy 412.377884 -291.8896) (xy 412.333422 -291.910698) (xy 412.286151 -291.92439) (xy 412.237296 -291.930322)
			(xy 412.188121 -291.928341) (xy 412.139902 -291.918497) (xy 412.093886 -291.901045) (xy 412.051265 -291.876438)
			(xy 412.013144 -291.845313) (xy 411.980509 -291.808476) (xy 411.954206 -291.76688) (xy 411.934915 -291.721604)
			(xy 411.923138 -291.67382) (xy 411.919178 -291.624766) (xy 411.58033 -291.624766) (xy 411.579835 -291.649373)
			(xy 411.57194 -291.69795) (xy 411.556356 -291.744631) (xy 411.533485 -291.788208) (xy 411.50392 -291.827552)
			(xy 411.468427 -291.861644) (xy 411.427924 -291.8896) (xy 411.383462 -291.910698) (xy 411.336191 -291.92439)
			(xy 411.287336 -291.930322) (xy 411.238161 -291.928341) (xy 411.189942 -291.918497) (xy 411.143926 -291.901045)
			(xy 411.101305 -291.876438) (xy 411.063184 -291.845313) (xy 411.030549 -291.808476) (xy 411.004246 -291.76688)
			(xy 410.984955 -291.721604) (xy 410.973178 -291.67382) (xy 410.969218 -291.624766) (xy 410.630116 -291.624766)
			(xy 410.629621 -291.649373) (xy 410.621726 -291.69795) (xy 410.606142 -291.744631) (xy 410.583271 -291.788208)
			(xy 410.553706 -291.827552) (xy 410.518213 -291.861644) (xy 410.47771 -291.8896) (xy 410.433248 -291.910698)
			(xy 410.385977 -291.92439) (xy 410.337122 -291.930322) (xy 410.287947 -291.928341) (xy 410.239728 -291.918497)
			(xy 410.193712 -291.901045) (xy 410.151091 -291.876438) (xy 410.11297 -291.845313) (xy 410.080335 -291.808476)
			(xy 410.054032 -291.76688) (xy 410.034741 -291.721604) (xy 410.022964 -291.67382) (xy 410.019004 -291.624766)
			(xy 409.680156 -291.624766) (xy 409.679661 -291.649373) (xy 409.671766 -291.69795) (xy 409.656182 -291.744631)
			(xy 409.633311 -291.788208) (xy 409.603746 -291.827552) (xy 409.568253 -291.861644) (xy 409.52775 -291.8896)
			(xy 409.483288 -291.910698) (xy 409.436017 -291.92439) (xy 409.387162 -291.930322) (xy 409.337987 -291.928341)
			(xy 409.289768 -291.918497) (xy 409.243752 -291.901045) (xy 409.201131 -291.876438) (xy 409.16301 -291.845313)
			(xy 409.130375 -291.808476) (xy 409.104072 -291.76688) (xy 409.084781 -291.721604) (xy 409.073004 -291.67382)
			(xy 409.069044 -291.624766) (xy 408.730196 -291.624766) (xy 408.729701 -291.649373) (xy 408.721806 -291.69795)
			(xy 408.706222 -291.744631) (xy 408.683351 -291.788208) (xy 408.653786 -291.827552) (xy 408.618293 -291.861644)
			(xy 408.57779 -291.8896) (xy 408.533328 -291.910698) (xy 408.486057 -291.92439) (xy 408.437202 -291.930322)
			(xy 408.388027 -291.928341) (xy 408.339808 -291.918497) (xy 408.293792 -291.901045) (xy 408.251171 -291.876438)
			(xy 408.21305 -291.845313) (xy 408.180415 -291.808476) (xy 408.154112 -291.76688) (xy 408.134821 -291.721604)
			(xy 408.123044 -291.67382) (xy 408.119084 -291.624766) (xy 406.830276 -291.624766) (xy 406.829781 -291.649373)
			(xy 406.821886 -291.69795) (xy 406.806302 -291.744631) (xy 406.783431 -291.788208) (xy 406.753866 -291.827552)
			(xy 406.718373 -291.861644) (xy 406.67787 -291.8896) (xy 406.633408 -291.910698) (xy 406.586137 -291.92439)
			(xy 406.537282 -291.930322) (xy 406.488107 -291.928341) (xy 406.439888 -291.918497) (xy 406.393872 -291.901045)
			(xy 406.351251 -291.876438) (xy 406.31313 -291.845313) (xy 406.280495 -291.808476) (xy 406.254192 -291.76688)
			(xy 406.234901 -291.721604) (xy 406.223124 -291.67382) (xy 406.219164 -291.624766) (xy 405.880316 -291.624766)
			(xy 405.879821 -291.649373) (xy 405.871926 -291.69795) (xy 405.856342 -291.744631) (xy 405.833471 -291.788208)
			(xy 405.803906 -291.827552) (xy 405.768413 -291.861644) (xy 405.72791 -291.8896) (xy 405.683448 -291.910698)
			(xy 405.636177 -291.92439) (xy 405.587322 -291.930322) (xy 405.538147 -291.928341) (xy 405.489928 -291.918497)
			(xy 405.443912 -291.901045) (xy 405.401291 -291.876438) (xy 405.36317 -291.845313) (xy 405.330535 -291.808476)
			(xy 405.304232 -291.76688) (xy 405.284941 -291.721604) (xy 405.273164 -291.67382) (xy 405.269204 -291.624766)
			(xy 404.930102 -291.624766) (xy 404.929607 -291.649373) (xy 404.921712 -291.69795) (xy 404.906128 -291.744631)
			(xy 404.883257 -291.788208) (xy 404.853692 -291.827552) (xy 404.818199 -291.861644) (xy 404.777696 -291.8896)
			(xy 404.733234 -291.910698) (xy 404.685963 -291.92439) (xy 404.637108 -291.930322) (xy 404.587933 -291.928341)
			(xy 404.539714 -291.918497) (xy 404.493698 -291.901045) (xy 404.451077 -291.876438) (xy 404.412956 -291.845313)
			(xy 404.380321 -291.808476) (xy 404.354018 -291.76688) (xy 404.334727 -291.721604) (xy 404.32295 -291.67382)
			(xy 404.31899 -291.624766) (xy 403.980142 -291.624766) (xy 403.979647 -291.649373) (xy 403.971752 -291.69795)
			(xy 403.956168 -291.744631) (xy 403.933297 -291.788208) (xy 403.903732 -291.827552) (xy 403.868239 -291.861644)
			(xy 403.827736 -291.8896) (xy 403.783274 -291.910698) (xy 403.736003 -291.92439) (xy 403.687148 -291.930322)
			(xy 403.637973 -291.928341) (xy 403.589754 -291.918497) (xy 403.543738 -291.901045) (xy 403.501117 -291.876438)
			(xy 403.462996 -291.845313) (xy 403.430361 -291.808476) (xy 403.404058 -291.76688) (xy 403.384767 -291.721604)
			(xy 403.37299 -291.67382) (xy 403.36903 -291.624766) (xy 403.030182 -291.624766) (xy 403.029687 -291.649373)
			(xy 403.021792 -291.69795) (xy 403.006208 -291.744631) (xy 402.983337 -291.788208) (xy 402.953772 -291.827552)
			(xy 402.918279 -291.861644) (xy 402.877776 -291.8896) (xy 402.833314 -291.910698) (xy 402.786043 -291.92439)
			(xy 402.737188 -291.930322) (xy 402.688013 -291.928341) (xy 402.639794 -291.918497) (xy 402.593778 -291.901045)
			(xy 402.551157 -291.876438) (xy 402.513036 -291.845313) (xy 402.480401 -291.808476) (xy 402.454098 -291.76688)
			(xy 402.434807 -291.721604) (xy 402.42303 -291.67382) (xy 402.41907 -291.624766) (xy 402.080222 -291.624766)
			(xy 402.079727 -291.649373) (xy 402.071832 -291.69795) (xy 402.056248 -291.744631) (xy 402.033377 -291.788208)
			(xy 402.003812 -291.827552) (xy 401.968319 -291.861644) (xy 401.927816 -291.8896) (xy 401.883354 -291.910698)
			(xy 401.836083 -291.92439) (xy 401.787228 -291.930322) (xy 401.738053 -291.928341) (xy 401.689834 -291.918497)
			(xy 401.643818 -291.901045) (xy 401.601197 -291.876438) (xy 401.563076 -291.845313) (xy 401.530441 -291.808476)
			(xy 401.504138 -291.76688) (xy 401.484847 -291.721604) (xy 401.47307 -291.67382) (xy 401.46911 -291.624766)
			(xy 401.130262 -291.624766) (xy 401.129767 -291.649373) (xy 401.121872 -291.69795) (xy 401.106288 -291.744631)
			(xy 401.083417 -291.788208) (xy 401.053852 -291.827552) (xy 401.018359 -291.861644) (xy 400.977856 -291.8896)
			(xy 400.933394 -291.910698) (xy 400.886123 -291.92439) (xy 400.837268 -291.930322) (xy 400.788093 -291.928341)
			(xy 400.739874 -291.918497) (xy 400.693858 -291.901045) (xy 400.651237 -291.876438) (xy 400.613116 -291.845313)
			(xy 400.580481 -291.808476) (xy 400.554178 -291.76688) (xy 400.534887 -291.721604) (xy 400.52311 -291.67382)
			(xy 400.51915 -291.624766) (xy 400.180302 -291.624766) (xy 400.179807 -291.649373) (xy 400.171912 -291.69795)
			(xy 400.156328 -291.744631) (xy 400.133457 -291.788208) (xy 400.103892 -291.827552) (xy 400.068399 -291.861644)
			(xy 400.027896 -291.8896) (xy 399.983434 -291.910698) (xy 399.936163 -291.92439) (xy 399.887308 -291.930322)
			(xy 399.838133 -291.928341) (xy 399.789914 -291.918497) (xy 399.743898 -291.901045) (xy 399.701277 -291.876438)
			(xy 399.663156 -291.845313) (xy 399.630521 -291.808476) (xy 399.604218 -291.76688) (xy 399.584927 -291.721604)
			(xy 399.57315 -291.67382) (xy 399.56919 -291.624766) (xy 399.230342 -291.624766) (xy 399.229847 -291.649373)
			(xy 399.221952 -291.69795) (xy 399.206368 -291.744631) (xy 399.183497 -291.788208) (xy 399.153932 -291.827552)
			(xy 399.118439 -291.861644) (xy 399.077936 -291.8896) (xy 399.033474 -291.910698) (xy 398.986203 -291.92439)
			(xy 398.937348 -291.930322) (xy 398.888173 -291.928341) (xy 398.839954 -291.918497) (xy 398.793938 -291.901045)
			(xy 398.751317 -291.876438) (xy 398.713196 -291.845313) (xy 398.680561 -291.808476) (xy 398.654258 -291.76688)
			(xy 398.634967 -291.721604) (xy 398.62319 -291.67382) (xy 398.61923 -291.624766) (xy 398.280128 -291.624766)
			(xy 398.279633 -291.649373) (xy 398.271738 -291.69795) (xy 398.256154 -291.744631) (xy 398.233283 -291.788208)
			(xy 398.203718 -291.827552) (xy 398.168225 -291.861644) (xy 398.127722 -291.8896) (xy 398.08326 -291.910698)
			(xy 398.035989 -291.92439) (xy 397.987134 -291.930322) (xy 397.937959 -291.928341) (xy 397.88974 -291.918497)
			(xy 397.843724 -291.901045) (xy 397.801103 -291.876438) (xy 397.762982 -291.845313) (xy 397.730347 -291.808476)
			(xy 397.704044 -291.76688) (xy 397.684753 -291.721604) (xy 397.672976 -291.67382) (xy 397.669016 -291.624766)
			(xy 397.35518 -291.624766) (xy 397.355181 -291.65116) (xy 397.346817 -291.703221) (xy 397.3303 -291.753296)
			(xy 397.306048 -291.800117) (xy 397.274676 -291.842497) (xy 397.236978 -291.879365) (xy 397.193909 -291.909784)
			(xy 397.146559 -291.932987) (xy 397.096129 -291.948384) (xy 397.070072 -291.952426) (xy 397.066008 -291.952934)
			(xy 397.054578 -291.95649) (xy 397.05026 -291.95776) (xy 397.02613 -291.968936) (xy 397.019526 -291.976048)
			(xy 397.004794 -291.991542) (xy 396.996666 -292.002718) (xy 396.993976 -292.00825) (xy 396.991032 -292.020191)
			(xy 396.990824 -292.02634) (xy 396.990824 -292.122098) (xy 441.55741 -292.122098) (xy 441.557853 -292.095494)
			(xy 441.565235 -292.0428) (xy 441.57987 -291.991644) (xy 441.601474 -291.943019) (xy 441.629626 -291.897869)
			(xy 441.663781 -291.85707) (xy 441.703276 -291.821415) (xy 441.72505 -291.806122) (xy 441.736488 -291.797731)
			(xy 441.754699 -291.776003) (xy 441.766224 -291.750101) (xy 441.770172 -291.722027) (xy 441.766239 -291.693951)
			(xy 441.754727 -291.668043) (xy 441.736528 -291.646305) (xy 441.72505 -291.637974) (xy 441.703261 -291.622704)
			(xy 441.663782 -291.587034) (xy 441.62964 -291.546226) (xy 441.601496 -291.501072) (xy 441.579897 -291.452447)
			(xy 441.565261 -291.401293) (xy 441.557871 -291.348601) (xy 441.55741 -291.321998) (xy 441.557896 -291.294747)
			(xy 441.565652 -291.240799) (xy 441.581007 -291.188504) (xy 441.603649 -291.138927) (xy 441.633115 -291.093077)
			(xy 441.668806 -291.051886) (xy 441.709997 -291.016195) (xy 441.755847 -290.986729) (xy 441.805424 -290.964087)
			(xy 441.857719 -290.948732) (xy 441.911667 -290.940976) (xy 441.966169 -290.940976) (xy 442.020117 -290.948732)
			(xy 442.072412 -290.964087) (xy 442.121989 -290.986729) (xy 442.167839 -291.016195) (xy 442.20903 -291.051886)
			(xy 442.244721 -291.093077) (xy 442.274187 -291.138927) (xy 442.296829 -291.188504) (xy 442.312184 -291.240799)
			(xy 442.31994 -291.294747) (xy 442.320426 -291.321998) (xy 442.320008 -291.348603) (xy 442.312625 -291.401299)
			(xy 442.297988 -291.452457) (xy 442.276381 -291.501083) (xy 442.248224 -291.546233) (xy 442.224928 -291.574056)
			(xy 450.443243 -291.574056) (xy 450.443243 -291.519544) (xy 450.451001 -291.465587) (xy 450.46636 -291.413284)
			(xy 450.489007 -291.363699) (xy 450.51848 -291.317843) (xy 450.55418 -291.276647) (xy 450.595379 -291.240953)
			(xy 450.64124 -291.211485) (xy 450.690827 -291.188844) (xy 450.743132 -291.173492) (xy 450.79709 -291.16574)
			(xy 450.824346 -291.16528) (xy 450.851716 -291.165758) (xy 450.905895 -291.17357) (xy 450.958399 -291.189055)
			(xy 451.008146 -291.211895) (xy 451.054113 -291.241619) (xy 451.075044 -291.25926) (xy 451.082156 -291.265356)
			(xy 451.099174 -291.271706) (xy 451.184518 -291.271706) (xy 451.201536 -291.265356) (xy 451.208648 -291.25926)
			(xy 451.229583 -291.241625) (xy 451.275556 -291.211914) (xy 451.325303 -291.189078) (xy 451.377802 -291.173585)
			(xy 451.431977 -291.165755) (xy 451.459346 -291.16528) (xy 451.486594 -291.165793) (xy 451.540535 -291.173555)
			(xy 451.592823 -291.188914) (xy 451.642393 -291.211557) (xy 451.688236 -291.241023) (xy 451.729419 -291.276714)
			(xy 451.765104 -291.317901) (xy 451.794565 -291.363748) (xy 451.817203 -291.41332) (xy 451.832555 -291.46561)
			(xy 451.84031 -291.519552) (xy 451.84031 -291.574048) (xy 451.840309 -291.574054) (xy 452.196643 -291.574054)
			(xy 452.196643 -291.519546) (xy 452.2044 -291.465593) (xy 452.219757 -291.413292) (xy 452.242401 -291.36371)
			(xy 452.271871 -291.317855) (xy 452.307566 -291.276661) (xy 452.348761 -291.240966) (xy 452.394617 -291.211497)
			(xy 452.4442 -291.188854) (xy 452.4965 -291.173499) (xy 452.550454 -291.165742) (xy 452.577708 -291.16528)
			(xy 452.605079 -291.165722) (xy 452.65926 -291.173543) (xy 452.711764 -291.189036) (xy 452.761511 -291.211884)
			(xy 452.807476 -291.241615) (xy 452.828406 -291.25926) (xy 452.835518 -291.265356) (xy 452.852536 -291.271706)
			(xy 452.93788 -291.271706) (xy 452.954898 -291.265356) (xy 452.96201 -291.25926) (xy 452.982922 -291.241596)
			(xy 453.028901 -291.211889) (xy 453.078654 -291.189059) (xy 453.131158 -291.173573) (xy 453.185338 -291.165751)
			(xy 453.212708 -291.16528) (xy 453.239958 -291.165791) (xy 453.293903 -291.173548) (xy 453.346195 -291.188903)
			(xy 453.39577 -291.211544) (xy 453.441618 -291.24101) (xy 453.482806 -291.2767) (xy 453.518495 -291.317889)
			(xy 453.54796 -291.363737) (xy 453.5706 -291.413312) (xy 453.585954 -291.465605) (xy 453.59371 -291.51955)
			(xy 453.59371 -291.57405) (xy 453.585954 -291.627995) (xy 453.5706 -291.680288) (xy 453.54796 -291.729863)
			(xy 453.518495 -291.775711) (xy 453.482806 -291.8169) (xy 453.441618 -291.85259) (xy 453.39577 -291.882056)
			(xy 453.346195 -291.904697) (xy 453.293903 -291.920052) (xy 453.239958 -291.927809) (xy 453.212708 -291.928296)
			(xy 453.185338 -291.927826) (xy 453.131159 -291.920009) (xy 453.078656 -291.904521) (xy 453.028909 -291.88168)
			(xy 452.982942 -291.851957) (xy 452.96201 -291.834316) (xy 452.954898 -291.82822) (xy 452.93788 -291.82187)
			(xy 452.852536 -291.82187) (xy 452.835518 -291.82822) (xy 452.828406 -291.834316) (xy 452.807485 -291.851968)
			(xy 452.761509 -291.881678) (xy 452.711758 -291.904511) (xy 452.659255 -291.919999) (xy 452.605078 -291.927824)
			(xy 452.577708 -291.928296) (xy 452.550454 -291.927858) (xy 452.4965 -291.920101) (xy 452.4442 -291.904746)
			(xy 452.394617 -291.882103) (xy 452.348761 -291.852634) (xy 452.307566 -291.816939) (xy 452.271871 -291.775745)
			(xy 452.242401 -291.72989) (xy 452.219757 -291.680308) (xy 452.2044 -291.628007) (xy 452.196643 -291.574054)
			(xy 451.840309 -291.574054) (xy 451.832555 -291.62799) (xy 451.817203 -291.68028) (xy 451.794565 -291.729852)
			(xy 451.765104 -291.775699) (xy 451.729419 -291.816886) (xy 451.688236 -291.852577) (xy 451.642393 -291.882043)
			(xy 451.592823 -291.904686) (xy 451.540535 -291.920045) (xy 451.486594 -291.927807) (xy 451.459346 -291.928296)
			(xy 451.431977 -291.927804) (xy 451.377799 -291.919993) (xy 451.325296 -291.90451) (xy 451.275549 -291.881674)
			(xy 451.229581 -291.851955) (xy 451.208648 -291.834316) (xy 451.201536 -291.82822) (xy 451.184518 -291.82187)
			(xy 451.099174 -291.82187) (xy 451.082156 -291.82822) (xy 451.075044 -291.834316) (xy 451.054108 -291.85195)
			(xy 451.008136 -291.881662) (xy 450.95839 -291.904499) (xy 450.90589 -291.919991) (xy 450.851715 -291.927821)
			(xy 450.824346 -291.928296) (xy 450.79709 -291.92786) (xy 450.743132 -291.920108) (xy 450.690827 -291.904756)
			(xy 450.64124 -291.882115) (xy 450.595379 -291.852647) (xy 450.55418 -291.816953) (xy 450.51848 -291.775757)
			(xy 450.489007 -291.729901) (xy 450.46636 -291.680316) (xy 450.451001 -291.628013) (xy 450.443243 -291.574056)
			(xy 442.224928 -291.574056) (xy 442.214064 -291.587031) (xy 442.174563 -291.622683) (xy 442.152786 -291.637974)
			(xy 442.141261 -291.64625) (xy 442.123058 -291.668007) (xy 442.111546 -291.693934) (xy 442.107612 -291.722027)
			(xy 442.11156 -291.750118) (xy 442.123087 -291.776039) (xy 442.141301 -291.797786) (xy 442.152786 -291.806122)
			(xy 442.174581 -291.821383) (xy 442.214058 -291.857056) (xy 442.248199 -291.897866) (xy 442.276341 -291.943021)
			(xy 442.297939 -291.991648) (xy 442.312575 -292.042803) (xy 442.319965 -292.095494) (xy 442.320426 -292.122098)
			(xy 442.31994 -292.149349) (xy 442.312184 -292.203297) (xy 442.296829 -292.255592) (xy 442.274187 -292.305169)
			(xy 442.244721 -292.351019) (xy 442.20903 -292.39221) (xy 442.167839 -292.427901) (xy 442.121989 -292.457367)
			(xy 442.072412 -292.480009) (xy 442.020117 -292.495364) (xy 441.966169 -292.50312) (xy 441.911667 -292.50312)
			(xy 441.857719 -292.495364) (xy 441.805424 -292.480009) (xy 441.755847 -292.457367) (xy 441.709997 -292.427901)
			(xy 441.668806 -292.39221) (xy 441.633115 -292.351019) (xy 441.603649 -292.305169) (xy 441.581007 -292.255592)
			(xy 441.565652 -292.203297) (xy 441.557896 -292.149349) (xy 441.55741 -292.122098) (xy 396.990824 -292.122098)
			(xy 396.990824 -292.173152) (xy 396.990991 -292.179306) (xy 396.993941 -292.191254) (xy 396.996666 -292.196774)
			(xy 397.004794 -292.20795) (xy 397.019526 -292.223444) (xy 397.02613 -292.230556) (xy 397.05026 -292.241732)
			(xy 397.054578 -292.243002) (xy 397.066008 -292.246558) (xy 397.070072 -292.247066) (xy 397.096115 -292.251174)
			(xy 397.146536 -292.266568) (xy 397.193877 -292.289766) (xy 397.236939 -292.32018) (xy 397.27463 -292.357041)
			(xy 397.305997 -292.399414) (xy 397.330244 -292.446226) (xy 397.346759 -292.496292) (xy 397.355121 -292.548344)
			(xy 397.355121 -292.574726) (xy 397.669016 -292.574726) (xy 397.672976 -292.525672) (xy 397.684753 -292.477888)
			(xy 397.704044 -292.432612) (xy 397.730347 -292.391016) (xy 397.762982 -292.354179) (xy 397.801103 -292.323054)
			(xy 397.843724 -292.298447) (xy 397.88974 -292.280995) (xy 397.937959 -292.271151) (xy 397.987134 -292.26917)
			(xy 398.035989 -292.275102) (xy 398.08326 -292.288794) (xy 398.127722 -292.309892) (xy 398.168225 -292.337848)
			(xy 398.203718 -292.37194) (xy 398.233283 -292.411284) (xy 398.256154 -292.454861) (xy 398.271738 -292.501542)
			(xy 398.279633 -292.550119) (xy 398.280128 -292.574726) (xy 398.280123 -292.57498) (xy 398.61923 -292.57498)
			(xy 398.62319 -292.525926) (xy 398.634967 -292.478142) (xy 398.654258 -292.432866) (xy 398.680561 -292.39127)
			(xy 398.713196 -292.354433) (xy 398.751317 -292.323308) (xy 398.793938 -292.298701) (xy 398.839954 -292.281249)
			(xy 398.888173 -292.271405) (xy 398.937348 -292.269424) (xy 398.986203 -292.275356) (xy 399.033474 -292.289048)
			(xy 399.077936 -292.310146) (xy 399.118439 -292.338102) (xy 399.153932 -292.372194) (xy 399.183497 -292.411538)
			(xy 399.206368 -292.455115) (xy 399.221952 -292.501796) (xy 399.229847 -292.550373) (xy 399.230342 -292.57498)
			(xy 399.56919 -292.57498) (xy 399.57315 -292.525926) (xy 399.584927 -292.478142) (xy 399.604218 -292.432866)
			(xy 399.630521 -292.39127) (xy 399.663156 -292.354433) (xy 399.701277 -292.323308) (xy 399.743898 -292.298701)
			(xy 399.789914 -292.281249) (xy 399.838133 -292.271405) (xy 399.887308 -292.269424) (xy 399.936163 -292.275356)
			(xy 399.983434 -292.289048) (xy 400.027896 -292.310146) (xy 400.068399 -292.338102) (xy 400.103892 -292.372194)
			(xy 400.133457 -292.411538) (xy 400.156328 -292.455115) (xy 400.171912 -292.501796) (xy 400.179807 -292.550373)
			(xy 400.180302 -292.57498) (xy 400.51915 -292.57498) (xy 400.52311 -292.525926) (xy 400.534887 -292.478142)
			(xy 400.554178 -292.432866) (xy 400.580481 -292.39127) (xy 400.613116 -292.354433) (xy 400.651237 -292.323308)
			(xy 400.693858 -292.298701) (xy 400.739874 -292.281249) (xy 400.788093 -292.271405) (xy 400.837268 -292.269424)
			(xy 400.886123 -292.275356) (xy 400.933394 -292.289048) (xy 400.977856 -292.310146) (xy 401.018359 -292.338102)
			(xy 401.053852 -292.372194) (xy 401.083417 -292.411538) (xy 401.106288 -292.455115) (xy 401.121872 -292.501796)
			(xy 401.129767 -292.550373) (xy 401.130262 -292.57498) (xy 401.46911 -292.57498) (xy 401.47307 -292.525926)
			(xy 401.484847 -292.478142) (xy 401.504138 -292.432866) (xy 401.530441 -292.39127) (xy 401.563076 -292.354433)
			(xy 401.601197 -292.323308) (xy 401.643818 -292.298701) (xy 401.689834 -292.281249) (xy 401.738053 -292.271405)
			(xy 401.787228 -292.269424) (xy 401.836083 -292.275356) (xy 401.883354 -292.289048) (xy 401.927816 -292.310146)
			(xy 401.968319 -292.338102) (xy 402.003812 -292.372194) (xy 402.033377 -292.411538) (xy 402.056248 -292.455115)
			(xy 402.071832 -292.501796) (xy 402.079727 -292.550373) (xy 402.080222 -292.57498) (xy 402.41907 -292.57498)
			(xy 402.42303 -292.525926) (xy 402.434807 -292.478142) (xy 402.454098 -292.432866) (xy 402.480401 -292.39127)
			(xy 402.513036 -292.354433) (xy 402.551157 -292.323308) (xy 402.593778 -292.298701) (xy 402.639794 -292.281249)
			(xy 402.688013 -292.271405) (xy 402.737188 -292.269424) (xy 402.786043 -292.275356) (xy 402.833314 -292.289048)
			(xy 402.877776 -292.310146) (xy 402.918279 -292.338102) (xy 402.953772 -292.372194) (xy 402.983337 -292.411538)
			(xy 403.006208 -292.455115) (xy 403.021792 -292.501796) (xy 403.029687 -292.550373) (xy 403.030182 -292.57498)
			(xy 403.36903 -292.57498) (xy 403.37299 -292.525926) (xy 403.384767 -292.478142) (xy 403.404058 -292.432866)
			(xy 403.430361 -292.39127) (xy 403.462996 -292.354433) (xy 403.501117 -292.323308) (xy 403.543738 -292.298701)
			(xy 403.589754 -292.281249) (xy 403.637973 -292.271405) (xy 403.687148 -292.269424) (xy 403.736003 -292.275356)
			(xy 403.783274 -292.289048) (xy 403.827736 -292.310146) (xy 403.868239 -292.338102) (xy 403.903732 -292.372194)
			(xy 403.933297 -292.411538) (xy 403.956168 -292.455115) (xy 403.971752 -292.501796) (xy 403.979647 -292.550373)
			(xy 403.980142 -292.57498) (xy 404.319244 -292.57498) (xy 404.323204 -292.525926) (xy 404.334981 -292.478142)
			(xy 404.354272 -292.432866) (xy 404.380575 -292.39127) (xy 404.41321 -292.354433) (xy 404.451331 -292.323308)
			(xy 404.493952 -292.298701) (xy 404.539968 -292.281249) (xy 404.588187 -292.271405) (xy 404.637362 -292.269424)
			(xy 404.686217 -292.275356) (xy 404.733488 -292.289048) (xy 404.77795 -292.310146) (xy 404.818453 -292.338102)
			(xy 404.853946 -292.372194) (xy 404.883511 -292.411538) (xy 404.906382 -292.455115) (xy 404.921966 -292.501796)
			(xy 404.929861 -292.550373) (xy 404.930356 -292.57498) (xy 405.269204 -292.57498) (xy 405.273164 -292.525926)
			(xy 405.284941 -292.478142) (xy 405.304232 -292.432866) (xy 405.330535 -292.39127) (xy 405.36317 -292.354433)
			(xy 405.401291 -292.323308) (xy 405.443912 -292.298701) (xy 405.489928 -292.281249) (xy 405.538147 -292.271405)
			(xy 405.587322 -292.269424) (xy 405.636177 -292.275356) (xy 405.683448 -292.289048) (xy 405.72791 -292.310146)
			(xy 405.768413 -292.338102) (xy 405.803906 -292.372194) (xy 405.833471 -292.411538) (xy 405.856342 -292.455115)
			(xy 405.871926 -292.501796) (xy 405.879821 -292.550373) (xy 405.880316 -292.57498) (xy 406.219164 -292.57498)
			(xy 406.223124 -292.525926) (xy 406.234901 -292.478142) (xy 406.254192 -292.432866) (xy 406.280495 -292.39127)
			(xy 406.31313 -292.354433) (xy 406.351251 -292.323308) (xy 406.393872 -292.298701) (xy 406.439888 -292.281249)
			(xy 406.488107 -292.271405) (xy 406.537282 -292.269424) (xy 406.586137 -292.275356) (xy 406.633408 -292.289048)
			(xy 406.67787 -292.310146) (xy 406.718373 -292.338102) (xy 406.753866 -292.372194) (xy 406.783431 -292.411538)
			(xy 406.806302 -292.455115) (xy 406.821886 -292.501796) (xy 406.829781 -292.550373) (xy 406.830271 -292.574726)
			(xy 408.119084 -292.574726) (xy 408.123044 -292.525672) (xy 408.134821 -292.477888) (xy 408.154112 -292.432612)
			(xy 408.180415 -292.391016) (xy 408.21305 -292.354179) (xy 408.251171 -292.323054) (xy 408.293792 -292.298447)
			(xy 408.339808 -292.280995) (xy 408.388027 -292.271151) (xy 408.437202 -292.26917) (xy 408.486057 -292.275102)
			(xy 408.533328 -292.288794) (xy 408.57779 -292.309892) (xy 408.618293 -292.337848) (xy 408.653786 -292.37194)
			(xy 408.683351 -292.411284) (xy 408.706222 -292.454861) (xy 408.721806 -292.501542) (xy 408.729701 -292.550119)
			(xy 408.730196 -292.574726) (xy 409.069044 -292.574726) (xy 409.073004 -292.525672) (xy 409.084781 -292.477888)
			(xy 409.104072 -292.432612) (xy 409.130375 -292.391016) (xy 409.16301 -292.354179) (xy 409.201131 -292.323054)
			(xy 409.243752 -292.298447) (xy 409.289768 -292.280995) (xy 409.337987 -292.271151) (xy 409.387162 -292.26917)
			(xy 409.436017 -292.275102) (xy 409.483288 -292.288794) (xy 409.52775 -292.309892) (xy 409.568253 -292.337848)
			(xy 409.603746 -292.37194) (xy 409.633311 -292.411284) (xy 409.656182 -292.454861) (xy 409.671766 -292.501542)
			(xy 409.679661 -292.550119) (xy 409.680156 -292.574726) (xy 410.019004 -292.574726) (xy 410.022964 -292.525672)
			(xy 410.034741 -292.477888) (xy 410.054032 -292.432612) (xy 410.080335 -292.391016) (xy 410.11297 -292.354179)
			(xy 410.151091 -292.323054) (xy 410.193712 -292.298447) (xy 410.239728 -292.280995) (xy 410.287947 -292.271151)
			(xy 410.337122 -292.26917) (xy 410.385977 -292.275102) (xy 410.433248 -292.288794) (xy 410.47771 -292.309892)
			(xy 410.518213 -292.337848) (xy 410.553706 -292.37194) (xy 410.583271 -292.411284) (xy 410.606142 -292.454861)
			(xy 410.621726 -292.501542) (xy 410.629621 -292.550119) (xy 410.630116 -292.574726) (xy 410.969218 -292.574726)
			(xy 410.973178 -292.525672) (xy 410.984955 -292.477888) (xy 411.004246 -292.432612) (xy 411.030549 -292.391016)
			(xy 411.063184 -292.354179) (xy 411.101305 -292.323054) (xy 411.143926 -292.298447) (xy 411.189942 -292.280995)
			(xy 411.238161 -292.271151) (xy 411.287336 -292.26917) (xy 411.336191 -292.275102) (xy 411.383462 -292.288794)
			(xy 411.427924 -292.309892) (xy 411.468427 -292.337848) (xy 411.50392 -292.37194) (xy 411.533485 -292.411284)
			(xy 411.556356 -292.454861) (xy 411.57194 -292.501542) (xy 411.579835 -292.550119) (xy 411.58033 -292.574726)
			(xy 411.919178 -292.574726) (xy 411.923138 -292.525672) (xy 411.934915 -292.477888) (xy 411.954206 -292.432612)
			(xy 411.980509 -292.391016) (xy 412.013144 -292.354179) (xy 412.051265 -292.323054) (xy 412.093886 -292.298447)
			(xy 412.139902 -292.280995) (xy 412.188121 -292.271151) (xy 412.237296 -292.26917) (xy 412.286151 -292.275102)
			(xy 412.333422 -292.288794) (xy 412.377884 -292.309892) (xy 412.418387 -292.337848) (xy 412.45388 -292.37194)
			(xy 412.483445 -292.411284) (xy 412.506316 -292.454861) (xy 412.5219 -292.501542) (xy 412.529795 -292.550119)
			(xy 412.53029 -292.574726) (xy 412.869138 -292.574726) (xy 412.873098 -292.525672) (xy 412.884875 -292.477888)
			(xy 412.904166 -292.432612) (xy 412.930469 -292.391016) (xy 412.963104 -292.354179) (xy 413.001225 -292.323054)
			(xy 413.043846 -292.298447) (xy 413.089862 -292.280995) (xy 413.138081 -292.271151) (xy 413.187256 -292.26917)
			(xy 413.236111 -292.275102) (xy 413.283382 -292.288794) (xy 413.327844 -292.309892) (xy 413.368347 -292.337848)
			(xy 413.40384 -292.37194) (xy 413.433405 -292.411284) (xy 413.456276 -292.454861) (xy 413.47186 -292.501542)
			(xy 413.479755 -292.550119) (xy 413.48025 -292.574726) (xy 413.819098 -292.574726) (xy 413.823058 -292.525672)
			(xy 413.834835 -292.477888) (xy 413.854126 -292.432612) (xy 413.880429 -292.391016) (xy 413.913064 -292.354179)
			(xy 413.951185 -292.323054) (xy 413.993806 -292.298447) (xy 414.039822 -292.280995) (xy 414.088041 -292.271151)
			(xy 414.137216 -292.26917) (xy 414.186071 -292.275102) (xy 414.233342 -292.288794) (xy 414.277804 -292.309892)
			(xy 414.318307 -292.337848) (xy 414.3538 -292.37194) (xy 414.383365 -292.411284) (xy 414.406236 -292.454861)
			(xy 414.42182 -292.501542) (xy 414.429715 -292.550119) (xy 414.43021 -292.574726) (xy 414.769058 -292.574726)
			(xy 414.773018 -292.525672) (xy 414.784795 -292.477888) (xy 414.804086 -292.432612) (xy 414.830389 -292.391016)
			(xy 414.863024 -292.354179) (xy 414.901145 -292.323054) (xy 414.943766 -292.298447) (xy 414.989782 -292.280995)
			(xy 415.038001 -292.271151) (xy 415.087176 -292.26917) (xy 415.136031 -292.275102) (xy 415.183302 -292.288794)
			(xy 415.227764 -292.309892) (xy 415.268267 -292.337848) (xy 415.30376 -292.37194) (xy 415.333325 -292.411284)
			(xy 415.356196 -292.454861) (xy 415.37178 -292.501542) (xy 415.379675 -292.550119) (xy 415.38017 -292.574726)
			(xy 415.719018 -292.574726) (xy 415.722978 -292.525672) (xy 415.734755 -292.477888) (xy 415.754046 -292.432612)
			(xy 415.780349 -292.391016) (xy 415.812984 -292.354179) (xy 415.851105 -292.323054) (xy 415.893726 -292.298447)
			(xy 415.939742 -292.280995) (xy 415.987961 -292.271151) (xy 416.037136 -292.26917) (xy 416.085991 -292.275102)
			(xy 416.133262 -292.288794) (xy 416.177724 -292.309892) (xy 416.218227 -292.337848) (xy 416.25372 -292.37194)
			(xy 416.283285 -292.411284) (xy 416.306156 -292.454861) (xy 416.32174 -292.501542) (xy 416.329635 -292.550119)
			(xy 416.33013 -292.574726) (xy 416.668978 -292.574726) (xy 416.672938 -292.525672) (xy 416.684715 -292.477888)
			(xy 416.704006 -292.432612) (xy 416.730309 -292.391016) (xy 416.762944 -292.354179) (xy 416.801065 -292.323054)
			(xy 416.843686 -292.298447) (xy 416.889702 -292.280995) (xy 416.937921 -292.271151) (xy 416.987096 -292.26917)
			(xy 417.035951 -292.275102) (xy 417.083222 -292.288794) (xy 417.127684 -292.309892) (xy 417.168187 -292.337848)
			(xy 417.20368 -292.37194) (xy 417.233245 -292.411284) (xy 417.256116 -292.454861) (xy 417.2717 -292.501542)
			(xy 417.279595 -292.550119) (xy 417.28009 -292.574726) (xy 417.619192 -292.574726) (xy 417.623152 -292.525672)
			(xy 417.634929 -292.477888) (xy 417.65422 -292.432612) (xy 417.680523 -292.391016) (xy 417.713158 -292.354179)
			(xy 417.751279 -292.323054) (xy 417.7939 -292.298447) (xy 417.839916 -292.280995) (xy 417.888135 -292.271151)
			(xy 417.93731 -292.26917) (xy 417.986165 -292.275102) (xy 418.033436 -292.288794) (xy 418.077898 -292.309892)
			(xy 418.118401 -292.337848) (xy 418.153894 -292.37194) (xy 418.183459 -292.411284) (xy 418.20633 -292.454861)
			(xy 418.221914 -292.501542) (xy 418.229809 -292.550119) (xy 418.230304 -292.574726) (xy 418.230299 -292.57498)
			(xy 418.569152 -292.57498) (xy 418.573112 -292.525926) (xy 418.584889 -292.478142) (xy 418.60418 -292.432866)
			(xy 418.630483 -292.39127) (xy 418.663118 -292.354433) (xy 418.701239 -292.323308) (xy 418.74386 -292.298701)
			(xy 418.789876 -292.281249) (xy 418.838095 -292.271405) (xy 418.88727 -292.269424) (xy 418.936125 -292.275356)
			(xy 418.983396 -292.289048) (xy 419.027858 -292.310146) (xy 419.068361 -292.338102) (xy 419.103854 -292.372194)
			(xy 419.133419 -292.411538) (xy 419.15629 -292.455115) (xy 419.171874 -292.501796) (xy 419.179769 -292.550373)
			(xy 419.180259 -292.574726) (xy 419.519112 -292.574726) (xy 419.523072 -292.525672) (xy 419.534849 -292.477888)
			(xy 419.55414 -292.432612) (xy 419.580443 -292.391016) (xy 419.613078 -292.354179) (xy 419.651199 -292.323054)
			(xy 419.69382 -292.298447) (xy 419.739836 -292.280995) (xy 419.788055 -292.271151) (xy 419.83723 -292.26917)
			(xy 419.886085 -292.275102) (xy 419.933356 -292.288794) (xy 419.977818 -292.309892) (xy 420.018321 -292.337848)
			(xy 420.053814 -292.37194) (xy 420.083379 -292.411284) (xy 420.10625 -292.454861) (xy 420.121834 -292.501542)
			(xy 420.129729 -292.550119) (xy 420.130224 -292.574726) (xy 420.469072 -292.574726) (xy 420.473032 -292.525672)
			(xy 420.484809 -292.477888) (xy 420.5041 -292.432612) (xy 420.530403 -292.391016) (xy 420.563038 -292.354179)
			(xy 420.601159 -292.323054) (xy 420.64378 -292.298447) (xy 420.689796 -292.280995) (xy 420.738015 -292.271151)
			(xy 420.78719 -292.26917) (xy 420.836045 -292.275102) (xy 420.883316 -292.288794) (xy 420.927778 -292.309892)
			(xy 420.968281 -292.337848) (xy 421.003774 -292.37194) (xy 421.033339 -292.411284) (xy 421.05621 -292.454861)
			(xy 421.071794 -292.501542) (xy 421.079689 -292.550119) (xy 421.080184 -292.574726) (xy 421.419032 -292.574726)
			(xy 421.422992 -292.525672) (xy 421.434769 -292.477888) (xy 421.45406 -292.432612) (xy 421.480363 -292.391016)
			(xy 421.512998 -292.354179) (xy 421.551119 -292.323054) (xy 421.59374 -292.298447) (xy 421.639756 -292.280995)
			(xy 421.687975 -292.271151) (xy 421.73715 -292.26917) (xy 421.786005 -292.275102) (xy 421.833276 -292.288794)
			(xy 421.877738 -292.309892) (xy 421.918241 -292.337848) (xy 421.953734 -292.37194) (xy 421.983299 -292.411284)
			(xy 422.00617 -292.454861) (xy 422.021754 -292.501542) (xy 422.029649 -292.550119) (xy 422.030144 -292.574726)
			(xy 422.368992 -292.574726) (xy 422.372952 -292.525672) (xy 422.384729 -292.477888) (xy 422.40402 -292.432612)
			(xy 422.430323 -292.391016) (xy 422.462958 -292.354179) (xy 422.501079 -292.323054) (xy 422.5437 -292.298447)
			(xy 422.589716 -292.280995) (xy 422.637935 -292.271151) (xy 422.68711 -292.26917) (xy 422.735965 -292.275102)
			(xy 422.783236 -292.288794) (xy 422.827698 -292.309892) (xy 422.868201 -292.337848) (xy 422.903694 -292.37194)
			(xy 422.933259 -292.411284) (xy 422.95613 -292.454861) (xy 422.971714 -292.501542) (xy 422.979609 -292.550119)
			(xy 422.980104 -292.574726) (xy 423.319206 -292.574726) (xy 423.323166 -292.525672) (xy 423.334943 -292.477888)
			(xy 423.354234 -292.432612) (xy 423.380537 -292.391016) (xy 423.413172 -292.354179) (xy 423.451293 -292.323054)
			(xy 423.493914 -292.298447) (xy 423.53993 -292.280995) (xy 423.588149 -292.271151) (xy 423.637324 -292.26917)
			(xy 423.686179 -292.275102) (xy 423.73345 -292.288794) (xy 423.777912 -292.309892) (xy 423.818415 -292.337848)
			(xy 423.853908 -292.37194) (xy 423.883473 -292.411284) (xy 423.906344 -292.454861) (xy 423.921928 -292.501542)
			(xy 423.929823 -292.550119) (xy 423.930318 -292.574726) (xy 424.269166 -292.574726) (xy 424.273126 -292.525672)
			(xy 424.284903 -292.477888) (xy 424.304194 -292.432612) (xy 424.330497 -292.391016) (xy 424.363132 -292.354179)
			(xy 424.401253 -292.323054) (xy 424.443874 -292.298447) (xy 424.48989 -292.280995) (xy 424.538109 -292.271151)
			(xy 424.587284 -292.26917) (xy 424.636139 -292.275102) (xy 424.68341 -292.288794) (xy 424.727872 -292.309892)
			(xy 424.768375 -292.337848) (xy 424.803868 -292.37194) (xy 424.833433 -292.411284) (xy 424.856304 -292.454861)
			(xy 424.871888 -292.501542) (xy 424.879783 -292.550119) (xy 424.880278 -292.574726) (xy 425.219126 -292.574726)
			(xy 425.223086 -292.525672) (xy 425.234863 -292.477888) (xy 425.254154 -292.432612) (xy 425.280457 -292.391016)
			(xy 425.313092 -292.354179) (xy 425.351213 -292.323054) (xy 425.393834 -292.298447) (xy 425.43985 -292.280995)
			(xy 425.488069 -292.271151) (xy 425.537244 -292.26917) (xy 425.586099 -292.275102) (xy 425.63337 -292.288794)
			(xy 425.677832 -292.309892) (xy 425.718335 -292.337848) (xy 425.753828 -292.37194) (xy 425.783393 -292.411284)
			(xy 425.806264 -292.454861) (xy 425.821848 -292.501542) (xy 425.829743 -292.550119) (xy 425.830238 -292.574726)
			(xy 426.169086 -292.574726) (xy 426.173046 -292.525672) (xy 426.184823 -292.477888) (xy 426.204114 -292.432612)
			(xy 426.230417 -292.391016) (xy 426.263052 -292.354179) (xy 426.301173 -292.323054) (xy 426.343794 -292.298447)
			(xy 426.38981 -292.280995) (xy 426.438029 -292.271151) (xy 426.487204 -292.26917) (xy 426.536059 -292.275102)
			(xy 426.58333 -292.288794) (xy 426.627792 -292.309892) (xy 426.668295 -292.337848) (xy 426.703788 -292.37194)
			(xy 426.733353 -292.411284) (xy 426.756224 -292.454861) (xy 426.771808 -292.501542) (xy 426.779703 -292.550119)
			(xy 426.780198 -292.574726) (xy 427.119046 -292.574726) (xy 427.123006 -292.525672) (xy 427.134783 -292.477888)
			(xy 427.154074 -292.432612) (xy 427.180377 -292.391016) (xy 427.213012 -292.354179) (xy 427.251133 -292.323054)
			(xy 427.293754 -292.298447) (xy 427.33977 -292.280995) (xy 427.387989 -292.271151) (xy 427.437164 -292.26917)
			(xy 427.486019 -292.275102) (xy 427.53329 -292.288794) (xy 427.577752 -292.309892) (xy 427.618255 -292.337848)
			(xy 427.653748 -292.37194) (xy 427.683313 -292.411284) (xy 427.706184 -292.454861) (xy 427.721768 -292.501542)
			(xy 427.729663 -292.550119) (xy 427.730158 -292.574726) (xy 428.069006 -292.574726) (xy 428.072966 -292.525672)
			(xy 428.084743 -292.477888) (xy 428.104034 -292.432612) (xy 428.130337 -292.391016) (xy 428.162972 -292.354179)
			(xy 428.201093 -292.323054) (xy 428.243714 -292.298447) (xy 428.28973 -292.280995) (xy 428.337949 -292.271151)
			(xy 428.387124 -292.26917) (xy 428.435979 -292.275102) (xy 428.48325 -292.288794) (xy 428.527712 -292.309892)
			(xy 428.568215 -292.337848) (xy 428.603708 -292.37194) (xy 428.633273 -292.411284) (xy 428.656144 -292.454861)
			(xy 428.671728 -292.501542) (xy 428.679623 -292.550119) (xy 428.680118 -292.574726) (xy 429.01922 -292.574726)
			(xy 429.02318 -292.525672) (xy 429.034957 -292.477888) (xy 429.054248 -292.432612) (xy 429.080551 -292.391016)
			(xy 429.113186 -292.354179) (xy 429.151307 -292.323054) (xy 429.193928 -292.298447) (xy 429.239944 -292.280995)
			(xy 429.288163 -292.271151) (xy 429.337338 -292.26917) (xy 429.386193 -292.275102) (xy 429.433464 -292.288794)
			(xy 429.477926 -292.309892) (xy 429.518429 -292.337848) (xy 429.553922 -292.37194) (xy 429.583487 -292.411284)
			(xy 429.606358 -292.454861) (xy 429.621942 -292.501542) (xy 429.629837 -292.550119) (xy 429.630332 -292.574726)
			(xy 429.630327 -292.57498) (xy 429.96918 -292.57498) (xy 429.97314 -292.525926) (xy 429.984917 -292.478142)
			(xy 430.004208 -292.432866) (xy 430.030511 -292.39127) (xy 430.063146 -292.354433) (xy 430.101267 -292.323308)
			(xy 430.143888 -292.298701) (xy 430.189904 -292.281249) (xy 430.238123 -292.271405) (xy 430.287298 -292.269424)
			(xy 430.336153 -292.275356) (xy 430.383424 -292.289048) (xy 430.427886 -292.310146) (xy 430.468389 -292.338102)
			(xy 430.503882 -292.372194) (xy 430.533447 -292.411538) (xy 430.556318 -292.455115) (xy 430.571902 -292.501796)
			(xy 430.579797 -292.550373) (xy 430.580292 -292.57498) (xy 430.91914 -292.57498) (xy 430.9231 -292.525926)
			(xy 430.934877 -292.478142) (xy 430.954168 -292.432866) (xy 430.980471 -292.39127) (xy 431.013106 -292.354433)
			(xy 431.051227 -292.323308) (xy 431.093848 -292.298701) (xy 431.139864 -292.281249) (xy 431.188083 -292.271405)
			(xy 431.237258 -292.269424) (xy 431.286113 -292.275356) (xy 431.333384 -292.289048) (xy 431.377846 -292.310146)
			(xy 431.418349 -292.338102) (xy 431.453842 -292.372194) (xy 431.483407 -292.411538) (xy 431.506278 -292.455115)
			(xy 431.521862 -292.501796) (xy 431.529757 -292.550373) (xy 431.530252 -292.57498) (xy 431.529757 -292.599587)
			(xy 431.521862 -292.648164) (xy 431.506278 -292.694845) (xy 431.483407 -292.738422) (xy 431.453842 -292.777766)
			(xy 431.418349 -292.811858) (xy 431.377846 -292.839814) (xy 431.333384 -292.860912) (xy 431.286113 -292.874604)
			(xy 431.237258 -292.880536) (xy 431.188083 -292.878555) (xy 431.139864 -292.868711) (xy 431.093848 -292.851259)
			(xy 431.051227 -292.826652) (xy 431.013106 -292.795527) (xy 430.980471 -292.75869) (xy 430.954168 -292.717094)
			(xy 430.934877 -292.671818) (xy 430.9231 -292.624034) (xy 430.91914 -292.57498) (xy 430.580292 -292.57498)
			(xy 430.579797 -292.599587) (xy 430.571902 -292.648164) (xy 430.556318 -292.694845) (xy 430.533447 -292.738422)
			(xy 430.503882 -292.777766) (xy 430.468389 -292.811858) (xy 430.427886 -292.839814) (xy 430.383424 -292.860912)
			(xy 430.336153 -292.874604) (xy 430.287298 -292.880536) (xy 430.238123 -292.878555) (xy 430.189904 -292.868711)
			(xy 430.143888 -292.851259) (xy 430.101267 -292.826652) (xy 430.063146 -292.795527) (xy 430.030511 -292.75869)
			(xy 430.004208 -292.717094) (xy 429.984917 -292.671818) (xy 429.97314 -292.624034) (xy 429.96918 -292.57498)
			(xy 429.630327 -292.57498) (xy 429.629837 -292.599333) (xy 429.621942 -292.64791) (xy 429.606358 -292.694591)
			(xy 429.583487 -292.738168) (xy 429.553922 -292.777512) (xy 429.518429 -292.811604) (xy 429.477926 -292.83956)
			(xy 429.433464 -292.860658) (xy 429.386193 -292.87435) (xy 429.337338 -292.880282) (xy 429.288163 -292.878301)
			(xy 429.239944 -292.868457) (xy 429.193928 -292.851005) (xy 429.151307 -292.826398) (xy 429.113186 -292.795273)
			(xy 429.080551 -292.758436) (xy 429.054248 -292.71684) (xy 429.034957 -292.671564) (xy 429.02318 -292.62378)
			(xy 429.01922 -292.574726) (xy 428.680118 -292.574726) (xy 428.679623 -292.599333) (xy 428.671728 -292.64791)
			(xy 428.656144 -292.694591) (xy 428.633273 -292.738168) (xy 428.603708 -292.777512) (xy 428.568215 -292.811604)
			(xy 428.527712 -292.83956) (xy 428.48325 -292.860658) (xy 428.435979 -292.87435) (xy 428.387124 -292.880282)
			(xy 428.337949 -292.878301) (xy 428.28973 -292.868457) (xy 428.243714 -292.851005) (xy 428.201093 -292.826398)
			(xy 428.162972 -292.795273) (xy 428.130337 -292.758436) (xy 428.104034 -292.71684) (xy 428.084743 -292.671564)
			(xy 428.072966 -292.62378) (xy 428.069006 -292.574726) (xy 427.730158 -292.574726) (xy 427.729663 -292.599333)
			(xy 427.721768 -292.64791) (xy 427.706184 -292.694591) (xy 427.683313 -292.738168) (xy 427.653748 -292.777512)
			(xy 427.618255 -292.811604) (xy 427.577752 -292.83956) (xy 427.53329 -292.860658) (xy 427.486019 -292.87435)
			(xy 427.437164 -292.880282) (xy 427.387989 -292.878301) (xy 427.33977 -292.868457) (xy 427.293754 -292.851005)
			(xy 427.251133 -292.826398) (xy 427.213012 -292.795273) (xy 427.180377 -292.758436) (xy 427.154074 -292.71684)
			(xy 427.134783 -292.671564) (xy 427.123006 -292.62378) (xy 427.119046 -292.574726) (xy 426.780198 -292.574726)
			(xy 426.779703 -292.599333) (xy 426.771808 -292.64791) (xy 426.756224 -292.694591) (xy 426.733353 -292.738168)
			(xy 426.703788 -292.777512) (xy 426.668295 -292.811604) (xy 426.627792 -292.83956) (xy 426.58333 -292.860658)
			(xy 426.536059 -292.87435) (xy 426.487204 -292.880282) (xy 426.438029 -292.878301) (xy 426.38981 -292.868457)
			(xy 426.343794 -292.851005) (xy 426.301173 -292.826398) (xy 426.263052 -292.795273) (xy 426.230417 -292.758436)
			(xy 426.204114 -292.71684) (xy 426.184823 -292.671564) (xy 426.173046 -292.62378) (xy 426.169086 -292.574726)
			(xy 425.830238 -292.574726) (xy 425.829743 -292.599333) (xy 425.821848 -292.64791) (xy 425.806264 -292.694591)
			(xy 425.783393 -292.738168) (xy 425.753828 -292.777512) (xy 425.718335 -292.811604) (xy 425.677832 -292.83956)
			(xy 425.63337 -292.860658) (xy 425.586099 -292.87435) (xy 425.537244 -292.880282) (xy 425.488069 -292.878301)
			(xy 425.43985 -292.868457) (xy 425.393834 -292.851005) (xy 425.351213 -292.826398) (xy 425.313092 -292.795273)
			(xy 425.280457 -292.758436) (xy 425.254154 -292.71684) (xy 425.234863 -292.671564) (xy 425.223086 -292.62378)
			(xy 425.219126 -292.574726) (xy 424.880278 -292.574726) (xy 424.879783 -292.599333) (xy 424.871888 -292.64791)
			(xy 424.856304 -292.694591) (xy 424.833433 -292.738168) (xy 424.803868 -292.777512) (xy 424.768375 -292.811604)
			(xy 424.727872 -292.83956) (xy 424.68341 -292.860658) (xy 424.636139 -292.87435) (xy 424.587284 -292.880282)
			(xy 424.538109 -292.878301) (xy 424.48989 -292.868457) (xy 424.443874 -292.851005) (xy 424.401253 -292.826398)
			(xy 424.363132 -292.795273) (xy 424.330497 -292.758436) (xy 424.304194 -292.71684) (xy 424.284903 -292.671564)
			(xy 424.273126 -292.62378) (xy 424.269166 -292.574726) (xy 423.930318 -292.574726) (xy 423.929823 -292.599333)
			(xy 423.921928 -292.64791) (xy 423.906344 -292.694591) (xy 423.883473 -292.738168) (xy 423.853908 -292.777512)
			(xy 423.818415 -292.811604) (xy 423.777912 -292.83956) (xy 423.73345 -292.860658) (xy 423.686179 -292.87435)
			(xy 423.637324 -292.880282) (xy 423.588149 -292.878301) (xy 423.53993 -292.868457) (xy 423.493914 -292.851005)
			(xy 423.451293 -292.826398) (xy 423.413172 -292.795273) (xy 423.380537 -292.758436) (xy 423.354234 -292.71684)
			(xy 423.334943 -292.671564) (xy 423.323166 -292.62378) (xy 423.319206 -292.574726) (xy 422.980104 -292.574726)
			(xy 422.979609 -292.599333) (xy 422.971714 -292.64791) (xy 422.95613 -292.694591) (xy 422.933259 -292.738168)
			(xy 422.903694 -292.777512) (xy 422.868201 -292.811604) (xy 422.827698 -292.83956) (xy 422.783236 -292.860658)
			(xy 422.735965 -292.87435) (xy 422.68711 -292.880282) (xy 422.637935 -292.878301) (xy 422.589716 -292.868457)
			(xy 422.5437 -292.851005) (xy 422.501079 -292.826398) (xy 422.462958 -292.795273) (xy 422.430323 -292.758436)
			(xy 422.40402 -292.71684) (xy 422.384729 -292.671564) (xy 422.372952 -292.62378) (xy 422.368992 -292.574726)
			(xy 422.030144 -292.574726) (xy 422.029649 -292.599333) (xy 422.021754 -292.64791) (xy 422.00617 -292.694591)
			(xy 421.983299 -292.738168) (xy 421.953734 -292.777512) (xy 421.918241 -292.811604) (xy 421.877738 -292.83956)
			(xy 421.833276 -292.860658) (xy 421.786005 -292.87435) (xy 421.73715 -292.880282) (xy 421.687975 -292.878301)
			(xy 421.639756 -292.868457) (xy 421.59374 -292.851005) (xy 421.551119 -292.826398) (xy 421.512998 -292.795273)
			(xy 421.480363 -292.758436) (xy 421.45406 -292.71684) (xy 421.434769 -292.671564) (xy 421.422992 -292.62378)
			(xy 421.419032 -292.574726) (xy 421.080184 -292.574726) (xy 421.079689 -292.599333) (xy 421.071794 -292.64791)
			(xy 421.05621 -292.694591) (xy 421.033339 -292.738168) (xy 421.003774 -292.777512) (xy 420.968281 -292.811604)
			(xy 420.927778 -292.83956) (xy 420.883316 -292.860658) (xy 420.836045 -292.87435) (xy 420.78719 -292.880282)
			(xy 420.738015 -292.878301) (xy 420.689796 -292.868457) (xy 420.64378 -292.851005) (xy 420.601159 -292.826398)
			(xy 420.563038 -292.795273) (xy 420.530403 -292.758436) (xy 420.5041 -292.71684) (xy 420.484809 -292.671564)
			(xy 420.473032 -292.62378) (xy 420.469072 -292.574726) (xy 420.130224 -292.574726) (xy 420.129729 -292.599333)
			(xy 420.121834 -292.64791) (xy 420.10625 -292.694591) (xy 420.083379 -292.738168) (xy 420.053814 -292.777512)
			(xy 420.018321 -292.811604) (xy 419.977818 -292.83956) (xy 419.933356 -292.860658) (xy 419.886085 -292.87435)
			(xy 419.83723 -292.880282) (xy 419.788055 -292.878301) (xy 419.739836 -292.868457) (xy 419.69382 -292.851005)
			(xy 419.651199 -292.826398) (xy 419.613078 -292.795273) (xy 419.580443 -292.758436) (xy 419.55414 -292.71684)
			(xy 419.534849 -292.671564) (xy 419.523072 -292.62378) (xy 419.519112 -292.574726) (xy 419.180259 -292.574726)
			(xy 419.180264 -292.57498) (xy 419.179769 -292.599587) (xy 419.171874 -292.648164) (xy 419.15629 -292.694845)
			(xy 419.133419 -292.738422) (xy 419.103854 -292.777766) (xy 419.068361 -292.811858) (xy 419.027858 -292.839814)
			(xy 418.983396 -292.860912) (xy 418.936125 -292.874604) (xy 418.88727 -292.880536) (xy 418.838095 -292.878555)
			(xy 418.789876 -292.868711) (xy 418.74386 -292.851259) (xy 418.701239 -292.826652) (xy 418.663118 -292.795527)
			(xy 418.630483 -292.75869) (xy 418.60418 -292.717094) (xy 418.584889 -292.671818) (xy 418.573112 -292.624034)
			(xy 418.569152 -292.57498) (xy 418.230299 -292.57498) (xy 418.229809 -292.599333) (xy 418.221914 -292.64791)
			(xy 418.20633 -292.694591) (xy 418.183459 -292.738168) (xy 418.153894 -292.777512) (xy 418.118401 -292.811604)
			(xy 418.077898 -292.83956) (xy 418.033436 -292.860658) (xy 417.986165 -292.87435) (xy 417.93731 -292.880282)
			(xy 417.888135 -292.878301) (xy 417.839916 -292.868457) (xy 417.7939 -292.851005) (xy 417.751279 -292.826398)
			(xy 417.713158 -292.795273) (xy 417.680523 -292.758436) (xy 417.65422 -292.71684) (xy 417.634929 -292.671564)
			(xy 417.623152 -292.62378) (xy 417.619192 -292.574726) (xy 417.28009 -292.574726) (xy 417.279595 -292.599333)
			(xy 417.2717 -292.64791) (xy 417.256116 -292.694591) (xy 417.233245 -292.738168) (xy 417.20368 -292.777512)
			(xy 417.168187 -292.811604) (xy 417.127684 -292.83956) (xy 417.083222 -292.860658) (xy 417.035951 -292.87435)
			(xy 416.987096 -292.880282) (xy 416.937921 -292.878301) (xy 416.889702 -292.868457) (xy 416.843686 -292.851005)
			(xy 416.801065 -292.826398) (xy 416.762944 -292.795273) (xy 416.730309 -292.758436) (xy 416.704006 -292.71684)
			(xy 416.684715 -292.671564) (xy 416.672938 -292.62378) (xy 416.668978 -292.574726) (xy 416.33013 -292.574726)
			(xy 416.329635 -292.599333) (xy 416.32174 -292.64791) (xy 416.306156 -292.694591) (xy 416.283285 -292.738168)
			(xy 416.25372 -292.777512) (xy 416.218227 -292.811604) (xy 416.177724 -292.83956) (xy 416.133262 -292.860658)
			(xy 416.085991 -292.87435) (xy 416.037136 -292.880282) (xy 415.987961 -292.878301) (xy 415.939742 -292.868457)
			(xy 415.893726 -292.851005) (xy 415.851105 -292.826398) (xy 415.812984 -292.795273) (xy 415.780349 -292.758436)
			(xy 415.754046 -292.71684) (xy 415.734755 -292.671564) (xy 415.722978 -292.62378) (xy 415.719018 -292.574726)
			(xy 415.38017 -292.574726) (xy 415.379675 -292.599333) (xy 415.37178 -292.64791) (xy 415.356196 -292.694591)
			(xy 415.333325 -292.738168) (xy 415.30376 -292.777512) (xy 415.268267 -292.811604) (xy 415.227764 -292.83956)
			(xy 415.183302 -292.860658) (xy 415.136031 -292.87435) (xy 415.087176 -292.880282) (xy 415.038001 -292.878301)
			(xy 414.989782 -292.868457) (xy 414.943766 -292.851005) (xy 414.901145 -292.826398) (xy 414.863024 -292.795273)
			(xy 414.830389 -292.758436) (xy 414.804086 -292.71684) (xy 414.784795 -292.671564) (xy 414.773018 -292.62378)
			(xy 414.769058 -292.574726) (xy 414.43021 -292.574726) (xy 414.429715 -292.599333) (xy 414.42182 -292.64791)
			(xy 414.406236 -292.694591) (xy 414.383365 -292.738168) (xy 414.3538 -292.777512) (xy 414.318307 -292.811604)
			(xy 414.277804 -292.83956) (xy 414.233342 -292.860658) (xy 414.186071 -292.87435) (xy 414.137216 -292.880282)
			(xy 414.088041 -292.878301) (xy 414.039822 -292.868457) (xy 413.993806 -292.851005) (xy 413.951185 -292.826398)
			(xy 413.913064 -292.795273) (xy 413.880429 -292.758436) (xy 413.854126 -292.71684) (xy 413.834835 -292.671564)
			(xy 413.823058 -292.62378) (xy 413.819098 -292.574726) (xy 413.48025 -292.574726) (xy 413.479755 -292.599333)
			(xy 413.47186 -292.64791) (xy 413.456276 -292.694591) (xy 413.433405 -292.738168) (xy 413.40384 -292.777512)
			(xy 413.368347 -292.811604) (xy 413.327844 -292.83956) (xy 413.283382 -292.860658) (xy 413.236111 -292.87435)
			(xy 413.187256 -292.880282) (xy 413.138081 -292.878301) (xy 413.089862 -292.868457) (xy 413.043846 -292.851005)
			(xy 413.001225 -292.826398) (xy 412.963104 -292.795273) (xy 412.930469 -292.758436) (xy 412.904166 -292.71684)
			(xy 412.884875 -292.671564) (xy 412.873098 -292.62378) (xy 412.869138 -292.574726) (xy 412.53029 -292.574726)
			(xy 412.529795 -292.599333) (xy 412.5219 -292.64791) (xy 412.506316 -292.694591) (xy 412.483445 -292.738168)
			(xy 412.45388 -292.777512) (xy 412.418387 -292.811604) (xy 412.377884 -292.83956) (xy 412.333422 -292.860658)
			(xy 412.286151 -292.87435) (xy 412.237296 -292.880282) (xy 412.188121 -292.878301) (xy 412.139902 -292.868457)
			(xy 412.093886 -292.851005) (xy 412.051265 -292.826398) (xy 412.013144 -292.795273) (xy 411.980509 -292.758436)
			(xy 411.954206 -292.71684) (xy 411.934915 -292.671564) (xy 411.923138 -292.62378) (xy 411.919178 -292.574726)
			(xy 411.58033 -292.574726) (xy 411.579835 -292.599333) (xy 411.57194 -292.64791) (xy 411.556356 -292.694591)
			(xy 411.533485 -292.738168) (xy 411.50392 -292.777512) (xy 411.468427 -292.811604) (xy 411.427924 -292.83956)
			(xy 411.383462 -292.860658) (xy 411.336191 -292.87435) (xy 411.287336 -292.880282) (xy 411.238161 -292.878301)
			(xy 411.189942 -292.868457) (xy 411.143926 -292.851005) (xy 411.101305 -292.826398) (xy 411.063184 -292.795273)
			(xy 411.030549 -292.758436) (xy 411.004246 -292.71684) (xy 410.984955 -292.671564) (xy 410.973178 -292.62378)
			(xy 410.969218 -292.574726) (xy 410.630116 -292.574726) (xy 410.629621 -292.599333) (xy 410.621726 -292.64791)
			(xy 410.606142 -292.694591) (xy 410.583271 -292.738168) (xy 410.553706 -292.777512) (xy 410.518213 -292.811604)
			(xy 410.47771 -292.83956) (xy 410.433248 -292.860658) (xy 410.385977 -292.87435) (xy 410.337122 -292.880282)
			(xy 410.287947 -292.878301) (xy 410.239728 -292.868457) (xy 410.193712 -292.851005) (xy 410.151091 -292.826398)
			(xy 410.11297 -292.795273) (xy 410.080335 -292.758436) (xy 410.054032 -292.71684) (xy 410.034741 -292.671564)
			(xy 410.022964 -292.62378) (xy 410.019004 -292.574726) (xy 409.680156 -292.574726) (xy 409.679661 -292.599333)
			(xy 409.671766 -292.64791) (xy 409.656182 -292.694591) (xy 409.633311 -292.738168) (xy 409.603746 -292.777512)
			(xy 409.568253 -292.811604) (xy 409.52775 -292.83956) (xy 409.483288 -292.860658) (xy 409.436017 -292.87435)
			(xy 409.387162 -292.880282) (xy 409.337987 -292.878301) (xy 409.289768 -292.868457) (xy 409.243752 -292.851005)
			(xy 409.201131 -292.826398) (xy 409.16301 -292.795273) (xy 409.130375 -292.758436) (xy 409.104072 -292.71684)
			(xy 409.084781 -292.671564) (xy 409.073004 -292.62378) (xy 409.069044 -292.574726) (xy 408.730196 -292.574726)
			(xy 408.729701 -292.599333) (xy 408.721806 -292.64791) (xy 408.706222 -292.694591) (xy 408.683351 -292.738168)
			(xy 408.653786 -292.777512) (xy 408.618293 -292.811604) (xy 408.57779 -292.83956) (xy 408.533328 -292.860658)
			(xy 408.486057 -292.87435) (xy 408.437202 -292.880282) (xy 408.388027 -292.878301) (xy 408.339808 -292.868457)
			(xy 408.293792 -292.851005) (xy 408.251171 -292.826398) (xy 408.21305 -292.795273) (xy 408.180415 -292.758436)
			(xy 408.154112 -292.71684) (xy 408.134821 -292.671564) (xy 408.123044 -292.62378) (xy 408.119084 -292.574726)
			(xy 406.830271 -292.574726) (xy 406.830276 -292.57498) (xy 406.829781 -292.599587) (xy 406.821886 -292.648164)
			(xy 406.806302 -292.694845) (xy 406.783431 -292.738422) (xy 406.753866 -292.777766) (xy 406.718373 -292.811858)
			(xy 406.67787 -292.839814) (xy 406.633408 -292.860912) (xy 406.586137 -292.874604) (xy 406.537282 -292.880536)
			(xy 406.488107 -292.878555) (xy 406.439888 -292.868711) (xy 406.393872 -292.851259) (xy 406.351251 -292.826652)
			(xy 406.31313 -292.795527) (xy 406.280495 -292.75869) (xy 406.254192 -292.717094) (xy 406.234901 -292.671818)
			(xy 406.223124 -292.624034) (xy 406.219164 -292.57498) (xy 405.880316 -292.57498) (xy 405.879821 -292.599587)
			(xy 405.871926 -292.648164) (xy 405.856342 -292.694845) (xy 405.833471 -292.738422) (xy 405.803906 -292.777766)
			(xy 405.768413 -292.811858) (xy 405.72791 -292.839814) (xy 405.683448 -292.860912) (xy 405.636177 -292.874604)
			(xy 405.587322 -292.880536) (xy 405.538147 -292.878555) (xy 405.489928 -292.868711) (xy 405.443912 -292.851259)
			(xy 405.401291 -292.826652) (xy 405.36317 -292.795527) (xy 405.330535 -292.75869) (xy 405.304232 -292.717094)
			(xy 405.284941 -292.671818) (xy 405.273164 -292.624034) (xy 405.269204 -292.57498) (xy 404.930356 -292.57498)
			(xy 404.929861 -292.599587) (xy 404.921966 -292.648164) (xy 404.906382 -292.694845) (xy 404.883511 -292.738422)
			(xy 404.853946 -292.777766) (xy 404.818453 -292.811858) (xy 404.77795 -292.839814) (xy 404.733488 -292.860912)
			(xy 404.686217 -292.874604) (xy 404.637362 -292.880536) (xy 404.588187 -292.878555) (xy 404.539968 -292.868711)
			(xy 404.493952 -292.851259) (xy 404.451331 -292.826652) (xy 404.41321 -292.795527) (xy 404.380575 -292.75869)
			(xy 404.354272 -292.717094) (xy 404.334981 -292.671818) (xy 404.323204 -292.624034) (xy 404.319244 -292.57498)
			(xy 403.980142 -292.57498) (xy 403.979647 -292.599587) (xy 403.971752 -292.648164) (xy 403.956168 -292.694845)
			(xy 403.933297 -292.738422) (xy 403.903732 -292.777766) (xy 403.868239 -292.811858) (xy 403.827736 -292.839814)
			(xy 403.783274 -292.860912) (xy 403.736003 -292.874604) (xy 403.687148 -292.880536) (xy 403.637973 -292.878555)
			(xy 403.589754 -292.868711) (xy 403.543738 -292.851259) (xy 403.501117 -292.826652) (xy 403.462996 -292.795527)
			(xy 403.430361 -292.75869) (xy 403.404058 -292.717094) (xy 403.384767 -292.671818) (xy 403.37299 -292.624034)
			(xy 403.36903 -292.57498) (xy 403.030182 -292.57498) (xy 403.029687 -292.599587) (xy 403.021792 -292.648164)
			(xy 403.006208 -292.694845) (xy 402.983337 -292.738422) (xy 402.953772 -292.777766) (xy 402.918279 -292.811858)
			(xy 402.877776 -292.839814) (xy 402.833314 -292.860912) (xy 402.786043 -292.874604) (xy 402.737188 -292.880536)
			(xy 402.688013 -292.878555) (xy 402.639794 -292.868711) (xy 402.593778 -292.851259) (xy 402.551157 -292.826652)
			(xy 402.513036 -292.795527) (xy 402.480401 -292.75869) (xy 402.454098 -292.717094) (xy 402.434807 -292.671818)
			(xy 402.42303 -292.624034) (xy 402.41907 -292.57498) (xy 402.080222 -292.57498) (xy 402.079727 -292.599587)
			(xy 402.071832 -292.648164) (xy 402.056248 -292.694845) (xy 402.033377 -292.738422) (xy 402.003812 -292.777766)
			(xy 401.968319 -292.811858) (xy 401.927816 -292.839814) (xy 401.883354 -292.860912) (xy 401.836083 -292.874604)
			(xy 401.787228 -292.880536) (xy 401.738053 -292.878555) (xy 401.689834 -292.868711) (xy 401.643818 -292.851259)
			(xy 401.601197 -292.826652) (xy 401.563076 -292.795527) (xy 401.530441 -292.75869) (xy 401.504138 -292.717094)
			(xy 401.484847 -292.671818) (xy 401.47307 -292.624034) (xy 401.46911 -292.57498) (xy 401.130262 -292.57498)
			(xy 401.129767 -292.599587) (xy 401.121872 -292.648164) (xy 401.106288 -292.694845) (xy 401.083417 -292.738422)
			(xy 401.053852 -292.777766) (xy 401.018359 -292.811858) (xy 400.977856 -292.839814) (xy 400.933394 -292.860912)
			(xy 400.886123 -292.874604) (xy 400.837268 -292.880536) (xy 400.788093 -292.878555) (xy 400.739874 -292.868711)
			(xy 400.693858 -292.851259) (xy 400.651237 -292.826652) (xy 400.613116 -292.795527) (xy 400.580481 -292.75869)
			(xy 400.554178 -292.717094) (xy 400.534887 -292.671818) (xy 400.52311 -292.624034) (xy 400.51915 -292.57498)
			(xy 400.180302 -292.57498) (xy 400.179807 -292.599587) (xy 400.171912 -292.648164) (xy 400.156328 -292.694845)
			(xy 400.133457 -292.738422) (xy 400.103892 -292.777766) (xy 400.068399 -292.811858) (xy 400.027896 -292.839814)
			(xy 399.983434 -292.860912) (xy 399.936163 -292.874604) (xy 399.887308 -292.880536) (xy 399.838133 -292.878555)
			(xy 399.789914 -292.868711) (xy 399.743898 -292.851259) (xy 399.701277 -292.826652) (xy 399.663156 -292.795527)
			(xy 399.630521 -292.75869) (xy 399.604218 -292.717094) (xy 399.584927 -292.671818) (xy 399.57315 -292.624034)
			(xy 399.56919 -292.57498) (xy 399.230342 -292.57498) (xy 399.229847 -292.599587) (xy 399.221952 -292.648164)
			(xy 399.206368 -292.694845) (xy 399.183497 -292.738422) (xy 399.153932 -292.777766) (xy 399.118439 -292.811858)
			(xy 399.077936 -292.839814) (xy 399.033474 -292.860912) (xy 398.986203 -292.874604) (xy 398.937348 -292.880536)
			(xy 398.888173 -292.878555) (xy 398.839954 -292.868711) (xy 398.793938 -292.851259) (xy 398.751317 -292.826652)
			(xy 398.713196 -292.795527) (xy 398.680561 -292.75869) (xy 398.654258 -292.717094) (xy 398.634967 -292.671818)
			(xy 398.62319 -292.624034) (xy 398.61923 -292.57498) (xy 398.280123 -292.57498) (xy 398.279633 -292.599333)
			(xy 398.271738 -292.64791) (xy 398.256154 -292.694591) (xy 398.233283 -292.738168) (xy 398.203718 -292.777512)
			(xy 398.168225 -292.811604) (xy 398.127722 -292.83956) (xy 398.08326 -292.860658) (xy 398.035989 -292.87435)
			(xy 397.987134 -292.880282) (xy 397.937959 -292.878301) (xy 397.88974 -292.868457) (xy 397.843724 -292.851005)
			(xy 397.801103 -292.826398) (xy 397.762982 -292.795273) (xy 397.730347 -292.758436) (xy 397.704044 -292.71684)
			(xy 397.684753 -292.671564) (xy 397.672976 -292.62378) (xy 397.669016 -292.574726) (xy 397.355121 -292.574726)
			(xy 397.355121 -292.601063) (xy 397.346757 -292.653115) (xy 397.330242 -292.703181) (xy 397.305993 -292.749992)
			(xy 397.274626 -292.792365) (xy 397.236933 -292.829224) (xy 397.193871 -292.859638) (xy 397.14653 -292.882835)
			(xy 397.096108 -292.898228) (xy 397.070072 -292.902386) (xy 397.066008 -292.902894) (xy 397.054578 -292.90645)
			(xy 397.05026 -292.90772) (xy 397.02613 -292.918896) (xy 397.019526 -292.926008) (xy 397.004794 -292.941502)
			(xy 396.996666 -292.952678) (xy 396.993971 -292.95821) (xy 396.991018 -292.97015) (xy 396.990824 -292.9763)
			(xy 396.990824 -293.123366) (xy 396.990993 -293.129519) (xy 396.993946 -293.141466) (xy 396.996666 -293.146988)
			(xy 397.004794 -293.158164) (xy 397.019526 -293.173658) (xy 397.02613 -293.18077) (xy 397.05026 -293.191946)
			(xy 397.054578 -293.193216) (xy 397.066008 -293.196772) (xy 397.070072 -293.19728) (xy 397.096114 -293.201388)
			(xy 397.146533 -293.216782) (xy 397.193872 -293.239979) (xy 397.236932 -293.270392) (xy 397.274621 -293.307251)
			(xy 397.305986 -293.349623) (xy 397.330232 -293.396433) (xy 397.346745 -293.446497) (xy 397.355108 -293.498547)
			(xy 397.355107 -293.52494) (xy 397.669016 -293.52494) (xy 397.672976 -293.475886) (xy 397.684753 -293.428102)
			(xy 397.704044 -293.382826) (xy 397.730347 -293.34123) (xy 397.762982 -293.304393) (xy 397.801103 -293.273268)
			(xy 397.843724 -293.248661) (xy 397.88974 -293.231209) (xy 397.937959 -293.221365) (xy 397.987134 -293.219384)
			(xy 398.035989 -293.225316) (xy 398.08326 -293.239008) (xy 398.127722 -293.260106) (xy 398.168225 -293.288062)
			(xy 398.203718 -293.322154) (xy 398.233283 -293.361498) (xy 398.256154 -293.405075) (xy 398.271738 -293.451756)
			(xy 398.279633 -293.500333) (xy 398.280128 -293.52494) (xy 398.61923 -293.52494) (xy 398.62319 -293.475886)
			(xy 398.634967 -293.428102) (xy 398.654258 -293.382826) (xy 398.680561 -293.34123) (xy 398.713196 -293.304393)
			(xy 398.751317 -293.273268) (xy 398.793938 -293.248661) (xy 398.839954 -293.231209) (xy 398.888173 -293.221365)
			(xy 398.937348 -293.219384) (xy 398.986203 -293.225316) (xy 399.033474 -293.239008) (xy 399.077936 -293.260106)
			(xy 399.118439 -293.288062) (xy 399.153932 -293.322154) (xy 399.183497 -293.361498) (xy 399.206368 -293.405075)
			(xy 399.221952 -293.451756) (xy 399.229847 -293.500333) (xy 399.230342 -293.52494) (xy 399.56919 -293.52494)
			(xy 399.57315 -293.475886) (xy 399.584927 -293.428102) (xy 399.604218 -293.382826) (xy 399.630521 -293.34123)
			(xy 399.663156 -293.304393) (xy 399.701277 -293.273268) (xy 399.743898 -293.248661) (xy 399.789914 -293.231209)
			(xy 399.838133 -293.221365) (xy 399.887308 -293.219384) (xy 399.936163 -293.225316) (xy 399.983434 -293.239008)
			(xy 400.027896 -293.260106) (xy 400.068399 -293.288062) (xy 400.103892 -293.322154) (xy 400.133457 -293.361498)
			(xy 400.156328 -293.405075) (xy 400.171912 -293.451756) (xy 400.179807 -293.500333) (xy 400.180302 -293.52494)
			(xy 400.51915 -293.52494) (xy 400.52311 -293.475886) (xy 400.534887 -293.428102) (xy 400.554178 -293.382826)
			(xy 400.580481 -293.34123) (xy 400.613116 -293.304393) (xy 400.651237 -293.273268) (xy 400.693858 -293.248661)
			(xy 400.739874 -293.231209) (xy 400.788093 -293.221365) (xy 400.837268 -293.219384) (xy 400.886123 -293.225316)
			(xy 400.933394 -293.239008) (xy 400.977856 -293.260106) (xy 401.018359 -293.288062) (xy 401.053852 -293.322154)
			(xy 401.083417 -293.361498) (xy 401.106288 -293.405075) (xy 401.121872 -293.451756) (xy 401.129767 -293.500333)
			(xy 401.130262 -293.52494) (xy 401.46911 -293.52494) (xy 401.47307 -293.475886) (xy 401.484847 -293.428102)
			(xy 401.504138 -293.382826) (xy 401.530441 -293.34123) (xy 401.563076 -293.304393) (xy 401.601197 -293.273268)
			(xy 401.643818 -293.248661) (xy 401.689834 -293.231209) (xy 401.738053 -293.221365) (xy 401.787228 -293.219384)
			(xy 401.836083 -293.225316) (xy 401.883354 -293.239008) (xy 401.927816 -293.260106) (xy 401.968319 -293.288062)
			(xy 402.003812 -293.322154) (xy 402.033377 -293.361498) (xy 402.056248 -293.405075) (xy 402.071832 -293.451756)
			(xy 402.079727 -293.500333) (xy 402.080222 -293.52494) (xy 402.41907 -293.52494) (xy 402.42303 -293.475886)
			(xy 402.434807 -293.428102) (xy 402.454098 -293.382826) (xy 402.480401 -293.34123) (xy 402.513036 -293.304393)
			(xy 402.551157 -293.273268) (xy 402.593778 -293.248661) (xy 402.639794 -293.231209) (xy 402.688013 -293.221365)
			(xy 402.737188 -293.219384) (xy 402.786043 -293.225316) (xy 402.833314 -293.239008) (xy 402.877776 -293.260106)
			(xy 402.918279 -293.288062) (xy 402.953772 -293.322154) (xy 402.983337 -293.361498) (xy 403.006208 -293.405075)
			(xy 403.021792 -293.451756) (xy 403.029687 -293.500333) (xy 403.030182 -293.52494) (xy 403.36903 -293.52494)
			(xy 403.37299 -293.475886) (xy 403.384767 -293.428102) (xy 403.404058 -293.382826) (xy 403.430361 -293.34123)
			(xy 403.462996 -293.304393) (xy 403.501117 -293.273268) (xy 403.543738 -293.248661) (xy 403.589754 -293.231209)
			(xy 403.637973 -293.221365) (xy 403.687148 -293.219384) (xy 403.736003 -293.225316) (xy 403.783274 -293.239008)
			(xy 403.827736 -293.260106) (xy 403.868239 -293.288062) (xy 403.903732 -293.322154) (xy 403.933297 -293.361498)
			(xy 403.956168 -293.405075) (xy 403.971752 -293.451756) (xy 403.979647 -293.500333) (xy 403.980142 -293.52494)
			(xy 404.31899 -293.52494) (xy 404.32295 -293.475886) (xy 404.334727 -293.428102) (xy 404.354018 -293.382826)
			(xy 404.380321 -293.34123) (xy 404.412956 -293.304393) (xy 404.451077 -293.273268) (xy 404.493698 -293.248661)
			(xy 404.539714 -293.231209) (xy 404.587933 -293.221365) (xy 404.637108 -293.219384) (xy 404.685963 -293.225316)
			(xy 404.733234 -293.239008) (xy 404.777696 -293.260106) (xy 404.818199 -293.288062) (xy 404.853692 -293.322154)
			(xy 404.883257 -293.361498) (xy 404.906128 -293.405075) (xy 404.921712 -293.451756) (xy 404.929607 -293.500333)
			(xy 404.930102 -293.52494) (xy 405.269204 -293.52494) (xy 405.273164 -293.475886) (xy 405.284941 -293.428102)
			(xy 405.304232 -293.382826) (xy 405.330535 -293.34123) (xy 405.36317 -293.304393) (xy 405.401291 -293.273268)
			(xy 405.443912 -293.248661) (xy 405.489928 -293.231209) (xy 405.538147 -293.221365) (xy 405.587322 -293.219384)
			(xy 405.636177 -293.225316) (xy 405.683448 -293.239008) (xy 405.72791 -293.260106) (xy 405.768413 -293.288062)
			(xy 405.803906 -293.322154) (xy 405.833471 -293.361498) (xy 405.856342 -293.405075) (xy 405.871926 -293.451756)
			(xy 405.879821 -293.500333) (xy 405.880316 -293.52494) (xy 406.219164 -293.52494) (xy 406.223124 -293.475886)
			(xy 406.234901 -293.428102) (xy 406.254192 -293.382826) (xy 406.280495 -293.34123) (xy 406.31313 -293.304393)
			(xy 406.351251 -293.273268) (xy 406.393872 -293.248661) (xy 406.439888 -293.231209) (xy 406.488107 -293.221365)
			(xy 406.537282 -293.219384) (xy 406.586137 -293.225316) (xy 406.633408 -293.239008) (xy 406.67787 -293.260106)
			(xy 406.718373 -293.288062) (xy 406.753866 -293.322154) (xy 406.783431 -293.361498) (xy 406.806302 -293.405075)
			(xy 406.821886 -293.451756) (xy 406.829781 -293.500333) (xy 406.830276 -293.52494) (xy 408.119084 -293.52494)
			(xy 408.123044 -293.475886) (xy 408.134821 -293.428102) (xy 408.154112 -293.382826) (xy 408.180415 -293.34123)
			(xy 408.21305 -293.304393) (xy 408.251171 -293.273268) (xy 408.293792 -293.248661) (xy 408.339808 -293.231209)
			(xy 408.388027 -293.221365) (xy 408.437202 -293.219384) (xy 408.486057 -293.225316) (xy 408.533328 -293.239008)
			(xy 408.57779 -293.260106) (xy 408.618293 -293.288062) (xy 408.653786 -293.322154) (xy 408.683351 -293.361498)
			(xy 408.706222 -293.405075) (xy 408.721806 -293.451756) (xy 408.729701 -293.500333) (xy 408.730196 -293.52494)
			(xy 409.069044 -293.52494) (xy 409.073004 -293.475886) (xy 409.084781 -293.428102) (xy 409.104072 -293.382826)
			(xy 409.130375 -293.34123) (xy 409.16301 -293.304393) (xy 409.201131 -293.273268) (xy 409.243752 -293.248661)
			(xy 409.289768 -293.231209) (xy 409.337987 -293.221365) (xy 409.387162 -293.219384) (xy 409.436017 -293.225316)
			(xy 409.483288 -293.239008) (xy 409.52775 -293.260106) (xy 409.568253 -293.288062) (xy 409.603746 -293.322154)
			(xy 409.633311 -293.361498) (xy 409.656182 -293.405075) (xy 409.671766 -293.451756) (xy 409.679661 -293.500333)
			(xy 409.680156 -293.52494) (xy 410.019004 -293.52494) (xy 410.022964 -293.475886) (xy 410.034741 -293.428102)
			(xy 410.054032 -293.382826) (xy 410.080335 -293.34123) (xy 410.11297 -293.304393) (xy 410.151091 -293.273268)
			(xy 410.193712 -293.248661) (xy 410.239728 -293.231209) (xy 410.287947 -293.221365) (xy 410.337122 -293.219384)
			(xy 410.385977 -293.225316) (xy 410.433248 -293.239008) (xy 410.47771 -293.260106) (xy 410.518213 -293.288062)
			(xy 410.553706 -293.322154) (xy 410.583271 -293.361498) (xy 410.606142 -293.405075) (xy 410.621726 -293.451756)
			(xy 410.629621 -293.500333) (xy 410.630116 -293.52494) (xy 410.969218 -293.52494) (xy 410.973178 -293.475886)
			(xy 410.984955 -293.428102) (xy 411.004246 -293.382826) (xy 411.030549 -293.34123) (xy 411.063184 -293.304393)
			(xy 411.101305 -293.273268) (xy 411.143926 -293.248661) (xy 411.189942 -293.231209) (xy 411.238161 -293.221365)
			(xy 411.287336 -293.219384) (xy 411.336191 -293.225316) (xy 411.383462 -293.239008) (xy 411.427924 -293.260106)
			(xy 411.468427 -293.288062) (xy 411.50392 -293.322154) (xy 411.533485 -293.361498) (xy 411.556356 -293.405075)
			(xy 411.57194 -293.451756) (xy 411.579835 -293.500333) (xy 411.58033 -293.52494) (xy 411.919178 -293.52494)
			(xy 411.923138 -293.475886) (xy 411.934915 -293.428102) (xy 411.954206 -293.382826) (xy 411.980509 -293.34123)
			(xy 412.013144 -293.304393) (xy 412.051265 -293.273268) (xy 412.093886 -293.248661) (xy 412.139902 -293.231209)
			(xy 412.188121 -293.221365) (xy 412.237296 -293.219384) (xy 412.286151 -293.225316) (xy 412.333422 -293.239008)
			(xy 412.377884 -293.260106) (xy 412.418387 -293.288062) (xy 412.45388 -293.322154) (xy 412.483445 -293.361498)
			(xy 412.506316 -293.405075) (xy 412.5219 -293.451756) (xy 412.529795 -293.500333) (xy 412.53029 -293.52494)
			(xy 412.869138 -293.52494) (xy 412.873098 -293.475886) (xy 412.884875 -293.428102) (xy 412.904166 -293.382826)
			(xy 412.930469 -293.34123) (xy 412.963104 -293.304393) (xy 413.001225 -293.273268) (xy 413.043846 -293.248661)
			(xy 413.089862 -293.231209) (xy 413.138081 -293.221365) (xy 413.187256 -293.219384) (xy 413.236111 -293.225316)
			(xy 413.283382 -293.239008) (xy 413.327844 -293.260106) (xy 413.368347 -293.288062) (xy 413.40384 -293.322154)
			(xy 413.433405 -293.361498) (xy 413.456276 -293.405075) (xy 413.47186 -293.451756) (xy 413.479755 -293.500333)
			(xy 413.48025 -293.52494) (xy 413.819098 -293.52494) (xy 413.823058 -293.475886) (xy 413.834835 -293.428102)
			(xy 413.854126 -293.382826) (xy 413.880429 -293.34123) (xy 413.913064 -293.304393) (xy 413.951185 -293.273268)
			(xy 413.993806 -293.248661) (xy 414.039822 -293.231209) (xy 414.088041 -293.221365) (xy 414.137216 -293.219384)
			(xy 414.186071 -293.225316) (xy 414.233342 -293.239008) (xy 414.277804 -293.260106) (xy 414.318307 -293.288062)
			(xy 414.3538 -293.322154) (xy 414.383365 -293.361498) (xy 414.406236 -293.405075) (xy 414.42182 -293.451756)
			(xy 414.429715 -293.500333) (xy 414.43021 -293.52494) (xy 414.769058 -293.52494) (xy 414.773018 -293.475886)
			(xy 414.784795 -293.428102) (xy 414.804086 -293.382826) (xy 414.830389 -293.34123) (xy 414.863024 -293.304393)
			(xy 414.901145 -293.273268) (xy 414.943766 -293.248661) (xy 414.989782 -293.231209) (xy 415.038001 -293.221365)
			(xy 415.087176 -293.219384) (xy 415.136031 -293.225316) (xy 415.183302 -293.239008) (xy 415.227764 -293.260106)
			(xy 415.268267 -293.288062) (xy 415.30376 -293.322154) (xy 415.333325 -293.361498) (xy 415.356196 -293.405075)
			(xy 415.37178 -293.451756) (xy 415.379675 -293.500333) (xy 415.38017 -293.52494) (xy 415.719018 -293.52494)
			(xy 415.722978 -293.475886) (xy 415.734755 -293.428102) (xy 415.754046 -293.382826) (xy 415.780349 -293.34123)
			(xy 415.812984 -293.304393) (xy 415.851105 -293.273268) (xy 415.893726 -293.248661) (xy 415.939742 -293.231209)
			(xy 415.987961 -293.221365) (xy 416.037136 -293.219384) (xy 416.085991 -293.225316) (xy 416.133262 -293.239008)
			(xy 416.177724 -293.260106) (xy 416.218227 -293.288062) (xy 416.25372 -293.322154) (xy 416.283285 -293.361498)
			(xy 416.306156 -293.405075) (xy 416.32174 -293.451756) (xy 416.329635 -293.500333) (xy 416.33013 -293.52494)
			(xy 416.668978 -293.52494) (xy 416.672938 -293.475886) (xy 416.684715 -293.428102) (xy 416.704006 -293.382826)
			(xy 416.730309 -293.34123) (xy 416.762944 -293.304393) (xy 416.801065 -293.273268) (xy 416.843686 -293.248661)
			(xy 416.889702 -293.231209) (xy 416.937921 -293.221365) (xy 416.987096 -293.219384) (xy 417.035951 -293.225316)
			(xy 417.083222 -293.239008) (xy 417.127684 -293.260106) (xy 417.168187 -293.288062) (xy 417.20368 -293.322154)
			(xy 417.233245 -293.361498) (xy 417.256116 -293.405075) (xy 417.2717 -293.451756) (xy 417.279595 -293.500333)
			(xy 417.28009 -293.52494) (xy 417.619192 -293.52494) (xy 417.623152 -293.475886) (xy 417.634929 -293.428102)
			(xy 417.65422 -293.382826) (xy 417.680523 -293.34123) (xy 417.713158 -293.304393) (xy 417.751279 -293.273268)
			(xy 417.7939 -293.248661) (xy 417.839916 -293.231209) (xy 417.888135 -293.221365) (xy 417.93731 -293.219384)
			(xy 417.986165 -293.225316) (xy 418.033436 -293.239008) (xy 418.077898 -293.260106) (xy 418.118401 -293.288062)
			(xy 418.153894 -293.322154) (xy 418.183459 -293.361498) (xy 418.20633 -293.405075) (xy 418.221914 -293.451756)
			(xy 418.229809 -293.500333) (xy 418.230304 -293.52494) (xy 419.519112 -293.52494) (xy 419.523072 -293.475886)
			(xy 419.534849 -293.428102) (xy 419.55414 -293.382826) (xy 419.580443 -293.34123) (xy 419.613078 -293.304393)
			(xy 419.651199 -293.273268) (xy 419.69382 -293.248661) (xy 419.739836 -293.231209) (xy 419.788055 -293.221365)
			(xy 419.83723 -293.219384) (xy 419.886085 -293.225316) (xy 419.933356 -293.239008) (xy 419.977818 -293.260106)
			(xy 420.018321 -293.288062) (xy 420.053814 -293.322154) (xy 420.083379 -293.361498) (xy 420.10625 -293.405075)
			(xy 420.121834 -293.451756) (xy 420.129729 -293.500333) (xy 420.130224 -293.52494) (xy 420.469072 -293.52494)
			(xy 420.473032 -293.475886) (xy 420.484809 -293.428102) (xy 420.5041 -293.382826) (xy 420.530403 -293.34123)
			(xy 420.563038 -293.304393) (xy 420.601159 -293.273268) (xy 420.64378 -293.248661) (xy 420.689796 -293.231209)
			(xy 420.738015 -293.221365) (xy 420.78719 -293.219384) (xy 420.836045 -293.225316) (xy 420.883316 -293.239008)
			(xy 420.927778 -293.260106) (xy 420.968281 -293.288062) (xy 421.003774 -293.322154) (xy 421.033339 -293.361498)
			(xy 421.05621 -293.405075) (xy 421.071794 -293.451756) (xy 421.079689 -293.500333) (xy 421.080184 -293.52494)
			(xy 421.419032 -293.52494) (xy 421.422992 -293.475886) (xy 421.434769 -293.428102) (xy 421.45406 -293.382826)
			(xy 421.480363 -293.34123) (xy 421.512998 -293.304393) (xy 421.551119 -293.273268) (xy 421.59374 -293.248661)
			(xy 421.639756 -293.231209) (xy 421.687975 -293.221365) (xy 421.73715 -293.219384) (xy 421.786005 -293.225316)
			(xy 421.833276 -293.239008) (xy 421.877738 -293.260106) (xy 421.918241 -293.288062) (xy 421.953734 -293.322154)
			(xy 421.983299 -293.361498) (xy 422.00617 -293.405075) (xy 422.021754 -293.451756) (xy 422.029649 -293.500333)
			(xy 422.030144 -293.52494) (xy 422.369246 -293.52494) (xy 422.373206 -293.475886) (xy 422.384983 -293.428102)
			(xy 422.404274 -293.382826) (xy 422.430577 -293.34123) (xy 422.463212 -293.304393) (xy 422.501333 -293.273268)
			(xy 422.543954 -293.248661) (xy 422.58997 -293.231209) (xy 422.638189 -293.221365) (xy 422.687364 -293.219384)
			(xy 422.736219 -293.225316) (xy 422.78349 -293.239008) (xy 422.827952 -293.260106) (xy 422.868455 -293.288062)
			(xy 422.903948 -293.322154) (xy 422.933513 -293.361498) (xy 422.956384 -293.405075) (xy 422.971968 -293.451756)
			(xy 422.979863 -293.500333) (xy 422.980358 -293.52494) (xy 423.319206 -293.52494) (xy 423.323166 -293.475886)
			(xy 423.334943 -293.428102) (xy 423.354234 -293.382826) (xy 423.380537 -293.34123) (xy 423.413172 -293.304393)
			(xy 423.451293 -293.273268) (xy 423.493914 -293.248661) (xy 423.53993 -293.231209) (xy 423.588149 -293.221365)
			(xy 423.637324 -293.219384) (xy 423.686179 -293.225316) (xy 423.73345 -293.239008) (xy 423.777912 -293.260106)
			(xy 423.818415 -293.288062) (xy 423.853908 -293.322154) (xy 423.883473 -293.361498) (xy 423.906344 -293.405075)
			(xy 423.921928 -293.451756) (xy 423.929823 -293.500333) (xy 423.930318 -293.52494) (xy 424.269166 -293.52494)
			(xy 424.273126 -293.475886) (xy 424.284903 -293.428102) (xy 424.304194 -293.382826) (xy 424.330497 -293.34123)
			(xy 424.363132 -293.304393) (xy 424.401253 -293.273268) (xy 424.443874 -293.248661) (xy 424.48989 -293.231209)
			(xy 424.538109 -293.221365) (xy 424.587284 -293.219384) (xy 424.636139 -293.225316) (xy 424.68341 -293.239008)
			(xy 424.727872 -293.260106) (xy 424.768375 -293.288062) (xy 424.803868 -293.322154) (xy 424.833433 -293.361498)
			(xy 424.856304 -293.405075) (xy 424.871888 -293.451756) (xy 424.879783 -293.500333) (xy 424.880278 -293.52494)
			(xy 425.219126 -293.52494) (xy 425.223086 -293.475886) (xy 425.234863 -293.428102) (xy 425.254154 -293.382826)
			(xy 425.280457 -293.34123) (xy 425.313092 -293.304393) (xy 425.351213 -293.273268) (xy 425.393834 -293.248661)
			(xy 425.43985 -293.231209) (xy 425.488069 -293.221365) (xy 425.537244 -293.219384) (xy 425.586099 -293.225316)
			(xy 425.63337 -293.239008) (xy 425.677832 -293.260106) (xy 425.718335 -293.288062) (xy 425.753828 -293.322154)
			(xy 425.783393 -293.361498) (xy 425.806264 -293.405075) (xy 425.821848 -293.451756) (xy 425.829743 -293.500333)
			(xy 425.830238 -293.52494) (xy 426.169086 -293.52494) (xy 426.173046 -293.475886) (xy 426.184823 -293.428102)
			(xy 426.204114 -293.382826) (xy 426.230417 -293.34123) (xy 426.263052 -293.304393) (xy 426.301173 -293.273268)
			(xy 426.343794 -293.248661) (xy 426.38981 -293.231209) (xy 426.438029 -293.221365) (xy 426.487204 -293.219384)
			(xy 426.536059 -293.225316) (xy 426.58333 -293.239008) (xy 426.627792 -293.260106) (xy 426.668295 -293.288062)
			(xy 426.703788 -293.322154) (xy 426.733353 -293.361498) (xy 426.756224 -293.405075) (xy 426.771808 -293.451756)
			(xy 426.779703 -293.500333) (xy 426.780198 -293.52494) (xy 427.119046 -293.52494) (xy 427.123006 -293.475886)
			(xy 427.134783 -293.428102) (xy 427.154074 -293.382826) (xy 427.180377 -293.34123) (xy 427.213012 -293.304393)
			(xy 427.251133 -293.273268) (xy 427.293754 -293.248661) (xy 427.33977 -293.231209) (xy 427.387989 -293.221365)
			(xy 427.437164 -293.219384) (xy 427.486019 -293.225316) (xy 427.53329 -293.239008) (xy 427.577752 -293.260106)
			(xy 427.618255 -293.288062) (xy 427.653748 -293.322154) (xy 427.683313 -293.361498) (xy 427.706184 -293.405075)
			(xy 427.721768 -293.451756) (xy 427.729663 -293.500333) (xy 427.730158 -293.52494) (xy 428.069006 -293.52494)
			(xy 428.072966 -293.475886) (xy 428.084743 -293.428102) (xy 428.104034 -293.382826) (xy 428.130337 -293.34123)
			(xy 428.162972 -293.304393) (xy 428.201093 -293.273268) (xy 428.243714 -293.248661) (xy 428.28973 -293.231209)
			(xy 428.337949 -293.221365) (xy 428.387124 -293.219384) (xy 428.435979 -293.225316) (xy 428.48325 -293.239008)
			(xy 428.527712 -293.260106) (xy 428.568215 -293.288062) (xy 428.603708 -293.322154) (xy 428.633273 -293.361498)
			(xy 428.656144 -293.405075) (xy 428.671728 -293.451756) (xy 428.679623 -293.500333) (xy 428.680118 -293.52494)
			(xy 429.01922 -293.52494) (xy 429.02318 -293.475886) (xy 429.034957 -293.428102) (xy 429.054248 -293.382826)
			(xy 429.080551 -293.34123) (xy 429.113186 -293.304393) (xy 429.151307 -293.273268) (xy 429.193928 -293.248661)
			(xy 429.239944 -293.231209) (xy 429.288163 -293.221365) (xy 429.337338 -293.219384) (xy 429.386193 -293.225316)
			(xy 429.433464 -293.239008) (xy 429.477926 -293.260106) (xy 429.518429 -293.288062) (xy 429.553922 -293.322154)
			(xy 429.583487 -293.361498) (xy 429.606358 -293.405075) (xy 429.621942 -293.451756) (xy 429.629837 -293.500333)
			(xy 429.630332 -293.52494) (xy 429.96918 -293.52494) (xy 429.97314 -293.475886) (xy 429.984917 -293.428102)
			(xy 430.004208 -293.382826) (xy 430.030511 -293.34123) (xy 430.063146 -293.304393) (xy 430.101267 -293.273268)
			(xy 430.143888 -293.248661) (xy 430.189904 -293.231209) (xy 430.238123 -293.221365) (xy 430.287298 -293.219384)
			(xy 430.336153 -293.225316) (xy 430.383424 -293.239008) (xy 430.427886 -293.260106) (xy 430.468389 -293.288062)
			(xy 430.503882 -293.322154) (xy 430.533447 -293.361498) (xy 430.556318 -293.405075) (xy 430.571902 -293.451756)
			(xy 430.579797 -293.500333) (xy 430.580292 -293.52494) (xy 430.91914 -293.52494) (xy 430.9231 -293.475886)
			(xy 430.934877 -293.428102) (xy 430.954168 -293.382826) (xy 430.980471 -293.34123) (xy 431.013106 -293.304393)
			(xy 431.051227 -293.273268) (xy 431.093848 -293.248661) (xy 431.139864 -293.231209) (xy 431.188083 -293.221365)
			(xy 431.237258 -293.219384) (xy 431.286113 -293.225316) (xy 431.333384 -293.239008) (xy 431.377846 -293.260106)
			(xy 431.418349 -293.288062) (xy 431.453842 -293.322154) (xy 431.483407 -293.361498) (xy 431.506278 -293.405075)
			(xy 431.521862 -293.451756) (xy 431.529757 -293.500333) (xy 431.530252 -293.52494) (xy 431.529757 -293.549547)
			(xy 431.521862 -293.598124) (xy 431.506278 -293.644805) (xy 431.483407 -293.688382) (xy 431.453842 -293.727726)
			(xy 431.418349 -293.761818) (xy 431.377846 -293.789774) (xy 431.333384 -293.810872) (xy 431.286113 -293.824564)
			(xy 431.237258 -293.830496) (xy 431.188083 -293.828515) (xy 431.139864 -293.818671) (xy 431.093848 -293.801219)
			(xy 431.051227 -293.776612) (xy 431.013106 -293.745487) (xy 430.980471 -293.70865) (xy 430.954168 -293.667054)
			(xy 430.934877 -293.621778) (xy 430.9231 -293.573994) (xy 430.91914 -293.52494) (xy 430.580292 -293.52494)
			(xy 430.579797 -293.549547) (xy 430.571902 -293.598124) (xy 430.556318 -293.644805) (xy 430.533447 -293.688382)
			(xy 430.503882 -293.727726) (xy 430.468389 -293.761818) (xy 430.427886 -293.789774) (xy 430.383424 -293.810872)
			(xy 430.336153 -293.824564) (xy 430.287298 -293.830496) (xy 430.238123 -293.828515) (xy 430.189904 -293.818671)
			(xy 430.143888 -293.801219) (xy 430.101267 -293.776612) (xy 430.063146 -293.745487) (xy 430.030511 -293.70865)
			(xy 430.004208 -293.667054) (xy 429.984917 -293.621778) (xy 429.97314 -293.573994) (xy 429.96918 -293.52494)
			(xy 429.630332 -293.52494) (xy 429.629837 -293.549547) (xy 429.621942 -293.598124) (xy 429.606358 -293.644805)
			(xy 429.583487 -293.688382) (xy 429.553922 -293.727726) (xy 429.518429 -293.761818) (xy 429.477926 -293.789774)
			(xy 429.433464 -293.810872) (xy 429.386193 -293.824564) (xy 429.337338 -293.830496) (xy 429.288163 -293.828515)
			(xy 429.239944 -293.818671) (xy 429.193928 -293.801219) (xy 429.151307 -293.776612) (xy 429.113186 -293.745487)
			(xy 429.080551 -293.70865) (xy 429.054248 -293.667054) (xy 429.034957 -293.621778) (xy 429.02318 -293.573994)
			(xy 429.01922 -293.52494) (xy 428.680118 -293.52494) (xy 428.679623 -293.549547) (xy 428.671728 -293.598124)
			(xy 428.656144 -293.644805) (xy 428.633273 -293.688382) (xy 428.603708 -293.727726) (xy 428.568215 -293.761818)
			(xy 428.527712 -293.789774) (xy 428.48325 -293.810872) (xy 428.435979 -293.824564) (xy 428.387124 -293.830496)
			(xy 428.337949 -293.828515) (xy 428.28973 -293.818671) (xy 428.243714 -293.801219) (xy 428.201093 -293.776612)
			(xy 428.162972 -293.745487) (xy 428.130337 -293.70865) (xy 428.104034 -293.667054) (xy 428.084743 -293.621778)
			(xy 428.072966 -293.573994) (xy 428.069006 -293.52494) (xy 427.730158 -293.52494) (xy 427.729663 -293.549547)
			(xy 427.721768 -293.598124) (xy 427.706184 -293.644805) (xy 427.683313 -293.688382) (xy 427.653748 -293.727726)
			(xy 427.618255 -293.761818) (xy 427.577752 -293.789774) (xy 427.53329 -293.810872) (xy 427.486019 -293.824564)
			(xy 427.437164 -293.830496) (xy 427.387989 -293.828515) (xy 427.33977 -293.818671) (xy 427.293754 -293.801219)
			(xy 427.251133 -293.776612) (xy 427.213012 -293.745487) (xy 427.180377 -293.70865) (xy 427.154074 -293.667054)
			(xy 427.134783 -293.621778) (xy 427.123006 -293.573994) (xy 427.119046 -293.52494) (xy 426.780198 -293.52494)
			(xy 426.779703 -293.549547) (xy 426.771808 -293.598124) (xy 426.756224 -293.644805) (xy 426.733353 -293.688382)
			(xy 426.703788 -293.727726) (xy 426.668295 -293.761818) (xy 426.627792 -293.789774) (xy 426.58333 -293.810872)
			(xy 426.536059 -293.824564) (xy 426.487204 -293.830496) (xy 426.438029 -293.828515) (xy 426.38981 -293.818671)
			(xy 426.343794 -293.801219) (xy 426.301173 -293.776612) (xy 426.263052 -293.745487) (xy 426.230417 -293.70865)
			(xy 426.204114 -293.667054) (xy 426.184823 -293.621778) (xy 426.173046 -293.573994) (xy 426.169086 -293.52494)
			(xy 425.830238 -293.52494) (xy 425.829743 -293.549547) (xy 425.821848 -293.598124) (xy 425.806264 -293.644805)
			(xy 425.783393 -293.688382) (xy 425.753828 -293.727726) (xy 425.718335 -293.761818) (xy 425.677832 -293.789774)
			(xy 425.63337 -293.810872) (xy 425.586099 -293.824564) (xy 425.537244 -293.830496) (xy 425.488069 -293.828515)
			(xy 425.43985 -293.818671) (xy 425.393834 -293.801219) (xy 425.351213 -293.776612) (xy 425.313092 -293.745487)
			(xy 425.280457 -293.70865) (xy 425.254154 -293.667054) (xy 425.234863 -293.621778) (xy 425.223086 -293.573994)
			(xy 425.219126 -293.52494) (xy 424.880278 -293.52494) (xy 424.879783 -293.549547) (xy 424.871888 -293.598124)
			(xy 424.856304 -293.644805) (xy 424.833433 -293.688382) (xy 424.803868 -293.727726) (xy 424.768375 -293.761818)
			(xy 424.727872 -293.789774) (xy 424.68341 -293.810872) (xy 424.636139 -293.824564) (xy 424.587284 -293.830496)
			(xy 424.538109 -293.828515) (xy 424.48989 -293.818671) (xy 424.443874 -293.801219) (xy 424.401253 -293.776612)
			(xy 424.363132 -293.745487) (xy 424.330497 -293.70865) (xy 424.304194 -293.667054) (xy 424.284903 -293.621778)
			(xy 424.273126 -293.573994) (xy 424.269166 -293.52494) (xy 423.930318 -293.52494) (xy 423.929823 -293.549547)
			(xy 423.921928 -293.598124) (xy 423.906344 -293.644805) (xy 423.883473 -293.688382) (xy 423.853908 -293.727726)
			(xy 423.818415 -293.761818) (xy 423.777912 -293.789774) (xy 423.73345 -293.810872) (xy 423.686179 -293.824564)
			(xy 423.637324 -293.830496) (xy 423.588149 -293.828515) (xy 423.53993 -293.818671) (xy 423.493914 -293.801219)
			(xy 423.451293 -293.776612) (xy 423.413172 -293.745487) (xy 423.380537 -293.70865) (xy 423.354234 -293.667054)
			(xy 423.334943 -293.621778) (xy 423.323166 -293.573994) (xy 423.319206 -293.52494) (xy 422.980358 -293.52494)
			(xy 422.979863 -293.549547) (xy 422.971968 -293.598124) (xy 422.956384 -293.644805) (xy 422.933513 -293.688382)
			(xy 422.903948 -293.727726) (xy 422.868455 -293.761818) (xy 422.827952 -293.789774) (xy 422.78349 -293.810872)
			(xy 422.736219 -293.824564) (xy 422.687364 -293.830496) (xy 422.638189 -293.828515) (xy 422.58997 -293.818671)
			(xy 422.543954 -293.801219) (xy 422.501333 -293.776612) (xy 422.463212 -293.745487) (xy 422.430577 -293.70865)
			(xy 422.404274 -293.667054) (xy 422.384983 -293.621778) (xy 422.373206 -293.573994) (xy 422.369246 -293.52494)
			(xy 422.030144 -293.52494) (xy 422.029649 -293.549547) (xy 422.021754 -293.598124) (xy 422.00617 -293.644805)
			(xy 421.983299 -293.688382) (xy 421.953734 -293.727726) (xy 421.918241 -293.761818) (xy 421.877738 -293.789774)
			(xy 421.833276 -293.810872) (xy 421.786005 -293.824564) (xy 421.73715 -293.830496) (xy 421.687975 -293.828515)
			(xy 421.639756 -293.818671) (xy 421.59374 -293.801219) (xy 421.551119 -293.776612) (xy 421.512998 -293.745487)
			(xy 421.480363 -293.70865) (xy 421.45406 -293.667054) (xy 421.434769 -293.621778) (xy 421.422992 -293.573994)
			(xy 421.419032 -293.52494) (xy 421.080184 -293.52494) (xy 421.079689 -293.549547) (xy 421.071794 -293.598124)
			(xy 421.05621 -293.644805) (xy 421.033339 -293.688382) (xy 421.003774 -293.727726) (xy 420.968281 -293.761818)
			(xy 420.927778 -293.789774) (xy 420.883316 -293.810872) (xy 420.836045 -293.824564) (xy 420.78719 -293.830496)
			(xy 420.738015 -293.828515) (xy 420.689796 -293.818671) (xy 420.64378 -293.801219) (xy 420.601159 -293.776612)
			(xy 420.563038 -293.745487) (xy 420.530403 -293.70865) (xy 420.5041 -293.667054) (xy 420.484809 -293.621778)
			(xy 420.473032 -293.573994) (xy 420.469072 -293.52494) (xy 420.130224 -293.52494) (xy 420.129729 -293.549547)
			(xy 420.121834 -293.598124) (xy 420.10625 -293.644805) (xy 420.083379 -293.688382) (xy 420.053814 -293.727726)
			(xy 420.018321 -293.761818) (xy 419.977818 -293.789774) (xy 419.933356 -293.810872) (xy 419.886085 -293.824564)
			(xy 419.83723 -293.830496) (xy 419.788055 -293.828515) (xy 419.739836 -293.818671) (xy 419.69382 -293.801219)
			(xy 419.651199 -293.776612) (xy 419.613078 -293.745487) (xy 419.580443 -293.70865) (xy 419.55414 -293.667054)
			(xy 419.534849 -293.621778) (xy 419.523072 -293.573994) (xy 419.519112 -293.52494) (xy 418.230304 -293.52494)
			(xy 418.229809 -293.549547) (xy 418.221914 -293.598124) (xy 418.20633 -293.644805) (xy 418.183459 -293.688382)
			(xy 418.153894 -293.727726) (xy 418.118401 -293.761818) (xy 418.077898 -293.789774) (xy 418.033436 -293.810872)
			(xy 417.986165 -293.824564) (xy 417.93731 -293.830496) (xy 417.888135 -293.828515) (xy 417.839916 -293.818671)
			(xy 417.7939 -293.801219) (xy 417.751279 -293.776612) (xy 417.713158 -293.745487) (xy 417.680523 -293.70865)
			(xy 417.65422 -293.667054) (xy 417.634929 -293.621778) (xy 417.623152 -293.573994) (xy 417.619192 -293.52494)
			(xy 417.28009 -293.52494) (xy 417.279595 -293.549547) (xy 417.2717 -293.598124) (xy 417.256116 -293.644805)
			(xy 417.233245 -293.688382) (xy 417.20368 -293.727726) (xy 417.168187 -293.761818) (xy 417.127684 -293.789774)
			(xy 417.083222 -293.810872) (xy 417.035951 -293.824564) (xy 416.987096 -293.830496) (xy 416.937921 -293.828515)
			(xy 416.889702 -293.818671) (xy 416.843686 -293.801219) (xy 416.801065 -293.776612) (xy 416.762944 -293.745487)
			(xy 416.730309 -293.70865) (xy 416.704006 -293.667054) (xy 416.684715 -293.621778) (xy 416.672938 -293.573994)
			(xy 416.668978 -293.52494) (xy 416.33013 -293.52494) (xy 416.329635 -293.549547) (xy 416.32174 -293.598124)
			(xy 416.306156 -293.644805) (xy 416.283285 -293.688382) (xy 416.25372 -293.727726) (xy 416.218227 -293.761818)
			(xy 416.177724 -293.789774) (xy 416.133262 -293.810872) (xy 416.085991 -293.824564) (xy 416.037136 -293.830496)
			(xy 415.987961 -293.828515) (xy 415.939742 -293.818671) (xy 415.893726 -293.801219) (xy 415.851105 -293.776612)
			(xy 415.812984 -293.745487) (xy 415.780349 -293.70865) (xy 415.754046 -293.667054) (xy 415.734755 -293.621778)
			(xy 415.722978 -293.573994) (xy 415.719018 -293.52494) (xy 415.38017 -293.52494) (xy 415.379675 -293.549547)
			(xy 415.37178 -293.598124) (xy 415.356196 -293.644805) (xy 415.333325 -293.688382) (xy 415.30376 -293.727726)
			(xy 415.268267 -293.761818) (xy 415.227764 -293.789774) (xy 415.183302 -293.810872) (xy 415.136031 -293.824564)
			(xy 415.087176 -293.830496) (xy 415.038001 -293.828515) (xy 414.989782 -293.818671) (xy 414.943766 -293.801219)
			(xy 414.901145 -293.776612) (xy 414.863024 -293.745487) (xy 414.830389 -293.70865) (xy 414.804086 -293.667054)
			(xy 414.784795 -293.621778) (xy 414.773018 -293.573994) (xy 414.769058 -293.52494) (xy 414.43021 -293.52494)
			(xy 414.429715 -293.549547) (xy 414.42182 -293.598124) (xy 414.406236 -293.644805) (xy 414.383365 -293.688382)
			(xy 414.3538 -293.727726) (xy 414.318307 -293.761818) (xy 414.277804 -293.789774) (xy 414.233342 -293.810872)
			(xy 414.186071 -293.824564) (xy 414.137216 -293.830496) (xy 414.088041 -293.828515) (xy 414.039822 -293.818671)
			(xy 413.993806 -293.801219) (xy 413.951185 -293.776612) (xy 413.913064 -293.745487) (xy 413.880429 -293.70865)
			(xy 413.854126 -293.667054) (xy 413.834835 -293.621778) (xy 413.823058 -293.573994) (xy 413.819098 -293.52494)
			(xy 413.48025 -293.52494) (xy 413.479755 -293.549547) (xy 413.47186 -293.598124) (xy 413.456276 -293.644805)
			(xy 413.433405 -293.688382) (xy 413.40384 -293.727726) (xy 413.368347 -293.761818) (xy 413.327844 -293.789774)
			(xy 413.283382 -293.810872) (xy 413.236111 -293.824564) (xy 413.187256 -293.830496) (xy 413.138081 -293.828515)
			(xy 413.089862 -293.818671) (xy 413.043846 -293.801219) (xy 413.001225 -293.776612) (xy 412.963104 -293.745487)
			(xy 412.930469 -293.70865) (xy 412.904166 -293.667054) (xy 412.884875 -293.621778) (xy 412.873098 -293.573994)
			(xy 412.869138 -293.52494) (xy 412.53029 -293.52494) (xy 412.529795 -293.549547) (xy 412.5219 -293.598124)
			(xy 412.506316 -293.644805) (xy 412.483445 -293.688382) (xy 412.45388 -293.727726) (xy 412.418387 -293.761818)
			(xy 412.377884 -293.789774) (xy 412.333422 -293.810872) (xy 412.286151 -293.824564) (xy 412.237296 -293.830496)
			(xy 412.188121 -293.828515) (xy 412.139902 -293.818671) (xy 412.093886 -293.801219) (xy 412.051265 -293.776612)
			(xy 412.013144 -293.745487) (xy 411.980509 -293.70865) (xy 411.954206 -293.667054) (xy 411.934915 -293.621778)
			(xy 411.923138 -293.573994) (xy 411.919178 -293.52494) (xy 411.58033 -293.52494) (xy 411.579835 -293.549547)
			(xy 411.57194 -293.598124) (xy 411.556356 -293.644805) (xy 411.533485 -293.688382) (xy 411.50392 -293.727726)
			(xy 411.468427 -293.761818) (xy 411.427924 -293.789774) (xy 411.383462 -293.810872) (xy 411.336191 -293.824564)
			(xy 411.287336 -293.830496) (xy 411.238161 -293.828515) (xy 411.189942 -293.818671) (xy 411.143926 -293.801219)
			(xy 411.101305 -293.776612) (xy 411.063184 -293.745487) (xy 411.030549 -293.70865) (xy 411.004246 -293.667054)
			(xy 410.984955 -293.621778) (xy 410.973178 -293.573994) (xy 410.969218 -293.52494) (xy 410.630116 -293.52494)
			(xy 410.629621 -293.549547) (xy 410.621726 -293.598124) (xy 410.606142 -293.644805) (xy 410.583271 -293.688382)
			(xy 410.553706 -293.727726) (xy 410.518213 -293.761818) (xy 410.47771 -293.789774) (xy 410.433248 -293.810872)
			(xy 410.385977 -293.824564) (xy 410.337122 -293.830496) (xy 410.287947 -293.828515) (xy 410.239728 -293.818671)
			(xy 410.193712 -293.801219) (xy 410.151091 -293.776612) (xy 410.11297 -293.745487) (xy 410.080335 -293.70865)
			(xy 410.054032 -293.667054) (xy 410.034741 -293.621778) (xy 410.022964 -293.573994) (xy 410.019004 -293.52494)
			(xy 409.680156 -293.52494) (xy 409.679661 -293.549547) (xy 409.671766 -293.598124) (xy 409.656182 -293.644805)
			(xy 409.633311 -293.688382) (xy 409.603746 -293.727726) (xy 409.568253 -293.761818) (xy 409.52775 -293.789774)
			(xy 409.483288 -293.810872) (xy 409.436017 -293.824564) (xy 409.387162 -293.830496) (xy 409.337987 -293.828515)
			(xy 409.289768 -293.818671) (xy 409.243752 -293.801219) (xy 409.201131 -293.776612) (xy 409.16301 -293.745487)
			(xy 409.130375 -293.70865) (xy 409.104072 -293.667054) (xy 409.084781 -293.621778) (xy 409.073004 -293.573994)
			(xy 409.069044 -293.52494) (xy 408.730196 -293.52494) (xy 408.729701 -293.549547) (xy 408.721806 -293.598124)
			(xy 408.706222 -293.644805) (xy 408.683351 -293.688382) (xy 408.653786 -293.727726) (xy 408.618293 -293.761818)
			(xy 408.57779 -293.789774) (xy 408.533328 -293.810872) (xy 408.486057 -293.824564) (xy 408.437202 -293.830496)
			(xy 408.388027 -293.828515) (xy 408.339808 -293.818671) (xy 408.293792 -293.801219) (xy 408.251171 -293.776612)
			(xy 408.21305 -293.745487) (xy 408.180415 -293.70865) (xy 408.154112 -293.667054) (xy 408.134821 -293.621778)
			(xy 408.123044 -293.573994) (xy 408.119084 -293.52494) (xy 406.830276 -293.52494) (xy 406.829781 -293.549547)
			(xy 406.821886 -293.598124) (xy 406.806302 -293.644805) (xy 406.783431 -293.688382) (xy 406.753866 -293.727726)
			(xy 406.718373 -293.761818) (xy 406.67787 -293.789774) (xy 406.633408 -293.810872) (xy 406.586137 -293.824564)
			(xy 406.537282 -293.830496) (xy 406.488107 -293.828515) (xy 406.439888 -293.818671) (xy 406.393872 -293.801219)
			(xy 406.351251 -293.776612) (xy 406.31313 -293.745487) (xy 406.280495 -293.70865) (xy 406.254192 -293.667054)
			(xy 406.234901 -293.621778) (xy 406.223124 -293.573994) (xy 406.219164 -293.52494) (xy 405.880316 -293.52494)
			(xy 405.879821 -293.549547) (xy 405.871926 -293.598124) (xy 405.856342 -293.644805) (xy 405.833471 -293.688382)
			(xy 405.803906 -293.727726) (xy 405.768413 -293.761818) (xy 405.72791 -293.789774) (xy 405.683448 -293.810872)
			(xy 405.636177 -293.824564) (xy 405.587322 -293.830496) (xy 405.538147 -293.828515) (xy 405.489928 -293.818671)
			(xy 405.443912 -293.801219) (xy 405.401291 -293.776612) (xy 405.36317 -293.745487) (xy 405.330535 -293.70865)
			(xy 405.304232 -293.667054) (xy 405.284941 -293.621778) (xy 405.273164 -293.573994) (xy 405.269204 -293.52494)
			(xy 404.930102 -293.52494) (xy 404.929607 -293.549547) (xy 404.921712 -293.598124) (xy 404.906128 -293.644805)
			(xy 404.883257 -293.688382) (xy 404.853692 -293.727726) (xy 404.818199 -293.761818) (xy 404.777696 -293.789774)
			(xy 404.733234 -293.810872) (xy 404.685963 -293.824564) (xy 404.637108 -293.830496) (xy 404.587933 -293.828515)
			(xy 404.539714 -293.818671) (xy 404.493698 -293.801219) (xy 404.451077 -293.776612) (xy 404.412956 -293.745487)
			(xy 404.380321 -293.70865) (xy 404.354018 -293.667054) (xy 404.334727 -293.621778) (xy 404.32295 -293.573994)
			(xy 404.31899 -293.52494) (xy 403.980142 -293.52494) (xy 403.979647 -293.549547) (xy 403.971752 -293.598124)
			(xy 403.956168 -293.644805) (xy 403.933297 -293.688382) (xy 403.903732 -293.727726) (xy 403.868239 -293.761818)
			(xy 403.827736 -293.789774) (xy 403.783274 -293.810872) (xy 403.736003 -293.824564) (xy 403.687148 -293.830496)
			(xy 403.637973 -293.828515) (xy 403.589754 -293.818671) (xy 403.543738 -293.801219) (xy 403.501117 -293.776612)
			(xy 403.462996 -293.745487) (xy 403.430361 -293.70865) (xy 403.404058 -293.667054) (xy 403.384767 -293.621778)
			(xy 403.37299 -293.573994) (xy 403.36903 -293.52494) (xy 403.030182 -293.52494) (xy 403.029687 -293.549547)
			(xy 403.021792 -293.598124) (xy 403.006208 -293.644805) (xy 402.983337 -293.688382) (xy 402.953772 -293.727726)
			(xy 402.918279 -293.761818) (xy 402.877776 -293.789774) (xy 402.833314 -293.810872) (xy 402.786043 -293.824564)
			(xy 402.737188 -293.830496) (xy 402.688013 -293.828515) (xy 402.639794 -293.818671) (xy 402.593778 -293.801219)
			(xy 402.551157 -293.776612) (xy 402.513036 -293.745487) (xy 402.480401 -293.70865) (xy 402.454098 -293.667054)
			(xy 402.434807 -293.621778) (xy 402.42303 -293.573994) (xy 402.41907 -293.52494) (xy 402.080222 -293.52494)
			(xy 402.079727 -293.549547) (xy 402.071832 -293.598124) (xy 402.056248 -293.644805) (xy 402.033377 -293.688382)
			(xy 402.003812 -293.727726) (xy 401.968319 -293.761818) (xy 401.927816 -293.789774) (xy 401.883354 -293.810872)
			(xy 401.836083 -293.824564) (xy 401.787228 -293.830496) (xy 401.738053 -293.828515) (xy 401.689834 -293.818671)
			(xy 401.643818 -293.801219) (xy 401.601197 -293.776612) (xy 401.563076 -293.745487) (xy 401.530441 -293.70865)
			(xy 401.504138 -293.667054) (xy 401.484847 -293.621778) (xy 401.47307 -293.573994) (xy 401.46911 -293.52494)
			(xy 401.130262 -293.52494) (xy 401.129767 -293.549547) (xy 401.121872 -293.598124) (xy 401.106288 -293.644805)
			(xy 401.083417 -293.688382) (xy 401.053852 -293.727726) (xy 401.018359 -293.761818) (xy 400.977856 -293.789774)
			(xy 400.933394 -293.810872) (xy 400.886123 -293.824564) (xy 400.837268 -293.830496) (xy 400.788093 -293.828515)
			(xy 400.739874 -293.818671) (xy 400.693858 -293.801219) (xy 400.651237 -293.776612) (xy 400.613116 -293.745487)
			(xy 400.580481 -293.70865) (xy 400.554178 -293.667054) (xy 400.534887 -293.621778) (xy 400.52311 -293.573994)
			(xy 400.51915 -293.52494) (xy 400.180302 -293.52494) (xy 400.179807 -293.549547) (xy 400.171912 -293.598124)
			(xy 400.156328 -293.644805) (xy 400.133457 -293.688382) (xy 400.103892 -293.727726) (xy 400.068399 -293.761818)
			(xy 400.027896 -293.789774) (xy 399.983434 -293.810872) (xy 399.936163 -293.824564) (xy 399.887308 -293.830496)
			(xy 399.838133 -293.828515) (xy 399.789914 -293.818671) (xy 399.743898 -293.801219) (xy 399.701277 -293.776612)
			(xy 399.663156 -293.745487) (xy 399.630521 -293.70865) (xy 399.604218 -293.667054) (xy 399.584927 -293.621778)
			(xy 399.57315 -293.573994) (xy 399.56919 -293.52494) (xy 399.230342 -293.52494) (xy 399.229847 -293.549547)
			(xy 399.221952 -293.598124) (xy 399.206368 -293.644805) (xy 399.183497 -293.688382) (xy 399.153932 -293.727726)
			(xy 399.118439 -293.761818) (xy 399.077936 -293.789774) (xy 399.033474 -293.810872) (xy 398.986203 -293.824564)
			(xy 398.937348 -293.830496) (xy 398.888173 -293.828515) (xy 398.839954 -293.818671) (xy 398.793938 -293.801219)
			(xy 398.751317 -293.776612) (xy 398.713196 -293.745487) (xy 398.680561 -293.70865) (xy 398.654258 -293.667054)
			(xy 398.634967 -293.621778) (xy 398.62319 -293.573994) (xy 398.61923 -293.52494) (xy 398.280128 -293.52494)
			(xy 398.279633 -293.549547) (xy 398.271738 -293.598124) (xy 398.256154 -293.644805) (xy 398.233283 -293.688382)
			(xy 398.203718 -293.727726) (xy 398.168225 -293.761818) (xy 398.127722 -293.789774) (xy 398.08326 -293.810872)
			(xy 398.035989 -293.824564) (xy 397.987134 -293.830496) (xy 397.937959 -293.828515) (xy 397.88974 -293.818671)
			(xy 397.843724 -293.801219) (xy 397.801103 -293.776612) (xy 397.762982 -293.745487) (xy 397.730347 -293.70865)
			(xy 397.704044 -293.667054) (xy 397.684753 -293.621778) (xy 397.672976 -293.573994) (xy 397.669016 -293.52494)
			(xy 397.355107 -293.52494) (xy 397.355107 -293.551264) (xy 397.346743 -293.603313) (xy 397.330228 -293.653377)
			(xy 397.30598 -293.700187) (xy 397.274614 -293.742557) (xy 397.236923 -293.779415) (xy 397.193863 -293.809827)
			(xy 397.146523 -293.833022) (xy 397.096103 -293.848415) (xy 397.070072 -293.8526) (xy 397.066008 -293.853108)
			(xy 397.054578 -293.856664) (xy 397.05026 -293.857934) (xy 397.02613 -293.86911) (xy 397.019526 -293.876222)
			(xy 397.004794 -293.891716) (xy 396.996666 -293.902892) (xy 396.993973 -293.908424) (xy 396.991023 -293.920364)
			(xy 396.990824 -293.926514) (xy 396.990824 -294.073326) (xy 396.990988 -294.079481) (xy 396.993933 -294.091432)
			(xy 396.996666 -294.096948) (xy 397.004794 -294.108124) (xy 397.019526 -294.123618) (xy 397.02613 -294.13073)
			(xy 397.05026 -294.141906) (xy 397.054578 -294.143176) (xy 397.066008 -294.146732) (xy 397.070072 -294.14724)
			(xy 397.096117 -294.151348) (xy 397.146542 -294.166743) (xy 397.193887 -294.189942) (xy 397.236953 -294.220358)
			(xy 397.274647 -294.257221) (xy 397.306017 -294.299597) (xy 397.330267 -294.346413) (xy 397.346783 -294.396483)
			(xy 397.355147 -294.448538) (xy 397.355147 -294.4749) (xy 397.669016 -294.4749) (xy 397.672976 -294.425846)
			(xy 397.684753 -294.378062) (xy 397.704044 -294.332786) (xy 397.730347 -294.29119) (xy 397.762982 -294.254353)
			(xy 397.801103 -294.223228) (xy 397.843724 -294.198621) (xy 397.88974 -294.181169) (xy 397.937959 -294.171325)
			(xy 397.987134 -294.169344) (xy 398.035989 -294.175276) (xy 398.08326 -294.188968) (xy 398.127722 -294.210066)
			(xy 398.168225 -294.238022) (xy 398.203718 -294.272114) (xy 398.233283 -294.311458) (xy 398.256154 -294.355035)
			(xy 398.271738 -294.401716) (xy 398.279633 -294.450293) (xy 398.280128 -294.4749) (xy 398.61923 -294.4749)
			(xy 398.62319 -294.425846) (xy 398.634967 -294.378062) (xy 398.654258 -294.332786) (xy 398.680561 -294.29119)
			(xy 398.713196 -294.254353) (xy 398.751317 -294.223228) (xy 398.793938 -294.198621) (xy 398.839954 -294.181169)
			(xy 398.888173 -294.171325) (xy 398.937348 -294.169344) (xy 398.986203 -294.175276) (xy 399.033474 -294.188968)
			(xy 399.077936 -294.210066) (xy 399.118439 -294.238022) (xy 399.153932 -294.272114) (xy 399.183497 -294.311458)
			(xy 399.206368 -294.355035) (xy 399.221952 -294.401716) (xy 399.229847 -294.450293) (xy 399.230342 -294.4749)
			(xy 399.56919 -294.4749) (xy 399.57315 -294.425846) (xy 399.584927 -294.378062) (xy 399.604218 -294.332786)
			(xy 399.630521 -294.29119) (xy 399.663156 -294.254353) (xy 399.701277 -294.223228) (xy 399.743898 -294.198621)
			(xy 399.789914 -294.181169) (xy 399.838133 -294.171325) (xy 399.887308 -294.169344) (xy 399.936163 -294.175276)
			(xy 399.983434 -294.188968) (xy 400.027896 -294.210066) (xy 400.068399 -294.238022) (xy 400.103892 -294.272114)
			(xy 400.133457 -294.311458) (xy 400.156328 -294.355035) (xy 400.171912 -294.401716) (xy 400.179807 -294.450293)
			(xy 400.180302 -294.4749) (xy 400.51915 -294.4749) (xy 400.52311 -294.425846) (xy 400.534887 -294.378062)
			(xy 400.554178 -294.332786) (xy 400.580481 -294.29119) (xy 400.613116 -294.254353) (xy 400.651237 -294.223228)
			(xy 400.693858 -294.198621) (xy 400.739874 -294.181169) (xy 400.788093 -294.171325) (xy 400.837268 -294.169344)
			(xy 400.886123 -294.175276) (xy 400.933394 -294.188968) (xy 400.977856 -294.210066) (xy 401.018359 -294.238022)
			(xy 401.053852 -294.272114) (xy 401.083417 -294.311458) (xy 401.106288 -294.355035) (xy 401.121872 -294.401716)
			(xy 401.129767 -294.450293) (xy 401.130262 -294.4749) (xy 401.46911 -294.4749) (xy 401.47307 -294.425846)
			(xy 401.484847 -294.378062) (xy 401.504138 -294.332786) (xy 401.530441 -294.29119) (xy 401.563076 -294.254353)
			(xy 401.601197 -294.223228) (xy 401.643818 -294.198621) (xy 401.689834 -294.181169) (xy 401.738053 -294.171325)
			(xy 401.787228 -294.169344) (xy 401.836083 -294.175276) (xy 401.883354 -294.188968) (xy 401.927816 -294.210066)
			(xy 401.968319 -294.238022) (xy 402.003812 -294.272114) (xy 402.033377 -294.311458) (xy 402.056248 -294.355035)
			(xy 402.071832 -294.401716) (xy 402.079727 -294.450293) (xy 402.080222 -294.4749) (xy 402.41907 -294.4749)
			(xy 402.42303 -294.425846) (xy 402.434807 -294.378062) (xy 402.454098 -294.332786) (xy 402.480401 -294.29119)
			(xy 402.513036 -294.254353) (xy 402.551157 -294.223228) (xy 402.593778 -294.198621) (xy 402.639794 -294.181169)
			(xy 402.688013 -294.171325) (xy 402.737188 -294.169344) (xy 402.786043 -294.175276) (xy 402.833314 -294.188968)
			(xy 402.877776 -294.210066) (xy 402.918279 -294.238022) (xy 402.953772 -294.272114) (xy 402.983337 -294.311458)
			(xy 403.006208 -294.355035) (xy 403.021792 -294.401716) (xy 403.029687 -294.450293) (xy 403.030182 -294.4749)
			(xy 403.36903 -294.4749) (xy 403.37299 -294.425846) (xy 403.384767 -294.378062) (xy 403.404058 -294.332786)
			(xy 403.430361 -294.29119) (xy 403.462996 -294.254353) (xy 403.501117 -294.223228) (xy 403.543738 -294.198621)
			(xy 403.589754 -294.181169) (xy 403.637973 -294.171325) (xy 403.687148 -294.169344) (xy 403.736003 -294.175276)
			(xy 403.783274 -294.188968) (xy 403.827736 -294.210066) (xy 403.868239 -294.238022) (xy 403.903732 -294.272114)
			(xy 403.933297 -294.311458) (xy 403.956168 -294.355035) (xy 403.971752 -294.401716) (xy 403.979647 -294.450293)
			(xy 403.980142 -294.4749) (xy 404.31899 -294.4749) (xy 404.32295 -294.425846) (xy 404.334727 -294.378062)
			(xy 404.354018 -294.332786) (xy 404.380321 -294.29119) (xy 404.412956 -294.254353) (xy 404.451077 -294.223228)
			(xy 404.493698 -294.198621) (xy 404.539714 -294.181169) (xy 404.587933 -294.171325) (xy 404.637108 -294.169344)
			(xy 404.685963 -294.175276) (xy 404.733234 -294.188968) (xy 404.777696 -294.210066) (xy 404.818199 -294.238022)
			(xy 404.853692 -294.272114) (xy 404.883257 -294.311458) (xy 404.906128 -294.355035) (xy 404.921712 -294.401716)
			(xy 404.929607 -294.450293) (xy 404.930102 -294.4749) (xy 405.269204 -294.4749) (xy 405.273164 -294.425846)
			(xy 405.284941 -294.378062) (xy 405.304232 -294.332786) (xy 405.330535 -294.29119) (xy 405.36317 -294.254353)
			(xy 405.401291 -294.223228) (xy 405.443912 -294.198621) (xy 405.489928 -294.181169) (xy 405.538147 -294.171325)
			(xy 405.587322 -294.169344) (xy 405.636177 -294.175276) (xy 405.683448 -294.188968) (xy 405.72791 -294.210066)
			(xy 405.768413 -294.238022) (xy 405.803906 -294.272114) (xy 405.833471 -294.311458) (xy 405.856342 -294.355035)
			(xy 405.871926 -294.401716) (xy 405.879821 -294.450293) (xy 405.880316 -294.4749) (xy 406.219164 -294.4749)
			(xy 406.223124 -294.425846) (xy 406.234901 -294.378062) (xy 406.254192 -294.332786) (xy 406.280495 -294.29119)
			(xy 406.31313 -294.254353) (xy 406.351251 -294.223228) (xy 406.393872 -294.198621) (xy 406.439888 -294.181169)
			(xy 406.488107 -294.171325) (xy 406.537282 -294.169344) (xy 406.586137 -294.175276) (xy 406.633408 -294.188968)
			(xy 406.67787 -294.210066) (xy 406.718373 -294.238022) (xy 406.753866 -294.272114) (xy 406.783431 -294.311458)
			(xy 406.806302 -294.355035) (xy 406.821886 -294.401716) (xy 406.829781 -294.450293) (xy 406.830276 -294.4749)
			(xy 408.119084 -294.4749) (xy 408.123044 -294.425846) (xy 408.134821 -294.378062) (xy 408.154112 -294.332786)
			(xy 408.180415 -294.29119) (xy 408.21305 -294.254353) (xy 408.251171 -294.223228) (xy 408.293792 -294.198621)
			(xy 408.339808 -294.181169) (xy 408.388027 -294.171325) (xy 408.437202 -294.169344) (xy 408.486057 -294.175276)
			(xy 408.533328 -294.188968) (xy 408.57779 -294.210066) (xy 408.618293 -294.238022) (xy 408.653786 -294.272114)
			(xy 408.683351 -294.311458) (xy 408.706222 -294.355035) (xy 408.721806 -294.401716) (xy 408.729701 -294.450293)
			(xy 408.730196 -294.4749) (xy 409.069044 -294.4749) (xy 409.073004 -294.425846) (xy 409.084781 -294.378062)
			(xy 409.104072 -294.332786) (xy 409.130375 -294.29119) (xy 409.16301 -294.254353) (xy 409.201131 -294.223228)
			(xy 409.243752 -294.198621) (xy 409.289768 -294.181169) (xy 409.337987 -294.171325) (xy 409.387162 -294.169344)
			(xy 409.436017 -294.175276) (xy 409.483288 -294.188968) (xy 409.52775 -294.210066) (xy 409.568253 -294.238022)
			(xy 409.603746 -294.272114) (xy 409.633311 -294.311458) (xy 409.656182 -294.355035) (xy 409.671766 -294.401716)
			(xy 409.679661 -294.450293) (xy 409.680156 -294.4749) (xy 410.019004 -294.4749) (xy 410.022964 -294.425846)
			(xy 410.034741 -294.378062) (xy 410.054032 -294.332786) (xy 410.080335 -294.29119) (xy 410.11297 -294.254353)
			(xy 410.151091 -294.223228) (xy 410.193712 -294.198621) (xy 410.239728 -294.181169) (xy 410.287947 -294.171325)
			(xy 410.337122 -294.169344) (xy 410.385977 -294.175276) (xy 410.433248 -294.188968) (xy 410.47771 -294.210066)
			(xy 410.518213 -294.238022) (xy 410.553706 -294.272114) (xy 410.583271 -294.311458) (xy 410.606142 -294.355035)
			(xy 410.621726 -294.401716) (xy 410.629621 -294.450293) (xy 410.630116 -294.4749) (xy 410.969218 -294.4749)
			(xy 410.973178 -294.425846) (xy 410.984955 -294.378062) (xy 411.004246 -294.332786) (xy 411.030549 -294.29119)
			(xy 411.063184 -294.254353) (xy 411.101305 -294.223228) (xy 411.143926 -294.198621) (xy 411.189942 -294.181169)
			(xy 411.238161 -294.171325) (xy 411.287336 -294.169344) (xy 411.336191 -294.175276) (xy 411.383462 -294.188968)
			(xy 411.427924 -294.210066) (xy 411.468427 -294.238022) (xy 411.50392 -294.272114) (xy 411.533485 -294.311458)
			(xy 411.556356 -294.355035) (xy 411.57194 -294.401716) (xy 411.579835 -294.450293) (xy 411.58033 -294.4749)
			(xy 411.919178 -294.4749) (xy 411.923138 -294.425846) (xy 411.934915 -294.378062) (xy 411.954206 -294.332786)
			(xy 411.980509 -294.29119) (xy 412.013144 -294.254353) (xy 412.051265 -294.223228) (xy 412.093886 -294.198621)
			(xy 412.139902 -294.181169) (xy 412.188121 -294.171325) (xy 412.237296 -294.169344) (xy 412.286151 -294.175276)
			(xy 412.333422 -294.188968) (xy 412.377884 -294.210066) (xy 412.418387 -294.238022) (xy 412.45388 -294.272114)
			(xy 412.483445 -294.311458) (xy 412.506316 -294.355035) (xy 412.5219 -294.401716) (xy 412.529795 -294.450293)
			(xy 412.53029 -294.4749) (xy 412.869138 -294.4749) (xy 412.873098 -294.425846) (xy 412.884875 -294.378062)
			(xy 412.904166 -294.332786) (xy 412.930469 -294.29119) (xy 412.963104 -294.254353) (xy 413.001225 -294.223228)
			(xy 413.043846 -294.198621) (xy 413.089862 -294.181169) (xy 413.138081 -294.171325) (xy 413.187256 -294.169344)
			(xy 413.236111 -294.175276) (xy 413.283382 -294.188968) (xy 413.327844 -294.210066) (xy 413.368347 -294.238022)
			(xy 413.40384 -294.272114) (xy 413.433405 -294.311458) (xy 413.456276 -294.355035) (xy 413.47186 -294.401716)
			(xy 413.479755 -294.450293) (xy 413.48025 -294.4749) (xy 413.819098 -294.4749) (xy 413.823058 -294.425846)
			(xy 413.834835 -294.378062) (xy 413.854126 -294.332786) (xy 413.880429 -294.29119) (xy 413.913064 -294.254353)
			(xy 413.951185 -294.223228) (xy 413.993806 -294.198621) (xy 414.039822 -294.181169) (xy 414.088041 -294.171325)
			(xy 414.137216 -294.169344) (xy 414.186071 -294.175276) (xy 414.233342 -294.188968) (xy 414.277804 -294.210066)
			(xy 414.318307 -294.238022) (xy 414.3538 -294.272114) (xy 414.383365 -294.311458) (xy 414.406236 -294.355035)
			(xy 414.42182 -294.401716) (xy 414.429715 -294.450293) (xy 414.43021 -294.4749) (xy 414.769058 -294.4749)
			(xy 414.773018 -294.425846) (xy 414.784795 -294.378062) (xy 414.804086 -294.332786) (xy 414.830389 -294.29119)
			(xy 414.863024 -294.254353) (xy 414.901145 -294.223228) (xy 414.943766 -294.198621) (xy 414.989782 -294.181169)
			(xy 415.038001 -294.171325) (xy 415.087176 -294.169344) (xy 415.136031 -294.175276) (xy 415.183302 -294.188968)
			(xy 415.227764 -294.210066) (xy 415.268267 -294.238022) (xy 415.30376 -294.272114) (xy 415.333325 -294.311458)
			(xy 415.356196 -294.355035) (xy 415.37178 -294.401716) (xy 415.379675 -294.450293) (xy 415.38017 -294.4749)
			(xy 415.719018 -294.4749) (xy 415.722978 -294.425846) (xy 415.734755 -294.378062) (xy 415.754046 -294.332786)
			(xy 415.780349 -294.29119) (xy 415.812984 -294.254353) (xy 415.851105 -294.223228) (xy 415.893726 -294.198621)
			(xy 415.939742 -294.181169) (xy 415.987961 -294.171325) (xy 416.037136 -294.169344) (xy 416.085991 -294.175276)
			(xy 416.133262 -294.188968) (xy 416.177724 -294.210066) (xy 416.218227 -294.238022) (xy 416.25372 -294.272114)
			(xy 416.283285 -294.311458) (xy 416.306156 -294.355035) (xy 416.32174 -294.401716) (xy 416.329635 -294.450293)
			(xy 416.33013 -294.4749) (xy 416.668978 -294.4749) (xy 416.672938 -294.425846) (xy 416.684715 -294.378062)
			(xy 416.704006 -294.332786) (xy 416.730309 -294.29119) (xy 416.762944 -294.254353) (xy 416.801065 -294.223228)
			(xy 416.843686 -294.198621) (xy 416.889702 -294.181169) (xy 416.937921 -294.171325) (xy 416.987096 -294.169344)
			(xy 417.035951 -294.175276) (xy 417.083222 -294.188968) (xy 417.127684 -294.210066) (xy 417.168187 -294.238022)
			(xy 417.20368 -294.272114) (xy 417.233245 -294.311458) (xy 417.256116 -294.355035) (xy 417.2717 -294.401716)
			(xy 417.279595 -294.450293) (xy 417.28009 -294.4749) (xy 417.619192 -294.4749) (xy 417.623152 -294.425846)
			(xy 417.634929 -294.378062) (xy 417.65422 -294.332786) (xy 417.680523 -294.29119) (xy 417.713158 -294.254353)
			(xy 417.751279 -294.223228) (xy 417.7939 -294.198621) (xy 417.839916 -294.181169) (xy 417.888135 -294.171325)
			(xy 417.93731 -294.169344) (xy 417.986165 -294.175276) (xy 418.033436 -294.188968) (xy 418.077898 -294.210066)
			(xy 418.118401 -294.238022) (xy 418.153894 -294.272114) (xy 418.183459 -294.311458) (xy 418.20633 -294.355035)
			(xy 418.221914 -294.401716) (xy 418.229809 -294.450293) (xy 418.230304 -294.4749) (xy 419.519112 -294.4749)
			(xy 419.523072 -294.425846) (xy 419.534849 -294.378062) (xy 419.55414 -294.332786) (xy 419.580443 -294.29119)
			(xy 419.613078 -294.254353) (xy 419.651199 -294.223228) (xy 419.69382 -294.198621) (xy 419.739836 -294.181169)
			(xy 419.788055 -294.171325) (xy 419.83723 -294.169344) (xy 419.886085 -294.175276) (xy 419.933356 -294.188968)
			(xy 419.977818 -294.210066) (xy 420.018321 -294.238022) (xy 420.053814 -294.272114) (xy 420.083379 -294.311458)
			(xy 420.10625 -294.355035) (xy 420.121834 -294.401716) (xy 420.129729 -294.450293) (xy 420.130224 -294.4749)
			(xy 420.469072 -294.4749) (xy 420.473032 -294.425846) (xy 420.484809 -294.378062) (xy 420.5041 -294.332786)
			(xy 420.530403 -294.29119) (xy 420.563038 -294.254353) (xy 420.601159 -294.223228) (xy 420.64378 -294.198621)
			(xy 420.689796 -294.181169) (xy 420.738015 -294.171325) (xy 420.78719 -294.169344) (xy 420.836045 -294.175276)
			(xy 420.883316 -294.188968) (xy 420.927778 -294.210066) (xy 420.968281 -294.238022) (xy 421.003774 -294.272114)
			(xy 421.033339 -294.311458) (xy 421.05621 -294.355035) (xy 421.071794 -294.401716) (xy 421.079689 -294.450293)
			(xy 421.080184 -294.4749) (xy 421.419032 -294.4749) (xy 421.422992 -294.425846) (xy 421.434769 -294.378062)
			(xy 421.45406 -294.332786) (xy 421.480363 -294.29119) (xy 421.512998 -294.254353) (xy 421.551119 -294.223228)
			(xy 421.59374 -294.198621) (xy 421.639756 -294.181169) (xy 421.687975 -294.171325) (xy 421.73715 -294.169344)
			(xy 421.786005 -294.175276) (xy 421.833276 -294.188968) (xy 421.877738 -294.210066) (xy 421.918241 -294.238022)
			(xy 421.953734 -294.272114) (xy 421.983299 -294.311458) (xy 422.00617 -294.355035) (xy 422.021754 -294.401716)
			(xy 422.029649 -294.450293) (xy 422.030144 -294.4749) (xy 422.368992 -294.4749) (xy 422.372952 -294.425846)
			(xy 422.384729 -294.378062) (xy 422.40402 -294.332786) (xy 422.430323 -294.29119) (xy 422.462958 -294.254353)
			(xy 422.501079 -294.223228) (xy 422.5437 -294.198621) (xy 422.589716 -294.181169) (xy 422.637935 -294.171325)
			(xy 422.68711 -294.169344) (xy 422.735965 -294.175276) (xy 422.783236 -294.188968) (xy 422.827698 -294.210066)
			(xy 422.868201 -294.238022) (xy 422.903694 -294.272114) (xy 422.933259 -294.311458) (xy 422.95613 -294.355035)
			(xy 422.971714 -294.401716) (xy 422.979609 -294.450293) (xy 422.980104 -294.4749) (xy 423.319206 -294.4749)
			(xy 423.323166 -294.425846) (xy 423.334943 -294.378062) (xy 423.354234 -294.332786) (xy 423.380537 -294.29119)
			(xy 423.413172 -294.254353) (xy 423.451293 -294.223228) (xy 423.493914 -294.198621) (xy 423.53993 -294.181169)
			(xy 423.588149 -294.171325) (xy 423.637324 -294.169344) (xy 423.686179 -294.175276) (xy 423.73345 -294.188968)
			(xy 423.777912 -294.210066) (xy 423.818415 -294.238022) (xy 423.853908 -294.272114) (xy 423.883473 -294.311458)
			(xy 423.906344 -294.355035) (xy 423.921928 -294.401716) (xy 423.929823 -294.450293) (xy 423.930318 -294.4749)
			(xy 424.269166 -294.4749) (xy 424.273126 -294.425846) (xy 424.284903 -294.378062) (xy 424.304194 -294.332786)
			(xy 424.330497 -294.29119) (xy 424.363132 -294.254353) (xy 424.401253 -294.223228) (xy 424.443874 -294.198621)
			(xy 424.48989 -294.181169) (xy 424.538109 -294.171325) (xy 424.587284 -294.169344) (xy 424.636139 -294.175276)
			(xy 424.68341 -294.188968) (xy 424.727872 -294.210066) (xy 424.768375 -294.238022) (xy 424.803868 -294.272114)
			(xy 424.833433 -294.311458) (xy 424.856304 -294.355035) (xy 424.871888 -294.401716) (xy 424.879783 -294.450293)
			(xy 424.880278 -294.4749) (xy 426.169086 -294.4749) (xy 426.173046 -294.425846) (xy 426.184823 -294.378062)
			(xy 426.204114 -294.332786) (xy 426.230417 -294.29119) (xy 426.263052 -294.254353) (xy 426.301173 -294.223228)
			(xy 426.343794 -294.198621) (xy 426.38981 -294.181169) (xy 426.438029 -294.171325) (xy 426.487204 -294.169344)
			(xy 426.536059 -294.175276) (xy 426.58333 -294.188968) (xy 426.627792 -294.210066) (xy 426.668295 -294.238022)
			(xy 426.703788 -294.272114) (xy 426.733353 -294.311458) (xy 426.756224 -294.355035) (xy 426.771808 -294.401716)
			(xy 426.779703 -294.450293) (xy 426.780198 -294.4749) (xy 427.119046 -294.4749) (xy 427.123006 -294.425846)
			(xy 427.134783 -294.378062) (xy 427.154074 -294.332786) (xy 427.180377 -294.29119) (xy 427.213012 -294.254353)
			(xy 427.251133 -294.223228) (xy 427.293754 -294.198621) (xy 427.33977 -294.181169) (xy 427.387989 -294.171325)
			(xy 427.437164 -294.169344) (xy 427.486019 -294.175276) (xy 427.53329 -294.188968) (xy 427.577752 -294.210066)
			(xy 427.618255 -294.238022) (xy 427.653748 -294.272114) (xy 427.683313 -294.311458) (xy 427.706184 -294.355035)
			(xy 427.721768 -294.401716) (xy 427.729663 -294.450293) (xy 427.730158 -294.4749) (xy 428.069006 -294.4749)
			(xy 428.072966 -294.425846) (xy 428.084743 -294.378062) (xy 428.104034 -294.332786) (xy 428.130337 -294.29119)
			(xy 428.162972 -294.254353) (xy 428.201093 -294.223228) (xy 428.243714 -294.198621) (xy 428.28973 -294.181169)
			(xy 428.337949 -294.171325) (xy 428.387124 -294.169344) (xy 428.435979 -294.175276) (xy 428.48325 -294.188968)
			(xy 428.527712 -294.210066) (xy 428.568215 -294.238022) (xy 428.603708 -294.272114) (xy 428.633273 -294.311458)
			(xy 428.656144 -294.355035) (xy 428.671728 -294.401716) (xy 428.679623 -294.450293) (xy 428.680118 -294.4749)
			(xy 429.01922 -294.4749) (xy 429.02318 -294.425846) (xy 429.034957 -294.378062) (xy 429.054248 -294.332786)
			(xy 429.080551 -294.29119) (xy 429.113186 -294.254353) (xy 429.151307 -294.223228) (xy 429.193928 -294.198621)
			(xy 429.239944 -294.181169) (xy 429.288163 -294.171325) (xy 429.337338 -294.169344) (xy 429.386193 -294.175276)
			(xy 429.433464 -294.188968) (xy 429.477926 -294.210066) (xy 429.518429 -294.238022) (xy 429.553922 -294.272114)
			(xy 429.583487 -294.311458) (xy 429.606358 -294.355035) (xy 429.621942 -294.401716) (xy 429.629837 -294.450293)
			(xy 429.630332 -294.4749) (xy 429.96918 -294.4749) (xy 429.97314 -294.425846) (xy 429.984917 -294.378062)
			(xy 430.004208 -294.332786) (xy 430.030511 -294.29119) (xy 430.063146 -294.254353) (xy 430.101267 -294.223228)
			(xy 430.143888 -294.198621) (xy 430.189904 -294.181169) (xy 430.238123 -294.171325) (xy 430.287298 -294.169344)
			(xy 430.336153 -294.175276) (xy 430.383424 -294.188968) (xy 430.427886 -294.210066) (xy 430.468389 -294.238022)
			(xy 430.503882 -294.272114) (xy 430.533447 -294.311458) (xy 430.556318 -294.355035) (xy 430.571902 -294.401716)
			(xy 430.579797 -294.450293) (xy 430.580292 -294.4749) (xy 430.91914 -294.4749) (xy 430.9231 -294.425846)
			(xy 430.934877 -294.378062) (xy 430.954168 -294.332786) (xy 430.980471 -294.29119) (xy 431.013106 -294.254353)
			(xy 431.051227 -294.223228) (xy 431.093848 -294.198621) (xy 431.139864 -294.181169) (xy 431.188083 -294.171325)
			(xy 431.237258 -294.169344) (xy 431.286113 -294.175276) (xy 431.333384 -294.188968) (xy 431.377846 -294.210066)
			(xy 431.418349 -294.238022) (xy 431.453842 -294.272114) (xy 431.483407 -294.311458) (xy 431.506278 -294.355035)
			(xy 431.521862 -294.401716) (xy 431.529757 -294.450293) (xy 431.530252 -294.4749) (xy 431.529757 -294.499507)
			(xy 431.521862 -294.548084) (xy 431.506278 -294.594765) (xy 431.483407 -294.638342) (xy 431.47054 -294.655465)
			(xy 437.463125 -294.655465) (xy 437.47088 -294.601509) (xy 437.486235 -294.549206) (xy 437.508877 -294.499621)
			(xy 437.538345 -294.453763) (xy 437.57404 -294.412565) (xy 437.615234 -294.376867) (xy 437.661089 -294.347394)
			(xy 437.710673 -294.324748) (xy 437.762974 -294.309388) (xy 437.816929 -294.301628) (xy 437.844184 -294.301164)
			(xy 437.869584 -294.301926) (xy 437.884316 -294.302449) (xy 437.913046 -294.295896) (xy 437.938712 -294.281417)
			(xy 437.959178 -294.260214) (xy 437.97274 -294.234052) (xy 437.978272 -294.205107) (xy 437.975313 -294.175788)
			(xy 437.970168 -294.161972) (xy 437.961006 -294.13877) (xy 437.948116 -294.090579) (xy 437.941616 -294.041119)
			(xy 437.941212 -294.016176) (xy 437.941704 -293.988927) (xy 437.949463 -293.934985) (xy 437.96482 -293.882695)
			(xy 437.987461 -293.833124) (xy 438.016927 -293.787279) (xy 438.052618 -293.746094) (xy 438.093806 -293.710407)
			(xy 438.139653 -293.680945) (xy 438.189227 -293.658308) (xy 438.241517 -293.642956) (xy 438.29546 -293.635202)
			(xy 438.349958 -293.635203) (xy 438.403901 -293.64296) (xy 438.456191 -293.658314) (xy 438.505763 -293.680954)
			(xy 438.551609 -293.710418) (xy 438.592796 -293.746107) (xy 438.628484 -293.787294) (xy 438.657948 -293.83314)
			(xy 438.680587 -293.882713) (xy 438.695941 -293.935003) (xy 438.702499 -293.980616) (xy 439.58078 -293.980616)
			(xy 439.584851 -293.924994) (xy 439.596977 -293.870557) (xy 439.6169 -293.818466) (xy 439.644196 -293.769831)
			(xy 439.678282 -293.725688) (xy 439.718431 -293.686979) (xy 439.763789 -293.654528) (xy 439.813389 -293.629027)
			(xy 439.866173 -293.61102) (xy 439.921016 -293.60089) (xy 439.97675 -293.598853) (xy 440.032187 -293.604953)
			(xy 440.086144 -293.619059) (xy 440.137473 -293.640871) (xy 440.185079 -293.669925) (xy 440.227947 -293.7056)
			(xy 440.265164 -293.747137) (xy 440.295937 -293.79365) (xy 440.319609 -293.844147) (xy 440.335677 -293.897554)
			(xy 440.343797 -293.95273) (xy 440.344306 -293.980616) (xy 440.343797 -294.008502) (xy 440.335677 -294.063678)
			(xy 440.319609 -294.117085) (xy 440.295937 -294.167582) (xy 440.265164 -294.214095) (xy 440.227947 -294.255632)
			(xy 440.185079 -294.291307) (xy 440.137473 -294.320361) (xy 440.086144 -294.342173) (xy 440.032187 -294.356279)
			(xy 439.97675 -294.362379) (xy 439.921016 -294.360342) (xy 439.866173 -294.350212) (xy 439.813389 -294.332205)
			(xy 439.763789 -294.306704) (xy 439.718431 -294.274253) (xy 439.678282 -294.235544) (xy 439.644196 -294.191401)
			(xy 439.6169 -294.142766) (xy 439.596977 -294.090675) (xy 439.584851 -294.036238) (xy 439.58078 -293.980616)
			(xy 438.702499 -293.980616) (xy 438.703697 -293.988946) (xy 438.703698 -294.043444) (xy 438.695943 -294.097387)
			(xy 438.680591 -294.149677) (xy 438.657953 -294.19925) (xy 438.62849 -294.245098) (xy 438.592803 -294.286285)
			(xy 438.551618 -294.321975) (xy 438.505773 -294.351441) (xy 438.456201 -294.374082) (xy 438.403911 -294.389438)
			(xy 438.349969 -294.397196) (xy 438.32272 -294.397684) (xy 438.29732 -294.396922) (xy 438.28259 -294.396475)
			(xy 438.253872 -294.403022) (xy 438.228216 -294.417492) (xy 438.207756 -294.438681) (xy 438.194192 -294.464827)
			(xy 438.188653 -294.493757) (xy 438.189439 -294.50157) (xy 438.83656 -294.50157) (xy 438.840631 -294.445948)
			(xy 438.852757 -294.391511) (xy 438.87268 -294.33942) (xy 438.899976 -294.290785) (xy 438.934062 -294.246642)
			(xy 438.974211 -294.207933) (xy 439.019569 -294.175482) (xy 439.069169 -294.149981) (xy 439.121953 -294.131974)
			(xy 439.176796 -294.121844) (xy 439.23253 -294.119807) (xy 439.287967 -294.125907) (xy 439.341924 -294.140013)
			(xy 439.393253 -294.161825) (xy 439.440859 -294.190879) (xy 439.483727 -294.226554) (xy 439.520944 -294.268091)
			(xy 439.551717 -294.314604) (xy 439.575389 -294.365101) (xy 439.591457 -294.418508) (xy 439.599577 -294.473684)
			(xy 439.600086 -294.50157) (xy 439.599577 -294.529456) (xy 439.591457 -294.584632) (xy 439.575389 -294.638039)
			(xy 439.551717 -294.688536) (xy 439.520944 -294.735049) (xy 439.483727 -294.776586) (xy 439.440859 -294.812261)
			(xy 439.393253 -294.841315) (xy 439.341924 -294.863127) (xy 439.287967 -294.877233) (xy 439.23253 -294.883333)
			(xy 439.176796 -294.881296) (xy 439.121953 -294.871166) (xy 439.069169 -294.853159) (xy 439.019569 -294.827658)
			(xy 438.974211 -294.795207) (xy 438.934062 -294.756498) (xy 438.899976 -294.712355) (xy 438.87268 -294.66372)
			(xy 438.852757 -294.611629) (xy 438.840631 -294.557192) (xy 438.83656 -294.50157) (xy 438.189439 -294.50157)
			(xy 438.1916 -294.523064) (xy 438.196736 -294.536876) (xy 438.205882 -294.560084) (xy 438.218779 -294.608272)
			(xy 438.225284 -294.65773) (xy 438.225692 -294.682672) (xy 438.225275 -294.709927) (xy 438.217521 -294.763883)
			(xy 438.202168 -294.816186) (xy 438.179527 -294.865772) (xy 438.15006 -294.911631) (xy 438.114366 -294.952829)
			(xy 438.073172 -294.988529) (xy 438.027318 -295.018002) (xy 437.977735 -295.04065) (xy 437.925434 -295.05601)
			(xy 437.871479 -295.063771) (xy 437.816969 -295.063775) (xy 437.763013 -295.056021) (xy 437.71071 -295.040666)
			(xy 437.661125 -295.018025) (xy 437.615266 -294.988557) (xy 437.574068 -294.952863) (xy 437.538369 -294.911669)
			(xy 437.508896 -294.865814) (xy 437.486249 -294.816231) (xy 437.470889 -294.76393) (xy 437.463128 -294.709975)
			(xy 437.463125 -294.655465) (xy 431.47054 -294.655465) (xy 431.453842 -294.677686) (xy 431.418349 -294.711778)
			(xy 431.377846 -294.739734) (xy 431.333384 -294.760832) (xy 431.286113 -294.774524) (xy 431.237258 -294.780456)
			(xy 431.188083 -294.778475) (xy 431.139864 -294.768631) (xy 431.093848 -294.751179) (xy 431.051227 -294.726572)
			(xy 431.013106 -294.695447) (xy 430.980471 -294.65861) (xy 430.954168 -294.617014) (xy 430.934877 -294.571738)
			(xy 430.9231 -294.523954) (xy 430.91914 -294.4749) (xy 430.580292 -294.4749) (xy 430.579797 -294.499507)
			(xy 430.571902 -294.548084) (xy 430.556318 -294.594765) (xy 430.533447 -294.638342) (xy 430.503882 -294.677686)
			(xy 430.468389 -294.711778) (xy 430.427886 -294.739734) (xy 430.383424 -294.760832) (xy 430.336153 -294.774524)
			(xy 430.287298 -294.780456) (xy 430.238123 -294.778475) (xy 430.189904 -294.768631) (xy 430.143888 -294.751179)
			(xy 430.101267 -294.726572) (xy 430.063146 -294.695447) (xy 430.030511 -294.65861) (xy 430.004208 -294.617014)
			(xy 429.984917 -294.571738) (xy 429.97314 -294.523954) (xy 429.96918 -294.4749) (xy 429.630332 -294.4749)
			(xy 429.629837 -294.499507) (xy 429.621942 -294.548084) (xy 429.606358 -294.594765) (xy 429.583487 -294.638342)
			(xy 429.553922 -294.677686) (xy 429.518429 -294.711778) (xy 429.477926 -294.739734) (xy 429.433464 -294.760832)
			(xy 429.386193 -294.774524) (xy 429.337338 -294.780456) (xy 429.288163 -294.778475) (xy 429.239944 -294.768631)
			(xy 429.193928 -294.751179) (xy 429.151307 -294.726572) (xy 429.113186 -294.695447) (xy 429.080551 -294.65861)
			(xy 429.054248 -294.617014) (xy 429.034957 -294.571738) (xy 429.02318 -294.523954) (xy 429.01922 -294.4749)
			(xy 428.680118 -294.4749) (xy 428.679623 -294.499507) (xy 428.671728 -294.548084) (xy 428.656144 -294.594765)
			(xy 428.633273 -294.638342) (xy 428.603708 -294.677686) (xy 428.568215 -294.711778) (xy 428.527712 -294.739734)
			(xy 428.48325 -294.760832) (xy 428.435979 -294.774524) (xy 428.387124 -294.780456) (xy 428.337949 -294.778475)
			(xy 428.28973 -294.768631) (xy 428.243714 -294.751179) (xy 428.201093 -294.726572) (xy 428.162972 -294.695447)
			(xy 428.130337 -294.65861) (xy 428.104034 -294.617014) (xy 428.084743 -294.571738) (xy 428.072966 -294.523954)
			(xy 428.069006 -294.4749) (xy 427.730158 -294.4749) (xy 427.729663 -294.499507) (xy 427.721768 -294.548084)
			(xy 427.706184 -294.594765) (xy 427.683313 -294.638342) (xy 427.653748 -294.677686) (xy 427.618255 -294.711778)
			(xy 427.577752 -294.739734) (xy 427.53329 -294.760832) (xy 427.486019 -294.774524) (xy 427.437164 -294.780456)
			(xy 427.387989 -294.778475) (xy 427.33977 -294.768631) (xy 427.293754 -294.751179) (xy 427.251133 -294.726572)
			(xy 427.213012 -294.695447) (xy 427.180377 -294.65861) (xy 427.154074 -294.617014) (xy 427.134783 -294.571738)
			(xy 427.123006 -294.523954) (xy 427.119046 -294.4749) (xy 426.780198 -294.4749) (xy 426.779703 -294.499507)
			(xy 426.771808 -294.548084) (xy 426.756224 -294.594765) (xy 426.733353 -294.638342) (xy 426.703788 -294.677686)
			(xy 426.668295 -294.711778) (xy 426.627792 -294.739734) (xy 426.58333 -294.760832) (xy 426.536059 -294.774524)
			(xy 426.487204 -294.780456) (xy 426.438029 -294.778475) (xy 426.38981 -294.768631) (xy 426.343794 -294.751179)
			(xy 426.301173 -294.726572) (xy 426.263052 -294.695447) (xy 426.230417 -294.65861) (xy 426.204114 -294.617014)
			(xy 426.184823 -294.571738) (xy 426.173046 -294.523954) (xy 426.169086 -294.4749) (xy 424.880278 -294.4749)
			(xy 424.879783 -294.499507) (xy 424.871888 -294.548084) (xy 424.856304 -294.594765) (xy 424.833433 -294.638342)
			(xy 424.803868 -294.677686) (xy 424.768375 -294.711778) (xy 424.727872 -294.739734) (xy 424.68341 -294.760832)
			(xy 424.636139 -294.774524) (xy 424.587284 -294.780456) (xy 424.538109 -294.778475) (xy 424.48989 -294.768631)
			(xy 424.443874 -294.751179) (xy 424.401253 -294.726572) (xy 424.363132 -294.695447) (xy 424.330497 -294.65861)
			(xy 424.304194 -294.617014) (xy 424.284903 -294.571738) (xy 424.273126 -294.523954) (xy 424.269166 -294.4749)
			(xy 423.930318 -294.4749) (xy 423.929823 -294.499507) (xy 423.921928 -294.548084) (xy 423.906344 -294.594765)
			(xy 423.883473 -294.638342) (xy 423.853908 -294.677686) (xy 423.818415 -294.711778) (xy 423.777912 -294.739734)
			(xy 423.73345 -294.760832) (xy 423.686179 -294.774524) (xy 423.637324 -294.780456) (xy 423.588149 -294.778475)
			(xy 423.53993 -294.768631) (xy 423.493914 -294.751179) (xy 423.451293 -294.726572) (xy 423.413172 -294.695447)
			(xy 423.380537 -294.65861) (xy 423.354234 -294.617014) (xy 423.334943 -294.571738) (xy 423.323166 -294.523954)
			(xy 423.319206 -294.4749) (xy 422.980104 -294.4749) (xy 422.979609 -294.499507) (xy 422.971714 -294.548084)
			(xy 422.95613 -294.594765) (xy 422.933259 -294.638342) (xy 422.903694 -294.677686) (xy 422.868201 -294.711778)
			(xy 422.827698 -294.739734) (xy 422.783236 -294.760832) (xy 422.735965 -294.774524) (xy 422.68711 -294.780456)
			(xy 422.637935 -294.778475) (xy 422.589716 -294.768631) (xy 422.5437 -294.751179) (xy 422.501079 -294.726572)
			(xy 422.462958 -294.695447) (xy 422.430323 -294.65861) (xy 422.40402 -294.617014) (xy 422.384729 -294.571738)
			(xy 422.372952 -294.523954) (xy 422.368992 -294.4749) (xy 422.030144 -294.4749) (xy 422.029649 -294.499507)
			(xy 422.021754 -294.548084) (xy 422.00617 -294.594765) (xy 421.983299 -294.638342) (xy 421.953734 -294.677686)
			(xy 421.918241 -294.711778) (xy 421.877738 -294.739734) (xy 421.833276 -294.760832) (xy 421.786005 -294.774524)
			(xy 421.73715 -294.780456) (xy 421.687975 -294.778475) (xy 421.639756 -294.768631) (xy 421.59374 -294.751179)
			(xy 421.551119 -294.726572) (xy 421.512998 -294.695447) (xy 421.480363 -294.65861) (xy 421.45406 -294.617014)
			(xy 421.434769 -294.571738) (xy 421.422992 -294.523954) (xy 421.419032 -294.4749) (xy 421.080184 -294.4749)
			(xy 421.079689 -294.499507) (xy 421.071794 -294.548084) (xy 421.05621 -294.594765) (xy 421.033339 -294.638342)
			(xy 421.003774 -294.677686) (xy 420.968281 -294.711778) (xy 420.927778 -294.739734) (xy 420.883316 -294.760832)
			(xy 420.836045 -294.774524) (xy 420.78719 -294.780456) (xy 420.738015 -294.778475) (xy 420.689796 -294.768631)
			(xy 420.64378 -294.751179) (xy 420.601159 -294.726572) (xy 420.563038 -294.695447) (xy 420.530403 -294.65861)
			(xy 420.5041 -294.617014) (xy 420.484809 -294.571738) (xy 420.473032 -294.523954) (xy 420.469072 -294.4749)
			(xy 420.130224 -294.4749) (xy 420.129729 -294.499507) (xy 420.121834 -294.548084) (xy 420.10625 -294.594765)
			(xy 420.083379 -294.638342) (xy 420.053814 -294.677686) (xy 420.018321 -294.711778) (xy 419.977818 -294.739734)
			(xy 419.933356 -294.760832) (xy 419.886085 -294.774524) (xy 419.83723 -294.780456) (xy 419.788055 -294.778475)
			(xy 419.739836 -294.768631) (xy 419.69382 -294.751179) (xy 419.651199 -294.726572) (xy 419.613078 -294.695447)
			(xy 419.580443 -294.65861) (xy 419.55414 -294.617014) (xy 419.534849 -294.571738) (xy 419.523072 -294.523954)
			(xy 419.519112 -294.4749) (xy 418.230304 -294.4749) (xy 418.229809 -294.499507) (xy 418.221914 -294.548084)
			(xy 418.20633 -294.594765) (xy 418.183459 -294.638342) (xy 418.153894 -294.677686) (xy 418.118401 -294.711778)
			(xy 418.077898 -294.739734) (xy 418.033436 -294.760832) (xy 417.986165 -294.774524) (xy 417.93731 -294.780456)
			(xy 417.888135 -294.778475) (xy 417.839916 -294.768631) (xy 417.7939 -294.751179) (xy 417.751279 -294.726572)
			(xy 417.713158 -294.695447) (xy 417.680523 -294.65861) (xy 417.65422 -294.617014) (xy 417.634929 -294.571738)
			(xy 417.623152 -294.523954) (xy 417.619192 -294.4749) (xy 417.28009 -294.4749) (xy 417.279595 -294.499507)
			(xy 417.2717 -294.548084) (xy 417.256116 -294.594765) (xy 417.233245 -294.638342) (xy 417.20368 -294.677686)
			(xy 417.168187 -294.711778) (xy 417.127684 -294.739734) (xy 417.083222 -294.760832) (xy 417.035951 -294.774524)
			(xy 416.987096 -294.780456) (xy 416.937921 -294.778475) (xy 416.889702 -294.768631) (xy 416.843686 -294.751179)
			(xy 416.801065 -294.726572) (xy 416.762944 -294.695447) (xy 416.730309 -294.65861) (xy 416.704006 -294.617014)
			(xy 416.684715 -294.571738) (xy 416.672938 -294.523954) (xy 416.668978 -294.4749) (xy 416.33013 -294.4749)
			(xy 416.329635 -294.499507) (xy 416.32174 -294.548084) (xy 416.306156 -294.594765) (xy 416.283285 -294.638342)
			(xy 416.25372 -294.677686) (xy 416.218227 -294.711778) (xy 416.177724 -294.739734) (xy 416.133262 -294.760832)
			(xy 416.085991 -294.774524) (xy 416.037136 -294.780456) (xy 415.987961 -294.778475) (xy 415.939742 -294.768631)
			(xy 415.893726 -294.751179) (xy 415.851105 -294.726572) (xy 415.812984 -294.695447) (xy 415.780349 -294.65861)
			(xy 415.754046 -294.617014) (xy 415.734755 -294.571738) (xy 415.722978 -294.523954) (xy 415.719018 -294.4749)
			(xy 415.38017 -294.4749) (xy 415.379675 -294.499507) (xy 415.37178 -294.548084) (xy 415.356196 -294.594765)
			(xy 415.333325 -294.638342) (xy 415.30376 -294.677686) (xy 415.268267 -294.711778) (xy 415.227764 -294.739734)
			(xy 415.183302 -294.760832) (xy 415.136031 -294.774524) (xy 415.087176 -294.780456) (xy 415.038001 -294.778475)
			(xy 414.989782 -294.768631) (xy 414.943766 -294.751179) (xy 414.901145 -294.726572) (xy 414.863024 -294.695447)
			(xy 414.830389 -294.65861) (xy 414.804086 -294.617014) (xy 414.784795 -294.571738) (xy 414.773018 -294.523954)
			(xy 414.769058 -294.4749) (xy 414.43021 -294.4749) (xy 414.429715 -294.499507) (xy 414.42182 -294.548084)
			(xy 414.406236 -294.594765) (xy 414.383365 -294.638342) (xy 414.3538 -294.677686) (xy 414.318307 -294.711778)
			(xy 414.277804 -294.739734) (xy 414.233342 -294.760832) (xy 414.186071 -294.774524) (xy 414.137216 -294.780456)
			(xy 414.088041 -294.778475) (xy 414.039822 -294.768631) (xy 413.993806 -294.751179) (xy 413.951185 -294.726572)
			(xy 413.913064 -294.695447) (xy 413.880429 -294.65861) (xy 413.854126 -294.617014) (xy 413.834835 -294.571738)
			(xy 413.823058 -294.523954) (xy 413.819098 -294.4749) (xy 413.48025 -294.4749) (xy 413.479755 -294.499507)
			(xy 413.47186 -294.548084) (xy 413.456276 -294.594765) (xy 413.433405 -294.638342) (xy 413.40384 -294.677686)
			(xy 413.368347 -294.711778) (xy 413.327844 -294.739734) (xy 413.283382 -294.760832) (xy 413.236111 -294.774524)
			(xy 413.187256 -294.780456) (xy 413.138081 -294.778475) (xy 413.089862 -294.768631) (xy 413.043846 -294.751179)
			(xy 413.001225 -294.726572) (xy 412.963104 -294.695447) (xy 412.930469 -294.65861) (xy 412.904166 -294.617014)
			(xy 412.884875 -294.571738) (xy 412.873098 -294.523954) (xy 412.869138 -294.4749) (xy 412.53029 -294.4749)
			(xy 412.529795 -294.499507) (xy 412.5219 -294.548084) (xy 412.506316 -294.594765) (xy 412.483445 -294.638342)
			(xy 412.45388 -294.677686) (xy 412.418387 -294.711778) (xy 412.377884 -294.739734) (xy 412.333422 -294.760832)
			(xy 412.286151 -294.774524) (xy 412.237296 -294.780456) (xy 412.188121 -294.778475) (xy 412.139902 -294.768631)
			(xy 412.093886 -294.751179) (xy 412.051265 -294.726572) (xy 412.013144 -294.695447) (xy 411.980509 -294.65861)
			(xy 411.954206 -294.617014) (xy 411.934915 -294.571738) (xy 411.923138 -294.523954) (xy 411.919178 -294.4749)
			(xy 411.58033 -294.4749) (xy 411.579835 -294.499507) (xy 411.57194 -294.548084) (xy 411.556356 -294.594765)
			(xy 411.533485 -294.638342) (xy 411.50392 -294.677686) (xy 411.468427 -294.711778) (xy 411.427924 -294.739734)
			(xy 411.383462 -294.760832) (xy 411.336191 -294.774524) (xy 411.287336 -294.780456) (xy 411.238161 -294.778475)
			(xy 411.189942 -294.768631) (xy 411.143926 -294.751179) (xy 411.101305 -294.726572) (xy 411.063184 -294.695447)
			(xy 411.030549 -294.65861) (xy 411.004246 -294.617014) (xy 410.984955 -294.571738) (xy 410.973178 -294.523954)
			(xy 410.969218 -294.4749) (xy 410.630116 -294.4749) (xy 410.629621 -294.499507) (xy 410.621726 -294.548084)
			(xy 410.606142 -294.594765) (xy 410.583271 -294.638342) (xy 410.553706 -294.677686) (xy 410.518213 -294.711778)
			(xy 410.47771 -294.739734) (xy 410.433248 -294.760832) (xy 410.385977 -294.774524) (xy 410.337122 -294.780456)
			(xy 410.287947 -294.778475) (xy 410.239728 -294.768631) (xy 410.193712 -294.751179) (xy 410.151091 -294.726572)
			(xy 410.11297 -294.695447) (xy 410.080335 -294.65861) (xy 410.054032 -294.617014) (xy 410.034741 -294.571738)
			(xy 410.022964 -294.523954) (xy 410.019004 -294.4749) (xy 409.680156 -294.4749) (xy 409.679661 -294.499507)
			(xy 409.671766 -294.548084) (xy 409.656182 -294.594765) (xy 409.633311 -294.638342) (xy 409.603746 -294.677686)
			(xy 409.568253 -294.711778) (xy 409.52775 -294.739734) (xy 409.483288 -294.760832) (xy 409.436017 -294.774524)
			(xy 409.387162 -294.780456) (xy 409.337987 -294.778475) (xy 409.289768 -294.768631) (xy 409.243752 -294.751179)
			(xy 409.201131 -294.726572) (xy 409.16301 -294.695447) (xy 409.130375 -294.65861) (xy 409.104072 -294.617014)
			(xy 409.084781 -294.571738) (xy 409.073004 -294.523954) (xy 409.069044 -294.4749) (xy 408.730196 -294.4749)
			(xy 408.729701 -294.499507) (xy 408.721806 -294.548084) (xy 408.706222 -294.594765) (xy 408.683351 -294.638342)
			(xy 408.653786 -294.677686) (xy 408.618293 -294.711778) (xy 408.57779 -294.739734) (xy 408.533328 -294.760832)
			(xy 408.486057 -294.774524) (xy 408.437202 -294.780456) (xy 408.388027 -294.778475) (xy 408.339808 -294.768631)
			(xy 408.293792 -294.751179) (xy 408.251171 -294.726572) (xy 408.21305 -294.695447) (xy 408.180415 -294.65861)
			(xy 408.154112 -294.617014) (xy 408.134821 -294.571738) (xy 408.123044 -294.523954) (xy 408.119084 -294.4749)
			(xy 406.830276 -294.4749) (xy 406.829781 -294.499507) (xy 406.821886 -294.548084) (xy 406.806302 -294.594765)
			(xy 406.783431 -294.638342) (xy 406.753866 -294.677686) (xy 406.718373 -294.711778) (xy 406.67787 -294.739734)
			(xy 406.633408 -294.760832) (xy 406.586137 -294.774524) (xy 406.537282 -294.780456) (xy 406.488107 -294.778475)
			(xy 406.439888 -294.768631) (xy 406.393872 -294.751179) (xy 406.351251 -294.726572) (xy 406.31313 -294.695447)
			(xy 406.280495 -294.65861) (xy 406.254192 -294.617014) (xy 406.234901 -294.571738) (xy 406.223124 -294.523954)
			(xy 406.219164 -294.4749) (xy 405.880316 -294.4749) (xy 405.879821 -294.499507) (xy 405.871926 -294.548084)
			(xy 405.856342 -294.594765) (xy 405.833471 -294.638342) (xy 405.803906 -294.677686) (xy 405.768413 -294.711778)
			(xy 405.72791 -294.739734) (xy 405.683448 -294.760832) (xy 405.636177 -294.774524) (xy 405.587322 -294.780456)
			(xy 405.538147 -294.778475) (xy 405.489928 -294.768631) (xy 405.443912 -294.751179) (xy 405.401291 -294.726572)
			(xy 405.36317 -294.695447) (xy 405.330535 -294.65861) (xy 405.304232 -294.617014) (xy 405.284941 -294.571738)
			(xy 405.273164 -294.523954) (xy 405.269204 -294.4749) (xy 404.930102 -294.4749) (xy 404.929607 -294.499507)
			(xy 404.921712 -294.548084) (xy 404.906128 -294.594765) (xy 404.883257 -294.638342) (xy 404.853692 -294.677686)
			(xy 404.818199 -294.711778) (xy 404.777696 -294.739734) (xy 404.733234 -294.760832) (xy 404.685963 -294.774524)
			(xy 404.637108 -294.780456) (xy 404.587933 -294.778475) (xy 404.539714 -294.768631) (xy 404.493698 -294.751179)
			(xy 404.451077 -294.726572) (xy 404.412956 -294.695447) (xy 404.380321 -294.65861) (xy 404.354018 -294.617014)
			(xy 404.334727 -294.571738) (xy 404.32295 -294.523954) (xy 404.31899 -294.4749) (xy 403.980142 -294.4749)
			(xy 403.979647 -294.499507) (xy 403.971752 -294.548084) (xy 403.956168 -294.594765) (xy 403.933297 -294.638342)
			(xy 403.903732 -294.677686) (xy 403.868239 -294.711778) (xy 403.827736 -294.739734) (xy 403.783274 -294.760832)
			(xy 403.736003 -294.774524) (xy 403.687148 -294.780456) (xy 403.637973 -294.778475) (xy 403.589754 -294.768631)
			(xy 403.543738 -294.751179) (xy 403.501117 -294.726572) (xy 403.462996 -294.695447) (xy 403.430361 -294.65861)
			(xy 403.404058 -294.617014) (xy 403.384767 -294.571738) (xy 403.37299 -294.523954) (xy 403.36903 -294.4749)
			(xy 403.030182 -294.4749) (xy 403.029687 -294.499507) (xy 403.021792 -294.548084) (xy 403.006208 -294.594765)
			(xy 402.983337 -294.638342) (xy 402.953772 -294.677686) (xy 402.918279 -294.711778) (xy 402.877776 -294.739734)
			(xy 402.833314 -294.760832) (xy 402.786043 -294.774524) (xy 402.737188 -294.780456) (xy 402.688013 -294.778475)
			(xy 402.639794 -294.768631) (xy 402.593778 -294.751179) (xy 402.551157 -294.726572) (xy 402.513036 -294.695447)
			(xy 402.480401 -294.65861) (xy 402.454098 -294.617014) (xy 402.434807 -294.571738) (xy 402.42303 -294.523954)
			(xy 402.41907 -294.4749) (xy 402.080222 -294.4749) (xy 402.079727 -294.499507) (xy 402.071832 -294.548084)
			(xy 402.056248 -294.594765) (xy 402.033377 -294.638342) (xy 402.003812 -294.677686) (xy 401.968319 -294.711778)
			(xy 401.927816 -294.739734) (xy 401.883354 -294.760832) (xy 401.836083 -294.774524) (xy 401.787228 -294.780456)
			(xy 401.738053 -294.778475) (xy 401.689834 -294.768631) (xy 401.643818 -294.751179) (xy 401.601197 -294.726572)
			(xy 401.563076 -294.695447) (xy 401.530441 -294.65861) (xy 401.504138 -294.617014) (xy 401.484847 -294.571738)
			(xy 401.47307 -294.523954) (xy 401.46911 -294.4749) (xy 401.130262 -294.4749) (xy 401.129767 -294.499507)
			(xy 401.121872 -294.548084) (xy 401.106288 -294.594765) (xy 401.083417 -294.638342) (xy 401.053852 -294.677686)
			(xy 401.018359 -294.711778) (xy 400.977856 -294.739734) (xy 400.933394 -294.760832) (xy 400.886123 -294.774524)
			(xy 400.837268 -294.780456) (xy 400.788093 -294.778475) (xy 400.739874 -294.768631) (xy 400.693858 -294.751179)
			(xy 400.651237 -294.726572) (xy 400.613116 -294.695447) (xy 400.580481 -294.65861) (xy 400.554178 -294.617014)
			(xy 400.534887 -294.571738) (xy 400.52311 -294.523954) (xy 400.51915 -294.4749) (xy 400.180302 -294.4749)
			(xy 400.179807 -294.499507) (xy 400.171912 -294.548084) (xy 400.156328 -294.594765) (xy 400.133457 -294.638342)
			(xy 400.103892 -294.677686) (xy 400.068399 -294.711778) (xy 400.027896 -294.739734) (xy 399.983434 -294.760832)
			(xy 399.936163 -294.774524) (xy 399.887308 -294.780456) (xy 399.838133 -294.778475) (xy 399.789914 -294.768631)
			(xy 399.743898 -294.751179) (xy 399.701277 -294.726572) (xy 399.663156 -294.695447) (xy 399.630521 -294.65861)
			(xy 399.604218 -294.617014) (xy 399.584927 -294.571738) (xy 399.57315 -294.523954) (xy 399.56919 -294.4749)
			(xy 399.230342 -294.4749) (xy 399.229847 -294.499507) (xy 399.221952 -294.548084) (xy 399.206368 -294.594765)
			(xy 399.183497 -294.638342) (xy 399.153932 -294.677686) (xy 399.118439 -294.711778) (xy 399.077936 -294.739734)
			(xy 399.033474 -294.760832) (xy 398.986203 -294.774524) (xy 398.937348 -294.780456) (xy 398.888173 -294.778475)
			(xy 398.839954 -294.768631) (xy 398.793938 -294.751179) (xy 398.751317 -294.726572) (xy 398.713196 -294.695447)
			(xy 398.680561 -294.65861) (xy 398.654258 -294.617014) (xy 398.634967 -294.571738) (xy 398.62319 -294.523954)
			(xy 398.61923 -294.4749) (xy 398.280128 -294.4749) (xy 398.279633 -294.499507) (xy 398.271738 -294.548084)
			(xy 398.256154 -294.594765) (xy 398.233283 -294.638342) (xy 398.203718 -294.677686) (xy 398.168225 -294.711778)
			(xy 398.127722 -294.739734) (xy 398.08326 -294.760832) (xy 398.035989 -294.774524) (xy 397.987134 -294.780456)
			(xy 397.937959 -294.778475) (xy 397.88974 -294.768631) (xy 397.843724 -294.751179) (xy 397.801103 -294.726572)
			(xy 397.762982 -294.695447) (xy 397.730347 -294.65861) (xy 397.704044 -294.617014) (xy 397.684753 -294.571738)
			(xy 397.672976 -294.523954) (xy 397.669016 -294.4749) (xy 397.355147 -294.4749) (xy 397.355147 -294.501262)
			(xy 397.346783 -294.553317) (xy 397.330267 -294.603387) (xy 397.306017 -294.650203) (xy 397.274647 -294.692579)
			(xy 397.236953 -294.729442) (xy 397.193887 -294.759858) (xy 397.146542 -294.783057) (xy 397.096117 -294.798452)
			(xy 397.070072 -294.80256) (xy 397.066008 -294.803068) (xy 397.054578 -294.806624) (xy 397.05026 -294.807894)
			(xy 397.02613 -294.81907) (xy 397.019526 -294.826182) (xy 397.004794 -294.841676) (xy 396.996666 -294.852852)
			(xy 396.993969 -294.858383) (xy 396.991009 -294.870324) (xy 396.990824 -294.876474) (xy 396.990824 -295.355518)
			(xy 440.915804 -295.355518) (xy 440.919875 -295.299896) (xy 440.932001 -295.245459) (xy 440.951924 -295.193368)
			(xy 440.97922 -295.144733) (xy 441.013306 -295.10059) (xy 441.053455 -295.061881) (xy 441.098813 -295.02943)
			(xy 441.148413 -295.003929) (xy 441.201197 -294.985922) (xy 441.25604 -294.975792) (xy 441.311774 -294.973755)
			(xy 441.367211 -294.979855) (xy 441.421168 -294.993961) (xy 441.472497 -295.015773) (xy 441.520103 -295.044827)
			(xy 441.562971 -295.080502) (xy 441.600188 -295.122039) (xy 441.630961 -295.168552) (xy 441.654633 -295.219049)
			(xy 441.670701 -295.272456) (xy 441.678821 -295.327632) (xy 441.67933 -295.355518) (xy 441.678821 -295.383404)
			(xy 441.670701 -295.43858) (xy 441.654633 -295.491987) (xy 441.630961 -295.542484) (xy 441.600188 -295.588997)
			(xy 441.562971 -295.630534) (xy 441.520103 -295.666209) (xy 441.472497 -295.695263) (xy 441.421168 -295.717075)
			(xy 441.367211 -295.731181) (xy 441.311774 -295.737281) (xy 441.25604 -295.735244) (xy 441.201197 -295.725114)
			(xy 441.148413 -295.707107) (xy 441.098813 -295.681606) (xy 441.053455 -295.649155) (xy 441.013306 -295.610446)
			(xy 440.97922 -295.566303) (xy 440.951924 -295.517668) (xy 440.932001 -295.465577) (xy 440.919875 -295.41114)
			(xy 440.915804 -295.355518) (xy 396.990824 -295.355518) (xy 396.990824 -295.973246) (xy 396.990991 -295.9794)
			(xy 396.993939 -295.991349) (xy 396.996666 -295.996868) (xy 397.004794 -296.008044) (xy 397.019526 -296.023538)
			(xy 397.02613 -296.03065) (xy 397.05026 -296.041826) (xy 397.054578 -296.043096) (xy 397.066008 -296.046652)
			(xy 397.070072 -296.04716) (xy 397.096115 -296.051268) (xy 397.146538 -296.066662) (xy 397.19388 -296.089861)
			(xy 397.236942 -296.120275) (xy 397.274634 -296.157136) (xy 397.306001 -296.19951) (xy 397.330249 -296.246323)
			(xy 397.346764 -296.29639) (xy 397.355127 -296.348443) (xy 397.355127 -296.37482) (xy 397.669016 -296.37482)
			(xy 397.672976 -296.325766) (xy 397.684753 -296.277982) (xy 397.704044 -296.232706) (xy 397.730347 -296.19111)
			(xy 397.762982 -296.154273) (xy 397.801103 -296.123148) (xy 397.843724 -296.098541) (xy 397.88974 -296.081089)
			(xy 397.937959 -296.071245) (xy 397.987134 -296.069264) (xy 398.035989 -296.075196) (xy 398.08326 -296.088888)
			(xy 398.127722 -296.109986) (xy 398.168225 -296.137942) (xy 398.203718 -296.172034) (xy 398.233283 -296.211378)
			(xy 398.256154 -296.254955) (xy 398.271738 -296.301636) (xy 398.279633 -296.350213) (xy 398.280128 -296.37482)
			(xy 398.61923 -296.37482) (xy 398.62319 -296.325766) (xy 398.634967 -296.277982) (xy 398.654258 -296.232706)
			(xy 398.680561 -296.19111) (xy 398.713196 -296.154273) (xy 398.751317 -296.123148) (xy 398.793938 -296.098541)
			(xy 398.839954 -296.081089) (xy 398.888173 -296.071245) (xy 398.937348 -296.069264) (xy 398.986203 -296.075196)
			(xy 399.033474 -296.088888) (xy 399.077936 -296.109986) (xy 399.118439 -296.137942) (xy 399.153932 -296.172034)
			(xy 399.183497 -296.211378) (xy 399.206368 -296.254955) (xy 399.221952 -296.301636) (xy 399.229847 -296.350213)
			(xy 399.230342 -296.37482) (xy 399.56919 -296.37482) (xy 399.57315 -296.325766) (xy 399.584927 -296.277982)
			(xy 399.604218 -296.232706) (xy 399.630521 -296.19111) (xy 399.663156 -296.154273) (xy 399.701277 -296.123148)
			(xy 399.743898 -296.098541) (xy 399.789914 -296.081089) (xy 399.838133 -296.071245) (xy 399.887308 -296.069264)
			(xy 399.936163 -296.075196) (xy 399.983434 -296.088888) (xy 400.027896 -296.109986) (xy 400.068399 -296.137942)
			(xy 400.103892 -296.172034) (xy 400.133457 -296.211378) (xy 400.156328 -296.254955) (xy 400.171912 -296.301636)
			(xy 400.179807 -296.350213) (xy 400.180302 -296.37482) (xy 400.51915 -296.37482) (xy 400.52311 -296.325766)
			(xy 400.534887 -296.277982) (xy 400.554178 -296.232706) (xy 400.580481 -296.19111) (xy 400.613116 -296.154273)
			(xy 400.651237 -296.123148) (xy 400.693858 -296.098541) (xy 400.739874 -296.081089) (xy 400.788093 -296.071245)
			(xy 400.837268 -296.069264) (xy 400.886123 -296.075196) (xy 400.933394 -296.088888) (xy 400.977856 -296.109986)
			(xy 401.018359 -296.137942) (xy 401.053852 -296.172034) (xy 401.083417 -296.211378) (xy 401.106288 -296.254955)
			(xy 401.121872 -296.301636) (xy 401.129767 -296.350213) (xy 401.130262 -296.37482) (xy 401.46911 -296.37482)
			(xy 401.47307 -296.325766) (xy 401.484847 -296.277982) (xy 401.504138 -296.232706) (xy 401.530441 -296.19111)
			(xy 401.563076 -296.154273) (xy 401.601197 -296.123148) (xy 401.643818 -296.098541) (xy 401.689834 -296.081089)
			(xy 401.738053 -296.071245) (xy 401.787228 -296.069264) (xy 401.836083 -296.075196) (xy 401.883354 -296.088888)
			(xy 401.927816 -296.109986) (xy 401.968319 -296.137942) (xy 402.003812 -296.172034) (xy 402.033377 -296.211378)
			(xy 402.056248 -296.254955) (xy 402.071832 -296.301636) (xy 402.079727 -296.350213) (xy 402.080222 -296.37482)
			(xy 402.41907 -296.37482) (xy 402.42303 -296.325766) (xy 402.434807 -296.277982) (xy 402.454098 -296.232706)
			(xy 402.480401 -296.19111) (xy 402.513036 -296.154273) (xy 402.551157 -296.123148) (xy 402.593778 -296.098541)
			(xy 402.639794 -296.081089) (xy 402.688013 -296.071245) (xy 402.737188 -296.069264) (xy 402.786043 -296.075196)
			(xy 402.833314 -296.088888) (xy 402.877776 -296.109986) (xy 402.918279 -296.137942) (xy 402.953772 -296.172034)
			(xy 402.983337 -296.211378) (xy 403.006208 -296.254955) (xy 403.021792 -296.301636) (xy 403.029687 -296.350213)
			(xy 403.030182 -296.37482) (xy 403.36903 -296.37482) (xy 403.37299 -296.325766) (xy 403.384767 -296.277982)
			(xy 403.404058 -296.232706) (xy 403.430361 -296.19111) (xy 403.462996 -296.154273) (xy 403.501117 -296.123148)
			(xy 403.543738 -296.098541) (xy 403.589754 -296.081089) (xy 403.637973 -296.071245) (xy 403.687148 -296.069264)
			(xy 403.736003 -296.075196) (xy 403.783274 -296.088888) (xy 403.827736 -296.109986) (xy 403.868239 -296.137942)
			(xy 403.903732 -296.172034) (xy 403.933297 -296.211378) (xy 403.956168 -296.254955) (xy 403.971752 -296.301636)
			(xy 403.979647 -296.350213) (xy 403.980142 -296.37482) (xy 404.319244 -296.37482) (xy 404.323204 -296.325766)
			(xy 404.334981 -296.277982) (xy 404.354272 -296.232706) (xy 404.380575 -296.19111) (xy 404.41321 -296.154273)
			(xy 404.451331 -296.123148) (xy 404.493952 -296.098541) (xy 404.539968 -296.081089) (xy 404.588187 -296.071245)
			(xy 404.637362 -296.069264) (xy 404.686217 -296.075196) (xy 404.733488 -296.088888) (xy 404.77795 -296.109986)
			(xy 404.818453 -296.137942) (xy 404.853946 -296.172034) (xy 404.883511 -296.211378) (xy 404.906382 -296.254955)
			(xy 404.921966 -296.301636) (xy 404.929861 -296.350213) (xy 404.930356 -296.37482) (xy 405.269204 -296.37482)
			(xy 405.273164 -296.325766) (xy 405.284941 -296.277982) (xy 405.304232 -296.232706) (xy 405.330535 -296.19111)
			(xy 405.36317 -296.154273) (xy 405.401291 -296.123148) (xy 405.443912 -296.098541) (xy 405.489928 -296.081089)
			(xy 405.538147 -296.071245) (xy 405.587322 -296.069264) (xy 405.636177 -296.075196) (xy 405.683448 -296.088888)
			(xy 405.72791 -296.109986) (xy 405.768413 -296.137942) (xy 405.803906 -296.172034) (xy 405.833471 -296.211378)
			(xy 405.856342 -296.254955) (xy 405.871926 -296.301636) (xy 405.879821 -296.350213) (xy 405.880316 -296.37482)
			(xy 406.219164 -296.37482) (xy 406.223124 -296.325766) (xy 406.234901 -296.277982) (xy 406.254192 -296.232706)
			(xy 406.280495 -296.19111) (xy 406.31313 -296.154273) (xy 406.351251 -296.123148) (xy 406.393872 -296.098541)
			(xy 406.439888 -296.081089) (xy 406.488107 -296.071245) (xy 406.537282 -296.069264) (xy 406.586137 -296.075196)
			(xy 406.633408 -296.088888) (xy 406.67787 -296.109986) (xy 406.718373 -296.137942) (xy 406.753866 -296.172034)
			(xy 406.783431 -296.211378) (xy 406.806302 -296.254955) (xy 406.821886 -296.301636) (xy 406.829781 -296.350213)
			(xy 406.830276 -296.37482) (xy 408.119084 -296.37482) (xy 408.123044 -296.325766) (xy 408.134821 -296.277982)
			(xy 408.154112 -296.232706) (xy 408.180415 -296.19111) (xy 408.21305 -296.154273) (xy 408.251171 -296.123148)
			(xy 408.293792 -296.098541) (xy 408.339808 -296.081089) (xy 408.388027 -296.071245) (xy 408.437202 -296.069264)
			(xy 408.486057 -296.075196) (xy 408.533328 -296.088888) (xy 408.57779 -296.109986) (xy 408.618293 -296.137942)
			(xy 408.653786 -296.172034) (xy 408.683351 -296.211378) (xy 408.706222 -296.254955) (xy 408.721806 -296.301636)
			(xy 408.729701 -296.350213) (xy 408.730196 -296.37482) (xy 409.069044 -296.37482) (xy 409.073004 -296.325766)
			(xy 409.084781 -296.277982) (xy 409.104072 -296.232706) (xy 409.130375 -296.19111) (xy 409.16301 -296.154273)
			(xy 409.201131 -296.123148) (xy 409.243752 -296.098541) (xy 409.289768 -296.081089) (xy 409.337987 -296.071245)
			(xy 409.387162 -296.069264) (xy 409.436017 -296.075196) (xy 409.483288 -296.088888) (xy 409.52775 -296.109986)
			(xy 409.568253 -296.137942) (xy 409.603746 -296.172034) (xy 409.633311 -296.211378) (xy 409.656182 -296.254955)
			(xy 409.671766 -296.301636) (xy 409.679661 -296.350213) (xy 409.680156 -296.37482) (xy 410.019004 -296.37482)
			(xy 410.022964 -296.325766) (xy 410.034741 -296.277982) (xy 410.054032 -296.232706) (xy 410.080335 -296.19111)
			(xy 410.11297 -296.154273) (xy 410.151091 -296.123148) (xy 410.193712 -296.098541) (xy 410.239728 -296.081089)
			(xy 410.287947 -296.071245) (xy 410.337122 -296.069264) (xy 410.385977 -296.075196) (xy 410.433248 -296.088888)
			(xy 410.47771 -296.109986) (xy 410.518213 -296.137942) (xy 410.553706 -296.172034) (xy 410.583271 -296.211378)
			(xy 410.606142 -296.254955) (xy 410.621726 -296.301636) (xy 410.629621 -296.350213) (xy 410.630116 -296.37482)
			(xy 410.969218 -296.37482) (xy 410.973178 -296.325766) (xy 410.984955 -296.277982) (xy 411.004246 -296.232706)
			(xy 411.030549 -296.19111) (xy 411.063184 -296.154273) (xy 411.101305 -296.123148) (xy 411.143926 -296.098541)
			(xy 411.189942 -296.081089) (xy 411.238161 -296.071245) (xy 411.287336 -296.069264) (xy 411.336191 -296.075196)
			(xy 411.383462 -296.088888) (xy 411.427924 -296.109986) (xy 411.468427 -296.137942) (xy 411.50392 -296.172034)
			(xy 411.533485 -296.211378) (xy 411.556356 -296.254955) (xy 411.57194 -296.301636) (xy 411.579835 -296.350213)
			(xy 411.58033 -296.37482) (xy 411.919178 -296.37482) (xy 411.923138 -296.325766) (xy 411.934915 -296.277982)
			(xy 411.954206 -296.232706) (xy 411.980509 -296.19111) (xy 412.013144 -296.154273) (xy 412.051265 -296.123148)
			(xy 412.093886 -296.098541) (xy 412.139902 -296.081089) (xy 412.188121 -296.071245) (xy 412.237296 -296.069264)
			(xy 412.286151 -296.075196) (xy 412.333422 -296.088888) (xy 412.377884 -296.109986) (xy 412.418387 -296.137942)
			(xy 412.45388 -296.172034) (xy 412.483445 -296.211378) (xy 412.506316 -296.254955) (xy 412.5219 -296.301636)
			(xy 412.529795 -296.350213) (xy 412.53029 -296.37482) (xy 412.869138 -296.37482) (xy 412.873098 -296.325766)
			(xy 412.884875 -296.277982) (xy 412.904166 -296.232706) (xy 412.930469 -296.19111) (xy 412.963104 -296.154273)
			(xy 413.001225 -296.123148) (xy 413.043846 -296.098541) (xy 413.089862 -296.081089) (xy 413.138081 -296.071245)
			(xy 413.187256 -296.069264) (xy 413.236111 -296.075196) (xy 413.283382 -296.088888) (xy 413.327844 -296.109986)
			(xy 413.368347 -296.137942) (xy 413.40384 -296.172034) (xy 413.433405 -296.211378) (xy 413.456276 -296.254955)
			(xy 413.47186 -296.301636) (xy 413.479755 -296.350213) (xy 413.48025 -296.37482) (xy 413.819098 -296.37482)
			(xy 413.823058 -296.325766) (xy 413.834835 -296.277982) (xy 413.854126 -296.232706) (xy 413.880429 -296.19111)
			(xy 413.913064 -296.154273) (xy 413.951185 -296.123148) (xy 413.993806 -296.098541) (xy 414.039822 -296.081089)
			(xy 414.088041 -296.071245) (xy 414.137216 -296.069264) (xy 414.186071 -296.075196) (xy 414.233342 -296.088888)
			(xy 414.277804 -296.109986) (xy 414.318307 -296.137942) (xy 414.3538 -296.172034) (xy 414.383365 -296.211378)
			(xy 414.406236 -296.254955) (xy 414.42182 -296.301636) (xy 414.429715 -296.350213) (xy 414.43021 -296.37482)
			(xy 414.769058 -296.37482) (xy 414.773018 -296.325766) (xy 414.784795 -296.277982) (xy 414.804086 -296.232706)
			(xy 414.830389 -296.19111) (xy 414.863024 -296.154273) (xy 414.901145 -296.123148) (xy 414.943766 -296.098541)
			(xy 414.989782 -296.081089) (xy 415.038001 -296.071245) (xy 415.087176 -296.069264) (xy 415.136031 -296.075196)
			(xy 415.183302 -296.088888) (xy 415.227764 -296.109986) (xy 415.268267 -296.137942) (xy 415.30376 -296.172034)
			(xy 415.333325 -296.211378) (xy 415.356196 -296.254955) (xy 415.37178 -296.301636) (xy 415.379675 -296.350213)
			(xy 415.38017 -296.37482) (xy 415.719018 -296.37482) (xy 415.722978 -296.325766) (xy 415.734755 -296.277982)
			(xy 415.754046 -296.232706) (xy 415.780349 -296.19111) (xy 415.812984 -296.154273) (xy 415.851105 -296.123148)
			(xy 415.893726 -296.098541) (xy 415.939742 -296.081089) (xy 415.987961 -296.071245) (xy 416.037136 -296.069264)
			(xy 416.085991 -296.075196) (xy 416.133262 -296.088888) (xy 416.177724 -296.109986) (xy 416.218227 -296.137942)
			(xy 416.25372 -296.172034) (xy 416.283285 -296.211378) (xy 416.306156 -296.254955) (xy 416.32174 -296.301636)
			(xy 416.329635 -296.350213) (xy 416.33013 -296.37482) (xy 416.668978 -296.37482) (xy 416.672938 -296.325766)
			(xy 416.684715 -296.277982) (xy 416.704006 -296.232706) (xy 416.730309 -296.19111) (xy 416.762944 -296.154273)
			(xy 416.801065 -296.123148) (xy 416.843686 -296.098541) (xy 416.889702 -296.081089) (xy 416.937921 -296.071245)
			(xy 416.987096 -296.069264) (xy 417.035951 -296.075196) (xy 417.083222 -296.088888) (xy 417.127684 -296.109986)
			(xy 417.168187 -296.137942) (xy 417.20368 -296.172034) (xy 417.233245 -296.211378) (xy 417.256116 -296.254955)
			(xy 417.2717 -296.301636) (xy 417.279595 -296.350213) (xy 417.28009 -296.37482) (xy 417.619192 -296.37482)
			(xy 417.623152 -296.325766) (xy 417.634929 -296.277982) (xy 417.65422 -296.232706) (xy 417.680523 -296.19111)
			(xy 417.713158 -296.154273) (xy 417.751279 -296.123148) (xy 417.7939 -296.098541) (xy 417.839916 -296.081089)
			(xy 417.888135 -296.071245) (xy 417.93731 -296.069264) (xy 417.986165 -296.075196) (xy 418.033436 -296.088888)
			(xy 418.077898 -296.109986) (xy 418.118401 -296.137942) (xy 418.153894 -296.172034) (xy 418.183459 -296.211378)
			(xy 418.20633 -296.254955) (xy 418.221914 -296.301636) (xy 418.229809 -296.350213) (xy 418.230304 -296.37482)
			(xy 419.519112 -296.37482) (xy 419.523072 -296.325766) (xy 419.534849 -296.277982) (xy 419.55414 -296.232706)
			(xy 419.580443 -296.19111) (xy 419.613078 -296.154273) (xy 419.651199 -296.123148) (xy 419.69382 -296.098541)
			(xy 419.739836 -296.081089) (xy 419.788055 -296.071245) (xy 419.83723 -296.069264) (xy 419.886085 -296.075196)
			(xy 419.933356 -296.088888) (xy 419.977818 -296.109986) (xy 420.018321 -296.137942) (xy 420.053814 -296.172034)
			(xy 420.083379 -296.211378) (xy 420.10625 -296.254955) (xy 420.121834 -296.301636) (xy 420.129729 -296.350213)
			(xy 420.130224 -296.37482) (xy 420.469072 -296.37482) (xy 420.473032 -296.325766) (xy 420.484809 -296.277982)
			(xy 420.5041 -296.232706) (xy 420.530403 -296.19111) (xy 420.563038 -296.154273) (xy 420.601159 -296.123148)
			(xy 420.64378 -296.098541) (xy 420.689796 -296.081089) (xy 420.738015 -296.071245) (xy 420.78719 -296.069264)
			(xy 420.836045 -296.075196) (xy 420.883316 -296.088888) (xy 420.927778 -296.109986) (xy 420.968281 -296.137942)
			(xy 421.003774 -296.172034) (xy 421.033339 -296.211378) (xy 421.05621 -296.254955) (xy 421.071794 -296.301636)
			(xy 421.079689 -296.350213) (xy 421.080184 -296.37482) (xy 421.419032 -296.37482) (xy 421.422992 -296.325766)
			(xy 421.434769 -296.277982) (xy 421.45406 -296.232706) (xy 421.480363 -296.19111) (xy 421.512998 -296.154273)
			(xy 421.551119 -296.123148) (xy 421.59374 -296.098541) (xy 421.639756 -296.081089) (xy 421.687975 -296.071245)
			(xy 421.73715 -296.069264) (xy 421.786005 -296.075196) (xy 421.833276 -296.088888) (xy 421.877738 -296.109986)
			(xy 421.918241 -296.137942) (xy 421.953734 -296.172034) (xy 421.983299 -296.211378) (xy 422.00617 -296.254955)
			(xy 422.021754 -296.301636) (xy 422.029649 -296.350213) (xy 422.030144 -296.37482) (xy 422.368992 -296.37482)
			(xy 422.372952 -296.325766) (xy 422.384729 -296.277982) (xy 422.40402 -296.232706) (xy 422.430323 -296.19111)
			(xy 422.462958 -296.154273) (xy 422.501079 -296.123148) (xy 422.5437 -296.098541) (xy 422.589716 -296.081089)
			(xy 422.637935 -296.071245) (xy 422.68711 -296.069264) (xy 422.735965 -296.075196) (xy 422.783236 -296.088888)
			(xy 422.827698 -296.109986) (xy 422.868201 -296.137942) (xy 422.903694 -296.172034) (xy 422.933259 -296.211378)
			(xy 422.95613 -296.254955) (xy 422.971714 -296.301636) (xy 422.979609 -296.350213) (xy 422.980104 -296.37482)
			(xy 423.319206 -296.37482) (xy 423.323166 -296.325766) (xy 423.334943 -296.277982) (xy 423.354234 -296.232706)
			(xy 423.380537 -296.19111) (xy 423.413172 -296.154273) (xy 423.451293 -296.123148) (xy 423.493914 -296.098541)
			(xy 423.53993 -296.081089) (xy 423.588149 -296.071245) (xy 423.637324 -296.069264) (xy 423.686179 -296.075196)
			(xy 423.73345 -296.088888) (xy 423.777912 -296.109986) (xy 423.818415 -296.137942) (xy 423.853908 -296.172034)
			(xy 423.883473 -296.211378) (xy 423.906344 -296.254955) (xy 423.921928 -296.301636) (xy 423.929823 -296.350213)
			(xy 423.930318 -296.37482) (xy 424.269166 -296.37482) (xy 424.273126 -296.325766) (xy 424.284903 -296.277982)
			(xy 424.304194 -296.232706) (xy 424.330497 -296.19111) (xy 424.363132 -296.154273) (xy 424.401253 -296.123148)
			(xy 424.443874 -296.098541) (xy 424.48989 -296.081089) (xy 424.538109 -296.071245) (xy 424.587284 -296.069264)
			(xy 424.636139 -296.075196) (xy 424.68341 -296.088888) (xy 424.727872 -296.109986) (xy 424.768375 -296.137942)
			(xy 424.803868 -296.172034) (xy 424.833433 -296.211378) (xy 424.856304 -296.254955) (xy 424.871888 -296.301636)
			(xy 424.879783 -296.350213) (xy 424.880278 -296.37482) (xy 427.119046 -296.37482) (xy 427.123006 -296.325766)
			(xy 427.134783 -296.277982) (xy 427.154074 -296.232706) (xy 427.180377 -296.19111) (xy 427.213012 -296.154273)
			(xy 427.251133 -296.123148) (xy 427.293754 -296.098541) (xy 427.33977 -296.081089) (xy 427.387989 -296.071245)
			(xy 427.437164 -296.069264) (xy 427.486019 -296.075196) (xy 427.53329 -296.088888) (xy 427.577752 -296.109986)
			(xy 427.618255 -296.137942) (xy 427.653748 -296.172034) (xy 427.683313 -296.211378) (xy 427.706184 -296.254955)
			(xy 427.721768 -296.301636) (xy 427.729663 -296.350213) (xy 427.730158 -296.37482) (xy 428.069006 -296.37482)
			(xy 428.072966 -296.325766) (xy 428.084743 -296.277982) (xy 428.104034 -296.232706) (xy 428.130337 -296.19111)
			(xy 428.162972 -296.154273) (xy 428.201093 -296.123148) (xy 428.243714 -296.098541) (xy 428.28973 -296.081089)
			(xy 428.337949 -296.071245) (xy 428.387124 -296.069264) (xy 428.435979 -296.075196) (xy 428.48325 -296.088888)
			(xy 428.527712 -296.109986) (xy 428.568215 -296.137942) (xy 428.603708 -296.172034) (xy 428.633273 -296.211378)
			(xy 428.656144 -296.254955) (xy 428.671728 -296.301636) (xy 428.679623 -296.350213) (xy 428.680118 -296.37482)
			(xy 429.01922 -296.37482) (xy 429.02318 -296.325766) (xy 429.034957 -296.277982) (xy 429.054248 -296.232706)
			(xy 429.080551 -296.19111) (xy 429.113186 -296.154273) (xy 429.151307 -296.123148) (xy 429.193928 -296.098541)
			(xy 429.239944 -296.081089) (xy 429.288163 -296.071245) (xy 429.337338 -296.069264) (xy 429.386193 -296.075196)
			(xy 429.433464 -296.088888) (xy 429.477926 -296.109986) (xy 429.518429 -296.137942) (xy 429.553922 -296.172034)
			(xy 429.583487 -296.211378) (xy 429.606358 -296.254955) (xy 429.621942 -296.301636) (xy 429.629837 -296.350213)
			(xy 429.630332 -296.37482) (xy 429.96918 -296.37482) (xy 429.97314 -296.325766) (xy 429.984917 -296.277982)
			(xy 430.004208 -296.232706) (xy 430.030511 -296.19111) (xy 430.063146 -296.154273) (xy 430.101267 -296.123148)
			(xy 430.143888 -296.098541) (xy 430.189904 -296.081089) (xy 430.238123 -296.071245) (xy 430.287298 -296.069264)
			(xy 430.336153 -296.075196) (xy 430.383424 -296.088888) (xy 430.427886 -296.109986) (xy 430.468389 -296.137942)
			(xy 430.503882 -296.172034) (xy 430.533447 -296.211378) (xy 430.556318 -296.254955) (xy 430.571902 -296.301636)
			(xy 430.579797 -296.350213) (xy 430.580292 -296.37482) (xy 430.91914 -296.37482) (xy 430.9231 -296.325766)
			(xy 430.934877 -296.277982) (xy 430.954168 -296.232706) (xy 430.980471 -296.19111) (xy 431.013106 -296.154273)
			(xy 431.051227 -296.123148) (xy 431.093848 -296.098541) (xy 431.139864 -296.081089) (xy 431.188083 -296.071245)
			(xy 431.237258 -296.069264) (xy 431.286113 -296.075196) (xy 431.333384 -296.088888) (xy 431.377846 -296.109986)
			(xy 431.418349 -296.137942) (xy 431.453842 -296.172034) (xy 431.483407 -296.211378) (xy 431.506278 -296.254955)
			(xy 431.521862 -296.301636) (xy 431.529757 -296.350213) (xy 431.530252 -296.37482) (xy 431.529757 -296.399427)
			(xy 431.521862 -296.448004) (xy 431.506278 -296.494685) (xy 431.483407 -296.538262) (xy 431.453842 -296.577606)
			(xy 431.418349 -296.611698) (xy 431.416358 -296.613072) (xy 437.562496 -296.613072) (xy 437.566567 -296.55745)
			(xy 437.578693 -296.503013) (xy 437.598616 -296.450922) (xy 437.625912 -296.402287) (xy 437.659998 -296.358144)
			(xy 437.700147 -296.319435) (xy 437.745505 -296.286984) (xy 437.795105 -296.261483) (xy 437.847889 -296.243476)
			(xy 437.902732 -296.233346) (xy 437.958466 -296.231309) (xy 438.013903 -296.237409) (xy 438.06786 -296.251515)
			(xy 438.119189 -296.273327) (xy 438.166795 -296.302381) (xy 438.209663 -296.338056) (xy 438.24688 -296.379593)
			(xy 438.277653 -296.426106) (xy 438.301325 -296.476603) (xy 438.317393 -296.53001) (xy 438.325513 -296.585186)
			(xy 438.326022 -296.613072) (xy 438.837322 -296.613072) (xy 438.841393 -296.55745) (xy 438.853519 -296.503013)
			(xy 438.873442 -296.450922) (xy 438.900738 -296.402287) (xy 438.934824 -296.358144) (xy 438.974973 -296.319435)
			(xy 439.020331 -296.286984) (xy 439.069931 -296.261483) (xy 439.122715 -296.243476) (xy 439.177558 -296.233346)
			(xy 439.233292 -296.231309) (xy 439.288729 -296.237409) (xy 439.342686 -296.251515) (xy 439.394015 -296.273327)
			(xy 439.441621 -296.302381) (xy 439.484489 -296.338056) (xy 439.521706 -296.379593) (xy 439.552479 -296.426106)
			(xy 439.576151 -296.476603) (xy 439.592219 -296.53001) (xy 439.600339 -296.585186) (xy 439.600848 -296.613072)
			(xy 439.600339 -296.640958) (xy 439.592219 -296.696134) (xy 439.576151 -296.749541) (xy 439.552479 -296.800038)
			(xy 439.521706 -296.846551) (xy 439.484489 -296.888088) (xy 439.441621 -296.923763) (xy 439.394015 -296.952817)
			(xy 439.342686 -296.974629) (xy 439.288729 -296.988735) (xy 439.233292 -296.994835) (xy 439.177558 -296.992798)
			(xy 439.122715 -296.982668) (xy 439.069931 -296.964661) (xy 439.020331 -296.93916) (xy 438.974973 -296.906709)
			(xy 438.934824 -296.868) (xy 438.900738 -296.823857) (xy 438.873442 -296.775222) (xy 438.853519 -296.723131)
			(xy 438.841393 -296.668694) (xy 438.837322 -296.613072) (xy 438.326022 -296.613072) (xy 438.325513 -296.640958)
			(xy 438.317393 -296.696134) (xy 438.301325 -296.749541) (xy 438.277653 -296.800038) (xy 438.24688 -296.846551)
			(xy 438.209663 -296.888088) (xy 438.166795 -296.923763) (xy 438.119189 -296.952817) (xy 438.06786 -296.974629)
			(xy 438.013903 -296.988735) (xy 437.958466 -296.994835) (xy 437.902732 -296.992798) (xy 437.847889 -296.982668)
			(xy 437.795105 -296.964661) (xy 437.745505 -296.93916) (xy 437.700147 -296.906709) (xy 437.659998 -296.868)
			(xy 437.625912 -296.823857) (xy 437.598616 -296.775222) (xy 437.578693 -296.723131) (xy 437.566567 -296.668694)
			(xy 437.562496 -296.613072) (xy 431.416358 -296.613072) (xy 431.377846 -296.639654) (xy 431.333384 -296.660752)
			(xy 431.286113 -296.674444) (xy 431.237258 -296.680376) (xy 431.188083 -296.678395) (xy 431.139864 -296.668551)
			(xy 431.093848 -296.651099) (xy 431.051227 -296.626492) (xy 431.013106 -296.595367) (xy 430.980471 -296.55853)
			(xy 430.954168 -296.516934) (xy 430.934877 -296.471658) (xy 430.9231 -296.423874) (xy 430.91914 -296.37482)
			(xy 430.580292 -296.37482) (xy 430.579797 -296.399427) (xy 430.571902 -296.448004) (xy 430.556318 -296.494685)
			(xy 430.533447 -296.538262) (xy 430.503882 -296.577606) (xy 430.468389 -296.611698) (xy 430.427886 -296.639654)
			(xy 430.383424 -296.660752) (xy 430.336153 -296.674444) (xy 430.287298 -296.680376) (xy 430.238123 -296.678395)
			(xy 430.189904 -296.668551) (xy 430.143888 -296.651099) (xy 430.101267 -296.626492) (xy 430.063146 -296.595367)
			(xy 430.030511 -296.55853) (xy 430.004208 -296.516934) (xy 429.984917 -296.471658) (xy 429.97314 -296.423874)
			(xy 429.96918 -296.37482) (xy 429.630332 -296.37482) (xy 429.629837 -296.399427) (xy 429.621942 -296.448004)
			(xy 429.606358 -296.494685) (xy 429.583487 -296.538262) (xy 429.553922 -296.577606) (xy 429.518429 -296.611698)
			(xy 429.477926 -296.639654) (xy 429.433464 -296.660752) (xy 429.386193 -296.674444) (xy 429.337338 -296.680376)
			(xy 429.288163 -296.678395) (xy 429.239944 -296.668551) (xy 429.193928 -296.651099) (xy 429.151307 -296.626492)
			(xy 429.113186 -296.595367) (xy 429.080551 -296.55853) (xy 429.054248 -296.516934) (xy 429.034957 -296.471658)
			(xy 429.02318 -296.423874) (xy 429.01922 -296.37482) (xy 428.680118 -296.37482) (xy 428.679623 -296.399427)
			(xy 428.671728 -296.448004) (xy 428.656144 -296.494685) (xy 428.633273 -296.538262) (xy 428.603708 -296.577606)
			(xy 428.568215 -296.611698) (xy 428.527712 -296.639654) (xy 428.48325 -296.660752) (xy 428.435979 -296.674444)
			(xy 428.387124 -296.680376) (xy 428.337949 -296.678395) (xy 428.28973 -296.668551) (xy 428.243714 -296.651099)
			(xy 428.201093 -296.626492) (xy 428.162972 -296.595367) (xy 428.130337 -296.55853) (xy 428.104034 -296.516934)
			(xy 428.084743 -296.471658) (xy 428.072966 -296.423874) (xy 428.069006 -296.37482) (xy 427.730158 -296.37482)
			(xy 427.729663 -296.399427) (xy 427.721768 -296.448004) (xy 427.706184 -296.494685) (xy 427.683313 -296.538262)
			(xy 427.653748 -296.577606) (xy 427.618255 -296.611698) (xy 427.577752 -296.639654) (xy 427.53329 -296.660752)
			(xy 427.486019 -296.674444) (xy 427.437164 -296.680376) (xy 427.387989 -296.678395) (xy 427.33977 -296.668551)
			(xy 427.293754 -296.651099) (xy 427.251133 -296.626492) (xy 427.213012 -296.595367) (xy 427.180377 -296.55853)
			(xy 427.154074 -296.516934) (xy 427.134783 -296.471658) (xy 427.123006 -296.423874) (xy 427.119046 -296.37482)
			(xy 424.880278 -296.37482) (xy 424.879783 -296.399427) (xy 424.871888 -296.448004) (xy 424.856304 -296.494685)
			(xy 424.833433 -296.538262) (xy 424.803868 -296.577606) (xy 424.768375 -296.611698) (xy 424.727872 -296.639654)
			(xy 424.68341 -296.660752) (xy 424.636139 -296.674444) (xy 424.587284 -296.680376) (xy 424.538109 -296.678395)
			(xy 424.48989 -296.668551) (xy 424.443874 -296.651099) (xy 424.401253 -296.626492) (xy 424.363132 -296.595367)
			(xy 424.330497 -296.55853) (xy 424.304194 -296.516934) (xy 424.284903 -296.471658) (xy 424.273126 -296.423874)
			(xy 424.269166 -296.37482) (xy 423.930318 -296.37482) (xy 423.929823 -296.399427) (xy 423.921928 -296.448004)
			(xy 423.906344 -296.494685) (xy 423.883473 -296.538262) (xy 423.853908 -296.577606) (xy 423.818415 -296.611698)
			(xy 423.777912 -296.639654) (xy 423.73345 -296.660752) (xy 423.686179 -296.674444) (xy 423.637324 -296.680376)
			(xy 423.588149 -296.678395) (xy 423.53993 -296.668551) (xy 423.493914 -296.651099) (xy 423.451293 -296.626492)
			(xy 423.413172 -296.595367) (xy 423.380537 -296.55853) (xy 423.354234 -296.516934) (xy 423.334943 -296.471658)
			(xy 423.323166 -296.423874) (xy 423.319206 -296.37482) (xy 422.980104 -296.37482) (xy 422.979609 -296.399427)
			(xy 422.971714 -296.448004) (xy 422.95613 -296.494685) (xy 422.933259 -296.538262) (xy 422.903694 -296.577606)
			(xy 422.868201 -296.611698) (xy 422.827698 -296.639654) (xy 422.783236 -296.660752) (xy 422.735965 -296.674444)
			(xy 422.68711 -296.680376) (xy 422.637935 -296.678395) (xy 422.589716 -296.668551) (xy 422.5437 -296.651099)
			(xy 422.501079 -296.626492) (xy 422.462958 -296.595367) (xy 422.430323 -296.55853) (xy 422.40402 -296.516934)
			(xy 422.384729 -296.471658) (xy 422.372952 -296.423874) (xy 422.368992 -296.37482) (xy 422.030144 -296.37482)
			(xy 422.029649 -296.399427) (xy 422.021754 -296.448004) (xy 422.00617 -296.494685) (xy 421.983299 -296.538262)
			(xy 421.953734 -296.577606) (xy 421.918241 -296.611698) (xy 421.877738 -296.639654) (xy 421.833276 -296.660752)
			(xy 421.786005 -296.674444) (xy 421.73715 -296.680376) (xy 421.687975 -296.678395) (xy 421.639756 -296.668551)
			(xy 421.59374 -296.651099) (xy 421.551119 -296.626492) (xy 421.512998 -296.595367) (xy 421.480363 -296.55853)
			(xy 421.45406 -296.516934) (xy 421.434769 -296.471658) (xy 421.422992 -296.423874) (xy 421.419032 -296.37482)
			(xy 421.080184 -296.37482) (xy 421.079689 -296.399427) (xy 421.071794 -296.448004) (xy 421.05621 -296.494685)
			(xy 421.033339 -296.538262) (xy 421.003774 -296.577606) (xy 420.968281 -296.611698) (xy 420.927778 -296.639654)
			(xy 420.883316 -296.660752) (xy 420.836045 -296.674444) (xy 420.78719 -296.680376) (xy 420.738015 -296.678395)
			(xy 420.689796 -296.668551) (xy 420.64378 -296.651099) (xy 420.601159 -296.626492) (xy 420.563038 -296.595367)
			(xy 420.530403 -296.55853) (xy 420.5041 -296.516934) (xy 420.484809 -296.471658) (xy 420.473032 -296.423874)
			(xy 420.469072 -296.37482) (xy 420.130224 -296.37482) (xy 420.129729 -296.399427) (xy 420.121834 -296.448004)
			(xy 420.10625 -296.494685) (xy 420.083379 -296.538262) (xy 420.053814 -296.577606) (xy 420.018321 -296.611698)
			(xy 419.977818 -296.639654) (xy 419.933356 -296.660752) (xy 419.886085 -296.674444) (xy 419.83723 -296.680376)
			(xy 419.788055 -296.678395) (xy 419.739836 -296.668551) (xy 419.69382 -296.651099) (xy 419.651199 -296.626492)
			(xy 419.613078 -296.595367) (xy 419.580443 -296.55853) (xy 419.55414 -296.516934) (xy 419.534849 -296.471658)
			(xy 419.523072 -296.423874) (xy 419.519112 -296.37482) (xy 418.230304 -296.37482) (xy 418.229809 -296.399427)
			(xy 418.221914 -296.448004) (xy 418.20633 -296.494685) (xy 418.183459 -296.538262) (xy 418.153894 -296.577606)
			(xy 418.118401 -296.611698) (xy 418.077898 -296.639654) (xy 418.033436 -296.660752) (xy 417.986165 -296.674444)
			(xy 417.93731 -296.680376) (xy 417.888135 -296.678395) (xy 417.839916 -296.668551) (xy 417.7939 -296.651099)
			(xy 417.751279 -296.626492) (xy 417.713158 -296.595367) (xy 417.680523 -296.55853) (xy 417.65422 -296.516934)
			(xy 417.634929 -296.471658) (xy 417.623152 -296.423874) (xy 417.619192 -296.37482) (xy 417.28009 -296.37482)
			(xy 417.279595 -296.399427) (xy 417.2717 -296.448004) (xy 417.256116 -296.494685) (xy 417.233245 -296.538262)
			(xy 417.20368 -296.577606) (xy 417.168187 -296.611698) (xy 417.127684 -296.639654) (xy 417.083222 -296.660752)
			(xy 417.035951 -296.674444) (xy 416.987096 -296.680376) (xy 416.937921 -296.678395) (xy 416.889702 -296.668551)
			(xy 416.843686 -296.651099) (xy 416.801065 -296.626492) (xy 416.762944 -296.595367) (xy 416.730309 -296.55853)
			(xy 416.704006 -296.516934) (xy 416.684715 -296.471658) (xy 416.672938 -296.423874) (xy 416.668978 -296.37482)
			(xy 416.33013 -296.37482) (xy 416.329635 -296.399427) (xy 416.32174 -296.448004) (xy 416.306156 -296.494685)
			(xy 416.283285 -296.538262) (xy 416.25372 -296.577606) (xy 416.218227 -296.611698) (xy 416.177724 -296.639654)
			(xy 416.133262 -296.660752) (xy 416.085991 -296.674444) (xy 416.037136 -296.680376) (xy 415.987961 -296.678395)
			(xy 415.939742 -296.668551) (xy 415.893726 -296.651099) (xy 415.851105 -296.626492) (xy 415.812984 -296.595367)
			(xy 415.780349 -296.55853) (xy 415.754046 -296.516934) (xy 415.734755 -296.471658) (xy 415.722978 -296.423874)
			(xy 415.719018 -296.37482) (xy 415.38017 -296.37482) (xy 415.379675 -296.399427) (xy 415.37178 -296.448004)
			(xy 415.356196 -296.494685) (xy 415.333325 -296.538262) (xy 415.30376 -296.577606) (xy 415.268267 -296.611698)
			(xy 415.227764 -296.639654) (xy 415.183302 -296.660752) (xy 415.136031 -296.674444) (xy 415.087176 -296.680376)
			(xy 415.038001 -296.678395) (xy 414.989782 -296.668551) (xy 414.943766 -296.651099) (xy 414.901145 -296.626492)
			(xy 414.863024 -296.595367) (xy 414.830389 -296.55853) (xy 414.804086 -296.516934) (xy 414.784795 -296.471658)
			(xy 414.773018 -296.423874) (xy 414.769058 -296.37482) (xy 414.43021 -296.37482) (xy 414.429715 -296.399427)
			(xy 414.42182 -296.448004) (xy 414.406236 -296.494685) (xy 414.383365 -296.538262) (xy 414.3538 -296.577606)
			(xy 414.318307 -296.611698) (xy 414.277804 -296.639654) (xy 414.233342 -296.660752) (xy 414.186071 -296.674444)
			(xy 414.137216 -296.680376) (xy 414.088041 -296.678395) (xy 414.039822 -296.668551) (xy 413.993806 -296.651099)
			(xy 413.951185 -296.626492) (xy 413.913064 -296.595367) (xy 413.880429 -296.55853) (xy 413.854126 -296.516934)
			(xy 413.834835 -296.471658) (xy 413.823058 -296.423874) (xy 413.819098 -296.37482) (xy 413.48025 -296.37482)
			(xy 413.479755 -296.399427) (xy 413.47186 -296.448004) (xy 413.456276 -296.494685) (xy 413.433405 -296.538262)
			(xy 413.40384 -296.577606) (xy 413.368347 -296.611698) (xy 413.327844 -296.639654) (xy 413.283382 -296.660752)
			(xy 413.236111 -296.674444) (xy 413.187256 -296.680376) (xy 413.138081 -296.678395) (xy 413.089862 -296.668551)
			(xy 413.043846 -296.651099) (xy 413.001225 -296.626492) (xy 412.963104 -296.595367) (xy 412.930469 -296.55853)
			(xy 412.904166 -296.516934) (xy 412.884875 -296.471658) (xy 412.873098 -296.423874) (xy 412.869138 -296.37482)
			(xy 412.53029 -296.37482) (xy 412.529795 -296.399427) (xy 412.5219 -296.448004) (xy 412.506316 -296.494685)
			(xy 412.483445 -296.538262) (xy 412.45388 -296.577606) (xy 412.418387 -296.611698) (xy 412.377884 -296.639654)
			(xy 412.333422 -296.660752) (xy 412.286151 -296.674444) (xy 412.237296 -296.680376) (xy 412.188121 -296.678395)
			(xy 412.139902 -296.668551) (xy 412.093886 -296.651099) (xy 412.051265 -296.626492) (xy 412.013144 -296.595367)
			(xy 411.980509 -296.55853) (xy 411.954206 -296.516934) (xy 411.934915 -296.471658) (xy 411.923138 -296.423874)
			(xy 411.919178 -296.37482) (xy 411.58033 -296.37482) (xy 411.579835 -296.399427) (xy 411.57194 -296.448004)
			(xy 411.556356 -296.494685) (xy 411.533485 -296.538262) (xy 411.50392 -296.577606) (xy 411.468427 -296.611698)
			(xy 411.427924 -296.639654) (xy 411.383462 -296.660752) (xy 411.336191 -296.674444) (xy 411.287336 -296.680376)
			(xy 411.238161 -296.678395) (xy 411.189942 -296.668551) (xy 411.143926 -296.651099) (xy 411.101305 -296.626492)
			(xy 411.063184 -296.595367) (xy 411.030549 -296.55853) (xy 411.004246 -296.516934) (xy 410.984955 -296.471658)
			(xy 410.973178 -296.423874) (xy 410.969218 -296.37482) (xy 410.630116 -296.37482) (xy 410.629621 -296.399427)
			(xy 410.621726 -296.448004) (xy 410.606142 -296.494685) (xy 410.583271 -296.538262) (xy 410.553706 -296.577606)
			(xy 410.518213 -296.611698) (xy 410.47771 -296.639654) (xy 410.433248 -296.660752) (xy 410.385977 -296.674444)
			(xy 410.337122 -296.680376) (xy 410.287947 -296.678395) (xy 410.239728 -296.668551) (xy 410.193712 -296.651099)
			(xy 410.151091 -296.626492) (xy 410.11297 -296.595367) (xy 410.080335 -296.55853) (xy 410.054032 -296.516934)
			(xy 410.034741 -296.471658) (xy 410.022964 -296.423874) (xy 410.019004 -296.37482) (xy 409.680156 -296.37482)
			(xy 409.679661 -296.399427) (xy 409.671766 -296.448004) (xy 409.656182 -296.494685) (xy 409.633311 -296.538262)
			(xy 409.603746 -296.577606) (xy 409.568253 -296.611698) (xy 409.52775 -296.639654) (xy 409.483288 -296.660752)
			(xy 409.436017 -296.674444) (xy 409.387162 -296.680376) (xy 409.337987 -296.678395) (xy 409.289768 -296.668551)
			(xy 409.243752 -296.651099) (xy 409.201131 -296.626492) (xy 409.16301 -296.595367) (xy 409.130375 -296.55853)
			(xy 409.104072 -296.516934) (xy 409.084781 -296.471658) (xy 409.073004 -296.423874) (xy 409.069044 -296.37482)
			(xy 408.730196 -296.37482) (xy 408.729701 -296.399427) (xy 408.721806 -296.448004) (xy 408.706222 -296.494685)
			(xy 408.683351 -296.538262) (xy 408.653786 -296.577606) (xy 408.618293 -296.611698) (xy 408.57779 -296.639654)
			(xy 408.533328 -296.660752) (xy 408.486057 -296.674444) (xy 408.437202 -296.680376) (xy 408.388027 -296.678395)
			(xy 408.339808 -296.668551) (xy 408.293792 -296.651099) (xy 408.251171 -296.626492) (xy 408.21305 -296.595367)
			(xy 408.180415 -296.55853) (xy 408.154112 -296.516934) (xy 408.134821 -296.471658) (xy 408.123044 -296.423874)
			(xy 408.119084 -296.37482) (xy 406.830276 -296.37482) (xy 406.829781 -296.399427) (xy 406.821886 -296.448004)
			(xy 406.806302 -296.494685) (xy 406.783431 -296.538262) (xy 406.753866 -296.577606) (xy 406.718373 -296.611698)
			(xy 406.67787 -296.639654) (xy 406.633408 -296.660752) (xy 406.586137 -296.674444) (xy 406.537282 -296.680376)
			(xy 406.488107 -296.678395) (xy 406.439888 -296.668551) (xy 406.393872 -296.651099) (xy 406.351251 -296.626492)
			(xy 406.31313 -296.595367) (xy 406.280495 -296.55853) (xy 406.254192 -296.516934) (xy 406.234901 -296.471658)
			(xy 406.223124 -296.423874) (xy 406.219164 -296.37482) (xy 405.880316 -296.37482) (xy 405.879821 -296.399427)
			(xy 405.871926 -296.448004) (xy 405.856342 -296.494685) (xy 405.833471 -296.538262) (xy 405.803906 -296.577606)
			(xy 405.768413 -296.611698) (xy 405.72791 -296.639654) (xy 405.683448 -296.660752) (xy 405.636177 -296.674444)
			(xy 405.587322 -296.680376) (xy 405.538147 -296.678395) (xy 405.489928 -296.668551) (xy 405.443912 -296.651099)
			(xy 405.401291 -296.626492) (xy 405.36317 -296.595367) (xy 405.330535 -296.55853) (xy 405.304232 -296.516934)
			(xy 405.284941 -296.471658) (xy 405.273164 -296.423874) (xy 405.269204 -296.37482) (xy 404.930356 -296.37482)
			(xy 404.929861 -296.399427) (xy 404.921966 -296.448004) (xy 404.906382 -296.494685) (xy 404.883511 -296.538262)
			(xy 404.853946 -296.577606) (xy 404.818453 -296.611698) (xy 404.77795 -296.639654) (xy 404.733488 -296.660752)
			(xy 404.686217 -296.674444) (xy 404.637362 -296.680376) (xy 404.588187 -296.678395) (xy 404.539968 -296.668551)
			(xy 404.493952 -296.651099) (xy 404.451331 -296.626492) (xy 404.41321 -296.595367) (xy 404.380575 -296.55853)
			(xy 404.354272 -296.516934) (xy 404.334981 -296.471658) (xy 404.323204 -296.423874) (xy 404.319244 -296.37482)
			(xy 403.980142 -296.37482) (xy 403.979647 -296.399427) (xy 403.971752 -296.448004) (xy 403.956168 -296.494685)
			(xy 403.933297 -296.538262) (xy 403.903732 -296.577606) (xy 403.868239 -296.611698) (xy 403.827736 -296.639654)
			(xy 403.783274 -296.660752) (xy 403.736003 -296.674444) (xy 403.687148 -296.680376) (xy 403.637973 -296.678395)
			(xy 403.589754 -296.668551) (xy 403.543738 -296.651099) (xy 403.501117 -296.626492) (xy 403.462996 -296.595367)
			(xy 403.430361 -296.55853) (xy 403.404058 -296.516934) (xy 403.384767 -296.471658) (xy 403.37299 -296.423874)
			(xy 403.36903 -296.37482) (xy 403.030182 -296.37482) (xy 403.029687 -296.399427) (xy 403.021792 -296.448004)
			(xy 403.006208 -296.494685) (xy 402.983337 -296.538262) (xy 402.953772 -296.577606) (xy 402.918279 -296.611698)
			(xy 402.877776 -296.639654) (xy 402.833314 -296.660752) (xy 402.786043 -296.674444) (xy 402.737188 -296.680376)
			(xy 402.688013 -296.678395) (xy 402.639794 -296.668551) (xy 402.593778 -296.651099) (xy 402.551157 -296.626492)
			(xy 402.513036 -296.595367) (xy 402.480401 -296.55853) (xy 402.454098 -296.516934) (xy 402.434807 -296.471658)
			(xy 402.42303 -296.423874) (xy 402.41907 -296.37482) (xy 402.080222 -296.37482) (xy 402.079727 -296.399427)
			(xy 402.071832 -296.448004) (xy 402.056248 -296.494685) (xy 402.033377 -296.538262) (xy 402.003812 -296.577606)
			(xy 401.968319 -296.611698) (xy 401.927816 -296.639654) (xy 401.883354 -296.660752) (xy 401.836083 -296.674444)
			(xy 401.787228 -296.680376) (xy 401.738053 -296.678395) (xy 401.689834 -296.668551) (xy 401.643818 -296.651099)
			(xy 401.601197 -296.626492) (xy 401.563076 -296.595367) (xy 401.530441 -296.55853) (xy 401.504138 -296.516934)
			(xy 401.484847 -296.471658) (xy 401.47307 -296.423874) (xy 401.46911 -296.37482) (xy 401.130262 -296.37482)
			(xy 401.129767 -296.399427) (xy 401.121872 -296.448004) (xy 401.106288 -296.494685) (xy 401.083417 -296.538262)
			(xy 401.053852 -296.577606) (xy 401.018359 -296.611698) (xy 400.977856 -296.639654) (xy 400.933394 -296.660752)
			(xy 400.886123 -296.674444) (xy 400.837268 -296.680376) (xy 400.788093 -296.678395) (xy 400.739874 -296.668551)
			(xy 400.693858 -296.651099) (xy 400.651237 -296.626492) (xy 400.613116 -296.595367) (xy 400.580481 -296.55853)
			(xy 400.554178 -296.516934) (xy 400.534887 -296.471658) (xy 400.52311 -296.423874) (xy 400.51915 -296.37482)
			(xy 400.180302 -296.37482) (xy 400.179807 -296.399427) (xy 400.171912 -296.448004) (xy 400.156328 -296.494685)
			(xy 400.133457 -296.538262) (xy 400.103892 -296.577606) (xy 400.068399 -296.611698) (xy 400.027896 -296.639654)
			(xy 399.983434 -296.660752) (xy 399.936163 -296.674444) (xy 399.887308 -296.680376) (xy 399.838133 -296.678395)
			(xy 399.789914 -296.668551) (xy 399.743898 -296.651099) (xy 399.701277 -296.626492) (xy 399.663156 -296.595367)
			(xy 399.630521 -296.55853) (xy 399.604218 -296.516934) (xy 399.584927 -296.471658) (xy 399.57315 -296.423874)
			(xy 399.56919 -296.37482) (xy 399.230342 -296.37482) (xy 399.229847 -296.399427) (xy 399.221952 -296.448004)
			(xy 399.206368 -296.494685) (xy 399.183497 -296.538262) (xy 399.153932 -296.577606) (xy 399.118439 -296.611698)
			(xy 399.077936 -296.639654) (xy 399.033474 -296.660752) (xy 398.986203 -296.674444) (xy 398.937348 -296.680376)
			(xy 398.888173 -296.678395) (xy 398.839954 -296.668551) (xy 398.793938 -296.651099) (xy 398.751317 -296.626492)
			(xy 398.713196 -296.595367) (xy 398.680561 -296.55853) (xy 398.654258 -296.516934) (xy 398.634967 -296.471658)
			(xy 398.62319 -296.423874) (xy 398.61923 -296.37482) (xy 398.280128 -296.37482) (xy 398.279633 -296.399427)
			(xy 398.271738 -296.448004) (xy 398.256154 -296.494685) (xy 398.233283 -296.538262) (xy 398.203718 -296.577606)
			(xy 398.168225 -296.611698) (xy 398.127722 -296.639654) (xy 398.08326 -296.660752) (xy 398.035989 -296.674444)
			(xy 397.987134 -296.680376) (xy 397.937959 -296.678395) (xy 397.88974 -296.668551) (xy 397.843724 -296.651099)
			(xy 397.801103 -296.626492) (xy 397.762982 -296.595367) (xy 397.730347 -296.55853) (xy 397.704044 -296.516934)
			(xy 397.684753 -296.471658) (xy 397.672976 -296.423874) (xy 397.669016 -296.37482) (xy 397.355127 -296.37482)
			(xy 397.355127 -296.401163) (xy 397.346763 -296.453215) (xy 397.330247 -296.503282) (xy 397.305999 -296.550095)
			(xy 397.274631 -296.592468) (xy 397.236938 -296.629328) (xy 397.193875 -296.659742) (xy 397.146533 -296.68294)
			(xy 397.09611 -296.698333) (xy 397.070072 -296.70248) (xy 397.066008 -296.702988) (xy 397.054578 -296.706544)
			(xy 397.05026 -296.707814) (xy 397.02613 -296.71899) (xy 397.019526 -296.726102) (xy 397.004794 -296.741596)
			(xy 396.996666 -296.752772) (xy 396.993971 -296.758303) (xy 396.991016 -296.770244) (xy 396.990824 -296.776394)
			(xy 396.990824 -296.923206) (xy 396.990998 -296.929358) (xy 396.993959 -296.9413) (xy 396.996666 -296.946828)
			(xy 397.004794 -296.958004) (xy 397.019526 -296.973498) (xy 397.02613 -296.98061) (xy 397.05026 -296.991786)
			(xy 397.054578 -296.993056) (xy 397.066008 -296.996612) (xy 397.070072 -296.99712) (xy 397.096118 -297.001228)
			(xy 397.146547 -297.016623) (xy 397.193895 -297.039824) (xy 397.236963 -297.070241) (xy 397.27466 -297.107106)
			(xy 397.306032 -297.149484) (xy 397.330284 -297.196303) (xy 397.346801 -297.246375) (xy 397.355166 -297.298434)
			(xy 397.355166 -297.32478) (xy 397.669016 -297.32478) (xy 397.672976 -297.275726) (xy 397.684753 -297.227942)
			(xy 397.704044 -297.182666) (xy 397.730347 -297.14107) (xy 397.762982 -297.104233) (xy 397.801103 -297.073108)
			(xy 397.843724 -297.048501) (xy 397.88974 -297.031049) (xy 397.937959 -297.021205) (xy 397.987134 -297.019224)
			(xy 398.035989 -297.025156) (xy 398.08326 -297.038848) (xy 398.127722 -297.059946) (xy 398.168225 -297.087902)
			(xy 398.203718 -297.121994) (xy 398.233283 -297.161338) (xy 398.256154 -297.204915) (xy 398.271738 -297.251596)
			(xy 398.279633 -297.300173) (xy 398.280128 -297.32478) (xy 398.61923 -297.32478) (xy 398.62319 -297.275726)
			(xy 398.634967 -297.227942) (xy 398.654258 -297.182666) (xy 398.680561 -297.14107) (xy 398.713196 -297.104233)
			(xy 398.751317 -297.073108) (xy 398.793938 -297.048501) (xy 398.839954 -297.031049) (xy 398.888173 -297.021205)
			(xy 398.937348 -297.019224) (xy 398.986203 -297.025156) (xy 399.033474 -297.038848) (xy 399.077936 -297.059946)
			(xy 399.118439 -297.087902) (xy 399.153932 -297.121994) (xy 399.183497 -297.161338) (xy 399.206368 -297.204915)
			(xy 399.221952 -297.251596) (xy 399.229847 -297.300173) (xy 399.230342 -297.32478) (xy 399.56919 -297.32478)
			(xy 399.57315 -297.275726) (xy 399.584927 -297.227942) (xy 399.604218 -297.182666) (xy 399.630521 -297.14107)
			(xy 399.663156 -297.104233) (xy 399.701277 -297.073108) (xy 399.743898 -297.048501) (xy 399.789914 -297.031049)
			(xy 399.838133 -297.021205) (xy 399.887308 -297.019224) (xy 399.936163 -297.025156) (xy 399.983434 -297.038848)
			(xy 400.027896 -297.059946) (xy 400.068399 -297.087902) (xy 400.103892 -297.121994) (xy 400.133457 -297.161338)
			(xy 400.156328 -297.204915) (xy 400.171912 -297.251596) (xy 400.179807 -297.300173) (xy 400.180302 -297.32478)
			(xy 400.51915 -297.32478) (xy 400.52311 -297.275726) (xy 400.534887 -297.227942) (xy 400.554178 -297.182666)
			(xy 400.580481 -297.14107) (xy 400.613116 -297.104233) (xy 400.651237 -297.073108) (xy 400.693858 -297.048501)
			(xy 400.739874 -297.031049) (xy 400.788093 -297.021205) (xy 400.837268 -297.019224) (xy 400.886123 -297.025156)
			(xy 400.933394 -297.038848) (xy 400.977856 -297.059946) (xy 401.018359 -297.087902) (xy 401.053852 -297.121994)
			(xy 401.083417 -297.161338) (xy 401.106288 -297.204915) (xy 401.121872 -297.251596) (xy 401.129767 -297.300173)
			(xy 401.130262 -297.32478) (xy 401.46911 -297.32478) (xy 401.47307 -297.275726) (xy 401.484847 -297.227942)
			(xy 401.504138 -297.182666) (xy 401.530441 -297.14107) (xy 401.563076 -297.104233) (xy 401.601197 -297.073108)
			(xy 401.643818 -297.048501) (xy 401.689834 -297.031049) (xy 401.738053 -297.021205) (xy 401.787228 -297.019224)
			(xy 401.836083 -297.025156) (xy 401.883354 -297.038848) (xy 401.927816 -297.059946) (xy 401.968319 -297.087902)
			(xy 402.003812 -297.121994) (xy 402.033377 -297.161338) (xy 402.056248 -297.204915) (xy 402.071832 -297.251596)
			(xy 402.079727 -297.300173) (xy 402.080222 -297.32478) (xy 402.41907 -297.32478) (xy 402.42303 -297.275726)
			(xy 402.434807 -297.227942) (xy 402.454098 -297.182666) (xy 402.480401 -297.14107) (xy 402.513036 -297.104233)
			(xy 402.551157 -297.073108) (xy 402.593778 -297.048501) (xy 402.639794 -297.031049) (xy 402.688013 -297.021205)
			(xy 402.737188 -297.019224) (xy 402.786043 -297.025156) (xy 402.833314 -297.038848) (xy 402.877776 -297.059946)
			(xy 402.918279 -297.087902) (xy 402.953772 -297.121994) (xy 402.983337 -297.161338) (xy 403.006208 -297.204915)
			(xy 403.021792 -297.251596) (xy 403.029687 -297.300173) (xy 403.030182 -297.32478) (xy 403.36903 -297.32478)
			(xy 403.37299 -297.275726) (xy 403.384767 -297.227942) (xy 403.404058 -297.182666) (xy 403.430361 -297.14107)
			(xy 403.462996 -297.104233) (xy 403.501117 -297.073108) (xy 403.543738 -297.048501) (xy 403.589754 -297.031049)
			(xy 403.637973 -297.021205) (xy 403.687148 -297.019224) (xy 403.736003 -297.025156) (xy 403.783274 -297.038848)
			(xy 403.827736 -297.059946) (xy 403.868239 -297.087902) (xy 403.903732 -297.121994) (xy 403.933297 -297.161338)
			(xy 403.956168 -297.204915) (xy 403.971752 -297.251596) (xy 403.979647 -297.300173) (xy 403.980142 -297.32478)
			(xy 404.31899 -297.32478) (xy 404.32295 -297.275726) (xy 404.334727 -297.227942) (xy 404.354018 -297.182666)
			(xy 404.380321 -297.14107) (xy 404.412956 -297.104233) (xy 404.451077 -297.073108) (xy 404.493698 -297.048501)
			(xy 404.539714 -297.031049) (xy 404.587933 -297.021205) (xy 404.637108 -297.019224) (xy 404.685963 -297.025156)
			(xy 404.733234 -297.038848) (xy 404.777696 -297.059946) (xy 404.818199 -297.087902) (xy 404.853692 -297.121994)
			(xy 404.883257 -297.161338) (xy 404.906128 -297.204915) (xy 404.921712 -297.251596) (xy 404.929607 -297.300173)
			(xy 404.930102 -297.32478) (xy 405.269204 -297.32478) (xy 405.273164 -297.275726) (xy 405.284941 -297.227942)
			(xy 405.304232 -297.182666) (xy 405.330535 -297.14107) (xy 405.36317 -297.104233) (xy 405.401291 -297.073108)
			(xy 405.443912 -297.048501) (xy 405.489928 -297.031049) (xy 405.538147 -297.021205) (xy 405.587322 -297.019224)
			(xy 405.636177 -297.025156) (xy 405.683448 -297.038848) (xy 405.72791 -297.059946) (xy 405.768413 -297.087902)
			(xy 405.803906 -297.121994) (xy 405.833471 -297.161338) (xy 405.856342 -297.204915) (xy 405.871926 -297.251596)
			(xy 405.879821 -297.300173) (xy 405.880316 -297.32478) (xy 406.219164 -297.32478) (xy 406.223124 -297.275726)
			(xy 406.234901 -297.227942) (xy 406.254192 -297.182666) (xy 406.280495 -297.14107) (xy 406.31313 -297.104233)
			(xy 406.351251 -297.073108) (xy 406.393872 -297.048501) (xy 406.439888 -297.031049) (xy 406.488107 -297.021205)
			(xy 406.537282 -297.019224) (xy 406.586137 -297.025156) (xy 406.633408 -297.038848) (xy 406.67787 -297.059946)
			(xy 406.718373 -297.087902) (xy 406.753866 -297.121994) (xy 406.783431 -297.161338) (xy 406.806302 -297.204915)
			(xy 406.821886 -297.251596) (xy 406.829781 -297.300173) (xy 406.830276 -297.32478) (xy 408.119084 -297.32478)
			(xy 408.123044 -297.275726) (xy 408.134821 -297.227942) (xy 408.154112 -297.182666) (xy 408.180415 -297.14107)
			(xy 408.21305 -297.104233) (xy 408.251171 -297.073108) (xy 408.293792 -297.048501) (xy 408.339808 -297.031049)
			(xy 408.388027 -297.021205) (xy 408.437202 -297.019224) (xy 408.486057 -297.025156) (xy 408.533328 -297.038848)
			(xy 408.57779 -297.059946) (xy 408.618293 -297.087902) (xy 408.653786 -297.121994) (xy 408.683351 -297.161338)
			(xy 408.706222 -297.204915) (xy 408.721806 -297.251596) (xy 408.729701 -297.300173) (xy 408.730196 -297.32478)
			(xy 409.069044 -297.32478) (xy 409.073004 -297.275726) (xy 409.084781 -297.227942) (xy 409.104072 -297.182666)
			(xy 409.130375 -297.14107) (xy 409.16301 -297.104233) (xy 409.201131 -297.073108) (xy 409.243752 -297.048501)
			(xy 409.289768 -297.031049) (xy 409.337987 -297.021205) (xy 409.387162 -297.019224) (xy 409.436017 -297.025156)
			(xy 409.483288 -297.038848) (xy 409.52775 -297.059946) (xy 409.568253 -297.087902) (xy 409.603746 -297.121994)
			(xy 409.633311 -297.161338) (xy 409.656182 -297.204915) (xy 409.671766 -297.251596) (xy 409.679661 -297.300173)
			(xy 409.680156 -297.32478) (xy 410.019004 -297.32478) (xy 410.022964 -297.275726) (xy 410.034741 -297.227942)
			(xy 410.054032 -297.182666) (xy 410.080335 -297.14107) (xy 410.11297 -297.104233) (xy 410.151091 -297.073108)
			(xy 410.193712 -297.048501) (xy 410.239728 -297.031049) (xy 410.287947 -297.021205) (xy 410.337122 -297.019224)
			(xy 410.385977 -297.025156) (xy 410.433248 -297.038848) (xy 410.47771 -297.059946) (xy 410.518213 -297.087902)
			(xy 410.553706 -297.121994) (xy 410.583271 -297.161338) (xy 410.606142 -297.204915) (xy 410.621726 -297.251596)
			(xy 410.629621 -297.300173) (xy 410.630116 -297.32478) (xy 410.969218 -297.32478) (xy 410.973178 -297.275726)
			(xy 410.984955 -297.227942) (xy 411.004246 -297.182666) (xy 411.030549 -297.14107) (xy 411.063184 -297.104233)
			(xy 411.101305 -297.073108) (xy 411.143926 -297.048501) (xy 411.189942 -297.031049) (xy 411.238161 -297.021205)
			(xy 411.287336 -297.019224) (xy 411.336191 -297.025156) (xy 411.383462 -297.038848) (xy 411.427924 -297.059946)
			(xy 411.468427 -297.087902) (xy 411.50392 -297.121994) (xy 411.533485 -297.161338) (xy 411.556356 -297.204915)
			(xy 411.57194 -297.251596) (xy 411.579835 -297.300173) (xy 411.58033 -297.32478) (xy 411.919178 -297.32478)
			(xy 411.923138 -297.275726) (xy 411.934915 -297.227942) (xy 411.954206 -297.182666) (xy 411.980509 -297.14107)
			(xy 412.013144 -297.104233) (xy 412.051265 -297.073108) (xy 412.093886 -297.048501) (xy 412.139902 -297.031049)
			(xy 412.188121 -297.021205) (xy 412.237296 -297.019224) (xy 412.286151 -297.025156) (xy 412.333422 -297.038848)
			(xy 412.377884 -297.059946) (xy 412.418387 -297.087902) (xy 412.45388 -297.121994) (xy 412.483445 -297.161338)
			(xy 412.506316 -297.204915) (xy 412.5219 -297.251596) (xy 412.529795 -297.300173) (xy 412.53029 -297.32478)
			(xy 412.869138 -297.32478) (xy 412.873098 -297.275726) (xy 412.884875 -297.227942) (xy 412.904166 -297.182666)
			(xy 412.930469 -297.14107) (xy 412.963104 -297.104233) (xy 413.001225 -297.073108) (xy 413.043846 -297.048501)
			(xy 413.089862 -297.031049) (xy 413.138081 -297.021205) (xy 413.187256 -297.019224) (xy 413.236111 -297.025156)
			(xy 413.283382 -297.038848) (xy 413.327844 -297.059946) (xy 413.368347 -297.087902) (xy 413.40384 -297.121994)
			(xy 413.433405 -297.161338) (xy 413.456276 -297.204915) (xy 413.47186 -297.251596) (xy 413.479755 -297.300173)
			(xy 413.48025 -297.32478) (xy 413.819098 -297.32478) (xy 413.823058 -297.275726) (xy 413.834835 -297.227942)
			(xy 413.854126 -297.182666) (xy 413.880429 -297.14107) (xy 413.913064 -297.104233) (xy 413.951185 -297.073108)
			(xy 413.993806 -297.048501) (xy 414.039822 -297.031049) (xy 414.088041 -297.021205) (xy 414.137216 -297.019224)
			(xy 414.186071 -297.025156) (xy 414.233342 -297.038848) (xy 414.277804 -297.059946) (xy 414.318307 -297.087902)
			(xy 414.3538 -297.121994) (xy 414.383365 -297.161338) (xy 414.406236 -297.204915) (xy 414.42182 -297.251596)
			(xy 414.429715 -297.300173) (xy 414.43021 -297.32478) (xy 414.769058 -297.32478) (xy 414.773018 -297.275726)
			(xy 414.784795 -297.227942) (xy 414.804086 -297.182666) (xy 414.830389 -297.14107) (xy 414.863024 -297.104233)
			(xy 414.901145 -297.073108) (xy 414.943766 -297.048501) (xy 414.989782 -297.031049) (xy 415.038001 -297.021205)
			(xy 415.087176 -297.019224) (xy 415.136031 -297.025156) (xy 415.183302 -297.038848) (xy 415.227764 -297.059946)
			(xy 415.268267 -297.087902) (xy 415.30376 -297.121994) (xy 415.333325 -297.161338) (xy 415.356196 -297.204915)
			(xy 415.37178 -297.251596) (xy 415.379675 -297.300173) (xy 415.38017 -297.32478) (xy 415.719018 -297.32478)
			(xy 415.722978 -297.275726) (xy 415.734755 -297.227942) (xy 415.754046 -297.182666) (xy 415.780349 -297.14107)
			(xy 415.812984 -297.104233) (xy 415.851105 -297.073108) (xy 415.893726 -297.048501) (xy 415.939742 -297.031049)
			(xy 415.987961 -297.021205) (xy 416.037136 -297.019224) (xy 416.085991 -297.025156) (xy 416.133262 -297.038848)
			(xy 416.177724 -297.059946) (xy 416.218227 -297.087902) (xy 416.25372 -297.121994) (xy 416.283285 -297.161338)
			(xy 416.306156 -297.204915) (xy 416.32174 -297.251596) (xy 416.329635 -297.300173) (xy 416.33013 -297.32478)
			(xy 416.668978 -297.32478) (xy 416.672938 -297.275726) (xy 416.684715 -297.227942) (xy 416.704006 -297.182666)
			(xy 416.730309 -297.14107) (xy 416.762944 -297.104233) (xy 416.801065 -297.073108) (xy 416.843686 -297.048501)
			(xy 416.889702 -297.031049) (xy 416.937921 -297.021205) (xy 416.987096 -297.019224) (xy 417.035951 -297.025156)
			(xy 417.083222 -297.038848) (xy 417.127684 -297.059946) (xy 417.168187 -297.087902) (xy 417.20368 -297.121994)
			(xy 417.233245 -297.161338) (xy 417.256116 -297.204915) (xy 417.2717 -297.251596) (xy 417.279595 -297.300173)
			(xy 417.28009 -297.32478) (xy 417.619192 -297.32478) (xy 417.623152 -297.275726) (xy 417.634929 -297.227942)
			(xy 417.65422 -297.182666) (xy 417.680523 -297.14107) (xy 417.713158 -297.104233) (xy 417.751279 -297.073108)
			(xy 417.7939 -297.048501) (xy 417.839916 -297.031049) (xy 417.888135 -297.021205) (xy 417.93731 -297.019224)
			(xy 417.986165 -297.025156) (xy 418.033436 -297.038848) (xy 418.077898 -297.059946) (xy 418.118401 -297.087902)
			(xy 418.153894 -297.121994) (xy 418.183459 -297.161338) (xy 418.20633 -297.204915) (xy 418.221914 -297.251596)
			(xy 418.229809 -297.300173) (xy 418.230304 -297.32478) (xy 419.519112 -297.32478) (xy 419.523072 -297.275726)
			(xy 419.534849 -297.227942) (xy 419.55414 -297.182666) (xy 419.580443 -297.14107) (xy 419.613078 -297.104233)
			(xy 419.651199 -297.073108) (xy 419.69382 -297.048501) (xy 419.739836 -297.031049) (xy 419.788055 -297.021205)
			(xy 419.83723 -297.019224) (xy 419.886085 -297.025156) (xy 419.933356 -297.038848) (xy 419.977818 -297.059946)
			(xy 420.018321 -297.087902) (xy 420.053814 -297.121994) (xy 420.083379 -297.161338) (xy 420.10625 -297.204915)
			(xy 420.121834 -297.251596) (xy 420.129729 -297.300173) (xy 420.130224 -297.32478) (xy 420.469072 -297.32478)
			(xy 420.473032 -297.275726) (xy 420.484809 -297.227942) (xy 420.5041 -297.182666) (xy 420.530403 -297.14107)
			(xy 420.563038 -297.104233) (xy 420.601159 -297.073108) (xy 420.64378 -297.048501) (xy 420.689796 -297.031049)
			(xy 420.738015 -297.021205) (xy 420.78719 -297.019224) (xy 420.836045 -297.025156) (xy 420.883316 -297.038848)
			(xy 420.927778 -297.059946) (xy 420.968281 -297.087902) (xy 421.003774 -297.121994) (xy 421.033339 -297.161338)
			(xy 421.05621 -297.204915) (xy 421.071794 -297.251596) (xy 421.079689 -297.300173) (xy 421.080184 -297.32478)
			(xy 421.419032 -297.32478) (xy 421.422992 -297.275726) (xy 421.434769 -297.227942) (xy 421.45406 -297.182666)
			(xy 421.480363 -297.14107) (xy 421.512998 -297.104233) (xy 421.551119 -297.073108) (xy 421.59374 -297.048501)
			(xy 421.639756 -297.031049) (xy 421.687975 -297.021205) (xy 421.73715 -297.019224) (xy 421.786005 -297.025156)
			(xy 421.833276 -297.038848) (xy 421.877738 -297.059946) (xy 421.918241 -297.087902) (xy 421.953734 -297.121994)
			(xy 421.983299 -297.161338) (xy 422.00617 -297.204915) (xy 422.021754 -297.251596) (xy 422.029649 -297.300173)
			(xy 422.030144 -297.32478) (xy 422.369246 -297.32478) (xy 422.373206 -297.275726) (xy 422.384983 -297.227942)
			(xy 422.404274 -297.182666) (xy 422.430577 -297.14107) (xy 422.463212 -297.104233) (xy 422.501333 -297.073108)
			(xy 422.543954 -297.048501) (xy 422.58997 -297.031049) (xy 422.638189 -297.021205) (xy 422.687364 -297.019224)
			(xy 422.736219 -297.025156) (xy 422.78349 -297.038848) (xy 422.827952 -297.059946) (xy 422.868455 -297.087902)
			(xy 422.903948 -297.121994) (xy 422.933513 -297.161338) (xy 422.956384 -297.204915) (xy 422.971968 -297.251596)
			(xy 422.979863 -297.300173) (xy 422.980358 -297.32478) (xy 423.319206 -297.32478) (xy 423.323166 -297.275726)
			(xy 423.334943 -297.227942) (xy 423.354234 -297.182666) (xy 423.380537 -297.14107) (xy 423.413172 -297.104233)
			(xy 423.451293 -297.073108) (xy 423.493914 -297.048501) (xy 423.53993 -297.031049) (xy 423.588149 -297.021205)
			(xy 423.637324 -297.019224) (xy 423.686179 -297.025156) (xy 423.73345 -297.038848) (xy 423.777912 -297.059946)
			(xy 423.818415 -297.087902) (xy 423.853908 -297.121994) (xy 423.883473 -297.161338) (xy 423.906344 -297.204915)
			(xy 423.921928 -297.251596) (xy 423.929823 -297.300173) (xy 423.930318 -297.32478) (xy 424.269166 -297.32478)
			(xy 424.273126 -297.275726) (xy 424.284903 -297.227942) (xy 424.304194 -297.182666) (xy 424.330497 -297.14107)
			(xy 424.363132 -297.104233) (xy 424.401253 -297.073108) (xy 424.443874 -297.048501) (xy 424.48989 -297.031049)
			(xy 424.538109 -297.021205) (xy 424.587284 -297.019224) (xy 424.636139 -297.025156) (xy 424.68341 -297.038848)
			(xy 424.727872 -297.059946) (xy 424.768375 -297.087902) (xy 424.803868 -297.121994) (xy 424.833433 -297.161338)
			(xy 424.856304 -297.204915) (xy 424.871888 -297.251596) (xy 424.879783 -297.300173) (xy 424.880278 -297.32478)
			(xy 425.219126 -297.32478) (xy 425.223086 -297.275726) (xy 425.234863 -297.227942) (xy 425.254154 -297.182666)
			(xy 425.280457 -297.14107) (xy 425.313092 -297.104233) (xy 425.351213 -297.073108) (xy 425.393834 -297.048501)
			(xy 425.43985 -297.031049) (xy 425.488069 -297.021205) (xy 425.537244 -297.019224) (xy 425.586099 -297.025156)
			(xy 425.63337 -297.038848) (xy 425.677832 -297.059946) (xy 425.718335 -297.087902) (xy 425.753828 -297.121994)
			(xy 425.783393 -297.161338) (xy 425.806264 -297.204915) (xy 425.821848 -297.251596) (xy 425.829743 -297.300173)
			(xy 425.830238 -297.32478) (xy 426.169086 -297.32478) (xy 426.173046 -297.275726) (xy 426.184823 -297.227942)
			(xy 426.204114 -297.182666) (xy 426.230417 -297.14107) (xy 426.263052 -297.104233) (xy 426.301173 -297.073108)
			(xy 426.343794 -297.048501) (xy 426.38981 -297.031049) (xy 426.438029 -297.021205) (xy 426.487204 -297.019224)
			(xy 426.536059 -297.025156) (xy 426.58333 -297.038848) (xy 426.627792 -297.059946) (xy 426.668295 -297.087902)
			(xy 426.703788 -297.121994) (xy 426.733353 -297.161338) (xy 426.756224 -297.204915) (xy 426.771808 -297.251596)
			(xy 426.779703 -297.300173) (xy 426.780198 -297.32478) (xy 427.119046 -297.32478) (xy 427.123006 -297.275726)
			(xy 427.134783 -297.227942) (xy 427.154074 -297.182666) (xy 427.180377 -297.14107) (xy 427.213012 -297.104233)
			(xy 427.251133 -297.073108) (xy 427.293754 -297.048501) (xy 427.33977 -297.031049) (xy 427.387989 -297.021205)
			(xy 427.437164 -297.019224) (xy 427.486019 -297.025156) (xy 427.53329 -297.038848) (xy 427.577752 -297.059946)
			(xy 427.618255 -297.087902) (xy 427.653748 -297.121994) (xy 427.683313 -297.161338) (xy 427.706184 -297.204915)
			(xy 427.721768 -297.251596) (xy 427.729663 -297.300173) (xy 427.730158 -297.32478) (xy 428.069006 -297.32478)
			(xy 428.072966 -297.275726) (xy 428.084743 -297.227942) (xy 428.104034 -297.182666) (xy 428.130337 -297.14107)
			(xy 428.162972 -297.104233) (xy 428.201093 -297.073108) (xy 428.243714 -297.048501) (xy 428.28973 -297.031049)
			(xy 428.337949 -297.021205) (xy 428.387124 -297.019224) (xy 428.435979 -297.025156) (xy 428.48325 -297.038848)
			(xy 428.527712 -297.059946) (xy 428.568215 -297.087902) (xy 428.603708 -297.121994) (xy 428.633273 -297.161338)
			(xy 428.656144 -297.204915) (xy 428.671728 -297.251596) (xy 428.679623 -297.300173) (xy 428.680118 -297.32478)
			(xy 429.01922 -297.32478) (xy 429.02318 -297.275726) (xy 429.034957 -297.227942) (xy 429.054248 -297.182666)
			(xy 429.080551 -297.14107) (xy 429.113186 -297.104233) (xy 429.151307 -297.073108) (xy 429.193928 -297.048501)
			(xy 429.239944 -297.031049) (xy 429.288163 -297.021205) (xy 429.337338 -297.019224) (xy 429.386193 -297.025156)
			(xy 429.433464 -297.038848) (xy 429.477926 -297.059946) (xy 429.518429 -297.087902) (xy 429.553922 -297.121994)
			(xy 429.583487 -297.161338) (xy 429.606358 -297.204915) (xy 429.621942 -297.251596) (xy 429.629837 -297.300173)
			(xy 429.630332 -297.32478) (xy 429.96918 -297.32478) (xy 429.97314 -297.275726) (xy 429.984917 -297.227942)
			(xy 430.004208 -297.182666) (xy 430.030511 -297.14107) (xy 430.063146 -297.104233) (xy 430.101267 -297.073108)
			(xy 430.143888 -297.048501) (xy 430.189904 -297.031049) (xy 430.238123 -297.021205) (xy 430.287298 -297.019224)
			(xy 430.336153 -297.025156) (xy 430.383424 -297.038848) (xy 430.427886 -297.059946) (xy 430.468389 -297.087902)
			(xy 430.503882 -297.121994) (xy 430.533447 -297.161338) (xy 430.556318 -297.204915) (xy 430.571902 -297.251596)
			(xy 430.579797 -297.300173) (xy 430.580292 -297.32478) (xy 430.91914 -297.32478) (xy 430.9231 -297.275726)
			(xy 430.934877 -297.227942) (xy 430.954168 -297.182666) (xy 430.980471 -297.14107) (xy 431.013106 -297.104233)
			(xy 431.051227 -297.073108) (xy 431.093848 -297.048501) (xy 431.139864 -297.031049) (xy 431.188083 -297.021205)
			(xy 431.237258 -297.019224) (xy 431.286113 -297.025156) (xy 431.333384 -297.038848) (xy 431.377846 -297.059946)
			(xy 431.418349 -297.087902) (xy 431.453842 -297.121994) (xy 431.483407 -297.161338) (xy 431.506278 -297.204915)
			(xy 431.521862 -297.251596) (xy 431.529757 -297.300173) (xy 431.530252 -297.32478) (xy 431.529757 -297.349387)
			(xy 431.521862 -297.397964) (xy 431.506278 -297.444645) (xy 431.483407 -297.488222) (xy 431.453842 -297.527566)
			(xy 431.418349 -297.561658) (xy 431.377846 -297.589614) (xy 431.333384 -297.610712) (xy 431.286113 -297.624404)
			(xy 431.237258 -297.630336) (xy 431.188083 -297.628355) (xy 431.139864 -297.618511) (xy 431.093848 -297.601059)
			(xy 431.051227 -297.576452) (xy 431.013106 -297.545327) (xy 430.980471 -297.50849) (xy 430.954168 -297.466894)
			(xy 430.934877 -297.421618) (xy 430.9231 -297.373834) (xy 430.91914 -297.32478) (xy 430.580292 -297.32478)
			(xy 430.579797 -297.349387) (xy 430.571902 -297.397964) (xy 430.556318 -297.444645) (xy 430.533447 -297.488222)
			(xy 430.503882 -297.527566) (xy 430.468389 -297.561658) (xy 430.427886 -297.589614) (xy 430.383424 -297.610712)
			(xy 430.336153 -297.624404) (xy 430.287298 -297.630336) (xy 430.238123 -297.628355) (xy 430.189904 -297.618511)
			(xy 430.143888 -297.601059) (xy 430.101267 -297.576452) (xy 430.063146 -297.545327) (xy 430.030511 -297.50849)
			(xy 430.004208 -297.466894) (xy 429.984917 -297.421618) (xy 429.97314 -297.373834) (xy 429.96918 -297.32478)
			(xy 429.630332 -297.32478) (xy 429.629837 -297.349387) (xy 429.621942 -297.397964) (xy 429.606358 -297.444645)
			(xy 429.583487 -297.488222) (xy 429.553922 -297.527566) (xy 429.518429 -297.561658) (xy 429.477926 -297.589614)
			(xy 429.433464 -297.610712) (xy 429.386193 -297.624404) (xy 429.337338 -297.630336) (xy 429.288163 -297.628355)
			(xy 429.239944 -297.618511) (xy 429.193928 -297.601059) (xy 429.151307 -297.576452) (xy 429.113186 -297.545327)
			(xy 429.080551 -297.50849) (xy 429.054248 -297.466894) (xy 429.034957 -297.421618) (xy 429.02318 -297.373834)
			(xy 429.01922 -297.32478) (xy 428.680118 -297.32478) (xy 428.679623 -297.349387) (xy 428.671728 -297.397964)
			(xy 428.656144 -297.444645) (xy 428.633273 -297.488222) (xy 428.603708 -297.527566) (xy 428.568215 -297.561658)
			(xy 428.527712 -297.589614) (xy 428.48325 -297.610712) (xy 428.435979 -297.624404) (xy 428.387124 -297.630336)
			(xy 428.337949 -297.628355) (xy 428.28973 -297.618511) (xy 428.243714 -297.601059) (xy 428.201093 -297.576452)
			(xy 428.162972 -297.545327) (xy 428.130337 -297.50849) (xy 428.104034 -297.466894) (xy 428.084743 -297.421618)
			(xy 428.072966 -297.373834) (xy 428.069006 -297.32478) (xy 427.730158 -297.32478) (xy 427.729663 -297.349387)
			(xy 427.721768 -297.397964) (xy 427.706184 -297.444645) (xy 427.683313 -297.488222) (xy 427.653748 -297.527566)
			(xy 427.618255 -297.561658) (xy 427.577752 -297.589614) (xy 427.53329 -297.610712) (xy 427.486019 -297.624404)
			(xy 427.437164 -297.630336) (xy 427.387989 -297.628355) (xy 427.33977 -297.618511) (xy 427.293754 -297.601059)
			(xy 427.251133 -297.576452) (xy 427.213012 -297.545327) (xy 427.180377 -297.50849) (xy 427.154074 -297.466894)
			(xy 427.134783 -297.421618) (xy 427.123006 -297.373834) (xy 427.119046 -297.32478) (xy 426.780198 -297.32478)
			(xy 426.779703 -297.349387) (xy 426.771808 -297.397964) (xy 426.756224 -297.444645) (xy 426.733353 -297.488222)
			(xy 426.703788 -297.527566) (xy 426.668295 -297.561658) (xy 426.627792 -297.589614) (xy 426.58333 -297.610712)
			(xy 426.536059 -297.624404) (xy 426.487204 -297.630336) (xy 426.438029 -297.628355) (xy 426.38981 -297.618511)
			(xy 426.343794 -297.601059) (xy 426.301173 -297.576452) (xy 426.263052 -297.545327) (xy 426.230417 -297.50849)
			(xy 426.204114 -297.466894) (xy 426.184823 -297.421618) (xy 426.173046 -297.373834) (xy 426.169086 -297.32478)
			(xy 425.830238 -297.32478) (xy 425.829743 -297.349387) (xy 425.821848 -297.397964) (xy 425.806264 -297.444645)
			(xy 425.783393 -297.488222) (xy 425.753828 -297.527566) (xy 425.718335 -297.561658) (xy 425.677832 -297.589614)
			(xy 425.63337 -297.610712) (xy 425.586099 -297.624404) (xy 425.537244 -297.630336) (xy 425.488069 -297.628355)
			(xy 425.43985 -297.618511) (xy 425.393834 -297.601059) (xy 425.351213 -297.576452) (xy 425.313092 -297.545327)
			(xy 425.280457 -297.50849) (xy 425.254154 -297.466894) (xy 425.234863 -297.421618) (xy 425.223086 -297.373834)
			(xy 425.219126 -297.32478) (xy 424.880278 -297.32478) (xy 424.879783 -297.349387) (xy 424.871888 -297.397964)
			(xy 424.856304 -297.444645) (xy 424.833433 -297.488222) (xy 424.803868 -297.527566) (xy 424.768375 -297.561658)
			(xy 424.727872 -297.589614) (xy 424.68341 -297.610712) (xy 424.636139 -297.624404) (xy 424.587284 -297.630336)
			(xy 424.538109 -297.628355) (xy 424.48989 -297.618511) (xy 424.443874 -297.601059) (xy 424.401253 -297.576452)
			(xy 424.363132 -297.545327) (xy 424.330497 -297.50849) (xy 424.304194 -297.466894) (xy 424.284903 -297.421618)
			(xy 424.273126 -297.373834) (xy 424.269166 -297.32478) (xy 423.930318 -297.32478) (xy 423.929823 -297.349387)
			(xy 423.921928 -297.397964) (xy 423.906344 -297.444645) (xy 423.883473 -297.488222) (xy 423.853908 -297.527566)
			(xy 423.818415 -297.561658) (xy 423.777912 -297.589614) (xy 423.73345 -297.610712) (xy 423.686179 -297.624404)
			(xy 423.637324 -297.630336) (xy 423.588149 -297.628355) (xy 423.53993 -297.618511) (xy 423.493914 -297.601059)
			(xy 423.451293 -297.576452) (xy 423.413172 -297.545327) (xy 423.380537 -297.50849) (xy 423.354234 -297.466894)
			(xy 423.334943 -297.421618) (xy 423.323166 -297.373834) (xy 423.319206 -297.32478) (xy 422.980358 -297.32478)
			(xy 422.979863 -297.349387) (xy 422.971968 -297.397964) (xy 422.956384 -297.444645) (xy 422.933513 -297.488222)
			(xy 422.903948 -297.527566) (xy 422.868455 -297.561658) (xy 422.827952 -297.589614) (xy 422.78349 -297.610712)
			(xy 422.736219 -297.624404) (xy 422.687364 -297.630336) (xy 422.638189 -297.628355) (xy 422.58997 -297.618511)
			(xy 422.543954 -297.601059) (xy 422.501333 -297.576452) (xy 422.463212 -297.545327) (xy 422.430577 -297.50849)
			(xy 422.404274 -297.466894) (xy 422.384983 -297.421618) (xy 422.373206 -297.373834) (xy 422.369246 -297.32478)
			(xy 422.030144 -297.32478) (xy 422.029649 -297.349387) (xy 422.021754 -297.397964) (xy 422.00617 -297.444645)
			(xy 421.983299 -297.488222) (xy 421.953734 -297.527566) (xy 421.918241 -297.561658) (xy 421.877738 -297.589614)
			(xy 421.833276 -297.610712) (xy 421.786005 -297.624404) (xy 421.73715 -297.630336) (xy 421.687975 -297.628355)
			(xy 421.639756 -297.618511) (xy 421.59374 -297.601059) (xy 421.551119 -297.576452) (xy 421.512998 -297.545327)
			(xy 421.480363 -297.50849) (xy 421.45406 -297.466894) (xy 421.434769 -297.421618) (xy 421.422992 -297.373834)
			(xy 421.419032 -297.32478) (xy 421.080184 -297.32478) (xy 421.079689 -297.349387) (xy 421.071794 -297.397964)
			(xy 421.05621 -297.444645) (xy 421.033339 -297.488222) (xy 421.003774 -297.527566) (xy 420.968281 -297.561658)
			(xy 420.927778 -297.589614) (xy 420.883316 -297.610712) (xy 420.836045 -297.624404) (xy 420.78719 -297.630336)
			(xy 420.738015 -297.628355) (xy 420.689796 -297.618511) (xy 420.64378 -297.601059) (xy 420.601159 -297.576452)
			(xy 420.563038 -297.545327) (xy 420.530403 -297.50849) (xy 420.5041 -297.466894) (xy 420.484809 -297.421618)
			(xy 420.473032 -297.373834) (xy 420.469072 -297.32478) (xy 420.130224 -297.32478) (xy 420.129729 -297.349387)
			(xy 420.121834 -297.397964) (xy 420.10625 -297.444645) (xy 420.083379 -297.488222) (xy 420.053814 -297.527566)
			(xy 420.018321 -297.561658) (xy 419.977818 -297.589614) (xy 419.933356 -297.610712) (xy 419.886085 -297.624404)
			(xy 419.83723 -297.630336) (xy 419.788055 -297.628355) (xy 419.739836 -297.618511) (xy 419.69382 -297.601059)
			(xy 419.651199 -297.576452) (xy 419.613078 -297.545327) (xy 419.580443 -297.50849) (xy 419.55414 -297.466894)
			(xy 419.534849 -297.421618) (xy 419.523072 -297.373834) (xy 419.519112 -297.32478) (xy 418.230304 -297.32478)
			(xy 418.229809 -297.349387) (xy 418.221914 -297.397964) (xy 418.20633 -297.444645) (xy 418.183459 -297.488222)
			(xy 418.153894 -297.527566) (xy 418.118401 -297.561658) (xy 418.077898 -297.589614) (xy 418.033436 -297.610712)
			(xy 417.986165 -297.624404) (xy 417.93731 -297.630336) (xy 417.888135 -297.628355) (xy 417.839916 -297.618511)
			(xy 417.7939 -297.601059) (xy 417.751279 -297.576452) (xy 417.713158 -297.545327) (xy 417.680523 -297.50849)
			(xy 417.65422 -297.466894) (xy 417.634929 -297.421618) (xy 417.623152 -297.373834) (xy 417.619192 -297.32478)
			(xy 417.28009 -297.32478) (xy 417.279595 -297.349387) (xy 417.2717 -297.397964) (xy 417.256116 -297.444645)
			(xy 417.233245 -297.488222) (xy 417.20368 -297.527566) (xy 417.168187 -297.561658) (xy 417.127684 -297.589614)
			(xy 417.083222 -297.610712) (xy 417.035951 -297.624404) (xy 416.987096 -297.630336) (xy 416.937921 -297.628355)
			(xy 416.889702 -297.618511) (xy 416.843686 -297.601059) (xy 416.801065 -297.576452) (xy 416.762944 -297.545327)
			(xy 416.730309 -297.50849) (xy 416.704006 -297.466894) (xy 416.684715 -297.421618) (xy 416.672938 -297.373834)
			(xy 416.668978 -297.32478) (xy 416.33013 -297.32478) (xy 416.329635 -297.349387) (xy 416.32174 -297.397964)
			(xy 416.306156 -297.444645) (xy 416.283285 -297.488222) (xy 416.25372 -297.527566) (xy 416.218227 -297.561658)
			(xy 416.177724 -297.589614) (xy 416.133262 -297.610712) (xy 416.085991 -297.624404) (xy 416.037136 -297.630336)
			(xy 415.987961 -297.628355) (xy 415.939742 -297.618511) (xy 415.893726 -297.601059) (xy 415.851105 -297.576452)
			(xy 415.812984 -297.545327) (xy 415.780349 -297.50849) (xy 415.754046 -297.466894) (xy 415.734755 -297.421618)
			(xy 415.722978 -297.373834) (xy 415.719018 -297.32478) (xy 415.38017 -297.32478) (xy 415.379675 -297.349387)
			(xy 415.37178 -297.397964) (xy 415.356196 -297.444645) (xy 415.333325 -297.488222) (xy 415.30376 -297.527566)
			(xy 415.268267 -297.561658) (xy 415.227764 -297.589614) (xy 415.183302 -297.610712) (xy 415.136031 -297.624404)
			(xy 415.087176 -297.630336) (xy 415.038001 -297.628355) (xy 414.989782 -297.618511) (xy 414.943766 -297.601059)
			(xy 414.901145 -297.576452) (xy 414.863024 -297.545327) (xy 414.830389 -297.50849) (xy 414.804086 -297.466894)
			(xy 414.784795 -297.421618) (xy 414.773018 -297.373834) (xy 414.769058 -297.32478) (xy 414.43021 -297.32478)
			(xy 414.429715 -297.349387) (xy 414.42182 -297.397964) (xy 414.406236 -297.444645) (xy 414.383365 -297.488222)
			(xy 414.3538 -297.527566) (xy 414.318307 -297.561658) (xy 414.277804 -297.589614) (xy 414.233342 -297.610712)
			(xy 414.186071 -297.624404) (xy 414.137216 -297.630336) (xy 414.088041 -297.628355) (xy 414.039822 -297.618511)
			(xy 413.993806 -297.601059) (xy 413.951185 -297.576452) (xy 413.913064 -297.545327) (xy 413.880429 -297.50849)
			(xy 413.854126 -297.466894) (xy 413.834835 -297.421618) (xy 413.823058 -297.373834) (xy 413.819098 -297.32478)
			(xy 413.48025 -297.32478) (xy 413.479755 -297.349387) (xy 413.47186 -297.397964) (xy 413.456276 -297.444645)
			(xy 413.433405 -297.488222) (xy 413.40384 -297.527566) (xy 413.368347 -297.561658) (xy 413.327844 -297.589614)
			(xy 413.283382 -297.610712) (xy 413.236111 -297.624404) (xy 413.187256 -297.630336) (xy 413.138081 -297.628355)
			(xy 413.089862 -297.618511) (xy 413.043846 -297.601059) (xy 413.001225 -297.576452) (xy 412.963104 -297.545327)
			(xy 412.930469 -297.50849) (xy 412.904166 -297.466894) (xy 412.884875 -297.421618) (xy 412.873098 -297.373834)
			(xy 412.869138 -297.32478) (xy 412.53029 -297.32478) (xy 412.529795 -297.349387) (xy 412.5219 -297.397964)
			(xy 412.506316 -297.444645) (xy 412.483445 -297.488222) (xy 412.45388 -297.527566) (xy 412.418387 -297.561658)
			(xy 412.377884 -297.589614) (xy 412.333422 -297.610712) (xy 412.286151 -297.624404) (xy 412.237296 -297.630336)
			(xy 412.188121 -297.628355) (xy 412.139902 -297.618511) (xy 412.093886 -297.601059) (xy 412.051265 -297.576452)
			(xy 412.013144 -297.545327) (xy 411.980509 -297.50849) (xy 411.954206 -297.466894) (xy 411.934915 -297.421618)
			(xy 411.923138 -297.373834) (xy 411.919178 -297.32478) (xy 411.58033 -297.32478) (xy 411.579835 -297.349387)
			(xy 411.57194 -297.397964) (xy 411.556356 -297.444645) (xy 411.533485 -297.488222) (xy 411.50392 -297.527566)
			(xy 411.468427 -297.561658) (xy 411.427924 -297.589614) (xy 411.383462 -297.610712) (xy 411.336191 -297.624404)
			(xy 411.287336 -297.630336) (xy 411.238161 -297.628355) (xy 411.189942 -297.618511) (xy 411.143926 -297.601059)
			(xy 411.101305 -297.576452) (xy 411.063184 -297.545327) (xy 411.030549 -297.50849) (xy 411.004246 -297.466894)
			(xy 410.984955 -297.421618) (xy 410.973178 -297.373834) (xy 410.969218 -297.32478) (xy 410.630116 -297.32478)
			(xy 410.629621 -297.349387) (xy 410.621726 -297.397964) (xy 410.606142 -297.444645) (xy 410.583271 -297.488222)
			(xy 410.553706 -297.527566) (xy 410.518213 -297.561658) (xy 410.47771 -297.589614) (xy 410.433248 -297.610712)
			(xy 410.385977 -297.624404) (xy 410.337122 -297.630336) (xy 410.287947 -297.628355) (xy 410.239728 -297.618511)
			(xy 410.193712 -297.601059) (xy 410.151091 -297.576452) (xy 410.11297 -297.545327) (xy 410.080335 -297.50849)
			(xy 410.054032 -297.466894) (xy 410.034741 -297.421618) (xy 410.022964 -297.373834) (xy 410.019004 -297.32478)
			(xy 409.680156 -297.32478) (xy 409.679661 -297.349387) (xy 409.671766 -297.397964) (xy 409.656182 -297.444645)
			(xy 409.633311 -297.488222) (xy 409.603746 -297.527566) (xy 409.568253 -297.561658) (xy 409.52775 -297.589614)
			(xy 409.483288 -297.610712) (xy 409.436017 -297.624404) (xy 409.387162 -297.630336) (xy 409.337987 -297.628355)
			(xy 409.289768 -297.618511) (xy 409.243752 -297.601059) (xy 409.201131 -297.576452) (xy 409.16301 -297.545327)
			(xy 409.130375 -297.50849) (xy 409.104072 -297.466894) (xy 409.084781 -297.421618) (xy 409.073004 -297.373834)
			(xy 409.069044 -297.32478) (xy 408.730196 -297.32478) (xy 408.729701 -297.349387) (xy 408.721806 -297.397964)
			(xy 408.706222 -297.444645) (xy 408.683351 -297.488222) (xy 408.653786 -297.527566) (xy 408.618293 -297.561658)
			(xy 408.57779 -297.589614) (xy 408.533328 -297.610712) (xy 408.486057 -297.624404) (xy 408.437202 -297.630336)
			(xy 408.388027 -297.628355) (xy 408.339808 -297.618511) (xy 408.293792 -297.601059) (xy 408.251171 -297.576452)
			(xy 408.21305 -297.545327) (xy 408.180415 -297.50849) (xy 408.154112 -297.466894) (xy 408.134821 -297.421618)
			(xy 408.123044 -297.373834) (xy 408.119084 -297.32478) (xy 406.830276 -297.32478) (xy 406.829781 -297.349387)
			(xy 406.821886 -297.397964) (xy 406.806302 -297.444645) (xy 406.783431 -297.488222) (xy 406.753866 -297.527566)
			(xy 406.718373 -297.561658) (xy 406.67787 -297.589614) (xy 406.633408 -297.610712) (xy 406.586137 -297.624404)
			(xy 406.537282 -297.630336) (xy 406.488107 -297.628355) (xy 406.439888 -297.618511) (xy 406.393872 -297.601059)
			(xy 406.351251 -297.576452) (xy 406.31313 -297.545327) (xy 406.280495 -297.50849) (xy 406.254192 -297.466894)
			(xy 406.234901 -297.421618) (xy 406.223124 -297.373834) (xy 406.219164 -297.32478) (xy 405.880316 -297.32478)
			(xy 405.879821 -297.349387) (xy 405.871926 -297.397964) (xy 405.856342 -297.444645) (xy 405.833471 -297.488222)
			(xy 405.803906 -297.527566) (xy 405.768413 -297.561658) (xy 405.72791 -297.589614) (xy 405.683448 -297.610712)
			(xy 405.636177 -297.624404) (xy 405.587322 -297.630336) (xy 405.538147 -297.628355) (xy 405.489928 -297.618511)
			(xy 405.443912 -297.601059) (xy 405.401291 -297.576452) (xy 405.36317 -297.545327) (xy 405.330535 -297.50849)
			(xy 405.304232 -297.466894) (xy 405.284941 -297.421618) (xy 405.273164 -297.373834) (xy 405.269204 -297.32478)
			(xy 404.930102 -297.32478) (xy 404.929607 -297.349387) (xy 404.921712 -297.397964) (xy 404.906128 -297.444645)
			(xy 404.883257 -297.488222) (xy 404.853692 -297.527566) (xy 404.818199 -297.561658) (xy 404.777696 -297.589614)
			(xy 404.733234 -297.610712) (xy 404.685963 -297.624404) (xy 404.637108 -297.630336) (xy 404.587933 -297.628355)
			(xy 404.539714 -297.618511) (xy 404.493698 -297.601059) (xy 404.451077 -297.576452) (xy 404.412956 -297.545327)
			(xy 404.380321 -297.50849) (xy 404.354018 -297.466894) (xy 404.334727 -297.421618) (xy 404.32295 -297.373834)
			(xy 404.31899 -297.32478) (xy 403.980142 -297.32478) (xy 403.979647 -297.349387) (xy 403.971752 -297.397964)
			(xy 403.956168 -297.444645) (xy 403.933297 -297.488222) (xy 403.903732 -297.527566) (xy 403.868239 -297.561658)
			(xy 403.827736 -297.589614) (xy 403.783274 -297.610712) (xy 403.736003 -297.624404) (xy 403.687148 -297.630336)
			(xy 403.637973 -297.628355) (xy 403.589754 -297.618511) (xy 403.543738 -297.601059) (xy 403.501117 -297.576452)
			(xy 403.462996 -297.545327) (xy 403.430361 -297.50849) (xy 403.404058 -297.466894) (xy 403.384767 -297.421618)
			(xy 403.37299 -297.373834) (xy 403.36903 -297.32478) (xy 403.030182 -297.32478) (xy 403.029687 -297.349387)
			(xy 403.021792 -297.397964) (xy 403.006208 -297.444645) (xy 402.983337 -297.488222) (xy 402.953772 -297.527566)
			(xy 402.918279 -297.561658) (xy 402.877776 -297.589614) (xy 402.833314 -297.610712) (xy 402.786043 -297.624404)
			(xy 402.737188 -297.630336) (xy 402.688013 -297.628355) (xy 402.639794 -297.618511) (xy 402.593778 -297.601059)
			(xy 402.551157 -297.576452) (xy 402.513036 -297.545327) (xy 402.480401 -297.50849) (xy 402.454098 -297.466894)
			(xy 402.434807 -297.421618) (xy 402.42303 -297.373834) (xy 402.41907 -297.32478) (xy 402.080222 -297.32478)
			(xy 402.079727 -297.349387) (xy 402.071832 -297.397964) (xy 402.056248 -297.444645) (xy 402.033377 -297.488222)
			(xy 402.003812 -297.527566) (xy 401.968319 -297.561658) (xy 401.927816 -297.589614) (xy 401.883354 -297.610712)
			(xy 401.836083 -297.624404) (xy 401.787228 -297.630336) (xy 401.738053 -297.628355) (xy 401.689834 -297.618511)
			(xy 401.643818 -297.601059) (xy 401.601197 -297.576452) (xy 401.563076 -297.545327) (xy 401.530441 -297.50849)
			(xy 401.504138 -297.466894) (xy 401.484847 -297.421618) (xy 401.47307 -297.373834) (xy 401.46911 -297.32478)
			(xy 401.130262 -297.32478) (xy 401.129767 -297.349387) (xy 401.121872 -297.397964) (xy 401.106288 -297.444645)
			(xy 401.083417 -297.488222) (xy 401.053852 -297.527566) (xy 401.018359 -297.561658) (xy 400.977856 -297.589614)
			(xy 400.933394 -297.610712) (xy 400.886123 -297.624404) (xy 400.837268 -297.630336) (xy 400.788093 -297.628355)
			(xy 400.739874 -297.618511) (xy 400.693858 -297.601059) (xy 400.651237 -297.576452) (xy 400.613116 -297.545327)
			(xy 400.580481 -297.50849) (xy 400.554178 -297.466894) (xy 400.534887 -297.421618) (xy 400.52311 -297.373834)
			(xy 400.51915 -297.32478) (xy 400.180302 -297.32478) (xy 400.179807 -297.349387) (xy 400.171912 -297.397964)
			(xy 400.156328 -297.444645) (xy 400.133457 -297.488222) (xy 400.103892 -297.527566) (xy 400.068399 -297.561658)
			(xy 400.027896 -297.589614) (xy 399.983434 -297.610712) (xy 399.936163 -297.624404) (xy 399.887308 -297.630336)
			(xy 399.838133 -297.628355) (xy 399.789914 -297.618511) (xy 399.743898 -297.601059) (xy 399.701277 -297.576452)
			(xy 399.663156 -297.545327) (xy 399.630521 -297.50849) (xy 399.604218 -297.466894) (xy 399.584927 -297.421618)
			(xy 399.57315 -297.373834) (xy 399.56919 -297.32478) (xy 399.230342 -297.32478) (xy 399.229847 -297.349387)
			(xy 399.221952 -297.397964) (xy 399.206368 -297.444645) (xy 399.183497 -297.488222) (xy 399.153932 -297.527566)
			(xy 399.118439 -297.561658) (xy 399.077936 -297.589614) (xy 399.033474 -297.610712) (xy 398.986203 -297.624404)
			(xy 398.937348 -297.630336) (xy 398.888173 -297.628355) (xy 398.839954 -297.618511) (xy 398.793938 -297.601059)
			(xy 398.751317 -297.576452) (xy 398.713196 -297.545327) (xy 398.680561 -297.50849) (xy 398.654258 -297.466894)
			(xy 398.634967 -297.421618) (xy 398.62319 -297.373834) (xy 398.61923 -297.32478) (xy 398.280128 -297.32478)
			(xy 398.279633 -297.349387) (xy 398.271738 -297.397964) (xy 398.256154 -297.444645) (xy 398.233283 -297.488222)
			(xy 398.203718 -297.527566) (xy 398.168225 -297.561658) (xy 398.127722 -297.589614) (xy 398.08326 -297.610712)
			(xy 398.035989 -297.624404) (xy 397.987134 -297.630336) (xy 397.937959 -297.628355) (xy 397.88974 -297.618511)
			(xy 397.843724 -297.601059) (xy 397.801103 -297.576452) (xy 397.762982 -297.545327) (xy 397.730347 -297.50849)
			(xy 397.704044 -297.466894) (xy 397.684753 -297.421618) (xy 397.672976 -297.373834) (xy 397.669016 -297.32478)
			(xy 397.355166 -297.32478) (xy 397.355167 -297.351161) (xy 397.346803 -297.40322) (xy 397.330286 -297.453292)
			(xy 397.306035 -297.500111) (xy 397.274664 -297.54249) (xy 397.236967 -297.579355) (xy 397.1939 -297.609774)
			(xy 397.146552 -297.632975) (xy 397.096124 -297.648371) (xy 397.070072 -297.65244) (xy 397.066008 -297.652948)
			(xy 397.054578 -297.656504) (xy 397.05026 -297.657774) (xy 397.02613 -297.66895) (xy 397.019526 -297.676062)
			(xy 397.004794 -297.691556) (xy 396.996666 -297.702732) (xy 396.993977 -297.708265) (xy 396.991036 -297.720205)
			(xy 396.990824 -297.726354) (xy 396.990824 -297.873166) (xy 396.990993 -297.879319) (xy 396.993946 -297.891266)
			(xy 396.996666 -297.896788) (xy 397.004794 -297.907964) (xy 397.019526 -297.923458) (xy 397.02613 -297.93057)
			(xy 397.05026 -297.941746) (xy 397.054578 -297.943016) (xy 397.066008 -297.946572) (xy 397.070072 -297.94708)
			(xy 397.096114 -297.951188) (xy 397.146533 -297.966582) (xy 397.193872 -297.989779) (xy 397.236932 -298.020192)
			(xy 397.274621 -298.057051) (xy 397.305986 -298.099423) (xy 397.330232 -298.146233) (xy 397.346745 -298.196297)
			(xy 397.355108 -298.248347) (xy 397.355107 -298.27474) (xy 397.669016 -298.27474) (xy 397.672976 -298.225686)
			(xy 397.684753 -298.177902) (xy 397.704044 -298.132626) (xy 397.730347 -298.09103) (xy 397.762982 -298.054193)
			(xy 397.801103 -298.023068) (xy 397.843724 -297.998461) (xy 397.88974 -297.981009) (xy 397.937959 -297.971165)
			(xy 397.987134 -297.969184) (xy 398.035989 -297.975116) (xy 398.08326 -297.988808) (xy 398.127722 -298.009906)
			(xy 398.168225 -298.037862) (xy 398.203718 -298.071954) (xy 398.233283 -298.111298) (xy 398.256154 -298.154875)
			(xy 398.271738 -298.201556) (xy 398.279633 -298.250133) (xy 398.280128 -298.27474) (xy 398.61923 -298.27474)
			(xy 398.62319 -298.225686) (xy 398.634967 -298.177902) (xy 398.654258 -298.132626) (xy 398.680561 -298.09103)
			(xy 398.713196 -298.054193) (xy 398.751317 -298.023068) (xy 398.793938 -297.998461) (xy 398.839954 -297.981009)
			(xy 398.888173 -297.971165) (xy 398.937348 -297.969184) (xy 398.986203 -297.975116) (xy 399.033474 -297.988808)
			(xy 399.077936 -298.009906) (xy 399.118439 -298.037862) (xy 399.153932 -298.071954) (xy 399.183497 -298.111298)
			(xy 399.206368 -298.154875) (xy 399.221952 -298.201556) (xy 399.229847 -298.250133) (xy 399.230342 -298.27474)
			(xy 399.56919 -298.27474) (xy 399.57315 -298.225686) (xy 399.584927 -298.177902) (xy 399.604218 -298.132626)
			(xy 399.630521 -298.09103) (xy 399.663156 -298.054193) (xy 399.701277 -298.023068) (xy 399.743898 -297.998461)
			(xy 399.789914 -297.981009) (xy 399.838133 -297.971165) (xy 399.887308 -297.969184) (xy 399.936163 -297.975116)
			(xy 399.983434 -297.988808) (xy 400.027896 -298.009906) (xy 400.068399 -298.037862) (xy 400.103892 -298.071954)
			(xy 400.133457 -298.111298) (xy 400.156328 -298.154875) (xy 400.171912 -298.201556) (xy 400.179807 -298.250133)
			(xy 400.180302 -298.27474) (xy 400.51915 -298.27474) (xy 400.52311 -298.225686) (xy 400.534887 -298.177902)
			(xy 400.554178 -298.132626) (xy 400.580481 -298.09103) (xy 400.613116 -298.054193) (xy 400.651237 -298.023068)
			(xy 400.693858 -297.998461) (xy 400.739874 -297.981009) (xy 400.788093 -297.971165) (xy 400.837268 -297.969184)
			(xy 400.886123 -297.975116) (xy 400.933394 -297.988808) (xy 400.977856 -298.009906) (xy 401.018359 -298.037862)
			(xy 401.053852 -298.071954) (xy 401.083417 -298.111298) (xy 401.106288 -298.154875) (xy 401.121872 -298.201556)
			(xy 401.129767 -298.250133) (xy 401.130262 -298.27474) (xy 401.46911 -298.27474) (xy 401.47307 -298.225686)
			(xy 401.484847 -298.177902) (xy 401.504138 -298.132626) (xy 401.530441 -298.09103) (xy 401.563076 -298.054193)
			(xy 401.601197 -298.023068) (xy 401.643818 -297.998461) (xy 401.689834 -297.981009) (xy 401.738053 -297.971165)
			(xy 401.787228 -297.969184) (xy 401.836083 -297.975116) (xy 401.883354 -297.988808) (xy 401.927816 -298.009906)
			(xy 401.968319 -298.037862) (xy 402.003812 -298.071954) (xy 402.033377 -298.111298) (xy 402.056248 -298.154875)
			(xy 402.071832 -298.201556) (xy 402.079727 -298.250133) (xy 402.080222 -298.27474) (xy 402.41907 -298.27474)
			(xy 402.42303 -298.225686) (xy 402.434807 -298.177902) (xy 402.454098 -298.132626) (xy 402.480401 -298.09103)
			(xy 402.513036 -298.054193) (xy 402.551157 -298.023068) (xy 402.593778 -297.998461) (xy 402.639794 -297.981009)
			(xy 402.688013 -297.971165) (xy 402.737188 -297.969184) (xy 402.786043 -297.975116) (xy 402.833314 -297.988808)
			(xy 402.877776 -298.009906) (xy 402.918279 -298.037862) (xy 402.953772 -298.071954) (xy 402.983337 -298.111298)
			(xy 403.006208 -298.154875) (xy 403.021792 -298.201556) (xy 403.029687 -298.250133) (xy 403.030182 -298.27474)
			(xy 403.36903 -298.27474) (xy 403.37299 -298.225686) (xy 403.384767 -298.177902) (xy 403.404058 -298.132626)
			(xy 403.430361 -298.09103) (xy 403.462996 -298.054193) (xy 403.501117 -298.023068) (xy 403.543738 -297.998461)
			(xy 403.589754 -297.981009) (xy 403.637973 -297.971165) (xy 403.687148 -297.969184) (xy 403.736003 -297.975116)
			(xy 403.783274 -297.988808) (xy 403.827736 -298.009906) (xy 403.868239 -298.037862) (xy 403.903732 -298.071954)
			(xy 403.933297 -298.111298) (xy 403.956168 -298.154875) (xy 403.971752 -298.201556) (xy 403.979647 -298.250133)
			(xy 403.980142 -298.27474) (xy 404.31899 -298.27474) (xy 404.32295 -298.225686) (xy 404.334727 -298.177902)
			(xy 404.354018 -298.132626) (xy 404.380321 -298.09103) (xy 404.412956 -298.054193) (xy 404.451077 -298.023068)
			(xy 404.493698 -297.998461) (xy 404.539714 -297.981009) (xy 404.587933 -297.971165) (xy 404.637108 -297.969184)
			(xy 404.685963 -297.975116) (xy 404.733234 -297.988808) (xy 404.777696 -298.009906) (xy 404.818199 -298.037862)
			(xy 404.853692 -298.071954) (xy 404.883257 -298.111298) (xy 404.906128 -298.154875) (xy 404.921712 -298.201556)
			(xy 404.929607 -298.250133) (xy 404.930102 -298.27474) (xy 405.269204 -298.27474) (xy 405.273164 -298.225686)
			(xy 405.284941 -298.177902) (xy 405.304232 -298.132626) (xy 405.330535 -298.09103) (xy 405.36317 -298.054193)
			(xy 405.401291 -298.023068) (xy 405.443912 -297.998461) (xy 405.489928 -297.981009) (xy 405.538147 -297.971165)
			(xy 405.587322 -297.969184) (xy 405.636177 -297.975116) (xy 405.683448 -297.988808) (xy 405.72791 -298.009906)
			(xy 405.768413 -298.037862) (xy 405.803906 -298.071954) (xy 405.833471 -298.111298) (xy 405.856342 -298.154875)
			(xy 405.871926 -298.201556) (xy 405.879821 -298.250133) (xy 405.880316 -298.27474) (xy 406.219164 -298.27474)
			(xy 406.223124 -298.225686) (xy 406.234901 -298.177902) (xy 406.254192 -298.132626) (xy 406.280495 -298.09103)
			(xy 406.31313 -298.054193) (xy 406.351251 -298.023068) (xy 406.393872 -297.998461) (xy 406.439888 -297.981009)
			(xy 406.488107 -297.971165) (xy 406.537282 -297.969184) (xy 406.586137 -297.975116) (xy 406.633408 -297.988808)
			(xy 406.67787 -298.009906) (xy 406.718373 -298.037862) (xy 406.753866 -298.071954) (xy 406.783431 -298.111298)
			(xy 406.806302 -298.154875) (xy 406.821886 -298.201556) (xy 406.829781 -298.250133) (xy 406.830276 -298.27474)
			(xy 408.119084 -298.27474) (xy 408.123044 -298.225686) (xy 408.134821 -298.177902) (xy 408.154112 -298.132626)
			(xy 408.180415 -298.09103) (xy 408.21305 -298.054193) (xy 408.251171 -298.023068) (xy 408.293792 -297.998461)
			(xy 408.339808 -297.981009) (xy 408.388027 -297.971165) (xy 408.437202 -297.969184) (xy 408.486057 -297.975116)
			(xy 408.533328 -297.988808) (xy 408.57779 -298.009906) (xy 408.618293 -298.037862) (xy 408.653786 -298.071954)
			(xy 408.683351 -298.111298) (xy 408.706222 -298.154875) (xy 408.721806 -298.201556) (xy 408.729701 -298.250133)
			(xy 408.730196 -298.27474) (xy 409.069044 -298.27474) (xy 409.073004 -298.225686) (xy 409.084781 -298.177902)
			(xy 409.104072 -298.132626) (xy 409.130375 -298.09103) (xy 409.16301 -298.054193) (xy 409.201131 -298.023068)
			(xy 409.243752 -297.998461) (xy 409.289768 -297.981009) (xy 409.337987 -297.971165) (xy 409.387162 -297.969184)
			(xy 409.436017 -297.975116) (xy 409.483288 -297.988808) (xy 409.52775 -298.009906) (xy 409.568253 -298.037862)
			(xy 409.603746 -298.071954) (xy 409.633311 -298.111298) (xy 409.656182 -298.154875) (xy 409.671766 -298.201556)
			(xy 409.679661 -298.250133) (xy 409.680156 -298.27474) (xy 410.019004 -298.27474) (xy 410.022964 -298.225686)
			(xy 410.034741 -298.177902) (xy 410.054032 -298.132626) (xy 410.080335 -298.09103) (xy 410.11297 -298.054193)
			(xy 410.151091 -298.023068) (xy 410.193712 -297.998461) (xy 410.239728 -297.981009) (xy 410.287947 -297.971165)
			(xy 410.337122 -297.969184) (xy 410.385977 -297.975116) (xy 410.433248 -297.988808) (xy 410.47771 -298.009906)
			(xy 410.518213 -298.037862) (xy 410.553706 -298.071954) (xy 410.583271 -298.111298) (xy 410.606142 -298.154875)
			(xy 410.621726 -298.201556) (xy 410.629621 -298.250133) (xy 410.630116 -298.27474) (xy 410.969218 -298.27474)
			(xy 410.973178 -298.225686) (xy 410.984955 -298.177902) (xy 411.004246 -298.132626) (xy 411.030549 -298.09103)
			(xy 411.063184 -298.054193) (xy 411.101305 -298.023068) (xy 411.143926 -297.998461) (xy 411.189942 -297.981009)
			(xy 411.238161 -297.971165) (xy 411.287336 -297.969184) (xy 411.336191 -297.975116) (xy 411.383462 -297.988808)
			(xy 411.427924 -298.009906) (xy 411.468427 -298.037862) (xy 411.50392 -298.071954) (xy 411.533485 -298.111298)
			(xy 411.556356 -298.154875) (xy 411.57194 -298.201556) (xy 411.579835 -298.250133) (xy 411.58033 -298.27474)
			(xy 411.919178 -298.27474) (xy 411.923138 -298.225686) (xy 411.934915 -298.177902) (xy 411.954206 -298.132626)
			(xy 411.980509 -298.09103) (xy 412.013144 -298.054193) (xy 412.051265 -298.023068) (xy 412.093886 -297.998461)
			(xy 412.139902 -297.981009) (xy 412.188121 -297.971165) (xy 412.237296 -297.969184) (xy 412.286151 -297.975116)
			(xy 412.333422 -297.988808) (xy 412.377884 -298.009906) (xy 412.418387 -298.037862) (xy 412.45388 -298.071954)
			(xy 412.483445 -298.111298) (xy 412.506316 -298.154875) (xy 412.5219 -298.201556) (xy 412.529795 -298.250133)
			(xy 412.53029 -298.27474) (xy 412.869138 -298.27474) (xy 412.873098 -298.225686) (xy 412.884875 -298.177902)
			(xy 412.904166 -298.132626) (xy 412.930469 -298.09103) (xy 412.963104 -298.054193) (xy 413.001225 -298.023068)
			(xy 413.043846 -297.998461) (xy 413.089862 -297.981009) (xy 413.138081 -297.971165) (xy 413.187256 -297.969184)
			(xy 413.236111 -297.975116) (xy 413.283382 -297.988808) (xy 413.327844 -298.009906) (xy 413.368347 -298.037862)
			(xy 413.40384 -298.071954) (xy 413.433405 -298.111298) (xy 413.456276 -298.154875) (xy 413.47186 -298.201556)
			(xy 413.479755 -298.250133) (xy 413.48025 -298.27474) (xy 413.819098 -298.27474) (xy 413.823058 -298.225686)
			(xy 413.834835 -298.177902) (xy 413.854126 -298.132626) (xy 413.880429 -298.09103) (xy 413.913064 -298.054193)
			(xy 413.951185 -298.023068) (xy 413.993806 -297.998461) (xy 414.039822 -297.981009) (xy 414.088041 -297.971165)
			(xy 414.137216 -297.969184) (xy 414.186071 -297.975116) (xy 414.233342 -297.988808) (xy 414.277804 -298.009906)
			(xy 414.318307 -298.037862) (xy 414.3538 -298.071954) (xy 414.383365 -298.111298) (xy 414.406236 -298.154875)
			(xy 414.42182 -298.201556) (xy 414.429715 -298.250133) (xy 414.43021 -298.27474) (xy 414.769058 -298.27474)
			(xy 414.773018 -298.225686) (xy 414.784795 -298.177902) (xy 414.804086 -298.132626) (xy 414.830389 -298.09103)
			(xy 414.863024 -298.054193) (xy 414.901145 -298.023068) (xy 414.943766 -297.998461) (xy 414.989782 -297.981009)
			(xy 415.038001 -297.971165) (xy 415.087176 -297.969184) (xy 415.136031 -297.975116) (xy 415.183302 -297.988808)
			(xy 415.227764 -298.009906) (xy 415.268267 -298.037862) (xy 415.30376 -298.071954) (xy 415.333325 -298.111298)
			(xy 415.356196 -298.154875) (xy 415.37178 -298.201556) (xy 415.379675 -298.250133) (xy 415.38017 -298.27474)
			(xy 415.719018 -298.27474) (xy 415.722978 -298.225686) (xy 415.734755 -298.177902) (xy 415.754046 -298.132626)
			(xy 415.780349 -298.09103) (xy 415.812984 -298.054193) (xy 415.851105 -298.023068) (xy 415.893726 -297.998461)
			(xy 415.939742 -297.981009) (xy 415.987961 -297.971165) (xy 416.037136 -297.969184) (xy 416.085991 -297.975116)
			(xy 416.133262 -297.988808) (xy 416.177724 -298.009906) (xy 416.218227 -298.037862) (xy 416.25372 -298.071954)
			(xy 416.283285 -298.111298) (xy 416.306156 -298.154875) (xy 416.32174 -298.201556) (xy 416.329635 -298.250133)
			(xy 416.33013 -298.27474) (xy 416.668978 -298.27474) (xy 416.672938 -298.225686) (xy 416.684715 -298.177902)
			(xy 416.704006 -298.132626) (xy 416.730309 -298.09103) (xy 416.762944 -298.054193) (xy 416.801065 -298.023068)
			(xy 416.843686 -297.998461) (xy 416.889702 -297.981009) (xy 416.937921 -297.971165) (xy 416.987096 -297.969184)
			(xy 417.035951 -297.975116) (xy 417.083222 -297.988808) (xy 417.127684 -298.009906) (xy 417.168187 -298.037862)
			(xy 417.20368 -298.071954) (xy 417.233245 -298.111298) (xy 417.256116 -298.154875) (xy 417.2717 -298.201556)
			(xy 417.279595 -298.250133) (xy 417.28009 -298.27474) (xy 417.619192 -298.27474) (xy 417.623152 -298.225686)
			(xy 417.634929 -298.177902) (xy 417.65422 -298.132626) (xy 417.680523 -298.09103) (xy 417.713158 -298.054193)
			(xy 417.751279 -298.023068) (xy 417.7939 -297.998461) (xy 417.839916 -297.981009) (xy 417.888135 -297.971165)
			(xy 417.93731 -297.969184) (xy 417.986165 -297.975116) (xy 418.033436 -297.988808) (xy 418.077898 -298.009906)
			(xy 418.118401 -298.037862) (xy 418.153894 -298.071954) (xy 418.183459 -298.111298) (xy 418.20633 -298.154875)
			(xy 418.221914 -298.201556) (xy 418.229809 -298.250133) (xy 418.230304 -298.27474) (xy 419.519112 -298.27474)
			(xy 419.523072 -298.225686) (xy 419.534849 -298.177902) (xy 419.55414 -298.132626) (xy 419.580443 -298.09103)
			(xy 419.613078 -298.054193) (xy 419.651199 -298.023068) (xy 419.69382 -297.998461) (xy 419.739836 -297.981009)
			(xy 419.788055 -297.971165) (xy 419.83723 -297.969184) (xy 419.886085 -297.975116) (xy 419.933356 -297.988808)
			(xy 419.977818 -298.009906) (xy 420.018321 -298.037862) (xy 420.053814 -298.071954) (xy 420.083379 -298.111298)
			(xy 420.10625 -298.154875) (xy 420.121834 -298.201556) (xy 420.129729 -298.250133) (xy 420.130224 -298.27474)
			(xy 420.469072 -298.27474) (xy 420.473032 -298.225686) (xy 420.484809 -298.177902) (xy 420.5041 -298.132626)
			(xy 420.530403 -298.09103) (xy 420.563038 -298.054193) (xy 420.601159 -298.023068) (xy 420.64378 -297.998461)
			(xy 420.689796 -297.981009) (xy 420.738015 -297.971165) (xy 420.78719 -297.969184) (xy 420.836045 -297.975116)
			(xy 420.883316 -297.988808) (xy 420.927778 -298.009906) (xy 420.968281 -298.037862) (xy 421.003774 -298.071954)
			(xy 421.033339 -298.111298) (xy 421.05621 -298.154875) (xy 421.071794 -298.201556) (xy 421.079689 -298.250133)
			(xy 421.080184 -298.27474) (xy 421.419032 -298.27474) (xy 421.422992 -298.225686) (xy 421.434769 -298.177902)
			(xy 421.45406 -298.132626) (xy 421.480363 -298.09103) (xy 421.512998 -298.054193) (xy 421.551119 -298.023068)
			(xy 421.59374 -297.998461) (xy 421.639756 -297.981009) (xy 421.687975 -297.971165) (xy 421.73715 -297.969184)
			(xy 421.786005 -297.975116) (xy 421.833276 -297.988808) (xy 421.877738 -298.009906) (xy 421.918241 -298.037862)
			(xy 421.953734 -298.071954) (xy 421.983299 -298.111298) (xy 422.00617 -298.154875) (xy 422.021754 -298.201556)
			(xy 422.029649 -298.250133) (xy 422.030144 -298.27474) (xy 422.368992 -298.27474) (xy 422.372952 -298.225686)
			(xy 422.384729 -298.177902) (xy 422.40402 -298.132626) (xy 422.430323 -298.09103) (xy 422.462958 -298.054193)
			(xy 422.501079 -298.023068) (xy 422.5437 -297.998461) (xy 422.589716 -297.981009) (xy 422.637935 -297.971165)
			(xy 422.68711 -297.969184) (xy 422.735965 -297.975116) (xy 422.783236 -297.988808) (xy 422.827698 -298.009906)
			(xy 422.868201 -298.037862) (xy 422.903694 -298.071954) (xy 422.933259 -298.111298) (xy 422.95613 -298.154875)
			(xy 422.971714 -298.201556) (xy 422.979609 -298.250133) (xy 422.980104 -298.27474) (xy 423.319206 -298.27474)
			(xy 423.323166 -298.225686) (xy 423.334943 -298.177902) (xy 423.354234 -298.132626) (xy 423.380537 -298.09103)
			(xy 423.413172 -298.054193) (xy 423.451293 -298.023068) (xy 423.493914 -297.998461) (xy 423.53993 -297.981009)
			(xy 423.588149 -297.971165) (xy 423.637324 -297.969184) (xy 423.686179 -297.975116) (xy 423.73345 -297.988808)
			(xy 423.777912 -298.009906) (xy 423.818415 -298.037862) (xy 423.853908 -298.071954) (xy 423.883473 -298.111298)
			(xy 423.906344 -298.154875) (xy 423.921928 -298.201556) (xy 423.929823 -298.250133) (xy 423.930318 -298.27474)
			(xy 424.269166 -298.27474) (xy 424.273126 -298.225686) (xy 424.284903 -298.177902) (xy 424.304194 -298.132626)
			(xy 424.330497 -298.09103) (xy 424.363132 -298.054193) (xy 424.401253 -298.023068) (xy 424.443874 -297.998461)
			(xy 424.48989 -297.981009) (xy 424.538109 -297.971165) (xy 424.587284 -297.969184) (xy 424.636139 -297.975116)
			(xy 424.68341 -297.988808) (xy 424.727872 -298.009906) (xy 424.768375 -298.037862) (xy 424.803868 -298.071954)
			(xy 424.833433 -298.111298) (xy 424.856304 -298.154875) (xy 424.871888 -298.201556) (xy 424.879783 -298.250133)
			(xy 424.880278 -298.27474) (xy 425.219126 -298.27474) (xy 425.223086 -298.225686) (xy 425.234863 -298.177902)
			(xy 425.254154 -298.132626) (xy 425.280457 -298.09103) (xy 425.313092 -298.054193) (xy 425.351213 -298.023068)
			(xy 425.393834 -297.998461) (xy 425.43985 -297.981009) (xy 425.488069 -297.971165) (xy 425.537244 -297.969184)
			(xy 425.586099 -297.975116) (xy 425.63337 -297.988808) (xy 425.677832 -298.009906) (xy 425.718335 -298.037862)
			(xy 425.753828 -298.071954) (xy 425.783393 -298.111298) (xy 425.806264 -298.154875) (xy 425.821848 -298.201556)
			(xy 425.829743 -298.250133) (xy 425.830238 -298.27474) (xy 426.169086 -298.27474) (xy 426.173046 -298.225686)
			(xy 426.184823 -298.177902) (xy 426.204114 -298.132626) (xy 426.230417 -298.09103) (xy 426.263052 -298.054193)
			(xy 426.301173 -298.023068) (xy 426.343794 -297.998461) (xy 426.38981 -297.981009) (xy 426.438029 -297.971165)
			(xy 426.487204 -297.969184) (xy 426.536059 -297.975116) (xy 426.58333 -297.988808) (xy 426.627792 -298.009906)
			(xy 426.668295 -298.037862) (xy 426.703788 -298.071954) (xy 426.733353 -298.111298) (xy 426.756224 -298.154875)
			(xy 426.771808 -298.201556) (xy 426.779703 -298.250133) (xy 426.780198 -298.27474) (xy 427.119046 -298.27474)
			(xy 427.123006 -298.225686) (xy 427.134783 -298.177902) (xy 427.154074 -298.132626) (xy 427.180377 -298.09103)
			(xy 427.213012 -298.054193) (xy 427.251133 -298.023068) (xy 427.293754 -297.998461) (xy 427.33977 -297.981009)
			(xy 427.387989 -297.971165) (xy 427.437164 -297.969184) (xy 427.486019 -297.975116) (xy 427.53329 -297.988808)
			(xy 427.577752 -298.009906) (xy 427.618255 -298.037862) (xy 427.653748 -298.071954) (xy 427.683313 -298.111298)
			(xy 427.706184 -298.154875) (xy 427.721768 -298.201556) (xy 427.729663 -298.250133) (xy 427.730158 -298.27474)
			(xy 428.069006 -298.27474) (xy 428.072966 -298.225686) (xy 428.084743 -298.177902) (xy 428.104034 -298.132626)
			(xy 428.130337 -298.09103) (xy 428.162972 -298.054193) (xy 428.201093 -298.023068) (xy 428.243714 -297.998461)
			(xy 428.28973 -297.981009) (xy 428.337949 -297.971165) (xy 428.387124 -297.969184) (xy 428.435979 -297.975116)
			(xy 428.48325 -297.988808) (xy 428.527712 -298.009906) (xy 428.568215 -298.037862) (xy 428.603708 -298.071954)
			(xy 428.633273 -298.111298) (xy 428.656144 -298.154875) (xy 428.671728 -298.201556) (xy 428.679623 -298.250133)
			(xy 428.680118 -298.27474) (xy 429.01922 -298.27474) (xy 429.02318 -298.225686) (xy 429.034957 -298.177902)
			(xy 429.054248 -298.132626) (xy 429.080551 -298.09103) (xy 429.113186 -298.054193) (xy 429.151307 -298.023068)
			(xy 429.193928 -297.998461) (xy 429.239944 -297.981009) (xy 429.288163 -297.971165) (xy 429.337338 -297.969184)
			(xy 429.386193 -297.975116) (xy 429.433464 -297.988808) (xy 429.477926 -298.009906) (xy 429.518429 -298.037862)
			(xy 429.553922 -298.071954) (xy 429.583487 -298.111298) (xy 429.606358 -298.154875) (xy 429.621942 -298.201556)
			(xy 429.629837 -298.250133) (xy 429.630332 -298.27474) (xy 429.96918 -298.27474) (xy 429.97314 -298.225686)
			(xy 429.984917 -298.177902) (xy 430.004208 -298.132626) (xy 430.030511 -298.09103) (xy 430.063146 -298.054193)
			(xy 430.101267 -298.023068) (xy 430.143888 -297.998461) (xy 430.189904 -297.981009) (xy 430.238123 -297.971165)
			(xy 430.287298 -297.969184) (xy 430.336153 -297.975116) (xy 430.383424 -297.988808) (xy 430.427886 -298.009906)
			(xy 430.468389 -298.037862) (xy 430.503882 -298.071954) (xy 430.533447 -298.111298) (xy 430.556318 -298.154875)
			(xy 430.571902 -298.201556) (xy 430.579797 -298.250133) (xy 430.580292 -298.27474) (xy 430.91914 -298.27474)
			(xy 430.9231 -298.225686) (xy 430.934877 -298.177902) (xy 430.954168 -298.132626) (xy 430.980471 -298.09103)
			(xy 431.013106 -298.054193) (xy 431.051227 -298.023068) (xy 431.093848 -297.998461) (xy 431.139864 -297.981009)
			(xy 431.188083 -297.971165) (xy 431.237258 -297.969184) (xy 431.286113 -297.975116) (xy 431.333384 -297.988808)
			(xy 431.377846 -298.009906) (xy 431.418349 -298.037862) (xy 431.453842 -298.071954) (xy 431.483407 -298.111298)
			(xy 431.506278 -298.154875) (xy 431.521862 -298.201556) (xy 431.529757 -298.250133) (xy 431.530252 -298.27474)
			(xy 431.529757 -298.299347) (xy 431.525612 -298.324851) (xy 432.282578 -298.324851) (xy 432.282578 -298.270349)
			(xy 432.290334 -298.216401) (xy 432.305689 -298.164106) (xy 432.328331 -298.114529) (xy 432.357797 -298.068679)
			(xy 432.393488 -298.027488) (xy 432.434679 -297.991797) (xy 432.480529 -297.962331) (xy 432.530106 -297.939689)
			(xy 432.582401 -297.924334) (xy 432.636349 -297.916578) (xy 432.6636 -297.916092) (xy 432.688532 -297.916503)
			(xy 432.737972 -297.922985) (xy 432.786146 -297.935851) (xy 432.832235 -297.954882) (xy 432.875452 -297.979755)
			(xy 432.895502 -297.994578) (xy 432.906521 -298.002476) (xy 432.931603 -298.012733) (xy 432.958502 -298.016018)
			(xy 432.985316 -298.012099) (xy 433.01015 -298.001253) (xy 433.031248 -297.984246) (xy 433.047119 -297.962281)
			(xy 433.05664 -297.93691) (xy 433.058316 -297.923458) (xy 433.061444 -297.895404) (xy 433.074876 -297.84058)
			(xy 433.096235 -297.788332) (xy 433.125056 -297.739799) (xy 433.16071 -297.696039) (xy 433.20242 -297.658008)
			(xy 433.249276 -297.626534) (xy 433.300257 -297.602303) (xy 433.354249 -297.585845) (xy 433.410077 -297.577518)
			(xy 433.4383 -297.577002) (xy 433.465552 -297.577468) (xy 433.519501 -297.585225) (xy 433.571797 -297.60058)
			(xy 433.621376 -297.623222) (xy 433.667227 -297.652689) (xy 433.693322 -297.6753) (xy 434.599586 -297.6753)
			(xy 434.603657 -297.619678) (xy 434.615783 -297.565241) (xy 434.635706 -297.51315) (xy 434.663002 -297.464515)
			(xy 434.697088 -297.420372) (xy 434.737237 -297.381663) (xy 434.782595 -297.349212) (xy 434.832195 -297.323711)
			(xy 434.884979 -297.305704) (xy 434.939822 -297.295574) (xy 434.995556 -297.293537) (xy 435.050993 -297.299637)
			(xy 435.10495 -297.313743) (xy 435.156279 -297.335555) (xy 435.203885 -297.364609) (xy 435.216152 -297.374818)
			(xy 440.915804 -297.374818) (xy 440.919875 -297.319196) (xy 440.932001 -297.264759) (xy 440.951924 -297.212668)
			(xy 440.97922 -297.164033) (xy 441.013306 -297.11989) (xy 441.053455 -297.081181) (xy 441.098813 -297.04873)
			(xy 441.148413 -297.023229) (xy 441.201197 -297.005222) (xy 441.25604 -296.995092) (xy 441.311774 -296.993055)
			(xy 441.367211 -296.999155) (xy 441.421168 -297.013261) (xy 441.472497 -297.035073) (xy 441.520103 -297.064127)
			(xy 441.562971 -297.099802) (xy 441.600188 -297.141339) (xy 441.630961 -297.187852) (xy 441.654633 -297.238349)
			(xy 441.670701 -297.291756) (xy 441.678821 -297.346932) (xy 441.67933 -297.374818) (xy 441.678821 -297.402704)
			(xy 441.670701 -297.45788) (xy 441.654633 -297.511287) (xy 441.630961 -297.561784) (xy 441.600188 -297.608297)
			(xy 441.562971 -297.649834) (xy 441.520103 -297.685509) (xy 441.472497 -297.714563) (xy 441.421168 -297.736375)
			(xy 441.367211 -297.750481) (xy 441.311774 -297.756581) (xy 441.25604 -297.754544) (xy 441.201197 -297.744414)
			(xy 441.148413 -297.726407) (xy 441.098813 -297.700906) (xy 441.053455 -297.668455) (xy 441.013306 -297.629746)
			(xy 440.97922 -297.585603) (xy 440.951924 -297.536968) (xy 440.932001 -297.484877) (xy 440.919875 -297.43044)
			(xy 440.915804 -297.374818) (xy 435.216152 -297.374818) (xy 435.246753 -297.400284) (xy 435.28397 -297.441821)
			(xy 435.314743 -297.488334) (xy 435.338415 -297.538831) (xy 435.354483 -297.592238) (xy 435.362603 -297.647414)
			(xy 435.363112 -297.6753) (xy 435.362603 -297.703186) (xy 435.354483 -297.758362) (xy 435.338415 -297.811769)
			(xy 435.314743 -297.862266) (xy 435.28397 -297.908779) (xy 435.246753 -297.950316) (xy 435.203885 -297.985991)
			(xy 435.156279 -298.015045) (xy 435.10495 -298.036857) (xy 435.050993 -298.050963) (xy 434.995556 -298.057063)
			(xy 434.939822 -298.055026) (xy 434.884979 -298.044896) (xy 434.832195 -298.026889) (xy 434.782595 -298.001388)
			(xy 434.737237 -297.968937) (xy 434.697088 -297.930228) (xy 434.663002 -297.886085) (xy 434.635706 -297.83745)
			(xy 434.615783 -297.785359) (xy 434.603657 -297.730922) (xy 434.599586 -297.6753) (xy 433.693322 -297.6753)
			(xy 433.708419 -297.688381) (xy 433.744111 -297.729573) (xy 433.773578 -297.775424) (xy 433.79622 -297.825003)
			(xy 433.811575 -297.877299) (xy 433.819332 -297.931248) (xy 433.819332 -297.985752) (xy 433.811575 -298.039701)
			(xy 433.79622 -298.091997) (xy 433.773578 -298.141576) (xy 433.744111 -298.187427) (xy 433.708419 -298.228619)
			(xy 433.667227 -298.264311) (xy 433.621376 -298.293778) (xy 433.571797 -298.31642) (xy 433.519501 -298.331775)
			(xy 433.465552 -298.339532) (xy 433.4383 -298.340018) (xy 433.413368 -298.339605) (xy 433.363929 -298.333123)
			(xy 433.315754 -298.320258) (xy 433.269666 -298.301227) (xy 433.226449 -298.276355) (xy 433.206398 -298.261532)
			(xy 433.195383 -298.253628) (xy 433.170299 -298.243369) (xy 433.143399 -298.240082) (xy 433.116583 -298.244002)
			(xy 433.091748 -298.254849) (xy 433.070649 -298.271858) (xy 433.054779 -298.293825) (xy 433.045259 -298.319199)
			(xy 433.043584 -298.332652) (xy 433.040464 -298.360707) (xy 433.027031 -298.415531) (xy 433.00567 -298.467779)
			(xy 432.976848 -298.516312) (xy 432.941193 -298.560071) (xy 432.899482 -298.598103) (xy 432.852626 -298.629577)
			(xy 432.801645 -298.653807) (xy 432.747651 -298.670265) (xy 432.691823 -298.678592) (xy 432.6636 -298.679108)
			(xy 432.636349 -298.678622) (xy 432.582401 -298.670866) (xy 432.530106 -298.655511) (xy 432.480529 -298.632869)
			(xy 432.434679 -298.603403) (xy 432.393488 -298.567712) (xy 432.357797 -298.526521) (xy 432.328331 -298.480671)
			(xy 432.305689 -298.431094) (xy 432.290334 -298.378799) (xy 432.282578 -298.324851) (xy 431.525612 -298.324851)
			(xy 431.521862 -298.347924) (xy 431.506278 -298.394605) (xy 431.483407 -298.438182) (xy 431.453842 -298.477526)
			(xy 431.418349 -298.511618) (xy 431.377846 -298.539574) (xy 431.333384 -298.560672) (xy 431.286113 -298.574364)
			(xy 431.237258 -298.580296) (xy 431.188083 -298.578315) (xy 431.139864 -298.568471) (xy 431.093848 -298.551019)
			(xy 431.051227 -298.526412) (xy 431.013106 -298.495287) (xy 430.980471 -298.45845) (xy 430.954168 -298.416854)
			(xy 430.934877 -298.371578) (xy 430.9231 -298.323794) (xy 430.91914 -298.27474) (xy 430.580292 -298.27474)
			(xy 430.579797 -298.299347) (xy 430.571902 -298.347924) (xy 430.556318 -298.394605) (xy 430.533447 -298.438182)
			(xy 430.503882 -298.477526) (xy 430.468389 -298.511618) (xy 430.427886 -298.539574) (xy 430.383424 -298.560672)
			(xy 430.336153 -298.574364) (xy 430.287298 -298.580296) (xy 430.238123 -298.578315) (xy 430.189904 -298.568471)
			(xy 430.143888 -298.551019) (xy 430.101267 -298.526412) (xy 430.063146 -298.495287) (xy 430.030511 -298.45845)
			(xy 430.004208 -298.416854) (xy 429.984917 -298.371578) (xy 429.97314 -298.323794) (xy 429.96918 -298.27474)
			(xy 429.630332 -298.27474) (xy 429.629837 -298.299347) (xy 429.621942 -298.347924) (xy 429.606358 -298.394605)
			(xy 429.583487 -298.438182) (xy 429.553922 -298.477526) (xy 429.518429 -298.511618) (xy 429.477926 -298.539574)
			(xy 429.433464 -298.560672) (xy 429.386193 -298.574364) (xy 429.337338 -298.580296) (xy 429.288163 -298.578315)
			(xy 429.239944 -298.568471) (xy 429.193928 -298.551019) (xy 429.151307 -298.526412) (xy 429.113186 -298.495287)
			(xy 429.080551 -298.45845) (xy 429.054248 -298.416854) (xy 429.034957 -298.371578) (xy 429.02318 -298.323794)
			(xy 429.01922 -298.27474) (xy 428.680118 -298.27474) (xy 428.679623 -298.299347) (xy 428.671728 -298.347924)
			(xy 428.656144 -298.394605) (xy 428.633273 -298.438182) (xy 428.603708 -298.477526) (xy 428.568215 -298.511618)
			(xy 428.527712 -298.539574) (xy 428.48325 -298.560672) (xy 428.435979 -298.574364) (xy 428.387124 -298.580296)
			(xy 428.337949 -298.578315) (xy 428.28973 -298.568471) (xy 428.243714 -298.551019) (xy 428.201093 -298.526412)
			(xy 428.162972 -298.495287) (xy 428.130337 -298.45845) (xy 428.104034 -298.416854) (xy 428.084743 -298.371578)
			(xy 428.072966 -298.323794) (xy 428.069006 -298.27474) (xy 427.730158 -298.27474) (xy 427.729663 -298.299347)
			(xy 427.721768 -298.347924) (xy 427.706184 -298.394605) (xy 427.683313 -298.438182) (xy 427.653748 -298.477526)
			(xy 427.618255 -298.511618) (xy 427.577752 -298.539574) (xy 427.53329 -298.560672) (xy 427.486019 -298.574364)
			(xy 427.437164 -298.580296) (xy 427.387989 -298.578315) (xy 427.33977 -298.568471) (xy 427.293754 -298.551019)
			(xy 427.251133 -298.526412) (xy 427.213012 -298.495287) (xy 427.180377 -298.45845) (xy 427.154074 -298.416854)
			(xy 427.134783 -298.371578) (xy 427.123006 -298.323794) (xy 427.119046 -298.27474) (xy 426.780198 -298.27474)
			(xy 426.779703 -298.299347) (xy 426.771808 -298.347924) (xy 426.756224 -298.394605) (xy 426.733353 -298.438182)
			(xy 426.703788 -298.477526) (xy 426.668295 -298.511618) (xy 426.627792 -298.539574) (xy 426.58333 -298.560672)
			(xy 426.536059 -298.574364) (xy 426.487204 -298.580296) (xy 426.438029 -298.578315) (xy 426.38981 -298.568471)
			(xy 426.343794 -298.551019) (xy 426.301173 -298.526412) (xy 426.263052 -298.495287) (xy 426.230417 -298.45845)
			(xy 426.204114 -298.416854) (xy 426.184823 -298.371578) (xy 426.173046 -298.323794) (xy 426.169086 -298.27474)
			(xy 425.830238 -298.27474) (xy 425.829743 -298.299347) (xy 425.821848 -298.347924) (xy 425.806264 -298.394605)
			(xy 425.783393 -298.438182) (xy 425.753828 -298.477526) (xy 425.718335 -298.511618) (xy 425.677832 -298.539574)
			(xy 425.63337 -298.560672) (xy 425.586099 -298.574364) (xy 425.537244 -298.580296) (xy 425.488069 -298.578315)
			(xy 425.43985 -298.568471) (xy 425.393834 -298.551019) (xy 425.351213 -298.526412) (xy 425.313092 -298.495287)
			(xy 425.280457 -298.45845) (xy 425.254154 -298.416854) (xy 425.234863 -298.371578) (xy 425.223086 -298.323794)
			(xy 425.219126 -298.27474) (xy 424.880278 -298.27474) (xy 424.879783 -298.299347) (xy 424.871888 -298.347924)
			(xy 424.856304 -298.394605) (xy 424.833433 -298.438182) (xy 424.803868 -298.477526) (xy 424.768375 -298.511618)
			(xy 424.727872 -298.539574) (xy 424.68341 -298.560672) (xy 424.636139 -298.574364) (xy 424.587284 -298.580296)
			(xy 424.538109 -298.578315) (xy 424.48989 -298.568471) (xy 424.443874 -298.551019) (xy 424.401253 -298.526412)
			(xy 424.363132 -298.495287) (xy 424.330497 -298.45845) (xy 424.304194 -298.416854) (xy 424.284903 -298.371578)
			(xy 424.273126 -298.323794) (xy 424.269166 -298.27474) (xy 423.930318 -298.27474) (xy 423.929823 -298.299347)
			(xy 423.921928 -298.347924) (xy 423.906344 -298.394605) (xy 423.883473 -298.438182) (xy 423.853908 -298.477526)
			(xy 423.818415 -298.511618) (xy 423.777912 -298.539574) (xy 423.73345 -298.560672) (xy 423.686179 -298.574364)
			(xy 423.637324 -298.580296) (xy 423.588149 -298.578315) (xy 423.53993 -298.568471) (xy 423.493914 -298.551019)
			(xy 423.451293 -298.526412) (xy 423.413172 -298.495287) (xy 423.380537 -298.45845) (xy 423.354234 -298.416854)
			(xy 423.334943 -298.371578) (xy 423.323166 -298.323794) (xy 423.319206 -298.27474) (xy 422.980104 -298.27474)
			(xy 422.979609 -298.299347) (xy 422.971714 -298.347924) (xy 422.95613 -298.394605) (xy 422.933259 -298.438182)
			(xy 422.903694 -298.477526) (xy 422.868201 -298.511618) (xy 422.827698 -298.539574) (xy 422.783236 -298.560672)
			(xy 422.735965 -298.574364) (xy 422.68711 -298.580296) (xy 422.637935 -298.578315) (xy 422.589716 -298.568471)
			(xy 422.5437 -298.551019) (xy 422.501079 -298.526412) (xy 422.462958 -298.495287) (xy 422.430323 -298.45845)
			(xy 422.40402 -298.416854) (xy 422.384729 -298.371578) (xy 422.372952 -298.323794) (xy 422.368992 -298.27474)
			(xy 422.030144 -298.27474) (xy 422.029649 -298.299347) (xy 422.021754 -298.347924) (xy 422.00617 -298.394605)
			(xy 421.983299 -298.438182) (xy 421.953734 -298.477526) (xy 421.918241 -298.511618) (xy 421.877738 -298.539574)
			(xy 421.833276 -298.560672) (xy 421.786005 -298.574364) (xy 421.73715 -298.580296) (xy 421.687975 -298.578315)
			(xy 421.639756 -298.568471) (xy 421.59374 -298.551019) (xy 421.551119 -298.526412) (xy 421.512998 -298.495287)
			(xy 421.480363 -298.45845) (xy 421.45406 -298.416854) (xy 421.434769 -298.371578) (xy 421.422992 -298.323794)
			(xy 421.419032 -298.27474) (xy 421.080184 -298.27474) (xy 421.079689 -298.299347) (xy 421.071794 -298.347924)
			(xy 421.05621 -298.394605) (xy 421.033339 -298.438182) (xy 421.003774 -298.477526) (xy 420.968281 -298.511618)
			(xy 420.927778 -298.539574) (xy 420.883316 -298.560672) (xy 420.836045 -298.574364) (xy 420.78719 -298.580296)
			(xy 420.738015 -298.578315) (xy 420.689796 -298.568471) (xy 420.64378 -298.551019) (xy 420.601159 -298.526412)
			(xy 420.563038 -298.495287) (xy 420.530403 -298.45845) (xy 420.5041 -298.416854) (xy 420.484809 -298.371578)
			(xy 420.473032 -298.323794) (xy 420.469072 -298.27474) (xy 420.130224 -298.27474) (xy 420.129729 -298.299347)
			(xy 420.121834 -298.347924) (xy 420.10625 -298.394605) (xy 420.083379 -298.438182) (xy 420.053814 -298.477526)
			(xy 420.018321 -298.511618) (xy 419.977818 -298.539574) (xy 419.933356 -298.560672) (xy 419.886085 -298.574364)
			(xy 419.83723 -298.580296) (xy 419.788055 -298.578315) (xy 419.739836 -298.568471) (xy 419.69382 -298.551019)
			(xy 419.651199 -298.526412) (xy 419.613078 -298.495287) (xy 419.580443 -298.45845) (xy 419.55414 -298.416854)
			(xy 419.534849 -298.371578) (xy 419.523072 -298.323794) (xy 419.519112 -298.27474) (xy 418.230304 -298.27474)
			(xy 418.229809 -298.299347) (xy 418.221914 -298.347924) (xy 418.20633 -298.394605) (xy 418.183459 -298.438182)
			(xy 418.153894 -298.477526) (xy 418.118401 -298.511618) (xy 418.077898 -298.539574) (xy 418.033436 -298.560672)
			(xy 417.986165 -298.574364) (xy 417.93731 -298.580296) (xy 417.888135 -298.578315) (xy 417.839916 -298.568471)
			(xy 417.7939 -298.551019) (xy 417.751279 -298.526412) (xy 417.713158 -298.495287) (xy 417.680523 -298.45845)
			(xy 417.65422 -298.416854) (xy 417.634929 -298.371578) (xy 417.623152 -298.323794) (xy 417.619192 -298.27474)
			(xy 417.28009 -298.27474) (xy 417.279595 -298.299347) (xy 417.2717 -298.347924) (xy 417.256116 -298.394605)
			(xy 417.233245 -298.438182) (xy 417.20368 -298.477526) (xy 417.168187 -298.511618) (xy 417.127684 -298.539574)
			(xy 417.083222 -298.560672) (xy 417.035951 -298.574364) (xy 416.987096 -298.580296) (xy 416.937921 -298.578315)
			(xy 416.889702 -298.568471) (xy 416.843686 -298.551019) (xy 416.801065 -298.526412) (xy 416.762944 -298.495287)
			(xy 416.730309 -298.45845) (xy 416.704006 -298.416854) (xy 416.684715 -298.371578) (xy 416.672938 -298.323794)
			(xy 416.668978 -298.27474) (xy 416.33013 -298.27474) (xy 416.329635 -298.299347) (xy 416.32174 -298.347924)
			(xy 416.306156 -298.394605) (xy 416.283285 -298.438182) (xy 416.25372 -298.477526) (xy 416.218227 -298.511618)
			(xy 416.177724 -298.539574) (xy 416.133262 -298.560672) (xy 416.085991 -298.574364) (xy 416.037136 -298.580296)
			(xy 415.987961 -298.578315) (xy 415.939742 -298.568471) (xy 415.893726 -298.551019) (xy 415.851105 -298.526412)
			(xy 415.812984 -298.495287) (xy 415.780349 -298.45845) (xy 415.754046 -298.416854) (xy 415.734755 -298.371578)
			(xy 415.722978 -298.323794) (xy 415.719018 -298.27474) (xy 415.38017 -298.27474) (xy 415.379675 -298.299347)
			(xy 415.37178 -298.347924) (xy 415.356196 -298.394605) (xy 415.333325 -298.438182) (xy 415.30376 -298.477526)
			(xy 415.268267 -298.511618) (xy 415.227764 -298.539574) (xy 415.183302 -298.560672) (xy 415.136031 -298.574364)
			(xy 415.087176 -298.580296) (xy 415.038001 -298.578315) (xy 414.989782 -298.568471) (xy 414.943766 -298.551019)
			(xy 414.901145 -298.526412) (xy 414.863024 -298.495287) (xy 414.830389 -298.45845) (xy 414.804086 -298.416854)
			(xy 414.784795 -298.371578) (xy 414.773018 -298.323794) (xy 414.769058 -298.27474) (xy 414.43021 -298.27474)
			(xy 414.429715 -298.299347) (xy 414.42182 -298.347924) (xy 414.406236 -298.394605) (xy 414.383365 -298.438182)
			(xy 414.3538 -298.477526) (xy 414.318307 -298.511618) (xy 414.277804 -298.539574) (xy 414.233342 -298.560672)
			(xy 414.186071 -298.574364) (xy 414.137216 -298.580296) (xy 414.088041 -298.578315) (xy 414.039822 -298.568471)
			(xy 413.993806 -298.551019) (xy 413.951185 -298.526412) (xy 413.913064 -298.495287) (xy 413.880429 -298.45845)
			(xy 413.854126 -298.416854) (xy 413.834835 -298.371578) (xy 413.823058 -298.323794) (xy 413.819098 -298.27474)
			(xy 413.48025 -298.27474) (xy 413.479755 -298.299347) (xy 413.47186 -298.347924) (xy 413.456276 -298.394605)
			(xy 413.433405 -298.438182) (xy 413.40384 -298.477526) (xy 413.368347 -298.511618) (xy 413.327844 -298.539574)
			(xy 413.283382 -298.560672) (xy 413.236111 -298.574364) (xy 413.187256 -298.580296) (xy 413.138081 -298.578315)
			(xy 413.089862 -298.568471) (xy 413.043846 -298.551019) (xy 413.001225 -298.526412) (xy 412.963104 -298.495287)
			(xy 412.930469 -298.45845) (xy 412.904166 -298.416854) (xy 412.884875 -298.371578) (xy 412.873098 -298.323794)
			(xy 412.869138 -298.27474) (xy 412.53029 -298.27474) (xy 412.529795 -298.299347) (xy 412.5219 -298.347924)
			(xy 412.506316 -298.394605) (xy 412.483445 -298.438182) (xy 412.45388 -298.477526) (xy 412.418387 -298.511618)
			(xy 412.377884 -298.539574) (xy 412.333422 -298.560672) (xy 412.286151 -298.574364) (xy 412.237296 -298.580296)
			(xy 412.188121 -298.578315) (xy 412.139902 -298.568471) (xy 412.093886 -298.551019) (xy 412.051265 -298.526412)
			(xy 412.013144 -298.495287) (xy 411.980509 -298.45845) (xy 411.954206 -298.416854) (xy 411.934915 -298.371578)
			(xy 411.923138 -298.323794) (xy 411.919178 -298.27474) (xy 411.58033 -298.27474) (xy 411.579835 -298.299347)
			(xy 411.57194 -298.347924) (xy 411.556356 -298.394605) (xy 411.533485 -298.438182) (xy 411.50392 -298.477526)
			(xy 411.468427 -298.511618) (xy 411.427924 -298.539574) (xy 411.383462 -298.560672) (xy 411.336191 -298.574364)
			(xy 411.287336 -298.580296) (xy 411.238161 -298.578315) (xy 411.189942 -298.568471) (xy 411.143926 -298.551019)
			(xy 411.101305 -298.526412) (xy 411.063184 -298.495287) (xy 411.030549 -298.45845) (xy 411.004246 -298.416854)
			(xy 410.984955 -298.371578) (xy 410.973178 -298.323794) (xy 410.969218 -298.27474) (xy 410.630116 -298.27474)
			(xy 410.629621 -298.299347) (xy 410.621726 -298.347924) (xy 410.606142 -298.394605) (xy 410.583271 -298.438182)
			(xy 410.553706 -298.477526) (xy 410.518213 -298.511618) (xy 410.47771 -298.539574) (xy 410.433248 -298.560672)
			(xy 410.385977 -298.574364) (xy 410.337122 -298.580296) (xy 410.287947 -298.578315) (xy 410.239728 -298.568471)
			(xy 410.193712 -298.551019) (xy 410.151091 -298.526412) (xy 410.11297 -298.495287) (xy 410.080335 -298.45845)
			(xy 410.054032 -298.416854) (xy 410.034741 -298.371578) (xy 410.022964 -298.323794) (xy 410.019004 -298.27474)
			(xy 409.680156 -298.27474) (xy 409.679661 -298.299347) (xy 409.671766 -298.347924) (xy 409.656182 -298.394605)
			(xy 409.633311 -298.438182) (xy 409.603746 -298.477526) (xy 409.568253 -298.511618) (xy 409.52775 -298.539574)
			(xy 409.483288 -298.560672) (xy 409.436017 -298.574364) (xy 409.387162 -298.580296) (xy 409.337987 -298.578315)
			(xy 409.289768 -298.568471) (xy 409.243752 -298.551019) (xy 409.201131 -298.526412) (xy 409.16301 -298.495287)
			(xy 409.130375 -298.45845) (xy 409.104072 -298.416854) (xy 409.084781 -298.371578) (xy 409.073004 -298.323794)
			(xy 409.069044 -298.27474) (xy 408.730196 -298.27474) (xy 408.729701 -298.299347) (xy 408.721806 -298.347924)
			(xy 408.706222 -298.394605) (xy 408.683351 -298.438182) (xy 408.653786 -298.477526) (xy 408.618293 -298.511618)
			(xy 408.57779 -298.539574) (xy 408.533328 -298.560672) (xy 408.486057 -298.574364) (xy 408.437202 -298.580296)
			(xy 408.388027 -298.578315) (xy 408.339808 -298.568471) (xy 408.293792 -298.551019) (xy 408.251171 -298.526412)
			(xy 408.21305 -298.495287) (xy 408.180415 -298.45845) (xy 408.154112 -298.416854) (xy 408.134821 -298.371578)
			(xy 408.123044 -298.323794) (xy 408.119084 -298.27474) (xy 406.830276 -298.27474) (xy 406.829781 -298.299347)
			(xy 406.821886 -298.347924) (xy 406.806302 -298.394605) (xy 406.783431 -298.438182) (xy 406.753866 -298.477526)
			(xy 406.718373 -298.511618) (xy 406.67787 -298.539574) (xy 406.633408 -298.560672) (xy 406.586137 -298.574364)
			(xy 406.537282 -298.580296) (xy 406.488107 -298.578315) (xy 406.439888 -298.568471) (xy 406.393872 -298.551019)
			(xy 406.351251 -298.526412) (xy 406.31313 -298.495287) (xy 406.280495 -298.45845) (xy 406.254192 -298.416854)
			(xy 406.234901 -298.371578) (xy 406.223124 -298.323794) (xy 406.219164 -298.27474) (xy 405.880316 -298.27474)
			(xy 405.879821 -298.299347) (xy 405.871926 -298.347924) (xy 405.856342 -298.394605) (xy 405.833471 -298.438182)
			(xy 405.803906 -298.477526) (xy 405.768413 -298.511618) (xy 405.72791 -298.539574) (xy 405.683448 -298.560672)
			(xy 405.636177 -298.574364) (xy 405.587322 -298.580296) (xy 405.538147 -298.578315) (xy 405.489928 -298.568471)
			(xy 405.443912 -298.551019) (xy 405.401291 -298.526412) (xy 405.36317 -298.495287) (xy 405.330535 -298.45845)
			(xy 405.304232 -298.416854) (xy 405.284941 -298.371578) (xy 405.273164 -298.323794) (xy 405.269204 -298.27474)
			(xy 404.930102 -298.27474) (xy 404.929607 -298.299347) (xy 404.921712 -298.347924) (xy 404.906128 -298.394605)
			(xy 404.883257 -298.438182) (xy 404.853692 -298.477526) (xy 404.818199 -298.511618) (xy 404.777696 -298.539574)
			(xy 404.733234 -298.560672) (xy 404.685963 -298.574364) (xy 404.637108 -298.580296) (xy 404.587933 -298.578315)
			(xy 404.539714 -298.568471) (xy 404.493698 -298.551019) (xy 404.451077 -298.526412) (xy 404.412956 -298.495287)
			(xy 404.380321 -298.45845) (xy 404.354018 -298.416854) (xy 404.334727 -298.371578) (xy 404.32295 -298.323794)
			(xy 404.31899 -298.27474) (xy 403.980142 -298.27474) (xy 403.979647 -298.299347) (xy 403.971752 -298.347924)
			(xy 403.956168 -298.394605) (xy 403.933297 -298.438182) (xy 403.903732 -298.477526) (xy 403.868239 -298.511618)
			(xy 403.827736 -298.539574) (xy 403.783274 -298.560672) (xy 403.736003 -298.574364) (xy 403.687148 -298.580296)
			(xy 403.637973 -298.578315) (xy 403.589754 -298.568471) (xy 403.543738 -298.551019) (xy 403.501117 -298.526412)
			(xy 403.462996 -298.495287) (xy 403.430361 -298.45845) (xy 403.404058 -298.416854) (xy 403.384767 -298.371578)
			(xy 403.37299 -298.323794) (xy 403.36903 -298.27474) (xy 403.030182 -298.27474) (xy 403.029687 -298.299347)
			(xy 403.021792 -298.347924) (xy 403.006208 -298.394605) (xy 402.983337 -298.438182) (xy 402.953772 -298.477526)
			(xy 402.918279 -298.511618) (xy 402.877776 -298.539574) (xy 402.833314 -298.560672) (xy 402.786043 -298.574364)
			(xy 402.737188 -298.580296) (xy 402.688013 -298.578315) (xy 402.639794 -298.568471) (xy 402.593778 -298.551019)
			(xy 402.551157 -298.526412) (xy 402.513036 -298.495287) (xy 402.480401 -298.45845) (xy 402.454098 -298.416854)
			(xy 402.434807 -298.371578) (xy 402.42303 -298.323794) (xy 402.41907 -298.27474) (xy 402.080222 -298.27474)
			(xy 402.079727 -298.299347) (xy 402.071832 -298.347924) (xy 402.056248 -298.394605) (xy 402.033377 -298.438182)
			(xy 402.003812 -298.477526) (xy 401.968319 -298.511618) (xy 401.927816 -298.539574) (xy 401.883354 -298.560672)
			(xy 401.836083 -298.574364) (xy 401.787228 -298.580296) (xy 401.738053 -298.578315) (xy 401.689834 -298.568471)
			(xy 401.643818 -298.551019) (xy 401.601197 -298.526412) (xy 401.563076 -298.495287) (xy 401.530441 -298.45845)
			(xy 401.504138 -298.416854) (xy 401.484847 -298.371578) (xy 401.47307 -298.323794) (xy 401.46911 -298.27474)
			(xy 401.130262 -298.27474) (xy 401.129767 -298.299347) (xy 401.121872 -298.347924) (xy 401.106288 -298.394605)
			(xy 401.083417 -298.438182) (xy 401.053852 -298.477526) (xy 401.018359 -298.511618) (xy 400.977856 -298.539574)
			(xy 400.933394 -298.560672) (xy 400.886123 -298.574364) (xy 400.837268 -298.580296) (xy 400.788093 -298.578315)
			(xy 400.739874 -298.568471) (xy 400.693858 -298.551019) (xy 400.651237 -298.526412) (xy 400.613116 -298.495287)
			(xy 400.580481 -298.45845) (xy 400.554178 -298.416854) (xy 400.534887 -298.371578) (xy 400.52311 -298.323794)
			(xy 400.51915 -298.27474) (xy 400.180302 -298.27474) (xy 400.179807 -298.299347) (xy 400.171912 -298.347924)
			(xy 400.156328 -298.394605) (xy 400.133457 -298.438182) (xy 400.103892 -298.477526) (xy 400.068399 -298.511618)
			(xy 400.027896 -298.539574) (xy 399.983434 -298.560672) (xy 399.936163 -298.574364) (xy 399.887308 -298.580296)
			(xy 399.838133 -298.578315) (xy 399.789914 -298.568471) (xy 399.743898 -298.551019) (xy 399.701277 -298.526412)
			(xy 399.663156 -298.495287) (xy 399.630521 -298.45845) (xy 399.604218 -298.416854) (xy 399.584927 -298.371578)
			(xy 399.57315 -298.323794) (xy 399.56919 -298.27474) (xy 399.230342 -298.27474) (xy 399.229847 -298.299347)
			(xy 399.221952 -298.347924) (xy 399.206368 -298.394605) (xy 399.183497 -298.438182) (xy 399.153932 -298.477526)
			(xy 399.118439 -298.511618) (xy 399.077936 -298.539574) (xy 399.033474 -298.560672) (xy 398.986203 -298.574364)
			(xy 398.937348 -298.580296) (xy 398.888173 -298.578315) (xy 398.839954 -298.568471) (xy 398.793938 -298.551019)
			(xy 398.751317 -298.526412) (xy 398.713196 -298.495287) (xy 398.680561 -298.45845) (xy 398.654258 -298.416854)
			(xy 398.634967 -298.371578) (xy 398.62319 -298.323794) (xy 398.61923 -298.27474) (xy 398.280128 -298.27474)
			(xy 398.279633 -298.299347) (xy 398.271738 -298.347924) (xy 398.256154 -298.394605) (xy 398.233283 -298.438182)
			(xy 398.203718 -298.477526) (xy 398.168225 -298.511618) (xy 398.127722 -298.539574) (xy 398.08326 -298.560672)
			(xy 398.035989 -298.574364) (xy 397.987134 -298.580296) (xy 397.937959 -298.578315) (xy 397.88974 -298.568471)
			(xy 397.843724 -298.551019) (xy 397.801103 -298.526412) (xy 397.762982 -298.495287) (xy 397.730347 -298.45845)
			(xy 397.704044 -298.416854) (xy 397.684753 -298.371578) (xy 397.672976 -298.323794) (xy 397.669016 -298.27474)
			(xy 397.355107 -298.27474) (xy 397.355107 -298.301064) (xy 397.346743 -298.353113) (xy 397.330228 -298.403177)
			(xy 397.30598 -298.449987) (xy 397.274614 -298.492357) (xy 397.236923 -298.529215) (xy 397.193863 -298.559627)
			(xy 397.146523 -298.582822) (xy 397.096103 -298.598215) (xy 397.070072 -298.6024) (xy 397.066008 -298.602908)
			(xy 397.054578 -298.606464) (xy 397.05026 -298.607734) (xy 397.02613 -298.61891) (xy 397.019526 -298.626022)
			(xy 397.004794 -298.641516) (xy 396.996666 -298.652692) (xy 396.993973 -298.658224) (xy 396.991023 -298.670164)
			(xy 396.990824 -298.676314) (xy 396.990824 -298.713652) (xy 434.780688 -298.713652) (xy 434.784759 -298.65803)
			(xy 434.796885 -298.603593) (xy 434.816808 -298.551502) (xy 434.844104 -298.502867) (xy 434.87819 -298.458724)
			(xy 434.918339 -298.420015) (xy 434.963697 -298.387564) (xy 435.013297 -298.362063) (xy 435.066081 -298.344056)
			(xy 435.120924 -298.333926) (xy 435.176658 -298.331889) (xy 435.232095 -298.337989) (xy 435.286052 -298.352095)
			(xy 435.337381 -298.373907) (xy 435.384987 -298.402961) (xy 435.427855 -298.438636) (xy 435.465072 -298.480173)
			(xy 435.495845 -298.526686) (xy 435.519517 -298.577183) (xy 435.535585 -298.63059) (xy 435.543705 -298.685766)
			(xy 435.544214 -298.713652) (xy 435.543705 -298.741538) (xy 435.535585 -298.796714) (xy 435.519517 -298.850121)
			(xy 435.495845 -298.900618) (xy 435.465072 -298.947131) (xy 435.427855 -298.988668) (xy 435.384987 -299.024343)
			(xy 435.337381 -299.053397) (xy 435.286052 -299.075209) (xy 435.232095 -299.089315) (xy 435.176658 -299.095415)
			(xy 435.120924 -299.093378) (xy 435.066081 -299.083248) (xy 435.013297 -299.065241) (xy 434.963697 -299.03974)
			(xy 434.918339 -299.007289) (xy 434.87819 -298.96858) (xy 434.844104 -298.924437) (xy 434.816808 -298.875802)
			(xy 434.796885 -298.823711) (xy 434.784759 -298.769274) (xy 434.780688 -298.713652) (xy 396.990824 -298.713652)
			(xy 396.990824 -298.82338) (xy 396.990995 -298.829533) (xy 396.99395 -298.841478) (xy 396.996666 -298.847002)
			(xy 397.004794 -298.858178) (xy 397.019526 -298.873672) (xy 397.02613 -298.880784) (xy 397.05026 -298.89196)
			(xy 397.054578 -298.89323) (xy 397.066008 -298.896786) (xy 397.070072 -298.897294) (xy 397.09612 -298.901402)
			(xy 397.146553 -298.916798) (xy 397.193905 -298.94) (xy 397.236977 -298.970419) (xy 397.274678 -299.007287)
			(xy 397.306052 -299.049668) (xy 397.330306 -299.096489) (xy 397.346825 -299.146566) (xy 397.355192 -299.198628)
			(xy 397.355192 -299.224954) (xy 397.669016 -299.224954) (xy 397.672976 -299.1759) (xy 397.684753 -299.128116)
			(xy 397.704044 -299.08284) (xy 397.730347 -299.041244) (xy 397.762982 -299.004407) (xy 397.801103 -298.973282)
			(xy 397.843724 -298.948675) (xy 397.88974 -298.931223) (xy 397.937959 -298.921379) (xy 397.987134 -298.919398)
			(xy 398.035989 -298.92533) (xy 398.08326 -298.939022) (xy 398.127722 -298.96012) (xy 398.168225 -298.988076)
			(xy 398.203718 -299.022168) (xy 398.233283 -299.061512) (xy 398.256154 -299.105089) (xy 398.271738 -299.15177)
			(xy 398.279633 -299.200347) (xy 398.280128 -299.224954) (xy 398.61923 -299.224954) (xy 398.62319 -299.1759)
			(xy 398.634967 -299.128116) (xy 398.654258 -299.08284) (xy 398.680561 -299.041244) (xy 398.713196 -299.004407)
			(xy 398.751317 -298.973282) (xy 398.793938 -298.948675) (xy 398.839954 -298.931223) (xy 398.888173 -298.921379)
			(xy 398.937348 -298.919398) (xy 398.986203 -298.92533) (xy 399.033474 -298.939022) (xy 399.077936 -298.96012)
			(xy 399.118439 -298.988076) (xy 399.153932 -299.022168) (xy 399.183497 -299.061512) (xy 399.206368 -299.105089)
			(xy 399.221952 -299.15177) (xy 399.229847 -299.200347) (xy 399.230342 -299.224954) (xy 399.56919 -299.224954)
			(xy 399.57315 -299.1759) (xy 399.584927 -299.128116) (xy 399.604218 -299.08284) (xy 399.630521 -299.041244)
			(xy 399.663156 -299.004407) (xy 399.701277 -298.973282) (xy 399.743898 -298.948675) (xy 399.789914 -298.931223)
			(xy 399.838133 -298.921379) (xy 399.887308 -298.919398) (xy 399.936163 -298.92533) (xy 399.983434 -298.939022)
			(xy 400.027896 -298.96012) (xy 400.068399 -298.988076) (xy 400.103892 -299.022168) (xy 400.133457 -299.061512)
			(xy 400.156328 -299.105089) (xy 400.171912 -299.15177) (xy 400.179807 -299.200347) (xy 400.180302 -299.224954)
			(xy 400.51915 -299.224954) (xy 400.52311 -299.1759) (xy 400.534887 -299.128116) (xy 400.554178 -299.08284)
			(xy 400.580481 -299.041244) (xy 400.613116 -299.004407) (xy 400.651237 -298.973282) (xy 400.693858 -298.948675)
			(xy 400.739874 -298.931223) (xy 400.788093 -298.921379) (xy 400.837268 -298.919398) (xy 400.886123 -298.92533)
			(xy 400.933394 -298.939022) (xy 400.977856 -298.96012) (xy 401.018359 -298.988076) (xy 401.053852 -299.022168)
			(xy 401.083417 -299.061512) (xy 401.106288 -299.105089) (xy 401.121872 -299.15177) (xy 401.129767 -299.200347)
			(xy 401.130262 -299.224954) (xy 401.46911 -299.224954) (xy 401.47307 -299.1759) (xy 401.484847 -299.128116)
			(xy 401.504138 -299.08284) (xy 401.530441 -299.041244) (xy 401.563076 -299.004407) (xy 401.601197 -298.973282)
			(xy 401.643818 -298.948675) (xy 401.689834 -298.931223) (xy 401.738053 -298.921379) (xy 401.787228 -298.919398)
			(xy 401.836083 -298.92533) (xy 401.883354 -298.939022) (xy 401.927816 -298.96012) (xy 401.968319 -298.988076)
			(xy 402.003812 -299.022168) (xy 402.033377 -299.061512) (xy 402.056248 -299.105089) (xy 402.071832 -299.15177)
			(xy 402.079727 -299.200347) (xy 402.080222 -299.224954) (xy 402.41907 -299.224954) (xy 402.42303 -299.1759)
			(xy 402.434807 -299.128116) (xy 402.454098 -299.08284) (xy 402.480401 -299.041244) (xy 402.513036 -299.004407)
			(xy 402.551157 -298.973282) (xy 402.593778 -298.948675) (xy 402.639794 -298.931223) (xy 402.688013 -298.921379)
			(xy 402.737188 -298.919398) (xy 402.786043 -298.92533) (xy 402.833314 -298.939022) (xy 402.877776 -298.96012)
			(xy 402.918279 -298.988076) (xy 402.953772 -299.022168) (xy 402.983337 -299.061512) (xy 403.006208 -299.105089)
			(xy 403.021792 -299.15177) (xy 403.029687 -299.200347) (xy 403.030182 -299.224954) (xy 403.36903 -299.224954)
			(xy 403.37299 -299.1759) (xy 403.384767 -299.128116) (xy 403.404058 -299.08284) (xy 403.430361 -299.041244)
			(xy 403.462996 -299.004407) (xy 403.501117 -298.973282) (xy 403.543738 -298.948675) (xy 403.589754 -298.931223)
			(xy 403.637973 -298.921379) (xy 403.687148 -298.919398) (xy 403.736003 -298.92533) (xy 403.783274 -298.939022)
			(xy 403.827736 -298.96012) (xy 403.868239 -298.988076) (xy 403.903732 -299.022168) (xy 403.933297 -299.061512)
			(xy 403.956168 -299.105089) (xy 403.971752 -299.15177) (xy 403.979647 -299.200347) (xy 403.980142 -299.224954)
			(xy 404.31899 -299.224954) (xy 404.32295 -299.1759) (xy 404.334727 -299.128116) (xy 404.354018 -299.08284)
			(xy 404.380321 -299.041244) (xy 404.412956 -299.004407) (xy 404.451077 -298.973282) (xy 404.493698 -298.948675)
			(xy 404.539714 -298.931223) (xy 404.587933 -298.921379) (xy 404.637108 -298.919398) (xy 404.685963 -298.92533)
			(xy 404.733234 -298.939022) (xy 404.777696 -298.96012) (xy 404.818199 -298.988076) (xy 404.853692 -299.022168)
			(xy 404.883257 -299.061512) (xy 404.906128 -299.105089) (xy 404.921712 -299.15177) (xy 404.929607 -299.200347)
			(xy 404.930102 -299.224954) (xy 405.269204 -299.224954) (xy 405.273164 -299.1759) (xy 405.284941 -299.128116)
			(xy 405.304232 -299.08284) (xy 405.330535 -299.041244) (xy 405.36317 -299.004407) (xy 405.401291 -298.973282)
			(xy 405.443912 -298.948675) (xy 405.489928 -298.931223) (xy 405.538147 -298.921379) (xy 405.587322 -298.919398)
			(xy 405.636177 -298.92533) (xy 405.683448 -298.939022) (xy 405.72791 -298.96012) (xy 405.768413 -298.988076)
			(xy 405.803906 -299.022168) (xy 405.833471 -299.061512) (xy 405.856342 -299.105089) (xy 405.871926 -299.15177)
			(xy 405.879821 -299.200347) (xy 405.880316 -299.224954) (xy 406.219164 -299.224954) (xy 406.223124 -299.1759)
			(xy 406.234901 -299.128116) (xy 406.254192 -299.08284) (xy 406.280495 -299.041244) (xy 406.31313 -299.004407)
			(xy 406.351251 -298.973282) (xy 406.393872 -298.948675) (xy 406.439888 -298.931223) (xy 406.488107 -298.921379)
			(xy 406.537282 -298.919398) (xy 406.586137 -298.92533) (xy 406.633408 -298.939022) (xy 406.67787 -298.96012)
			(xy 406.718373 -298.988076) (xy 406.753866 -299.022168) (xy 406.783431 -299.061512) (xy 406.806302 -299.105089)
			(xy 406.821886 -299.15177) (xy 406.829781 -299.200347) (xy 406.830276 -299.224954) (xy 408.119084 -299.224954)
			(xy 408.123044 -299.1759) (xy 408.134821 -299.128116) (xy 408.154112 -299.08284) (xy 408.180415 -299.041244)
			(xy 408.21305 -299.004407) (xy 408.251171 -298.973282) (xy 408.293792 -298.948675) (xy 408.339808 -298.931223)
			(xy 408.388027 -298.921379) (xy 408.437202 -298.919398) (xy 408.486057 -298.92533) (xy 408.533328 -298.939022)
			(xy 408.57779 -298.96012) (xy 408.618293 -298.988076) (xy 408.653786 -299.022168) (xy 408.683351 -299.061512)
			(xy 408.706222 -299.105089) (xy 408.721806 -299.15177) (xy 408.729701 -299.200347) (xy 408.730196 -299.224954)
			(xy 409.069044 -299.224954) (xy 409.073004 -299.1759) (xy 409.084781 -299.128116) (xy 409.104072 -299.08284)
			(xy 409.130375 -299.041244) (xy 409.16301 -299.004407) (xy 409.201131 -298.973282) (xy 409.243752 -298.948675)
			(xy 409.289768 -298.931223) (xy 409.337987 -298.921379) (xy 409.387162 -298.919398) (xy 409.436017 -298.92533)
			(xy 409.483288 -298.939022) (xy 409.52775 -298.96012) (xy 409.568253 -298.988076) (xy 409.603746 -299.022168)
			(xy 409.633311 -299.061512) (xy 409.656182 -299.105089) (xy 409.671766 -299.15177) (xy 409.679661 -299.200347)
			(xy 409.680156 -299.224954) (xy 410.019004 -299.224954) (xy 410.022964 -299.1759) (xy 410.034741 -299.128116)
			(xy 410.054032 -299.08284) (xy 410.080335 -299.041244) (xy 410.11297 -299.004407) (xy 410.151091 -298.973282)
			(xy 410.193712 -298.948675) (xy 410.239728 -298.931223) (xy 410.287947 -298.921379) (xy 410.337122 -298.919398)
			(xy 410.385977 -298.92533) (xy 410.433248 -298.939022) (xy 410.47771 -298.96012) (xy 410.518213 -298.988076)
			(xy 410.553706 -299.022168) (xy 410.583271 -299.061512) (xy 410.606142 -299.105089) (xy 410.621726 -299.15177)
			(xy 410.629621 -299.200347) (xy 410.630116 -299.224954) (xy 410.969218 -299.224954) (xy 410.973178 -299.1759)
			(xy 410.984955 -299.128116) (xy 411.004246 -299.08284) (xy 411.030549 -299.041244) (xy 411.063184 -299.004407)
			(xy 411.101305 -298.973282) (xy 411.143926 -298.948675) (xy 411.189942 -298.931223) (xy 411.238161 -298.921379)
			(xy 411.287336 -298.919398) (xy 411.336191 -298.92533) (xy 411.383462 -298.939022) (xy 411.427924 -298.96012)
			(xy 411.468427 -298.988076) (xy 411.50392 -299.022168) (xy 411.533485 -299.061512) (xy 411.556356 -299.105089)
			(xy 411.57194 -299.15177) (xy 411.579835 -299.200347) (xy 411.58033 -299.224954) (xy 411.919178 -299.224954)
			(xy 411.923138 -299.1759) (xy 411.934915 -299.128116) (xy 411.954206 -299.08284) (xy 411.980509 -299.041244)
			(xy 412.013144 -299.004407) (xy 412.051265 -298.973282) (xy 412.093886 -298.948675) (xy 412.139902 -298.931223)
			(xy 412.188121 -298.921379) (xy 412.237296 -298.919398) (xy 412.286151 -298.92533) (xy 412.333422 -298.939022)
			(xy 412.377884 -298.96012) (xy 412.418387 -298.988076) (xy 412.45388 -299.022168) (xy 412.483445 -299.061512)
			(xy 412.506316 -299.105089) (xy 412.5219 -299.15177) (xy 412.529795 -299.200347) (xy 412.53029 -299.224954)
			(xy 412.869138 -299.224954) (xy 412.873098 -299.1759) (xy 412.884875 -299.128116) (xy 412.904166 -299.08284)
			(xy 412.930469 -299.041244) (xy 412.963104 -299.004407) (xy 413.001225 -298.973282) (xy 413.043846 -298.948675)
			(xy 413.089862 -298.931223) (xy 413.138081 -298.921379) (xy 413.187256 -298.919398) (xy 413.236111 -298.92533)
			(xy 413.283382 -298.939022) (xy 413.327844 -298.96012) (xy 413.368347 -298.988076) (xy 413.40384 -299.022168)
			(xy 413.433405 -299.061512) (xy 413.456276 -299.105089) (xy 413.47186 -299.15177) (xy 413.479755 -299.200347)
			(xy 413.48025 -299.224954) (xy 413.819098 -299.224954) (xy 413.823058 -299.1759) (xy 413.834835 -299.128116)
			(xy 413.854126 -299.08284) (xy 413.880429 -299.041244) (xy 413.913064 -299.004407) (xy 413.951185 -298.973282)
			(xy 413.993806 -298.948675) (xy 414.039822 -298.931223) (xy 414.088041 -298.921379) (xy 414.137216 -298.919398)
			(xy 414.186071 -298.92533) (xy 414.233342 -298.939022) (xy 414.277804 -298.96012) (xy 414.318307 -298.988076)
			(xy 414.3538 -299.022168) (xy 414.383365 -299.061512) (xy 414.406236 -299.105089) (xy 414.42182 -299.15177)
			(xy 414.429715 -299.200347) (xy 414.43021 -299.224954) (xy 414.769058 -299.224954) (xy 414.773018 -299.1759)
			(xy 414.784795 -299.128116) (xy 414.804086 -299.08284) (xy 414.830389 -299.041244) (xy 414.863024 -299.004407)
			(xy 414.901145 -298.973282) (xy 414.943766 -298.948675) (xy 414.989782 -298.931223) (xy 415.038001 -298.921379)
			(xy 415.087176 -298.919398) (xy 415.136031 -298.92533) (xy 415.183302 -298.939022) (xy 415.227764 -298.96012)
			(xy 415.268267 -298.988076) (xy 415.30376 -299.022168) (xy 415.333325 -299.061512) (xy 415.356196 -299.105089)
			(xy 415.37178 -299.15177) (xy 415.379675 -299.200347) (xy 415.38017 -299.224954) (xy 415.719018 -299.224954)
			(xy 415.722978 -299.1759) (xy 415.734755 -299.128116) (xy 415.754046 -299.08284) (xy 415.780349 -299.041244)
			(xy 415.812984 -299.004407) (xy 415.851105 -298.973282) (xy 415.893726 -298.948675) (xy 415.939742 -298.931223)
			(xy 415.987961 -298.921379) (xy 416.037136 -298.919398) (xy 416.085991 -298.92533) (xy 416.133262 -298.939022)
			(xy 416.177724 -298.96012) (xy 416.218227 -298.988076) (xy 416.25372 -299.022168) (xy 416.283285 -299.061512)
			(xy 416.306156 -299.105089) (xy 416.32174 -299.15177) (xy 416.329635 -299.200347) (xy 416.33013 -299.224954)
			(xy 416.668978 -299.224954) (xy 416.672938 -299.1759) (xy 416.684715 -299.128116) (xy 416.704006 -299.08284)
			(xy 416.730309 -299.041244) (xy 416.762944 -299.004407) (xy 416.801065 -298.973282) (xy 416.843686 -298.948675)
			(xy 416.889702 -298.931223) (xy 416.937921 -298.921379) (xy 416.987096 -298.919398) (xy 417.035951 -298.92533)
			(xy 417.083222 -298.939022) (xy 417.127684 -298.96012) (xy 417.168187 -298.988076) (xy 417.20368 -299.022168)
			(xy 417.233245 -299.061512) (xy 417.256116 -299.105089) (xy 417.2717 -299.15177) (xy 417.279595 -299.200347)
			(xy 417.28009 -299.224954) (xy 417.619192 -299.224954) (xy 417.623152 -299.1759) (xy 417.634929 -299.128116)
			(xy 417.65422 -299.08284) (xy 417.680523 -299.041244) (xy 417.713158 -299.004407) (xy 417.751279 -298.973282)
			(xy 417.7939 -298.948675) (xy 417.839916 -298.931223) (xy 417.888135 -298.921379) (xy 417.93731 -298.919398)
			(xy 417.986165 -298.92533) (xy 418.033436 -298.939022) (xy 418.077898 -298.96012) (xy 418.118401 -298.988076)
			(xy 418.153894 -299.022168) (xy 418.183459 -299.061512) (xy 418.20633 -299.105089) (xy 418.221914 -299.15177)
			(xy 418.229809 -299.200347) (xy 418.230304 -299.224954) (xy 418.569152 -299.224954) (xy 418.573112 -299.1759)
			(xy 418.584889 -299.128116) (xy 418.60418 -299.08284) (xy 418.630483 -299.041244) (xy 418.663118 -299.004407)
			(xy 418.701239 -298.973282) (xy 418.74386 -298.948675) (xy 418.789876 -298.931223) (xy 418.838095 -298.921379)
			(xy 418.88727 -298.919398) (xy 418.936125 -298.92533) (xy 418.983396 -298.939022) (xy 419.027858 -298.96012)
			(xy 419.068361 -298.988076) (xy 419.103854 -299.022168) (xy 419.133419 -299.061512) (xy 419.15629 -299.105089)
			(xy 419.171874 -299.15177) (xy 419.179769 -299.200347) (xy 419.180264 -299.224954) (xy 419.519112 -299.224954)
			(xy 419.523072 -299.1759) (xy 419.534849 -299.128116) (xy 419.55414 -299.08284) (xy 419.580443 -299.041244)
			(xy 419.613078 -299.004407) (xy 419.651199 -298.973282) (xy 419.69382 -298.948675) (xy 419.739836 -298.931223)
			(xy 419.788055 -298.921379) (xy 419.83723 -298.919398) (xy 419.886085 -298.92533) (xy 419.933356 -298.939022)
			(xy 419.977818 -298.96012) (xy 420.018321 -298.988076) (xy 420.053814 -299.022168) (xy 420.083379 -299.061512)
			(xy 420.10625 -299.105089) (xy 420.121834 -299.15177) (xy 420.129729 -299.200347) (xy 420.130224 -299.224954)
			(xy 420.469072 -299.224954) (xy 420.473032 -299.1759) (xy 420.484809 -299.128116) (xy 420.5041 -299.08284)
			(xy 420.530403 -299.041244) (xy 420.563038 -299.004407) (xy 420.601159 -298.973282) (xy 420.64378 -298.948675)
			(xy 420.689796 -298.931223) (xy 420.738015 -298.921379) (xy 420.78719 -298.919398) (xy 420.836045 -298.92533)
			(xy 420.883316 -298.939022) (xy 420.927778 -298.96012) (xy 420.968281 -298.988076) (xy 421.003774 -299.022168)
			(xy 421.033339 -299.061512) (xy 421.05621 -299.105089) (xy 421.071794 -299.15177) (xy 421.079689 -299.200347)
			(xy 421.080184 -299.224954) (xy 421.419032 -299.224954) (xy 421.422992 -299.1759) (xy 421.434769 -299.128116)
			(xy 421.45406 -299.08284) (xy 421.480363 -299.041244) (xy 421.512998 -299.004407) (xy 421.551119 -298.973282)
			(xy 421.59374 -298.948675) (xy 421.639756 -298.931223) (xy 421.687975 -298.921379) (xy 421.73715 -298.919398)
			(xy 421.786005 -298.92533) (xy 421.833276 -298.939022) (xy 421.877738 -298.96012) (xy 421.918241 -298.988076)
			(xy 421.953734 -299.022168) (xy 421.983299 -299.061512) (xy 422.00617 -299.105089) (xy 422.021754 -299.15177)
			(xy 422.029649 -299.200347) (xy 422.030144 -299.224954) (xy 424.269166 -299.224954) (xy 424.273126 -299.1759)
			(xy 424.284903 -299.128116) (xy 424.304194 -299.08284) (xy 424.330497 -299.041244) (xy 424.363132 -299.004407)
			(xy 424.401253 -298.973282) (xy 424.443874 -298.948675) (xy 424.48989 -298.931223) (xy 424.538109 -298.921379)
			(xy 424.587284 -298.919398) (xy 424.636139 -298.92533) (xy 424.68341 -298.939022) (xy 424.727872 -298.96012)
			(xy 424.768375 -298.988076) (xy 424.803868 -299.022168) (xy 424.833433 -299.061512) (xy 424.856304 -299.105089)
			(xy 424.871888 -299.15177) (xy 424.879783 -299.200347) (xy 424.880278 -299.224954) (xy 425.219126 -299.224954)
			(xy 425.223086 -299.1759) (xy 425.234863 -299.128116) (xy 425.254154 -299.08284) (xy 425.280457 -299.041244)
			(xy 425.313092 -299.004407) (xy 425.351213 -298.973282) (xy 425.393834 -298.948675) (xy 425.43985 -298.931223)
			(xy 425.488069 -298.921379) (xy 425.537244 -298.919398) (xy 425.586099 -298.92533) (xy 425.63337 -298.939022)
			(xy 425.677832 -298.96012) (xy 425.718335 -298.988076) (xy 425.753828 -299.022168) (xy 425.783393 -299.061512)
			(xy 425.806264 -299.105089) (xy 425.821848 -299.15177) (xy 425.829743 -299.200347) (xy 425.830238 -299.224954)
			(xy 426.169086 -299.224954) (xy 426.173046 -299.1759) (xy 426.184823 -299.128116) (xy 426.204114 -299.08284)
			(xy 426.230417 -299.041244) (xy 426.263052 -299.004407) (xy 426.301173 -298.973282) (xy 426.343794 -298.948675)
			(xy 426.38981 -298.931223) (xy 426.438029 -298.921379) (xy 426.487204 -298.919398) (xy 426.536059 -298.92533)
			(xy 426.58333 -298.939022) (xy 426.627792 -298.96012) (xy 426.668295 -298.988076) (xy 426.703788 -299.022168)
			(xy 426.733353 -299.061512) (xy 426.756224 -299.105089) (xy 426.771808 -299.15177) (xy 426.779703 -299.200347)
			(xy 426.780198 -299.224954) (xy 427.119046 -299.224954) (xy 427.123006 -299.1759) (xy 427.134783 -299.128116)
			(xy 427.154074 -299.08284) (xy 427.180377 -299.041244) (xy 427.213012 -299.004407) (xy 427.251133 -298.973282)
			(xy 427.293754 -298.948675) (xy 427.33977 -298.931223) (xy 427.387989 -298.921379) (xy 427.437164 -298.919398)
			(xy 427.486019 -298.92533) (xy 427.53329 -298.939022) (xy 427.577752 -298.96012) (xy 427.618255 -298.988076)
			(xy 427.653748 -299.022168) (xy 427.683313 -299.061512) (xy 427.706184 -299.105089) (xy 427.721768 -299.15177)
			(xy 427.729663 -299.200347) (xy 427.730158 -299.224954) (xy 428.069006 -299.224954) (xy 428.072966 -299.1759)
			(xy 428.084743 -299.128116) (xy 428.104034 -299.08284) (xy 428.130337 -299.041244) (xy 428.162972 -299.004407)
			(xy 428.201093 -298.973282) (xy 428.243714 -298.948675) (xy 428.28973 -298.931223) (xy 428.337949 -298.921379)
			(xy 428.387124 -298.919398) (xy 428.435979 -298.92533) (xy 428.48325 -298.939022) (xy 428.527712 -298.96012)
			(xy 428.568215 -298.988076) (xy 428.603708 -299.022168) (xy 428.633273 -299.061512) (xy 428.656144 -299.105089)
			(xy 428.671728 -299.15177) (xy 428.679623 -299.200347) (xy 428.680118 -299.224954) (xy 429.01922 -299.224954)
			(xy 429.02318 -299.1759) (xy 429.034957 -299.128116) (xy 429.054248 -299.08284) (xy 429.080551 -299.041244)
			(xy 429.113186 -299.004407) (xy 429.151307 -298.973282) (xy 429.193928 -298.948675) (xy 429.239944 -298.931223)
			(xy 429.288163 -298.921379) (xy 429.337338 -298.919398) (xy 429.386193 -298.92533) (xy 429.433464 -298.939022)
			(xy 429.477926 -298.96012) (xy 429.518429 -298.988076) (xy 429.553922 -299.022168) (xy 429.583487 -299.061512)
			(xy 429.606358 -299.105089) (xy 429.621942 -299.15177) (xy 429.629837 -299.200347) (xy 429.630332 -299.224954)
			(xy 429.96918 -299.224954) (xy 429.97314 -299.1759) (xy 429.984917 -299.128116) (xy 430.004208 -299.08284)
			(xy 430.030511 -299.041244) (xy 430.063146 -299.004407) (xy 430.101267 -298.973282) (xy 430.143888 -298.948675)
			(xy 430.189904 -298.931223) (xy 430.238123 -298.921379) (xy 430.287298 -298.919398) (xy 430.336153 -298.92533)
			(xy 430.383424 -298.939022) (xy 430.427886 -298.96012) (xy 430.468389 -298.988076) (xy 430.503882 -299.022168)
			(xy 430.533447 -299.061512) (xy 430.556318 -299.105089) (xy 430.571902 -299.15177) (xy 430.579797 -299.200347)
			(xy 430.580292 -299.224954) (xy 430.91914 -299.224954) (xy 430.9231 -299.1759) (xy 430.934877 -299.128116)
			(xy 430.954168 -299.08284) (xy 430.980471 -299.041244) (xy 431.013106 -299.004407) (xy 431.051227 -298.973282)
			(xy 431.093848 -298.948675) (xy 431.139864 -298.931223) (xy 431.188083 -298.921379) (xy 431.237258 -298.919398)
			(xy 431.286113 -298.92533) (xy 431.333384 -298.939022) (xy 431.377846 -298.96012) (xy 431.418349 -298.988076)
			(xy 431.453842 -299.022168) (xy 431.483407 -299.061512) (xy 431.506278 -299.105089) (xy 431.521862 -299.15177)
			(xy 431.529757 -299.200347) (xy 431.530252 -299.224954) (xy 431.529757 -299.249561) (xy 431.525954 -299.27296)
			(xy 438.614564 -299.27296) (xy 438.618635 -299.217338) (xy 438.630761 -299.162901) (xy 438.650684 -299.11081)
			(xy 438.67798 -299.062175) (xy 438.712066 -299.018032) (xy 438.752215 -298.979323) (xy 438.797573 -298.946872)
			(xy 438.847173 -298.921371) (xy 438.899957 -298.903364) (xy 438.9548 -298.893234) (xy 439.010534 -298.891197)
			(xy 439.065971 -298.897297) (xy 439.119928 -298.911403) (xy 439.171257 -298.933215) (xy 439.218863 -298.962269)
			(xy 439.261731 -298.997944) (xy 439.298948 -299.039481) (xy 439.329721 -299.085994) (xy 439.353393 -299.136491)
			(xy 439.369461 -299.189898) (xy 439.377581 -299.245074) (xy 439.37809 -299.27296) (xy 439.377581 -299.300846)
			(xy 439.369461 -299.356022) (xy 439.353393 -299.409429) (xy 439.329721 -299.459926) (xy 439.298948 -299.506439)
			(xy 439.261731 -299.547976) (xy 439.218863 -299.583651) (xy 439.171257 -299.612705) (xy 439.119928 -299.634517)
			(xy 439.065971 -299.648623) (xy 439.010534 -299.654723) (xy 438.9548 -299.652686) (xy 438.899957 -299.642556)
			(xy 438.847173 -299.624549) (xy 438.797573 -299.599048) (xy 438.752215 -299.566597) (xy 438.712066 -299.527888)
			(xy 438.67798 -299.483745) (xy 438.650684 -299.43511) (xy 438.630761 -299.383019) (xy 438.618635 -299.328582)
			(xy 438.614564 -299.27296) (xy 431.525954 -299.27296) (xy 431.521862 -299.298138) (xy 431.506278 -299.344819)
			(xy 431.483407 -299.388396) (xy 431.453842 -299.42774) (xy 431.418349 -299.461832) (xy 431.377846 -299.489788)
			(xy 431.333384 -299.510886) (xy 431.286113 -299.524578) (xy 431.237258 -299.53051) (xy 431.188083 -299.528529)
			(xy 431.139864 -299.518685) (xy 431.093848 -299.501233) (xy 431.051227 -299.476626) (xy 431.013106 -299.445501)
			(xy 430.980471 -299.408664) (xy 430.954168 -299.367068) (xy 430.934877 -299.321792) (xy 430.9231 -299.274008)
			(xy 430.91914 -299.224954) (xy 430.580292 -299.224954) (xy 430.579797 -299.249561) (xy 430.571902 -299.298138)
			(xy 430.556318 -299.344819) (xy 430.533447 -299.388396) (xy 430.503882 -299.42774) (xy 430.468389 -299.461832)
			(xy 430.427886 -299.489788) (xy 430.383424 -299.510886) (xy 430.336153 -299.524578) (xy 430.287298 -299.53051)
			(xy 430.238123 -299.528529) (xy 430.189904 -299.518685) (xy 430.143888 -299.501233) (xy 430.101267 -299.476626)
			(xy 430.063146 -299.445501) (xy 430.030511 -299.408664) (xy 430.004208 -299.367068) (xy 429.984917 -299.321792)
			(xy 429.97314 -299.274008) (xy 429.96918 -299.224954) (xy 429.630332 -299.224954) (xy 429.629837 -299.249561)
			(xy 429.621942 -299.298138) (xy 429.606358 -299.344819) (xy 429.583487 -299.388396) (xy 429.553922 -299.42774)
			(xy 429.518429 -299.461832) (xy 429.477926 -299.489788) (xy 429.433464 -299.510886) (xy 429.386193 -299.524578)
			(xy 429.337338 -299.53051) (xy 429.288163 -299.528529) (xy 429.239944 -299.518685) (xy 429.193928 -299.501233)
			(xy 429.151307 -299.476626) (xy 429.113186 -299.445501) (xy 429.080551 -299.408664) (xy 429.054248 -299.367068)
			(xy 429.034957 -299.321792) (xy 429.02318 -299.274008) (xy 429.01922 -299.224954) (xy 428.680118 -299.224954)
			(xy 428.679623 -299.249561) (xy 428.671728 -299.298138) (xy 428.656144 -299.344819) (xy 428.633273 -299.388396)
			(xy 428.603708 -299.42774) (xy 428.568215 -299.461832) (xy 428.527712 -299.489788) (xy 428.48325 -299.510886)
			(xy 428.435979 -299.524578) (xy 428.387124 -299.53051) (xy 428.337949 -299.528529) (xy 428.28973 -299.518685)
			(xy 428.243714 -299.501233) (xy 428.201093 -299.476626) (xy 428.162972 -299.445501) (xy 428.130337 -299.408664)
			(xy 428.104034 -299.367068) (xy 428.084743 -299.321792) (xy 428.072966 -299.274008) (xy 428.069006 -299.224954)
			(xy 427.730158 -299.224954) (xy 427.729663 -299.249561) (xy 427.721768 -299.298138) (xy 427.706184 -299.344819)
			(xy 427.683313 -299.388396) (xy 427.653748 -299.42774) (xy 427.618255 -299.461832) (xy 427.577752 -299.489788)
			(xy 427.53329 -299.510886) (xy 427.486019 -299.524578) (xy 427.437164 -299.53051) (xy 427.387989 -299.528529)
			(xy 427.33977 -299.518685) (xy 427.293754 -299.501233) (xy 427.251133 -299.476626) (xy 427.213012 -299.445501)
			(xy 427.180377 -299.408664) (xy 427.154074 -299.367068) (xy 427.134783 -299.321792) (xy 427.123006 -299.274008)
			(xy 427.119046 -299.224954) (xy 426.780198 -299.224954) (xy 426.779703 -299.249561) (xy 426.771808 -299.298138)
			(xy 426.756224 -299.344819) (xy 426.733353 -299.388396) (xy 426.703788 -299.42774) (xy 426.668295 -299.461832)
			(xy 426.627792 -299.489788) (xy 426.58333 -299.510886) (xy 426.536059 -299.524578) (xy 426.487204 -299.53051)
			(xy 426.438029 -299.528529) (xy 426.38981 -299.518685) (xy 426.343794 -299.501233) (xy 426.301173 -299.476626)
			(xy 426.263052 -299.445501) (xy 426.230417 -299.408664) (xy 426.204114 -299.367068) (xy 426.184823 -299.321792)
			(xy 426.173046 -299.274008) (xy 426.169086 -299.224954) (xy 425.830238 -299.224954) (xy 425.829743 -299.249561)
			(xy 425.821848 -299.298138) (xy 425.806264 -299.344819) (xy 425.783393 -299.388396) (xy 425.753828 -299.42774)
			(xy 425.718335 -299.461832) (xy 425.677832 -299.489788) (xy 425.63337 -299.510886) (xy 425.586099 -299.524578)
			(xy 425.537244 -299.53051) (xy 425.488069 -299.528529) (xy 425.43985 -299.518685) (xy 425.393834 -299.501233)
			(xy 425.351213 -299.476626) (xy 425.313092 -299.445501) (xy 425.280457 -299.408664) (xy 425.254154 -299.367068)
			(xy 425.234863 -299.321792) (xy 425.223086 -299.274008) (xy 425.219126 -299.224954) (xy 424.880278 -299.224954)
			(xy 424.879783 -299.249561) (xy 424.871888 -299.298138) (xy 424.856304 -299.344819) (xy 424.833433 -299.388396)
			(xy 424.803868 -299.42774) (xy 424.768375 -299.461832) (xy 424.727872 -299.489788) (xy 424.68341 -299.510886)
			(xy 424.636139 -299.524578) (xy 424.587284 -299.53051) (xy 424.538109 -299.528529) (xy 424.48989 -299.518685)
			(xy 424.443874 -299.501233) (xy 424.401253 -299.476626) (xy 424.363132 -299.445501) (xy 424.330497 -299.408664)
			(xy 424.304194 -299.367068) (xy 424.284903 -299.321792) (xy 424.273126 -299.274008) (xy 424.269166 -299.224954)
			(xy 422.030144 -299.224954) (xy 422.029649 -299.249561) (xy 422.021754 -299.298138) (xy 422.00617 -299.344819)
			(xy 421.983299 -299.388396) (xy 421.953734 -299.42774) (xy 421.918241 -299.461832) (xy 421.877738 -299.489788)
			(xy 421.833276 -299.510886) (xy 421.786005 -299.524578) (xy 421.73715 -299.53051) (xy 421.687975 -299.528529)
			(xy 421.639756 -299.518685) (xy 421.59374 -299.501233) (xy 421.551119 -299.476626) (xy 421.512998 -299.445501)
			(xy 421.480363 -299.408664) (xy 421.45406 -299.367068) (xy 421.434769 -299.321792) (xy 421.422992 -299.274008)
			(xy 421.419032 -299.224954) (xy 421.080184 -299.224954) (xy 421.079689 -299.249561) (xy 421.071794 -299.298138)
			(xy 421.05621 -299.344819) (xy 421.033339 -299.388396) (xy 421.003774 -299.42774) (xy 420.968281 -299.461832)
			(xy 420.927778 -299.489788) (xy 420.883316 -299.510886) (xy 420.836045 -299.524578) (xy 420.78719 -299.53051)
			(xy 420.738015 -299.528529) (xy 420.689796 -299.518685) (xy 420.64378 -299.501233) (xy 420.601159 -299.476626)
			(xy 420.563038 -299.445501) (xy 420.530403 -299.408664) (xy 420.5041 -299.367068) (xy 420.484809 -299.321792)
			(xy 420.473032 -299.274008) (xy 420.469072 -299.224954) (xy 420.130224 -299.224954) (xy 420.129729 -299.249561)
			(xy 420.121834 -299.298138) (xy 420.10625 -299.344819) (xy 420.083379 -299.388396) (xy 420.053814 -299.42774)
			(xy 420.018321 -299.461832) (xy 419.977818 -299.489788) (xy 419.933356 -299.510886) (xy 419.886085 -299.524578)
			(xy 419.83723 -299.53051) (xy 419.788055 -299.528529) (xy 419.739836 -299.518685) (xy 419.69382 -299.501233)
			(xy 419.651199 -299.476626) (xy 419.613078 -299.445501) (xy 419.580443 -299.408664) (xy 419.55414 -299.367068)
			(xy 419.534849 -299.321792) (xy 419.523072 -299.274008) (xy 419.519112 -299.224954) (xy 419.180264 -299.224954)
			(xy 419.179769 -299.249561) (xy 419.171874 -299.298138) (xy 419.15629 -299.344819) (xy 419.133419 -299.388396)
			(xy 419.103854 -299.42774) (xy 419.068361 -299.461832) (xy 419.027858 -299.489788) (xy 418.983396 -299.510886)
			(xy 418.936125 -299.524578) (xy 418.88727 -299.53051) (xy 418.838095 -299.528529) (xy 418.789876 -299.518685)
			(xy 418.74386 -299.501233) (xy 418.701239 -299.476626) (xy 418.663118 -299.445501) (xy 418.630483 -299.408664)
			(xy 418.60418 -299.367068) (xy 418.584889 -299.321792) (xy 418.573112 -299.274008) (xy 418.569152 -299.224954)
			(xy 418.230304 -299.224954) (xy 418.229809 -299.249561) (xy 418.221914 -299.298138) (xy 418.20633 -299.344819)
			(xy 418.183459 -299.388396) (xy 418.153894 -299.42774) (xy 418.118401 -299.461832) (xy 418.077898 -299.489788)
			(xy 418.033436 -299.510886) (xy 417.986165 -299.524578) (xy 417.93731 -299.53051) (xy 417.888135 -299.528529)
			(xy 417.839916 -299.518685) (xy 417.7939 -299.501233) (xy 417.751279 -299.476626) (xy 417.713158 -299.445501)
			(xy 417.680523 -299.408664) (xy 417.65422 -299.367068) (xy 417.634929 -299.321792) (xy 417.623152 -299.274008)
			(xy 417.619192 -299.224954) (xy 417.28009 -299.224954) (xy 417.279595 -299.249561) (xy 417.2717 -299.298138)
			(xy 417.256116 -299.344819) (xy 417.233245 -299.388396) (xy 417.20368 -299.42774) (xy 417.168187 -299.461832)
			(xy 417.127684 -299.489788) (xy 417.083222 -299.510886) (xy 417.035951 -299.524578) (xy 416.987096 -299.53051)
			(xy 416.937921 -299.528529) (xy 416.889702 -299.518685) (xy 416.843686 -299.501233) (xy 416.801065 -299.476626)
			(xy 416.762944 -299.445501) (xy 416.730309 -299.408664) (xy 416.704006 -299.367068) (xy 416.684715 -299.321792)
			(xy 416.672938 -299.274008) (xy 416.668978 -299.224954) (xy 416.33013 -299.224954) (xy 416.329635 -299.249561)
			(xy 416.32174 -299.298138) (xy 416.306156 -299.344819) (xy 416.283285 -299.388396) (xy 416.25372 -299.42774)
			(xy 416.218227 -299.461832) (xy 416.177724 -299.489788) (xy 416.133262 -299.510886) (xy 416.085991 -299.524578)
			(xy 416.037136 -299.53051) (xy 415.987961 -299.528529) (xy 415.939742 -299.518685) (xy 415.893726 -299.501233)
			(xy 415.851105 -299.476626) (xy 415.812984 -299.445501) (xy 415.780349 -299.408664) (xy 415.754046 -299.367068)
			(xy 415.734755 -299.321792) (xy 415.722978 -299.274008) (xy 415.719018 -299.224954) (xy 415.38017 -299.224954)
			(xy 415.379675 -299.249561) (xy 415.37178 -299.298138) (xy 415.356196 -299.344819) (xy 415.333325 -299.388396)
			(xy 415.30376 -299.42774) (xy 415.268267 -299.461832) (xy 415.227764 -299.489788) (xy 415.183302 -299.510886)
			(xy 415.136031 -299.524578) (xy 415.087176 -299.53051) (xy 415.038001 -299.528529) (xy 414.989782 -299.518685)
			(xy 414.943766 -299.501233) (xy 414.901145 -299.476626) (xy 414.863024 -299.445501) (xy 414.830389 -299.408664)
			(xy 414.804086 -299.367068) (xy 414.784795 -299.321792) (xy 414.773018 -299.274008) (xy 414.769058 -299.224954)
			(xy 414.43021 -299.224954) (xy 414.429715 -299.249561) (xy 414.42182 -299.298138) (xy 414.406236 -299.344819)
			(xy 414.383365 -299.388396) (xy 414.3538 -299.42774) (xy 414.318307 -299.461832) (xy 414.277804 -299.489788)
			(xy 414.233342 -299.510886) (xy 414.186071 -299.524578) (xy 414.137216 -299.53051) (xy 414.088041 -299.528529)
			(xy 414.039822 -299.518685) (xy 413.993806 -299.501233) (xy 413.951185 -299.476626) (xy 413.913064 -299.445501)
			(xy 413.880429 -299.408664) (xy 413.854126 -299.367068) (xy 413.834835 -299.321792) (xy 413.823058 -299.274008)
			(xy 413.819098 -299.224954) (xy 413.48025 -299.224954) (xy 413.479755 -299.249561) (xy 413.47186 -299.298138)
			(xy 413.456276 -299.344819) (xy 413.433405 -299.388396) (xy 413.40384 -299.42774) (xy 413.368347 -299.461832)
			(xy 413.327844 -299.489788) (xy 413.283382 -299.510886) (xy 413.236111 -299.524578) (xy 413.187256 -299.53051)
			(xy 413.138081 -299.528529) (xy 413.089862 -299.518685) (xy 413.043846 -299.501233) (xy 413.001225 -299.476626)
			(xy 412.963104 -299.445501) (xy 412.930469 -299.408664) (xy 412.904166 -299.367068) (xy 412.884875 -299.321792)
			(xy 412.873098 -299.274008) (xy 412.869138 -299.224954) (xy 412.53029 -299.224954) (xy 412.529795 -299.249561)
			(xy 412.5219 -299.298138) (xy 412.506316 -299.344819) (xy 412.483445 -299.388396) (xy 412.45388 -299.42774)
			(xy 412.418387 -299.461832) (xy 412.377884 -299.489788) (xy 412.333422 -299.510886) (xy 412.286151 -299.524578)
			(xy 412.237296 -299.53051) (xy 412.188121 -299.528529) (xy 412.139902 -299.518685) (xy 412.093886 -299.501233)
			(xy 412.051265 -299.476626) (xy 412.013144 -299.445501) (xy 411.980509 -299.408664) (xy 411.954206 -299.367068)
			(xy 411.934915 -299.321792) (xy 411.923138 -299.274008) (xy 411.919178 -299.224954) (xy 411.58033 -299.224954)
			(xy 411.579835 -299.249561) (xy 411.57194 -299.298138) (xy 411.556356 -299.344819) (xy 411.533485 -299.388396)
			(xy 411.50392 -299.42774) (xy 411.468427 -299.461832) (xy 411.427924 -299.489788) (xy 411.383462 -299.510886)
			(xy 411.336191 -299.524578) (xy 411.287336 -299.53051) (xy 411.238161 -299.528529) (xy 411.189942 -299.518685)
			(xy 411.143926 -299.501233) (xy 411.101305 -299.476626) (xy 411.063184 -299.445501) (xy 411.030549 -299.408664)
			(xy 411.004246 -299.367068) (xy 410.984955 -299.321792) (xy 410.973178 -299.274008) (xy 410.969218 -299.224954)
			(xy 410.630116 -299.224954) (xy 410.629621 -299.249561) (xy 410.621726 -299.298138) (xy 410.606142 -299.344819)
			(xy 410.583271 -299.388396) (xy 410.553706 -299.42774) (xy 410.518213 -299.461832) (xy 410.47771 -299.489788)
			(xy 410.433248 -299.510886) (xy 410.385977 -299.524578) (xy 410.337122 -299.53051) (xy 410.287947 -299.528529)
			(xy 410.239728 -299.518685) (xy 410.193712 -299.501233) (xy 410.151091 -299.476626) (xy 410.11297 -299.445501)
			(xy 410.080335 -299.408664) (xy 410.054032 -299.367068) (xy 410.034741 -299.321792) (xy 410.022964 -299.274008)
			(xy 410.019004 -299.224954) (xy 409.680156 -299.224954) (xy 409.679661 -299.249561) (xy 409.671766 -299.298138)
			(xy 409.656182 -299.344819) (xy 409.633311 -299.388396) (xy 409.603746 -299.42774) (xy 409.568253 -299.461832)
			(xy 409.52775 -299.489788) (xy 409.483288 -299.510886) (xy 409.436017 -299.524578) (xy 409.387162 -299.53051)
			(xy 409.337987 -299.528529) (xy 409.289768 -299.518685) (xy 409.243752 -299.501233) (xy 409.201131 -299.476626)
			(xy 409.16301 -299.445501) (xy 409.130375 -299.408664) (xy 409.104072 -299.367068) (xy 409.084781 -299.321792)
			(xy 409.073004 -299.274008) (xy 409.069044 -299.224954) (xy 408.730196 -299.224954) (xy 408.729701 -299.249561)
			(xy 408.721806 -299.298138) (xy 408.706222 -299.344819) (xy 408.683351 -299.388396) (xy 408.653786 -299.42774)
			(xy 408.618293 -299.461832) (xy 408.57779 -299.489788) (xy 408.533328 -299.510886) (xy 408.486057 -299.524578)
			(xy 408.437202 -299.53051) (xy 408.388027 -299.528529) (xy 408.339808 -299.518685) (xy 408.293792 -299.501233)
			(xy 408.251171 -299.476626) (xy 408.21305 -299.445501) (xy 408.180415 -299.408664) (xy 408.154112 -299.367068)
			(xy 408.134821 -299.321792) (xy 408.123044 -299.274008) (xy 408.119084 -299.224954) (xy 406.830276 -299.224954)
			(xy 406.829781 -299.249561) (xy 406.821886 -299.298138) (xy 406.806302 -299.344819) (xy 406.783431 -299.388396)
			(xy 406.753866 -299.42774) (xy 406.718373 -299.461832) (xy 406.67787 -299.489788) (xy 406.633408 -299.510886)
			(xy 406.586137 -299.524578) (xy 406.537282 -299.53051) (xy 406.488107 -299.528529) (xy 406.439888 -299.518685)
			(xy 406.393872 -299.501233) (xy 406.351251 -299.476626) (xy 406.31313 -299.445501) (xy 406.280495 -299.408664)
			(xy 406.254192 -299.367068) (xy 406.234901 -299.321792) (xy 406.223124 -299.274008) (xy 406.219164 -299.224954)
			(xy 405.880316 -299.224954) (xy 405.879821 -299.249561) (xy 405.871926 -299.298138) (xy 405.856342 -299.344819)
			(xy 405.833471 -299.388396) (xy 405.803906 -299.42774) (xy 405.768413 -299.461832) (xy 405.72791 -299.489788)
			(xy 405.683448 -299.510886) (xy 405.636177 -299.524578) (xy 405.587322 -299.53051) (xy 405.538147 -299.528529)
			(xy 405.489928 -299.518685) (xy 405.443912 -299.501233) (xy 405.401291 -299.476626) (xy 405.36317 -299.445501)
			(xy 405.330535 -299.408664) (xy 405.304232 -299.367068) (xy 405.284941 -299.321792) (xy 405.273164 -299.274008)
			(xy 405.269204 -299.224954) (xy 404.930102 -299.224954) (xy 404.929607 -299.249561) (xy 404.921712 -299.298138)
			(xy 404.906128 -299.344819) (xy 404.883257 -299.388396) (xy 404.853692 -299.42774) (xy 404.818199 -299.461832)
			(xy 404.777696 -299.489788) (xy 404.733234 -299.510886) (xy 404.685963 -299.524578) (xy 404.637108 -299.53051)
			(xy 404.587933 -299.528529) (xy 404.539714 -299.518685) (xy 404.493698 -299.501233) (xy 404.451077 -299.476626)
			(xy 404.412956 -299.445501) (xy 404.380321 -299.408664) (xy 404.354018 -299.367068) (xy 404.334727 -299.321792)
			(xy 404.32295 -299.274008) (xy 404.31899 -299.224954) (xy 403.980142 -299.224954) (xy 403.979647 -299.249561)
			(xy 403.971752 -299.298138) (xy 403.956168 -299.344819) (xy 403.933297 -299.388396) (xy 403.903732 -299.42774)
			(xy 403.868239 -299.461832) (xy 403.827736 -299.489788) (xy 403.783274 -299.510886) (xy 403.736003 -299.524578)
			(xy 403.687148 -299.53051) (xy 403.637973 -299.528529) (xy 403.589754 -299.518685) (xy 403.543738 -299.501233)
			(xy 403.501117 -299.476626) (xy 403.462996 -299.445501) (xy 403.430361 -299.408664) (xy 403.404058 -299.367068)
			(xy 403.384767 -299.321792) (xy 403.37299 -299.274008) (xy 403.36903 -299.224954) (xy 403.030182 -299.224954)
			(xy 403.029687 -299.249561) (xy 403.021792 -299.298138) (xy 403.006208 -299.344819) (xy 402.983337 -299.388396)
			(xy 402.953772 -299.42774) (xy 402.918279 -299.461832) (xy 402.877776 -299.489788) (xy 402.833314 -299.510886)
			(xy 402.786043 -299.524578) (xy 402.737188 -299.53051) (xy 402.688013 -299.528529) (xy 402.639794 -299.518685)
			(xy 402.593778 -299.501233) (xy 402.551157 -299.476626) (xy 402.513036 -299.445501) (xy 402.480401 -299.408664)
			(xy 402.454098 -299.367068) (xy 402.434807 -299.321792) (xy 402.42303 -299.274008) (xy 402.41907 -299.224954)
			(xy 402.080222 -299.224954) (xy 402.079727 -299.249561) (xy 402.071832 -299.298138) (xy 402.056248 -299.344819)
			(xy 402.033377 -299.388396) (xy 402.003812 -299.42774) (xy 401.968319 -299.461832) (xy 401.927816 -299.489788)
			(xy 401.883354 -299.510886) (xy 401.836083 -299.524578) (xy 401.787228 -299.53051) (xy 401.738053 -299.528529)
			(xy 401.689834 -299.518685) (xy 401.643818 -299.501233) (xy 401.601197 -299.476626) (xy 401.563076 -299.445501)
			(xy 401.530441 -299.408664) (xy 401.504138 -299.367068) (xy 401.484847 -299.321792) (xy 401.47307 -299.274008)
			(xy 401.46911 -299.224954) (xy 401.130262 -299.224954) (xy 401.129767 -299.249561) (xy 401.121872 -299.298138)
			(xy 401.106288 -299.344819) (xy 401.083417 -299.388396) (xy 401.053852 -299.42774) (xy 401.018359 -299.461832)
			(xy 400.977856 -299.489788) (xy 400.933394 -299.510886) (xy 400.886123 -299.524578) (xy 400.837268 -299.53051)
			(xy 400.788093 -299.528529) (xy 400.739874 -299.518685) (xy 400.693858 -299.501233) (xy 400.651237 -299.476626)
			(xy 400.613116 -299.445501) (xy 400.580481 -299.408664) (xy 400.554178 -299.367068) (xy 400.534887 -299.321792)
			(xy 400.52311 -299.274008) (xy 400.51915 -299.224954) (xy 400.180302 -299.224954) (xy 400.179807 -299.249561)
			(xy 400.171912 -299.298138) (xy 400.156328 -299.344819) (xy 400.133457 -299.388396) (xy 400.103892 -299.42774)
			(xy 400.068399 -299.461832) (xy 400.027896 -299.489788) (xy 399.983434 -299.510886) (xy 399.936163 -299.524578)
			(xy 399.887308 -299.53051) (xy 399.838133 -299.528529) (xy 399.789914 -299.518685) (xy 399.743898 -299.501233)
			(xy 399.701277 -299.476626) (xy 399.663156 -299.445501) (xy 399.630521 -299.408664) (xy 399.604218 -299.367068)
			(xy 399.584927 -299.321792) (xy 399.57315 -299.274008) (xy 399.56919 -299.224954) (xy 399.230342 -299.224954)
			(xy 399.229847 -299.249561) (xy 399.221952 -299.298138) (xy 399.206368 -299.344819) (xy 399.183497 -299.388396)
			(xy 399.153932 -299.42774) (xy 399.118439 -299.461832) (xy 399.077936 -299.489788) (xy 399.033474 -299.510886)
			(xy 398.986203 -299.524578) (xy 398.937348 -299.53051) (xy 398.888173 -299.528529) (xy 398.839954 -299.518685)
			(xy 398.793938 -299.501233) (xy 398.751317 -299.476626) (xy 398.713196 -299.445501) (xy 398.680561 -299.408664)
			(xy 398.654258 -299.367068) (xy 398.634967 -299.321792) (xy 398.62319 -299.274008) (xy 398.61923 -299.224954)
			(xy 398.280128 -299.224954) (xy 398.279633 -299.249561) (xy 398.271738 -299.298138) (xy 398.256154 -299.344819)
			(xy 398.233283 -299.388396) (xy 398.203718 -299.42774) (xy 398.168225 -299.461832) (xy 398.127722 -299.489788)
			(xy 398.08326 -299.510886) (xy 398.035989 -299.524578) (xy 397.987134 -299.53051) (xy 397.937959 -299.528529)
			(xy 397.88974 -299.518685) (xy 397.843724 -299.501233) (xy 397.801103 -299.476626) (xy 397.762982 -299.445501)
			(xy 397.730347 -299.408664) (xy 397.704044 -299.367068) (xy 397.684753 -299.321792) (xy 397.672976 -299.274008)
			(xy 397.669016 -299.224954) (xy 397.355192 -299.224954) (xy 397.355193 -299.251359) (xy 397.346828 -299.303422)
			(xy 397.330311 -299.353499) (xy 397.306059 -299.400322) (xy 397.274686 -299.442704) (xy 397.236987 -299.479573)
			(xy 397.193916 -299.509994) (xy 397.146565 -299.533197) (xy 397.096133 -299.548595) (xy 397.070072 -299.552614)
			(xy 397.066008 -299.553122) (xy 397.054578 -299.556678) (xy 397.05026 -299.557948) (xy 397.02613 -299.569124)
			(xy 397.019526 -299.576236) (xy 397.004794 -299.59173) (xy 396.996666 -299.602906) (xy 396.993975 -299.608438)
			(xy 396.991028 -299.620379) (xy 396.990824 -299.626528) (xy 396.990824 -299.76445) (xy 436.341772 -299.76445)
			(xy 436.345843 -299.708828) (xy 436.357969 -299.654391) (xy 436.377892 -299.6023) (xy 436.405188 -299.553665)
			(xy 436.439274 -299.509522) (xy 436.479423 -299.470813) (xy 436.524781 -299.438362) (xy 436.574381 -299.412861)
			(xy 436.627165 -299.394854) (xy 436.682008 -299.384724) (xy 436.737742 -299.382687) (xy 436.793179 -299.388787)
			(xy 436.847136 -299.402893) (xy 436.898465 -299.424705) (xy 436.946071 -299.453759) (xy 436.988939 -299.489434)
			(xy 437.026156 -299.530971) (xy 437.056929 -299.577484) (xy 437.080601 -299.627981) (xy 437.096669 -299.681388)
			(xy 437.104789 -299.736564) (xy 437.105298 -299.76445) (xy 437.10502 -299.77969) (xy 440.93841 -299.77969)
			(xy 440.942481 -299.724068) (xy 440.954607 -299.669631) (xy 440.97453 -299.61754) (xy 441.001826 -299.568905)
			(xy 441.035912 -299.524762) (xy 441.076061 -299.486053) (xy 441.121419 -299.453602) (xy 441.171019 -299.428101)
			(xy 441.223803 -299.410094) (xy 441.278646 -299.399964) (xy 441.33438 -299.397927) (xy 441.389817 -299.404027)
			(xy 441.443774 -299.418133) (xy 441.495103 -299.439945) (xy 441.542709 -299.468999) (xy 441.585577 -299.504674)
			(xy 441.622794 -299.546211) (xy 441.653567 -299.592724) (xy 441.677239 -299.643221) (xy 441.693307 -299.696628)
			(xy 441.701427 -299.751804) (xy 441.701936 -299.77969) (xy 441.701427 -299.807576) (xy 441.693307 -299.862752)
			(xy 441.677239 -299.916159) (xy 441.653567 -299.966656) (xy 441.622794 -300.013169) (xy 441.585577 -300.054706)
			(xy 441.542709 -300.090381) (xy 441.495103 -300.119435) (xy 441.443774 -300.141247) (xy 441.389817 -300.155353)
			(xy 441.33438 -300.161453) (xy 441.278646 -300.159416) (xy 441.223803 -300.149286) (xy 441.171019 -300.131279)
			(xy 441.121419 -300.105778) (xy 441.076061 -300.073327) (xy 441.035912 -300.034618) (xy 441.001826 -299.990475)
			(xy 440.97453 -299.94184) (xy 440.954607 -299.889749) (xy 440.942481 -299.835312) (xy 440.93841 -299.77969)
			(xy 437.10502 -299.77969) (xy 437.104789 -299.792336) (xy 437.096669 -299.847512) (xy 437.080601 -299.900919)
			(xy 437.056929 -299.951416) (xy 437.026156 -299.997929) (xy 436.988939 -300.039466) (xy 436.946071 -300.075141)
			(xy 436.898465 -300.104195) (xy 436.847136 -300.126007) (xy 436.793179 -300.140113) (xy 436.737742 -300.146213)
			(xy 436.682008 -300.144176) (xy 436.627165 -300.134046) (xy 436.574381 -300.116039) (xy 436.524781 -300.090538)
			(xy 436.479423 -300.058087) (xy 436.439274 -300.019378) (xy 436.405188 -299.975235) (xy 436.377892 -299.9266)
			(xy 436.357969 -299.874509) (xy 436.345843 -299.820072) (xy 436.341772 -299.76445) (xy 396.990824 -299.76445)
			(xy 396.990824 -299.77334) (xy 396.99099 -299.779494) (xy 396.993937 -299.791444) (xy 396.996666 -299.796962)
			(xy 397.004794 -299.808138) (xy 397.019526 -299.823632) (xy 397.02613 -299.830744) (xy 397.05026 -299.84192)
			(xy 397.054578 -299.84319) (xy 397.066008 -299.846746) (xy 397.070072 -299.847254) (xy 397.096116 -299.851362)
			(xy 397.146539 -299.866756) (xy 397.193882 -299.889955) (xy 397.236945 -299.92037) (xy 397.274638 -299.957232)
			(xy 397.306006 -299.999606) (xy 397.330255 -300.04642) (xy 397.34677 -300.096488) (xy 397.355133 -300.148541)
			(xy 397.355133 -300.174914) (xy 397.669016 -300.174914) (xy 397.672976 -300.12586) (xy 397.684753 -300.078076)
			(xy 397.704044 -300.0328) (xy 397.730347 -299.991204) (xy 397.762982 -299.954367) (xy 397.801103 -299.923242)
			(xy 397.843724 -299.898635) (xy 397.88974 -299.881183) (xy 397.937959 -299.871339) (xy 397.987134 -299.869358)
			(xy 398.035989 -299.87529) (xy 398.08326 -299.888982) (xy 398.127722 -299.91008) (xy 398.168225 -299.938036)
			(xy 398.203718 -299.972128) (xy 398.233283 -300.011472) (xy 398.256154 -300.055049) (xy 398.271738 -300.10173)
			(xy 398.279633 -300.150307) (xy 398.280128 -300.174914) (xy 398.61923 -300.174914) (xy 398.62319 -300.12586)
			(xy 398.634967 -300.078076) (xy 398.654258 -300.0328) (xy 398.680561 -299.991204) (xy 398.713196 -299.954367)
			(xy 398.751317 -299.923242) (xy 398.793938 -299.898635) (xy 398.839954 -299.881183) (xy 398.888173 -299.871339)
			(xy 398.937348 -299.869358) (xy 398.986203 -299.87529) (xy 399.033474 -299.888982) (xy 399.077936 -299.91008)
			(xy 399.118439 -299.938036) (xy 399.153932 -299.972128) (xy 399.183497 -300.011472) (xy 399.206368 -300.055049)
			(xy 399.221952 -300.10173) (xy 399.229847 -300.150307) (xy 399.230342 -300.174914) (xy 399.56919 -300.174914)
			(xy 399.57315 -300.12586) (xy 399.584927 -300.078076) (xy 399.604218 -300.0328) (xy 399.630521 -299.991204)
			(xy 399.663156 -299.954367) (xy 399.701277 -299.923242) (xy 399.743898 -299.898635) (xy 399.789914 -299.881183)
			(xy 399.838133 -299.871339) (xy 399.887308 -299.869358) (xy 399.936163 -299.87529) (xy 399.983434 -299.888982)
			(xy 400.027896 -299.91008) (xy 400.068399 -299.938036) (xy 400.103892 -299.972128) (xy 400.133457 -300.011472)
			(xy 400.156328 -300.055049) (xy 400.171912 -300.10173) (xy 400.179807 -300.150307) (xy 400.180302 -300.174914)
			(xy 400.51915 -300.174914) (xy 400.52311 -300.12586) (xy 400.534887 -300.078076) (xy 400.554178 -300.0328)
			(xy 400.580481 -299.991204) (xy 400.613116 -299.954367) (xy 400.651237 -299.923242) (xy 400.693858 -299.898635)
			(xy 400.739874 -299.881183) (xy 400.788093 -299.871339) (xy 400.837268 -299.869358) (xy 400.886123 -299.87529)
			(xy 400.933394 -299.888982) (xy 400.977856 -299.91008) (xy 401.018359 -299.938036) (xy 401.053852 -299.972128)
			(xy 401.083417 -300.011472) (xy 401.106288 -300.055049) (xy 401.121872 -300.10173) (xy 401.129767 -300.150307)
			(xy 401.130262 -300.174914) (xy 401.46911 -300.174914) (xy 401.47307 -300.12586) (xy 401.484847 -300.078076)
			(xy 401.504138 -300.0328) (xy 401.530441 -299.991204) (xy 401.563076 -299.954367) (xy 401.601197 -299.923242)
			(xy 401.643818 -299.898635) (xy 401.689834 -299.881183) (xy 401.738053 -299.871339) (xy 401.787228 -299.869358)
			(xy 401.836083 -299.87529) (xy 401.883354 -299.888982) (xy 401.927816 -299.91008) (xy 401.968319 -299.938036)
			(xy 402.003812 -299.972128) (xy 402.033377 -300.011472) (xy 402.056248 -300.055049) (xy 402.071832 -300.10173)
			(xy 402.079727 -300.150307) (xy 402.080222 -300.174914) (xy 402.41907 -300.174914) (xy 402.42303 -300.12586)
			(xy 402.434807 -300.078076) (xy 402.454098 -300.0328) (xy 402.480401 -299.991204) (xy 402.513036 -299.954367)
			(xy 402.551157 -299.923242) (xy 402.593778 -299.898635) (xy 402.639794 -299.881183) (xy 402.688013 -299.871339)
			(xy 402.737188 -299.869358) (xy 402.786043 -299.87529) (xy 402.833314 -299.888982) (xy 402.877776 -299.91008)
			(xy 402.918279 -299.938036) (xy 402.953772 -299.972128) (xy 402.983337 -300.011472) (xy 403.006208 -300.055049)
			(xy 403.021792 -300.10173) (xy 403.029687 -300.150307) (xy 403.030182 -300.174914) (xy 403.36903 -300.174914)
			(xy 403.37299 -300.12586) (xy 403.384767 -300.078076) (xy 403.404058 -300.0328) (xy 403.430361 -299.991204)
			(xy 403.462996 -299.954367) (xy 403.501117 -299.923242) (xy 403.543738 -299.898635) (xy 403.589754 -299.881183)
			(xy 403.637973 -299.871339) (xy 403.687148 -299.869358) (xy 403.736003 -299.87529) (xy 403.783274 -299.888982)
			(xy 403.827736 -299.91008) (xy 403.868239 -299.938036) (xy 403.903732 -299.972128) (xy 403.933297 -300.011472)
			(xy 403.956168 -300.055049) (xy 403.971752 -300.10173) (xy 403.979647 -300.150307) (xy 403.980142 -300.174914)
			(xy 404.31899 -300.174914) (xy 404.32295 -300.12586) (xy 404.334727 -300.078076) (xy 404.354018 -300.0328)
			(xy 404.380321 -299.991204) (xy 404.412956 -299.954367) (xy 404.451077 -299.923242) (xy 404.493698 -299.898635)
			(xy 404.539714 -299.881183) (xy 404.587933 -299.871339) (xy 404.637108 -299.869358) (xy 404.685963 -299.87529)
			(xy 404.733234 -299.888982) (xy 404.777696 -299.91008) (xy 404.818199 -299.938036) (xy 404.853692 -299.972128)
			(xy 404.883257 -300.011472) (xy 404.906128 -300.055049) (xy 404.921712 -300.10173) (xy 404.929607 -300.150307)
			(xy 404.930102 -300.174914) (xy 405.269204 -300.174914) (xy 405.273164 -300.12586) (xy 405.284941 -300.078076)
			(xy 405.304232 -300.0328) (xy 405.330535 -299.991204) (xy 405.36317 -299.954367) (xy 405.401291 -299.923242)
			(xy 405.443912 -299.898635) (xy 405.489928 -299.881183) (xy 405.538147 -299.871339) (xy 405.587322 -299.869358)
			(xy 405.636177 -299.87529) (xy 405.683448 -299.888982) (xy 405.72791 -299.91008) (xy 405.768413 -299.938036)
			(xy 405.803906 -299.972128) (xy 405.833471 -300.011472) (xy 405.856342 -300.055049) (xy 405.871926 -300.10173)
			(xy 405.879821 -300.150307) (xy 405.880316 -300.174914) (xy 406.219164 -300.174914) (xy 406.223124 -300.12586)
			(xy 406.234901 -300.078076) (xy 406.254192 -300.0328) (xy 406.280495 -299.991204) (xy 406.31313 -299.954367)
			(xy 406.351251 -299.923242) (xy 406.393872 -299.898635) (xy 406.439888 -299.881183) (xy 406.488107 -299.871339)
			(xy 406.537282 -299.869358) (xy 406.586137 -299.87529) (xy 406.633408 -299.888982) (xy 406.67787 -299.91008)
			(xy 406.718373 -299.938036) (xy 406.753866 -299.972128) (xy 406.783431 -300.011472) (xy 406.806302 -300.055049)
			(xy 406.821886 -300.10173) (xy 406.829781 -300.150307) (xy 406.830276 -300.174914) (xy 408.119084 -300.174914)
			(xy 408.123044 -300.12586) (xy 408.134821 -300.078076) (xy 408.154112 -300.0328) (xy 408.180415 -299.991204)
			(xy 408.21305 -299.954367) (xy 408.251171 -299.923242) (xy 408.293792 -299.898635) (xy 408.339808 -299.881183)
			(xy 408.388027 -299.871339) (xy 408.437202 -299.869358) (xy 408.486057 -299.87529) (xy 408.533328 -299.888982)
			(xy 408.57779 -299.91008) (xy 408.618293 -299.938036) (xy 408.653786 -299.972128) (xy 408.683351 -300.011472)
			(xy 408.706222 -300.055049) (xy 408.721806 -300.10173) (xy 408.729701 -300.150307) (xy 408.730196 -300.174914)
			(xy 409.069044 -300.174914) (xy 409.073004 -300.12586) (xy 409.084781 -300.078076) (xy 409.104072 -300.0328)
			(xy 409.130375 -299.991204) (xy 409.16301 -299.954367) (xy 409.201131 -299.923242) (xy 409.243752 -299.898635)
			(xy 409.289768 -299.881183) (xy 409.337987 -299.871339) (xy 409.387162 -299.869358) (xy 409.436017 -299.87529)
			(xy 409.483288 -299.888982) (xy 409.52775 -299.91008) (xy 409.568253 -299.938036) (xy 409.603746 -299.972128)
			(xy 409.633311 -300.011472) (xy 409.656182 -300.055049) (xy 409.671766 -300.10173) (xy 409.679661 -300.150307)
			(xy 409.680156 -300.174914) (xy 410.019004 -300.174914) (xy 410.022964 -300.12586) (xy 410.034741 -300.078076)
			(xy 410.054032 -300.0328) (xy 410.080335 -299.991204) (xy 410.11297 -299.954367) (xy 410.151091 -299.923242)
			(xy 410.193712 -299.898635) (xy 410.239728 -299.881183) (xy 410.287947 -299.871339) (xy 410.337122 -299.869358)
			(xy 410.385977 -299.87529) (xy 410.433248 -299.888982) (xy 410.47771 -299.91008) (xy 410.518213 -299.938036)
			(xy 410.553706 -299.972128) (xy 410.583271 -300.011472) (xy 410.606142 -300.055049) (xy 410.621726 -300.10173)
			(xy 410.629621 -300.150307) (xy 410.630116 -300.174914) (xy 410.969218 -300.174914) (xy 410.973178 -300.12586)
			(xy 410.984955 -300.078076) (xy 411.004246 -300.0328) (xy 411.030549 -299.991204) (xy 411.063184 -299.954367)
			(xy 411.101305 -299.923242) (xy 411.143926 -299.898635) (xy 411.189942 -299.881183) (xy 411.238161 -299.871339)
			(xy 411.287336 -299.869358) (xy 411.336191 -299.87529) (xy 411.383462 -299.888982) (xy 411.427924 -299.91008)
			(xy 411.468427 -299.938036) (xy 411.50392 -299.972128) (xy 411.533485 -300.011472) (xy 411.556356 -300.055049)
			(xy 411.57194 -300.10173) (xy 411.579835 -300.150307) (xy 411.58033 -300.174914) (xy 411.919178 -300.174914)
			(xy 411.923138 -300.12586) (xy 411.934915 -300.078076) (xy 411.954206 -300.0328) (xy 411.980509 -299.991204)
			(xy 412.013144 -299.954367) (xy 412.051265 -299.923242) (xy 412.093886 -299.898635) (xy 412.139902 -299.881183)
			(xy 412.188121 -299.871339) (xy 412.237296 -299.869358) (xy 412.286151 -299.87529) (xy 412.333422 -299.888982)
			(xy 412.377884 -299.91008) (xy 412.418387 -299.938036) (xy 412.45388 -299.972128) (xy 412.483445 -300.011472)
			(xy 412.506316 -300.055049) (xy 412.5219 -300.10173) (xy 412.529795 -300.150307) (xy 412.53029 -300.174914)
			(xy 412.869138 -300.174914) (xy 412.873098 -300.12586) (xy 412.884875 -300.078076) (xy 412.904166 -300.0328)
			(xy 412.930469 -299.991204) (xy 412.963104 -299.954367) (xy 413.001225 -299.923242) (xy 413.043846 -299.898635)
			(xy 413.089862 -299.881183) (xy 413.138081 -299.871339) (xy 413.187256 -299.869358) (xy 413.236111 -299.87529)
			(xy 413.283382 -299.888982) (xy 413.327844 -299.91008) (xy 413.368347 -299.938036) (xy 413.40384 -299.972128)
			(xy 413.433405 -300.011472) (xy 413.456276 -300.055049) (xy 413.47186 -300.10173) (xy 413.479755 -300.150307)
			(xy 413.48025 -300.174914) (xy 413.819098 -300.174914) (xy 413.823058 -300.12586) (xy 413.834835 -300.078076)
			(xy 413.854126 -300.0328) (xy 413.880429 -299.991204) (xy 413.913064 -299.954367) (xy 413.951185 -299.923242)
			(xy 413.993806 -299.898635) (xy 414.039822 -299.881183) (xy 414.088041 -299.871339) (xy 414.137216 -299.869358)
			(xy 414.186071 -299.87529) (xy 414.233342 -299.888982) (xy 414.277804 -299.91008) (xy 414.318307 -299.938036)
			(xy 414.3538 -299.972128) (xy 414.383365 -300.011472) (xy 414.406236 -300.055049) (xy 414.42182 -300.10173)
			(xy 414.429715 -300.150307) (xy 414.43021 -300.174914) (xy 414.769058 -300.174914) (xy 414.773018 -300.12586)
			(xy 414.784795 -300.078076) (xy 414.804086 -300.0328) (xy 414.830389 -299.991204) (xy 414.863024 -299.954367)
			(xy 414.901145 -299.923242) (xy 414.943766 -299.898635) (xy 414.989782 -299.881183) (xy 415.038001 -299.871339)
			(xy 415.087176 -299.869358) (xy 415.136031 -299.87529) (xy 415.183302 -299.888982) (xy 415.227764 -299.91008)
			(xy 415.268267 -299.938036) (xy 415.30376 -299.972128) (xy 415.333325 -300.011472) (xy 415.356196 -300.055049)
			(xy 415.37178 -300.10173) (xy 415.379675 -300.150307) (xy 415.38017 -300.174914) (xy 415.719018 -300.174914)
			(xy 415.722978 -300.12586) (xy 415.734755 -300.078076) (xy 415.754046 -300.0328) (xy 415.780349 -299.991204)
			(xy 415.812984 -299.954367) (xy 415.851105 -299.923242) (xy 415.893726 -299.898635) (xy 415.939742 -299.881183)
			(xy 415.987961 -299.871339) (xy 416.037136 -299.869358) (xy 416.085991 -299.87529) (xy 416.133262 -299.888982)
			(xy 416.177724 -299.91008) (xy 416.218227 -299.938036) (xy 416.25372 -299.972128) (xy 416.283285 -300.011472)
			(xy 416.306156 -300.055049) (xy 416.32174 -300.10173) (xy 416.329635 -300.150307) (xy 416.33013 -300.174914)
			(xy 416.668978 -300.174914) (xy 416.672938 -300.12586) (xy 416.684715 -300.078076) (xy 416.704006 -300.0328)
			(xy 416.730309 -299.991204) (xy 416.762944 -299.954367) (xy 416.801065 -299.923242) (xy 416.843686 -299.898635)
			(xy 416.889702 -299.881183) (xy 416.937921 -299.871339) (xy 416.987096 -299.869358) (xy 417.035951 -299.87529)
			(xy 417.083222 -299.888982) (xy 417.127684 -299.91008) (xy 417.168187 -299.938036) (xy 417.20368 -299.972128)
			(xy 417.233245 -300.011472) (xy 417.256116 -300.055049) (xy 417.2717 -300.10173) (xy 417.279595 -300.150307)
			(xy 417.28009 -300.174914) (xy 417.619192 -300.174914) (xy 417.623152 -300.12586) (xy 417.634929 -300.078076)
			(xy 417.65422 -300.0328) (xy 417.680523 -299.991204) (xy 417.713158 -299.954367) (xy 417.751279 -299.923242)
			(xy 417.7939 -299.898635) (xy 417.839916 -299.881183) (xy 417.888135 -299.871339) (xy 417.93731 -299.869358)
			(xy 417.986165 -299.87529) (xy 418.033436 -299.888982) (xy 418.077898 -299.91008) (xy 418.118401 -299.938036)
			(xy 418.153894 -299.972128) (xy 418.183459 -300.011472) (xy 418.20633 -300.055049) (xy 418.221914 -300.10173)
			(xy 418.229809 -300.150307) (xy 418.230304 -300.174914) (xy 418.569152 -300.174914) (xy 418.573112 -300.12586)
			(xy 418.584889 -300.078076) (xy 418.60418 -300.0328) (xy 418.630483 -299.991204) (xy 418.663118 -299.954367)
			(xy 418.701239 -299.923242) (xy 418.74386 -299.898635) (xy 418.789876 -299.881183) (xy 418.838095 -299.871339)
			(xy 418.88727 -299.869358) (xy 418.936125 -299.87529) (xy 418.983396 -299.888982) (xy 419.027858 -299.91008)
			(xy 419.068361 -299.938036) (xy 419.103854 -299.972128) (xy 419.133419 -300.011472) (xy 419.15629 -300.055049)
			(xy 419.171874 -300.10173) (xy 419.179769 -300.150307) (xy 419.180264 -300.174914) (xy 419.519112 -300.174914)
			(xy 419.523072 -300.12586) (xy 419.534849 -300.078076) (xy 419.55414 -300.0328) (xy 419.580443 -299.991204)
			(xy 419.613078 -299.954367) (xy 419.651199 -299.923242) (xy 419.69382 -299.898635) (xy 419.739836 -299.881183)
			(xy 419.788055 -299.871339) (xy 419.83723 -299.869358) (xy 419.886085 -299.87529) (xy 419.933356 -299.888982)
			(xy 419.977818 -299.91008) (xy 420.018321 -299.938036) (xy 420.053814 -299.972128) (xy 420.083379 -300.011472)
			(xy 420.10625 -300.055049) (xy 420.121834 -300.10173) (xy 420.129729 -300.150307) (xy 420.130224 -300.174914)
			(xy 420.469072 -300.174914) (xy 420.473032 -300.12586) (xy 420.484809 -300.078076) (xy 420.5041 -300.0328)
			(xy 420.530403 -299.991204) (xy 420.563038 -299.954367) (xy 420.601159 -299.923242) (xy 420.64378 -299.898635)
			(xy 420.689796 -299.881183) (xy 420.738015 -299.871339) (xy 420.78719 -299.869358) (xy 420.836045 -299.87529)
			(xy 420.883316 -299.888982) (xy 420.927778 -299.91008) (xy 420.968281 -299.938036) (xy 421.003774 -299.972128)
			(xy 421.033339 -300.011472) (xy 421.05621 -300.055049) (xy 421.071794 -300.10173) (xy 421.079689 -300.150307)
			(xy 421.080184 -300.174914) (xy 421.419032 -300.174914) (xy 421.422992 -300.12586) (xy 421.434769 -300.078076)
			(xy 421.45406 -300.0328) (xy 421.480363 -299.991204) (xy 421.512998 -299.954367) (xy 421.551119 -299.923242)
			(xy 421.59374 -299.898635) (xy 421.639756 -299.881183) (xy 421.687975 -299.871339) (xy 421.73715 -299.869358)
			(xy 421.786005 -299.87529) (xy 421.833276 -299.888982) (xy 421.877738 -299.91008) (xy 421.918241 -299.938036)
			(xy 421.953734 -299.972128) (xy 421.983299 -300.011472) (xy 422.00617 -300.055049) (xy 422.021754 -300.10173)
			(xy 422.029649 -300.150307) (xy 422.030144 -300.174914) (xy 422.368992 -300.174914) (xy 422.372952 -300.12586)
			(xy 422.384729 -300.078076) (xy 422.40402 -300.0328) (xy 422.430323 -299.991204) (xy 422.462958 -299.954367)
			(xy 422.501079 -299.923242) (xy 422.5437 -299.898635) (xy 422.589716 -299.881183) (xy 422.637935 -299.871339)
			(xy 422.68711 -299.869358) (xy 422.735965 -299.87529) (xy 422.783236 -299.888982) (xy 422.827698 -299.91008)
			(xy 422.868201 -299.938036) (xy 422.903694 -299.972128) (xy 422.933259 -300.011472) (xy 422.95613 -300.055049)
			(xy 422.971714 -300.10173) (xy 422.979609 -300.150307) (xy 422.980104 -300.174914) (xy 423.319206 -300.174914)
			(xy 423.323166 -300.12586) (xy 423.334943 -300.078076) (xy 423.354234 -300.0328) (xy 423.380537 -299.991204)
			(xy 423.413172 -299.954367) (xy 423.451293 -299.923242) (xy 423.493914 -299.898635) (xy 423.53993 -299.881183)
			(xy 423.588149 -299.871339) (xy 423.637324 -299.869358) (xy 423.686179 -299.87529) (xy 423.73345 -299.888982)
			(xy 423.777912 -299.91008) (xy 423.818415 -299.938036) (xy 423.853908 -299.972128) (xy 423.883473 -300.011472)
			(xy 423.906344 -300.055049) (xy 423.921928 -300.10173) (xy 423.929823 -300.150307) (xy 423.930318 -300.174914)
			(xy 424.269166 -300.174914) (xy 424.273126 -300.12586) (xy 424.284903 -300.078076) (xy 424.304194 -300.0328)
			(xy 424.330497 -299.991204) (xy 424.363132 -299.954367) (xy 424.401253 -299.923242) (xy 424.443874 -299.898635)
			(xy 424.48989 -299.881183) (xy 424.538109 -299.871339) (xy 424.587284 -299.869358) (xy 424.636139 -299.87529)
			(xy 424.68341 -299.888982) (xy 424.727872 -299.91008) (xy 424.768375 -299.938036) (xy 424.803868 -299.972128)
			(xy 424.833433 -300.011472) (xy 424.856304 -300.055049) (xy 424.871888 -300.10173) (xy 424.879783 -300.150307)
			(xy 424.880278 -300.174914) (xy 425.219126 -300.174914) (xy 425.223086 -300.12586) (xy 425.234863 -300.078076)
			(xy 425.254154 -300.0328) (xy 425.280457 -299.991204) (xy 425.313092 -299.954367) (xy 425.351213 -299.923242)
			(xy 425.393834 -299.898635) (xy 425.43985 -299.881183) (xy 425.488069 -299.871339) (xy 425.537244 -299.869358)
			(xy 425.586099 -299.87529) (xy 425.63337 -299.888982) (xy 425.677832 -299.91008) (xy 425.718335 -299.938036)
			(xy 425.753828 -299.972128) (xy 425.783393 -300.011472) (xy 425.806264 -300.055049) (xy 425.821848 -300.10173)
			(xy 425.829743 -300.150307) (xy 425.830238 -300.174914) (xy 426.169086 -300.174914) (xy 426.173046 -300.12586)
			(xy 426.184823 -300.078076) (xy 426.204114 -300.0328) (xy 426.230417 -299.991204) (xy 426.263052 -299.954367)
			(xy 426.301173 -299.923242) (xy 426.343794 -299.898635) (xy 426.38981 -299.881183) (xy 426.438029 -299.871339)
			(xy 426.487204 -299.869358) (xy 426.536059 -299.87529) (xy 426.58333 -299.888982) (xy 426.627792 -299.91008)
			(xy 426.668295 -299.938036) (xy 426.703788 -299.972128) (xy 426.733353 -300.011472) (xy 426.756224 -300.055049)
			(xy 426.771808 -300.10173) (xy 426.779703 -300.150307) (xy 426.780198 -300.174914) (xy 427.119046 -300.174914)
			(xy 427.123006 -300.12586) (xy 427.134783 -300.078076) (xy 427.154074 -300.0328) (xy 427.180377 -299.991204)
			(xy 427.213012 -299.954367) (xy 427.251133 -299.923242) (xy 427.293754 -299.898635) (xy 427.33977 -299.881183)
			(xy 427.387989 -299.871339) (xy 427.437164 -299.869358) (xy 427.486019 -299.87529) (xy 427.53329 -299.888982)
			(xy 427.577752 -299.91008) (xy 427.618255 -299.938036) (xy 427.653748 -299.972128) (xy 427.683313 -300.011472)
			(xy 427.706184 -300.055049) (xy 427.721768 -300.10173) (xy 427.729663 -300.150307) (xy 427.730158 -300.174914)
			(xy 428.069006 -300.174914) (xy 428.072966 -300.12586) (xy 428.084743 -300.078076) (xy 428.104034 -300.0328)
			(xy 428.130337 -299.991204) (xy 428.162972 -299.954367) (xy 428.201093 -299.923242) (xy 428.243714 -299.898635)
			(xy 428.28973 -299.881183) (xy 428.337949 -299.871339) (xy 428.387124 -299.869358) (xy 428.435979 -299.87529)
			(xy 428.48325 -299.888982) (xy 428.527712 -299.91008) (xy 428.568215 -299.938036) (xy 428.603708 -299.972128)
			(xy 428.633273 -300.011472) (xy 428.656144 -300.055049) (xy 428.671728 -300.10173) (xy 428.679623 -300.150307)
			(xy 428.680118 -300.174914) (xy 429.01922 -300.174914) (xy 429.02318 -300.12586) (xy 429.034957 -300.078076)
			(xy 429.054248 -300.0328) (xy 429.080551 -299.991204) (xy 429.113186 -299.954367) (xy 429.151307 -299.923242)
			(xy 429.193928 -299.898635) (xy 429.239944 -299.881183) (xy 429.288163 -299.871339) (xy 429.337338 -299.869358)
			(xy 429.386193 -299.87529) (xy 429.433464 -299.888982) (xy 429.477926 -299.91008) (xy 429.518429 -299.938036)
			(xy 429.553922 -299.972128) (xy 429.583487 -300.011472) (xy 429.606358 -300.055049) (xy 429.621942 -300.10173)
			(xy 429.629837 -300.150307) (xy 429.630332 -300.174914) (xy 429.96918 -300.174914) (xy 429.97314 -300.12586)
			(xy 429.984917 -300.078076) (xy 430.004208 -300.0328) (xy 430.030511 -299.991204) (xy 430.063146 -299.954367)
			(xy 430.101267 -299.923242) (xy 430.143888 -299.898635) (xy 430.189904 -299.881183) (xy 430.238123 -299.871339)
			(xy 430.287298 -299.869358) (xy 430.336153 -299.87529) (xy 430.383424 -299.888982) (xy 430.427886 -299.91008)
			(xy 430.468389 -299.938036) (xy 430.503882 -299.972128) (xy 430.533447 -300.011472) (xy 430.556318 -300.055049)
			(xy 430.571902 -300.10173) (xy 430.579797 -300.150307) (xy 430.580292 -300.174914) (xy 430.91914 -300.174914)
			(xy 430.9231 -300.12586) (xy 430.934877 -300.078076) (xy 430.954168 -300.0328) (xy 430.980471 -299.991204)
			(xy 431.013106 -299.954367) (xy 431.051227 -299.923242) (xy 431.093848 -299.898635) (xy 431.139864 -299.881183)
			(xy 431.188083 -299.871339) (xy 431.237258 -299.869358) (xy 431.286113 -299.87529) (xy 431.333384 -299.888982)
			(xy 431.377846 -299.91008) (xy 431.418349 -299.938036) (xy 431.453842 -299.972128) (xy 431.483407 -300.011472)
			(xy 431.506278 -300.055049) (xy 431.521862 -300.10173) (xy 431.529757 -300.150307) (xy 431.530252 -300.174914)
			(xy 431.529757 -300.199521) (xy 431.521862 -300.248098) (xy 431.506278 -300.294779) (xy 431.483407 -300.338356)
			(xy 431.453842 -300.3777) (xy 431.418349 -300.411792) (xy 431.377846 -300.439748) (xy 431.333384 -300.460846)
			(xy 431.286113 -300.474538) (xy 431.237258 -300.48047) (xy 431.188083 -300.478489) (xy 431.139864 -300.468645)
			(xy 431.093848 -300.451193) (xy 431.051227 -300.426586) (xy 431.013106 -300.395461) (xy 430.980471 -300.358624)
			(xy 430.954168 -300.317028) (xy 430.934877 -300.271752) (xy 430.9231 -300.223968) (xy 430.91914 -300.174914)
			(xy 430.580292 -300.174914) (xy 430.579797 -300.199521) (xy 430.571902 -300.248098) (xy 430.556318 -300.294779)
			(xy 430.533447 -300.338356) (xy 430.503882 -300.3777) (xy 430.468389 -300.411792) (xy 430.427886 -300.439748)
			(xy 430.383424 -300.460846) (xy 430.336153 -300.474538) (xy 430.287298 -300.48047) (xy 430.238123 -300.478489)
			(xy 430.189904 -300.468645) (xy 430.143888 -300.451193) (xy 430.101267 -300.426586) (xy 430.063146 -300.395461)
			(xy 430.030511 -300.358624) (xy 430.004208 -300.317028) (xy 429.984917 -300.271752) (xy 429.97314 -300.223968)
			(xy 429.96918 -300.174914) (xy 429.630332 -300.174914) (xy 429.629837 -300.199521) (xy 429.621942 -300.248098)
			(xy 429.606358 -300.294779) (xy 429.583487 -300.338356) (xy 429.553922 -300.3777) (xy 429.518429 -300.411792)
			(xy 429.477926 -300.439748) (xy 429.433464 -300.460846) (xy 429.386193 -300.474538) (xy 429.337338 -300.48047)
			(xy 429.288163 -300.478489) (xy 429.239944 -300.468645) (xy 429.193928 -300.451193) (xy 429.151307 -300.426586)
			(xy 429.113186 -300.395461) (xy 429.080551 -300.358624) (xy 429.054248 -300.317028) (xy 429.034957 -300.271752)
			(xy 429.02318 -300.223968) (xy 429.01922 -300.174914) (xy 428.680118 -300.174914) (xy 428.679623 -300.199521)
			(xy 428.671728 -300.248098) (xy 428.656144 -300.294779) (xy 428.633273 -300.338356) (xy 428.603708 -300.3777)
			(xy 428.568215 -300.411792) (xy 428.527712 -300.439748) (xy 428.48325 -300.460846) (xy 428.435979 -300.474538)
			(xy 428.387124 -300.48047) (xy 428.337949 -300.478489) (xy 428.28973 -300.468645) (xy 428.243714 -300.451193)
			(xy 428.201093 -300.426586) (xy 428.162972 -300.395461) (xy 428.130337 -300.358624) (xy 428.104034 -300.317028)
			(xy 428.084743 -300.271752) (xy 428.072966 -300.223968) (xy 428.069006 -300.174914) (xy 427.730158 -300.174914)
			(xy 427.729663 -300.199521) (xy 427.721768 -300.248098) (xy 427.706184 -300.294779) (xy 427.683313 -300.338356)
			(xy 427.653748 -300.3777) (xy 427.618255 -300.411792) (xy 427.577752 -300.439748) (xy 427.53329 -300.460846)
			(xy 427.486019 -300.474538) (xy 427.437164 -300.48047) (xy 427.387989 -300.478489) (xy 427.33977 -300.468645)
			(xy 427.293754 -300.451193) (xy 427.251133 -300.426586) (xy 427.213012 -300.395461) (xy 427.180377 -300.358624)
			(xy 427.154074 -300.317028) (xy 427.134783 -300.271752) (xy 427.123006 -300.223968) (xy 427.119046 -300.174914)
			(xy 426.780198 -300.174914) (xy 426.779703 -300.199521) (xy 426.771808 -300.248098) (xy 426.756224 -300.294779)
			(xy 426.733353 -300.338356) (xy 426.703788 -300.3777) (xy 426.668295 -300.411792) (xy 426.627792 -300.439748)
			(xy 426.58333 -300.460846) (xy 426.536059 -300.474538) (xy 426.487204 -300.48047) (xy 426.438029 -300.478489)
			(xy 426.38981 -300.468645) (xy 426.343794 -300.451193) (xy 426.301173 -300.426586) (xy 426.263052 -300.395461)
			(xy 426.230417 -300.358624) (xy 426.204114 -300.317028) (xy 426.184823 -300.271752) (xy 426.173046 -300.223968)
			(xy 426.169086 -300.174914) (xy 425.830238 -300.174914) (xy 425.829743 -300.199521) (xy 425.821848 -300.248098)
			(xy 425.806264 -300.294779) (xy 425.783393 -300.338356) (xy 425.753828 -300.3777) (xy 425.718335 -300.411792)
			(xy 425.677832 -300.439748) (xy 425.63337 -300.460846) (xy 425.586099 -300.474538) (xy 425.537244 -300.48047)
			(xy 425.488069 -300.478489) (xy 425.43985 -300.468645) (xy 425.393834 -300.451193) (xy 425.351213 -300.426586)
			(xy 425.313092 -300.395461) (xy 425.280457 -300.358624) (xy 425.254154 -300.317028) (xy 425.234863 -300.271752)
			(xy 425.223086 -300.223968) (xy 425.219126 -300.174914) (xy 424.880278 -300.174914) (xy 424.879783 -300.199521)
			(xy 424.871888 -300.248098) (xy 424.856304 -300.294779) (xy 424.833433 -300.338356) (xy 424.803868 -300.3777)
			(xy 424.768375 -300.411792) (xy 424.727872 -300.439748) (xy 424.68341 -300.460846) (xy 424.636139 -300.474538)
			(xy 424.587284 -300.48047) (xy 424.538109 -300.478489) (xy 424.48989 -300.468645) (xy 424.443874 -300.451193)
			(xy 424.401253 -300.426586) (xy 424.363132 -300.395461) (xy 424.330497 -300.358624) (xy 424.304194 -300.317028)
			(xy 424.284903 -300.271752) (xy 424.273126 -300.223968) (xy 424.269166 -300.174914) (xy 423.930318 -300.174914)
			(xy 423.929823 -300.199521) (xy 423.921928 -300.248098) (xy 423.906344 -300.294779) (xy 423.883473 -300.338356)
			(xy 423.853908 -300.3777) (xy 423.818415 -300.411792) (xy 423.777912 -300.439748) (xy 423.73345 -300.460846)
			(xy 423.686179 -300.474538) (xy 423.637324 -300.48047) (xy 423.588149 -300.478489) (xy 423.53993 -300.468645)
			(xy 423.493914 -300.451193) (xy 423.451293 -300.426586) (xy 423.413172 -300.395461) (xy 423.380537 -300.358624)
			(xy 423.354234 -300.317028) (xy 423.334943 -300.271752) (xy 423.323166 -300.223968) (xy 423.319206 -300.174914)
			(xy 422.980104 -300.174914) (xy 422.979609 -300.199521) (xy 422.971714 -300.248098) (xy 422.95613 -300.294779)
			(xy 422.933259 -300.338356) (xy 422.903694 -300.3777) (xy 422.868201 -300.411792) (xy 422.827698 -300.439748)
			(xy 422.783236 -300.460846) (xy 422.735965 -300.474538) (xy 422.68711 -300.48047) (xy 422.637935 -300.478489)
			(xy 422.589716 -300.468645) (xy 422.5437 -300.451193) (xy 422.501079 -300.426586) (xy 422.462958 -300.395461)
			(xy 422.430323 -300.358624) (xy 422.40402 -300.317028) (xy 422.384729 -300.271752) (xy 422.372952 -300.223968)
			(xy 422.368992 -300.174914) (xy 422.030144 -300.174914) (xy 422.029649 -300.199521) (xy 422.021754 -300.248098)
			(xy 422.00617 -300.294779) (xy 421.983299 -300.338356) (xy 421.953734 -300.3777) (xy 421.918241 -300.411792)
			(xy 421.877738 -300.439748) (xy 421.833276 -300.460846) (xy 421.786005 -300.474538) (xy 421.73715 -300.48047)
			(xy 421.687975 -300.478489) (xy 421.639756 -300.468645) (xy 421.59374 -300.451193) (xy 421.551119 -300.426586)
			(xy 421.512998 -300.395461) (xy 421.480363 -300.358624) (xy 421.45406 -300.317028) (xy 421.434769 -300.271752)
			(xy 421.422992 -300.223968) (xy 421.419032 -300.174914) (xy 421.080184 -300.174914) (xy 421.079689 -300.199521)
			(xy 421.071794 -300.248098) (xy 421.05621 -300.294779) (xy 421.033339 -300.338356) (xy 421.003774 -300.3777)
			(xy 420.968281 -300.411792) (xy 420.927778 -300.439748) (xy 420.883316 -300.460846) (xy 420.836045 -300.474538)
			(xy 420.78719 -300.48047) (xy 420.738015 -300.478489) (xy 420.689796 -300.468645) (xy 420.64378 -300.451193)
			(xy 420.601159 -300.426586) (xy 420.563038 -300.395461) (xy 420.530403 -300.358624) (xy 420.5041 -300.317028)
			(xy 420.484809 -300.271752) (xy 420.473032 -300.223968) (xy 420.469072 -300.174914) (xy 420.130224 -300.174914)
			(xy 420.129729 -300.199521) (xy 420.121834 -300.248098) (xy 420.10625 -300.294779) (xy 420.083379 -300.338356)
			(xy 420.053814 -300.3777) (xy 420.018321 -300.411792) (xy 419.977818 -300.439748) (xy 419.933356 -300.460846)
			(xy 419.886085 -300.474538) (xy 419.83723 -300.48047) (xy 419.788055 -300.478489) (xy 419.739836 -300.468645)
			(xy 419.69382 -300.451193) (xy 419.651199 -300.426586) (xy 419.613078 -300.395461) (xy 419.580443 -300.358624)
			(xy 419.55414 -300.317028) (xy 419.534849 -300.271752) (xy 419.523072 -300.223968) (xy 419.519112 -300.174914)
			(xy 419.180264 -300.174914) (xy 419.179769 -300.199521) (xy 419.171874 -300.248098) (xy 419.15629 -300.294779)
			(xy 419.133419 -300.338356) (xy 419.103854 -300.3777) (xy 419.068361 -300.411792) (xy 419.027858 -300.439748)
			(xy 418.983396 -300.460846) (xy 418.936125 -300.474538) (xy 418.88727 -300.48047) (xy 418.838095 -300.478489)
			(xy 418.789876 -300.468645) (xy 418.74386 -300.451193) (xy 418.701239 -300.426586) (xy 418.663118 -300.395461)
			(xy 418.630483 -300.358624) (xy 418.60418 -300.317028) (xy 418.584889 -300.271752) (xy 418.573112 -300.223968)
			(xy 418.569152 -300.174914) (xy 418.230304 -300.174914) (xy 418.229809 -300.199521) (xy 418.221914 -300.248098)
			(xy 418.20633 -300.294779) (xy 418.183459 -300.338356) (xy 418.153894 -300.3777) (xy 418.118401 -300.411792)
			(xy 418.077898 -300.439748) (xy 418.033436 -300.460846) (xy 417.986165 -300.474538) (xy 417.93731 -300.48047)
			(xy 417.888135 -300.478489) (xy 417.839916 -300.468645) (xy 417.7939 -300.451193) (xy 417.751279 -300.426586)
			(xy 417.713158 -300.395461) (xy 417.680523 -300.358624) (xy 417.65422 -300.317028) (xy 417.634929 -300.271752)
			(xy 417.623152 -300.223968) (xy 417.619192 -300.174914) (xy 417.28009 -300.174914) (xy 417.279595 -300.199521)
			(xy 417.2717 -300.248098) (xy 417.256116 -300.294779) (xy 417.233245 -300.338356) (xy 417.20368 -300.3777)
			(xy 417.168187 -300.411792) (xy 417.127684 -300.439748) (xy 417.083222 -300.460846) (xy 417.035951 -300.474538)
			(xy 416.987096 -300.48047) (xy 416.937921 -300.478489) (xy 416.889702 -300.468645) (xy 416.843686 -300.451193)
			(xy 416.801065 -300.426586) (xy 416.762944 -300.395461) (xy 416.730309 -300.358624) (xy 416.704006 -300.317028)
			(xy 416.684715 -300.271752) (xy 416.672938 -300.223968) (xy 416.668978 -300.174914) (xy 416.33013 -300.174914)
			(xy 416.329635 -300.199521) (xy 416.32174 -300.248098) (xy 416.306156 -300.294779) (xy 416.283285 -300.338356)
			(xy 416.25372 -300.3777) (xy 416.218227 -300.411792) (xy 416.177724 -300.439748) (xy 416.133262 -300.460846)
			(xy 416.085991 -300.474538) (xy 416.037136 -300.48047) (xy 415.987961 -300.478489) (xy 415.939742 -300.468645)
			(xy 415.893726 -300.451193) (xy 415.851105 -300.426586) (xy 415.812984 -300.395461) (xy 415.780349 -300.358624)
			(xy 415.754046 -300.317028) (xy 415.734755 -300.271752) (xy 415.722978 -300.223968) (xy 415.719018 -300.174914)
			(xy 415.38017 -300.174914) (xy 415.379675 -300.199521) (xy 415.37178 -300.248098) (xy 415.356196 -300.294779)
			(xy 415.333325 -300.338356) (xy 415.30376 -300.3777) (xy 415.268267 -300.411792) (xy 415.227764 -300.439748)
			(xy 415.183302 -300.460846) (xy 415.136031 -300.474538) (xy 415.087176 -300.48047) (xy 415.038001 -300.478489)
			(xy 414.989782 -300.468645) (xy 414.943766 -300.451193) (xy 414.901145 -300.426586) (xy 414.863024 -300.395461)
			(xy 414.830389 -300.358624) (xy 414.804086 -300.317028) (xy 414.784795 -300.271752) (xy 414.773018 -300.223968)
			(xy 414.769058 -300.174914) (xy 414.43021 -300.174914) (xy 414.429715 -300.199521) (xy 414.42182 -300.248098)
			(xy 414.406236 -300.294779) (xy 414.383365 -300.338356) (xy 414.3538 -300.3777) (xy 414.318307 -300.411792)
			(xy 414.277804 -300.439748) (xy 414.233342 -300.460846) (xy 414.186071 -300.474538) (xy 414.137216 -300.48047)
			(xy 414.088041 -300.478489) (xy 414.039822 -300.468645) (xy 413.993806 -300.451193) (xy 413.951185 -300.426586)
			(xy 413.913064 -300.395461) (xy 413.880429 -300.358624) (xy 413.854126 -300.317028) (xy 413.834835 -300.271752)
			(xy 413.823058 -300.223968) (xy 413.819098 -300.174914) (xy 413.48025 -300.174914) (xy 413.479755 -300.199521)
			(xy 413.47186 -300.248098) (xy 413.456276 -300.294779) (xy 413.433405 -300.338356) (xy 413.40384 -300.3777)
			(xy 413.368347 -300.411792) (xy 413.327844 -300.439748) (xy 413.283382 -300.460846) (xy 413.236111 -300.474538)
			(xy 413.187256 -300.48047) (xy 413.138081 -300.478489) (xy 413.089862 -300.468645) (xy 413.043846 -300.451193)
			(xy 413.001225 -300.426586) (xy 412.963104 -300.395461) (xy 412.930469 -300.358624) (xy 412.904166 -300.317028)
			(xy 412.884875 -300.271752) (xy 412.873098 -300.223968) (xy 412.869138 -300.174914) (xy 412.53029 -300.174914)
			(xy 412.529795 -300.199521) (xy 412.5219 -300.248098) (xy 412.506316 -300.294779) (xy 412.483445 -300.338356)
			(xy 412.45388 -300.3777) (xy 412.418387 -300.411792) (xy 412.377884 -300.439748) (xy 412.333422 -300.460846)
			(xy 412.286151 -300.474538) (xy 412.237296 -300.48047) (xy 412.188121 -300.478489) (xy 412.139902 -300.468645)
			(xy 412.093886 -300.451193) (xy 412.051265 -300.426586) (xy 412.013144 -300.395461) (xy 411.980509 -300.358624)
			(xy 411.954206 -300.317028) (xy 411.934915 -300.271752) (xy 411.923138 -300.223968) (xy 411.919178 -300.174914)
			(xy 411.58033 -300.174914) (xy 411.579835 -300.199521) (xy 411.57194 -300.248098) (xy 411.556356 -300.294779)
			(xy 411.533485 -300.338356) (xy 411.50392 -300.3777) (xy 411.468427 -300.411792) (xy 411.427924 -300.439748)
			(xy 411.383462 -300.460846) (xy 411.336191 -300.474538) (xy 411.287336 -300.48047) (xy 411.238161 -300.478489)
			(xy 411.189942 -300.468645) (xy 411.143926 -300.451193) (xy 411.101305 -300.426586) (xy 411.063184 -300.395461)
			(xy 411.030549 -300.358624) (xy 411.004246 -300.317028) (xy 410.984955 -300.271752) (xy 410.973178 -300.223968)
			(xy 410.969218 -300.174914) (xy 410.630116 -300.174914) (xy 410.629621 -300.199521) (xy 410.621726 -300.248098)
			(xy 410.606142 -300.294779) (xy 410.583271 -300.338356) (xy 410.553706 -300.3777) (xy 410.518213 -300.411792)
			(xy 410.47771 -300.439748) (xy 410.433248 -300.460846) (xy 410.385977 -300.474538) (xy 410.337122 -300.48047)
			(xy 410.287947 -300.478489) (xy 410.239728 -300.468645) (xy 410.193712 -300.451193) (xy 410.151091 -300.426586)
			(xy 410.11297 -300.395461) (xy 410.080335 -300.358624) (xy 410.054032 -300.317028) (xy 410.034741 -300.271752)
			(xy 410.022964 -300.223968) (xy 410.019004 -300.174914) (xy 409.680156 -300.174914) (xy 409.679661 -300.199521)
			(xy 409.671766 -300.248098) (xy 409.656182 -300.294779) (xy 409.633311 -300.338356) (xy 409.603746 -300.3777)
			(xy 409.568253 -300.411792) (xy 409.52775 -300.439748) (xy 409.483288 -300.460846) (xy 409.436017 -300.474538)
			(xy 409.387162 -300.48047) (xy 409.337987 -300.478489) (xy 409.289768 -300.468645) (xy 409.243752 -300.451193)
			(xy 409.201131 -300.426586) (xy 409.16301 -300.395461) (xy 409.130375 -300.358624) (xy 409.104072 -300.317028)
			(xy 409.084781 -300.271752) (xy 409.073004 -300.223968) (xy 409.069044 -300.174914) (xy 408.730196 -300.174914)
			(xy 408.729701 -300.199521) (xy 408.721806 -300.248098) (xy 408.706222 -300.294779) (xy 408.683351 -300.338356)
			(xy 408.653786 -300.3777) (xy 408.618293 -300.411792) (xy 408.57779 -300.439748) (xy 408.533328 -300.460846)
			(xy 408.486057 -300.474538) (xy 408.437202 -300.48047) (xy 408.388027 -300.478489) (xy 408.339808 -300.468645)
			(xy 408.293792 -300.451193) (xy 408.251171 -300.426586) (xy 408.21305 -300.395461) (xy 408.180415 -300.358624)
			(xy 408.154112 -300.317028) (xy 408.134821 -300.271752) (xy 408.123044 -300.223968) (xy 408.119084 -300.174914)
			(xy 406.830276 -300.174914) (xy 406.829781 -300.199521) (xy 406.821886 -300.248098) (xy 406.806302 -300.294779)
			(xy 406.783431 -300.338356) (xy 406.753866 -300.3777) (xy 406.718373 -300.411792) (xy 406.67787 -300.439748)
			(xy 406.633408 -300.460846) (xy 406.586137 -300.474538) (xy 406.537282 -300.48047) (xy 406.488107 -300.478489)
			(xy 406.439888 -300.468645) (xy 406.393872 -300.451193) (xy 406.351251 -300.426586) (xy 406.31313 -300.395461)
			(xy 406.280495 -300.358624) (xy 406.254192 -300.317028) (xy 406.234901 -300.271752) (xy 406.223124 -300.223968)
			(xy 406.219164 -300.174914) (xy 405.880316 -300.174914) (xy 405.879821 -300.199521) (xy 405.871926 -300.248098)
			(xy 405.856342 -300.294779) (xy 405.833471 -300.338356) (xy 405.803906 -300.3777) (xy 405.768413 -300.411792)
			(xy 405.72791 -300.439748) (xy 405.683448 -300.460846) (xy 405.636177 -300.474538) (xy 405.587322 -300.48047)
			(xy 405.538147 -300.478489) (xy 405.489928 -300.468645) (xy 405.443912 -300.451193) (xy 405.401291 -300.426586)
			(xy 405.36317 -300.395461) (xy 405.330535 -300.358624) (xy 405.304232 -300.317028) (xy 405.284941 -300.271752)
			(xy 405.273164 -300.223968) (xy 405.269204 -300.174914) (xy 404.930102 -300.174914) (xy 404.929607 -300.199521)
			(xy 404.921712 -300.248098) (xy 404.906128 -300.294779) (xy 404.883257 -300.338356) (xy 404.853692 -300.3777)
			(xy 404.818199 -300.411792) (xy 404.777696 -300.439748) (xy 404.733234 -300.460846) (xy 404.685963 -300.474538)
			(xy 404.637108 -300.48047) (xy 404.587933 -300.478489) (xy 404.539714 -300.468645) (xy 404.493698 -300.451193)
			(xy 404.451077 -300.426586) (xy 404.412956 -300.395461) (xy 404.380321 -300.358624) (xy 404.354018 -300.317028)
			(xy 404.334727 -300.271752) (xy 404.32295 -300.223968) (xy 404.31899 -300.174914) (xy 403.980142 -300.174914)
			(xy 403.979647 -300.199521) (xy 403.971752 -300.248098) (xy 403.956168 -300.294779) (xy 403.933297 -300.338356)
			(xy 403.903732 -300.3777) (xy 403.868239 -300.411792) (xy 403.827736 -300.439748) (xy 403.783274 -300.460846)
			(xy 403.736003 -300.474538) (xy 403.687148 -300.48047) (xy 403.637973 -300.478489) (xy 403.589754 -300.468645)
			(xy 403.543738 -300.451193) (xy 403.501117 -300.426586) (xy 403.462996 -300.395461) (xy 403.430361 -300.358624)
			(xy 403.404058 -300.317028) (xy 403.384767 -300.271752) (xy 403.37299 -300.223968) (xy 403.36903 -300.174914)
			(xy 403.030182 -300.174914) (xy 403.029687 -300.199521) (xy 403.021792 -300.248098) (xy 403.006208 -300.294779)
			(xy 402.983337 -300.338356) (xy 402.953772 -300.3777) (xy 402.918279 -300.411792) (xy 402.877776 -300.439748)
			(xy 402.833314 -300.460846) (xy 402.786043 -300.474538) (xy 402.737188 -300.48047) (xy 402.688013 -300.478489)
			(xy 402.639794 -300.468645) (xy 402.593778 -300.451193) (xy 402.551157 -300.426586) (xy 402.513036 -300.395461)
			(xy 402.480401 -300.358624) (xy 402.454098 -300.317028) (xy 402.434807 -300.271752) (xy 402.42303 -300.223968)
			(xy 402.41907 -300.174914) (xy 402.080222 -300.174914) (xy 402.079727 -300.199521) (xy 402.071832 -300.248098)
			(xy 402.056248 -300.294779) (xy 402.033377 -300.338356) (xy 402.003812 -300.3777) (xy 401.968319 -300.411792)
			(xy 401.927816 -300.439748) (xy 401.883354 -300.460846) (xy 401.836083 -300.474538) (xy 401.787228 -300.48047)
			(xy 401.738053 -300.478489) (xy 401.689834 -300.468645) (xy 401.643818 -300.451193) (xy 401.601197 -300.426586)
			(xy 401.563076 -300.395461) (xy 401.530441 -300.358624) (xy 401.504138 -300.317028) (xy 401.484847 -300.271752)
			(xy 401.47307 -300.223968) (xy 401.46911 -300.174914) (xy 401.130262 -300.174914) (xy 401.129767 -300.199521)
			(xy 401.121872 -300.248098) (xy 401.106288 -300.294779) (xy 401.083417 -300.338356) (xy 401.053852 -300.3777)
			(xy 401.018359 -300.411792) (xy 400.977856 -300.439748) (xy 400.933394 -300.460846) (xy 400.886123 -300.474538)
			(xy 400.837268 -300.48047) (xy 400.788093 -300.478489) (xy 400.739874 -300.468645) (xy 400.693858 -300.451193)
			(xy 400.651237 -300.426586) (xy 400.613116 -300.395461) (xy 400.580481 -300.358624) (xy 400.554178 -300.317028)
			(xy 400.534887 -300.271752) (xy 400.52311 -300.223968) (xy 400.51915 -300.174914) (xy 400.180302 -300.174914)
			(xy 400.179807 -300.199521) (xy 400.171912 -300.248098) (xy 400.156328 -300.294779) (xy 400.133457 -300.338356)
			(xy 400.103892 -300.3777) (xy 400.068399 -300.411792) (xy 400.027896 -300.439748) (xy 399.983434 -300.460846)
			(xy 399.936163 -300.474538) (xy 399.887308 -300.48047) (xy 399.838133 -300.478489) (xy 399.789914 -300.468645)
			(xy 399.743898 -300.451193) (xy 399.701277 -300.426586) (xy 399.663156 -300.395461) (xy 399.630521 -300.358624)
			(xy 399.604218 -300.317028) (xy 399.584927 -300.271752) (xy 399.57315 -300.223968) (xy 399.56919 -300.174914)
			(xy 399.230342 -300.174914) (xy 399.229847 -300.199521) (xy 399.221952 -300.248098) (xy 399.206368 -300.294779)
			(xy 399.183497 -300.338356) (xy 399.153932 -300.3777) (xy 399.118439 -300.411792) (xy 399.077936 -300.439748)
			(xy 399.033474 -300.460846) (xy 398.986203 -300.474538) (xy 398.937348 -300.48047) (xy 398.888173 -300.478489)
			(xy 398.839954 -300.468645) (xy 398.793938 -300.451193) (xy 398.751317 -300.426586) (xy 398.713196 -300.395461)
			(xy 398.680561 -300.358624) (xy 398.654258 -300.317028) (xy 398.634967 -300.271752) (xy 398.62319 -300.223968)
			(xy 398.61923 -300.174914) (xy 398.280128 -300.174914) (xy 398.279633 -300.199521) (xy 398.271738 -300.248098)
			(xy 398.256154 -300.294779) (xy 398.233283 -300.338356) (xy 398.203718 -300.3777) (xy 398.168225 -300.411792)
			(xy 398.127722 -300.439748) (xy 398.08326 -300.460846) (xy 398.035989 -300.474538) (xy 397.987134 -300.48047)
			(xy 397.937959 -300.478489) (xy 397.88974 -300.468645) (xy 397.843724 -300.451193) (xy 397.801103 -300.426586)
			(xy 397.762982 -300.395461) (xy 397.730347 -300.358624) (xy 397.704044 -300.317028) (xy 397.684753 -300.271752)
			(xy 397.672976 -300.223968) (xy 397.669016 -300.174914) (xy 397.355133 -300.174914) (xy 397.355133 -300.201263)
			(xy 397.346769 -300.253316) (xy 397.330253 -300.303384) (xy 397.306004 -300.350197) (xy 397.274636 -300.392571)
			(xy 397.236942 -300.429432) (xy 397.193879 -300.459847) (xy 397.146536 -300.483045) (xy 397.096112 -300.498439)
			(xy 397.070072 -300.502574) (xy 397.066008 -300.503082) (xy 397.054578 -300.506638) (xy 397.05026 -300.507908)
			(xy 397.02613 -300.519084) (xy 397.019526 -300.526196) (xy 397.004794 -300.54169) (xy 396.996666 -300.552866)
			(xy 396.99397 -300.558397) (xy 396.991014 -300.570338) (xy 396.990824 -300.576488) (xy 396.990824 -300.7233)
			(xy 396.990997 -300.729452) (xy 396.993957 -300.741395) (xy 396.996666 -300.746922) (xy 397.004794 -300.758098)
			(xy 397.019526 -300.773592) (xy 397.02613 -300.780704) (xy 397.05026 -300.79188) (xy 397.054578 -300.79315)
			(xy 397.066008 -300.796706) (xy 397.070072 -300.797214) (xy 397.096119 -300.801322) (xy 397.146549 -300.816718)
			(xy 397.193898 -300.839918) (xy 397.236966 -300.870336) (xy 397.274664 -300.907202) (xy 397.306037 -300.94958)
			(xy 397.330289 -300.996399) (xy 397.346807 -301.046473) (xy 397.355172 -301.098533) (xy 397.355172 -301.124874)
			(xy 397.669016 -301.124874) (xy 397.672976 -301.07582) (xy 397.684753 -301.028036) (xy 397.704044 -300.98276)
			(xy 397.730347 -300.941164) (xy 397.762982 -300.904327) (xy 397.801103 -300.873202) (xy 397.843724 -300.848595)
			(xy 397.88974 -300.831143) (xy 397.937959 -300.821299) (xy 397.987134 -300.819318) (xy 398.035989 -300.82525)
			(xy 398.08326 -300.838942) (xy 398.127722 -300.86004) (xy 398.168225 -300.887996) (xy 398.203718 -300.922088)
			(xy 398.233283 -300.961432) (xy 398.256154 -301.005009) (xy 398.271738 -301.05169) (xy 398.279633 -301.100267)
			(xy 398.280128 -301.124874) (xy 398.61923 -301.124874) (xy 398.62319 -301.07582) (xy 398.634967 -301.028036)
			(xy 398.654258 -300.98276) (xy 398.680561 -300.941164) (xy 398.713196 -300.904327) (xy 398.751317 -300.873202)
			(xy 398.793938 -300.848595) (xy 398.839954 -300.831143) (xy 398.888173 -300.821299) (xy 398.937348 -300.819318)
			(xy 398.986203 -300.82525) (xy 399.033474 -300.838942) (xy 399.077936 -300.86004) (xy 399.118439 -300.887996)
			(xy 399.153932 -300.922088) (xy 399.183497 -300.961432) (xy 399.206368 -301.005009) (xy 399.221952 -301.05169)
			(xy 399.229847 -301.100267) (xy 399.230342 -301.124874) (xy 399.56919 -301.124874) (xy 399.57315 -301.07582)
			(xy 399.584927 -301.028036) (xy 399.604218 -300.98276) (xy 399.630521 -300.941164) (xy 399.663156 -300.904327)
			(xy 399.701277 -300.873202) (xy 399.743898 -300.848595) (xy 399.789914 -300.831143) (xy 399.838133 -300.821299)
			(xy 399.887308 -300.819318) (xy 399.936163 -300.82525) (xy 399.983434 -300.838942) (xy 400.027896 -300.86004)
			(xy 400.068399 -300.887996) (xy 400.103892 -300.922088) (xy 400.133457 -300.961432) (xy 400.156328 -301.005009)
			(xy 400.171912 -301.05169) (xy 400.179807 -301.100267) (xy 400.180302 -301.124874) (xy 400.51915 -301.124874)
			(xy 400.52311 -301.07582) (xy 400.534887 -301.028036) (xy 400.554178 -300.98276) (xy 400.580481 -300.941164)
			(xy 400.613116 -300.904327) (xy 400.651237 -300.873202) (xy 400.693858 -300.848595) (xy 400.739874 -300.831143)
			(xy 400.788093 -300.821299) (xy 400.837268 -300.819318) (xy 400.886123 -300.82525) (xy 400.933394 -300.838942)
			(xy 400.977856 -300.86004) (xy 401.018359 -300.887996) (xy 401.053852 -300.922088) (xy 401.083417 -300.961432)
			(xy 401.106288 -301.005009) (xy 401.121872 -301.05169) (xy 401.129767 -301.100267) (xy 401.130262 -301.124874)
			(xy 401.46911 -301.124874) (xy 401.47307 -301.07582) (xy 401.484847 -301.028036) (xy 401.504138 -300.98276)
			(xy 401.530441 -300.941164) (xy 401.563076 -300.904327) (xy 401.601197 -300.873202) (xy 401.643818 -300.848595)
			(xy 401.689834 -300.831143) (xy 401.738053 -300.821299) (xy 401.787228 -300.819318) (xy 401.836083 -300.82525)
			(xy 401.883354 -300.838942) (xy 401.927816 -300.86004) (xy 401.968319 -300.887996) (xy 402.003812 -300.922088)
			(xy 402.033377 -300.961432) (xy 402.056248 -301.005009) (xy 402.071832 -301.05169) (xy 402.079727 -301.100267)
			(xy 402.080222 -301.124874) (xy 402.41907 -301.124874) (xy 402.42303 -301.07582) (xy 402.434807 -301.028036)
			(xy 402.454098 -300.98276) (xy 402.480401 -300.941164) (xy 402.513036 -300.904327) (xy 402.551157 -300.873202)
			(xy 402.593778 -300.848595) (xy 402.639794 -300.831143) (xy 402.688013 -300.821299) (xy 402.737188 -300.819318)
			(xy 402.786043 -300.82525) (xy 402.833314 -300.838942) (xy 402.877776 -300.86004) (xy 402.918279 -300.887996)
			(xy 402.953772 -300.922088) (xy 402.983337 -300.961432) (xy 403.006208 -301.005009) (xy 403.021792 -301.05169)
			(xy 403.029687 -301.100267) (xy 403.030182 -301.124874) (xy 403.36903 -301.124874) (xy 403.37299 -301.07582)
			(xy 403.384767 -301.028036) (xy 403.404058 -300.98276) (xy 403.430361 -300.941164) (xy 403.462996 -300.904327)
			(xy 403.501117 -300.873202) (xy 403.543738 -300.848595) (xy 403.589754 -300.831143) (xy 403.637973 -300.821299)
			(xy 403.687148 -300.819318) (xy 403.736003 -300.82525) (xy 403.783274 -300.838942) (xy 403.827736 -300.86004)
			(xy 403.868239 -300.887996) (xy 403.903732 -300.922088) (xy 403.933297 -300.961432) (xy 403.956168 -301.005009)
			(xy 403.971752 -301.05169) (xy 403.979647 -301.100267) (xy 403.980142 -301.124874) (xy 404.31899 -301.124874)
			(xy 404.32295 -301.07582) (xy 404.334727 -301.028036) (xy 404.354018 -300.98276) (xy 404.380321 -300.941164)
			(xy 404.412956 -300.904327) (xy 404.451077 -300.873202) (xy 404.493698 -300.848595) (xy 404.539714 -300.831143)
			(xy 404.587933 -300.821299) (xy 404.637108 -300.819318) (xy 404.685963 -300.82525) (xy 404.733234 -300.838942)
			(xy 404.777696 -300.86004) (xy 404.818199 -300.887996) (xy 404.853692 -300.922088) (xy 404.883257 -300.961432)
			(xy 404.906128 -301.005009) (xy 404.921712 -301.05169) (xy 404.929607 -301.100267) (xy 404.930102 -301.124874)
			(xy 405.269204 -301.124874) (xy 405.273164 -301.07582) (xy 405.284941 -301.028036) (xy 405.304232 -300.98276)
			(xy 405.330535 -300.941164) (xy 405.36317 -300.904327) (xy 405.401291 -300.873202) (xy 405.443912 -300.848595)
			(xy 405.489928 -300.831143) (xy 405.538147 -300.821299) (xy 405.587322 -300.819318) (xy 405.636177 -300.82525)
			(xy 405.683448 -300.838942) (xy 405.72791 -300.86004) (xy 405.768413 -300.887996) (xy 405.803906 -300.922088)
			(xy 405.833471 -300.961432) (xy 405.856342 -301.005009) (xy 405.871926 -301.05169) (xy 405.879821 -301.100267)
			(xy 405.880316 -301.124874) (xy 406.219164 -301.124874) (xy 406.223124 -301.07582) (xy 406.234901 -301.028036)
			(xy 406.254192 -300.98276) (xy 406.280495 -300.941164) (xy 406.31313 -300.904327) (xy 406.351251 -300.873202)
			(xy 406.393872 -300.848595) (xy 406.439888 -300.831143) (xy 406.488107 -300.821299) (xy 406.537282 -300.819318)
			(xy 406.586137 -300.82525) (xy 406.633408 -300.838942) (xy 406.67787 -300.86004) (xy 406.718373 -300.887996)
			(xy 406.753866 -300.922088) (xy 406.783431 -300.961432) (xy 406.806302 -301.005009) (xy 406.821886 -301.05169)
			(xy 406.829781 -301.100267) (xy 406.830276 -301.124874) (xy 408.119084 -301.124874) (xy 408.123044 -301.07582)
			(xy 408.134821 -301.028036) (xy 408.154112 -300.98276) (xy 408.180415 -300.941164) (xy 408.21305 -300.904327)
			(xy 408.251171 -300.873202) (xy 408.293792 -300.848595) (xy 408.339808 -300.831143) (xy 408.388027 -300.821299)
			(xy 408.437202 -300.819318) (xy 408.486057 -300.82525) (xy 408.533328 -300.838942) (xy 408.57779 -300.86004)
			(xy 408.618293 -300.887996) (xy 408.653786 -300.922088) (xy 408.683351 -300.961432) (xy 408.706222 -301.005009)
			(xy 408.721806 -301.05169) (xy 408.729701 -301.100267) (xy 408.730196 -301.124874) (xy 409.069044 -301.124874)
			(xy 409.073004 -301.07582) (xy 409.084781 -301.028036) (xy 409.104072 -300.98276) (xy 409.130375 -300.941164)
			(xy 409.16301 -300.904327) (xy 409.201131 -300.873202) (xy 409.243752 -300.848595) (xy 409.289768 -300.831143)
			(xy 409.337987 -300.821299) (xy 409.387162 -300.819318) (xy 409.436017 -300.82525) (xy 409.483288 -300.838942)
			(xy 409.52775 -300.86004) (xy 409.568253 -300.887996) (xy 409.603746 -300.922088) (xy 409.633311 -300.961432)
			(xy 409.656182 -301.005009) (xy 409.671766 -301.05169) (xy 409.679661 -301.100267) (xy 409.680156 -301.124874)
			(xy 410.019004 -301.124874) (xy 410.022964 -301.07582) (xy 410.034741 -301.028036) (xy 410.054032 -300.98276)
			(xy 410.080335 -300.941164) (xy 410.11297 -300.904327) (xy 410.151091 -300.873202) (xy 410.193712 -300.848595)
			(xy 410.239728 -300.831143) (xy 410.287947 -300.821299) (xy 410.337122 -300.819318) (xy 410.385977 -300.82525)
			(xy 410.433248 -300.838942) (xy 410.47771 -300.86004) (xy 410.518213 -300.887996) (xy 410.553706 -300.922088)
			(xy 410.583271 -300.961432) (xy 410.606142 -301.005009) (xy 410.621726 -301.05169) (xy 410.629621 -301.100267)
			(xy 410.630116 -301.124874) (xy 410.969218 -301.124874) (xy 410.973178 -301.07582) (xy 410.984955 -301.028036)
			(xy 411.004246 -300.98276) (xy 411.030549 -300.941164) (xy 411.063184 -300.904327) (xy 411.101305 -300.873202)
			(xy 411.143926 -300.848595) (xy 411.189942 -300.831143) (xy 411.238161 -300.821299) (xy 411.287336 -300.819318)
			(xy 411.336191 -300.82525) (xy 411.383462 -300.838942) (xy 411.427924 -300.86004) (xy 411.468427 -300.887996)
			(xy 411.50392 -300.922088) (xy 411.533485 -300.961432) (xy 411.556356 -301.005009) (xy 411.57194 -301.05169)
			(xy 411.579835 -301.100267) (xy 411.58033 -301.124874) (xy 411.919178 -301.124874) (xy 411.923138 -301.07582)
			(xy 411.934915 -301.028036) (xy 411.954206 -300.98276) (xy 411.980509 -300.941164) (xy 412.013144 -300.904327)
			(xy 412.051265 -300.873202) (xy 412.093886 -300.848595) (xy 412.139902 -300.831143) (xy 412.188121 -300.821299)
			(xy 412.237296 -300.819318) (xy 412.286151 -300.82525) (xy 412.333422 -300.838942) (xy 412.377884 -300.86004)
			(xy 412.418387 -300.887996) (xy 412.45388 -300.922088) (xy 412.483445 -300.961432) (xy 412.506316 -301.005009)
			(xy 412.5219 -301.05169) (xy 412.529795 -301.100267) (xy 412.53029 -301.124874) (xy 412.869138 -301.124874)
			(xy 412.873098 -301.07582) (xy 412.884875 -301.028036) (xy 412.904166 -300.98276) (xy 412.930469 -300.941164)
			(xy 412.963104 -300.904327) (xy 413.001225 -300.873202) (xy 413.043846 -300.848595) (xy 413.089862 -300.831143)
			(xy 413.138081 -300.821299) (xy 413.187256 -300.819318) (xy 413.236111 -300.82525) (xy 413.283382 -300.838942)
			(xy 413.327844 -300.86004) (xy 413.368347 -300.887996) (xy 413.40384 -300.922088) (xy 413.433405 -300.961432)
			(xy 413.456276 -301.005009) (xy 413.47186 -301.05169) (xy 413.479755 -301.100267) (xy 413.48025 -301.124874)
			(xy 413.819098 -301.124874) (xy 413.823058 -301.07582) (xy 413.834835 -301.028036) (xy 413.854126 -300.98276)
			(xy 413.880429 -300.941164) (xy 413.913064 -300.904327) (xy 413.951185 -300.873202) (xy 413.993806 -300.848595)
			(xy 414.039822 -300.831143) (xy 414.088041 -300.821299) (xy 414.137216 -300.819318) (xy 414.186071 -300.82525)
			(xy 414.233342 -300.838942) (xy 414.277804 -300.86004) (xy 414.318307 -300.887996) (xy 414.3538 -300.922088)
			(xy 414.383365 -300.961432) (xy 414.406236 -301.005009) (xy 414.42182 -301.05169) (xy 414.429715 -301.100267)
			(xy 414.43021 -301.124874) (xy 414.769058 -301.124874) (xy 414.773018 -301.07582) (xy 414.784795 -301.028036)
			(xy 414.804086 -300.98276) (xy 414.830389 -300.941164) (xy 414.863024 -300.904327) (xy 414.901145 -300.873202)
			(xy 414.943766 -300.848595) (xy 414.989782 -300.831143) (xy 415.038001 -300.821299) (xy 415.087176 -300.819318)
			(xy 415.136031 -300.82525) (xy 415.183302 -300.838942) (xy 415.227764 -300.86004) (xy 415.268267 -300.887996)
			(xy 415.30376 -300.922088) (xy 415.333325 -300.961432) (xy 415.356196 -301.005009) (xy 415.37178 -301.05169)
			(xy 415.379675 -301.100267) (xy 415.38017 -301.124874) (xy 415.719018 -301.124874) (xy 415.722978 -301.07582)
			(xy 415.734755 -301.028036) (xy 415.754046 -300.98276) (xy 415.780349 -300.941164) (xy 415.812984 -300.904327)
			(xy 415.851105 -300.873202) (xy 415.893726 -300.848595) (xy 415.939742 -300.831143) (xy 415.987961 -300.821299)
			(xy 416.037136 -300.819318) (xy 416.085991 -300.82525) (xy 416.133262 -300.838942) (xy 416.177724 -300.86004)
			(xy 416.218227 -300.887996) (xy 416.25372 -300.922088) (xy 416.283285 -300.961432) (xy 416.306156 -301.005009)
			(xy 416.32174 -301.05169) (xy 416.329635 -301.100267) (xy 416.33013 -301.124874) (xy 416.668978 -301.124874)
			(xy 416.672938 -301.07582) (xy 416.684715 -301.028036) (xy 416.704006 -300.98276) (xy 416.730309 -300.941164)
			(xy 416.762944 -300.904327) (xy 416.801065 -300.873202) (xy 416.843686 -300.848595) (xy 416.889702 -300.831143)
			(xy 416.937921 -300.821299) (xy 416.987096 -300.819318) (xy 417.035951 -300.82525) (xy 417.083222 -300.838942)
			(xy 417.127684 -300.86004) (xy 417.168187 -300.887996) (xy 417.20368 -300.922088) (xy 417.233245 -300.961432)
			(xy 417.256116 -301.005009) (xy 417.2717 -301.05169) (xy 417.279595 -301.100267) (xy 417.28009 -301.124874)
			(xy 417.619192 -301.124874) (xy 417.623152 -301.07582) (xy 417.634929 -301.028036) (xy 417.65422 -300.98276)
			(xy 417.680523 -300.941164) (xy 417.713158 -300.904327) (xy 417.751279 -300.873202) (xy 417.7939 -300.848595)
			(xy 417.839916 -300.831143) (xy 417.888135 -300.821299) (xy 417.93731 -300.819318) (xy 417.986165 -300.82525)
			(xy 418.033436 -300.838942) (xy 418.077898 -300.86004) (xy 418.118401 -300.887996) (xy 418.153894 -300.922088)
			(xy 418.183459 -300.961432) (xy 418.20633 -301.005009) (xy 418.221914 -301.05169) (xy 418.229809 -301.100267)
			(xy 418.230304 -301.124874) (xy 418.569152 -301.124874) (xy 418.573112 -301.07582) (xy 418.584889 -301.028036)
			(xy 418.60418 -300.98276) (xy 418.630483 -300.941164) (xy 418.663118 -300.904327) (xy 418.701239 -300.873202)
			(xy 418.74386 -300.848595) (xy 418.789876 -300.831143) (xy 418.838095 -300.821299) (xy 418.88727 -300.819318)
			(xy 418.936125 -300.82525) (xy 418.983396 -300.838942) (xy 419.027858 -300.86004) (xy 419.068361 -300.887996)
			(xy 419.103854 -300.922088) (xy 419.133419 -300.961432) (xy 419.15629 -301.005009) (xy 419.171874 -301.05169)
			(xy 419.179769 -301.100267) (xy 419.180264 -301.124874) (xy 419.519112 -301.124874) (xy 419.523072 -301.07582)
			(xy 419.534849 -301.028036) (xy 419.55414 -300.98276) (xy 419.580443 -300.941164) (xy 419.613078 -300.904327)
			(xy 419.651199 -300.873202) (xy 419.69382 -300.848595) (xy 419.739836 -300.831143) (xy 419.788055 -300.821299)
			(xy 419.83723 -300.819318) (xy 419.886085 -300.82525) (xy 419.933356 -300.838942) (xy 419.977818 -300.86004)
			(xy 420.018321 -300.887996) (xy 420.053814 -300.922088) (xy 420.083379 -300.961432) (xy 420.10625 -301.005009)
			(xy 420.121834 -301.05169) (xy 420.129729 -301.100267) (xy 420.130224 -301.124874) (xy 420.469072 -301.124874)
			(xy 420.473032 -301.07582) (xy 420.484809 -301.028036) (xy 420.5041 -300.98276) (xy 420.530403 -300.941164)
			(xy 420.563038 -300.904327) (xy 420.601159 -300.873202) (xy 420.64378 -300.848595) (xy 420.689796 -300.831143)
			(xy 420.738015 -300.821299) (xy 420.78719 -300.819318) (xy 420.836045 -300.82525) (xy 420.883316 -300.838942)
			(xy 420.927778 -300.86004) (xy 420.968281 -300.887996) (xy 421.003774 -300.922088) (xy 421.033339 -300.961432)
			(xy 421.05621 -301.005009) (xy 421.071794 -301.05169) (xy 421.079689 -301.100267) (xy 421.080184 -301.124874)
			(xy 421.419032 -301.124874) (xy 421.422992 -301.07582) (xy 421.434769 -301.028036) (xy 421.45406 -300.98276)
			(xy 421.480363 -300.941164) (xy 421.512998 -300.904327) (xy 421.551119 -300.873202) (xy 421.59374 -300.848595)
			(xy 421.639756 -300.831143) (xy 421.687975 -300.821299) (xy 421.73715 -300.819318) (xy 421.786005 -300.82525)
			(xy 421.833276 -300.838942) (xy 421.877738 -300.86004) (xy 421.918241 -300.887996) (xy 421.953734 -300.922088)
			(xy 421.983299 -300.961432) (xy 422.00617 -301.005009) (xy 422.021754 -301.05169) (xy 422.029649 -301.100267)
			(xy 422.030144 -301.124874) (xy 424.269166 -301.124874) (xy 424.273126 -301.07582) (xy 424.284903 -301.028036)
			(xy 424.304194 -300.98276) (xy 424.330497 -300.941164) (xy 424.363132 -300.904327) (xy 424.401253 -300.873202)
			(xy 424.443874 -300.848595) (xy 424.48989 -300.831143) (xy 424.538109 -300.821299) (xy 424.587284 -300.819318)
			(xy 424.636139 -300.82525) (xy 424.68341 -300.838942) (xy 424.727872 -300.86004) (xy 424.768375 -300.887996)
			(xy 424.803868 -300.922088) (xy 424.833433 -300.961432) (xy 424.856304 -301.005009) (xy 424.871888 -301.05169)
			(xy 424.879783 -301.100267) (xy 424.880278 -301.124874) (xy 425.219126 -301.124874) (xy 425.223086 -301.07582)
			(xy 425.234863 -301.028036) (xy 425.254154 -300.98276) (xy 425.280457 -300.941164) (xy 425.313092 -300.904327)
			(xy 425.351213 -300.873202) (xy 425.393834 -300.848595) (xy 425.43985 -300.831143) (xy 425.488069 -300.821299)
			(xy 425.537244 -300.819318) (xy 425.586099 -300.82525) (xy 425.63337 -300.838942) (xy 425.677832 -300.86004)
			(xy 425.718335 -300.887996) (xy 425.753828 -300.922088) (xy 425.783393 -300.961432) (xy 425.806264 -301.005009)
			(xy 425.821848 -301.05169) (xy 425.829743 -301.100267) (xy 425.830238 -301.124874) (xy 426.169086 -301.124874)
			(xy 426.173046 -301.07582) (xy 426.184823 -301.028036) (xy 426.204114 -300.98276) (xy 426.230417 -300.941164)
			(xy 426.263052 -300.904327) (xy 426.301173 -300.873202) (xy 426.343794 -300.848595) (xy 426.38981 -300.831143)
			(xy 426.438029 -300.821299) (xy 426.487204 -300.819318) (xy 426.536059 -300.82525) (xy 426.58333 -300.838942)
			(xy 426.627792 -300.86004) (xy 426.668295 -300.887996) (xy 426.703788 -300.922088) (xy 426.733353 -300.961432)
			(xy 426.756224 -301.005009) (xy 426.771808 -301.05169) (xy 426.779703 -301.100267) (xy 426.780198 -301.124874)
			(xy 427.119046 -301.124874) (xy 427.123006 -301.07582) (xy 427.134783 -301.028036) (xy 427.154074 -300.98276)
			(xy 427.180377 -300.941164) (xy 427.213012 -300.904327) (xy 427.251133 -300.873202) (xy 427.293754 -300.848595)
			(xy 427.33977 -300.831143) (xy 427.387989 -300.821299) (xy 427.437164 -300.819318) (xy 427.486019 -300.82525)
			(xy 427.53329 -300.838942) (xy 427.577752 -300.86004) (xy 427.618255 -300.887996) (xy 427.653748 -300.922088)
			(xy 427.683313 -300.961432) (xy 427.706184 -301.005009) (xy 427.721768 -301.05169) (xy 427.729663 -301.100267)
			(xy 427.730158 -301.124874) (xy 428.069006 -301.124874) (xy 428.072966 -301.07582) (xy 428.084743 -301.028036)
			(xy 428.104034 -300.98276) (xy 428.130337 -300.941164) (xy 428.162972 -300.904327) (xy 428.201093 -300.873202)
			(xy 428.243714 -300.848595) (xy 428.28973 -300.831143) (xy 428.337949 -300.821299) (xy 428.387124 -300.819318)
			(xy 428.435979 -300.82525) (xy 428.48325 -300.838942) (xy 428.527712 -300.86004) (xy 428.568215 -300.887996)
			(xy 428.603708 -300.922088) (xy 428.633273 -300.961432) (xy 428.656144 -301.005009) (xy 428.671728 -301.05169)
			(xy 428.679623 -301.100267) (xy 428.680118 -301.124874) (xy 429.01922 -301.124874) (xy 429.02318 -301.07582)
			(xy 429.034957 -301.028036) (xy 429.054248 -300.98276) (xy 429.080551 -300.941164) (xy 429.113186 -300.904327)
			(xy 429.151307 -300.873202) (xy 429.193928 -300.848595) (xy 429.239944 -300.831143) (xy 429.288163 -300.821299)
			(xy 429.337338 -300.819318) (xy 429.386193 -300.82525) (xy 429.433464 -300.838942) (xy 429.477926 -300.86004)
			(xy 429.518429 -300.887996) (xy 429.553922 -300.922088) (xy 429.583487 -300.961432) (xy 429.606358 -301.005009)
			(xy 429.621942 -301.05169) (xy 429.629837 -301.100267) (xy 429.630332 -301.124874) (xy 429.96918 -301.124874)
			(xy 429.97314 -301.07582) (xy 429.984917 -301.028036) (xy 430.004208 -300.98276) (xy 430.030511 -300.941164)
			(xy 430.063146 -300.904327) (xy 430.101267 -300.873202) (xy 430.143888 -300.848595) (xy 430.189904 -300.831143)
			(xy 430.238123 -300.821299) (xy 430.287298 -300.819318) (xy 430.336153 -300.82525) (xy 430.383424 -300.838942)
			(xy 430.427886 -300.86004) (xy 430.468389 -300.887996) (xy 430.503882 -300.922088) (xy 430.533447 -300.961432)
			(xy 430.556318 -301.005009) (xy 430.571902 -301.05169) (xy 430.579797 -301.100267) (xy 430.580292 -301.124874)
			(xy 430.91914 -301.124874) (xy 430.9231 -301.07582) (xy 430.934877 -301.028036) (xy 430.954168 -300.98276)
			(xy 430.980471 -300.941164) (xy 431.013106 -300.904327) (xy 431.051227 -300.873202) (xy 431.093848 -300.848595)
			(xy 431.139864 -300.831143) (xy 431.188083 -300.821299) (xy 431.237258 -300.819318) (xy 431.286113 -300.82525)
			(xy 431.333384 -300.838942) (xy 431.377846 -300.86004) (xy 431.418349 -300.887996) (xy 431.453842 -300.922088)
			(xy 431.483407 -300.961432) (xy 431.506278 -301.005009) (xy 431.51865 -301.04207) (xy 438.617104 -301.04207)
			(xy 438.621175 -300.986448) (xy 438.633301 -300.932011) (xy 438.653224 -300.87992) (xy 438.68052 -300.831285)
			(xy 438.714606 -300.787142) (xy 438.754755 -300.748433) (xy 438.800113 -300.715982) (xy 438.849713 -300.690481)
			(xy 438.902497 -300.672474) (xy 438.95734 -300.662344) (xy 439.013074 -300.660307) (xy 439.068511 -300.666407)
			(xy 439.122468 -300.680513) (xy 439.173797 -300.702325) (xy 439.221403 -300.731379) (xy 439.264271 -300.767054)
			(xy 439.301488 -300.808591) (xy 439.332261 -300.855104) (xy 439.355933 -300.905601) (xy 439.372001 -300.959008)
			(xy 439.380121 -301.014184) (xy 439.38063 -301.04207) (xy 439.380477 -301.050452) (xy 440.990988 -301.050452)
			(xy 440.995059 -300.99483) (xy 441.007185 -300.940393) (xy 441.027108 -300.888302) (xy 441.054404 -300.839667)
			(xy 441.08849 -300.795524) (xy 441.128639 -300.756815) (xy 441.173997 -300.724364) (xy 441.223597 -300.698863)
			(xy 441.276381 -300.680856) (xy 441.331224 -300.670726) (xy 441.386958 -300.668689) (xy 441.442395 -300.674789)
			(xy 441.496352 -300.688895) (xy 441.547681 -300.710707) (xy 441.595287 -300.739761) (xy 441.638155 -300.775436)
			(xy 441.675372 -300.816973) (xy 441.706145 -300.863486) (xy 441.729817 -300.913983) (xy 441.745885 -300.96739)
			(xy 441.754005 -301.022566) (xy 441.754514 -301.050452) (xy 441.754005 -301.078338) (xy 441.745885 -301.133514)
			(xy 441.729817 -301.186921) (xy 441.706145 -301.237418) (xy 441.675372 -301.283931) (xy 441.638155 -301.325468)
			(xy 441.595287 -301.361143) (xy 441.547681 -301.390197) (xy 441.496352 -301.412009) (xy 441.442395 -301.426115)
			(xy 441.386958 -301.432215) (xy 441.331224 -301.430178) (xy 441.276381 -301.420048) (xy 441.223597 -301.402041)
			(xy 441.173997 -301.37654) (xy 441.128639 -301.344089) (xy 441.08849 -301.30538) (xy 441.054404 -301.261237)
			(xy 441.027108 -301.212602) (xy 441.007185 -301.160511) (xy 440.995059 -301.106074) (xy 440.990988 -301.050452)
			(xy 439.380477 -301.050452) (xy 439.380121 -301.069956) (xy 439.372001 -301.125132) (xy 439.355933 -301.178539)
			(xy 439.332261 -301.229036) (xy 439.301488 -301.275549) (xy 439.264271 -301.317086) (xy 439.221403 -301.352761)
			(xy 439.173797 -301.381815) (xy 439.122468 -301.403627) (xy 439.068511 -301.417733) (xy 439.013074 -301.423833)
			(xy 438.95734 -301.421796) (xy 438.902497 -301.411666) (xy 438.849713 -301.393659) (xy 438.800113 -301.368158)
			(xy 438.754755 -301.335707) (xy 438.714606 -301.296998) (xy 438.68052 -301.252855) (xy 438.653224 -301.20422)
			(xy 438.633301 -301.152129) (xy 438.621175 -301.097692) (xy 438.617104 -301.04207) (xy 431.51865 -301.04207)
			(xy 431.521862 -301.05169) (xy 431.529757 -301.100267) (xy 431.530252 -301.124874) (xy 431.529757 -301.149481)
			(xy 431.521862 -301.198058) (xy 431.506278 -301.244739) (xy 431.483407 -301.288316) (xy 431.453842 -301.32766)
			(xy 431.418349 -301.361752) (xy 431.377846 -301.389708) (xy 431.333384 -301.410806) (xy 431.286113 -301.424498)
			(xy 431.237258 -301.43043) (xy 431.188083 -301.428449) (xy 431.139864 -301.418605) (xy 431.093848 -301.401153)
			(xy 431.051227 -301.376546) (xy 431.013106 -301.345421) (xy 430.980471 -301.308584) (xy 430.954168 -301.266988)
			(xy 430.934877 -301.221712) (xy 430.9231 -301.173928) (xy 430.91914 -301.124874) (xy 430.580292 -301.124874)
			(xy 430.579797 -301.149481) (xy 430.571902 -301.198058) (xy 430.556318 -301.244739) (xy 430.533447 -301.288316)
			(xy 430.503882 -301.32766) (xy 430.468389 -301.361752) (xy 430.427886 -301.389708) (xy 430.383424 -301.410806)
			(xy 430.336153 -301.424498) (xy 430.287298 -301.43043) (xy 430.238123 -301.428449) (xy 430.189904 -301.418605)
			(xy 430.143888 -301.401153) (xy 430.101267 -301.376546) (xy 430.063146 -301.345421) (xy 430.030511 -301.308584)
			(xy 430.004208 -301.266988) (xy 429.984917 -301.221712) (xy 429.97314 -301.173928) (xy 429.96918 -301.124874)
			(xy 429.630332 -301.124874) (xy 429.629837 -301.149481) (xy 429.621942 -301.198058) (xy 429.606358 -301.244739)
			(xy 429.583487 -301.288316) (xy 429.553922 -301.32766) (xy 429.518429 -301.361752) (xy 429.477926 -301.389708)
			(xy 429.433464 -301.410806) (xy 429.386193 -301.424498) (xy 429.337338 -301.43043) (xy 429.288163 -301.428449)
			(xy 429.239944 -301.418605) (xy 429.193928 -301.401153) (xy 429.151307 -301.376546) (xy 429.113186 -301.345421)
			(xy 429.080551 -301.308584) (xy 429.054248 -301.266988) (xy 429.034957 -301.221712) (xy 429.02318 -301.173928)
			(xy 429.01922 -301.124874) (xy 428.680118 -301.124874) (xy 428.679623 -301.149481) (xy 428.671728 -301.198058)
			(xy 428.656144 -301.244739) (xy 428.633273 -301.288316) (xy 428.603708 -301.32766) (xy 428.568215 -301.361752)
			(xy 428.527712 -301.389708) (xy 428.48325 -301.410806) (xy 428.435979 -301.424498) (xy 428.387124 -301.43043)
			(xy 428.337949 -301.428449) (xy 428.28973 -301.418605) (xy 428.243714 -301.401153) (xy 428.201093 -301.376546)
			(xy 428.162972 -301.345421) (xy 428.130337 -301.308584) (xy 428.104034 -301.266988) (xy 428.084743 -301.221712)
			(xy 428.072966 -301.173928) (xy 428.069006 -301.124874) (xy 427.730158 -301.124874) (xy 427.729663 -301.149481)
			(xy 427.721768 -301.198058) (xy 427.706184 -301.244739) (xy 427.683313 -301.288316) (xy 427.653748 -301.32766)
			(xy 427.618255 -301.361752) (xy 427.577752 -301.389708) (xy 427.53329 -301.410806) (xy 427.486019 -301.424498)
			(xy 427.437164 -301.43043) (xy 427.387989 -301.428449) (xy 427.33977 -301.418605) (xy 427.293754 -301.401153)
			(xy 427.251133 -301.376546) (xy 427.213012 -301.345421) (xy 427.180377 -301.308584) (xy 427.154074 -301.266988)
			(xy 427.134783 -301.221712) (xy 427.123006 -301.173928) (xy 427.119046 -301.124874) (xy 426.780198 -301.124874)
			(xy 426.779703 -301.149481) (xy 426.771808 -301.198058) (xy 426.756224 -301.244739) (xy 426.733353 -301.288316)
			(xy 426.703788 -301.32766) (xy 426.668295 -301.361752) (xy 426.627792 -301.389708) (xy 426.58333 -301.410806)
			(xy 426.536059 -301.424498) (xy 426.487204 -301.43043) (xy 426.438029 -301.428449) (xy 426.38981 -301.418605)
			(xy 426.343794 -301.401153) (xy 426.301173 -301.376546) (xy 426.263052 -301.345421) (xy 426.230417 -301.308584)
			(xy 426.204114 -301.266988) (xy 426.184823 -301.221712) (xy 426.173046 -301.173928) (xy 426.169086 -301.124874)
			(xy 425.830238 -301.124874) (xy 425.829743 -301.149481) (xy 425.821848 -301.198058) (xy 425.806264 -301.244739)
			(xy 425.783393 -301.288316) (xy 425.753828 -301.32766) (xy 425.718335 -301.361752) (xy 425.677832 -301.389708)
			(xy 425.63337 -301.410806) (xy 425.586099 -301.424498) (xy 425.537244 -301.43043) (xy 425.488069 -301.428449)
			(xy 425.43985 -301.418605) (xy 425.393834 -301.401153) (xy 425.351213 -301.376546) (xy 425.313092 -301.345421)
			(xy 425.280457 -301.308584) (xy 425.254154 -301.266988) (xy 425.234863 -301.221712) (xy 425.223086 -301.173928)
			(xy 425.219126 -301.124874) (xy 424.880278 -301.124874) (xy 424.879783 -301.149481) (xy 424.871888 -301.198058)
			(xy 424.856304 -301.244739) (xy 424.833433 -301.288316) (xy 424.803868 -301.32766) (xy 424.768375 -301.361752)
			(xy 424.727872 -301.389708) (xy 424.68341 -301.410806) (xy 424.636139 -301.424498) (xy 424.587284 -301.43043)
			(xy 424.538109 -301.428449) (xy 424.48989 -301.418605) (xy 424.443874 -301.401153) (xy 424.401253 -301.376546)
			(xy 424.363132 -301.345421) (xy 424.330497 -301.308584) (xy 424.304194 -301.266988) (xy 424.284903 -301.221712)
			(xy 424.273126 -301.173928) (xy 424.269166 -301.124874) (xy 422.030144 -301.124874) (xy 422.029649 -301.149481)
			(xy 422.021754 -301.198058) (xy 422.00617 -301.244739) (xy 421.983299 -301.288316) (xy 421.953734 -301.32766)
			(xy 421.918241 -301.361752) (xy 421.877738 -301.389708) (xy 421.833276 -301.410806) (xy 421.786005 -301.424498)
			(xy 421.73715 -301.43043) (xy 421.687975 -301.428449) (xy 421.639756 -301.418605) (xy 421.59374 -301.401153)
			(xy 421.551119 -301.376546) (xy 421.512998 -301.345421) (xy 421.480363 -301.308584) (xy 421.45406 -301.266988)
			(xy 421.434769 -301.221712) (xy 421.422992 -301.173928) (xy 421.419032 -301.124874) (xy 421.080184 -301.124874)
			(xy 421.079689 -301.149481) (xy 421.071794 -301.198058) (xy 421.05621 -301.244739) (xy 421.033339 -301.288316)
			(xy 421.003774 -301.32766) (xy 420.968281 -301.361752) (xy 420.927778 -301.389708) (xy 420.883316 -301.410806)
			(xy 420.836045 -301.424498) (xy 420.78719 -301.43043) (xy 420.738015 -301.428449) (xy 420.689796 -301.418605)
			(xy 420.64378 -301.401153) (xy 420.601159 -301.376546) (xy 420.563038 -301.345421) (xy 420.530403 -301.308584)
			(xy 420.5041 -301.266988) (xy 420.484809 -301.221712) (xy 420.473032 -301.173928) (xy 420.469072 -301.124874)
			(xy 420.130224 -301.124874) (xy 420.129729 -301.149481) (xy 420.121834 -301.198058) (xy 420.10625 -301.244739)
			(xy 420.083379 -301.288316) (xy 420.053814 -301.32766) (xy 420.018321 -301.361752) (xy 419.977818 -301.389708)
			(xy 419.933356 -301.410806) (xy 419.886085 -301.424498) (xy 419.83723 -301.43043) (xy 419.788055 -301.428449)
			(xy 419.739836 -301.418605) (xy 419.69382 -301.401153) (xy 419.651199 -301.376546) (xy 419.613078 -301.345421)
			(xy 419.580443 -301.308584) (xy 419.55414 -301.266988) (xy 419.534849 -301.221712) (xy 419.523072 -301.173928)
			(xy 419.519112 -301.124874) (xy 419.180264 -301.124874) (xy 419.179769 -301.149481) (xy 419.171874 -301.198058)
			(xy 419.15629 -301.244739) (xy 419.133419 -301.288316) (xy 419.103854 -301.32766) (xy 419.068361 -301.361752)
			(xy 419.027858 -301.389708) (xy 418.983396 -301.410806) (xy 418.936125 -301.424498) (xy 418.88727 -301.43043)
			(xy 418.838095 -301.428449) (xy 418.789876 -301.418605) (xy 418.74386 -301.401153) (xy 418.701239 -301.376546)
			(xy 418.663118 -301.345421) (xy 418.630483 -301.308584) (xy 418.60418 -301.266988) (xy 418.584889 -301.221712)
			(xy 418.573112 -301.173928) (xy 418.569152 -301.124874) (xy 418.230304 -301.124874) (xy 418.229809 -301.149481)
			(xy 418.221914 -301.198058) (xy 418.20633 -301.244739) (xy 418.183459 -301.288316) (xy 418.153894 -301.32766)
			(xy 418.118401 -301.361752) (xy 418.077898 -301.389708) (xy 418.033436 -301.410806) (xy 417.986165 -301.424498)
			(xy 417.93731 -301.43043) (xy 417.888135 -301.428449) (xy 417.839916 -301.418605) (xy 417.7939 -301.401153)
			(xy 417.751279 -301.376546) (xy 417.713158 -301.345421) (xy 417.680523 -301.308584) (xy 417.65422 -301.266988)
			(xy 417.634929 -301.221712) (xy 417.623152 -301.173928) (xy 417.619192 -301.124874) (xy 417.28009 -301.124874)
			(xy 417.279595 -301.149481) (xy 417.2717 -301.198058) (xy 417.256116 -301.244739) (xy 417.233245 -301.288316)
			(xy 417.20368 -301.32766) (xy 417.168187 -301.361752) (xy 417.127684 -301.389708) (xy 417.083222 -301.410806)
			(xy 417.035951 -301.424498) (xy 416.987096 -301.43043) (xy 416.937921 -301.428449) (xy 416.889702 -301.418605)
			(xy 416.843686 -301.401153) (xy 416.801065 -301.376546) (xy 416.762944 -301.345421) (xy 416.730309 -301.308584)
			(xy 416.704006 -301.266988) (xy 416.684715 -301.221712) (xy 416.672938 -301.173928) (xy 416.668978 -301.124874)
			(xy 416.33013 -301.124874) (xy 416.329635 -301.149481) (xy 416.32174 -301.198058) (xy 416.306156 -301.244739)
			(xy 416.283285 -301.288316) (xy 416.25372 -301.32766) (xy 416.218227 -301.361752) (xy 416.177724 -301.389708)
			(xy 416.133262 -301.410806) (xy 416.085991 -301.424498) (xy 416.037136 -301.43043) (xy 415.987961 -301.428449)
			(xy 415.939742 -301.418605) (xy 415.893726 -301.401153) (xy 415.851105 -301.376546) (xy 415.812984 -301.345421)
			(xy 415.780349 -301.308584) (xy 415.754046 -301.266988) (xy 415.734755 -301.221712) (xy 415.722978 -301.173928)
			(xy 415.719018 -301.124874) (xy 415.38017 -301.124874) (xy 415.379675 -301.149481) (xy 415.37178 -301.198058)
			(xy 415.356196 -301.244739) (xy 415.333325 -301.288316) (xy 415.30376 -301.32766) (xy 415.268267 -301.361752)
			(xy 415.227764 -301.389708) (xy 415.183302 -301.410806) (xy 415.136031 -301.424498) (xy 415.087176 -301.43043)
			(xy 415.038001 -301.428449) (xy 414.989782 -301.418605) (xy 414.943766 -301.401153) (xy 414.901145 -301.376546)
			(xy 414.863024 -301.345421) (xy 414.830389 -301.308584) (xy 414.804086 -301.266988) (xy 414.784795 -301.221712)
			(xy 414.773018 -301.173928) (xy 414.769058 -301.124874) (xy 414.43021 -301.124874) (xy 414.429715 -301.149481)
			(xy 414.42182 -301.198058) (xy 414.406236 -301.244739) (xy 414.383365 -301.288316) (xy 414.3538 -301.32766)
			(xy 414.318307 -301.361752) (xy 414.277804 -301.389708) (xy 414.233342 -301.410806) (xy 414.186071 -301.424498)
			(xy 414.137216 -301.43043) (xy 414.088041 -301.428449) (xy 414.039822 -301.418605) (xy 413.993806 -301.401153)
			(xy 413.951185 -301.376546) (xy 413.913064 -301.345421) (xy 413.880429 -301.308584) (xy 413.854126 -301.266988)
			(xy 413.834835 -301.221712) (xy 413.823058 -301.173928) (xy 413.819098 -301.124874) (xy 413.48025 -301.124874)
			(xy 413.479755 -301.149481) (xy 413.47186 -301.198058) (xy 413.456276 -301.244739) (xy 413.433405 -301.288316)
			(xy 413.40384 -301.32766) (xy 413.368347 -301.361752) (xy 413.327844 -301.389708) (xy 413.283382 -301.410806)
			(xy 413.236111 -301.424498) (xy 413.187256 -301.43043) (xy 413.138081 -301.428449) (xy 413.089862 -301.418605)
			(xy 413.043846 -301.401153) (xy 413.001225 -301.376546) (xy 412.963104 -301.345421) (xy 412.930469 -301.308584)
			(xy 412.904166 -301.266988) (xy 412.884875 -301.221712) (xy 412.873098 -301.173928) (xy 412.869138 -301.124874)
			(xy 412.53029 -301.124874) (xy 412.529795 -301.149481) (xy 412.5219 -301.198058) (xy 412.506316 -301.244739)
			(xy 412.483445 -301.288316) (xy 412.45388 -301.32766) (xy 412.418387 -301.361752) (xy 412.377884 -301.389708)
			(xy 412.333422 -301.410806) (xy 412.286151 -301.424498) (xy 412.237296 -301.43043) (xy 412.188121 -301.428449)
			(xy 412.139902 -301.418605) (xy 412.093886 -301.401153) (xy 412.051265 -301.376546) (xy 412.013144 -301.345421)
			(xy 411.980509 -301.308584) (xy 411.954206 -301.266988) (xy 411.934915 -301.221712) (xy 411.923138 -301.173928)
			(xy 411.919178 -301.124874) (xy 411.58033 -301.124874) (xy 411.579835 -301.149481) (xy 411.57194 -301.198058)
			(xy 411.556356 -301.244739) (xy 411.533485 -301.288316) (xy 411.50392 -301.32766) (xy 411.468427 -301.361752)
			(xy 411.427924 -301.389708) (xy 411.383462 -301.410806) (xy 411.336191 -301.424498) (xy 411.287336 -301.43043)
			(xy 411.238161 -301.428449) (xy 411.189942 -301.418605) (xy 411.143926 -301.401153) (xy 411.101305 -301.376546)
			(xy 411.063184 -301.345421) (xy 411.030549 -301.308584) (xy 411.004246 -301.266988) (xy 410.984955 -301.221712)
			(xy 410.973178 -301.173928) (xy 410.969218 -301.124874) (xy 410.630116 -301.124874) (xy 410.629621 -301.149481)
			(xy 410.621726 -301.198058) (xy 410.606142 -301.244739) (xy 410.583271 -301.288316) (xy 410.553706 -301.32766)
			(xy 410.518213 -301.361752) (xy 410.47771 -301.389708) (xy 410.433248 -301.410806) (xy 410.385977 -301.424498)
			(xy 410.337122 -301.43043) (xy 410.287947 -301.428449) (xy 410.239728 -301.418605) (xy 410.193712 -301.401153)
			(xy 410.151091 -301.376546) (xy 410.11297 -301.345421) (xy 410.080335 -301.308584) (xy 410.054032 -301.266988)
			(xy 410.034741 -301.221712) (xy 410.022964 -301.173928) (xy 410.019004 -301.124874) (xy 409.680156 -301.124874)
			(xy 409.679661 -301.149481) (xy 409.671766 -301.198058) (xy 409.656182 -301.244739) (xy 409.633311 -301.288316)
			(xy 409.603746 -301.32766) (xy 409.568253 -301.361752) (xy 409.52775 -301.389708) (xy 409.483288 -301.410806)
			(xy 409.436017 -301.424498) (xy 409.387162 -301.43043) (xy 409.337987 -301.428449) (xy 409.289768 -301.418605)
			(xy 409.243752 -301.401153) (xy 409.201131 -301.376546) (xy 409.16301 -301.345421) (xy 409.130375 -301.308584)
			(xy 409.104072 -301.266988) (xy 409.084781 -301.221712) (xy 409.073004 -301.173928) (xy 409.069044 -301.124874)
			(xy 408.730196 -301.124874) (xy 408.729701 -301.149481) (xy 408.721806 -301.198058) (xy 408.706222 -301.244739)
			(xy 408.683351 -301.288316) (xy 408.653786 -301.32766) (xy 408.618293 -301.361752) (xy 408.57779 -301.389708)
			(xy 408.533328 -301.410806) (xy 408.486057 -301.424498) (xy 408.437202 -301.43043) (xy 408.388027 -301.428449)
			(xy 408.339808 -301.418605) (xy 408.293792 -301.401153) (xy 408.251171 -301.376546) (xy 408.21305 -301.345421)
			(xy 408.180415 -301.308584) (xy 408.154112 -301.266988) (xy 408.134821 -301.221712) (xy 408.123044 -301.173928)
			(xy 408.119084 -301.124874) (xy 406.830276 -301.124874) (xy 406.829781 -301.149481) (xy 406.821886 -301.198058)
			(xy 406.806302 -301.244739) (xy 406.783431 -301.288316) (xy 406.753866 -301.32766) (xy 406.718373 -301.361752)
			(xy 406.67787 -301.389708) (xy 406.633408 -301.410806) (xy 406.586137 -301.424498) (xy 406.537282 -301.43043)
			(xy 406.488107 -301.428449) (xy 406.439888 -301.418605) (xy 406.393872 -301.401153) (xy 406.351251 -301.376546)
			(xy 406.31313 -301.345421) (xy 406.280495 -301.308584) (xy 406.254192 -301.266988) (xy 406.234901 -301.221712)
			(xy 406.223124 -301.173928) (xy 406.219164 -301.124874) (xy 405.880316 -301.124874) (xy 405.879821 -301.149481)
			(xy 405.871926 -301.198058) (xy 405.856342 -301.244739) (xy 405.833471 -301.288316) (xy 405.803906 -301.32766)
			(xy 405.768413 -301.361752) (xy 405.72791 -301.389708) (xy 405.683448 -301.410806) (xy 405.636177 -301.424498)
			(xy 405.587322 -301.43043) (xy 405.538147 -301.428449) (xy 405.489928 -301.418605) (xy 405.443912 -301.401153)
			(xy 405.401291 -301.376546) (xy 405.36317 -301.345421) (xy 405.330535 -301.308584) (xy 405.304232 -301.266988)
			(xy 405.284941 -301.221712) (xy 405.273164 -301.173928) (xy 405.269204 -301.124874) (xy 404.930102 -301.124874)
			(xy 404.929607 -301.149481) (xy 404.921712 -301.198058) (xy 404.906128 -301.244739) (xy 404.883257 -301.288316)
			(xy 404.853692 -301.32766) (xy 404.818199 -301.361752) (xy 404.777696 -301.389708) (xy 404.733234 -301.410806)
			(xy 404.685963 -301.424498) (xy 404.637108 -301.43043) (xy 404.587933 -301.428449) (xy 404.539714 -301.418605)
			(xy 404.493698 -301.401153) (xy 404.451077 -301.376546) (xy 404.412956 -301.345421) (xy 404.380321 -301.308584)
			(xy 404.354018 -301.266988) (xy 404.334727 -301.221712) (xy 404.32295 -301.173928) (xy 404.31899 -301.124874)
			(xy 403.980142 -301.124874) (xy 403.979647 -301.149481) (xy 403.971752 -301.198058) (xy 403.956168 -301.244739)
			(xy 403.933297 -301.288316) (xy 403.903732 -301.32766) (xy 403.868239 -301.361752) (xy 403.827736 -301.389708)
			(xy 403.783274 -301.410806) (xy 403.736003 -301.424498) (xy 403.687148 -301.43043) (xy 403.637973 -301.428449)
			(xy 403.589754 -301.418605) (xy 403.543738 -301.401153) (xy 403.501117 -301.376546) (xy 403.462996 -301.345421)
			(xy 403.430361 -301.308584) (xy 403.404058 -301.266988) (xy 403.384767 -301.221712) (xy 403.37299 -301.173928)
			(xy 403.36903 -301.124874) (xy 403.030182 -301.124874) (xy 403.029687 -301.149481) (xy 403.021792 -301.198058)
			(xy 403.006208 -301.244739) (xy 402.983337 -301.288316) (xy 402.953772 -301.32766) (xy 402.918279 -301.361752)
			(xy 402.877776 -301.389708) (xy 402.833314 -301.410806) (xy 402.786043 -301.424498) (xy 402.737188 -301.43043)
			(xy 402.688013 -301.428449) (xy 402.639794 -301.418605) (xy 402.593778 -301.401153) (xy 402.551157 -301.376546)
			(xy 402.513036 -301.345421) (xy 402.480401 -301.308584) (xy 402.454098 -301.266988) (xy 402.434807 -301.221712)
			(xy 402.42303 -301.173928) (xy 402.41907 -301.124874) (xy 402.080222 -301.124874) (xy 402.079727 -301.149481)
			(xy 402.071832 -301.198058) (xy 402.056248 -301.244739) (xy 402.033377 -301.288316) (xy 402.003812 -301.32766)
			(xy 401.968319 -301.361752) (xy 401.927816 -301.389708) (xy 401.883354 -301.410806) (xy 401.836083 -301.424498)
			(xy 401.787228 -301.43043) (xy 401.738053 -301.428449) (xy 401.689834 -301.418605) (xy 401.643818 -301.401153)
			(xy 401.601197 -301.376546) (xy 401.563076 -301.345421) (xy 401.530441 -301.308584) (xy 401.504138 -301.266988)
			(xy 401.484847 -301.221712) (xy 401.47307 -301.173928) (xy 401.46911 -301.124874) (xy 401.130262 -301.124874)
			(xy 401.129767 -301.149481) (xy 401.121872 -301.198058) (xy 401.106288 -301.244739) (xy 401.083417 -301.288316)
			(xy 401.053852 -301.32766) (xy 401.018359 -301.361752) (xy 400.977856 -301.389708) (xy 400.933394 -301.410806)
			(xy 400.886123 -301.424498) (xy 400.837268 -301.43043) (xy 400.788093 -301.428449) (xy 400.739874 -301.418605)
			(xy 400.693858 -301.401153) (xy 400.651237 -301.376546) (xy 400.613116 -301.345421) (xy 400.580481 -301.308584)
			(xy 400.554178 -301.266988) (xy 400.534887 -301.221712) (xy 400.52311 -301.173928) (xy 400.51915 -301.124874)
			(xy 400.180302 -301.124874) (xy 400.179807 -301.149481) (xy 400.171912 -301.198058) (xy 400.156328 -301.244739)
			(xy 400.133457 -301.288316) (xy 400.103892 -301.32766) (xy 400.068399 -301.361752) (xy 400.027896 -301.389708)
			(xy 399.983434 -301.410806) (xy 399.936163 -301.424498) (xy 399.887308 -301.43043) (xy 399.838133 -301.428449)
			(xy 399.789914 -301.418605) (xy 399.743898 -301.401153) (xy 399.701277 -301.376546) (xy 399.663156 -301.345421)
			(xy 399.630521 -301.308584) (xy 399.604218 -301.266988) (xy 399.584927 -301.221712) (xy 399.57315 -301.173928)
			(xy 399.56919 -301.124874) (xy 399.230342 -301.124874) (xy 399.229847 -301.149481) (xy 399.221952 -301.198058)
			(xy 399.206368 -301.244739) (xy 399.183497 -301.288316) (xy 399.153932 -301.32766) (xy 399.118439 -301.361752)
			(xy 399.077936 -301.389708) (xy 399.033474 -301.410806) (xy 398.986203 -301.424498) (xy 398.937348 -301.43043)
			(xy 398.888173 -301.428449) (xy 398.839954 -301.418605) (xy 398.793938 -301.401153) (xy 398.751317 -301.376546)
			(xy 398.713196 -301.345421) (xy 398.680561 -301.308584) (xy 398.654258 -301.266988) (xy 398.634967 -301.221712)
			(xy 398.62319 -301.173928) (xy 398.61923 -301.124874) (xy 398.280128 -301.124874) (xy 398.279633 -301.149481)
			(xy 398.271738 -301.198058) (xy 398.256154 -301.244739) (xy 398.233283 -301.288316) (xy 398.203718 -301.32766)
			(xy 398.168225 -301.361752) (xy 398.127722 -301.389708) (xy 398.08326 -301.410806) (xy 398.035989 -301.424498)
			(xy 397.987134 -301.43043) (xy 397.937959 -301.428449) (xy 397.88974 -301.418605) (xy 397.843724 -301.401153)
			(xy 397.801103 -301.376546) (xy 397.762982 -301.345421) (xy 397.730347 -301.308584) (xy 397.704044 -301.266988)
			(xy 397.684753 -301.221712) (xy 397.672976 -301.173928) (xy 397.669016 -301.124874) (xy 397.355172 -301.124874)
			(xy 397.355173 -301.15126) (xy 397.346809 -301.20332) (xy 397.330292 -301.253394) (xy 397.306041 -301.300213)
			(xy 397.274669 -301.342593) (xy 397.236972 -301.379459) (xy 397.193904 -301.409878) (xy 397.146555 -301.43308)
			(xy 397.096126 -301.448476) (xy 397.070072 -301.452534) (xy 397.066008 -301.453042) (xy 397.054578 -301.456598)
			(xy 397.05026 -301.457868) (xy 397.02613 -301.469044) (xy 397.019526 -301.476156) (xy 397.004794 -301.49165)
			(xy 396.996666 -301.502826) (xy 396.993977 -301.508359) (xy 396.991034 -301.520299) (xy 396.990824 -301.526448)
			(xy 396.990824 -302.074834) (xy 397.669016 -302.074834) (xy 397.672976 -302.02578) (xy 397.684753 -301.977996)
			(xy 397.704044 -301.93272) (xy 397.730347 -301.891124) (xy 397.762982 -301.854287) (xy 397.801103 -301.823162)
			(xy 397.843724 -301.798555) (xy 397.88974 -301.781103) (xy 397.937959 -301.771259) (xy 397.987134 -301.769278)
			(xy 398.035989 -301.77521) (xy 398.08326 -301.788902) (xy 398.127722 -301.81) (xy 398.168225 -301.837956)
			(xy 398.203718 -301.872048) (xy 398.233283 -301.911392) (xy 398.256154 -301.954969) (xy 398.271738 -302.00165)
			(xy 398.279633 -302.050227) (xy 398.280128 -302.074834) (xy 398.61923 -302.074834) (xy 398.62319 -302.02578)
			(xy 398.634967 -301.977996) (xy 398.654258 -301.93272) (xy 398.680561 -301.891124) (xy 398.713196 -301.854287)
			(xy 398.751317 -301.823162) (xy 398.793938 -301.798555) (xy 398.839954 -301.781103) (xy 398.888173 -301.771259)
			(xy 398.937348 -301.769278) (xy 398.986203 -301.77521) (xy 399.033474 -301.788902) (xy 399.077936 -301.81)
			(xy 399.118439 -301.837956) (xy 399.153932 -301.872048) (xy 399.183497 -301.911392) (xy 399.206368 -301.954969)
			(xy 399.221952 -302.00165) (xy 399.229847 -302.050227) (xy 399.230342 -302.074834) (xy 399.56919 -302.074834)
			(xy 399.57315 -302.02578) (xy 399.584927 -301.977996) (xy 399.604218 -301.93272) (xy 399.630521 -301.891124)
			(xy 399.663156 -301.854287) (xy 399.701277 -301.823162) (xy 399.743898 -301.798555) (xy 399.789914 -301.781103)
			(xy 399.838133 -301.771259) (xy 399.887308 -301.769278) (xy 399.936163 -301.77521) (xy 399.983434 -301.788902)
			(xy 400.027896 -301.81) (xy 400.068399 -301.837956) (xy 400.103892 -301.872048) (xy 400.133457 -301.911392)
			(xy 400.156328 -301.954969) (xy 400.171912 -302.00165) (xy 400.179807 -302.050227) (xy 400.180302 -302.074834)
			(xy 400.51915 -302.074834) (xy 400.52311 -302.02578) (xy 400.534887 -301.977996) (xy 400.554178 -301.93272)
			(xy 400.580481 -301.891124) (xy 400.613116 -301.854287) (xy 400.651237 -301.823162) (xy 400.693858 -301.798555)
			(xy 400.739874 -301.781103) (xy 400.788093 -301.771259) (xy 400.837268 -301.769278) (xy 400.886123 -301.77521)
			(xy 400.933394 -301.788902) (xy 400.977856 -301.81) (xy 401.018359 -301.837956) (xy 401.053852 -301.872048)
			(xy 401.083417 -301.911392) (xy 401.106288 -301.954969) (xy 401.121872 -302.00165) (xy 401.129767 -302.050227)
			(xy 401.130262 -302.074834) (xy 401.46911 -302.074834) (xy 401.47307 -302.02578) (xy 401.484847 -301.977996)
			(xy 401.504138 -301.93272) (xy 401.530441 -301.891124) (xy 401.563076 -301.854287) (xy 401.601197 -301.823162)
			(xy 401.643818 -301.798555) (xy 401.689834 -301.781103) (xy 401.738053 -301.771259) (xy 401.787228 -301.769278)
			(xy 401.836083 -301.77521) (xy 401.883354 -301.788902) (xy 401.927816 -301.81) (xy 401.968319 -301.837956)
			(xy 402.003812 -301.872048) (xy 402.033377 -301.911392) (xy 402.056248 -301.954969) (xy 402.071832 -302.00165)
			(xy 402.079727 -302.050227) (xy 402.080222 -302.074834) (xy 402.41907 -302.074834) (xy 402.42303 -302.02578)
			(xy 402.434807 -301.977996) (xy 402.454098 -301.93272) (xy 402.480401 -301.891124) (xy 402.513036 -301.854287)
			(xy 402.551157 -301.823162) (xy 402.593778 -301.798555) (xy 402.639794 -301.781103) (xy 402.688013 -301.771259)
			(xy 402.737188 -301.769278) (xy 402.786043 -301.77521) (xy 402.833314 -301.788902) (xy 402.877776 -301.81)
			(xy 402.918279 -301.837956) (xy 402.953772 -301.872048) (xy 402.983337 -301.911392) (xy 403.006208 -301.954969)
			(xy 403.021792 -302.00165) (xy 403.029687 -302.050227) (xy 403.030182 -302.074834) (xy 403.36903 -302.074834)
			(xy 403.37299 -302.02578) (xy 403.384767 -301.977996) (xy 403.404058 -301.93272) (xy 403.430361 -301.891124)
			(xy 403.462996 -301.854287) (xy 403.501117 -301.823162) (xy 403.543738 -301.798555) (xy 403.589754 -301.781103)
			(xy 403.637973 -301.771259) (xy 403.687148 -301.769278) (xy 403.736003 -301.77521) (xy 403.783274 -301.788902)
			(xy 403.827736 -301.81) (xy 403.868239 -301.837956) (xy 403.903732 -301.872048) (xy 403.933297 -301.911392)
			(xy 403.956168 -301.954969) (xy 403.971752 -302.00165) (xy 403.979647 -302.050227) (xy 403.980142 -302.074834)
			(xy 404.31899 -302.074834) (xy 404.32295 -302.02578) (xy 404.334727 -301.977996) (xy 404.354018 -301.93272)
			(xy 404.380321 -301.891124) (xy 404.412956 -301.854287) (xy 404.451077 -301.823162) (xy 404.493698 -301.798555)
			(xy 404.539714 -301.781103) (xy 404.587933 -301.771259) (xy 404.637108 -301.769278) (xy 404.685963 -301.77521)
			(xy 404.733234 -301.788902) (xy 404.777696 -301.81) (xy 404.818199 -301.837956) (xy 404.853692 -301.872048)
			(xy 404.883257 -301.911392) (xy 404.906128 -301.954969) (xy 404.921712 -302.00165) (xy 404.929607 -302.050227)
			(xy 404.930102 -302.074834) (xy 405.269204 -302.074834) (xy 405.273164 -302.02578) (xy 405.284941 -301.977996)
			(xy 405.304232 -301.93272) (xy 405.330535 -301.891124) (xy 405.36317 -301.854287) (xy 405.401291 -301.823162)
			(xy 405.443912 -301.798555) (xy 405.489928 -301.781103) (xy 405.538147 -301.771259) (xy 405.587322 -301.769278)
			(xy 405.636177 -301.77521) (xy 405.683448 -301.788902) (xy 405.72791 -301.81) (xy 405.768413 -301.837956)
			(xy 405.803906 -301.872048) (xy 405.833471 -301.911392) (xy 405.856342 -301.954969) (xy 405.871926 -302.00165)
			(xy 405.879821 -302.050227) (xy 405.880316 -302.074834) (xy 406.219164 -302.074834) (xy 406.223124 -302.02578)
			(xy 406.234901 -301.977996) (xy 406.254192 -301.93272) (xy 406.280495 -301.891124) (xy 406.31313 -301.854287)
			(xy 406.351251 -301.823162) (xy 406.393872 -301.798555) (xy 406.439888 -301.781103) (xy 406.488107 -301.771259)
			(xy 406.537282 -301.769278) (xy 406.586137 -301.77521) (xy 406.633408 -301.788902) (xy 406.67787 -301.81)
			(xy 406.718373 -301.837956) (xy 406.753866 -301.872048) (xy 406.783431 -301.911392) (xy 406.806302 -301.954969)
			(xy 406.821886 -302.00165) (xy 406.829781 -302.050227) (xy 406.830276 -302.074834) (xy 408.119084 -302.074834)
			(xy 408.123044 -302.02578) (xy 408.134821 -301.977996) (xy 408.154112 -301.93272) (xy 408.180415 -301.891124)
			(xy 408.21305 -301.854287) (xy 408.251171 -301.823162) (xy 408.293792 -301.798555) (xy 408.339808 -301.781103)
			(xy 408.388027 -301.771259) (xy 408.437202 -301.769278) (xy 408.486057 -301.77521) (xy 408.533328 -301.788902)
			(xy 408.57779 -301.81) (xy 408.618293 -301.837956) (xy 408.653786 -301.872048) (xy 408.683351 -301.911392)
			(xy 408.706222 -301.954969) (xy 408.721806 -302.00165) (xy 408.729701 -302.050227) (xy 408.730196 -302.074834)
			(xy 409.069044 -302.074834) (xy 409.073004 -302.02578) (xy 409.084781 -301.977996) (xy 409.104072 -301.93272)
			(xy 409.130375 -301.891124) (xy 409.16301 -301.854287) (xy 409.201131 -301.823162) (xy 409.243752 -301.798555)
			(xy 409.289768 -301.781103) (xy 409.337987 -301.771259) (xy 409.387162 -301.769278) (xy 409.436017 -301.77521)
			(xy 409.483288 -301.788902) (xy 409.52775 -301.81) (xy 409.568253 -301.837956) (xy 409.603746 -301.872048)
			(xy 409.633311 -301.911392) (xy 409.656182 -301.954969) (xy 409.671766 -302.00165) (xy 409.679661 -302.050227)
			(xy 409.680156 -302.074834) (xy 410.019004 -302.074834) (xy 410.022964 -302.02578) (xy 410.034741 -301.977996)
			(xy 410.054032 -301.93272) (xy 410.080335 -301.891124) (xy 410.11297 -301.854287) (xy 410.151091 -301.823162)
			(xy 410.193712 -301.798555) (xy 410.239728 -301.781103) (xy 410.287947 -301.771259) (xy 410.337122 -301.769278)
			(xy 410.385977 -301.77521) (xy 410.433248 -301.788902) (xy 410.47771 -301.81) (xy 410.518213 -301.837956)
			(xy 410.553706 -301.872048) (xy 410.583271 -301.911392) (xy 410.606142 -301.954969) (xy 410.621726 -302.00165)
			(xy 410.629621 -302.050227) (xy 410.630116 -302.074834) (xy 410.969218 -302.074834) (xy 410.973178 -302.02578)
			(xy 410.984955 -301.977996) (xy 411.004246 -301.93272) (xy 411.030549 -301.891124) (xy 411.063184 -301.854287)
			(xy 411.101305 -301.823162) (xy 411.143926 -301.798555) (xy 411.189942 -301.781103) (xy 411.238161 -301.771259)
			(xy 411.287336 -301.769278) (xy 411.336191 -301.77521) (xy 411.383462 -301.788902) (xy 411.427924 -301.81)
			(xy 411.468427 -301.837956) (xy 411.50392 -301.872048) (xy 411.533485 -301.911392) (xy 411.556356 -301.954969)
			(xy 411.57194 -302.00165) (xy 411.579835 -302.050227) (xy 411.58033 -302.074834) (xy 411.919178 -302.074834)
			(xy 411.923138 -302.02578) (xy 411.934915 -301.977996) (xy 411.954206 -301.93272) (xy 411.980509 -301.891124)
			(xy 412.013144 -301.854287) (xy 412.051265 -301.823162) (xy 412.093886 -301.798555) (xy 412.139902 -301.781103)
			(xy 412.188121 -301.771259) (xy 412.237296 -301.769278) (xy 412.286151 -301.77521) (xy 412.333422 -301.788902)
			(xy 412.377884 -301.81) (xy 412.418387 -301.837956) (xy 412.45388 -301.872048) (xy 412.483445 -301.911392)
			(xy 412.506316 -301.954969) (xy 412.5219 -302.00165) (xy 412.529795 -302.050227) (xy 412.53029 -302.074834)
			(xy 412.869138 -302.074834) (xy 412.873098 -302.02578) (xy 412.884875 -301.977996) (xy 412.904166 -301.93272)
			(xy 412.930469 -301.891124) (xy 412.963104 -301.854287) (xy 413.001225 -301.823162) (xy 413.043846 -301.798555)
			(xy 413.089862 -301.781103) (xy 413.138081 -301.771259) (xy 413.187256 -301.769278) (xy 413.236111 -301.77521)
			(xy 413.283382 -301.788902) (xy 413.327844 -301.81) (xy 413.368347 -301.837956) (xy 413.40384 -301.872048)
			(xy 413.433405 -301.911392) (xy 413.456276 -301.954969) (xy 413.47186 -302.00165) (xy 413.479755 -302.050227)
			(xy 413.48025 -302.074834) (xy 413.819098 -302.074834) (xy 413.823058 -302.02578) (xy 413.834835 -301.977996)
			(xy 413.854126 -301.93272) (xy 413.880429 -301.891124) (xy 413.913064 -301.854287) (xy 413.951185 -301.823162)
			(xy 413.993806 -301.798555) (xy 414.039822 -301.781103) (xy 414.088041 -301.771259) (xy 414.137216 -301.769278)
			(xy 414.186071 -301.77521) (xy 414.233342 -301.788902) (xy 414.277804 -301.81) (xy 414.318307 -301.837956)
			(xy 414.3538 -301.872048) (xy 414.383365 -301.911392) (xy 414.406236 -301.954969) (xy 414.42182 -302.00165)
			(xy 414.429715 -302.050227) (xy 414.43021 -302.074834) (xy 414.769058 -302.074834) (xy 414.773018 -302.02578)
			(xy 414.784795 -301.977996) (xy 414.804086 -301.93272) (xy 414.830389 -301.891124) (xy 414.863024 -301.854287)
			(xy 414.901145 -301.823162) (xy 414.943766 -301.798555) (xy 414.989782 -301.781103) (xy 415.038001 -301.771259)
			(xy 415.087176 -301.769278) (xy 415.136031 -301.77521) (xy 415.183302 -301.788902) (xy 415.227764 -301.81)
			(xy 415.268267 -301.837956) (xy 415.30376 -301.872048) (xy 415.333325 -301.911392) (xy 415.356196 -301.954969)
			(xy 415.37178 -302.00165) (xy 415.379675 -302.050227) (xy 415.38017 -302.074834) (xy 415.719018 -302.074834)
			(xy 415.722978 -302.02578) (xy 415.734755 -301.977996) (xy 415.754046 -301.93272) (xy 415.780349 -301.891124)
			(xy 415.812984 -301.854287) (xy 415.851105 -301.823162) (xy 415.893726 -301.798555) (xy 415.939742 -301.781103)
			(xy 415.987961 -301.771259) (xy 416.037136 -301.769278) (xy 416.085991 -301.77521) (xy 416.133262 -301.788902)
			(xy 416.177724 -301.81) (xy 416.218227 -301.837956) (xy 416.25372 -301.872048) (xy 416.283285 -301.911392)
			(xy 416.306156 -301.954969) (xy 416.32174 -302.00165) (xy 416.329635 -302.050227) (xy 416.33013 -302.074834)
			(xy 416.668978 -302.074834) (xy 416.672938 -302.02578) (xy 416.684715 -301.977996) (xy 416.704006 -301.93272)
			(xy 416.730309 -301.891124) (xy 416.762944 -301.854287) (xy 416.801065 -301.823162) (xy 416.843686 -301.798555)
			(xy 416.889702 -301.781103) (xy 416.937921 -301.771259) (xy 416.987096 -301.769278) (xy 417.035951 -301.77521)
			(xy 417.083222 -301.788902) (xy 417.127684 -301.81) (xy 417.168187 -301.837956) (xy 417.20368 -301.872048)
			(xy 417.233245 -301.911392) (xy 417.256116 -301.954969) (xy 417.2717 -302.00165) (xy 417.279595 -302.050227)
			(xy 417.28009 -302.074834) (xy 417.619192 -302.074834) (xy 417.623152 -302.02578) (xy 417.634929 -301.977996)
			(xy 417.65422 -301.93272) (xy 417.680523 -301.891124) (xy 417.713158 -301.854287) (xy 417.751279 -301.823162)
			(xy 417.7939 -301.798555) (xy 417.839916 -301.781103) (xy 417.888135 -301.771259) (xy 417.93731 -301.769278)
			(xy 417.986165 -301.77521) (xy 418.033436 -301.788902) (xy 418.077898 -301.81) (xy 418.118401 -301.837956)
			(xy 418.153894 -301.872048) (xy 418.183459 -301.911392) (xy 418.20633 -301.954969) (xy 418.221914 -302.00165)
			(xy 418.229809 -302.050227) (xy 418.230304 -302.074834) (xy 418.569152 -302.074834) (xy 418.573112 -302.02578)
			(xy 418.584889 -301.977996) (xy 418.60418 -301.93272) (xy 418.630483 -301.891124) (xy 418.663118 -301.854287)
			(xy 418.701239 -301.823162) (xy 418.74386 -301.798555) (xy 418.789876 -301.781103) (xy 418.838095 -301.771259)
			(xy 418.88727 -301.769278) (xy 418.936125 -301.77521) (xy 418.983396 -301.788902) (xy 419.027858 -301.81)
			(xy 419.068361 -301.837956) (xy 419.103854 -301.872048) (xy 419.133419 -301.911392) (xy 419.15629 -301.954969)
			(xy 419.171874 -302.00165) (xy 419.179769 -302.050227) (xy 419.180264 -302.074834) (xy 419.519112 -302.074834)
			(xy 419.523072 -302.02578) (xy 419.534849 -301.977996) (xy 419.55414 -301.93272) (xy 419.580443 -301.891124)
			(xy 419.613078 -301.854287) (xy 419.651199 -301.823162) (xy 419.69382 -301.798555) (xy 419.739836 -301.781103)
			(xy 419.788055 -301.771259) (xy 419.83723 -301.769278) (xy 419.886085 -301.77521) (xy 419.933356 -301.788902)
			(xy 419.977818 -301.81) (xy 420.018321 -301.837956) (xy 420.053814 -301.872048) (xy 420.083379 -301.911392)
			(xy 420.10625 -301.954969) (xy 420.121834 -302.00165) (xy 420.129729 -302.050227) (xy 420.130224 -302.074834)
			(xy 420.469072 -302.074834) (xy 420.473032 -302.02578) (xy 420.484809 -301.977996) (xy 420.5041 -301.93272)
			(xy 420.530403 -301.891124) (xy 420.563038 -301.854287) (xy 420.601159 -301.823162) (xy 420.64378 -301.798555)
			(xy 420.689796 -301.781103) (xy 420.738015 -301.771259) (xy 420.78719 -301.769278) (xy 420.836045 -301.77521)
			(xy 420.883316 -301.788902) (xy 420.927778 -301.81) (xy 420.968281 -301.837956) (xy 421.003774 -301.872048)
			(xy 421.033339 -301.911392) (xy 421.05621 -301.954969) (xy 421.071794 -302.00165) (xy 421.079689 -302.050227)
			(xy 421.080184 -302.074834) (xy 421.419032 -302.074834) (xy 421.422992 -302.02578) (xy 421.434769 -301.977996)
			(xy 421.45406 -301.93272) (xy 421.480363 -301.891124) (xy 421.512998 -301.854287) (xy 421.551119 -301.823162)
			(xy 421.59374 -301.798555) (xy 421.639756 -301.781103) (xy 421.687975 -301.771259) (xy 421.73715 -301.769278)
			(xy 421.786005 -301.77521) (xy 421.833276 -301.788902) (xy 421.877738 -301.81) (xy 421.918241 -301.837956)
			(xy 421.953734 -301.872048) (xy 421.983299 -301.911392) (xy 422.00617 -301.954969) (xy 422.021754 -302.00165)
			(xy 422.029649 -302.050227) (xy 422.030144 -302.074834) (xy 422.368992 -302.074834) (xy 422.372952 -302.02578)
			(xy 422.384729 -301.977996) (xy 422.40402 -301.93272) (xy 422.430323 -301.891124) (xy 422.462958 -301.854287)
			(xy 422.501079 -301.823162) (xy 422.5437 -301.798555) (xy 422.589716 -301.781103) (xy 422.637935 -301.771259)
			(xy 422.68711 -301.769278) (xy 422.735965 -301.77521) (xy 422.783236 -301.788902) (xy 422.827698 -301.81)
			(xy 422.868201 -301.837956) (xy 422.903694 -301.872048) (xy 422.933259 -301.911392) (xy 422.95613 -301.954969)
			(xy 422.971714 -302.00165) (xy 422.979609 -302.050227) (xy 422.980104 -302.074834) (xy 423.319206 -302.074834)
			(xy 423.323166 -302.02578) (xy 423.334943 -301.977996) (xy 423.354234 -301.93272) (xy 423.380537 -301.891124)
			(xy 423.413172 -301.854287) (xy 423.451293 -301.823162) (xy 423.493914 -301.798555) (xy 423.53993 -301.781103)
			(xy 423.588149 -301.771259) (xy 423.637324 -301.769278) (xy 423.686179 -301.77521) (xy 423.73345 -301.788902)
			(xy 423.777912 -301.81) (xy 423.818415 -301.837956) (xy 423.853908 -301.872048) (xy 423.883473 -301.911392)
			(xy 423.906344 -301.954969) (xy 423.921928 -302.00165) (xy 423.929823 -302.050227) (xy 423.930318 -302.074834)
			(xy 424.269166 -302.074834) (xy 424.273126 -302.02578) (xy 424.284903 -301.977996) (xy 424.304194 -301.93272)
			(xy 424.330497 -301.891124) (xy 424.363132 -301.854287) (xy 424.401253 -301.823162) (xy 424.443874 -301.798555)
			(xy 424.48989 -301.781103) (xy 424.538109 -301.771259) (xy 424.587284 -301.769278) (xy 424.636139 -301.77521)
			(xy 424.68341 -301.788902) (xy 424.727872 -301.81) (xy 424.768375 -301.837956) (xy 424.803868 -301.872048)
			(xy 424.833433 -301.911392) (xy 424.856304 -301.954969) (xy 424.871888 -302.00165) (xy 424.879783 -302.050227)
			(xy 424.880278 -302.074834) (xy 425.219126 -302.074834) (xy 425.223086 -302.02578) (xy 425.234863 -301.977996)
			(xy 425.254154 -301.93272) (xy 425.280457 -301.891124) (xy 425.313092 -301.854287) (xy 425.351213 -301.823162)
			(xy 425.393834 -301.798555) (xy 425.43985 -301.781103) (xy 425.488069 -301.771259) (xy 425.537244 -301.769278)
			(xy 425.586099 -301.77521) (xy 425.63337 -301.788902) (xy 425.677832 -301.81) (xy 425.718335 -301.837956)
			(xy 425.753828 -301.872048) (xy 425.783393 -301.911392) (xy 425.806264 -301.954969) (xy 425.821848 -302.00165)
			(xy 425.829743 -302.050227) (xy 425.830238 -302.074834) (xy 426.169086 -302.074834) (xy 426.173046 -302.02578)
			(xy 426.184823 -301.977996) (xy 426.204114 -301.93272) (xy 426.230417 -301.891124) (xy 426.263052 -301.854287)
			(xy 426.301173 -301.823162) (xy 426.343794 -301.798555) (xy 426.38981 -301.781103) (xy 426.438029 -301.771259)
			(xy 426.487204 -301.769278) (xy 426.536059 -301.77521) (xy 426.58333 -301.788902) (xy 426.627792 -301.81)
			(xy 426.668295 -301.837956) (xy 426.703788 -301.872048) (xy 426.733353 -301.911392) (xy 426.756224 -301.954969)
			(xy 426.771808 -302.00165) (xy 426.779703 -302.050227) (xy 426.780198 -302.074834) (xy 427.119046 -302.074834)
			(xy 427.123006 -302.02578) (xy 427.134783 -301.977996) (xy 427.154074 -301.93272) (xy 427.180377 -301.891124)
			(xy 427.213012 -301.854287) (xy 427.251133 -301.823162) (xy 427.293754 -301.798555) (xy 427.33977 -301.781103)
			(xy 427.387989 -301.771259) (xy 427.437164 -301.769278) (xy 427.486019 -301.77521) (xy 427.53329 -301.788902)
			(xy 427.577752 -301.81) (xy 427.618255 -301.837956) (xy 427.653748 -301.872048) (xy 427.683313 -301.911392)
			(xy 427.706184 -301.954969) (xy 427.721768 -302.00165) (xy 427.729663 -302.050227) (xy 427.730158 -302.074834)
			(xy 428.069006 -302.074834) (xy 428.072966 -302.02578) (xy 428.084743 -301.977996) (xy 428.104034 -301.93272)
			(xy 428.130337 -301.891124) (xy 428.162972 -301.854287) (xy 428.201093 -301.823162) (xy 428.243714 -301.798555)
			(xy 428.28973 -301.781103) (xy 428.337949 -301.771259) (xy 428.387124 -301.769278) (xy 428.435979 -301.77521)
			(xy 428.48325 -301.788902) (xy 428.527712 -301.81) (xy 428.568215 -301.837956) (xy 428.603708 -301.872048)
			(xy 428.633273 -301.911392) (xy 428.656144 -301.954969) (xy 428.671728 -302.00165) (xy 428.679623 -302.050227)
			(xy 428.680118 -302.074834) (xy 429.01922 -302.074834) (xy 429.02318 -302.02578) (xy 429.034957 -301.977996)
			(xy 429.054248 -301.93272) (xy 429.080551 -301.891124) (xy 429.113186 -301.854287) (xy 429.151307 -301.823162)
			(xy 429.193928 -301.798555) (xy 429.239944 -301.781103) (xy 429.288163 -301.771259) (xy 429.337338 -301.769278)
			(xy 429.386193 -301.77521) (xy 429.433464 -301.788902) (xy 429.477926 -301.81) (xy 429.518429 -301.837956)
			(xy 429.553922 -301.872048) (xy 429.583487 -301.911392) (xy 429.606358 -301.954969) (xy 429.621942 -302.00165)
			(xy 429.629837 -302.050227) (xy 429.630332 -302.074834) (xy 429.96918 -302.074834) (xy 429.97314 -302.02578)
			(xy 429.984917 -301.977996) (xy 430.004208 -301.93272) (xy 430.030511 -301.891124) (xy 430.063146 -301.854287)
			(xy 430.101267 -301.823162) (xy 430.143888 -301.798555) (xy 430.189904 -301.781103) (xy 430.238123 -301.771259)
			(xy 430.287298 -301.769278) (xy 430.336153 -301.77521) (xy 430.383424 -301.788902) (xy 430.427886 -301.81)
			(xy 430.468389 -301.837956) (xy 430.503882 -301.872048) (xy 430.533447 -301.911392) (xy 430.556318 -301.954969)
			(xy 430.571902 -302.00165) (xy 430.579797 -302.050227) (xy 430.580292 -302.074834) (xy 430.91914 -302.074834)
			(xy 430.9231 -302.02578) (xy 430.934877 -301.977996) (xy 430.954168 -301.93272) (xy 430.980471 -301.891124)
			(xy 431.013106 -301.854287) (xy 431.051227 -301.823162) (xy 431.093848 -301.798555) (xy 431.139864 -301.781103)
			(xy 431.188083 -301.771259) (xy 431.237258 -301.769278) (xy 431.286113 -301.77521) (xy 431.333384 -301.788902)
			(xy 431.377846 -301.81) (xy 431.418349 -301.837956) (xy 431.453842 -301.872048) (xy 431.483407 -301.911392)
			(xy 431.506278 -301.954969) (xy 431.521862 -302.00165) (xy 431.529757 -302.050227) (xy 431.529997 -302.062134)
			(xy 433.675788 -302.062134) (xy 433.679859 -302.006512) (xy 433.691985 -301.952075) (xy 433.711908 -301.899984)
			(xy 433.739204 -301.851349) (xy 433.77329 -301.807206) (xy 433.813439 -301.768497) (xy 433.858797 -301.736046)
			(xy 433.908397 -301.710545) (xy 433.961181 -301.692538) (xy 434.016024 -301.682408) (xy 434.071758 -301.680371)
			(xy 434.127195 -301.686471) (xy 434.181152 -301.700577) (xy 434.232481 -301.722389) (xy 434.280087 -301.751443)
			(xy 434.322955 -301.787118) (xy 434.360172 -301.828655) (xy 434.390945 -301.875168) (xy 434.392741 -301.879)
			(xy 434.647592 -301.879) (xy 434.651663 -301.823378) (xy 434.663789 -301.768941) (xy 434.683712 -301.71685)
			(xy 434.711008 -301.668215) (xy 434.745094 -301.624072) (xy 434.785243 -301.585363) (xy 434.830601 -301.552912)
			(xy 434.880201 -301.527411) (xy 434.932985 -301.509404) (xy 434.987828 -301.499274) (xy 435.043562 -301.497237)
			(xy 435.098999 -301.503337) (xy 435.152956 -301.517443) (xy 435.204285 -301.539255) (xy 435.226168 -301.55261)
			(xy 436.41975 -301.55261) (xy 436.423821 -301.496988) (xy 436.435947 -301.442551) (xy 436.45587 -301.39046)
			(xy 436.483166 -301.341825) (xy 436.517252 -301.297682) (xy 436.557401 -301.258973) (xy 436.602759 -301.226522)
			(xy 436.652359 -301.201021) (xy 436.705143 -301.183014) (xy 436.759986 -301.172884) (xy 436.81572 -301.170847)
			(xy 436.871157 -301.176947) (xy 436.925114 -301.191053) (xy 436.976443 -301.212865) (xy 437.024049 -301.241919)
			(xy 437.066917 -301.277594) (xy 437.104134 -301.319131) (xy 437.134907 -301.365644) (xy 437.158579 -301.416141)
			(xy 437.174647 -301.469548) (xy 437.182767 -301.524724) (xy 437.183276 -301.55261) (xy 437.182836 -301.57674)
			(xy 439.81319 -301.57674) (xy 439.817261 -301.521118) (xy 439.829387 -301.466681) (xy 439.84931 -301.41459)
			(xy 439.876606 -301.365955) (xy 439.910692 -301.321812) (xy 439.950841 -301.283103) (xy 439.996199 -301.250652)
			(xy 440.045799 -301.225151) (xy 440.098583 -301.207144) (xy 440.153426 -301.197014) (xy 440.20916 -301.194977)
			(xy 440.264597 -301.201077) (xy 440.318554 -301.215183) (xy 440.369883 -301.236995) (xy 440.417489 -301.266049)
			(xy 440.460357 -301.301724) (xy 440.497574 -301.343261) (xy 440.528347 -301.389774) (xy 440.552019 -301.440271)
			(xy 440.568087 -301.493678) (xy 440.576207 -301.548854) (xy 440.576716 -301.57674) (xy 440.576207 -301.604626)
			(xy 440.568087 -301.659802) (xy 440.552019 -301.713209) (xy 440.528347 -301.763706) (xy 440.497574 -301.810219)
			(xy 440.460357 -301.851756) (xy 440.417489 -301.887431) (xy 440.369883 -301.916485) (xy 440.318554 -301.938297)
			(xy 440.264597 -301.952403) (xy 440.20916 -301.958503) (xy 440.153426 -301.956466) (xy 440.098583 -301.946336)
			(xy 440.045799 -301.928329) (xy 439.996199 -301.902828) (xy 439.950841 -301.870377) (xy 439.910692 -301.831668)
			(xy 439.876606 -301.787525) (xy 439.84931 -301.73889) (xy 439.829387 -301.686799) (xy 439.817261 -301.632362)
			(xy 439.81319 -301.57674) (xy 437.182836 -301.57674) (xy 437.182767 -301.580496) (xy 437.174647 -301.635672)
			(xy 437.158579 -301.689079) (xy 437.134907 -301.739576) (xy 437.104134 -301.786089) (xy 437.066917 -301.827626)
			(xy 437.024049 -301.863301) (xy 436.976443 -301.892355) (xy 436.925114 -301.914167) (xy 436.871157 -301.928273)
			(xy 436.81572 -301.934373) (xy 436.759986 -301.932336) (xy 436.705143 -301.922206) (xy 436.652359 -301.904199)
			(xy 436.602759 -301.878698) (xy 436.557401 -301.846247) (xy 436.517252 -301.807538) (xy 436.483166 -301.763395)
			(xy 436.45587 -301.71476) (xy 436.435947 -301.662669) (xy 436.423821 -301.608232) (xy 436.41975 -301.55261)
			(xy 435.226168 -301.55261) (xy 435.251891 -301.568309) (xy 435.294759 -301.603984) (xy 435.331976 -301.645521)
			(xy 435.362749 -301.692034) (xy 435.386421 -301.742531) (xy 435.402489 -301.795938) (xy 435.410609 -301.851114)
			(xy 435.411118 -301.879) (xy 435.410609 -301.906886) (xy 435.402489 -301.962062) (xy 435.386421 -302.015469)
			(xy 435.362749 -302.065966) (xy 435.331976 -302.112479) (xy 435.294759 -302.154016) (xy 435.251891 -302.189691)
			(xy 435.204285 -302.218745) (xy 435.152956 -302.240557) (xy 435.098999 -302.254663) (xy 435.043562 -302.260763)
			(xy 434.987828 -302.258726) (xy 434.932985 -302.248596) (xy 434.880201 -302.230589) (xy 434.830601 -302.205088)
			(xy 434.785243 -302.172637) (xy 434.745094 -302.133928) (xy 434.711008 -302.089785) (xy 434.683712 -302.04115)
			(xy 434.663789 -301.989059) (xy 434.651663 -301.934622) (xy 434.647592 -301.879) (xy 434.392741 -301.879)
			(xy 434.414617 -301.925665) (xy 434.430685 -301.979072) (xy 434.438805 -302.034248) (xy 434.439314 -302.062134)
			(xy 434.438805 -302.09002) (xy 434.430685 -302.145196) (xy 434.414617 -302.198603) (xy 434.390945 -302.2491)
			(xy 434.360172 -302.295613) (xy 434.322955 -302.33715) (xy 434.280087 -302.372825) (xy 434.232481 -302.401879)
			(xy 434.181152 -302.423691) (xy 434.127195 -302.437797) (xy 434.071758 -302.443897) (xy 434.016024 -302.44186)
			(xy 433.961181 -302.43173) (xy 433.908397 -302.413723) (xy 433.858797 -302.388222) (xy 433.813439 -302.355771)
			(xy 433.77329 -302.317062) (xy 433.739204 -302.272919) (xy 433.711908 -302.224284) (xy 433.691985 -302.172193)
			(xy 433.679859 -302.117756) (xy 433.675788 -302.062134) (xy 431.529997 -302.062134) (xy 431.530252 -302.074834)
			(xy 431.529757 -302.099441) (xy 431.521862 -302.148018) (xy 431.506278 -302.194699) (xy 431.483407 -302.238276)
			(xy 431.453842 -302.27762) (xy 431.418349 -302.311712) (xy 431.377846 -302.339668) (xy 431.333384 -302.360766)
			(xy 431.286113 -302.374458) (xy 431.237258 -302.38039) (xy 431.188083 -302.378409) (xy 431.139864 -302.368565)
			(xy 431.093848 -302.351113) (xy 431.051227 -302.326506) (xy 431.013106 -302.295381) (xy 430.980471 -302.258544)
			(xy 430.954168 -302.216948) (xy 430.934877 -302.171672) (xy 430.9231 -302.123888) (xy 430.91914 -302.074834)
			(xy 430.580292 -302.074834) (xy 430.579797 -302.099441) (xy 430.571902 -302.148018) (xy 430.556318 -302.194699)
			(xy 430.533447 -302.238276) (xy 430.503882 -302.27762) (xy 430.468389 -302.311712) (xy 430.427886 -302.339668)
			(xy 430.383424 -302.360766) (xy 430.336153 -302.374458) (xy 430.287298 -302.38039) (xy 430.238123 -302.378409)
			(xy 430.189904 -302.368565) (xy 430.143888 -302.351113) (xy 430.101267 -302.326506) (xy 430.063146 -302.295381)
			(xy 430.030511 -302.258544) (xy 430.004208 -302.216948) (xy 429.984917 -302.171672) (xy 429.97314 -302.123888)
			(xy 429.96918 -302.074834) (xy 429.630332 -302.074834) (xy 429.629837 -302.099441) (xy 429.621942 -302.148018)
			(xy 429.606358 -302.194699) (xy 429.583487 -302.238276) (xy 429.553922 -302.27762) (xy 429.518429 -302.311712)
			(xy 429.477926 -302.339668) (xy 429.433464 -302.360766) (xy 429.386193 -302.374458) (xy 429.337338 -302.38039)
			(xy 429.288163 -302.378409) (xy 429.239944 -302.368565) (xy 429.193928 -302.351113) (xy 429.151307 -302.326506)
			(xy 429.113186 -302.295381) (xy 429.080551 -302.258544) (xy 429.054248 -302.216948) (xy 429.034957 -302.171672)
			(xy 429.02318 -302.123888) (xy 429.01922 -302.074834) (xy 428.680118 -302.074834) (xy 428.679623 -302.099441)
			(xy 428.671728 -302.148018) (xy 428.656144 -302.194699) (xy 428.633273 -302.238276) (xy 428.603708 -302.27762)
			(xy 428.568215 -302.311712) (xy 428.527712 -302.339668) (xy 428.48325 -302.360766) (xy 428.435979 -302.374458)
			(xy 428.387124 -302.38039) (xy 428.337949 -302.378409) (xy 428.28973 -302.368565) (xy 428.243714 -302.351113)
			(xy 428.201093 -302.326506) (xy 428.162972 -302.295381) (xy 428.130337 -302.258544) (xy 428.104034 -302.216948)
			(xy 428.084743 -302.171672) (xy 428.072966 -302.123888) (xy 428.069006 -302.074834) (xy 427.730158 -302.074834)
			(xy 427.729663 -302.099441) (xy 427.721768 -302.148018) (xy 427.706184 -302.194699) (xy 427.683313 -302.238276)
			(xy 427.653748 -302.27762) (xy 427.618255 -302.311712) (xy 427.577752 -302.339668) (xy 427.53329 -302.360766)
			(xy 427.486019 -302.374458) (xy 427.437164 -302.38039) (xy 427.387989 -302.378409) (xy 427.33977 -302.368565)
			(xy 427.293754 -302.351113) (xy 427.251133 -302.326506) (xy 427.213012 -302.295381) (xy 427.180377 -302.258544)
			(xy 427.154074 -302.216948) (xy 427.134783 -302.171672) (xy 427.123006 -302.123888) (xy 427.119046 -302.074834)
			(xy 426.780198 -302.074834) (xy 426.779703 -302.099441) (xy 426.771808 -302.148018) (xy 426.756224 -302.194699)
			(xy 426.733353 -302.238276) (xy 426.703788 -302.27762) (xy 426.668295 -302.311712) (xy 426.627792 -302.339668)
			(xy 426.58333 -302.360766) (xy 426.536059 -302.374458) (xy 426.487204 -302.38039) (xy 426.438029 -302.378409)
			(xy 426.38981 -302.368565) (xy 426.343794 -302.351113) (xy 426.301173 -302.326506) (xy 426.263052 -302.295381)
			(xy 426.230417 -302.258544) (xy 426.204114 -302.216948) (xy 426.184823 -302.171672) (xy 426.173046 -302.123888)
			(xy 426.169086 -302.074834) (xy 425.830238 -302.074834) (xy 425.829743 -302.099441) (xy 425.821848 -302.148018)
			(xy 425.806264 -302.194699) (xy 425.783393 -302.238276) (xy 425.753828 -302.27762) (xy 425.718335 -302.311712)
			(xy 425.677832 -302.339668) (xy 425.63337 -302.360766) (xy 425.586099 -302.374458) (xy 425.537244 -302.38039)
			(xy 425.488069 -302.378409) (xy 425.43985 -302.368565) (xy 425.393834 -302.351113) (xy 425.351213 -302.326506)
			(xy 425.313092 -302.295381) (xy 425.280457 -302.258544) (xy 425.254154 -302.216948) (xy 425.234863 -302.171672)
			(xy 425.223086 -302.123888) (xy 425.219126 -302.074834) (xy 424.880278 -302.074834) (xy 424.879783 -302.099441)
			(xy 424.871888 -302.148018) (xy 424.856304 -302.194699) (xy 424.833433 -302.238276) (xy 424.803868 -302.27762)
			(xy 424.768375 -302.311712) (xy 424.727872 -302.339668) (xy 424.68341 -302.360766) (xy 424.636139 -302.374458)
			(xy 424.587284 -302.38039) (xy 424.538109 -302.378409) (xy 424.48989 -302.368565) (xy 424.443874 -302.351113)
			(xy 424.401253 -302.326506) (xy 424.363132 -302.295381) (xy 424.330497 -302.258544) (xy 424.304194 -302.216948)
			(xy 424.284903 -302.171672) (xy 424.273126 -302.123888) (xy 424.269166 -302.074834) (xy 423.930318 -302.074834)
			(xy 423.929823 -302.099441) (xy 423.921928 -302.148018) (xy 423.906344 -302.194699) (xy 423.883473 -302.238276)
			(xy 423.853908 -302.27762) (xy 423.818415 -302.311712) (xy 423.777912 -302.339668) (xy 423.73345 -302.360766)
			(xy 423.686179 -302.374458) (xy 423.637324 -302.38039) (xy 423.588149 -302.378409) (xy 423.53993 -302.368565)
			(xy 423.493914 -302.351113) (xy 423.451293 -302.326506) (xy 423.413172 -302.295381) (xy 423.380537 -302.258544)
			(xy 423.354234 -302.216948) (xy 423.334943 -302.171672) (xy 423.323166 -302.123888) (xy 423.319206 -302.074834)
			(xy 422.980104 -302.074834) (xy 422.979609 -302.099441) (xy 422.971714 -302.148018) (xy 422.95613 -302.194699)
			(xy 422.933259 -302.238276) (xy 422.903694 -302.27762) (xy 422.868201 -302.311712) (xy 422.827698 -302.339668)
			(xy 422.783236 -302.360766) (xy 422.735965 -302.374458) (xy 422.68711 -302.38039) (xy 422.637935 -302.378409)
			(xy 422.589716 -302.368565) (xy 422.5437 -302.351113) (xy 422.501079 -302.326506) (xy 422.462958 -302.295381)
			(xy 422.430323 -302.258544) (xy 422.40402 -302.216948) (xy 422.384729 -302.171672) (xy 422.372952 -302.123888)
			(xy 422.368992 -302.074834) (xy 422.030144 -302.074834) (xy 422.029649 -302.099441) (xy 422.021754 -302.148018)
			(xy 422.00617 -302.194699) (xy 421.983299 -302.238276) (xy 421.953734 -302.27762) (xy 421.918241 -302.311712)
			(xy 421.877738 -302.339668) (xy 421.833276 -302.360766) (xy 421.786005 -302.374458) (xy 421.73715 -302.38039)
			(xy 421.687975 -302.378409) (xy 421.639756 -302.368565) (xy 421.59374 -302.351113) (xy 421.551119 -302.326506)
			(xy 421.512998 -302.295381) (xy 421.480363 -302.258544) (xy 421.45406 -302.216948) (xy 421.434769 -302.171672)
			(xy 421.422992 -302.123888) (xy 421.419032 -302.074834) (xy 421.080184 -302.074834) (xy 421.079689 -302.099441)
			(xy 421.071794 -302.148018) (xy 421.05621 -302.194699) (xy 421.033339 -302.238276) (xy 421.003774 -302.27762)
			(xy 420.968281 -302.311712) (xy 420.927778 -302.339668) (xy 420.883316 -302.360766) (xy 420.836045 -302.374458)
			(xy 420.78719 -302.38039) (xy 420.738015 -302.378409) (xy 420.689796 -302.368565) (xy 420.64378 -302.351113)
			(xy 420.601159 -302.326506) (xy 420.563038 -302.295381) (xy 420.530403 -302.258544) (xy 420.5041 -302.216948)
			(xy 420.484809 -302.171672) (xy 420.473032 -302.123888) (xy 420.469072 -302.074834) (xy 420.130224 -302.074834)
			(xy 420.129729 -302.099441) (xy 420.121834 -302.148018) (xy 420.10625 -302.194699) (xy 420.083379 -302.238276)
			(xy 420.053814 -302.27762) (xy 420.018321 -302.311712) (xy 419.977818 -302.339668) (xy 419.933356 -302.360766)
			(xy 419.886085 -302.374458) (xy 419.83723 -302.38039) (xy 419.788055 -302.378409) (xy 419.739836 -302.368565)
			(xy 419.69382 -302.351113) (xy 419.651199 -302.326506) (xy 419.613078 -302.295381) (xy 419.580443 -302.258544)
			(xy 419.55414 -302.216948) (xy 419.534849 -302.171672) (xy 419.523072 -302.123888) (xy 419.519112 -302.074834)
			(xy 419.180264 -302.074834) (xy 419.179769 -302.099441) (xy 419.171874 -302.148018) (xy 419.15629 -302.194699)
			(xy 419.133419 -302.238276) (xy 419.103854 -302.27762) (xy 419.068361 -302.311712) (xy 419.027858 -302.339668)
			(xy 418.983396 -302.360766) (xy 418.936125 -302.374458) (xy 418.88727 -302.38039) (xy 418.838095 -302.378409)
			(xy 418.789876 -302.368565) (xy 418.74386 -302.351113) (xy 418.701239 -302.326506) (xy 418.663118 -302.295381)
			(xy 418.630483 -302.258544) (xy 418.60418 -302.216948) (xy 418.584889 -302.171672) (xy 418.573112 -302.123888)
			(xy 418.569152 -302.074834) (xy 418.230304 -302.074834) (xy 418.229809 -302.099441) (xy 418.221914 -302.148018)
			(xy 418.20633 -302.194699) (xy 418.183459 -302.238276) (xy 418.153894 -302.27762) (xy 418.118401 -302.311712)
			(xy 418.077898 -302.339668) (xy 418.033436 -302.360766) (xy 417.986165 -302.374458) (xy 417.93731 -302.38039)
			(xy 417.888135 -302.378409) (xy 417.839916 -302.368565) (xy 417.7939 -302.351113) (xy 417.751279 -302.326506)
			(xy 417.713158 -302.295381) (xy 417.680523 -302.258544) (xy 417.65422 -302.216948) (xy 417.634929 -302.171672)
			(xy 417.623152 -302.123888) (xy 417.619192 -302.074834) (xy 417.28009 -302.074834) (xy 417.279595 -302.099441)
			(xy 417.2717 -302.148018) (xy 417.256116 -302.194699) (xy 417.233245 -302.238276) (xy 417.20368 -302.27762)
			(xy 417.168187 -302.311712) (xy 417.127684 -302.339668) (xy 417.083222 -302.360766) (xy 417.035951 -302.374458)
			(xy 416.987096 -302.38039) (xy 416.937921 -302.378409) (xy 416.889702 -302.368565) (xy 416.843686 -302.351113)
			(xy 416.801065 -302.326506) (xy 416.762944 -302.295381) (xy 416.730309 -302.258544) (xy 416.704006 -302.216948)
			(xy 416.684715 -302.171672) (xy 416.672938 -302.123888) (xy 416.668978 -302.074834) (xy 416.33013 -302.074834)
			(xy 416.329635 -302.099441) (xy 416.32174 -302.148018) (xy 416.306156 -302.194699) (xy 416.283285 -302.238276)
			(xy 416.25372 -302.27762) (xy 416.218227 -302.311712) (xy 416.177724 -302.339668) (xy 416.133262 -302.360766)
			(xy 416.085991 -302.374458) (xy 416.037136 -302.38039) (xy 415.987961 -302.378409) (xy 415.939742 -302.368565)
			(xy 415.893726 -302.351113) (xy 415.851105 -302.326506) (xy 415.812984 -302.295381) (xy 415.780349 -302.258544)
			(xy 415.754046 -302.216948) (xy 415.734755 -302.171672) (xy 415.722978 -302.123888) (xy 415.719018 -302.074834)
			(xy 415.38017 -302.074834) (xy 415.379675 -302.099441) (xy 415.37178 -302.148018) (xy 415.356196 -302.194699)
			(xy 415.333325 -302.238276) (xy 415.30376 -302.27762) (xy 415.268267 -302.311712) (xy 415.227764 -302.339668)
			(xy 415.183302 -302.360766) (xy 415.136031 -302.374458) (xy 415.087176 -302.38039) (xy 415.038001 -302.378409)
			(xy 414.989782 -302.368565) (xy 414.943766 -302.351113) (xy 414.901145 -302.326506) (xy 414.863024 -302.295381)
			(xy 414.830389 -302.258544) (xy 414.804086 -302.216948) (xy 414.784795 -302.171672) (xy 414.773018 -302.123888)
			(xy 414.769058 -302.074834) (xy 414.43021 -302.074834) (xy 414.429715 -302.099441) (xy 414.42182 -302.148018)
			(xy 414.406236 -302.194699) (xy 414.383365 -302.238276) (xy 414.3538 -302.27762) (xy 414.318307 -302.311712)
			(xy 414.277804 -302.339668) (xy 414.233342 -302.360766) (xy 414.186071 -302.374458) (xy 414.137216 -302.38039)
			(xy 414.088041 -302.378409) (xy 414.039822 -302.368565) (xy 413.993806 -302.351113) (xy 413.951185 -302.326506)
			(xy 413.913064 -302.295381) (xy 413.880429 -302.258544) (xy 413.854126 -302.216948) (xy 413.834835 -302.171672)
			(xy 413.823058 -302.123888) (xy 413.819098 -302.074834) (xy 413.48025 -302.074834) (xy 413.479755 -302.099441)
			(xy 413.47186 -302.148018) (xy 413.456276 -302.194699) (xy 413.433405 -302.238276) (xy 413.40384 -302.27762)
			(xy 413.368347 -302.311712) (xy 413.327844 -302.339668) (xy 413.283382 -302.360766) (xy 413.236111 -302.374458)
			(xy 413.187256 -302.38039) (xy 413.138081 -302.378409) (xy 413.089862 -302.368565) (xy 413.043846 -302.351113)
			(xy 413.001225 -302.326506) (xy 412.963104 -302.295381) (xy 412.930469 -302.258544) (xy 412.904166 -302.216948)
			(xy 412.884875 -302.171672) (xy 412.873098 -302.123888) (xy 412.869138 -302.074834) (xy 412.53029 -302.074834)
			(xy 412.529795 -302.099441) (xy 412.5219 -302.148018) (xy 412.506316 -302.194699) (xy 412.483445 -302.238276)
			(xy 412.45388 -302.27762) (xy 412.418387 -302.311712) (xy 412.377884 -302.339668) (xy 412.333422 -302.360766)
			(xy 412.286151 -302.374458) (xy 412.237296 -302.38039) (xy 412.188121 -302.378409) (xy 412.139902 -302.368565)
			(xy 412.093886 -302.351113) (xy 412.051265 -302.326506) (xy 412.013144 -302.295381) (xy 411.980509 -302.258544)
			(xy 411.954206 -302.216948) (xy 411.934915 -302.171672) (xy 411.923138 -302.123888) (xy 411.919178 -302.074834)
			(xy 411.58033 -302.074834) (xy 411.579835 -302.099441) (xy 411.57194 -302.148018) (xy 411.556356 -302.194699)
			(xy 411.533485 -302.238276) (xy 411.50392 -302.27762) (xy 411.468427 -302.311712) (xy 411.427924 -302.339668)
			(xy 411.383462 -302.360766) (xy 411.336191 -302.374458) (xy 411.287336 -302.38039) (xy 411.238161 -302.378409)
			(xy 411.189942 -302.368565) (xy 411.143926 -302.351113) (xy 411.101305 -302.326506) (xy 411.063184 -302.295381)
			(xy 411.030549 -302.258544) (xy 411.004246 -302.216948) (xy 410.984955 -302.171672) (xy 410.973178 -302.123888)
			(xy 410.969218 -302.074834) (xy 410.630116 -302.074834) (xy 410.629621 -302.099441) (xy 410.621726 -302.148018)
			(xy 410.606142 -302.194699) (xy 410.583271 -302.238276) (xy 410.553706 -302.27762) (xy 410.518213 -302.311712)
			(xy 410.47771 -302.339668) (xy 410.433248 -302.360766) (xy 410.385977 -302.374458) (xy 410.337122 -302.38039)
			(xy 410.287947 -302.378409) (xy 410.239728 -302.368565) (xy 410.193712 -302.351113) (xy 410.151091 -302.326506)
			(xy 410.11297 -302.295381) (xy 410.080335 -302.258544) (xy 410.054032 -302.216948) (xy 410.034741 -302.171672)
			(xy 410.022964 -302.123888) (xy 410.019004 -302.074834) (xy 409.680156 -302.074834) (xy 409.679661 -302.099441)
			(xy 409.671766 -302.148018) (xy 409.656182 -302.194699) (xy 409.633311 -302.238276) (xy 409.603746 -302.27762)
			(xy 409.568253 -302.311712) (xy 409.52775 -302.339668) (xy 409.483288 -302.360766) (xy 409.436017 -302.374458)
			(xy 409.387162 -302.38039) (xy 409.337987 -302.378409) (xy 409.289768 -302.368565) (xy 409.243752 -302.351113)
			(xy 409.201131 -302.326506) (xy 409.16301 -302.295381) (xy 409.130375 -302.258544) (xy 409.104072 -302.216948)
			(xy 409.084781 -302.171672) (xy 409.073004 -302.123888) (xy 409.069044 -302.074834) (xy 408.730196 -302.074834)
			(xy 408.729701 -302.099441) (xy 408.721806 -302.148018) (xy 408.706222 -302.194699) (xy 408.683351 -302.238276)
			(xy 408.653786 -302.27762) (xy 408.618293 -302.311712) (xy 408.57779 -302.339668) (xy 408.533328 -302.360766)
			(xy 408.486057 -302.374458) (xy 408.437202 -302.38039) (xy 408.388027 -302.378409) (xy 408.339808 -302.368565)
			(xy 408.293792 -302.351113) (xy 408.251171 -302.326506) (xy 408.21305 -302.295381) (xy 408.180415 -302.258544)
			(xy 408.154112 -302.216948) (xy 408.134821 -302.171672) (xy 408.123044 -302.123888) (xy 408.119084 -302.074834)
			(xy 406.830276 -302.074834) (xy 406.829781 -302.099441) (xy 406.821886 -302.148018) (xy 406.806302 -302.194699)
			(xy 406.783431 -302.238276) (xy 406.753866 -302.27762) (xy 406.718373 -302.311712) (xy 406.67787 -302.339668)
			(xy 406.633408 -302.360766) (xy 406.586137 -302.374458) (xy 406.537282 -302.38039) (xy 406.488107 -302.378409)
			(xy 406.439888 -302.368565) (xy 406.393872 -302.351113) (xy 406.351251 -302.326506) (xy 406.31313 -302.295381)
			(xy 406.280495 -302.258544) (xy 406.254192 -302.216948) (xy 406.234901 -302.171672) (xy 406.223124 -302.123888)
			(xy 406.219164 -302.074834) (xy 405.880316 -302.074834) (xy 405.879821 -302.099441) (xy 405.871926 -302.148018)
			(xy 405.856342 -302.194699) (xy 405.833471 -302.238276) (xy 405.803906 -302.27762) (xy 405.768413 -302.311712)
			(xy 405.72791 -302.339668) (xy 405.683448 -302.360766) (xy 405.636177 -302.374458) (xy 405.587322 -302.38039)
			(xy 405.538147 -302.378409) (xy 405.489928 -302.368565) (xy 405.443912 -302.351113) (xy 405.401291 -302.326506)
			(xy 405.36317 -302.295381) (xy 405.330535 -302.258544) (xy 405.304232 -302.216948) (xy 405.284941 -302.171672)
			(xy 405.273164 -302.123888) (xy 405.269204 -302.074834) (xy 404.930102 -302.074834) (xy 404.929607 -302.099441)
			(xy 404.921712 -302.148018) (xy 404.906128 -302.194699) (xy 404.883257 -302.238276) (xy 404.853692 -302.27762)
			(xy 404.818199 -302.311712) (xy 404.777696 -302.339668) (xy 404.733234 -302.360766) (xy 404.685963 -302.374458)
			(xy 404.637108 -302.38039) (xy 404.587933 -302.378409) (xy 404.539714 -302.368565) (xy 404.493698 -302.351113)
			(xy 404.451077 -302.326506) (xy 404.412956 -302.295381) (xy 404.380321 -302.258544) (xy 404.354018 -302.216948)
			(xy 404.334727 -302.171672) (xy 404.32295 -302.123888) (xy 404.31899 -302.074834) (xy 403.980142 -302.074834)
			(xy 403.979647 -302.099441) (xy 403.971752 -302.148018) (xy 403.956168 -302.194699) (xy 403.933297 -302.238276)
			(xy 403.903732 -302.27762) (xy 403.868239 -302.311712) (xy 403.827736 -302.339668) (xy 403.783274 -302.360766)
			(xy 403.736003 -302.374458) (xy 403.687148 -302.38039) (xy 403.637973 -302.378409) (xy 403.589754 -302.368565)
			(xy 403.543738 -302.351113) (xy 403.501117 -302.326506) (xy 403.462996 -302.295381) (xy 403.430361 -302.258544)
			(xy 403.404058 -302.216948) (xy 403.384767 -302.171672) (xy 403.37299 -302.123888) (xy 403.36903 -302.074834)
			(xy 403.030182 -302.074834) (xy 403.029687 -302.099441) (xy 403.021792 -302.148018) (xy 403.006208 -302.194699)
			(xy 402.983337 -302.238276) (xy 402.953772 -302.27762) (xy 402.918279 -302.311712) (xy 402.877776 -302.339668)
			(xy 402.833314 -302.360766) (xy 402.786043 -302.374458) (xy 402.737188 -302.38039) (xy 402.688013 -302.378409)
			(xy 402.639794 -302.368565) (xy 402.593778 -302.351113) (xy 402.551157 -302.326506) (xy 402.513036 -302.295381)
			(xy 402.480401 -302.258544) (xy 402.454098 -302.216948) (xy 402.434807 -302.171672) (xy 402.42303 -302.123888)
			(xy 402.41907 -302.074834) (xy 402.080222 -302.074834) (xy 402.079727 -302.099441) (xy 402.071832 -302.148018)
			(xy 402.056248 -302.194699) (xy 402.033377 -302.238276) (xy 402.003812 -302.27762) (xy 401.968319 -302.311712)
			(xy 401.927816 -302.339668) (xy 401.883354 -302.360766) (xy 401.836083 -302.374458) (xy 401.787228 -302.38039)
			(xy 401.738053 -302.378409) (xy 401.689834 -302.368565) (xy 401.643818 -302.351113) (xy 401.601197 -302.326506)
			(xy 401.563076 -302.295381) (xy 401.530441 -302.258544) (xy 401.504138 -302.216948) (xy 401.484847 -302.171672)
			(xy 401.47307 -302.123888) (xy 401.46911 -302.074834) (xy 401.130262 -302.074834) (xy 401.129767 -302.099441)
			(xy 401.121872 -302.148018) (xy 401.106288 -302.194699) (xy 401.083417 -302.238276) (xy 401.053852 -302.27762)
			(xy 401.018359 -302.311712) (xy 400.977856 -302.339668) (xy 400.933394 -302.360766) (xy 400.886123 -302.374458)
			(xy 400.837268 -302.38039) (xy 400.788093 -302.378409) (xy 400.739874 -302.368565) (xy 400.693858 -302.351113)
			(xy 400.651237 -302.326506) (xy 400.613116 -302.295381) (xy 400.580481 -302.258544) (xy 400.554178 -302.216948)
			(xy 400.534887 -302.171672) (xy 400.52311 -302.123888) (xy 400.51915 -302.074834) (xy 400.180302 -302.074834)
			(xy 400.179807 -302.099441) (xy 400.171912 -302.148018) (xy 400.156328 -302.194699) (xy 400.133457 -302.238276)
			(xy 400.103892 -302.27762) (xy 400.068399 -302.311712) (xy 400.027896 -302.339668) (xy 399.983434 -302.360766)
			(xy 399.936163 -302.374458) (xy 399.887308 -302.38039) (xy 399.838133 -302.378409) (xy 399.789914 -302.368565)
			(xy 399.743898 -302.351113) (xy 399.701277 -302.326506) (xy 399.663156 -302.295381) (xy 399.630521 -302.258544)
			(xy 399.604218 -302.216948) (xy 399.584927 -302.171672) (xy 399.57315 -302.123888) (xy 399.56919 -302.074834)
			(xy 399.230342 -302.074834) (xy 399.229847 -302.099441) (xy 399.221952 -302.148018) (xy 399.206368 -302.194699)
			(xy 399.183497 -302.238276) (xy 399.153932 -302.27762) (xy 399.118439 -302.311712) (xy 399.077936 -302.339668)
			(xy 399.033474 -302.360766) (xy 398.986203 -302.374458) (xy 398.937348 -302.38039) (xy 398.888173 -302.378409)
			(xy 398.839954 -302.368565) (xy 398.793938 -302.351113) (xy 398.751317 -302.326506) (xy 398.713196 -302.295381)
			(xy 398.680561 -302.258544) (xy 398.654258 -302.216948) (xy 398.634967 -302.171672) (xy 398.62319 -302.123888)
			(xy 398.61923 -302.074834) (xy 398.280128 -302.074834) (xy 398.279633 -302.099441) (xy 398.271738 -302.148018)
			(xy 398.256154 -302.194699) (xy 398.233283 -302.238276) (xy 398.203718 -302.27762) (xy 398.168225 -302.311712)
			(xy 398.127722 -302.339668) (xy 398.08326 -302.360766) (xy 398.035989 -302.374458) (xy 397.987134 -302.38039)
			(xy 397.937959 -302.378409) (xy 397.88974 -302.368565) (xy 397.843724 -302.351113) (xy 397.801103 -302.326506)
			(xy 397.762982 -302.295381) (xy 397.730347 -302.258544) (xy 397.704044 -302.216948) (xy 397.684753 -302.171672)
			(xy 397.672976 -302.123888) (xy 397.669016 -302.074834) (xy 396.990824 -302.074834) (xy 396.990824 -302.62322)
			(xy 396.990999 -302.629372) (xy 396.993963 -302.641312) (xy 396.996666 -302.646842) (xy 397.004794 -302.658018)
			(xy 397.019526 -302.673512) (xy 397.02613 -302.680624) (xy 397.05026 -302.6918) (xy 397.054578 -302.69307)
			(xy 397.066008 -302.696626) (xy 397.070072 -302.697134) (xy 397.096117 -302.701242) (xy 397.146544 -302.716637)
			(xy 397.19389 -302.739837) (xy 397.236956 -302.770253) (xy 397.274651 -302.807117) (xy 397.306021 -302.849493)
			(xy 397.330272 -302.89631) (xy 397.346788 -302.94638) (xy 397.355152 -302.998437) (xy 397.355152 -303.024794)
			(xy 397.669016 -303.024794) (xy 397.672976 -302.97574) (xy 397.684753 -302.927956) (xy 397.704044 -302.88268)
			(xy 397.730347 -302.841084) (xy 397.762982 -302.804247) (xy 397.801103 -302.773122) (xy 397.843724 -302.748515)
			(xy 397.88974 -302.731063) (xy 397.937959 -302.721219) (xy 397.987134 -302.719238) (xy 398.035989 -302.72517)
			(xy 398.08326 -302.738862) (xy 398.127722 -302.75996) (xy 398.168225 -302.787916) (xy 398.203718 -302.822008)
			(xy 398.233283 -302.861352) (xy 398.256154 -302.904929) (xy 398.271738 -302.95161) (xy 398.279633 -303.000187)
			(xy 398.280128 -303.024794) (xy 416.668978 -303.024794) (xy 416.672938 -302.97574) (xy 416.684715 -302.927956)
			(xy 416.704006 -302.88268) (xy 416.730309 -302.841084) (xy 416.762944 -302.804247) (xy 416.801065 -302.773122)
			(xy 416.843686 -302.748515) (xy 416.889702 -302.731063) (xy 416.937921 -302.721219) (xy 416.987096 -302.719238)
			(xy 417.035951 -302.72517) (xy 417.083222 -302.738862) (xy 417.127684 -302.75996) (xy 417.168187 -302.787916)
			(xy 417.20368 -302.822008) (xy 417.233245 -302.861352) (xy 417.256116 -302.904929) (xy 417.2717 -302.95161)
			(xy 417.279595 -303.000187) (xy 417.28009 -303.024794) (xy 417.619192 -303.024794) (xy 417.623152 -302.97574)
			(xy 417.634929 -302.927956) (xy 417.65422 -302.88268) (xy 417.680523 -302.841084) (xy 417.713158 -302.804247)
			(xy 417.751279 -302.773122) (xy 417.7939 -302.748515) (xy 417.839916 -302.731063) (xy 417.888135 -302.721219)
			(xy 417.93731 -302.719238) (xy 417.986165 -302.72517) (xy 418.033436 -302.738862) (xy 418.077898 -302.75996)
			(xy 418.118401 -302.787916) (xy 418.153894 -302.822008) (xy 418.183459 -302.861352) (xy 418.20633 -302.904929)
			(xy 418.221914 -302.95161) (xy 418.229809 -303.000187) (xy 418.230304 -303.024794) (xy 418.569152 -303.024794)
			(xy 418.573112 -302.97574) (xy 418.584889 -302.927956) (xy 418.60418 -302.88268) (xy 418.630483 -302.841084)
			(xy 418.663118 -302.804247) (xy 418.701239 -302.773122) (xy 418.74386 -302.748515) (xy 418.789876 -302.731063)
			(xy 418.838095 -302.721219) (xy 418.88727 -302.719238) (xy 418.936125 -302.72517) (xy 418.983396 -302.738862)
			(xy 419.027858 -302.75996) (xy 419.068361 -302.787916) (xy 419.103854 -302.822008) (xy 419.133419 -302.861352)
			(xy 419.15629 -302.904929) (xy 419.171874 -302.95161) (xy 419.179769 -303.000187) (xy 419.180264 -303.024794)
			(xy 419.519112 -303.024794) (xy 419.523072 -302.97574) (xy 419.534849 -302.927956) (xy 419.55414 -302.88268)
			(xy 419.580443 -302.841084) (xy 419.613078 -302.804247) (xy 419.651199 -302.773122) (xy 419.69382 -302.748515)
			(xy 419.739836 -302.731063) (xy 419.788055 -302.721219) (xy 419.83723 -302.719238) (xy 419.886085 -302.72517)
			(xy 419.933356 -302.738862) (xy 419.977818 -302.75996) (xy 420.018321 -302.787916) (xy 420.053814 -302.822008)
			(xy 420.083379 -302.861352) (xy 420.10625 -302.904929) (xy 420.121834 -302.95161) (xy 420.129729 -303.000187)
			(xy 420.130224 -303.024794) (xy 420.469072 -303.024794) (xy 420.473032 -302.97574) (xy 420.484809 -302.927956)
			(xy 420.5041 -302.88268) (xy 420.530403 -302.841084) (xy 420.563038 -302.804247) (xy 420.601159 -302.773122)
			(xy 420.64378 -302.748515) (xy 420.689796 -302.731063) (xy 420.738015 -302.721219) (xy 420.78719 -302.719238)
			(xy 420.836045 -302.72517) (xy 420.883316 -302.738862) (xy 420.927778 -302.75996) (xy 420.968281 -302.787916)
			(xy 421.003774 -302.822008) (xy 421.033339 -302.861352) (xy 421.05621 -302.904929) (xy 421.071794 -302.95161)
			(xy 421.079689 -303.000187) (xy 421.080184 -303.024794) (xy 421.419032 -303.024794) (xy 421.422992 -302.97574)
			(xy 421.434769 -302.927956) (xy 421.45406 -302.88268) (xy 421.480363 -302.841084) (xy 421.512998 -302.804247)
			(xy 421.551119 -302.773122) (xy 421.59374 -302.748515) (xy 421.639756 -302.731063) (xy 421.687975 -302.721219)
			(xy 421.73715 -302.719238) (xy 421.786005 -302.72517) (xy 421.833276 -302.738862) (xy 421.877738 -302.75996)
			(xy 421.918241 -302.787916) (xy 421.953734 -302.822008) (xy 421.983299 -302.861352) (xy 422.00617 -302.904929)
			(xy 422.021754 -302.95161) (xy 422.029649 -303.000187) (xy 422.030144 -303.024794) (xy 422.029649 -303.049401)
			(xy 422.021754 -303.097978) (xy 422.00617 -303.144659) (xy 421.983299 -303.188236) (xy 421.953734 -303.22758)
			(xy 421.918241 -303.261672) (xy 421.877738 -303.289628) (xy 421.833276 -303.310726) (xy 421.786005 -303.324418)
			(xy 421.73715 -303.33035) (xy 421.687975 -303.328369) (xy 421.639756 -303.318525) (xy 421.59374 -303.301073)
			(xy 421.551119 -303.276466) (xy 421.512998 -303.245341) (xy 421.480363 -303.208504) (xy 421.45406 -303.166908)
			(xy 421.434769 -303.121632) (xy 421.422992 -303.073848) (xy 421.419032 -303.024794) (xy 421.080184 -303.024794)
			(xy 421.079689 -303.049401) (xy 421.071794 -303.097978) (xy 421.05621 -303.144659) (xy 421.033339 -303.188236)
			(xy 421.003774 -303.22758) (xy 420.968281 -303.261672) (xy 420.927778 -303.289628) (xy 420.883316 -303.310726)
			(xy 420.836045 -303.324418) (xy 420.78719 -303.33035) (xy 420.738015 -303.328369) (xy 420.689796 -303.318525)
			(xy 420.64378 -303.301073) (xy 420.601159 -303.276466) (xy 420.563038 -303.245341) (xy 420.530403 -303.208504)
			(xy 420.5041 -303.166908) (xy 420.484809 -303.121632) (xy 420.473032 -303.073848) (xy 420.469072 -303.024794)
			(xy 420.130224 -303.024794) (xy 420.129729 -303.049401) (xy 420.121834 -303.097978) (xy 420.10625 -303.144659)
			(xy 420.083379 -303.188236) (xy 420.053814 -303.22758) (xy 420.018321 -303.261672) (xy 419.977818 -303.289628)
			(xy 419.933356 -303.310726) (xy 419.886085 -303.324418) (xy 419.83723 -303.33035) (xy 419.788055 -303.328369)
			(xy 419.739836 -303.318525) (xy 419.69382 -303.301073) (xy 419.651199 -303.276466) (xy 419.613078 -303.245341)
			(xy 419.580443 -303.208504) (xy 419.55414 -303.166908) (xy 419.534849 -303.121632) (xy 419.523072 -303.073848)
			(xy 419.519112 -303.024794) (xy 419.180264 -303.024794) (xy 419.179769 -303.049401) (xy 419.171874 -303.097978)
			(xy 419.15629 -303.144659) (xy 419.133419 -303.188236) (xy 419.103854 -303.22758) (xy 419.068361 -303.261672)
			(xy 419.027858 -303.289628) (xy 418.983396 -303.310726) (xy 418.936125 -303.324418) (xy 418.88727 -303.33035)
			(xy 418.838095 -303.328369) (xy 418.789876 -303.318525) (xy 418.74386 -303.301073) (xy 418.701239 -303.276466)
			(xy 418.663118 -303.245341) (xy 418.630483 -303.208504) (xy 418.60418 -303.166908) (xy 418.584889 -303.121632)
			(xy 418.573112 -303.073848) (xy 418.569152 -303.024794) (xy 418.230304 -303.024794) (xy 418.229809 -303.049401)
			(xy 418.221914 -303.097978) (xy 418.20633 -303.144659) (xy 418.183459 -303.188236) (xy 418.153894 -303.22758)
			(xy 418.118401 -303.261672) (xy 418.077898 -303.289628) (xy 418.033436 -303.310726) (xy 417.986165 -303.324418)
			(xy 417.93731 -303.33035) (xy 417.888135 -303.328369) (xy 417.839916 -303.318525) (xy 417.7939 -303.301073)
			(xy 417.751279 -303.276466) (xy 417.713158 -303.245341) (xy 417.680523 -303.208504) (xy 417.65422 -303.166908)
			(xy 417.634929 -303.121632) (xy 417.623152 -303.073848) (xy 417.619192 -303.024794) (xy 417.28009 -303.024794)
			(xy 417.279595 -303.049401) (xy 417.2717 -303.097978) (xy 417.256116 -303.144659) (xy 417.233245 -303.188236)
			(xy 417.20368 -303.22758) (xy 417.168187 -303.261672) (xy 417.127684 -303.289628) (xy 417.083222 -303.310726)
			(xy 417.035951 -303.324418) (xy 416.987096 -303.33035) (xy 416.937921 -303.328369) (xy 416.889702 -303.318525)
			(xy 416.843686 -303.301073) (xy 416.801065 -303.276466) (xy 416.762944 -303.245341) (xy 416.730309 -303.208504)
			(xy 416.704006 -303.166908) (xy 416.684715 -303.121632) (xy 416.672938 -303.073848) (xy 416.668978 -303.024794)
			(xy 398.280128 -303.024794) (xy 398.279633 -303.049401) (xy 398.271738 -303.097978) (xy 398.256154 -303.144659)
			(xy 398.233283 -303.188236) (xy 398.203718 -303.22758) (xy 398.168225 -303.261672) (xy 398.127722 -303.289628)
			(xy 398.08326 -303.310726) (xy 398.035989 -303.324418) (xy 397.987134 -303.33035) (xy 397.937959 -303.328369)
			(xy 397.88974 -303.318525) (xy 397.843724 -303.301073) (xy 397.801103 -303.276466) (xy 397.762982 -303.245341)
			(xy 397.730347 -303.208504) (xy 397.704044 -303.166908) (xy 397.684753 -303.121632) (xy 397.672976 -303.073848)
			(xy 397.669016 -303.024794) (xy 397.355152 -303.024794) (xy 397.355153 -303.051161) (xy 397.346789 -303.103218)
			(xy 397.330272 -303.153289) (xy 397.306022 -303.200105) (xy 397.274652 -303.242482) (xy 397.236957 -303.279346)
			(xy 397.193891 -303.309763) (xy 397.146545 -303.332962) (xy 397.096119 -303.348358) (xy 397.070072 -303.352454)
			(xy 397.066008 -303.352962) (xy 397.054578 -303.356518) (xy 397.05026 -303.357788) (xy 397.02613 -303.368964)
			(xy 397.019526 -303.376076) (xy 397.004794 -303.39157) (xy 396.996666 -303.402746) (xy 396.993968 -303.408277)
			(xy 396.991007 -303.420217) (xy 396.990824 -303.426368) (xy 396.990824 -303.499774) (xy 422.844226 -303.499774)
			(xy 422.848186 -303.45072) (xy 422.859963 -303.402936) (xy 422.879254 -303.35766) (xy 422.905557 -303.316064)
			(xy 422.938192 -303.279227) (xy 422.976313 -303.248102) (xy 423.018934 -303.223495) (xy 423.06495 -303.206043)
			(xy 423.113169 -303.196199) (xy 423.162344 -303.194218) (xy 423.211199 -303.20015) (xy 423.25847 -303.213842)
			(xy 423.302932 -303.23494) (xy 423.343435 -303.262896) (xy 423.378928 -303.296988) (xy 423.408493 -303.336332)
			(xy 423.431364 -303.379909) (xy 423.446948 -303.42659) (xy 423.454843 -303.475167) (xy 423.455172 -303.491533)
			(xy 423.794255 -303.491533) (xy 423.79962 -303.442177) (xy 423.8129 -303.39434) (xy 423.833744 -303.349281)
			(xy 423.861603 -303.308188) (xy 423.895743 -303.272143) (xy 423.935265 -303.242097) (xy 423.979128 -303.21884)
			(xy 424.026175 -303.202986) (xy 424.075167 -303.194953) (xy 424.09999 -303.194466) (xy 424.114173 -303.194644)
			(xy 424.142413 -303.197315) (xy 424.156378 -303.1998) (xy 424.170345 -303.201961) (xy 424.198479 -303.199387)
			(xy 424.224829 -303.1892) (xy 424.247378 -303.17218) (xy 424.264398 -303.149632) (xy 424.274586 -303.123282)
			(xy 424.277161 -303.095148) (xy 424.274996 -303.081182) (xy 424.272521 -303.067216) (xy 424.269848 -303.038976)
			(xy 424.269662 -303.024794) (xy 424.270184 -302.999973) (xy 424.278217 -302.950986) (xy 424.294068 -302.903943)
			(xy 424.317322 -302.860085) (xy 424.347365 -302.820567) (xy 424.383406 -302.786429) (xy 424.424495 -302.758573)
			(xy 424.469549 -302.73773) (xy 424.517382 -302.724452) (xy 424.566732 -302.719087) (xy 424.616301 -302.721777)
			(xy 424.664781 -302.73245) (xy 424.710896 -302.750827) (xy 424.753431 -302.776422) (xy 424.791264 -302.808562)
			(xy 424.823399 -302.846399) (xy 424.848989 -302.888936) (xy 424.86736 -302.935053) (xy 424.878028 -302.983535)
			(xy 424.880262 -303.024794) (xy 425.219126 -303.024794) (xy 425.223086 -302.97574) (xy 425.234863 -302.927956)
			(xy 425.254154 -302.88268) (xy 425.280457 -302.841084) (xy 425.313092 -302.804247) (xy 425.351213 -302.773122)
			(xy 425.393834 -302.748515) (xy 425.43985 -302.731063) (xy 425.488069 -302.721219) (xy 425.537244 -302.719238)
			(xy 425.586099 -302.72517) (xy 425.63337 -302.738862) (xy 425.677832 -302.75996) (xy 425.718335 -302.787916)
			(xy 425.753828 -302.822008) (xy 425.783393 -302.861352) (xy 425.806264 -302.904929) (xy 425.821848 -302.95161)
			(xy 425.829743 -303.000187) (xy 425.830238 -303.024794) (xy 425.830071 -303.033077) (xy 426.169191 -303.033077)
			(xy 426.171879 -302.98351) (xy 426.182551 -302.935031) (xy 426.200925 -302.888917) (xy 426.226517 -302.846384)
			(xy 426.258653 -302.80855) (xy 426.296487 -302.776415) (xy 426.339021 -302.750823) (xy 426.385135 -302.73245)
			(xy 426.433614 -302.721779) (xy 426.483181 -302.719091) (xy 426.532529 -302.724458) (xy 426.580359 -302.737738)
			(xy 426.625411 -302.75858) (xy 426.666498 -302.786437) (xy 426.702536 -302.820574) (xy 426.732577 -302.860091)
			(xy 426.755829 -302.903948) (xy 426.77168 -302.950989) (xy 426.779712 -302.999974) (xy 426.780198 -303.024794)
			(xy 426.780021 -303.038977) (xy 426.777349 -303.067217) (xy 426.774864 -303.081182) (xy 426.772578 -303.093628)
			(xy 426.779944 -303.11725) (xy 426.857414 -303.19472) (xy 426.881036 -303.202086) (xy 426.893482 -303.1998)
			(xy 426.907447 -303.197316) (xy 426.935687 -303.194649) (xy 426.94987 -303.194466) (xy 426.964053 -303.194647)
			(xy 426.992293 -303.197316) (xy 427.006258 -303.1998) (xy 427.018704 -303.202086) (xy 427.042326 -303.19472)
			(xy 427.119796 -303.11725) (xy 427.127162 -303.093628) (xy 427.124876 -303.081182) (xy 427.122401 -303.067216)
			(xy 427.119728 -303.038976) (xy 427.119542 -303.024794) (xy 427.119984 -302.999975) (xy 427.128016 -302.95099)
			(xy 427.143866 -302.90395) (xy 427.167117 -302.860093) (xy 427.197157 -302.820576) (xy 427.233194 -302.786439)
			(xy 427.274279 -302.758581) (xy 427.319329 -302.737737) (xy 427.367158 -302.724456) (xy 427.416506 -302.719087)
			(xy 427.466072 -302.721773) (xy 427.514551 -302.732441) (xy 427.560665 -302.750812) (xy 427.6032 -302.776401)
			(xy 427.641035 -302.808533) (xy 427.673174 -302.846364) (xy 427.698769 -302.888895) (xy 427.717146 -302.935007)
			(xy 427.727821 -302.983484) (xy 427.730065 -303.024794) (xy 428.069006 -303.024794) (xy 428.072966 -302.97574)
			(xy 428.084743 -302.927956) (xy 428.104034 -302.88268) (xy 428.130337 -302.841084) (xy 428.162972 -302.804247)
			(xy 428.201093 -302.773122) (xy 428.243714 -302.748515) (xy 428.28973 -302.731063) (xy 428.337949 -302.721219)
			(xy 428.387124 -302.719238) (xy 428.435979 -302.72517) (xy 428.48325 -302.738862) (xy 428.527712 -302.75996)
			(xy 428.568215 -302.787916) (xy 428.603708 -302.822008) (xy 428.633273 -302.861352) (xy 428.656144 -302.904929)
			(xy 428.671728 -302.95161) (xy 428.679623 -303.000187) (xy 428.680118 -303.024794) (xy 429.01922 -303.024794)
			(xy 429.02318 -302.97574) (xy 429.034957 -302.927956) (xy 429.054248 -302.88268) (xy 429.080551 -302.841084)
			(xy 429.113186 -302.804247) (xy 429.151307 -302.773122) (xy 429.193928 -302.748515) (xy 429.239944 -302.731063)
			(xy 429.288163 -302.721219) (xy 429.337338 -302.719238) (xy 429.386193 -302.72517) (xy 429.433464 -302.738862)
			(xy 429.477926 -302.75996) (xy 429.518429 -302.787916) (xy 429.553922 -302.822008) (xy 429.583487 -302.861352)
			(xy 429.606358 -302.904929) (xy 429.621942 -302.95161) (xy 429.629837 -303.000187) (xy 429.630332 -303.024794)
			(xy 429.96918 -303.024794) (xy 429.97314 -302.97574) (xy 429.984917 -302.927956) (xy 430.004208 -302.88268)
			(xy 430.030511 -302.841084) (xy 430.063146 -302.804247) (xy 430.101267 -302.773122) (xy 430.143888 -302.748515)
			(xy 430.189904 -302.731063) (xy 430.238123 -302.721219) (xy 430.287298 -302.719238) (xy 430.336153 -302.72517)
			(xy 430.383424 -302.738862) (xy 430.427886 -302.75996) (xy 430.468389 -302.787916) (xy 430.503882 -302.822008)
			(xy 430.533447 -302.861352) (xy 430.556318 -302.904929) (xy 430.571902 -302.95161) (xy 430.579797 -303.000187)
			(xy 430.580292 -303.024794) (xy 430.9039 -303.024794) (xy 430.90786 -302.97574) (xy 430.919637 -302.927956)
			(xy 430.938928 -302.88268) (xy 430.965231 -302.841084) (xy 430.997866 -302.804247) (xy 431.035987 -302.773122)
			(xy 431.078608 -302.748515) (xy 431.124624 -302.731063) (xy 431.172843 -302.721219) (xy 431.222018 -302.719238)
			(xy 431.270873 -302.72517) (xy 431.318144 -302.738862) (xy 431.362606 -302.75996) (xy 431.403109 -302.787916)
			(xy 431.438602 -302.822008) (xy 431.468167 -302.861352) (xy 431.491038 -302.904929) (xy 431.506622 -302.95161)
			(xy 431.514517 -303.000187) (xy 431.515012 -303.024794) (xy 431.514517 -303.049401) (xy 431.506622 -303.097978)
			(xy 431.491038 -303.144659) (xy 431.468167 -303.188236) (xy 431.438602 -303.22758) (xy 431.428387 -303.237392)
			(xy 434.411374 -303.237392) (xy 434.41186 -303.210141) (xy 434.419616 -303.156193) (xy 434.434971 -303.103898)
			(xy 434.457613 -303.054321) (xy 434.487079 -303.008471) (xy 434.52277 -302.96728) (xy 434.563961 -302.931589)
			(xy 434.609811 -302.902123) (xy 434.659388 -302.879481) (xy 434.711683 -302.864126) (xy 434.765631 -302.85637)
			(xy 434.820133 -302.85637) (xy 434.874081 -302.864126) (xy 434.926376 -302.879481) (xy 434.975953 -302.902123)
			(xy 435.021803 -302.931589) (xy 435.062994 -302.96728) (xy 435.098685 -303.008471) (xy 435.110481 -303.026826)
			(xy 436.919622 -303.026826) (xy 436.923693 -302.971204) (xy 436.935819 -302.916767) (xy 436.955742 -302.864676)
			(xy 436.983038 -302.816041) (xy 437.017124 -302.771898) (xy 437.057273 -302.733189) (xy 437.102631 -302.700738)
			(xy 437.152231 -302.675237) (xy 437.205015 -302.65723) (xy 437.259858 -302.6471) (xy 437.315592 -302.645063)
			(xy 437.371029 -302.651163) (xy 437.424986 -302.665269) (xy 437.476315 -302.687081) (xy 437.523921 -302.716135)
			(xy 437.566789 -302.75181) (xy 437.604006 -302.793347) (xy 437.634779 -302.83986) (xy 437.658451 -302.890357)
			(xy 437.674519 -302.943764) (xy 437.682639 -302.99894) (xy 437.683148 -303.026826) (xy 437.935622 -303.026826)
			(xy 437.939693 -302.971204) (xy 437.951819 -302.916767) (xy 437.971742 -302.864676) (xy 437.999038 -302.816041)
			(xy 438.033124 -302.771898) (xy 438.073273 -302.733189) (xy 438.118631 -302.700738) (xy 438.168231 -302.675237)
			(xy 438.221015 -302.65723) (xy 438.275858 -302.6471) (xy 438.331592 -302.645063) (xy 438.387029 -302.651163)
			(xy 438.440986 -302.665269) (xy 438.492315 -302.687081) (xy 438.539921 -302.716135) (xy 438.582789 -302.75181)
			(xy 438.620006 -302.793347) (xy 438.650779 -302.83986) (xy 438.674451 -302.890357) (xy 438.690519 -302.943764)
			(xy 438.698639 -302.99894) (xy 438.699148 -303.026826) (xy 438.951622 -303.026826) (xy 438.955693 -302.971204)
			(xy 438.967819 -302.916767) (xy 438.987742 -302.864676) (xy 439.015038 -302.816041) (xy 439.049124 -302.771898)
			(xy 439.089273 -302.733189) (xy 439.134631 -302.700738) (xy 439.184231 -302.675237) (xy 439.237015 -302.65723)
			(xy 439.291858 -302.6471) (xy 439.347592 -302.645063) (xy 439.403029 -302.651163) (xy 439.456986 -302.665269)
			(xy 439.508315 -302.687081) (xy 439.555921 -302.716135) (xy 439.598789 -302.75181) (xy 439.636006 -302.793347)
			(xy 439.666779 -302.83986) (xy 439.690451 -302.890357) (xy 439.706519 -302.943764) (xy 439.714639 -302.99894)
			(xy 439.715148 -303.026826) (xy 439.967622 -303.026826) (xy 439.971693 -302.971204) (xy 439.983819 -302.916767)
			(xy 440.003742 -302.864676) (xy 440.031038 -302.816041) (xy 440.065124 -302.771898) (xy 440.105273 -302.733189)
			(xy 440.150631 -302.700738) (xy 440.200231 -302.675237) (xy 440.253015 -302.65723) (xy 440.307858 -302.6471)
			(xy 440.363592 -302.645063) (xy 440.419029 -302.651163) (xy 440.472986 -302.665269) (xy 440.524315 -302.687081)
			(xy 440.571921 -302.716135) (xy 440.614789 -302.75181) (xy 440.652006 -302.793347) (xy 440.682779 -302.83986)
			(xy 440.706451 -302.890357) (xy 440.722519 -302.943764) (xy 440.730639 -302.99894) (xy 440.731148 -303.026826)
			(xy 440.983622 -303.026826) (xy 440.987693 -302.971204) (xy 440.999819 -302.916767) (xy 441.019742 -302.864676)
			(xy 441.047038 -302.816041) (xy 441.081124 -302.771898) (xy 441.121273 -302.733189) (xy 441.166631 -302.700738)
			(xy 441.216231 -302.675237) (xy 441.269015 -302.65723) (xy 441.323858 -302.6471) (xy 441.379592 -302.645063)
			(xy 441.435029 -302.651163) (xy 441.488986 -302.665269) (xy 441.540315 -302.687081) (xy 441.587921 -302.716135)
			(xy 441.630789 -302.75181) (xy 441.668006 -302.793347) (xy 441.698779 -302.83986) (xy 441.722451 -302.890357)
			(xy 441.738519 -302.943764) (xy 441.746639 -302.99894) (xy 441.747148 -303.026826) (xy 441.746639 -303.054712)
			(xy 441.738519 -303.109888) (xy 441.722451 -303.163295) (xy 441.698779 -303.213792) (xy 441.668006 -303.260305)
			(xy 441.630789 -303.301842) (xy 441.587921 -303.337517) (xy 441.540315 -303.366571) (xy 441.488986 -303.388383)
			(xy 441.435029 -303.402489) (xy 441.379592 -303.408589) (xy 441.323858 -303.406552) (xy 441.269015 -303.396422)
			(xy 441.216231 -303.378415) (xy 441.166631 -303.352914) (xy 441.121273 -303.320463) (xy 441.081124 -303.281754)
			(xy 441.047038 -303.237611) (xy 441.019742 -303.188976) (xy 440.999819 -303.136885) (xy 440.987693 -303.082448)
			(xy 440.983622 -303.026826) (xy 440.731148 -303.026826) (xy 440.730639 -303.054712) (xy 440.722519 -303.109888)
			(xy 440.706451 -303.163295) (xy 440.682779 -303.213792) (xy 440.652006 -303.260305) (xy 440.614789 -303.301842)
			(xy 440.571921 -303.337517) (xy 440.524315 -303.366571) (xy 440.472986 -303.388383) (xy 440.419029 -303.402489)
			(xy 440.363592 -303.408589) (xy 440.307858 -303.406552) (xy 440.253015 -303.396422) (xy 440.200231 -303.378415)
			(xy 440.150631 -303.352914) (xy 440.105273 -303.320463) (xy 440.065124 -303.281754) (xy 440.031038 -303.237611)
			(xy 440.003742 -303.188976) (xy 439.983819 -303.136885) (xy 439.971693 -303.082448) (xy 439.967622 -303.026826)
			(xy 439.715148 -303.026826) (xy 439.714639 -303.054712) (xy 439.706519 -303.109888) (xy 439.690451 -303.163295)
			(xy 439.666779 -303.213792) (xy 439.636006 -303.260305) (xy 439.598789 -303.301842) (xy 439.555921 -303.337517)
			(xy 439.508315 -303.366571) (xy 439.456986 -303.388383) (xy 439.403029 -303.402489) (xy 439.347592 -303.408589)
			(xy 439.291858 -303.406552) (xy 439.237015 -303.396422) (xy 439.184231 -303.378415) (xy 439.134631 -303.352914)
			(xy 439.089273 -303.320463) (xy 439.049124 -303.281754) (xy 439.015038 -303.237611) (xy 438.987742 -303.188976)
			(xy 438.967819 -303.136885) (xy 438.955693 -303.082448) (xy 438.951622 -303.026826) (xy 438.699148 -303.026826)
			(xy 438.698639 -303.054712) (xy 438.690519 -303.109888) (xy 438.674451 -303.163295) (xy 438.650779 -303.213792)
			(xy 438.620006 -303.260305) (xy 438.582789 -303.301842) (xy 438.539921 -303.337517) (xy 438.492315 -303.366571)
			(xy 438.440986 -303.388383) (xy 438.387029 -303.402489) (xy 438.331592 -303.408589) (xy 438.275858 -303.406552)
			(xy 438.221015 -303.396422) (xy 438.168231 -303.378415) (xy 438.118631 -303.352914) (xy 438.073273 -303.320463)
			(xy 438.033124 -303.281754) (xy 437.999038 -303.237611) (xy 437.971742 -303.188976) (xy 437.951819 -303.136885)
			(xy 437.939693 -303.082448) (xy 437.935622 -303.026826) (xy 437.683148 -303.026826) (xy 437.682639 -303.054712)
			(xy 437.674519 -303.109888) (xy 437.658451 -303.163295) (xy 437.634779 -303.213792) (xy 437.604006 -303.260305)
			(xy 437.566789 -303.301842) (xy 437.523921 -303.337517) (xy 437.476315 -303.366571) (xy 437.424986 -303.388383)
			(xy 437.371029 -303.402489) (xy 437.315592 -303.408589) (xy 437.259858 -303.406552) (xy 437.205015 -303.396422)
			(xy 437.152231 -303.378415) (xy 437.102631 -303.352914) (xy 437.057273 -303.320463) (xy 437.017124 -303.281754)
			(xy 436.983038 -303.237611) (xy 436.955742 -303.188976) (xy 436.935819 -303.136885) (xy 436.923693 -303.082448)
			(xy 436.919622 -303.026826) (xy 435.110481 -303.026826) (xy 435.128151 -303.054321) (xy 435.150793 -303.103898)
			(xy 435.166148 -303.156193) (xy 435.173904 -303.210141) (xy 435.17439 -303.237392) (xy 435.173917 -303.265054)
			(xy 435.165948 -303.3198) (xy 435.150161 -303.372823) (xy 435.126886 -303.423013) (xy 435.11216 -303.446434)
			(xy 435.106064 -303.455578) (xy 435.102762 -303.477168) (xy 435.128924 -303.57191) (xy 435.14264 -303.58842)
			(xy 435.152546 -303.593246) (xy 435.176365 -303.605269) (xy 435.220622 -303.635074) (xy 435.260295 -303.670753)
			(xy 435.294611 -303.711612) (xy 435.3229 -303.756852) (xy 435.34461 -303.805593) (xy 435.359318 -303.856883)
			(xy 435.366738 -303.909721) (xy 435.367176 -303.9364) (xy 435.36669 -303.963651) (xy 435.358934 -304.017599)
			(xy 435.343579 -304.069894) (xy 435.320937 -304.119471) (xy 435.291471 -304.165321) (xy 435.25578 -304.206512)
			(xy 435.214589 -304.242203) (xy 435.168739 -304.271669) (xy 435.119162 -304.294311) (xy 435.066867 -304.309666)
			(xy 435.012919 -304.317422) (xy 434.958417 -304.317422) (xy 434.904469 -304.309666) (xy 434.852174 -304.294311)
			(xy 434.802597 -304.271669) (xy 434.756747 -304.242203) (xy 434.715556 -304.206512) (xy 434.679865 -304.165321)
			(xy 434.650399 -304.119471) (xy 434.627757 -304.069894) (xy 434.612402 -304.017599) (xy 434.604646 -303.963651)
			(xy 434.60416 -303.9364) (xy 434.604621 -303.908738) (xy 434.612592 -303.85399) (xy 434.628383 -303.800967)
			(xy 434.651662 -303.750779) (xy 434.66639 -303.727358) (xy 434.672486 -303.718214) (xy 434.675788 -303.696624)
			(xy 434.649626 -303.601882) (xy 434.63591 -303.585372) (xy 434.626004 -303.580546) (xy 434.602193 -303.568507)
			(xy 434.557934 -303.538707) (xy 434.518259 -303.503031) (xy 434.483941 -303.462175) (xy 434.455651 -303.416936)
			(xy 434.43394 -303.368197) (xy 434.419231 -303.316908) (xy 434.411812 -303.26407) (xy 434.411374 -303.237392)
			(xy 431.428387 -303.237392) (xy 431.403109 -303.261672) (xy 431.362606 -303.289628) (xy 431.318144 -303.310726)
			(xy 431.270873 -303.324418) (xy 431.222018 -303.33035) (xy 431.172843 -303.328369) (xy 431.124624 -303.318525)
			(xy 431.078608 -303.301073) (xy 431.035987 -303.276466) (xy 430.997866 -303.245341) (xy 430.965231 -303.208504)
			(xy 430.938928 -303.166908) (xy 430.919637 -303.121632) (xy 430.90786 -303.073848) (xy 430.9039 -303.024794)
			(xy 430.580292 -303.024794) (xy 430.579797 -303.049401) (xy 430.571902 -303.097978) (xy 430.556318 -303.144659)
			(xy 430.533447 -303.188236) (xy 430.503882 -303.22758) (xy 430.468389 -303.261672) (xy 430.427886 -303.289628)
			(xy 430.383424 -303.310726) (xy 430.336153 -303.324418) (xy 430.287298 -303.33035) (xy 430.238123 -303.328369)
			(xy 430.189904 -303.318525) (xy 430.143888 -303.301073) (xy 430.101267 -303.276466) (xy 430.063146 -303.245341)
			(xy 430.030511 -303.208504) (xy 430.004208 -303.166908) (xy 429.984917 -303.121632) (xy 429.97314 -303.073848)
			(xy 429.96918 -303.024794) (xy 429.630332 -303.024794) (xy 429.629837 -303.049401) (xy 429.621942 -303.097978)
			(xy 429.606358 -303.144659) (xy 429.583487 -303.188236) (xy 429.553922 -303.22758) (xy 429.518429 -303.261672)
			(xy 429.477926 -303.289628) (xy 429.433464 -303.310726) (xy 429.386193 -303.324418) (xy 429.337338 -303.33035)
			(xy 429.288163 -303.328369) (xy 429.239944 -303.318525) (xy 429.193928 -303.301073) (xy 429.151307 -303.276466)
			(xy 429.113186 -303.245341) (xy 429.080551 -303.208504) (xy 429.054248 -303.166908) (xy 429.034957 -303.121632)
			(xy 429.02318 -303.073848) (xy 429.01922 -303.024794) (xy 428.680118 -303.024794) (xy 428.679623 -303.049401)
			(xy 428.671728 -303.097978) (xy 428.656144 -303.144659) (xy 428.633273 -303.188236) (xy 428.603708 -303.22758)
			(xy 428.568215 -303.261672) (xy 428.527712 -303.289628) (xy 428.48325 -303.310726) (xy 428.435979 -303.324418)
			(xy 428.387124 -303.33035) (xy 428.337949 -303.328369) (xy 428.28973 -303.318525) (xy 428.243714 -303.301073)
			(xy 428.201093 -303.276466) (xy 428.162972 -303.245341) (xy 428.130337 -303.208504) (xy 428.104034 -303.166908)
			(xy 428.084743 -303.121632) (xy 428.072966 -303.073848) (xy 428.069006 -303.024794) (xy 427.730065 -303.024794)
			(xy 427.730514 -303.03305) (xy 427.725152 -303.082398) (xy 427.711878 -303.130229) (xy 427.69104 -303.175283)
			(xy 427.663189 -303.216372) (xy 427.629057 -303.252414) (xy 427.589544 -303.282459) (xy 427.545691 -303.305717)
			(xy 427.498653 -303.321574) (xy 427.449669 -303.329612) (xy 427.42485 -303.330102) (xy 427.410667 -303.329919)
			(xy 427.382427 -303.327251) (xy 427.368462 -303.324768) (xy 427.356016 -303.322482) (xy 427.332394 -303.329848)
			(xy 427.254924 -303.407318) (xy 427.247558 -303.43094) (xy 427.249844 -303.443386) (xy 427.252314 -303.457353)
			(xy 427.25499 -303.485592) (xy 427.255178 -303.499774) (xy 427.254656 -303.525029) (xy 427.246343 -303.574851)
			(xy 427.229942 -303.622625) (xy 427.205901 -303.667048) (xy 427.174877 -303.706908) (xy 427.137715 -303.741118)
			(xy 427.095429 -303.768744) (xy 427.049173 -303.789034) (xy 427.000208 -303.801434) (xy 426.94987 -303.805605)
			(xy 426.899532 -303.801434) (xy 426.850567 -303.789034) (xy 426.804311 -303.768744) (xy 426.762025 -303.741118)
			(xy 426.724863 -303.706908) (xy 426.693839 -303.667048) (xy 426.669798 -303.622625) (xy 426.653397 -303.574851)
			(xy 426.645084 -303.525029) (xy 426.644562 -303.499774) (xy 426.644736 -303.485591) (xy 426.64741 -303.457351)
			(xy 426.649896 -303.443386) (xy 426.652182 -303.43094) (xy 426.644816 -303.407318) (xy 426.567346 -303.329848)
			(xy 426.543724 -303.322482) (xy 426.531278 -303.324768) (xy 426.517312 -303.327243) (xy 426.489072 -303.329916)
			(xy 426.47489 -303.330102) (xy 426.45007 -303.329611) (xy 426.401085 -303.321579) (xy 426.354044 -303.305728)
			(xy 426.310188 -303.282475) (xy 426.270671 -303.252433) (xy 426.236535 -303.216394) (xy 426.208678 -303.175308)
			(xy 426.187836 -303.130256) (xy 426.174557 -303.082425) (xy 426.169191 -303.033077) (xy 425.830071 -303.033077)
			(xy 425.829743 -303.049401) (xy 425.821848 -303.097978) (xy 425.806264 -303.144659) (xy 425.783393 -303.188236)
			(xy 425.753828 -303.22758) (xy 425.718335 -303.261672) (xy 425.677832 -303.289628) (xy 425.63337 -303.310726)
			(xy 425.586099 -303.324418) (xy 425.537244 -303.33035) (xy 425.488069 -303.328369) (xy 425.43985 -303.318525)
			(xy 425.393834 -303.301073) (xy 425.351213 -303.276466) (xy 425.313092 -303.245341) (xy 425.280457 -303.208504)
			(xy 425.254154 -303.166908) (xy 425.234863 -303.121632) (xy 425.223086 -303.073848) (xy 425.219126 -303.024794)
			(xy 424.880262 -303.024794) (xy 424.880712 -303.033104) (xy 424.875341 -303.082454) (xy 424.862057 -303.130285)
			(xy 424.84121 -303.175337) (xy 424.813348 -303.216422) (xy 424.779207 -303.252459) (xy 424.739685 -303.282497)
			(xy 424.695824 -303.305746) (xy 424.648779 -303.321592) (xy 424.599791 -303.329619) (xy 424.57497 -303.330102)
			(xy 424.560787 -303.32993) (xy 424.532547 -303.327255) (xy 424.518582 -303.324768) (xy 424.504617 -303.322603)
			(xy 424.476487 -303.325186) (xy 424.450141 -303.335378) (xy 424.427596 -303.352398) (xy 424.410576 -303.374944)
			(xy 424.400386 -303.40129) (xy 424.397803 -303.42942) (xy 424.399964 -303.443386) (xy 424.402434 -303.457353)
			(xy 424.40511 -303.485592) (xy 424.405298 -303.499774) (xy 424.40485 -303.524597) (xy 424.396822 -303.57359)
			(xy 424.380974 -303.620639) (xy 424.357723 -303.664504) (xy 424.327681 -303.70403) (xy 424.29164 -303.738175)
			(xy 424.250551 -303.766039) (xy 424.205494 -303.786888) (xy 424.157658 -303.800173) (xy 424.108303 -303.805544)
			(xy 424.058729 -303.80286) (xy 424.010243 -303.79219) (xy 423.964121 -303.773817) (xy 423.92158 -303.748224)
			(xy 423.883739 -303.716086) (xy 423.851597 -303.67825) (xy 423.825999 -303.635711) (xy 423.80762 -303.589592)
			(xy 423.796945 -303.541106) (xy 423.794255 -303.491533) (xy 423.455172 -303.491533) (xy 423.455338 -303.499774)
			(xy 423.454843 -303.524381) (xy 423.446948 -303.572958) (xy 423.431364 -303.619639) (xy 423.408493 -303.663216)
			(xy 423.378928 -303.70256) (xy 423.343435 -303.736652) (xy 423.302932 -303.764608) (xy 423.25847 -303.785706)
			(xy 423.211199 -303.799398) (xy 423.162344 -303.80533) (xy 423.113169 -303.803349) (xy 423.06495 -303.793505)
			(xy 423.018934 -303.776053) (xy 422.976313 -303.751446) (xy 422.938192 -303.720321) (xy 422.905557 -303.683484)
			(xy 422.879254 -303.641888) (xy 422.859963 -303.596612) (xy 422.848186 -303.548828) (xy 422.844226 -303.499774)
			(xy 396.990824 -303.499774) (xy 396.990824 -303.57318) (xy 396.990995 -303.579333) (xy 396.99395 -303.591278)
			(xy 396.996666 -303.596802) (xy 397.004794 -303.607978) (xy 397.019526 -303.623472) (xy 397.02613 -303.630584)
			(xy 397.05026 -303.64176) (xy 397.054578 -303.64303) (xy 397.066008 -303.646586) (xy 397.070072 -303.647094)
			(xy 397.09612 -303.651202) (xy 397.146553 -303.666598) (xy 397.193905 -303.6898) (xy 397.236977 -303.720219)
			(xy 397.274678 -303.757087) (xy 397.306052 -303.799468) (xy 397.330306 -303.846289) (xy 397.346825 -303.896366)
			(xy 397.355192 -303.948428) (xy 397.355192 -303.974754) (xy 397.669016 -303.974754) (xy 397.672976 -303.9257)
			(xy 397.684753 -303.877916) (xy 397.704044 -303.83264) (xy 397.730347 -303.791044) (xy 397.762982 -303.754207)
			(xy 397.801103 -303.723082) (xy 397.843724 -303.698475) (xy 397.88974 -303.681023) (xy 397.937959 -303.671179)
			(xy 397.987134 -303.669198) (xy 398.035989 -303.67513) (xy 398.08326 -303.688822) (xy 398.127722 -303.70992)
			(xy 398.168225 -303.737876) (xy 398.203718 -303.771968) (xy 398.233283 -303.811312) (xy 398.256154 -303.854889)
			(xy 398.271738 -303.90157) (xy 398.279633 -303.950147) (xy 398.280128 -303.974754) (xy 398.61923 -303.974754)
			(xy 398.62319 -303.9257) (xy 398.634967 -303.877916) (xy 398.654258 -303.83264) (xy 398.680561 -303.791044)
			(xy 398.713196 -303.754207) (xy 398.751317 -303.723082) (xy 398.793938 -303.698475) (xy 398.839954 -303.681023)
			(xy 398.888173 -303.671179) (xy 398.937348 -303.669198) (xy 398.986203 -303.67513) (xy 399.033474 -303.688822)
			(xy 399.077936 -303.70992) (xy 399.118439 -303.737876) (xy 399.153932 -303.771968) (xy 399.183497 -303.811312)
			(xy 399.206368 -303.854889) (xy 399.221952 -303.90157) (xy 399.229847 -303.950147) (xy 399.230342 -303.974754)
			(xy 399.56919 -303.974754) (xy 399.57315 -303.9257) (xy 399.584927 -303.877916) (xy 399.604218 -303.83264)
			(xy 399.630521 -303.791044) (xy 399.663156 -303.754207) (xy 399.701277 -303.723082) (xy 399.743898 -303.698475)
			(xy 399.789914 -303.681023) (xy 399.838133 -303.671179) (xy 399.887308 -303.669198) (xy 399.936163 -303.67513)
			(xy 399.983434 -303.688822) (xy 400.027896 -303.70992) (xy 400.068399 -303.737876) (xy 400.103892 -303.771968)
			(xy 400.133457 -303.811312) (xy 400.156328 -303.854889) (xy 400.171912 -303.90157) (xy 400.179807 -303.950147)
			(xy 400.180302 -303.974754) (xy 400.51915 -303.974754) (xy 400.52311 -303.9257) (xy 400.534887 -303.877916)
			(xy 400.554178 -303.83264) (xy 400.580481 -303.791044) (xy 400.613116 -303.754207) (xy 400.651237 -303.723082)
			(xy 400.693858 -303.698475) (xy 400.739874 -303.681023) (xy 400.788093 -303.671179) (xy 400.837268 -303.669198)
			(xy 400.886123 -303.67513) (xy 400.933394 -303.688822) (xy 400.977856 -303.70992) (xy 401.018359 -303.737876)
			(xy 401.053852 -303.771968) (xy 401.083417 -303.811312) (xy 401.106288 -303.854889) (xy 401.121872 -303.90157)
			(xy 401.129767 -303.950147) (xy 401.130262 -303.974754) (xy 401.46911 -303.974754) (xy 401.47307 -303.9257)
			(xy 401.484847 -303.877916) (xy 401.504138 -303.83264) (xy 401.530441 -303.791044) (xy 401.563076 -303.754207)
			(xy 401.601197 -303.723082) (xy 401.643818 -303.698475) (xy 401.689834 -303.681023) (xy 401.738053 -303.671179)
			(xy 401.787228 -303.669198) (xy 401.836083 -303.67513) (xy 401.883354 -303.688822) (xy 401.927816 -303.70992)
			(xy 401.968319 -303.737876) (xy 402.003812 -303.771968) (xy 402.033377 -303.811312) (xy 402.056248 -303.854889)
			(xy 402.071832 -303.90157) (xy 402.079727 -303.950147) (xy 402.080222 -303.974754) (xy 402.41907 -303.974754)
			(xy 402.42303 -303.9257) (xy 402.434807 -303.877916) (xy 402.454098 -303.83264) (xy 402.480401 -303.791044)
			(xy 402.513036 -303.754207) (xy 402.551157 -303.723082) (xy 402.593778 -303.698475) (xy 402.639794 -303.681023)
			(xy 402.688013 -303.671179) (xy 402.737188 -303.669198) (xy 402.786043 -303.67513) (xy 402.833314 -303.688822)
			(xy 402.877776 -303.70992) (xy 402.918279 -303.737876) (xy 402.953772 -303.771968) (xy 402.983337 -303.811312)
			(xy 403.006208 -303.854889) (xy 403.021792 -303.90157) (xy 403.029687 -303.950147) (xy 403.030182 -303.974754)
			(xy 403.36903 -303.974754) (xy 403.37299 -303.9257) (xy 403.384767 -303.877916) (xy 403.404058 -303.83264)
			(xy 403.430361 -303.791044) (xy 403.462996 -303.754207) (xy 403.501117 -303.723082) (xy 403.543738 -303.698475)
			(xy 403.589754 -303.681023) (xy 403.637973 -303.671179) (xy 403.687148 -303.669198) (xy 403.736003 -303.67513)
			(xy 403.783274 -303.688822) (xy 403.827736 -303.70992) (xy 403.868239 -303.737876) (xy 403.903732 -303.771968)
			(xy 403.933297 -303.811312) (xy 403.956168 -303.854889) (xy 403.971752 -303.90157) (xy 403.979647 -303.950147)
			(xy 403.980142 -303.974754) (xy 404.31899 -303.974754) (xy 404.32295 -303.9257) (xy 404.334727 -303.877916)
			(xy 404.354018 -303.83264) (xy 404.380321 -303.791044) (xy 404.412956 -303.754207) (xy 404.451077 -303.723082)
			(xy 404.493698 -303.698475) (xy 404.539714 -303.681023) (xy 404.587933 -303.671179) (xy 404.637108 -303.669198)
			(xy 404.685963 -303.67513) (xy 404.733234 -303.688822) (xy 404.777696 -303.70992) (xy 404.818199 -303.737876)
			(xy 404.853692 -303.771968) (xy 404.883257 -303.811312) (xy 404.906128 -303.854889) (xy 404.921712 -303.90157)
			(xy 404.929607 -303.950147) (xy 404.930102 -303.974754) (xy 405.269204 -303.974754) (xy 405.273164 -303.9257)
			(xy 405.284941 -303.877916) (xy 405.304232 -303.83264) (xy 405.330535 -303.791044) (xy 405.36317 -303.754207)
			(xy 405.401291 -303.723082) (xy 405.443912 -303.698475) (xy 405.489928 -303.681023) (xy 405.538147 -303.671179)
			(xy 405.587322 -303.669198) (xy 405.636177 -303.67513) (xy 405.683448 -303.688822) (xy 405.72791 -303.70992)
			(xy 405.768413 -303.737876) (xy 405.803906 -303.771968) (xy 405.833471 -303.811312) (xy 405.856342 -303.854889)
			(xy 405.871926 -303.90157) (xy 405.879821 -303.950147) (xy 405.880316 -303.974754) (xy 406.219164 -303.974754)
			(xy 406.223124 -303.9257) (xy 406.234901 -303.877916) (xy 406.254192 -303.83264) (xy 406.280495 -303.791044)
			(xy 406.31313 -303.754207) (xy 406.351251 -303.723082) (xy 406.393872 -303.698475) (xy 406.439888 -303.681023)
			(xy 406.488107 -303.671179) (xy 406.537282 -303.669198) (xy 406.586137 -303.67513) (xy 406.633408 -303.688822)
			(xy 406.67787 -303.70992) (xy 406.718373 -303.737876) (xy 406.753866 -303.771968) (xy 406.783431 -303.811312)
			(xy 406.806302 -303.854889) (xy 406.821886 -303.90157) (xy 406.829781 -303.950147) (xy 406.830276 -303.974754)
			(xy 408.119084 -303.974754) (xy 408.123044 -303.9257) (xy 408.134821 -303.877916) (xy 408.154112 -303.83264)
			(xy 408.180415 -303.791044) (xy 408.21305 -303.754207) (xy 408.251171 -303.723082) (xy 408.293792 -303.698475)
			(xy 408.339808 -303.681023) (xy 408.388027 -303.671179) (xy 408.437202 -303.669198) (xy 408.486057 -303.67513)
			(xy 408.533328 -303.688822) (xy 408.57779 -303.70992) (xy 408.618293 -303.737876) (xy 408.653786 -303.771968)
			(xy 408.683351 -303.811312) (xy 408.706222 -303.854889) (xy 408.721806 -303.90157) (xy 408.729701 -303.950147)
			(xy 408.730196 -303.974754) (xy 409.069044 -303.974754) (xy 409.073004 -303.9257) (xy 409.084781 -303.877916)
			(xy 409.104072 -303.83264) (xy 409.130375 -303.791044) (xy 409.16301 -303.754207) (xy 409.201131 -303.723082)
			(xy 409.243752 -303.698475) (xy 409.289768 -303.681023) (xy 409.337987 -303.671179) (xy 409.387162 -303.669198)
			(xy 409.436017 -303.67513) (xy 409.483288 -303.688822) (xy 409.52775 -303.70992) (xy 409.568253 -303.737876)
			(xy 409.603746 -303.771968) (xy 409.633311 -303.811312) (xy 409.656182 -303.854889) (xy 409.671766 -303.90157)
			(xy 409.679661 -303.950147) (xy 409.680156 -303.974754) (xy 410.019004 -303.974754) (xy 410.022964 -303.9257)
			(xy 410.034741 -303.877916) (xy 410.054032 -303.83264) (xy 410.080335 -303.791044) (xy 410.11297 -303.754207)
			(xy 410.151091 -303.723082) (xy 410.193712 -303.698475) (xy 410.239728 -303.681023) (xy 410.287947 -303.671179)
			(xy 410.337122 -303.669198) (xy 410.385977 -303.67513) (xy 410.433248 -303.688822) (xy 410.47771 -303.70992)
			(xy 410.518213 -303.737876) (xy 410.553706 -303.771968) (xy 410.583271 -303.811312) (xy 410.606142 -303.854889)
			(xy 410.621726 -303.90157) (xy 410.629621 -303.950147) (xy 410.630116 -303.974754) (xy 410.969218 -303.974754)
			(xy 410.973178 -303.9257) (xy 410.984955 -303.877916) (xy 411.004246 -303.83264) (xy 411.030549 -303.791044)
			(xy 411.063184 -303.754207) (xy 411.101305 -303.723082) (xy 411.143926 -303.698475) (xy 411.189942 -303.681023)
			(xy 411.238161 -303.671179) (xy 411.287336 -303.669198) (xy 411.336191 -303.67513) (xy 411.383462 -303.688822)
			(xy 411.427924 -303.70992) (xy 411.468427 -303.737876) (xy 411.50392 -303.771968) (xy 411.533485 -303.811312)
			(xy 411.556356 -303.854889) (xy 411.57194 -303.90157) (xy 411.579835 -303.950147) (xy 411.58033 -303.974754)
			(xy 411.919178 -303.974754) (xy 411.923138 -303.9257) (xy 411.934915 -303.877916) (xy 411.954206 -303.83264)
			(xy 411.980509 -303.791044) (xy 412.013144 -303.754207) (xy 412.051265 -303.723082) (xy 412.093886 -303.698475)
			(xy 412.139902 -303.681023) (xy 412.188121 -303.671179) (xy 412.237296 -303.669198) (xy 412.286151 -303.67513)
			(xy 412.333422 -303.688822) (xy 412.377884 -303.70992) (xy 412.418387 -303.737876) (xy 412.45388 -303.771968)
			(xy 412.483445 -303.811312) (xy 412.506316 -303.854889) (xy 412.5219 -303.90157) (xy 412.529795 -303.950147)
			(xy 412.53029 -303.974754) (xy 412.869138 -303.974754) (xy 412.873098 -303.9257) (xy 412.884875 -303.877916)
			(xy 412.904166 -303.83264) (xy 412.930469 -303.791044) (xy 412.963104 -303.754207) (xy 413.001225 -303.723082)
			(xy 413.043846 -303.698475) (xy 413.089862 -303.681023) (xy 413.138081 -303.671179) (xy 413.187256 -303.669198)
			(xy 413.236111 -303.67513) (xy 413.283382 -303.688822) (xy 413.327844 -303.70992) (xy 413.368347 -303.737876)
			(xy 413.40384 -303.771968) (xy 413.433405 -303.811312) (xy 413.456276 -303.854889) (xy 413.47186 -303.90157)
			(xy 413.479755 -303.950147) (xy 413.48025 -303.974754) (xy 413.819098 -303.974754) (xy 413.823058 -303.9257)
			(xy 413.834835 -303.877916) (xy 413.854126 -303.83264) (xy 413.880429 -303.791044) (xy 413.913064 -303.754207)
			(xy 413.951185 -303.723082) (xy 413.993806 -303.698475) (xy 414.039822 -303.681023) (xy 414.088041 -303.671179)
			(xy 414.137216 -303.669198) (xy 414.186071 -303.67513) (xy 414.233342 -303.688822) (xy 414.277804 -303.70992)
			(xy 414.318307 -303.737876) (xy 414.3538 -303.771968) (xy 414.383365 -303.811312) (xy 414.406236 -303.854889)
			(xy 414.42182 -303.90157) (xy 414.429715 -303.950147) (xy 414.43021 -303.974754) (xy 414.769058 -303.974754)
			(xy 414.773018 -303.9257) (xy 414.784795 -303.877916) (xy 414.804086 -303.83264) (xy 414.830389 -303.791044)
			(xy 414.863024 -303.754207) (xy 414.901145 -303.723082) (xy 414.943766 -303.698475) (xy 414.989782 -303.681023)
			(xy 415.038001 -303.671179) (xy 415.087176 -303.669198) (xy 415.136031 -303.67513) (xy 415.183302 -303.688822)
			(xy 415.227764 -303.70992) (xy 415.268267 -303.737876) (xy 415.30376 -303.771968) (xy 415.333325 -303.811312)
			(xy 415.356196 -303.854889) (xy 415.37178 -303.90157) (xy 415.379675 -303.950147) (xy 415.38017 -303.974754)
			(xy 415.719018 -303.974754) (xy 415.722978 -303.9257) (xy 415.734755 -303.877916) (xy 415.754046 -303.83264)
			(xy 415.780349 -303.791044) (xy 415.812984 -303.754207) (xy 415.851105 -303.723082) (xy 415.893726 -303.698475)
			(xy 415.939742 -303.681023) (xy 415.987961 -303.671179) (xy 416.037136 -303.669198) (xy 416.085991 -303.67513)
			(xy 416.133262 -303.688822) (xy 416.177724 -303.70992) (xy 416.218227 -303.737876) (xy 416.25372 -303.771968)
			(xy 416.283285 -303.811312) (xy 416.306156 -303.854889) (xy 416.32174 -303.90157) (xy 416.329635 -303.950147)
			(xy 416.330033 -303.969928) (xy 416.674058 -303.969928) (xy 416.678018 -303.920874) (xy 416.689795 -303.87309)
			(xy 416.709086 -303.827814) (xy 416.735389 -303.786218) (xy 416.768024 -303.749381) (xy 416.806145 -303.718256)
			(xy 416.848766 -303.693649) (xy 416.894782 -303.676197) (xy 416.943001 -303.666353) (xy 416.992176 -303.664372)
			(xy 417.041031 -303.670304) (xy 417.088302 -303.683996) (xy 417.132764 -303.705094) (xy 417.173267 -303.73305)
			(xy 417.20876 -303.767142) (xy 417.238325 -303.806486) (xy 417.261196 -303.850063) (xy 417.27678 -303.896744)
			(xy 417.284675 -303.945321) (xy 417.28517 -303.969928) (xy 417.285073 -303.974754) (xy 417.619192 -303.974754)
			(xy 417.623152 -303.9257) (xy 417.634929 -303.877916) (xy 417.65422 -303.83264) (xy 417.680523 -303.791044)
			(xy 417.713158 -303.754207) (xy 417.751279 -303.723082) (xy 417.7939 -303.698475) (xy 417.839916 -303.681023)
			(xy 417.888135 -303.671179) (xy 417.93731 -303.669198) (xy 417.986165 -303.67513) (xy 418.033436 -303.688822)
			(xy 418.077898 -303.70992) (xy 418.118401 -303.737876) (xy 418.153894 -303.771968) (xy 418.183459 -303.811312)
			(xy 418.20633 -303.854889) (xy 418.221914 -303.90157) (xy 418.229809 -303.950147) (xy 418.230304 -303.974754)
			(xy 418.569152 -303.974754) (xy 418.573112 -303.9257) (xy 418.584889 -303.877916) (xy 418.60418 -303.83264)
			(xy 418.630483 -303.791044) (xy 418.663118 -303.754207) (xy 418.701239 -303.723082) (xy 418.74386 -303.698475)
			(xy 418.789876 -303.681023) (xy 418.838095 -303.671179) (xy 418.88727 -303.669198) (xy 418.936125 -303.67513)
			(xy 418.983396 -303.688822) (xy 419.027858 -303.70992) (xy 419.068361 -303.737876) (xy 419.103854 -303.771968)
			(xy 419.133419 -303.811312) (xy 419.15629 -303.854889) (xy 419.171874 -303.90157) (xy 419.179769 -303.950147)
			(xy 419.180264 -303.974754) (xy 419.519112 -303.974754) (xy 419.523072 -303.9257) (xy 419.534849 -303.877916)
			(xy 419.55414 -303.83264) (xy 419.580443 -303.791044) (xy 419.613078 -303.754207) (xy 419.651199 -303.723082)
			(xy 419.69382 -303.698475) (xy 419.739836 -303.681023) (xy 419.788055 -303.671179) (xy 419.83723 -303.669198)
			(xy 419.886085 -303.67513) (xy 419.933356 -303.688822) (xy 419.977818 -303.70992) (xy 420.018321 -303.737876)
			(xy 420.053814 -303.771968) (xy 420.083379 -303.811312) (xy 420.10625 -303.854889) (xy 420.121834 -303.90157)
			(xy 420.129729 -303.950147) (xy 420.130224 -303.974754) (xy 420.469072 -303.974754) (xy 420.473032 -303.9257)
			(xy 420.484809 -303.877916) (xy 420.5041 -303.83264) (xy 420.530403 -303.791044) (xy 420.563038 -303.754207)
			(xy 420.601159 -303.723082) (xy 420.64378 -303.698475) (xy 420.689796 -303.681023) (xy 420.738015 -303.671179)
			(xy 420.78719 -303.669198) (xy 420.836045 -303.67513) (xy 420.883316 -303.688822) (xy 420.927778 -303.70992)
			(xy 420.968281 -303.737876) (xy 421.003774 -303.771968) (xy 421.033339 -303.811312) (xy 421.05621 -303.854889)
			(xy 421.071794 -303.90157) (xy 421.079689 -303.950147) (xy 421.080184 -303.974754) (xy 421.419032 -303.974754)
			(xy 421.422992 -303.9257) (xy 421.434769 -303.877916) (xy 421.45406 -303.83264) (xy 421.480363 -303.791044)
			(xy 421.512998 -303.754207) (xy 421.551119 -303.723082) (xy 421.59374 -303.698475) (xy 421.639756 -303.681023)
			(xy 421.687975 -303.671179) (xy 421.73715 -303.669198) (xy 421.786005 -303.67513) (xy 421.833276 -303.688822)
			(xy 421.877738 -303.70992) (xy 421.918241 -303.737876) (xy 421.953734 -303.771968) (xy 421.983299 -303.811312)
			(xy 422.00617 -303.854889) (xy 422.021754 -303.90157) (xy 422.029649 -303.950147) (xy 422.030144 -303.974754)
			(xy 422.029649 -303.999361) (xy 422.021754 -304.047938) (xy 422.00617 -304.094619) (xy 421.983299 -304.138196)
			(xy 421.953734 -304.17754) (xy 421.918241 -304.211632) (xy 421.877738 -304.239588) (xy 421.833276 -304.260686)
			(xy 421.786005 -304.274378) (xy 421.73715 -304.28031) (xy 421.687975 -304.278329) (xy 421.639756 -304.268485)
			(xy 421.59374 -304.251033) (xy 421.551119 -304.226426) (xy 421.512998 -304.195301) (xy 421.480363 -304.158464)
			(xy 421.45406 -304.116868) (xy 421.434769 -304.071592) (xy 421.422992 -304.023808) (xy 421.419032 -303.974754)
			(xy 421.080184 -303.974754) (xy 421.079689 -303.999361) (xy 421.071794 -304.047938) (xy 421.05621 -304.094619)
			(xy 421.033339 -304.138196) (xy 421.003774 -304.17754) (xy 420.968281 -304.211632) (xy 420.927778 -304.239588)
			(xy 420.883316 -304.260686) (xy 420.836045 -304.274378) (xy 420.78719 -304.28031) (xy 420.738015 -304.278329)
			(xy 420.689796 -304.268485) (xy 420.64378 -304.251033) (xy 420.601159 -304.226426) (xy 420.563038 -304.195301)
			(xy 420.530403 -304.158464) (xy 420.5041 -304.116868) (xy 420.484809 -304.071592) (xy 420.473032 -304.023808)
			(xy 420.469072 -303.974754) (xy 420.130224 -303.974754) (xy 420.129729 -303.999361) (xy 420.121834 -304.047938)
			(xy 420.10625 -304.094619) (xy 420.083379 -304.138196) (xy 420.053814 -304.17754) (xy 420.018321 -304.211632)
			(xy 419.977818 -304.239588) (xy 419.933356 -304.260686) (xy 419.886085 -304.274378) (xy 419.83723 -304.28031)
			(xy 419.788055 -304.278329) (xy 419.739836 -304.268485) (xy 419.69382 -304.251033) (xy 419.651199 -304.226426)
			(xy 419.613078 -304.195301) (xy 419.580443 -304.158464) (xy 419.55414 -304.116868) (xy 419.534849 -304.071592)
			(xy 419.523072 -304.023808) (xy 419.519112 -303.974754) (xy 419.180264 -303.974754) (xy 419.179769 -303.999361)
			(xy 419.171874 -304.047938) (xy 419.15629 -304.094619) (xy 419.133419 -304.138196) (xy 419.103854 -304.17754)
			(xy 419.068361 -304.211632) (xy 419.027858 -304.239588) (xy 418.983396 -304.260686) (xy 418.936125 -304.274378)
			(xy 418.88727 -304.28031) (xy 418.838095 -304.278329) (xy 418.789876 -304.268485) (xy 418.74386 -304.251033)
			(xy 418.701239 -304.226426) (xy 418.663118 -304.195301) (xy 418.630483 -304.158464) (xy 418.60418 -304.116868)
			(xy 418.584889 -304.071592) (xy 418.573112 -304.023808) (xy 418.569152 -303.974754) (xy 418.230304 -303.974754)
			(xy 418.229809 -303.999361) (xy 418.221914 -304.047938) (xy 418.20633 -304.094619) (xy 418.183459 -304.138196)
			(xy 418.153894 -304.17754) (xy 418.118401 -304.211632) (xy 418.077898 -304.239588) (xy 418.033436 -304.260686)
			(xy 417.986165 -304.274378) (xy 417.93731 -304.28031) (xy 417.888135 -304.278329) (xy 417.839916 -304.268485)
			(xy 417.7939 -304.251033) (xy 417.751279 -304.226426) (xy 417.713158 -304.195301) (xy 417.680523 -304.158464)
			(xy 417.65422 -304.116868) (xy 417.634929 -304.071592) (xy 417.623152 -304.023808) (xy 417.619192 -303.974754)
			(xy 417.285073 -303.974754) (xy 417.284675 -303.994535) (xy 417.27678 -304.043112) (xy 417.261196 -304.089793)
			(xy 417.238325 -304.13337) (xy 417.20876 -304.172714) (xy 417.173267 -304.206806) (xy 417.132764 -304.234762)
			(xy 417.088302 -304.25586) (xy 417.041031 -304.269552) (xy 416.992176 -304.275484) (xy 416.943001 -304.273503)
			(xy 416.894782 -304.263659) (xy 416.848766 -304.246207) (xy 416.806145 -304.2216) (xy 416.768024 -304.190475)
			(xy 416.735389 -304.153638) (xy 416.709086 -304.112042) (xy 416.689795 -304.066766) (xy 416.678018 -304.018982)
			(xy 416.674058 -303.969928) (xy 416.330033 -303.969928) (xy 416.33013 -303.974754) (xy 416.329635 -303.999361)
			(xy 416.32174 -304.047938) (xy 416.306156 -304.094619) (xy 416.283285 -304.138196) (xy 416.25372 -304.17754)
			(xy 416.218227 -304.211632) (xy 416.177724 -304.239588) (xy 416.133262 -304.260686) (xy 416.085991 -304.274378)
			(xy 416.037136 -304.28031) (xy 415.987961 -304.278329) (xy 415.939742 -304.268485) (xy 415.893726 -304.251033)
			(xy 415.851105 -304.226426) (xy 415.812984 -304.195301) (xy 415.780349 -304.158464) (xy 415.754046 -304.116868)
			(xy 415.734755 -304.071592) (xy 415.722978 -304.023808) (xy 415.719018 -303.974754) (xy 415.38017 -303.974754)
			(xy 415.379675 -303.999361) (xy 415.37178 -304.047938) (xy 415.356196 -304.094619) (xy 415.333325 -304.138196)
			(xy 415.30376 -304.17754) (xy 415.268267 -304.211632) (xy 415.227764 -304.239588) (xy 415.183302 -304.260686)
			(xy 415.136031 -304.274378) (xy 415.087176 -304.28031) (xy 415.038001 -304.278329) (xy 414.989782 -304.268485)
			(xy 414.943766 -304.251033) (xy 414.901145 -304.226426) (xy 414.863024 -304.195301) (xy 414.830389 -304.158464)
			(xy 414.804086 -304.116868) (xy 414.784795 -304.071592) (xy 414.773018 -304.023808) (xy 414.769058 -303.974754)
			(xy 414.43021 -303.974754) (xy 414.429715 -303.999361) (xy 414.42182 -304.047938) (xy 414.406236 -304.094619)
			(xy 414.383365 -304.138196) (xy 414.3538 -304.17754) (xy 414.318307 -304.211632) (xy 414.277804 -304.239588)
			(xy 414.233342 -304.260686) (xy 414.186071 -304.274378) (xy 414.137216 -304.28031) (xy 414.088041 -304.278329)
			(xy 414.039822 -304.268485) (xy 413.993806 -304.251033) (xy 413.951185 -304.226426) (xy 413.913064 -304.195301)
			(xy 413.880429 -304.158464) (xy 413.854126 -304.116868) (xy 413.834835 -304.071592) (xy 413.823058 -304.023808)
			(xy 413.819098 -303.974754) (xy 413.48025 -303.974754) (xy 413.479755 -303.999361) (xy 413.47186 -304.047938)
			(xy 413.456276 -304.094619) (xy 413.433405 -304.138196) (xy 413.40384 -304.17754) (xy 413.368347 -304.211632)
			(xy 413.327844 -304.239588) (xy 413.283382 -304.260686) (xy 413.236111 -304.274378) (xy 413.187256 -304.28031)
			(xy 413.138081 -304.278329) (xy 413.089862 -304.268485) (xy 413.043846 -304.251033) (xy 413.001225 -304.226426)
			(xy 412.963104 -304.195301) (xy 412.930469 -304.158464) (xy 412.904166 -304.116868) (xy 412.884875 -304.071592)
			(xy 412.873098 -304.023808) (xy 412.869138 -303.974754) (xy 412.53029 -303.974754) (xy 412.529795 -303.999361)
			(xy 412.5219 -304.047938) (xy 412.506316 -304.094619) (xy 412.483445 -304.138196) (xy 412.45388 -304.17754)
			(xy 412.418387 -304.211632) (xy 412.377884 -304.239588) (xy 412.333422 -304.260686) (xy 412.286151 -304.274378)
			(xy 412.237296 -304.28031) (xy 412.188121 -304.278329) (xy 412.139902 -304.268485) (xy 412.093886 -304.251033)
			(xy 412.051265 -304.226426) (xy 412.013144 -304.195301) (xy 411.980509 -304.158464) (xy 411.954206 -304.116868)
			(xy 411.934915 -304.071592) (xy 411.923138 -304.023808) (xy 411.919178 -303.974754) (xy 411.58033 -303.974754)
			(xy 411.579835 -303.999361) (xy 411.57194 -304.047938) (xy 411.556356 -304.094619) (xy 411.533485 -304.138196)
			(xy 411.50392 -304.17754) (xy 411.468427 -304.211632) (xy 411.427924 -304.239588) (xy 411.383462 -304.260686)
			(xy 411.336191 -304.274378) (xy 411.287336 -304.28031) (xy 411.238161 -304.278329) (xy 411.189942 -304.268485)
			(xy 411.143926 -304.251033) (xy 411.101305 -304.226426) (xy 411.063184 -304.195301) (xy 411.030549 -304.158464)
			(xy 411.004246 -304.116868) (xy 410.984955 -304.071592) (xy 410.973178 -304.023808) (xy 410.969218 -303.974754)
			(xy 410.630116 -303.974754) (xy 410.629621 -303.999361) (xy 410.621726 -304.047938) (xy 410.606142 -304.094619)
			(xy 410.583271 -304.138196) (xy 410.553706 -304.17754) (xy 410.518213 -304.211632) (xy 410.47771 -304.239588)
			(xy 410.433248 -304.260686) (xy 410.385977 -304.274378) (xy 410.337122 -304.28031) (xy 410.287947 -304.278329)
			(xy 410.239728 -304.268485) (xy 410.193712 -304.251033) (xy 410.151091 -304.226426) (xy 410.11297 -304.195301)
			(xy 410.080335 -304.158464) (xy 410.054032 -304.116868) (xy 410.034741 -304.071592) (xy 410.022964 -304.023808)
			(xy 410.019004 -303.974754) (xy 409.680156 -303.974754) (xy 409.679661 -303.999361) (xy 409.671766 -304.047938)
			(xy 409.656182 -304.094619) (xy 409.633311 -304.138196) (xy 409.603746 -304.17754) (xy 409.568253 -304.211632)
			(xy 409.52775 -304.239588) (xy 409.483288 -304.260686) (xy 409.436017 -304.274378) (xy 409.387162 -304.28031)
			(xy 409.337987 -304.278329) (xy 409.289768 -304.268485) (xy 409.243752 -304.251033) (xy 409.201131 -304.226426)
			(xy 409.16301 -304.195301) (xy 409.130375 -304.158464) (xy 409.104072 -304.116868) (xy 409.084781 -304.071592)
			(xy 409.073004 -304.023808) (xy 409.069044 -303.974754) (xy 408.730196 -303.974754) (xy 408.729701 -303.999361)
			(xy 408.721806 -304.047938) (xy 408.706222 -304.094619) (xy 408.683351 -304.138196) (xy 408.653786 -304.17754)
			(xy 408.618293 -304.211632) (xy 408.57779 -304.239588) (xy 408.533328 -304.260686) (xy 408.486057 -304.274378)
			(xy 408.437202 -304.28031) (xy 408.388027 -304.278329) (xy 408.339808 -304.268485) (xy 408.293792 -304.251033)
			(xy 408.251171 -304.226426) (xy 408.21305 -304.195301) (xy 408.180415 -304.158464) (xy 408.154112 -304.116868)
			(xy 408.134821 -304.071592) (xy 408.123044 -304.023808) (xy 408.119084 -303.974754) (xy 406.830276 -303.974754)
			(xy 406.829781 -303.999361) (xy 406.821886 -304.047938) (xy 406.806302 -304.094619) (xy 406.783431 -304.138196)
			(xy 406.753866 -304.17754) (xy 406.718373 -304.211632) (xy 406.67787 -304.239588) (xy 406.633408 -304.260686)
			(xy 406.586137 -304.274378) (xy 406.537282 -304.28031) (xy 406.488107 -304.278329) (xy 406.439888 -304.268485)
			(xy 406.393872 -304.251033) (xy 406.351251 -304.226426) (xy 406.31313 -304.195301) (xy 406.280495 -304.158464)
			(xy 406.254192 -304.116868) (xy 406.234901 -304.071592) (xy 406.223124 -304.023808) (xy 406.219164 -303.974754)
			(xy 405.880316 -303.974754) (xy 405.879821 -303.999361) (xy 405.871926 -304.047938) (xy 405.856342 -304.094619)
			(xy 405.833471 -304.138196) (xy 405.803906 -304.17754) (xy 405.768413 -304.211632) (xy 405.72791 -304.239588)
			(xy 405.683448 -304.260686) (xy 405.636177 -304.274378) (xy 405.587322 -304.28031) (xy 405.538147 -304.278329)
			(xy 405.489928 -304.268485) (xy 405.443912 -304.251033) (xy 405.401291 -304.226426) (xy 405.36317 -304.195301)
			(xy 405.330535 -304.158464) (xy 405.304232 -304.116868) (xy 405.284941 -304.071592) (xy 405.273164 -304.023808)
			(xy 405.269204 -303.974754) (xy 404.930102 -303.974754) (xy 404.929607 -303.999361) (xy 404.921712 -304.047938)
			(xy 404.906128 -304.094619) (xy 404.883257 -304.138196) (xy 404.853692 -304.17754) (xy 404.818199 -304.211632)
			(xy 404.777696 -304.239588) (xy 404.733234 -304.260686) (xy 404.685963 -304.274378) (xy 404.637108 -304.28031)
			(xy 404.587933 -304.278329) (xy 404.539714 -304.268485) (xy 404.493698 -304.251033) (xy 404.451077 -304.226426)
			(xy 404.412956 -304.195301) (xy 404.380321 -304.158464) (xy 404.354018 -304.116868) (xy 404.334727 -304.071592)
			(xy 404.32295 -304.023808) (xy 404.31899 -303.974754) (xy 403.980142 -303.974754) (xy 403.979647 -303.999361)
			(xy 403.971752 -304.047938) (xy 403.956168 -304.094619) (xy 403.933297 -304.138196) (xy 403.903732 -304.17754)
			(xy 403.868239 -304.211632) (xy 403.827736 -304.239588) (xy 403.783274 -304.260686) (xy 403.736003 -304.274378)
			(xy 403.687148 -304.28031) (xy 403.637973 -304.278329) (xy 403.589754 -304.268485) (xy 403.543738 -304.251033)
			(xy 403.501117 -304.226426) (xy 403.462996 -304.195301) (xy 403.430361 -304.158464) (xy 403.404058 -304.116868)
			(xy 403.384767 -304.071592) (xy 403.37299 -304.023808) (xy 403.36903 -303.974754) (xy 403.030182 -303.974754)
			(xy 403.029687 -303.999361) (xy 403.021792 -304.047938) (xy 403.006208 -304.094619) (xy 402.983337 -304.138196)
			(xy 402.953772 -304.17754) (xy 402.918279 -304.211632) (xy 402.877776 -304.239588) (xy 402.833314 -304.260686)
			(xy 402.786043 -304.274378) (xy 402.737188 -304.28031) (xy 402.688013 -304.278329) (xy 402.639794 -304.268485)
			(xy 402.593778 -304.251033) (xy 402.551157 -304.226426) (xy 402.513036 -304.195301) (xy 402.480401 -304.158464)
			(xy 402.454098 -304.116868) (xy 402.434807 -304.071592) (xy 402.42303 -304.023808) (xy 402.41907 -303.974754)
			(xy 402.080222 -303.974754) (xy 402.079727 -303.999361) (xy 402.071832 -304.047938) (xy 402.056248 -304.094619)
			(xy 402.033377 -304.138196) (xy 402.003812 -304.17754) (xy 401.968319 -304.211632) (xy 401.927816 -304.239588)
			(xy 401.883354 -304.260686) (xy 401.836083 -304.274378) (xy 401.787228 -304.28031) (xy 401.738053 -304.278329)
			(xy 401.689834 -304.268485) (xy 401.643818 -304.251033) (xy 401.601197 -304.226426) (xy 401.563076 -304.195301)
			(xy 401.530441 -304.158464) (xy 401.504138 -304.116868) (xy 401.484847 -304.071592) (xy 401.47307 -304.023808)
			(xy 401.46911 -303.974754) (xy 401.130262 -303.974754) (xy 401.129767 -303.999361) (xy 401.121872 -304.047938)
			(xy 401.106288 -304.094619) (xy 401.083417 -304.138196) (xy 401.053852 -304.17754) (xy 401.018359 -304.211632)
			(xy 400.977856 -304.239588) (xy 400.933394 -304.260686) (xy 400.886123 -304.274378) (xy 400.837268 -304.28031)
			(xy 400.788093 -304.278329) (xy 400.739874 -304.268485) (xy 400.693858 -304.251033) (xy 400.651237 -304.226426)
			(xy 400.613116 -304.195301) (xy 400.580481 -304.158464) (xy 400.554178 -304.116868) (xy 400.534887 -304.071592)
			(xy 400.52311 -304.023808) (xy 400.51915 -303.974754) (xy 400.180302 -303.974754) (xy 400.179807 -303.999361)
			(xy 400.171912 -304.047938) (xy 400.156328 -304.094619) (xy 400.133457 -304.138196) (xy 400.103892 -304.17754)
			(xy 400.068399 -304.211632) (xy 400.027896 -304.239588) (xy 399.983434 -304.260686) (xy 399.936163 -304.274378)
			(xy 399.887308 -304.28031) (xy 399.838133 -304.278329) (xy 399.789914 -304.268485) (xy 399.743898 -304.251033)
			(xy 399.701277 -304.226426) (xy 399.663156 -304.195301) (xy 399.630521 -304.158464) (xy 399.604218 -304.116868)
			(xy 399.584927 -304.071592) (xy 399.57315 -304.023808) (xy 399.56919 -303.974754) (xy 399.230342 -303.974754)
			(xy 399.229847 -303.999361) (xy 399.221952 -304.047938) (xy 399.206368 -304.094619) (xy 399.183497 -304.138196)
			(xy 399.153932 -304.17754) (xy 399.118439 -304.211632) (xy 399.077936 -304.239588) (xy 399.033474 -304.260686)
			(xy 398.986203 -304.274378) (xy 398.937348 -304.28031) (xy 398.888173 -304.278329) (xy 398.839954 -304.268485)
			(xy 398.793938 -304.251033) (xy 398.751317 -304.226426) (xy 398.713196 -304.195301) (xy 398.680561 -304.158464)
			(xy 398.654258 -304.116868) (xy 398.634967 -304.071592) (xy 398.62319 -304.023808) (xy 398.61923 -303.974754)
			(xy 398.280128 -303.974754) (xy 398.279633 -303.999361) (xy 398.271738 -304.047938) (xy 398.256154 -304.094619)
			(xy 398.233283 -304.138196) (xy 398.203718 -304.17754) (xy 398.168225 -304.211632) (xy 398.127722 -304.239588)
			(xy 398.08326 -304.260686) (xy 398.035989 -304.274378) (xy 397.987134 -304.28031) (xy 397.937959 -304.278329)
			(xy 397.88974 -304.268485) (xy 397.843724 -304.251033) (xy 397.801103 -304.226426) (xy 397.762982 -304.195301)
			(xy 397.730347 -304.158464) (xy 397.704044 -304.116868) (xy 397.684753 -304.071592) (xy 397.672976 -304.023808)
			(xy 397.669016 -303.974754) (xy 397.355192 -303.974754) (xy 397.355193 -304.001159) (xy 397.346828 -304.053222)
			(xy 397.330311 -304.103299) (xy 397.306059 -304.150122) (xy 397.274686 -304.192504) (xy 397.236987 -304.229373)
			(xy 397.193916 -304.259794) (xy 397.146565 -304.282997) (xy 397.096133 -304.298395) (xy 397.070072 -304.302414)
			(xy 397.066008 -304.302922) (xy 397.054578 -304.306478) (xy 397.05026 -304.307748) (xy 397.02613 -304.318924)
			(xy 397.019526 -304.326036) (xy 397.004794 -304.34153) (xy 396.996666 -304.352706) (xy 396.993975 -304.358238)
			(xy 396.991028 -304.370179) (xy 396.990824 -304.376328) (xy 396.990824 -304.475442) (xy 422.823382 -304.475442)
			(xy 422.823382 -304.424026) (xy 422.831425 -304.373244) (xy 422.847313 -304.324345) (xy 422.870656 -304.278533)
			(xy 422.900877 -304.236937) (xy 422.937233 -304.200581) (xy 422.978829 -304.17036) (xy 423.024641 -304.147017)
			(xy 423.07354 -304.131129) (xy 423.124322 -304.123086) (xy 423.175738 -304.123086) (xy 423.22652 -304.131129)
			(xy 423.275419 -304.147017) (xy 423.321231 -304.17036) (xy 423.362827 -304.200581) (xy 423.399183 -304.236937)
			(xy 423.429404 -304.278533) (xy 423.452747 -304.324345) (xy 423.468635 -304.373244) (xy 423.476678 -304.424026)
			(xy 423.477182 -304.449734) (xy 423.476678 -304.475442) (xy 423.773342 -304.475442) (xy 423.773342 -304.424026)
			(xy 423.781385 -304.373244) (xy 423.797273 -304.324345) (xy 423.820616 -304.278533) (xy 423.850837 -304.236937)
			(xy 423.887193 -304.200581) (xy 423.928789 -304.17036) (xy 423.974601 -304.147017) (xy 424.0235 -304.131129)
			(xy 424.074282 -304.123086) (xy 424.125698 -304.123086) (xy 424.17648 -304.131129) (xy 424.225379 -304.147017)
			(xy 424.271191 -304.17036) (xy 424.312787 -304.200581) (xy 424.349143 -304.236937) (xy 424.379364 -304.278533)
			(xy 424.402707 -304.324345) (xy 424.418595 -304.373244) (xy 424.426638 -304.424026) (xy 424.427142 -304.449734)
			(xy 424.744146 -304.449734) (xy 424.748106 -304.40068) (xy 424.759883 -304.352896) (xy 424.779174 -304.30762)
			(xy 424.805477 -304.266024) (xy 424.838112 -304.229187) (xy 424.876233 -304.198062) (xy 424.918854 -304.173455)
			(xy 424.96487 -304.156003) (xy 425.013089 -304.146159) (xy 425.062264 -304.144178) (xy 425.111119 -304.15011)
			(xy 425.15839 -304.163802) (xy 425.202852 -304.1849) (xy 425.243355 -304.212856) (xy 425.278848 -304.246948)
			(xy 425.308413 -304.286292) (xy 425.331284 -304.329869) (xy 425.346868 -304.37655) (xy 425.354763 -304.425127)
			(xy 425.355258 -304.449734) (xy 425.694106 -304.449734) (xy 425.698066 -304.40068) (xy 425.709843 -304.352896)
			(xy 425.729134 -304.30762) (xy 425.755437 -304.266024) (xy 425.788072 -304.229187) (xy 425.826193 -304.198062)
			(xy 425.868814 -304.173455) (xy 425.91483 -304.156003) (xy 425.963049 -304.146159) (xy 426.012224 -304.144178)
			(xy 426.061079 -304.15011) (xy 426.10835 -304.163802) (xy 426.152812 -304.1849) (xy 426.193315 -304.212856)
			(xy 426.228808 -304.246948) (xy 426.258373 -304.286292) (xy 426.281244 -304.329869) (xy 426.296828 -304.37655)
			(xy 426.304723 -304.425127) (xy 426.305218 -304.449734) (xy 426.644066 -304.449734) (xy 426.648026 -304.40068)
			(xy 426.659803 -304.352896) (xy 426.679094 -304.30762) (xy 426.705397 -304.266024) (xy 426.738032 -304.229187)
			(xy 426.776153 -304.198062) (xy 426.818774 -304.173455) (xy 426.86479 -304.156003) (xy 426.913009 -304.146159)
			(xy 426.962184 -304.144178) (xy 427.011039 -304.15011) (xy 427.05831 -304.163802) (xy 427.102772 -304.1849)
			(xy 427.143275 -304.212856) (xy 427.178768 -304.246948) (xy 427.208333 -304.286292) (xy 427.231204 -304.329869)
			(xy 427.246788 -304.37655) (xy 427.254683 -304.425127) (xy 427.255178 -304.449734) (xy 427.594026 -304.449734)
			(xy 427.597986 -304.40068) (xy 427.609763 -304.352896) (xy 427.629054 -304.30762) (xy 427.655357 -304.266024)
			(xy 427.687992 -304.229187) (xy 427.726113 -304.198062) (xy 427.768734 -304.173455) (xy 427.81475 -304.156003)
			(xy 427.862969 -304.146159) (xy 427.912144 -304.144178) (xy 427.960999 -304.15011) (xy 428.00827 -304.163802)
			(xy 428.052732 -304.1849) (xy 428.093235 -304.212856) (xy 428.128728 -304.246948) (xy 428.158293 -304.286292)
			(xy 428.181164 -304.329869) (xy 428.196748 -304.37655) (xy 428.204643 -304.425127) (xy 428.205138 -304.449734)
			(xy 428.543986 -304.449734) (xy 428.547946 -304.40068) (xy 428.559723 -304.352896) (xy 428.579014 -304.30762)
			(xy 428.605317 -304.266024) (xy 428.637952 -304.229187) (xy 428.676073 -304.198062) (xy 428.718694 -304.173455)
			(xy 428.76471 -304.156003) (xy 428.812929 -304.146159) (xy 428.862104 -304.144178) (xy 428.910959 -304.15011)
			(xy 428.95823 -304.163802) (xy 429.002692 -304.1849) (xy 429.043195 -304.212856) (xy 429.078688 -304.246948)
			(xy 429.108253 -304.286292) (xy 429.131124 -304.329869) (xy 429.146708 -304.37655) (xy 429.154603 -304.425127)
			(xy 429.155098 -304.449734) (xy 429.154603 -304.474341) (xy 429.154424 -304.475442) (xy 429.473356 -304.475442)
			(xy 429.473356 -304.424026) (xy 429.481399 -304.373244) (xy 429.497287 -304.324345) (xy 429.52063 -304.278533)
			(xy 429.550851 -304.236937) (xy 429.587207 -304.200581) (xy 429.628803 -304.17036) (xy 429.674615 -304.147017)
			(xy 429.723514 -304.131129) (xy 429.774296 -304.123086) (xy 429.825712 -304.123086) (xy 429.876494 -304.131129)
			(xy 429.925393 -304.147017) (xy 429.971205 -304.17036) (xy 430.012801 -304.200581) (xy 430.049157 -304.236937)
			(xy 430.079378 -304.278533) (xy 430.102721 -304.324345) (xy 430.118609 -304.373244) (xy 430.126652 -304.424026)
			(xy 430.127156 -304.449734) (xy 430.126652 -304.475442) (xy 430.423316 -304.475442) (xy 430.423316 -304.424026)
			(xy 430.431359 -304.373244) (xy 430.447247 -304.324345) (xy 430.47059 -304.278533) (xy 430.500811 -304.236937)
			(xy 430.537167 -304.200581) (xy 430.578763 -304.17036) (xy 430.624575 -304.147017) (xy 430.673474 -304.131129)
			(xy 430.724256 -304.123086) (xy 430.775672 -304.123086) (xy 430.826454 -304.131129) (xy 430.875353 -304.147017)
			(xy 430.921165 -304.17036) (xy 430.962761 -304.200581) (xy 430.999117 -304.236937) (xy 431.029338 -304.278533)
			(xy 431.052681 -304.324345) (xy 431.068569 -304.373244) (xy 431.076612 -304.424026) (xy 431.077116 -304.449734)
			(xy 431.394374 -304.449734) (xy 431.398334 -304.40068) (xy 431.410111 -304.352896) (xy 431.429402 -304.30762)
			(xy 431.455705 -304.266024) (xy 431.48834 -304.229187) (xy 431.526461 -304.198062) (xy 431.569082 -304.173455)
			(xy 431.615098 -304.156003) (xy 431.663317 -304.146159) (xy 431.712492 -304.144178) (xy 431.761347 -304.15011)
			(xy 431.808618 -304.163802) (xy 431.85308 -304.1849) (xy 431.893583 -304.212856) (xy 431.929076 -304.246948)
			(xy 431.958641 -304.286292) (xy 431.981512 -304.329869) (xy 431.997096 -304.37655) (xy 432.004991 -304.425127)
			(xy 432.005486 -304.449734) (xy 432.004991 -304.474341) (xy 431.997096 -304.522918) (xy 431.981512 -304.569599)
			(xy 431.958641 -304.613176) (xy 431.929076 -304.65252) (xy 431.893583 -304.686612) (xy 431.85308 -304.714568)
			(xy 431.808618 -304.735666) (xy 431.761347 -304.749358) (xy 431.712492 -304.75529) (xy 431.663317 -304.753309)
			(xy 431.615098 -304.743465) (xy 431.569082 -304.726013) (xy 431.526461 -304.701406) (xy 431.48834 -304.670281)
			(xy 431.455705 -304.633444) (xy 431.429402 -304.591848) (xy 431.410111 -304.546572) (xy 431.398334 -304.498788)
			(xy 431.394374 -304.449734) (xy 431.077116 -304.449734) (xy 431.076612 -304.475442) (xy 431.068569 -304.526224)
			(xy 431.052681 -304.575123) (xy 431.029338 -304.620935) (xy 430.999117 -304.662531) (xy 430.962761 -304.698887)
			(xy 430.921165 -304.729108) (xy 430.875353 -304.752451) (xy 430.826454 -304.768339) (xy 430.775672 -304.776382)
			(xy 430.724256 -304.776382) (xy 430.673474 -304.768339) (xy 430.624575 -304.752451) (xy 430.578763 -304.729108)
			(xy 430.537167 -304.698887) (xy 430.500811 -304.662531) (xy 430.47059 -304.620935) (xy 430.447247 -304.575123)
			(xy 430.431359 -304.526224) (xy 430.423316 -304.475442) (xy 430.126652 -304.475442) (xy 430.118609 -304.526224)
			(xy 430.102721 -304.575123) (xy 430.079378 -304.620935) (xy 430.049157 -304.662531) (xy 430.012801 -304.698887)
			(xy 429.971205 -304.729108) (xy 429.925393 -304.752451) (xy 429.876494 -304.768339) (xy 429.825712 -304.776382)
			(xy 429.774296 -304.776382) (xy 429.723514 -304.768339) (xy 429.674615 -304.752451) (xy 429.628803 -304.729108)
			(xy 429.587207 -304.698887) (xy 429.550851 -304.662531) (xy 429.52063 -304.620935) (xy 429.497287 -304.575123)
			(xy 429.481399 -304.526224) (xy 429.473356 -304.475442) (xy 429.154424 -304.475442) (xy 429.146708 -304.522918)
			(xy 429.131124 -304.569599) (xy 429.108253 -304.613176) (xy 429.078688 -304.65252) (xy 429.043195 -304.686612)
			(xy 429.002692 -304.714568) (xy 428.95823 -304.735666) (xy 428.910959 -304.749358) (xy 428.862104 -304.75529)
			(xy 428.812929 -304.753309) (xy 428.76471 -304.743465) (xy 428.718694 -304.726013) (xy 428.676073 -304.701406)
			(xy 428.637952 -304.670281) (xy 428.605317 -304.633444) (xy 428.579014 -304.591848) (xy 428.559723 -304.546572)
			(xy 428.547946 -304.498788) (xy 428.543986 -304.449734) (xy 428.205138 -304.449734) (xy 428.204643 -304.474341)
			(xy 428.196748 -304.522918) (xy 428.181164 -304.569599) (xy 428.158293 -304.613176) (xy 428.128728 -304.65252)
			(xy 428.093235 -304.686612) (xy 428.052732 -304.714568) (xy 428.00827 -304.735666) (xy 427.960999 -304.749358)
			(xy 427.912144 -304.75529) (xy 427.862969 -304.753309) (xy 427.81475 -304.743465) (xy 427.768734 -304.726013)
			(xy 427.726113 -304.701406) (xy 427.687992 -304.670281) (xy 427.655357 -304.633444) (xy 427.629054 -304.591848)
			(xy 427.609763 -304.546572) (xy 427.597986 -304.498788) (xy 427.594026 -304.449734) (xy 427.255178 -304.449734)
			(xy 427.254683 -304.474341) (xy 427.246788 -304.522918) (xy 427.231204 -304.569599) (xy 427.208333 -304.613176)
			(xy 427.178768 -304.65252) (xy 427.143275 -304.686612) (xy 427.102772 -304.714568) (xy 427.05831 -304.735666)
			(xy 427.011039 -304.749358) (xy 426.962184 -304.75529) (xy 426.913009 -304.753309) (xy 426.86479 -304.743465)
			(xy 426.818774 -304.726013) (xy 426.776153 -304.701406) (xy 426.738032 -304.670281) (xy 426.705397 -304.633444)
			(xy 426.679094 -304.591848) (xy 426.659803 -304.546572) (xy 426.648026 -304.498788) (xy 426.644066 -304.449734)
			(xy 426.305218 -304.449734) (xy 426.304723 -304.474341) (xy 426.296828 -304.522918) (xy 426.281244 -304.569599)
			(xy 426.258373 -304.613176) (xy 426.228808 -304.65252) (xy 426.193315 -304.686612) (xy 426.152812 -304.714568)
			(xy 426.10835 -304.735666) (xy 426.061079 -304.749358) (xy 426.012224 -304.75529) (xy 425.963049 -304.753309)
			(xy 425.91483 -304.743465) (xy 425.868814 -304.726013) (xy 425.826193 -304.701406) (xy 425.788072 -304.670281)
			(xy 425.755437 -304.633444) (xy 425.729134 -304.591848) (xy 425.709843 -304.546572) (xy 425.698066 -304.498788)
			(xy 425.694106 -304.449734) (xy 425.355258 -304.449734) (xy 425.354763 -304.474341) (xy 425.346868 -304.522918)
			(xy 425.331284 -304.569599) (xy 425.308413 -304.613176) (xy 425.278848 -304.65252) (xy 425.243355 -304.686612)
			(xy 425.202852 -304.714568) (xy 425.15839 -304.735666) (xy 425.111119 -304.749358) (xy 425.062264 -304.75529)
			(xy 425.013089 -304.753309) (xy 424.96487 -304.743465) (xy 424.918854 -304.726013) (xy 424.876233 -304.701406)
			(xy 424.838112 -304.670281) (xy 424.805477 -304.633444) (xy 424.779174 -304.591848) (xy 424.759883 -304.546572)
			(xy 424.748106 -304.498788) (xy 424.744146 -304.449734) (xy 424.427142 -304.449734) (xy 424.426638 -304.475442)
			(xy 424.418595 -304.526224) (xy 424.402707 -304.575123) (xy 424.379364 -304.620935) (xy 424.349143 -304.662531)
			(xy 424.312787 -304.698887) (xy 424.271191 -304.729108) (xy 424.225379 -304.752451) (xy 424.17648 -304.768339)
			(xy 424.125698 -304.776382) (xy 424.074282 -304.776382) (xy 424.0235 -304.768339) (xy 423.974601 -304.752451)
			(xy 423.928789 -304.729108) (xy 423.887193 -304.698887) (xy 423.850837 -304.662531) (xy 423.820616 -304.620935)
			(xy 423.797273 -304.575123) (xy 423.781385 -304.526224) (xy 423.773342 -304.475442) (xy 423.476678 -304.475442)
			(xy 423.468635 -304.526224) (xy 423.452747 -304.575123) (xy 423.429404 -304.620935) (xy 423.399183 -304.662531)
			(xy 423.362827 -304.698887) (xy 423.321231 -304.729108) (xy 423.275419 -304.752451) (xy 423.22652 -304.768339)
			(xy 423.175738 -304.776382) (xy 423.124322 -304.776382) (xy 423.07354 -304.768339) (xy 423.024641 -304.752451)
			(xy 422.978829 -304.729108) (xy 422.937233 -304.698887) (xy 422.900877 -304.662531) (xy 422.870656 -304.620935)
			(xy 422.847313 -304.575123) (xy 422.831425 -304.526224) (xy 422.823382 -304.475442) (xy 396.990824 -304.475442)
			(xy 396.990824 -304.52314) (xy 396.99099 -304.529294) (xy 396.993937 -304.541244) (xy 396.996666 -304.546762)
			(xy 397.004794 -304.557938) (xy 397.019526 -304.573432) (xy 397.02613 -304.580544) (xy 397.05026 -304.59172)
			(xy 397.054578 -304.59299) (xy 397.066008 -304.596546) (xy 397.070072 -304.597054) (xy 397.096116 -304.601162)
			(xy 397.146539 -304.616556) (xy 397.193882 -304.639755) (xy 397.236945 -304.67017) (xy 397.274638 -304.707032)
			(xy 397.306006 -304.749406) (xy 397.330255 -304.79622) (xy 397.34677 -304.846288) (xy 397.355133 -304.898341)
			(xy 397.355133 -304.924714) (xy 397.669016 -304.924714) (xy 397.672976 -304.87566) (xy 397.684753 -304.827876)
			(xy 397.704044 -304.7826) (xy 397.730347 -304.741004) (xy 397.762982 -304.704167) (xy 397.801103 -304.673042)
			(xy 397.843724 -304.648435) (xy 397.88974 -304.630983) (xy 397.937959 -304.621139) (xy 397.987134 -304.619158)
			(xy 398.035989 -304.62509) (xy 398.08326 -304.638782) (xy 398.127722 -304.65988) (xy 398.168225 -304.687836)
			(xy 398.203718 -304.721928) (xy 398.233283 -304.761272) (xy 398.256154 -304.804849) (xy 398.271738 -304.85153)
			(xy 398.279633 -304.900107) (xy 398.280128 -304.924714) (xy 398.61923 -304.924714) (xy 398.62319 -304.87566)
			(xy 398.634967 -304.827876) (xy 398.654258 -304.7826) (xy 398.680561 -304.741004) (xy 398.713196 -304.704167)
			(xy 398.751317 -304.673042) (xy 398.793938 -304.648435) (xy 398.839954 -304.630983) (xy 398.888173 -304.621139)
			(xy 398.937348 -304.619158) (xy 398.986203 -304.62509) (xy 399.033474 -304.638782) (xy 399.077936 -304.65988)
			(xy 399.118439 -304.687836) (xy 399.153932 -304.721928) (xy 399.183497 -304.761272) (xy 399.206368 -304.804849)
			(xy 399.221952 -304.85153) (xy 399.229847 -304.900107) (xy 399.230342 -304.924714) (xy 399.56919 -304.924714)
			(xy 399.57315 -304.87566) (xy 399.584927 -304.827876) (xy 399.604218 -304.7826) (xy 399.630521 -304.741004)
			(xy 399.663156 -304.704167) (xy 399.701277 -304.673042) (xy 399.743898 -304.648435) (xy 399.789914 -304.630983)
			(xy 399.838133 -304.621139) (xy 399.887308 -304.619158) (xy 399.936163 -304.62509) (xy 399.983434 -304.638782)
			(xy 400.027896 -304.65988) (xy 400.068399 -304.687836) (xy 400.103892 -304.721928) (xy 400.133457 -304.761272)
			(xy 400.156328 -304.804849) (xy 400.171912 -304.85153) (xy 400.179807 -304.900107) (xy 400.180302 -304.924714)
			(xy 400.51915 -304.924714) (xy 400.52311 -304.87566) (xy 400.534887 -304.827876) (xy 400.554178 -304.7826)
			(xy 400.580481 -304.741004) (xy 400.613116 -304.704167) (xy 400.651237 -304.673042) (xy 400.693858 -304.648435)
			(xy 400.739874 -304.630983) (xy 400.788093 -304.621139) (xy 400.837268 -304.619158) (xy 400.886123 -304.62509)
			(xy 400.933394 -304.638782) (xy 400.977856 -304.65988) (xy 401.018359 -304.687836) (xy 401.053852 -304.721928)
			(xy 401.083417 -304.761272) (xy 401.106288 -304.804849) (xy 401.121872 -304.85153) (xy 401.129767 -304.900107)
			(xy 401.130262 -304.924714) (xy 401.46911 -304.924714) (xy 401.47307 -304.87566) (xy 401.484847 -304.827876)
			(xy 401.504138 -304.7826) (xy 401.530441 -304.741004) (xy 401.563076 -304.704167) (xy 401.601197 -304.673042)
			(xy 401.643818 -304.648435) (xy 401.689834 -304.630983) (xy 401.738053 -304.621139) (xy 401.787228 -304.619158)
			(xy 401.836083 -304.62509) (xy 401.883354 -304.638782) (xy 401.927816 -304.65988) (xy 401.968319 -304.687836)
			(xy 402.003812 -304.721928) (xy 402.033377 -304.761272) (xy 402.056248 -304.804849) (xy 402.071832 -304.85153)
			(xy 402.079727 -304.900107) (xy 402.080222 -304.924714) (xy 402.41907 -304.924714) (xy 402.42303 -304.87566)
			(xy 402.434807 -304.827876) (xy 402.454098 -304.7826) (xy 402.480401 -304.741004) (xy 402.513036 -304.704167)
			(xy 402.551157 -304.673042) (xy 402.593778 -304.648435) (xy 402.639794 -304.630983) (xy 402.688013 -304.621139)
			(xy 402.737188 -304.619158) (xy 402.786043 -304.62509) (xy 402.833314 -304.638782) (xy 402.877776 -304.65988)
			(xy 402.918279 -304.687836) (xy 402.953772 -304.721928) (xy 402.983337 -304.761272) (xy 403.006208 -304.804849)
			(xy 403.021792 -304.85153) (xy 403.029687 -304.900107) (xy 403.030182 -304.924714) (xy 403.36903 -304.924714)
			(xy 403.37299 -304.87566) (xy 403.384767 -304.827876) (xy 403.404058 -304.7826) (xy 403.430361 -304.741004)
			(xy 403.462996 -304.704167) (xy 403.501117 -304.673042) (xy 403.543738 -304.648435) (xy 403.589754 -304.630983)
			(xy 403.637973 -304.621139) (xy 403.687148 -304.619158) (xy 403.736003 -304.62509) (xy 403.783274 -304.638782)
			(xy 403.827736 -304.65988) (xy 403.868239 -304.687836) (xy 403.903732 -304.721928) (xy 403.933297 -304.761272)
			(xy 403.956168 -304.804849) (xy 403.971752 -304.85153) (xy 403.979647 -304.900107) (xy 403.980142 -304.924714)
			(xy 404.31899 -304.924714) (xy 404.32295 -304.87566) (xy 404.334727 -304.827876) (xy 404.354018 -304.7826)
			(xy 404.380321 -304.741004) (xy 404.412956 -304.704167) (xy 404.451077 -304.673042) (xy 404.493698 -304.648435)
			(xy 404.539714 -304.630983) (xy 404.587933 -304.621139) (xy 404.637108 -304.619158) (xy 404.685963 -304.62509)
			(xy 404.733234 -304.638782) (xy 404.777696 -304.65988) (xy 404.818199 -304.687836) (xy 404.853692 -304.721928)
			(xy 404.883257 -304.761272) (xy 404.906128 -304.804849) (xy 404.921712 -304.85153) (xy 404.929607 -304.900107)
			(xy 404.930102 -304.924714) (xy 405.269204 -304.924714) (xy 405.273164 -304.87566) (xy 405.284941 -304.827876)
			(xy 405.304232 -304.7826) (xy 405.330535 -304.741004) (xy 405.36317 -304.704167) (xy 405.401291 -304.673042)
			(xy 405.443912 -304.648435) (xy 405.489928 -304.630983) (xy 405.538147 -304.621139) (xy 405.587322 -304.619158)
			(xy 405.636177 -304.62509) (xy 405.683448 -304.638782) (xy 405.72791 -304.65988) (xy 405.768413 -304.687836)
			(xy 405.803906 -304.721928) (xy 405.833471 -304.761272) (xy 405.856342 -304.804849) (xy 405.871926 -304.85153)
			(xy 405.879821 -304.900107) (xy 405.880316 -304.924714) (xy 406.219164 -304.924714) (xy 406.223124 -304.87566)
			(xy 406.234901 -304.827876) (xy 406.254192 -304.7826) (xy 406.280495 -304.741004) (xy 406.31313 -304.704167)
			(xy 406.351251 -304.673042) (xy 406.393872 -304.648435) (xy 406.439888 -304.630983) (xy 406.488107 -304.621139)
			(xy 406.537282 -304.619158) (xy 406.586137 -304.62509) (xy 406.633408 -304.638782) (xy 406.67787 -304.65988)
			(xy 406.718373 -304.687836) (xy 406.753866 -304.721928) (xy 406.783431 -304.761272) (xy 406.806302 -304.804849)
			(xy 406.821886 -304.85153) (xy 406.829781 -304.900107) (xy 406.830276 -304.924714) (xy 408.119084 -304.924714)
			(xy 408.123044 -304.87566) (xy 408.134821 -304.827876) (xy 408.154112 -304.7826) (xy 408.180415 -304.741004)
			(xy 408.21305 -304.704167) (xy 408.251171 -304.673042) (xy 408.293792 -304.648435) (xy 408.339808 -304.630983)
			(xy 408.388027 -304.621139) (xy 408.437202 -304.619158) (xy 408.486057 -304.62509) (xy 408.533328 -304.638782)
			(xy 408.57779 -304.65988) (xy 408.618293 -304.687836) (xy 408.653786 -304.721928) (xy 408.683351 -304.761272)
			(xy 408.706222 -304.804849) (xy 408.721806 -304.85153) (xy 408.729701 -304.900107) (xy 408.730196 -304.924714)
			(xy 409.069044 -304.924714) (xy 409.073004 -304.87566) (xy 409.084781 -304.827876) (xy 409.104072 -304.7826)
			(xy 409.130375 -304.741004) (xy 409.16301 -304.704167) (xy 409.201131 -304.673042) (xy 409.243752 -304.648435)
			(xy 409.289768 -304.630983) (xy 409.337987 -304.621139) (xy 409.387162 -304.619158) (xy 409.436017 -304.62509)
			(xy 409.483288 -304.638782) (xy 409.52775 -304.65988) (xy 409.568253 -304.687836) (xy 409.603746 -304.721928)
			(xy 409.633311 -304.761272) (xy 409.656182 -304.804849) (xy 409.671766 -304.85153) (xy 409.679661 -304.900107)
			(xy 409.680156 -304.924714) (xy 410.019004 -304.924714) (xy 410.022964 -304.87566) (xy 410.034741 -304.827876)
			(xy 410.054032 -304.7826) (xy 410.080335 -304.741004) (xy 410.11297 -304.704167) (xy 410.151091 -304.673042)
			(xy 410.193712 -304.648435) (xy 410.239728 -304.630983) (xy 410.287947 -304.621139) (xy 410.337122 -304.619158)
			(xy 410.385977 -304.62509) (xy 410.433248 -304.638782) (xy 410.47771 -304.65988) (xy 410.518213 -304.687836)
			(xy 410.553706 -304.721928) (xy 410.583271 -304.761272) (xy 410.606142 -304.804849) (xy 410.621726 -304.85153)
			(xy 410.629621 -304.900107) (xy 410.630116 -304.924714) (xy 410.969218 -304.924714) (xy 410.973178 -304.87566)
			(xy 410.984955 -304.827876) (xy 411.004246 -304.7826) (xy 411.030549 -304.741004) (xy 411.063184 -304.704167)
			(xy 411.101305 -304.673042) (xy 411.143926 -304.648435) (xy 411.189942 -304.630983) (xy 411.238161 -304.621139)
			(xy 411.287336 -304.619158) (xy 411.336191 -304.62509) (xy 411.383462 -304.638782) (xy 411.427924 -304.65988)
			(xy 411.468427 -304.687836) (xy 411.50392 -304.721928) (xy 411.533485 -304.761272) (xy 411.556356 -304.804849)
			(xy 411.57194 -304.85153) (xy 411.579835 -304.900107) (xy 411.58033 -304.924714) (xy 411.919178 -304.924714)
			(xy 411.923138 -304.87566) (xy 411.934915 -304.827876) (xy 411.954206 -304.7826) (xy 411.980509 -304.741004)
			(xy 412.013144 -304.704167) (xy 412.051265 -304.673042) (xy 412.093886 -304.648435) (xy 412.139902 -304.630983)
			(xy 412.188121 -304.621139) (xy 412.237296 -304.619158) (xy 412.286151 -304.62509) (xy 412.333422 -304.638782)
			(xy 412.377884 -304.65988) (xy 412.418387 -304.687836) (xy 412.45388 -304.721928) (xy 412.483445 -304.761272)
			(xy 412.506316 -304.804849) (xy 412.5219 -304.85153) (xy 412.529795 -304.900107) (xy 412.53029 -304.924714)
			(xy 412.869138 -304.924714) (xy 412.873098 -304.87566) (xy 412.884875 -304.827876) (xy 412.904166 -304.7826)
			(xy 412.930469 -304.741004) (xy 412.963104 -304.704167) (xy 413.001225 -304.673042) (xy 413.043846 -304.648435)
			(xy 413.089862 -304.630983) (xy 413.138081 -304.621139) (xy 413.187256 -304.619158) (xy 413.236111 -304.62509)
			(xy 413.283382 -304.638782) (xy 413.327844 -304.65988) (xy 413.368347 -304.687836) (xy 413.40384 -304.721928)
			(xy 413.433405 -304.761272) (xy 413.456276 -304.804849) (xy 413.47186 -304.85153) (xy 413.479755 -304.900107)
			(xy 413.48025 -304.924714) (xy 413.819098 -304.924714) (xy 413.823058 -304.87566) (xy 413.834835 -304.827876)
			(xy 413.854126 -304.7826) (xy 413.880429 -304.741004) (xy 413.913064 -304.704167) (xy 413.951185 -304.673042)
			(xy 413.993806 -304.648435) (xy 414.039822 -304.630983) (xy 414.088041 -304.621139) (xy 414.137216 -304.619158)
			(xy 414.186071 -304.62509) (xy 414.233342 -304.638782) (xy 414.277804 -304.65988) (xy 414.318307 -304.687836)
			(xy 414.3538 -304.721928) (xy 414.383365 -304.761272) (xy 414.406236 -304.804849) (xy 414.42182 -304.85153)
			(xy 414.429715 -304.900107) (xy 414.43021 -304.924714) (xy 414.769058 -304.924714) (xy 414.773018 -304.87566)
			(xy 414.784795 -304.827876) (xy 414.804086 -304.7826) (xy 414.830389 -304.741004) (xy 414.863024 -304.704167)
			(xy 414.901145 -304.673042) (xy 414.943766 -304.648435) (xy 414.989782 -304.630983) (xy 415.038001 -304.621139)
			(xy 415.087176 -304.619158) (xy 415.136031 -304.62509) (xy 415.183302 -304.638782) (xy 415.227764 -304.65988)
			(xy 415.268267 -304.687836) (xy 415.30376 -304.721928) (xy 415.333325 -304.761272) (xy 415.356196 -304.804849)
			(xy 415.37178 -304.85153) (xy 415.379675 -304.900107) (xy 415.38017 -304.924714) (xy 415.719018 -304.924714)
			(xy 415.722978 -304.87566) (xy 415.734755 -304.827876) (xy 415.754046 -304.7826) (xy 415.780349 -304.741004)
			(xy 415.812984 -304.704167) (xy 415.851105 -304.673042) (xy 415.893726 -304.648435) (xy 415.939742 -304.630983)
			(xy 415.987961 -304.621139) (xy 416.037136 -304.619158) (xy 416.085991 -304.62509) (xy 416.133262 -304.638782)
			(xy 416.177724 -304.65988) (xy 416.218227 -304.687836) (xy 416.25372 -304.721928) (xy 416.283285 -304.761272)
			(xy 416.306156 -304.804849) (xy 416.32174 -304.85153) (xy 416.329635 -304.900107) (xy 416.33013 -304.924714)
			(xy 416.668978 -304.924714) (xy 416.672938 -304.87566) (xy 416.684715 -304.827876) (xy 416.704006 -304.7826)
			(xy 416.730309 -304.741004) (xy 416.762944 -304.704167) (xy 416.801065 -304.673042) (xy 416.843686 -304.648435)
			(xy 416.889702 -304.630983) (xy 416.937921 -304.621139) (xy 416.987096 -304.619158) (xy 417.035951 -304.62509)
			(xy 417.083222 -304.638782) (xy 417.127684 -304.65988) (xy 417.168187 -304.687836) (xy 417.20368 -304.721928)
			(xy 417.233245 -304.761272) (xy 417.256116 -304.804849) (xy 417.2717 -304.85153) (xy 417.279595 -304.900107)
			(xy 417.28009 -304.924714) (xy 417.619192 -304.924714) (xy 417.623152 -304.87566) (xy 417.634929 -304.827876)
			(xy 417.65422 -304.7826) (xy 417.680523 -304.741004) (xy 417.713158 -304.704167) (xy 417.751279 -304.673042)
			(xy 417.7939 -304.648435) (xy 417.839916 -304.630983) (xy 417.888135 -304.621139) (xy 417.93731 -304.619158)
			(xy 417.986165 -304.62509) (xy 418.033436 -304.638782) (xy 418.077898 -304.65988) (xy 418.118401 -304.687836)
			(xy 418.153894 -304.721928) (xy 418.183459 -304.761272) (xy 418.20633 -304.804849) (xy 418.221914 -304.85153)
			(xy 418.229809 -304.900107) (xy 418.230304 -304.924714) (xy 418.569152 -304.924714) (xy 418.573112 -304.87566)
			(xy 418.584889 -304.827876) (xy 418.60418 -304.7826) (xy 418.630483 -304.741004) (xy 418.663118 -304.704167)
			(xy 418.701239 -304.673042) (xy 418.74386 -304.648435) (xy 418.789876 -304.630983) (xy 418.838095 -304.621139)
			(xy 418.88727 -304.619158) (xy 418.936125 -304.62509) (xy 418.983396 -304.638782) (xy 419.027858 -304.65988)
			(xy 419.068361 -304.687836) (xy 419.103854 -304.721928) (xy 419.133419 -304.761272) (xy 419.15629 -304.804849)
			(xy 419.171874 -304.85153) (xy 419.179769 -304.900107) (xy 419.180264 -304.924714) (xy 419.519112 -304.924714)
			(xy 419.523072 -304.87566) (xy 419.534849 -304.827876) (xy 419.55414 -304.7826) (xy 419.580443 -304.741004)
			(xy 419.613078 -304.704167) (xy 419.651199 -304.673042) (xy 419.69382 -304.648435) (xy 419.739836 -304.630983)
			(xy 419.788055 -304.621139) (xy 419.83723 -304.619158) (xy 419.886085 -304.62509) (xy 419.933356 -304.638782)
			(xy 419.977818 -304.65988) (xy 420.018321 -304.687836) (xy 420.053814 -304.721928) (xy 420.083379 -304.761272)
			(xy 420.10625 -304.804849) (xy 420.121834 -304.85153) (xy 420.129729 -304.900107) (xy 420.130224 -304.924714)
			(xy 420.469072 -304.924714) (xy 420.473032 -304.87566) (xy 420.484809 -304.827876) (xy 420.5041 -304.7826)
			(xy 420.530403 -304.741004) (xy 420.563038 -304.704167) (xy 420.601159 -304.673042) (xy 420.64378 -304.648435)
			(xy 420.689796 -304.630983) (xy 420.738015 -304.621139) (xy 420.78719 -304.619158) (xy 420.836045 -304.62509)
			(xy 420.883316 -304.638782) (xy 420.927778 -304.65988) (xy 420.968281 -304.687836) (xy 421.003774 -304.721928)
			(xy 421.033339 -304.761272) (xy 421.05621 -304.804849) (xy 421.071794 -304.85153) (xy 421.079689 -304.900107)
			(xy 421.080184 -304.924714) (xy 421.419032 -304.924714) (xy 421.422992 -304.87566) (xy 421.434769 -304.827876)
			(xy 421.45406 -304.7826) (xy 421.480363 -304.741004) (xy 421.512998 -304.704167) (xy 421.551119 -304.673042)
			(xy 421.59374 -304.648435) (xy 421.639756 -304.630983) (xy 421.687975 -304.621139) (xy 421.73715 -304.619158)
			(xy 421.786005 -304.62509) (xy 421.833276 -304.638782) (xy 421.877738 -304.65988) (xy 421.918241 -304.687836)
			(xy 421.953734 -304.721928) (xy 421.983299 -304.761272) (xy 421.993156 -304.780052) (xy 436.149734 -304.780052)
			(xy 436.149734 -304.725548) (xy 436.15749 -304.671598) (xy 436.172844 -304.619302) (xy 436.195484 -304.569722)
			(xy 436.224949 -304.523869) (xy 436.26064 -304.482675) (xy 436.301829 -304.446979) (xy 436.347678 -304.417508)
			(xy 436.397255 -304.394862) (xy 436.449549 -304.3795) (xy 436.503498 -304.371737) (xy 436.53075 -304.371248)
			(xy 436.557895 -304.371688) (xy 436.61164 -304.37937) (xy 436.663751 -304.3946) (xy 436.713173 -304.417069)
			(xy 436.758908 -304.446324) (xy 436.800029 -304.481771) (xy 436.835704 -304.522695) (xy 436.865213 -304.568266)
			(xy 436.887956 -304.617563) (xy 436.903475 -304.669588) (xy 436.90794 -304.696368) (xy 436.910763 -304.711197)
			(xy 436.923798 -304.738405) (xy 436.944204 -304.760626) (xy 436.970207 -304.775926) (xy 436.999542 -304.782973)
			(xy 437.029656 -304.781154) (xy 437.05793 -304.770627) (xy 437.070246 -304.7619) (xy 437.090311 -304.747097)
			(xy 437.133526 -304.722227) (xy 437.179611 -304.703192) (xy 437.227781 -304.690318) (xy 437.277218 -304.683822)
			(xy 437.302148 -304.683414) (xy 437.329399 -304.683859) (xy 437.383344 -304.691622) (xy 437.435636 -304.706982)
			(xy 437.48521 -304.729627) (xy 437.531057 -304.759096) (xy 437.572244 -304.79479) (xy 437.607933 -304.835981)
			(xy 437.637396 -304.881832) (xy 437.660035 -304.931409) (xy 437.675389 -304.983703) (xy 437.683144 -305.037649)
			(xy 437.683144 -305.064922) (xy 437.935114 -305.064922) (xy 437.939185 -305.0093) (xy 437.951311 -304.954863)
			(xy 437.971234 -304.902772) (xy 437.99853 -304.854137) (xy 438.032616 -304.809994) (xy 438.072765 -304.771285)
			(xy 438.118123 -304.738834) (xy 438.167723 -304.713333) (xy 438.220507 -304.695326) (xy 438.27535 -304.685196)
			(xy 438.331084 -304.683159) (xy 438.386521 -304.689259) (xy 438.440478 -304.703365) (xy 438.491807 -304.725177)
			(xy 438.539413 -304.754231) (xy 438.582281 -304.789906) (xy 438.619498 -304.831443) (xy 438.650271 -304.877956)
			(xy 438.673943 -304.928453) (xy 438.690011 -304.98186) (xy 438.698131 -305.037036) (xy 438.69864 -305.064922)
			(xy 438.943494 -305.064922) (xy 438.947565 -305.0093) (xy 438.959691 -304.954863) (xy 438.979614 -304.902772)
			(xy 439.00691 -304.854137) (xy 439.040996 -304.809994) (xy 439.081145 -304.771285) (xy 439.126503 -304.738834)
			(xy 439.176103 -304.713333) (xy 439.228887 -304.695326) (xy 439.28373 -304.685196) (xy 439.339464 -304.683159)
			(xy 439.394901 -304.689259) (xy 439.448858 -304.703365) (xy 439.500187 -304.725177) (xy 439.547793 -304.754231)
			(xy 439.590661 -304.789906) (xy 439.627878 -304.831443) (xy 439.658651 -304.877956) (xy 439.682323 -304.928453)
			(xy 439.698391 -304.98186) (xy 439.706511 -305.037036) (xy 439.707001 -305.063906) (xy 439.96813 -305.063906)
			(xy 439.972201 -305.008284) (xy 439.984327 -304.953847) (xy 440.00425 -304.901756) (xy 440.031546 -304.853121)
			(xy 440.065632 -304.808978) (xy 440.105781 -304.770269) (xy 440.151139 -304.737818) (xy 440.200739 -304.712317)
			(xy 440.253523 -304.69431) (xy 440.308366 -304.68418) (xy 440.3641 -304.682143) (xy 440.419537 -304.688243)
			(xy 440.473494 -304.702349) (xy 440.524823 -304.724161) (xy 440.572429 -304.753215) (xy 440.615297 -304.78889)
			(xy 440.652514 -304.830427) (xy 440.683287 -304.87694) (xy 440.706959 -304.927437) (xy 440.723027 -304.980844)
			(xy 440.731147 -305.03602) (xy 440.731331 -305.046126) (xy 440.98413 -305.046126) (xy 440.988201 -304.990504)
			(xy 441.000327 -304.936067) (xy 441.02025 -304.883976) (xy 441.047546 -304.835341) (xy 441.081632 -304.791198)
			(xy 441.121781 -304.752489) (xy 441.167139 -304.720038) (xy 441.216739 -304.694537) (xy 441.269523 -304.67653)
			(xy 441.324366 -304.6664) (xy 441.3801 -304.664363) (xy 441.435537 -304.670463) (xy 441.489494 -304.684569)
			(xy 441.540823 -304.706381) (xy 441.588429 -304.735435) (xy 441.631297 -304.77111) (xy 441.668514 -304.812647)
			(xy 441.699287 -304.85916) (xy 441.722959 -304.909657) (xy 441.739027 -304.963064) (xy 441.747147 -305.01824)
			(xy 441.747656 -305.046126) (xy 441.747147 -305.074012) (xy 441.739027 -305.129188) (xy 441.722959 -305.182595)
			(xy 441.699287 -305.233092) (xy 441.668514 -305.279605) (xy 441.631297 -305.321142) (xy 441.588429 -305.356817)
			(xy 441.540823 -305.385871) (xy 441.489494 -305.407683) (xy 441.435537 -305.421789) (xy 441.3801 -305.427889)
			(xy 441.324366 -305.425852) (xy 441.269523 -305.415722) (xy 441.216739 -305.397715) (xy 441.167139 -305.372214)
			(xy 441.121781 -305.339763) (xy 441.081632 -305.301054) (xy 441.047546 -305.256911) (xy 441.02025 -305.208276)
			(xy 441.000327 -305.156185) (xy 440.988201 -305.101748) (xy 440.98413 -305.046126) (xy 440.731331 -305.046126)
			(xy 440.731656 -305.063906) (xy 440.731147 -305.091792) (xy 440.723027 -305.146968) (xy 440.706959 -305.200375)
			(xy 440.683287 -305.250872) (xy 440.652514 -305.297385) (xy 440.615297 -305.338922) (xy 440.572429 -305.374597)
			(xy 440.524823 -305.403651) (xy 440.473494 -305.425463) (xy 440.419537 -305.439569) (xy 440.3641 -305.445669)
			(xy 440.308366 -305.443632) (xy 440.253523 -305.433502) (xy 440.200739 -305.415495) (xy 440.151139 -305.389994)
			(xy 440.105781 -305.357543) (xy 440.065632 -305.318834) (xy 440.031546 -305.274691) (xy 440.00425 -305.226056)
			(xy 439.984327 -305.173965) (xy 439.972201 -305.119528) (xy 439.96813 -305.063906) (xy 439.707001 -305.063906)
			(xy 439.70702 -305.064922) (xy 439.706511 -305.092808) (xy 439.698391 -305.147984) (xy 439.682323 -305.201391)
			(xy 439.658651 -305.251888) (xy 439.627878 -305.298401) (xy 439.590661 -305.339938) (xy 439.547793 -305.375613)
			(xy 439.500187 -305.404667) (xy 439.448858 -305.426479) (xy 439.394901 -305.440585) (xy 439.339464 -305.446685)
			(xy 439.28373 -305.444648) (xy 439.228887 -305.434518) (xy 439.176103 -305.416511) (xy 439.126503 -305.39101)
			(xy 439.081145 -305.358559) (xy 439.040996 -305.31985) (xy 439.00691 -305.275707) (xy 438.979614 -305.227072)
			(xy 438.959691 -305.174981) (xy 438.947565 -305.120544) (xy 438.943494 -305.064922) (xy 438.69864 -305.064922)
			(xy 438.698131 -305.092808) (xy 438.690011 -305.147984) (xy 438.673943 -305.201391) (xy 438.650271 -305.251888)
			(xy 438.619498 -305.298401) (xy 438.582281 -305.339938) (xy 438.539413 -305.375613) (xy 438.491807 -305.404667)
			(xy 438.440478 -305.426479) (xy 438.386521 -305.440585) (xy 438.331084 -305.446685) (xy 438.27535 -305.444648)
			(xy 438.220507 -305.434518) (xy 438.167723 -305.416511) (xy 438.118123 -305.39101) (xy 438.072765 -305.358559)
			(xy 438.032616 -305.31985) (xy 437.99853 -305.275707) (xy 437.971234 -305.227072) (xy 437.951311 -305.174981)
			(xy 437.939185 -305.120544) (xy 437.935114 -305.064922) (xy 437.683144 -305.064922) (xy 437.683144 -305.092151)
			(xy 437.675389 -305.146097) (xy 437.660035 -305.198391) (xy 437.637396 -305.247968) (xy 437.607933 -305.293819)
			(xy 437.572244 -305.33501) (xy 437.531057 -305.370704) (xy 437.48521 -305.400173) (xy 437.435636 -305.422818)
			(xy 437.383344 -305.438178) (xy 437.329399 -305.445941) (xy 437.302148 -305.44643) (xy 437.275002 -305.44601)
			(xy 437.221256 -305.438328) (xy 437.169143 -305.423097) (xy 437.119719 -305.400625) (xy 437.073984 -305.371369)
			(xy 437.032863 -305.335919) (xy 436.997188 -305.294993) (xy 436.96768 -305.249419) (xy 436.944938 -305.200119)
			(xy 436.929421 -305.148091) (xy 436.924958 -305.12131) (xy 436.922149 -305.106479) (xy 436.909109 -305.079272)
			(xy 436.8887 -305.057053) (xy 436.862695 -305.041755) (xy 436.83336 -305.034708) (xy 436.803244 -305.036527)
			(xy 436.774969 -305.047052) (xy 436.762652 -305.055778) (xy 436.742596 -305.070592) (xy 436.699377 -305.095459)
			(xy 436.65329 -305.11449) (xy 436.605118 -305.127362) (xy 436.555681 -305.133857) (xy 436.53075 -305.134264)
			(xy 436.503498 -305.133863) (xy 436.449549 -305.1261) (xy 436.397255 -305.110738) (xy 436.347678 -305.088092)
			(xy 436.301829 -305.058621) (xy 436.26064 -305.022925) (xy 436.224949 -304.981731) (xy 436.195484 -304.935878)
			(xy 436.172844 -304.886298) (xy 436.15749 -304.834002) (xy 436.149734 -304.780052) (xy 421.993156 -304.780052)
			(xy 422.00617 -304.804849) (xy 422.021754 -304.85153) (xy 422.029649 -304.900107) (xy 422.030144 -304.924714)
			(xy 422.029649 -304.949321) (xy 422.021754 -304.997898) (xy 422.00617 -305.044579) (xy 421.983299 -305.088156)
			(xy 421.953734 -305.1275) (xy 421.918241 -305.161592) (xy 421.877738 -305.189548) (xy 421.833276 -305.210646)
			(xy 421.786005 -305.224338) (xy 421.73715 -305.23027) (xy 421.687975 -305.228289) (xy 421.639756 -305.218445)
			(xy 421.59374 -305.200993) (xy 421.551119 -305.176386) (xy 421.512998 -305.145261) (xy 421.480363 -305.108424)
			(xy 421.45406 -305.066828) (xy 421.434769 -305.021552) (xy 421.422992 -304.973768) (xy 421.419032 -304.924714)
			(xy 421.080184 -304.924714) (xy 421.079689 -304.949321) (xy 421.071794 -304.997898) (xy 421.05621 -305.044579)
			(xy 421.033339 -305.088156) (xy 421.003774 -305.1275) (xy 420.968281 -305.161592) (xy 420.927778 -305.189548)
			(xy 420.883316 -305.210646) (xy 420.836045 -305.224338) (xy 420.78719 -305.23027) (xy 420.738015 -305.228289)
			(xy 420.689796 -305.218445) (xy 420.64378 -305.200993) (xy 420.601159 -305.176386) (xy 420.563038 -305.145261)
			(xy 420.530403 -305.108424) (xy 420.5041 -305.066828) (xy 420.484809 -305.021552) (xy 420.473032 -304.973768)
			(xy 420.469072 -304.924714) (xy 420.130224 -304.924714) (xy 420.129729 -304.949321) (xy 420.121834 -304.997898)
			(xy 420.10625 -305.044579) (xy 420.083379 -305.088156) (xy 420.053814 -305.1275) (xy 420.018321 -305.161592)
			(xy 419.977818 -305.189548) (xy 419.933356 -305.210646) (xy 419.886085 -305.224338) (xy 419.83723 -305.23027)
			(xy 419.788055 -305.228289) (xy 419.739836 -305.218445) (xy 419.69382 -305.200993) (xy 419.651199 -305.176386)
			(xy 419.613078 -305.145261) (xy 419.580443 -305.108424) (xy 419.55414 -305.066828) (xy 419.534849 -305.021552)
			(xy 419.523072 -304.973768) (xy 419.519112 -304.924714) (xy 419.180264 -304.924714) (xy 419.179769 -304.949321)
			(xy 419.171874 -304.997898) (xy 419.15629 -305.044579) (xy 419.133419 -305.088156) (xy 419.103854 -305.1275)
			(xy 419.068361 -305.161592) (xy 419.027858 -305.189548) (xy 418.983396 -305.210646) (xy 418.936125 -305.224338)
			(xy 418.88727 -305.23027) (xy 418.838095 -305.228289) (xy 418.789876 -305.218445) (xy 418.74386 -305.200993)
			(xy 418.701239 -305.176386) (xy 418.663118 -305.145261) (xy 418.630483 -305.108424) (xy 418.60418 -305.066828)
			(xy 418.584889 -305.021552) (xy 418.573112 -304.973768) (xy 418.569152 -304.924714) (xy 418.230304 -304.924714)
			(xy 418.229809 -304.949321) (xy 418.221914 -304.997898) (xy 418.20633 -305.044579) (xy 418.183459 -305.088156)
			(xy 418.153894 -305.1275) (xy 418.118401 -305.161592) (xy 418.077898 -305.189548) (xy 418.033436 -305.210646)
			(xy 417.986165 -305.224338) (xy 417.93731 -305.23027) (xy 417.888135 -305.228289) (xy 417.839916 -305.218445)
			(xy 417.7939 -305.200993) (xy 417.751279 -305.176386) (xy 417.713158 -305.145261) (xy 417.680523 -305.108424)
			(xy 417.65422 -305.066828) (xy 417.634929 -305.021552) (xy 417.623152 -304.973768) (xy 417.619192 -304.924714)
			(xy 417.28009 -304.924714) (xy 417.279595 -304.949321) (xy 417.2717 -304.997898) (xy 417.256116 -305.044579)
			(xy 417.233245 -305.088156) (xy 417.20368 -305.1275) (xy 417.168187 -305.161592) (xy 417.127684 -305.189548)
			(xy 417.083222 -305.210646) (xy 417.035951 -305.224338) (xy 416.987096 -305.23027) (xy 416.937921 -305.228289)
			(xy 416.889702 -305.218445) (xy 416.843686 -305.200993) (xy 416.801065 -305.176386) (xy 416.762944 -305.145261)
			(xy 416.730309 -305.108424) (xy 416.704006 -305.066828) (xy 416.684715 -305.021552) (xy 416.672938 -304.973768)
			(xy 416.668978 -304.924714) (xy 416.33013 -304.924714) (xy 416.329635 -304.949321) (xy 416.32174 -304.997898)
			(xy 416.306156 -305.044579) (xy 416.283285 -305.088156) (xy 416.25372 -305.1275) (xy 416.218227 -305.161592)
			(xy 416.177724 -305.189548) (xy 416.133262 -305.210646) (xy 416.085991 -305.224338) (xy 416.037136 -305.23027)
			(xy 415.987961 -305.228289) (xy 415.939742 -305.218445) (xy 415.893726 -305.200993) (xy 415.851105 -305.176386)
			(xy 415.812984 -305.145261) (xy 415.780349 -305.108424) (xy 415.754046 -305.066828) (xy 415.734755 -305.021552)
			(xy 415.722978 -304.973768) (xy 415.719018 -304.924714) (xy 415.38017 -304.924714) (xy 415.379675 -304.949321)
			(xy 415.37178 -304.997898) (xy 415.356196 -305.044579) (xy 415.333325 -305.088156) (xy 415.30376 -305.1275)
			(xy 415.268267 -305.161592) (xy 415.227764 -305.189548) (xy 415.183302 -305.210646) (xy 415.136031 -305.224338)
			(xy 415.087176 -305.23027) (xy 415.038001 -305.228289) (xy 414.989782 -305.218445) (xy 414.943766 -305.200993)
			(xy 414.901145 -305.176386) (xy 414.863024 -305.145261) (xy 414.830389 -305.108424) (xy 414.804086 -305.066828)
			(xy 414.784795 -305.021552) (xy 414.773018 -304.973768) (xy 414.769058 -304.924714) (xy 414.43021 -304.924714)
			(xy 414.429715 -304.949321) (xy 414.42182 -304.997898) (xy 414.406236 -305.044579) (xy 414.383365 -305.088156)
			(xy 414.3538 -305.1275) (xy 414.318307 -305.161592) (xy 414.277804 -305.189548) (xy 414.233342 -305.210646)
			(xy 414.186071 -305.224338) (xy 414.137216 -305.23027) (xy 414.088041 -305.228289) (xy 414.039822 -305.218445)
			(xy 413.993806 -305.200993) (xy 413.951185 -305.176386) (xy 413.913064 -305.145261) (xy 413.880429 -305.108424)
			(xy 413.854126 -305.066828) (xy 413.834835 -305.021552) (xy 413.823058 -304.973768) (xy 413.819098 -304.924714)
			(xy 413.48025 -304.924714) (xy 413.479755 -304.949321) (xy 413.47186 -304.997898) (xy 413.456276 -305.044579)
			(xy 413.433405 -305.088156) (xy 413.40384 -305.1275) (xy 413.368347 -305.161592) (xy 413.327844 -305.189548)
			(xy 413.283382 -305.210646) (xy 413.236111 -305.224338) (xy 413.187256 -305.23027) (xy 413.138081 -305.228289)
			(xy 413.089862 -305.218445) (xy 413.043846 -305.200993) (xy 413.001225 -305.176386) (xy 412.963104 -305.145261)
			(xy 412.930469 -305.108424) (xy 412.904166 -305.066828) (xy 412.884875 -305.021552) (xy 412.873098 -304.973768)
			(xy 412.869138 -304.924714) (xy 412.53029 -304.924714) (xy 412.529795 -304.949321) (xy 412.5219 -304.997898)
			(xy 412.506316 -305.044579) (xy 412.483445 -305.088156) (xy 412.45388 -305.1275) (xy 412.418387 -305.161592)
			(xy 412.377884 -305.189548) (xy 412.333422 -305.210646) (xy 412.286151 -305.224338) (xy 412.237296 -305.23027)
			(xy 412.188121 -305.228289) (xy 412.139902 -305.218445) (xy 412.093886 -305.200993) (xy 412.051265 -305.176386)
			(xy 412.013144 -305.145261) (xy 411.980509 -305.108424) (xy 411.954206 -305.066828) (xy 411.934915 -305.021552)
			(xy 411.923138 -304.973768) (xy 411.919178 -304.924714) (xy 411.58033 -304.924714) (xy 411.579835 -304.949321)
			(xy 411.57194 -304.997898) (xy 411.556356 -305.044579) (xy 411.533485 -305.088156) (xy 411.50392 -305.1275)
			(xy 411.468427 -305.161592) (xy 411.427924 -305.189548) (xy 411.383462 -305.210646) (xy 411.336191 -305.224338)
			(xy 411.287336 -305.23027) (xy 411.238161 -305.228289) (xy 411.189942 -305.218445) (xy 411.143926 -305.200993)
			(xy 411.101305 -305.176386) (xy 411.063184 -305.145261) (xy 411.030549 -305.108424) (xy 411.004246 -305.066828)
			(xy 410.984955 -305.021552) (xy 410.973178 -304.973768) (xy 410.969218 -304.924714) (xy 410.630116 -304.924714)
			(xy 410.629621 -304.949321) (xy 410.621726 -304.997898) (xy 410.606142 -305.044579) (xy 410.583271 -305.088156)
			(xy 410.553706 -305.1275) (xy 410.518213 -305.161592) (xy 410.47771 -305.189548) (xy 410.433248 -305.210646)
			(xy 410.385977 -305.224338) (xy 410.337122 -305.23027) (xy 410.287947 -305.228289) (xy 410.239728 -305.218445)
			(xy 410.193712 -305.200993) (xy 410.151091 -305.176386) (xy 410.11297 -305.145261) (xy 410.080335 -305.108424)
			(xy 410.054032 -305.066828) (xy 410.034741 -305.021552) (xy 410.022964 -304.973768) (xy 410.019004 -304.924714)
			(xy 409.680156 -304.924714) (xy 409.679661 -304.949321) (xy 409.671766 -304.997898) (xy 409.656182 -305.044579)
			(xy 409.633311 -305.088156) (xy 409.603746 -305.1275) (xy 409.568253 -305.161592) (xy 409.52775 -305.189548)
			(xy 409.483288 -305.210646) (xy 409.436017 -305.224338) (xy 409.387162 -305.23027) (xy 409.337987 -305.228289)
			(xy 409.289768 -305.218445) (xy 409.243752 -305.200993) (xy 409.201131 -305.176386) (xy 409.16301 -305.145261)
			(xy 409.130375 -305.108424) (xy 409.104072 -305.066828) (xy 409.084781 -305.021552) (xy 409.073004 -304.973768)
			(xy 409.069044 -304.924714) (xy 408.730196 -304.924714) (xy 408.729701 -304.949321) (xy 408.721806 -304.997898)
			(xy 408.706222 -305.044579) (xy 408.683351 -305.088156) (xy 408.653786 -305.1275) (xy 408.618293 -305.161592)
			(xy 408.57779 -305.189548) (xy 408.533328 -305.210646) (xy 408.486057 -305.224338) (xy 408.437202 -305.23027)
			(xy 408.388027 -305.228289) (xy 408.339808 -305.218445) (xy 408.293792 -305.200993) (xy 408.251171 -305.176386)
			(xy 408.21305 -305.145261) (xy 408.180415 -305.108424) (xy 408.154112 -305.066828) (xy 408.134821 -305.021552)
			(xy 408.123044 -304.973768) (xy 408.119084 -304.924714) (xy 406.830276 -304.924714) (xy 406.829781 -304.949321)
			(xy 406.821886 -304.997898) (xy 406.806302 -305.044579) (xy 406.783431 -305.088156) (xy 406.753866 -305.1275)
			(xy 406.718373 -305.161592) (xy 406.67787 -305.189548) (xy 406.633408 -305.210646) (xy 406.586137 -305.224338)
			(xy 406.537282 -305.23027) (xy 406.488107 -305.228289) (xy 406.439888 -305.218445) (xy 406.393872 -305.200993)
			(xy 406.351251 -305.176386) (xy 406.31313 -305.145261) (xy 406.280495 -305.108424) (xy 406.254192 -305.066828)
			(xy 406.234901 -305.021552) (xy 406.223124 -304.973768) (xy 406.219164 -304.924714) (xy 405.880316 -304.924714)
			(xy 405.879821 -304.949321) (xy 405.871926 -304.997898) (xy 405.856342 -305.044579) (xy 405.833471 -305.088156)
			(xy 405.803906 -305.1275) (xy 405.768413 -305.161592) (xy 405.72791 -305.189548) (xy 405.683448 -305.210646)
			(xy 405.636177 -305.224338) (xy 405.587322 -305.23027) (xy 405.538147 -305.228289) (xy 405.489928 -305.218445)
			(xy 405.443912 -305.200993) (xy 405.401291 -305.176386) (xy 405.36317 -305.145261) (xy 405.330535 -305.108424)
			(xy 405.304232 -305.066828) (xy 405.284941 -305.021552) (xy 405.273164 -304.973768) (xy 405.269204 -304.924714)
			(xy 404.930102 -304.924714) (xy 404.929607 -304.949321) (xy 404.921712 -304.997898) (xy 404.906128 -305.044579)
			(xy 404.883257 -305.088156) (xy 404.853692 -305.1275) (xy 404.818199 -305.161592) (xy 404.777696 -305.189548)
			(xy 404.733234 -305.210646) (xy 404.685963 -305.224338) (xy 404.637108 -305.23027) (xy 404.587933 -305.228289)
			(xy 404.539714 -305.218445) (xy 404.493698 -305.200993) (xy 404.451077 -305.176386) (xy 404.412956 -305.145261)
			(xy 404.380321 -305.108424) (xy 404.354018 -305.066828) (xy 404.334727 -305.021552) (xy 404.32295 -304.973768)
			(xy 404.31899 -304.924714) (xy 403.980142 -304.924714) (xy 403.979647 -304.949321) (xy 403.971752 -304.997898)
			(xy 403.956168 -305.044579) (xy 403.933297 -305.088156) (xy 403.903732 -305.1275) (xy 403.868239 -305.161592)
			(xy 403.827736 -305.189548) (xy 403.783274 -305.210646) (xy 403.736003 -305.224338) (xy 403.687148 -305.23027)
			(xy 403.637973 -305.228289) (xy 403.589754 -305.218445) (xy 403.543738 -305.200993) (xy 403.501117 -305.176386)
			(xy 403.462996 -305.145261) (xy 403.430361 -305.108424) (xy 403.404058 -305.066828) (xy 403.384767 -305.021552)
			(xy 403.37299 -304.973768) (xy 403.36903 -304.924714) (xy 403.030182 -304.924714) (xy 403.029687 -304.949321)
			(xy 403.021792 -304.997898) (xy 403.006208 -305.044579) (xy 402.983337 -305.088156) (xy 402.953772 -305.1275)
			(xy 402.918279 -305.161592) (xy 402.877776 -305.189548) (xy 402.833314 -305.210646) (xy 402.786043 -305.224338)
			(xy 402.737188 -305.23027) (xy 402.688013 -305.228289) (xy 402.639794 -305.218445) (xy 402.593778 -305.200993)
			(xy 402.551157 -305.176386) (xy 402.513036 -305.145261) (xy 402.480401 -305.108424) (xy 402.454098 -305.066828)
			(xy 402.434807 -305.021552) (xy 402.42303 -304.973768) (xy 402.41907 -304.924714) (xy 402.080222 -304.924714)
			(xy 402.079727 -304.949321) (xy 402.071832 -304.997898) (xy 402.056248 -305.044579) (xy 402.033377 -305.088156)
			(xy 402.003812 -305.1275) (xy 401.968319 -305.161592) (xy 401.927816 -305.189548) (xy 401.883354 -305.210646)
			(xy 401.836083 -305.224338) (xy 401.787228 -305.23027) (xy 401.738053 -305.228289) (xy 401.689834 -305.218445)
			(xy 401.643818 -305.200993) (xy 401.601197 -305.176386) (xy 401.563076 -305.145261) (xy 401.530441 -305.108424)
			(xy 401.504138 -305.066828) (xy 401.484847 -305.021552) (xy 401.47307 -304.973768) (xy 401.46911 -304.924714)
			(xy 401.130262 -304.924714) (xy 401.129767 -304.949321) (xy 401.121872 -304.997898) (xy 401.106288 -305.044579)
			(xy 401.083417 -305.088156) (xy 401.053852 -305.1275) (xy 401.018359 -305.161592) (xy 400.977856 -305.189548)
			(xy 400.933394 -305.210646) (xy 400.886123 -305.224338) (xy 400.837268 -305.23027) (xy 400.788093 -305.228289)
			(xy 400.739874 -305.218445) (xy 400.693858 -305.200993) (xy 400.651237 -305.176386) (xy 400.613116 -305.145261)
			(xy 400.580481 -305.108424) (xy 400.554178 -305.066828) (xy 400.534887 -305.021552) (xy 400.52311 -304.973768)
			(xy 400.51915 -304.924714) (xy 400.180302 -304.924714) (xy 400.179807 -304.949321) (xy 400.171912 -304.997898)
			(xy 400.156328 -305.044579) (xy 400.133457 -305.088156) (xy 400.103892 -305.1275) (xy 400.068399 -305.161592)
			(xy 400.027896 -305.189548) (xy 399.983434 -305.210646) (xy 399.936163 -305.224338) (xy 399.887308 -305.23027)
			(xy 399.838133 -305.228289) (xy 399.789914 -305.218445) (xy 399.743898 -305.200993) (xy 399.701277 -305.176386)
			(xy 399.663156 -305.145261) (xy 399.630521 -305.108424) (xy 399.604218 -305.066828) (xy 399.584927 -305.021552)
			(xy 399.57315 -304.973768) (xy 399.56919 -304.924714) (xy 399.230342 -304.924714) (xy 399.229847 -304.949321)
			(xy 399.221952 -304.997898) (xy 399.206368 -305.044579) (xy 399.183497 -305.088156) (xy 399.153932 -305.1275)
			(xy 399.118439 -305.161592) (xy 399.077936 -305.189548) (xy 399.033474 -305.210646) (xy 398.986203 -305.224338)
			(xy 398.937348 -305.23027) (xy 398.888173 -305.228289) (xy 398.839954 -305.218445) (xy 398.793938 -305.200993)
			(xy 398.751317 -305.176386) (xy 398.713196 -305.145261) (xy 398.680561 -305.108424) (xy 398.654258 -305.066828)
			(xy 398.634967 -305.021552) (xy 398.62319 -304.973768) (xy 398.61923 -304.924714) (xy 398.280128 -304.924714)
			(xy 398.279633 -304.949321) (xy 398.271738 -304.997898) (xy 398.256154 -305.044579) (xy 398.233283 -305.088156)
			(xy 398.203718 -305.1275) (xy 398.168225 -305.161592) (xy 398.127722 -305.189548) (xy 398.08326 -305.210646)
			(xy 398.035989 -305.224338) (xy 397.987134 -305.23027) (xy 397.937959 -305.228289) (xy 397.88974 -305.218445)
			(xy 397.843724 -305.200993) (xy 397.801103 -305.176386) (xy 397.762982 -305.145261) (xy 397.730347 -305.108424)
			(xy 397.704044 -305.066828) (xy 397.684753 -305.021552) (xy 397.672976 -304.973768) (xy 397.669016 -304.924714)
			(xy 397.355133 -304.924714) (xy 397.355133 -304.951063) (xy 397.346769 -305.003116) (xy 397.330253 -305.053184)
			(xy 397.306004 -305.099997) (xy 397.274636 -305.142371) (xy 397.236942 -305.179232) (xy 397.193879 -305.209647)
			(xy 397.146536 -305.232845) (xy 397.096112 -305.248239) (xy 397.070072 -305.252374) (xy 397.066008 -305.252882)
			(xy 397.054578 -305.256438) (xy 397.05026 -305.257708) (xy 397.02613 -305.268884) (xy 397.019526 -305.275996)
			(xy 397.004794 -305.29149) (xy 396.996666 -305.302666) (xy 396.99397 -305.308197) (xy 396.991014 -305.320138)
			(xy 396.990824 -305.326288) (xy 396.990824 -305.473354) (xy 396.990992 -305.479508) (xy 396.993942 -305.491456)
			(xy 396.996666 -305.496976) (xy 397.004794 -305.508152) (xy 397.019526 -305.523646) (xy 397.02613 -305.530758)
			(xy 397.05026 -305.541934) (xy 397.054578 -305.543204) (xy 397.066008 -305.54676) (xy 397.070072 -305.547268)
			(xy 397.096114 -305.551376) (xy 397.146536 -305.56677) (xy 397.193877 -305.589968) (xy 397.236938 -305.620382)
			(xy 397.274629 -305.657242) (xy 397.305995 -305.699615) (xy 397.330243 -305.746427) (xy 397.346757 -305.796493)
			(xy 397.355119 -305.848544) (xy 397.355119 -305.874928) (xy 397.669016 -305.874928) (xy 397.672976 -305.825874)
			(xy 397.684753 -305.77809) (xy 397.704044 -305.732814) (xy 397.730347 -305.691218) (xy 397.762982 -305.654381)
			(xy 397.801103 -305.623256) (xy 397.843724 -305.598649) (xy 397.88974 -305.581197) (xy 397.937959 -305.571353)
			(xy 397.987134 -305.569372) (xy 398.035989 -305.575304) (xy 398.08326 -305.588996) (xy 398.127722 -305.610094)
			(xy 398.168225 -305.63805) (xy 398.203718 -305.672142) (xy 398.233283 -305.711486) (xy 398.256154 -305.755063)
			(xy 398.271738 -305.801744) (xy 398.279633 -305.850321) (xy 398.280128 -305.874928) (xy 398.61923 -305.874928)
			(xy 398.62319 -305.825874) (xy 398.634967 -305.77809) (xy 398.654258 -305.732814) (xy 398.680561 -305.691218)
			(xy 398.713196 -305.654381) (xy 398.751317 -305.623256) (xy 398.793938 -305.598649) (xy 398.839954 -305.581197)
			(xy 398.888173 -305.571353) (xy 398.937348 -305.569372) (xy 398.986203 -305.575304) (xy 399.033474 -305.588996)
			(xy 399.077936 -305.610094) (xy 399.118439 -305.63805) (xy 399.153932 -305.672142) (xy 399.183497 -305.711486)
			(xy 399.206368 -305.755063) (xy 399.221952 -305.801744) (xy 399.229847 -305.850321) (xy 399.230342 -305.874928)
			(xy 399.56919 -305.874928) (xy 399.57315 -305.825874) (xy 399.584927 -305.77809) (xy 399.604218 -305.732814)
			(xy 399.630521 -305.691218) (xy 399.663156 -305.654381) (xy 399.701277 -305.623256) (xy 399.743898 -305.598649)
			(xy 399.789914 -305.581197) (xy 399.838133 -305.571353) (xy 399.887308 -305.569372) (xy 399.936163 -305.575304)
			(xy 399.983434 -305.588996) (xy 400.027896 -305.610094) (xy 400.068399 -305.63805) (xy 400.103892 -305.672142)
			(xy 400.133457 -305.711486) (xy 400.156328 -305.755063) (xy 400.171912 -305.801744) (xy 400.179807 -305.850321)
			(xy 400.180302 -305.874928) (xy 400.51915 -305.874928) (xy 400.52311 -305.825874) (xy 400.534887 -305.77809)
			(xy 400.554178 -305.732814) (xy 400.580481 -305.691218) (xy 400.613116 -305.654381) (xy 400.651237 -305.623256)
			(xy 400.693858 -305.598649) (xy 400.739874 -305.581197) (xy 400.788093 -305.571353) (xy 400.837268 -305.569372)
			(xy 400.886123 -305.575304) (xy 400.933394 -305.588996) (xy 400.977856 -305.610094) (xy 401.018359 -305.63805)
			(xy 401.053852 -305.672142) (xy 401.083417 -305.711486) (xy 401.106288 -305.755063) (xy 401.121872 -305.801744)
			(xy 401.129767 -305.850321) (xy 401.130262 -305.874928) (xy 401.46911 -305.874928) (xy 401.47307 -305.825874)
			(xy 401.484847 -305.77809) (xy 401.504138 -305.732814) (xy 401.530441 -305.691218) (xy 401.563076 -305.654381)
			(xy 401.601197 -305.623256) (xy 401.643818 -305.598649) (xy 401.689834 -305.581197) (xy 401.738053 -305.571353)
			(xy 401.787228 -305.569372) (xy 401.836083 -305.575304) (xy 401.883354 -305.588996) (xy 401.927816 -305.610094)
			(xy 401.968319 -305.63805) (xy 402.003812 -305.672142) (xy 402.033377 -305.711486) (xy 402.056248 -305.755063)
			(xy 402.071832 -305.801744) (xy 402.079727 -305.850321) (xy 402.080222 -305.874928) (xy 402.41907 -305.874928)
			(xy 402.42303 -305.825874) (xy 402.434807 -305.77809) (xy 402.454098 -305.732814) (xy 402.480401 -305.691218)
			(xy 402.513036 -305.654381) (xy 402.551157 -305.623256) (xy 402.593778 -305.598649) (xy 402.639794 -305.581197)
			(xy 402.688013 -305.571353) (xy 402.737188 -305.569372) (xy 402.786043 -305.575304) (xy 402.833314 -305.588996)
			(xy 402.877776 -305.610094) (xy 402.918279 -305.63805) (xy 402.953772 -305.672142) (xy 402.983337 -305.711486)
			(xy 403.006208 -305.755063) (xy 403.021792 -305.801744) (xy 403.029687 -305.850321) (xy 403.030182 -305.874928)
			(xy 403.36903 -305.874928) (xy 403.37299 -305.825874) (xy 403.384767 -305.77809) (xy 403.404058 -305.732814)
			(xy 403.430361 -305.691218) (xy 403.462996 -305.654381) (xy 403.501117 -305.623256) (xy 403.543738 -305.598649)
			(xy 403.589754 -305.581197) (xy 403.637973 -305.571353) (xy 403.687148 -305.569372) (xy 403.736003 -305.575304)
			(xy 403.783274 -305.588996) (xy 403.827736 -305.610094) (xy 403.868239 -305.63805) (xy 403.903732 -305.672142)
			(xy 403.933297 -305.711486) (xy 403.956168 -305.755063) (xy 403.971752 -305.801744) (xy 403.979647 -305.850321)
			(xy 403.980142 -305.874928) (xy 404.31899 -305.874928) (xy 404.32295 -305.825874) (xy 404.334727 -305.77809)
			(xy 404.354018 -305.732814) (xy 404.380321 -305.691218) (xy 404.412956 -305.654381) (xy 404.451077 -305.623256)
			(xy 404.493698 -305.598649) (xy 404.539714 -305.581197) (xy 404.587933 -305.571353) (xy 404.637108 -305.569372)
			(xy 404.685963 -305.575304) (xy 404.733234 -305.588996) (xy 404.777696 -305.610094) (xy 404.818199 -305.63805)
			(xy 404.853692 -305.672142) (xy 404.883257 -305.711486) (xy 404.906128 -305.755063) (xy 404.921712 -305.801744)
			(xy 404.929607 -305.850321) (xy 404.930102 -305.874928) (xy 405.269204 -305.874928) (xy 405.273164 -305.825874)
			(xy 405.284941 -305.77809) (xy 405.304232 -305.732814) (xy 405.330535 -305.691218) (xy 405.36317 -305.654381)
			(xy 405.401291 -305.623256) (xy 405.443912 -305.598649) (xy 405.489928 -305.581197) (xy 405.538147 -305.571353)
			(xy 405.587322 -305.569372) (xy 405.636177 -305.575304) (xy 405.683448 -305.588996) (xy 405.72791 -305.610094)
			(xy 405.768413 -305.63805) (xy 405.803906 -305.672142) (xy 405.833471 -305.711486) (xy 405.856342 -305.755063)
			(xy 405.871926 -305.801744) (xy 405.879821 -305.850321) (xy 405.880316 -305.874928) (xy 406.219164 -305.874928)
			(xy 406.223124 -305.825874) (xy 406.234901 -305.77809) (xy 406.254192 -305.732814) (xy 406.280495 -305.691218)
			(xy 406.31313 -305.654381) (xy 406.351251 -305.623256) (xy 406.393872 -305.598649) (xy 406.439888 -305.581197)
			(xy 406.488107 -305.571353) (xy 406.537282 -305.569372) (xy 406.586137 -305.575304) (xy 406.633408 -305.588996)
			(xy 406.67787 -305.610094) (xy 406.718373 -305.63805) (xy 406.753866 -305.672142) (xy 406.783431 -305.711486)
			(xy 406.806302 -305.755063) (xy 406.821886 -305.801744) (xy 406.829781 -305.850321) (xy 406.830276 -305.874928)
			(xy 408.119084 -305.874928) (xy 408.123044 -305.825874) (xy 408.134821 -305.77809) (xy 408.154112 -305.732814)
			(xy 408.180415 -305.691218) (xy 408.21305 -305.654381) (xy 408.251171 -305.623256) (xy 408.293792 -305.598649)
			(xy 408.339808 -305.581197) (xy 408.388027 -305.571353) (xy 408.437202 -305.569372) (xy 408.486057 -305.575304)
			(xy 408.533328 -305.588996) (xy 408.57779 -305.610094) (xy 408.618293 -305.63805) (xy 408.653786 -305.672142)
			(xy 408.683351 -305.711486) (xy 408.706222 -305.755063) (xy 408.721806 -305.801744) (xy 408.729701 -305.850321)
			(xy 408.730196 -305.874928) (xy 409.069044 -305.874928) (xy 409.073004 -305.825874) (xy 409.084781 -305.77809)
			(xy 409.104072 -305.732814) (xy 409.130375 -305.691218) (xy 409.16301 -305.654381) (xy 409.201131 -305.623256)
			(xy 409.243752 -305.598649) (xy 409.289768 -305.581197) (xy 409.337987 -305.571353) (xy 409.387162 -305.569372)
			(xy 409.436017 -305.575304) (xy 409.483288 -305.588996) (xy 409.52775 -305.610094) (xy 409.568253 -305.63805)
			(xy 409.603746 -305.672142) (xy 409.633311 -305.711486) (xy 409.656182 -305.755063) (xy 409.671766 -305.801744)
			(xy 409.679661 -305.850321) (xy 409.680156 -305.874928) (xy 410.019004 -305.874928) (xy 410.022964 -305.825874)
			(xy 410.034741 -305.77809) (xy 410.054032 -305.732814) (xy 410.080335 -305.691218) (xy 410.11297 -305.654381)
			(xy 410.151091 -305.623256) (xy 410.193712 -305.598649) (xy 410.239728 -305.581197) (xy 410.287947 -305.571353)
			(xy 410.337122 -305.569372) (xy 410.385977 -305.575304) (xy 410.433248 -305.588996) (xy 410.47771 -305.610094)
			(xy 410.518213 -305.63805) (xy 410.553706 -305.672142) (xy 410.583271 -305.711486) (xy 410.606142 -305.755063)
			(xy 410.621726 -305.801744) (xy 410.629621 -305.850321) (xy 410.630116 -305.874928) (xy 410.969218 -305.874928)
			(xy 410.973178 -305.825874) (xy 410.984955 -305.77809) (xy 411.004246 -305.732814) (xy 411.030549 -305.691218)
			(xy 411.063184 -305.654381) (xy 411.101305 -305.623256) (xy 411.143926 -305.598649) (xy 411.189942 -305.581197)
			(xy 411.238161 -305.571353) (xy 411.287336 -305.569372) (xy 411.336191 -305.575304) (xy 411.383462 -305.588996)
			(xy 411.427924 -305.610094) (xy 411.468427 -305.63805) (xy 411.50392 -305.672142) (xy 411.533485 -305.711486)
			(xy 411.556356 -305.755063) (xy 411.57194 -305.801744) (xy 411.579835 -305.850321) (xy 411.58033 -305.874928)
			(xy 411.919178 -305.874928) (xy 411.923138 -305.825874) (xy 411.934915 -305.77809) (xy 411.954206 -305.732814)
			(xy 411.980509 -305.691218) (xy 412.013144 -305.654381) (xy 412.051265 -305.623256) (xy 412.093886 -305.598649)
			(xy 412.139902 -305.581197) (xy 412.188121 -305.571353) (xy 412.237296 -305.569372) (xy 412.286151 -305.575304)
			(xy 412.333422 -305.588996) (xy 412.377884 -305.610094) (xy 412.418387 -305.63805) (xy 412.45388 -305.672142)
			(xy 412.483445 -305.711486) (xy 412.506316 -305.755063) (xy 412.5219 -305.801744) (xy 412.529795 -305.850321)
			(xy 412.53029 -305.874928) (xy 412.869138 -305.874928) (xy 412.873098 -305.825874) (xy 412.884875 -305.77809)
			(xy 412.904166 -305.732814) (xy 412.930469 -305.691218) (xy 412.963104 -305.654381) (xy 413.001225 -305.623256)
			(xy 413.043846 -305.598649) (xy 413.089862 -305.581197) (xy 413.138081 -305.571353) (xy 413.187256 -305.569372)
			(xy 413.236111 -305.575304) (xy 413.283382 -305.588996) (xy 413.327844 -305.610094) (xy 413.368347 -305.63805)
			(xy 413.40384 -305.672142) (xy 413.433405 -305.711486) (xy 413.456276 -305.755063) (xy 413.47186 -305.801744)
			(xy 413.479755 -305.850321) (xy 413.48025 -305.874928) (xy 413.819098 -305.874928) (xy 413.823058 -305.825874)
			(xy 413.834835 -305.77809) (xy 413.854126 -305.732814) (xy 413.880429 -305.691218) (xy 413.913064 -305.654381)
			(xy 413.951185 -305.623256) (xy 413.993806 -305.598649) (xy 414.039822 -305.581197) (xy 414.088041 -305.571353)
			(xy 414.137216 -305.569372) (xy 414.186071 -305.575304) (xy 414.233342 -305.588996) (xy 414.277804 -305.610094)
			(xy 414.318307 -305.63805) (xy 414.3538 -305.672142) (xy 414.383365 -305.711486) (xy 414.406236 -305.755063)
			(xy 414.42182 -305.801744) (xy 414.429715 -305.850321) (xy 414.43021 -305.874928) (xy 414.769058 -305.874928)
			(xy 414.773018 -305.825874) (xy 414.784795 -305.77809) (xy 414.804086 -305.732814) (xy 414.830389 -305.691218)
			(xy 414.863024 -305.654381) (xy 414.901145 -305.623256) (xy 414.943766 -305.598649) (xy 414.989782 -305.581197)
			(xy 415.038001 -305.571353) (xy 415.087176 -305.569372) (xy 415.136031 -305.575304) (xy 415.183302 -305.588996)
			(xy 415.227764 -305.610094) (xy 415.268267 -305.63805) (xy 415.30376 -305.672142) (xy 415.333325 -305.711486)
			(xy 415.356196 -305.755063) (xy 415.37178 -305.801744) (xy 415.379675 -305.850321) (xy 415.38017 -305.874928)
			(xy 415.719018 -305.874928) (xy 415.722978 -305.825874) (xy 415.734755 -305.77809) (xy 415.754046 -305.732814)
			(xy 415.780349 -305.691218) (xy 415.812984 -305.654381) (xy 415.851105 -305.623256) (xy 415.893726 -305.598649)
			(xy 415.939742 -305.581197) (xy 415.987961 -305.571353) (xy 416.037136 -305.569372) (xy 416.085991 -305.575304)
			(xy 416.133262 -305.588996) (xy 416.177724 -305.610094) (xy 416.218227 -305.63805) (xy 416.25372 -305.672142)
			(xy 416.283285 -305.711486) (xy 416.306156 -305.755063) (xy 416.32174 -305.801744) (xy 416.329635 -305.850321)
			(xy 416.33013 -305.874928) (xy 416.668978 -305.874928) (xy 416.672938 -305.825874) (xy 416.684715 -305.77809)
			(xy 416.704006 -305.732814) (xy 416.730309 -305.691218) (xy 416.762944 -305.654381) (xy 416.801065 -305.623256)
			(xy 416.843686 -305.598649) (xy 416.889702 -305.581197) (xy 416.937921 -305.571353) (xy 416.987096 -305.569372)
			(xy 417.035951 -305.575304) (xy 417.083222 -305.588996) (xy 417.127684 -305.610094) (xy 417.168187 -305.63805)
			(xy 417.20368 -305.672142) (xy 417.233245 -305.711486) (xy 417.256116 -305.755063) (xy 417.2717 -305.801744)
			(xy 417.279595 -305.850321) (xy 417.28009 -305.874928) (xy 417.619192 -305.874928) (xy 417.623152 -305.825874)
			(xy 417.634929 -305.77809) (xy 417.65422 -305.732814) (xy 417.680523 -305.691218) (xy 417.713158 -305.654381)
			(xy 417.751279 -305.623256) (xy 417.7939 -305.598649) (xy 417.839916 -305.581197) (xy 417.888135 -305.571353)
			(xy 417.93731 -305.569372) (xy 417.986165 -305.575304) (xy 418.033436 -305.588996) (xy 418.077898 -305.610094)
			(xy 418.118401 -305.63805) (xy 418.153894 -305.672142) (xy 418.183459 -305.711486) (xy 418.20633 -305.755063)
			(xy 418.221914 -305.801744) (xy 418.229809 -305.850321) (xy 418.230304 -305.874928) (xy 418.569152 -305.874928)
			(xy 418.573112 -305.825874) (xy 418.584889 -305.77809) (xy 418.60418 -305.732814) (xy 418.630483 -305.691218)
			(xy 418.663118 -305.654381) (xy 418.701239 -305.623256) (xy 418.74386 -305.598649) (xy 418.789876 -305.581197)
			(xy 418.838095 -305.571353) (xy 418.88727 -305.569372) (xy 418.936125 -305.575304) (xy 418.983396 -305.588996)
			(xy 419.027858 -305.610094) (xy 419.068361 -305.63805) (xy 419.103854 -305.672142) (xy 419.133419 -305.711486)
			(xy 419.15629 -305.755063) (xy 419.171874 -305.801744) (xy 419.179769 -305.850321) (xy 419.180264 -305.874928)
			(xy 419.519112 -305.874928) (xy 419.523072 -305.825874) (xy 419.534849 -305.77809) (xy 419.55414 -305.732814)
			(xy 419.580443 -305.691218) (xy 419.613078 -305.654381) (xy 419.651199 -305.623256) (xy 419.69382 -305.598649)
			(xy 419.739836 -305.581197) (xy 419.788055 -305.571353) (xy 419.83723 -305.569372) (xy 419.886085 -305.575304)
			(xy 419.933356 -305.588996) (xy 419.977818 -305.610094) (xy 420.018321 -305.63805) (xy 420.053814 -305.672142)
			(xy 420.083379 -305.711486) (xy 420.10625 -305.755063) (xy 420.121834 -305.801744) (xy 420.129729 -305.850321)
			(xy 420.130224 -305.874928) (xy 420.469072 -305.874928) (xy 420.473032 -305.825874) (xy 420.484809 -305.77809)
			(xy 420.5041 -305.732814) (xy 420.530403 -305.691218) (xy 420.563038 -305.654381) (xy 420.601159 -305.623256)
			(xy 420.64378 -305.598649) (xy 420.689796 -305.581197) (xy 420.738015 -305.571353) (xy 420.78719 -305.569372)
			(xy 420.836045 -305.575304) (xy 420.883316 -305.588996) (xy 420.927778 -305.610094) (xy 420.968281 -305.63805)
			(xy 421.003774 -305.672142) (xy 421.033339 -305.711486) (xy 421.05621 -305.755063) (xy 421.071794 -305.801744)
			(xy 421.079689 -305.850321) (xy 421.080184 -305.874928) (xy 421.419032 -305.874928) (xy 421.422992 -305.825874)
			(xy 421.434769 -305.77809) (xy 421.45406 -305.732814) (xy 421.480363 -305.691218) (xy 421.512998 -305.654381)
			(xy 421.551119 -305.623256) (xy 421.59374 -305.598649) (xy 421.639756 -305.581197) (xy 421.687975 -305.571353)
			(xy 421.73715 -305.569372) (xy 421.786005 -305.575304) (xy 421.833276 -305.588996) (xy 421.877738 -305.610094)
			(xy 421.918241 -305.63805) (xy 421.953734 -305.672142) (xy 421.983299 -305.711486) (xy 422.00617 -305.755063)
			(xy 422.021754 -305.801744) (xy 422.029649 -305.850321) (xy 422.030143 -305.8749) (xy 422.368997 -305.8749)
			(xy 422.373168 -305.824567) (xy 422.385566 -305.775607) (xy 422.405854 -305.729355) (xy 422.433477 -305.687073)
			(xy 422.467684 -305.649915) (xy 422.507539 -305.618893) (xy 422.551958 -305.594855) (xy 422.599727 -305.578455)
			(xy 422.649543 -305.570142) (xy 422.674796 -305.56962) (xy 422.689043 -305.569789) (xy 422.717411 -305.572457)
			(xy 422.731438 -305.574954) (xy 422.74363 -305.57724) (xy 422.76776 -305.569874) (xy 422.844976 -305.492658)
			(xy 422.852342 -305.468782) (xy 422.850056 -305.456336) (xy 422.847575 -305.442371) (xy 422.844906 -305.414131)
			(xy 422.844722 -305.399948) (xy 422.845126 -305.375123) (xy 422.853151 -305.326125) (xy 422.868997 -305.279072)
			(xy 422.892247 -305.235202) (xy 422.922288 -305.195671) (xy 422.958329 -305.161521) (xy 422.99942 -305.133652)
			(xy 423.044478 -305.112798) (xy 423.092316 -305.099509) (xy 423.141675 -305.094134) (xy 423.191253 -305.096815)
			(xy 423.239743 -305.107482) (xy 423.28587 -305.125853) (xy 423.328416 -305.151445) (xy 423.366262 -305.183583)
			(xy 423.398409 -305.22142) (xy 423.424012 -305.26396) (xy 423.442395 -305.310082) (xy 423.453074 -305.35857)
			(xy 423.455322 -305.399948) (xy 423.794186 -305.399948) (xy 423.798146 -305.350894) (xy 423.809923 -305.30311)
			(xy 423.829214 -305.257834) (xy 423.855517 -305.216238) (xy 423.888152 -305.179401) (xy 423.926273 -305.148276)
			(xy 423.968894 -305.123669) (xy 424.01491 -305.106217) (xy 424.063129 -305.096373) (xy 424.112304 -305.094392)
			(xy 424.161159 -305.100324) (xy 424.20843 -305.114016) (xy 424.252892 -305.135114) (xy 424.293395 -305.16307)
			(xy 424.328888 -305.197162) (xy 424.358453 -305.236506) (xy 424.381324 -305.280083) (xy 424.396908 -305.326764)
			(xy 424.404803 -305.375341) (xy 424.405298 -305.399948) (xy 424.404803 -305.424555) (xy 424.404624 -305.425656)
			(xy 424.723302 -305.425656) (xy 424.723302 -305.37424) (xy 424.731345 -305.323458) (xy 424.747233 -305.274559)
			(xy 424.770576 -305.228747) (xy 424.800797 -305.187151) (xy 424.837153 -305.150795) (xy 424.878749 -305.120574)
			(xy 424.924561 -305.097231) (xy 424.97346 -305.081343) (xy 425.024242 -305.0733) (xy 425.075658 -305.0733)
			(xy 425.12644 -305.081343) (xy 425.175339 -305.097231) (xy 425.221151 -305.120574) (xy 425.262747 -305.150795)
			(xy 425.299103 -305.187151) (xy 425.329324 -305.228747) (xy 425.352667 -305.274559) (xy 425.368555 -305.323458)
			(xy 425.376598 -305.37424) (xy 425.377102 -305.399948) (xy 425.376598 -305.425656) (xy 425.673262 -305.425656)
			(xy 425.673262 -305.37424) (xy 425.681305 -305.323458) (xy 425.697193 -305.274559) (xy 425.720536 -305.228747)
			(xy 425.750757 -305.187151) (xy 425.787113 -305.150795) (xy 425.828709 -305.120574) (xy 425.874521 -305.097231)
			(xy 425.92342 -305.081343) (xy 425.974202 -305.0733) (xy 426.025618 -305.0733) (xy 426.0764 -305.081343)
			(xy 426.125299 -305.097231) (xy 426.171111 -305.120574) (xy 426.212707 -305.150795) (xy 426.249063 -305.187151)
			(xy 426.279284 -305.228747) (xy 426.302627 -305.274559) (xy 426.318515 -305.323458) (xy 426.326558 -305.37424)
			(xy 426.327062 -305.399948) (xy 426.644066 -305.399948) (xy 426.648026 -305.350894) (xy 426.659803 -305.30311)
			(xy 426.679094 -305.257834) (xy 426.705397 -305.216238) (xy 426.738032 -305.179401) (xy 426.776153 -305.148276)
			(xy 426.818774 -305.123669) (xy 426.86479 -305.106217) (xy 426.913009 -305.096373) (xy 426.962184 -305.094392)
			(xy 427.011039 -305.100324) (xy 427.05831 -305.114016) (xy 427.102772 -305.135114) (xy 427.143275 -305.16307)
			(xy 427.178768 -305.197162) (xy 427.208333 -305.236506) (xy 427.231204 -305.280083) (xy 427.246788 -305.326764)
			(xy 427.254683 -305.375341) (xy 427.255178 -305.399948) (xy 427.254683 -305.424555) (xy 427.254504 -305.425656)
			(xy 427.573182 -305.425656) (xy 427.573182 -305.37424) (xy 427.581225 -305.323458) (xy 427.597113 -305.274559)
			(xy 427.620456 -305.228747) (xy 427.650677 -305.187151) (xy 427.687033 -305.150795) (xy 427.728629 -305.120574)
			(xy 427.774441 -305.097231) (xy 427.82334 -305.081343) (xy 427.874122 -305.0733) (xy 427.925538 -305.0733)
			(xy 427.97632 -305.081343) (xy 428.025219 -305.097231) (xy 428.071031 -305.120574) (xy 428.112627 -305.150795)
			(xy 428.148983 -305.187151) (xy 428.179204 -305.228747) (xy 428.202547 -305.274559) (xy 428.218435 -305.323458)
			(xy 428.226478 -305.37424) (xy 428.226982 -305.399948) (xy 428.226478 -305.425656) (xy 428.523142 -305.425656)
			(xy 428.523142 -305.37424) (xy 428.531185 -305.323458) (xy 428.547073 -305.274559) (xy 428.570416 -305.228747)
			(xy 428.600637 -305.187151) (xy 428.636993 -305.150795) (xy 428.678589 -305.120574) (xy 428.724401 -305.097231)
			(xy 428.7733 -305.081343) (xy 428.824082 -305.0733) (xy 428.875498 -305.0733) (xy 428.92628 -305.081343)
			(xy 428.975179 -305.097231) (xy 429.020991 -305.120574) (xy 429.062587 -305.150795) (xy 429.098943 -305.187151)
			(xy 429.129164 -305.228747) (xy 429.152507 -305.274559) (xy 429.168395 -305.323458) (xy 429.176438 -305.37424)
			(xy 429.176942 -305.399948) (xy 429.4942 -305.399948) (xy 429.49816 -305.350894) (xy 429.509937 -305.30311)
			(xy 429.529228 -305.257834) (xy 429.555531 -305.216238) (xy 429.588166 -305.179401) (xy 429.626287 -305.148276)
			(xy 429.668908 -305.123669) (xy 429.714924 -305.106217) (xy 429.763143 -305.096373) (xy 429.812318 -305.094392)
			(xy 429.861173 -305.100324) (xy 429.908444 -305.114016) (xy 429.952906 -305.135114) (xy 429.993409 -305.16307)
			(xy 430.028902 -305.197162) (xy 430.058467 -305.236506) (xy 430.081338 -305.280083) (xy 430.096922 -305.326764)
			(xy 430.104817 -305.375341) (xy 430.105312 -305.399948) (xy 430.44416 -305.399948) (xy 430.44812 -305.350894)
			(xy 430.459897 -305.30311) (xy 430.479188 -305.257834) (xy 430.505491 -305.216238) (xy 430.538126 -305.179401)
			(xy 430.576247 -305.148276) (xy 430.618868 -305.123669) (xy 430.664884 -305.106217) (xy 430.713103 -305.096373)
			(xy 430.762278 -305.094392) (xy 430.811133 -305.100324) (xy 430.858404 -305.114016) (xy 430.902866 -305.135114)
			(xy 430.943369 -305.16307) (xy 430.978862 -305.197162) (xy 431.008427 -305.236506) (xy 431.031298 -305.280083)
			(xy 431.046882 -305.326764) (xy 431.054777 -305.375341) (xy 431.055272 -305.399948) (xy 431.054777 -305.424555)
			(xy 431.046882 -305.473132) (xy 431.031298 -305.519813) (xy 431.008427 -305.56339) (xy 430.978862 -305.602734)
			(xy 430.943369 -305.636826) (xy 430.902866 -305.664782) (xy 430.858404 -305.68588) (xy 430.811133 -305.699572)
			(xy 430.762278 -305.705504) (xy 430.713103 -305.703523) (xy 430.664884 -305.693679) (xy 430.618868 -305.676227)
			(xy 430.576247 -305.65162) (xy 430.538126 -305.620495) (xy 430.505491 -305.583658) (xy 430.479188 -305.542062)
			(xy 430.459897 -305.496786) (xy 430.44812 -305.449002) (xy 430.44416 -305.399948) (xy 430.105312 -305.399948)
			(xy 430.104817 -305.424555) (xy 430.096922 -305.473132) (xy 430.081338 -305.519813) (xy 430.058467 -305.56339)
			(xy 430.028902 -305.602734) (xy 429.993409 -305.636826) (xy 429.952906 -305.664782) (xy 429.908444 -305.68588)
			(xy 429.861173 -305.699572) (xy 429.812318 -305.705504) (xy 429.763143 -305.703523) (xy 429.714924 -305.693679)
			(xy 429.668908 -305.676227) (xy 429.626287 -305.65162) (xy 429.588166 -305.620495) (xy 429.555531 -305.583658)
			(xy 429.529228 -305.542062) (xy 429.509937 -305.496786) (xy 429.49816 -305.449002) (xy 429.4942 -305.399948)
			(xy 429.176942 -305.399948) (xy 429.176438 -305.425656) (xy 429.168395 -305.476438) (xy 429.152507 -305.525337)
			(xy 429.129164 -305.571149) (xy 429.098943 -305.612745) (xy 429.062587 -305.649101) (xy 429.020991 -305.679322)
			(xy 428.975179 -305.702665) (xy 428.92628 -305.718553) (xy 428.875498 -305.726596) (xy 428.824082 -305.726596)
			(xy 428.7733 -305.718553) (xy 428.724401 -305.702665) (xy 428.678589 -305.679322) (xy 428.636993 -305.649101)
			(xy 428.600637 -305.612745) (xy 428.570416 -305.571149) (xy 428.547073 -305.525337) (xy 428.531185 -305.476438)
			(xy 428.523142 -305.425656) (xy 428.226478 -305.425656) (xy 428.218435 -305.476438) (xy 428.202547 -305.525337)
			(xy 428.179204 -305.571149) (xy 428.148983 -305.612745) (xy 428.112627 -305.649101) (xy 428.071031 -305.679322)
			(xy 428.025219 -305.702665) (xy 427.97632 -305.718553) (xy 427.925538 -305.726596) (xy 427.874122 -305.726596)
			(xy 427.82334 -305.718553) (xy 427.774441 -305.702665) (xy 427.728629 -305.679322) (xy 427.687033 -305.649101)
			(xy 427.650677 -305.612745) (xy 427.620456 -305.571149) (xy 427.597113 -305.525337) (xy 427.581225 -305.476438)
			(xy 427.573182 -305.425656) (xy 427.254504 -305.425656) (xy 427.246788 -305.473132) (xy 427.231204 -305.519813)
			(xy 427.208333 -305.56339) (xy 427.178768 -305.602734) (xy 427.143275 -305.636826) (xy 427.102772 -305.664782)
			(xy 427.05831 -305.68588) (xy 427.011039 -305.699572) (xy 426.962184 -305.705504) (xy 426.913009 -305.703523)
			(xy 426.86479 -305.693679) (xy 426.818774 -305.676227) (xy 426.776153 -305.65162) (xy 426.738032 -305.620495)
			(xy 426.705397 -305.583658) (xy 426.679094 -305.542062) (xy 426.659803 -305.496786) (xy 426.648026 -305.449002)
			(xy 426.644066 -305.399948) (xy 426.327062 -305.399948) (xy 426.326558 -305.425656) (xy 426.318515 -305.476438)
			(xy 426.302627 -305.525337) (xy 426.279284 -305.571149) (xy 426.249063 -305.612745) (xy 426.212707 -305.649101)
			(xy 426.171111 -305.679322) (xy 426.125299 -305.702665) (xy 426.0764 -305.718553) (xy 426.025618 -305.726596)
			(xy 425.974202 -305.726596) (xy 425.92342 -305.718553) (xy 425.874521 -305.702665) (xy 425.828709 -305.679322)
			(xy 425.787113 -305.649101) (xy 425.750757 -305.612745) (xy 425.720536 -305.571149) (xy 425.697193 -305.525337)
			(xy 425.681305 -305.476438) (xy 425.673262 -305.425656) (xy 425.376598 -305.425656) (xy 425.368555 -305.476438)
			(xy 425.352667 -305.525337) (xy 425.329324 -305.571149) (xy 425.299103 -305.612745) (xy 425.262747 -305.649101)
			(xy 425.221151 -305.679322) (xy 425.175339 -305.702665) (xy 425.12644 -305.718553) (xy 425.075658 -305.726596)
			(xy 425.024242 -305.726596) (xy 424.97346 -305.718553) (xy 424.924561 -305.702665) (xy 424.878749 -305.679322)
			(xy 424.837153 -305.649101) (xy 424.800797 -305.612745) (xy 424.770576 -305.571149) (xy 424.747233 -305.525337)
			(xy 424.731345 -305.476438) (xy 424.723302 -305.425656) (xy 424.404624 -305.425656) (xy 424.396908 -305.473132)
			(xy 424.381324 -305.519813) (xy 424.358453 -305.56339) (xy 424.328888 -305.602734) (xy 424.293395 -305.636826)
			(xy 424.252892 -305.664782) (xy 424.20843 -305.68588) (xy 424.161159 -305.699572) (xy 424.112304 -305.705504)
			(xy 424.063129 -305.703523) (xy 424.01491 -305.693679) (xy 423.968894 -305.676227) (xy 423.926273 -305.65162)
			(xy 423.888152 -305.620495) (xy 423.855517 -305.583658) (xy 423.829214 -305.542062) (xy 423.809923 -305.496786)
			(xy 423.798146 -305.449002) (xy 423.794186 -305.399948) (xy 423.455322 -305.399948) (xy 423.455768 -305.408147)
			(xy 423.450406 -305.457507) (xy 423.437129 -305.505349) (xy 423.416286 -305.550412) (xy 423.388428 -305.59151)
			(xy 423.354287 -305.62756) (xy 423.314764 -305.657611) (xy 423.2709 -305.680872) (xy 423.22385 -305.696731)
			(xy 423.174855 -305.704768) (xy 423.15003 -305.705256) (xy 423.135783 -305.705098) (xy 423.107415 -305.702423)
			(xy 423.093388 -305.699922) (xy 423.081196 -305.697636) (xy 423.057066 -305.705002) (xy 422.97985 -305.782218)
			(xy 422.972484 -305.806094) (xy 422.97477 -305.81854) (xy 422.977248 -305.832506) (xy 422.979919 -305.860745)
			(xy 422.980104 -305.874928) (xy 422.980034 -305.884799) (xy 422.978761 -305.9045) (xy 422.977564 -305.914298)
			(xy 422.97604 -305.926236) (xy 422.983914 -305.949096) (xy 423.060368 -306.022502) (xy 423.083228 -306.029614)
			(xy 423.09542 -306.027582) (xy 423.108965 -306.025369) (xy 423.136307 -306.02295) (xy 423.15003 -306.022756)
			(xy 423.175711 -306.023338) (xy 423.226441 -306.031376) (xy 423.27529 -306.04725) (xy 423.321054 -306.070569)
			(xy 423.362608 -306.100759) (xy 423.398928 -306.137077) (xy 423.429121 -306.178629) (xy 423.452442 -306.224392)
			(xy 423.468319 -306.27324) (xy 423.476361 -306.323969) (xy 423.476369 -306.375332) (xy 423.476324 -306.375616)
			(xy 423.773342 -306.375616) (xy 423.773342 -306.3242) (xy 423.781385 -306.273418) (xy 423.797273 -306.224519)
			(xy 423.820616 -306.178707) (xy 423.850837 -306.137111) (xy 423.887193 -306.100755) (xy 423.928789 -306.070534)
			(xy 423.974601 -306.047191) (xy 424.0235 -306.031303) (xy 424.074282 -306.02326) (xy 424.125698 -306.02326)
			(xy 424.17648 -306.031303) (xy 424.225379 -306.047191) (xy 424.271191 -306.070534) (xy 424.312787 -306.100755)
			(xy 424.349143 -306.137111) (xy 424.379364 -306.178707) (xy 424.402707 -306.224519) (xy 424.418595 -306.273418)
			(xy 424.426638 -306.3242) (xy 424.427142 -306.349908) (xy 424.744146 -306.349908) (xy 424.748106 -306.300854)
			(xy 424.759883 -306.25307) (xy 424.779174 -306.207794) (xy 424.805477 -306.166198) (xy 424.838112 -306.129361)
			(xy 424.876233 -306.098236) (xy 424.918854 -306.073629) (xy 424.96487 -306.056177) (xy 425.013089 -306.046333)
			(xy 425.062264 -306.044352) (xy 425.111119 -306.050284) (xy 425.15839 -306.063976) (xy 425.202852 -306.085074)
			(xy 425.243355 -306.11303) (xy 425.278848 -306.147122) (xy 425.308413 -306.186466) (xy 425.331284 -306.230043)
			(xy 425.346868 -306.276724) (xy 425.354763 -306.325301) (xy 425.355258 -306.349908) (xy 425.694106 -306.349908)
			(xy 425.698066 -306.300854) (xy 425.709843 -306.25307) (xy 425.729134 -306.207794) (xy 425.755437 -306.166198)
			(xy 425.788072 -306.129361) (xy 425.826193 -306.098236) (xy 425.868814 -306.073629) (xy 425.91483 -306.056177)
			(xy 425.963049 -306.046333) (xy 426.012224 -306.044352) (xy 426.061079 -306.050284) (xy 426.10835 -306.063976)
			(xy 426.152812 -306.085074) (xy 426.193315 -306.11303) (xy 426.228808 -306.147122) (xy 426.258373 -306.186466)
			(xy 426.281244 -306.230043) (xy 426.296828 -306.276724) (xy 426.304723 -306.325301) (xy 426.305218 -306.349908)
			(xy 426.644066 -306.349908) (xy 426.648026 -306.300854) (xy 426.659803 -306.25307) (xy 426.679094 -306.207794)
			(xy 426.705397 -306.166198) (xy 426.738032 -306.129361) (xy 426.776153 -306.098236) (xy 426.818774 -306.073629)
			(xy 426.86479 -306.056177) (xy 426.913009 -306.046333) (xy 426.962184 -306.044352) (xy 427.011039 -306.050284)
			(xy 427.05831 -306.063976) (xy 427.102772 -306.085074) (xy 427.143275 -306.11303) (xy 427.178768 -306.147122)
			(xy 427.208333 -306.186466) (xy 427.231204 -306.230043) (xy 427.246788 -306.276724) (xy 427.254683 -306.325301)
			(xy 427.255178 -306.349908) (xy 427.594026 -306.349908) (xy 427.597986 -306.300854) (xy 427.609763 -306.25307)
			(xy 427.629054 -306.207794) (xy 427.655357 -306.166198) (xy 427.687992 -306.129361) (xy 427.726113 -306.098236)
			(xy 427.768734 -306.073629) (xy 427.81475 -306.056177) (xy 427.862969 -306.046333) (xy 427.912144 -306.044352)
			(xy 427.960999 -306.050284) (xy 428.00827 -306.063976) (xy 428.052732 -306.085074) (xy 428.093235 -306.11303)
			(xy 428.128728 -306.147122) (xy 428.158293 -306.186466) (xy 428.181164 -306.230043) (xy 428.196748 -306.276724)
			(xy 428.204643 -306.325301) (xy 428.205138 -306.349908) (xy 428.543986 -306.349908) (xy 428.547946 -306.300854)
			(xy 428.559723 -306.25307) (xy 428.579014 -306.207794) (xy 428.605317 -306.166198) (xy 428.637952 -306.129361)
			(xy 428.676073 -306.098236) (xy 428.718694 -306.073629) (xy 428.76471 -306.056177) (xy 428.812929 -306.046333)
			(xy 428.862104 -306.044352) (xy 428.910959 -306.050284) (xy 428.95823 -306.063976) (xy 429.002692 -306.085074)
			(xy 429.043195 -306.11303) (xy 429.078688 -306.147122) (xy 429.108253 -306.186466) (xy 429.131124 -306.230043)
			(xy 429.146708 -306.276724) (xy 429.154603 -306.325301) (xy 429.155098 -306.349908) (xy 429.154603 -306.374515)
			(xy 429.154424 -306.375616) (xy 429.473356 -306.375616) (xy 429.473356 -306.3242) (xy 429.481399 -306.273418)
			(xy 429.497287 -306.224519) (xy 429.52063 -306.178707) (xy 429.550851 -306.137111) (xy 429.587207 -306.100755)
			(xy 429.628803 -306.070534) (xy 429.674615 -306.047191) (xy 429.723514 -306.031303) (xy 429.774296 -306.02326)
			(xy 429.825712 -306.02326) (xy 429.876494 -306.031303) (xy 429.925393 -306.047191) (xy 429.971205 -306.070534)
			(xy 430.012801 -306.100755) (xy 430.049157 -306.137111) (xy 430.079378 -306.178707) (xy 430.102721 -306.224519)
			(xy 430.118609 -306.273418) (xy 430.126652 -306.3242) (xy 430.127156 -306.349908) (xy 430.126652 -306.375616)
			(xy 430.423316 -306.375616) (xy 430.423316 -306.3242) (xy 430.431359 -306.273418) (xy 430.447247 -306.224519)
			(xy 430.47059 -306.178707) (xy 430.500811 -306.137111) (xy 430.537167 -306.100755) (xy 430.578763 -306.070534)
			(xy 430.624575 -306.047191) (xy 430.673474 -306.031303) (xy 430.724256 -306.02326) (xy 430.775672 -306.02326)
			(xy 430.826454 -306.031303) (xy 430.875353 -306.047191) (xy 430.921165 -306.070534) (xy 430.962761 -306.100755)
			(xy 430.999117 -306.137111) (xy 431.029338 -306.178707) (xy 431.052681 -306.224519) (xy 431.068569 -306.273418)
			(xy 431.076612 -306.3242) (xy 431.077116 -306.349908) (xy 431.394374 -306.349908) (xy 431.398334 -306.300854)
			(xy 431.410111 -306.25307) (xy 431.429402 -306.207794) (xy 431.455705 -306.166198) (xy 431.48834 -306.129361)
			(xy 431.526461 -306.098236) (xy 431.569082 -306.073629) (xy 431.615098 -306.056177) (xy 431.663317 -306.046333)
			(xy 431.712492 -306.044352) (xy 431.761347 -306.050284) (xy 431.808618 -306.063976) (xy 431.85308 -306.085074)
			(xy 431.893583 -306.11303) (xy 431.929076 -306.147122) (xy 431.958641 -306.186466) (xy 431.981512 -306.230043)
			(xy 431.997096 -306.276724) (xy 432.004991 -306.325301) (xy 432.005486 -306.349908) (xy 432.004991 -306.374515)
			(xy 431.997096 -306.423092) (xy 431.981512 -306.469773) (xy 431.958641 -306.51335) (xy 431.929076 -306.552694)
			(xy 431.893583 -306.586786) (xy 431.85308 -306.614742) (xy 431.808618 -306.63584) (xy 431.761347 -306.649532)
			(xy 431.712492 -306.655464) (xy 431.663317 -306.653483) (xy 431.615098 -306.643639) (xy 431.569082 -306.626187)
			(xy 431.526461 -306.60158) (xy 431.48834 -306.570455) (xy 431.455705 -306.533618) (xy 431.429402 -306.492022)
			(xy 431.410111 -306.446746) (xy 431.398334 -306.398962) (xy 431.394374 -306.349908) (xy 431.077116 -306.349908)
			(xy 431.076612 -306.375616) (xy 431.068569 -306.426398) (xy 431.052681 -306.475297) (xy 431.029338 -306.521109)
			(xy 430.999117 -306.562705) (xy 430.962761 -306.599061) (xy 430.921165 -306.629282) (xy 430.875353 -306.652625)
			(xy 430.826454 -306.668513) (xy 430.775672 -306.676556) (xy 430.724256 -306.676556) (xy 430.673474 -306.668513)
			(xy 430.624575 -306.652625) (xy 430.578763 -306.629282) (xy 430.537167 -306.599061) (xy 430.500811 -306.562705)
			(xy 430.47059 -306.521109) (xy 430.447247 -306.475297) (xy 430.431359 -306.426398) (xy 430.423316 -306.375616)
			(xy 430.126652 -306.375616) (xy 430.118609 -306.426398) (xy 430.102721 -306.475297) (xy 430.079378 -306.521109)
			(xy 430.049157 -306.562705) (xy 430.012801 -306.599061) (xy 429.971205 -306.629282) (xy 429.925393 -306.652625)
			(xy 429.876494 -306.668513) (xy 429.825712 -306.676556) (xy 429.774296 -306.676556) (xy 429.723514 -306.668513)
			(xy 429.674615 -306.652625) (xy 429.628803 -306.629282) (xy 429.587207 -306.599061) (xy 429.550851 -306.562705)
			(xy 429.52063 -306.521109) (xy 429.497287 -306.475297) (xy 429.481399 -306.426398) (xy 429.473356 -306.375616)
			(xy 429.154424 -306.375616) (xy 429.146708 -306.423092) (xy 429.131124 -306.469773) (xy 429.108253 -306.51335)
			(xy 429.078688 -306.552694) (xy 429.043195 -306.586786) (xy 429.002692 -306.614742) (xy 428.95823 -306.63584)
			(xy 428.910959 -306.649532) (xy 428.862104 -306.655464) (xy 428.812929 -306.653483) (xy 428.76471 -306.643639)
			(xy 428.718694 -306.626187) (xy 428.676073 -306.60158) (xy 428.637952 -306.570455) (xy 428.605317 -306.533618)
			(xy 428.579014 -306.492022) (xy 428.559723 -306.446746) (xy 428.547946 -306.398962) (xy 428.543986 -306.349908)
			(xy 428.205138 -306.349908) (xy 428.204643 -306.374515) (xy 428.196748 -306.423092) (xy 428.181164 -306.469773)
			(xy 428.158293 -306.51335) (xy 428.128728 -306.552694) (xy 428.093235 -306.586786) (xy 428.052732 -306.614742)
			(xy 428.00827 -306.63584) (xy 427.960999 -306.649532) (xy 427.912144 -306.655464) (xy 427.862969 -306.653483)
			(xy 427.81475 -306.643639) (xy 427.768734 -306.626187) (xy 427.726113 -306.60158) (xy 427.687992 -306.570455)
			(xy 427.655357 -306.533618) (xy 427.629054 -306.492022) (xy 427.609763 -306.446746) (xy 427.597986 -306.398962)
			(xy 427.594026 -306.349908) (xy 427.255178 -306.349908) (xy 427.254683 -306.374515) (xy 427.246788 -306.423092)
			(xy 427.231204 -306.469773) (xy 427.208333 -306.51335) (xy 427.178768 -306.552694) (xy 427.143275 -306.586786)
			(xy 427.102772 -306.614742) (xy 427.05831 -306.63584) (xy 427.011039 -306.649532) (xy 426.962184 -306.655464)
			(xy 426.913009 -306.653483) (xy 426.86479 -306.643639) (xy 426.818774 -306.626187) (xy 426.776153 -306.60158)
			(xy 426.738032 -306.570455) (xy 426.705397 -306.533618) (xy 426.679094 -306.492022) (xy 426.659803 -306.446746)
			(xy 426.648026 -306.398962) (xy 426.644066 -306.349908) (xy 426.305218 -306.349908) (xy 426.304723 -306.374515)
			(xy 426.296828 -306.423092) (xy 426.281244 -306.469773) (xy 426.258373 -306.51335) (xy 426.228808 -306.552694)
			(xy 426.193315 -306.586786) (xy 426.152812 -306.614742) (xy 426.10835 -306.63584) (xy 426.061079 -306.649532)
			(xy 426.012224 -306.655464) (xy 425.963049 -306.653483) (xy 425.91483 -306.643639) (xy 425.868814 -306.626187)
			(xy 425.826193 -306.60158) (xy 425.788072 -306.570455) (xy 425.755437 -306.533618) (xy 425.729134 -306.492022)
			(xy 425.709843 -306.446746) (xy 425.698066 -306.398962) (xy 425.694106 -306.349908) (xy 425.355258 -306.349908)
			(xy 425.354763 -306.374515) (xy 425.346868 -306.423092) (xy 425.331284 -306.469773) (xy 425.308413 -306.51335)
			(xy 425.278848 -306.552694) (xy 425.243355 -306.586786) (xy 425.202852 -306.614742) (xy 425.15839 -306.63584)
			(xy 425.111119 -306.649532) (xy 425.062264 -306.655464) (xy 425.013089 -306.653483) (xy 424.96487 -306.643639)
			(xy 424.918854 -306.626187) (xy 424.876233 -306.60158) (xy 424.838112 -306.570455) (xy 424.805477 -306.533618)
			(xy 424.779174 -306.492022) (xy 424.759883 -306.446746) (xy 424.748106 -306.398962) (xy 424.744146 -306.349908)
			(xy 424.427142 -306.349908) (xy 424.426638 -306.375616) (xy 424.418595 -306.426398) (xy 424.402707 -306.475297)
			(xy 424.379364 -306.521109) (xy 424.349143 -306.562705) (xy 424.312787 -306.599061) (xy 424.271191 -306.629282)
			(xy 424.225379 -306.652625) (xy 424.17648 -306.668513) (xy 424.125698 -306.676556) (xy 424.074282 -306.676556)
			(xy 424.0235 -306.668513) (xy 423.974601 -306.652625) (xy 423.928789 -306.629282) (xy 423.887193 -306.599061)
			(xy 423.850837 -306.562705) (xy 423.820616 -306.521109) (xy 423.797273 -306.475297) (xy 423.781385 -306.426398)
			(xy 423.773342 -306.375616) (xy 423.476324 -306.375616) (xy 423.468343 -306.426064) (xy 423.45248 -306.474916)
			(xy 423.429172 -306.520686) (xy 423.398992 -306.562247) (xy 423.362683 -306.598576) (xy 423.321138 -306.628779)
			(xy 423.275381 -306.652112) (xy 423.226538 -306.668001) (xy 423.17581 -306.676055) (xy 423.124447 -306.676075)
			(xy 423.073713 -306.668061) (xy 423.024857 -306.652211) (xy 422.979081 -306.628914) (xy 422.937513 -306.598744)
			(xy 422.901175 -306.562443) (xy 422.870963 -306.520906) (xy 422.847618 -306.475155) (xy 422.831718 -306.426315)
			(xy 422.823652 -306.375589) (xy 422.823132 -306.349908) (xy 422.823281 -306.33619) (xy 422.825567 -306.308849)
			(xy 422.827704 -306.295298) (xy 422.829736 -306.28336) (xy 422.822624 -306.2605) (xy 422.748964 -306.184046)
			(xy 422.726358 -306.176172) (xy 422.714166 -306.177696) (xy 422.704367 -306.178883) (xy 422.684667 -306.180155)
			(xy 422.674796 -306.180236) (xy 422.649543 -306.179658) (xy 422.599727 -306.171345) (xy 422.551958 -306.154945)
			(xy 422.507539 -306.130907) (xy 422.467684 -306.099885) (xy 422.433477 -306.062727) (xy 422.405854 -306.020445)
			(xy 422.385566 -305.974193) (xy 422.373168 -305.925233) (xy 422.368997 -305.8749) (xy 422.030143 -305.8749)
			(xy 422.030144 -305.874928) (xy 422.029649 -305.899535) (xy 422.021754 -305.948112) (xy 422.00617 -305.994793)
			(xy 421.983299 -306.03837) (xy 421.953734 -306.077714) (xy 421.918241 -306.111806) (xy 421.877738 -306.139762)
			(xy 421.833276 -306.16086) (xy 421.786005 -306.174552) (xy 421.73715 -306.180484) (xy 421.687975 -306.178503)
			(xy 421.639756 -306.168659) (xy 421.59374 -306.151207) (xy 421.551119 -306.1266) (xy 421.512998 -306.095475)
			(xy 421.480363 -306.058638) (xy 421.45406 -306.017042) (xy 421.434769 -305.971766) (xy 421.422992 -305.923982)
			(xy 421.419032 -305.874928) (xy 421.080184 -305.874928) (xy 421.079689 -305.899535) (xy 421.071794 -305.948112)
			(xy 421.05621 -305.994793) (xy 421.033339 -306.03837) (xy 421.003774 -306.077714) (xy 420.968281 -306.111806)
			(xy 420.927778 -306.139762) (xy 420.883316 -306.16086) (xy 420.836045 -306.174552) (xy 420.78719 -306.180484)
			(xy 420.738015 -306.178503) (xy 420.689796 -306.168659) (xy 420.64378 -306.151207) (xy 420.601159 -306.1266)
			(xy 420.563038 -306.095475) (xy 420.530403 -306.058638) (xy 420.5041 -306.017042) (xy 420.484809 -305.971766)
			(xy 420.473032 -305.923982) (xy 420.469072 -305.874928) (xy 420.130224 -305.874928) (xy 420.129729 -305.899535)
			(xy 420.121834 -305.948112) (xy 420.10625 -305.994793) (xy 420.083379 -306.03837) (xy 420.053814 -306.077714)
			(xy 420.018321 -306.111806) (xy 419.977818 -306.139762) (xy 419.933356 -306.16086) (xy 419.886085 -306.174552)
			(xy 419.83723 -306.180484) (xy 419.788055 -306.178503) (xy 419.739836 -306.168659) (xy 419.69382 -306.151207)
			(xy 419.651199 -306.1266) (xy 419.613078 -306.095475) (xy 419.580443 -306.058638) (xy 419.55414 -306.017042)
			(xy 419.534849 -305.971766) (xy 419.523072 -305.923982) (xy 419.519112 -305.874928) (xy 419.180264 -305.874928)
			(xy 419.179769 -305.899535) (xy 419.171874 -305.948112) (xy 419.15629 -305.994793) (xy 419.133419 -306.03837)
			(xy 419.103854 -306.077714) (xy 419.068361 -306.111806) (xy 419.027858 -306.139762) (xy 418.983396 -306.16086)
			(xy 418.936125 -306.174552) (xy 418.88727 -306.180484) (xy 418.838095 -306.178503) (xy 418.789876 -306.168659)
			(xy 418.74386 -306.151207) (xy 418.701239 -306.1266) (xy 418.663118 -306.095475) (xy 418.630483 -306.058638)
			(xy 418.60418 -306.017042) (xy 418.584889 -305.971766) (xy 418.573112 -305.923982) (xy 418.569152 -305.874928)
			(xy 418.230304 -305.874928) (xy 418.229809 -305.899535) (xy 418.221914 -305.948112) (xy 418.20633 -305.994793)
			(xy 418.183459 -306.03837) (xy 418.153894 -306.077714) (xy 418.118401 -306.111806) (xy 418.077898 -306.139762)
			(xy 418.033436 -306.16086) (xy 417.986165 -306.174552) (xy 417.93731 -306.180484) (xy 417.888135 -306.178503)
			(xy 417.839916 -306.168659) (xy 417.7939 -306.151207) (xy 417.751279 -306.1266) (xy 417.713158 -306.095475)
			(xy 417.680523 -306.058638) (xy 417.65422 -306.017042) (xy 417.634929 -305.971766) (xy 417.623152 -305.923982)
			(xy 417.619192 -305.874928) (xy 417.28009 -305.874928) (xy 417.279595 -305.899535) (xy 417.2717 -305.948112)
			(xy 417.256116 -305.994793) (xy 417.233245 -306.03837) (xy 417.20368 -306.077714) (xy 417.168187 -306.111806)
			(xy 417.127684 -306.139762) (xy 417.083222 -306.16086) (xy 417.035951 -306.174552) (xy 416.987096 -306.180484)
			(xy 416.937921 -306.178503) (xy 416.889702 -306.168659) (xy 416.843686 -306.151207) (xy 416.801065 -306.1266)
			(xy 416.762944 -306.095475) (xy 416.730309 -306.058638) (xy 416.704006 -306.017042) (xy 416.684715 -305.971766)
			(xy 416.672938 -305.923982) (xy 416.668978 -305.874928) (xy 416.33013 -305.874928) (xy 416.329635 -305.899535)
			(xy 416.32174 -305.948112) (xy 416.306156 -305.994793) (xy 416.283285 -306.03837) (xy 416.25372 -306.077714)
			(xy 416.218227 -306.111806) (xy 416.177724 -306.139762) (xy 416.133262 -306.16086) (xy 416.085991 -306.174552)
			(xy 416.037136 -306.180484) (xy 415.987961 -306.178503) (xy 415.939742 -306.168659) (xy 415.893726 -306.151207)
			(xy 415.851105 -306.1266) (xy 415.812984 -306.095475) (xy 415.780349 -306.058638) (xy 415.754046 -306.017042)
			(xy 415.734755 -305.971766) (xy 415.722978 -305.923982) (xy 415.719018 -305.874928) (xy 415.38017 -305.874928)
			(xy 415.379675 -305.899535) (xy 415.37178 -305.948112) (xy 415.356196 -305.994793) (xy 415.333325 -306.03837)
			(xy 415.30376 -306.077714) (xy 415.268267 -306.111806) (xy 415.227764 -306.139762) (xy 415.183302 -306.16086)
			(xy 415.136031 -306.174552) (xy 415.087176 -306.180484) (xy 415.038001 -306.178503) (xy 414.989782 -306.168659)
			(xy 414.943766 -306.151207) (xy 414.901145 -306.1266) (xy 414.863024 -306.095475) (xy 414.830389 -306.058638)
			(xy 414.804086 -306.017042) (xy 414.784795 -305.971766) (xy 414.773018 -305.923982) (xy 414.769058 -305.874928)
			(xy 414.43021 -305.874928) (xy 414.429715 -305.899535) (xy 414.42182 -305.948112) (xy 414.406236 -305.994793)
			(xy 414.383365 -306.03837) (xy 414.3538 -306.077714) (xy 414.318307 -306.111806) (xy 414.277804 -306.139762)
			(xy 414.233342 -306.16086) (xy 414.186071 -306.174552) (xy 414.137216 -306.180484) (xy 414.088041 -306.178503)
			(xy 414.039822 -306.168659) (xy 413.993806 -306.151207) (xy 413.951185 -306.1266) (xy 413.913064 -306.095475)
			(xy 413.880429 -306.058638) (xy 413.854126 -306.017042) (xy 413.834835 -305.971766) (xy 413.823058 -305.923982)
			(xy 413.819098 -305.874928) (xy 413.48025 -305.874928) (xy 413.479755 -305.899535) (xy 413.47186 -305.948112)
			(xy 413.456276 -305.994793) (xy 413.433405 -306.03837) (xy 413.40384 -306.077714) (xy 413.368347 -306.111806)
			(xy 413.327844 -306.139762) (xy 413.283382 -306.16086) (xy 413.236111 -306.174552) (xy 413.187256 -306.180484)
			(xy 413.138081 -306.178503) (xy 413.089862 -306.168659) (xy 413.043846 -306.151207) (xy 413.001225 -306.1266)
			(xy 412.963104 -306.095475) (xy 412.930469 -306.058638) (xy 412.904166 -306.017042) (xy 412.884875 -305.971766)
			(xy 412.873098 -305.923982) (xy 412.869138 -305.874928) (xy 412.53029 -305.874928) (xy 412.529795 -305.899535)
			(xy 412.5219 -305.948112) (xy 412.506316 -305.994793) (xy 412.483445 -306.03837) (xy 412.45388 -306.077714)
			(xy 412.418387 -306.111806) (xy 412.377884 -306.139762) (xy 412.333422 -306.16086) (xy 412.286151 -306.174552)
			(xy 412.237296 -306.180484) (xy 412.188121 -306.178503) (xy 412.139902 -306.168659) (xy 412.093886 -306.151207)
			(xy 412.051265 -306.1266) (xy 412.013144 -306.095475) (xy 411.980509 -306.058638) (xy 411.954206 -306.017042)
			(xy 411.934915 -305.971766) (xy 411.923138 -305.923982) (xy 411.919178 -305.874928) (xy 411.58033 -305.874928)
			(xy 411.579835 -305.899535) (xy 411.57194 -305.948112) (xy 411.556356 -305.994793) (xy 411.533485 -306.03837)
			(xy 411.50392 -306.077714) (xy 411.468427 -306.111806) (xy 411.427924 -306.139762) (xy 411.383462 -306.16086)
			(xy 411.336191 -306.174552) (xy 411.287336 -306.180484) (xy 411.238161 -306.178503) (xy 411.189942 -306.168659)
			(xy 411.143926 -306.151207) (xy 411.101305 -306.1266) (xy 411.063184 -306.095475) (xy 411.030549 -306.058638)
			(xy 411.004246 -306.017042) (xy 410.984955 -305.971766) (xy 410.973178 -305.923982) (xy 410.969218 -305.874928)
			(xy 410.630116 -305.874928) (xy 410.629621 -305.899535) (xy 410.621726 -305.948112) (xy 410.606142 -305.994793)
			(xy 410.583271 -306.03837) (xy 410.553706 -306.077714) (xy 410.518213 -306.111806) (xy 410.47771 -306.139762)
			(xy 410.433248 -306.16086) (xy 410.385977 -306.174552) (xy 410.337122 -306.180484) (xy 410.287947 -306.178503)
			(xy 410.239728 -306.168659) (xy 410.193712 -306.151207) (xy 410.151091 -306.1266) (xy 410.11297 -306.095475)
			(xy 410.080335 -306.058638) (xy 410.054032 -306.017042) (xy 410.034741 -305.971766) (xy 410.022964 -305.923982)
			(xy 410.019004 -305.874928) (xy 409.680156 -305.874928) (xy 409.679661 -305.899535) (xy 409.671766 -305.948112)
			(xy 409.656182 -305.994793) (xy 409.633311 -306.03837) (xy 409.603746 -306.077714) (xy 409.568253 -306.111806)
			(xy 409.52775 -306.139762) (xy 409.483288 -306.16086) (xy 409.436017 -306.174552) (xy 409.387162 -306.180484)
			(xy 409.337987 -306.178503) (xy 409.289768 -306.168659) (xy 409.243752 -306.151207) (xy 409.201131 -306.1266)
			(xy 409.16301 -306.095475) (xy 409.130375 -306.058638) (xy 409.104072 -306.017042) (xy 409.084781 -305.971766)
			(xy 409.073004 -305.923982) (xy 409.069044 -305.874928) (xy 408.730196 -305.874928) (xy 408.729701 -305.899535)
			(xy 408.721806 -305.948112) (xy 408.706222 -305.994793) (xy 408.683351 -306.03837) (xy 408.653786 -306.077714)
			(xy 408.618293 -306.111806) (xy 408.57779 -306.139762) (xy 408.533328 -306.16086) (xy 408.486057 -306.174552)
			(xy 408.437202 -306.180484) (xy 408.388027 -306.178503) (xy 408.339808 -306.168659) (xy 408.293792 -306.151207)
			(xy 408.251171 -306.1266) (xy 408.21305 -306.095475) (xy 408.180415 -306.058638) (xy 408.154112 -306.017042)
			(xy 408.134821 -305.971766) (xy 408.123044 -305.923982) (xy 408.119084 -305.874928) (xy 406.830276 -305.874928)
			(xy 406.829781 -305.899535) (xy 406.821886 -305.948112) (xy 406.806302 -305.994793) (xy 406.783431 -306.03837)
			(xy 406.753866 -306.077714) (xy 406.718373 -306.111806) (xy 406.67787 -306.139762) (xy 406.633408 -306.16086)
			(xy 406.586137 -306.174552) (xy 406.537282 -306.180484) (xy 406.488107 -306.178503) (xy 406.439888 -306.168659)
			(xy 406.393872 -306.151207) (xy 406.351251 -306.1266) (xy 406.31313 -306.095475) (xy 406.280495 -306.058638)
			(xy 406.254192 -306.017042) (xy 406.234901 -305.971766) (xy 406.223124 -305.923982) (xy 406.219164 -305.874928)
			(xy 405.880316 -305.874928) (xy 405.879821 -305.899535) (xy 405.871926 -305.948112) (xy 405.856342 -305.994793)
			(xy 405.833471 -306.03837) (xy 405.803906 -306.077714) (xy 405.768413 -306.111806) (xy 405.72791 -306.139762)
			(xy 405.683448 -306.16086) (xy 405.636177 -306.174552) (xy 405.587322 -306.180484) (xy 405.538147 -306.178503)
			(xy 405.489928 -306.168659) (xy 405.443912 -306.151207) (xy 405.401291 -306.1266) (xy 405.36317 -306.095475)
			(xy 405.330535 -306.058638) (xy 405.304232 -306.017042) (xy 405.284941 -305.971766) (xy 405.273164 -305.923982)
			(xy 405.269204 -305.874928) (xy 404.930102 -305.874928) (xy 404.929607 -305.899535) (xy 404.921712 -305.948112)
			(xy 404.906128 -305.994793) (xy 404.883257 -306.03837) (xy 404.853692 -306.077714) (xy 404.818199 -306.111806)
			(xy 404.777696 -306.139762) (xy 404.733234 -306.16086) (xy 404.685963 -306.174552) (xy 404.637108 -306.180484)
			(xy 404.587933 -306.178503) (xy 404.539714 -306.168659) (xy 404.493698 -306.151207) (xy 404.451077 -306.1266)
			(xy 404.412956 -306.095475) (xy 404.380321 -306.058638) (xy 404.354018 -306.017042) (xy 404.334727 -305.971766)
			(xy 404.32295 -305.923982) (xy 404.31899 -305.874928) (xy 403.980142 -305.874928) (xy 403.979647 -305.899535)
			(xy 403.971752 -305.948112) (xy 403.956168 -305.994793) (xy 403.933297 -306.03837) (xy 403.903732 -306.077714)
			(xy 403.868239 -306.111806) (xy 403.827736 -306.139762) (xy 403.783274 -306.16086) (xy 403.736003 -306.174552)
			(xy 403.687148 -306.180484) (xy 403.637973 -306.178503) (xy 403.589754 -306.168659) (xy 403.543738 -306.151207)
			(xy 403.501117 -306.1266) (xy 403.462996 -306.095475) (xy 403.430361 -306.058638) (xy 403.404058 -306.017042)
			(xy 403.384767 -305.971766) (xy 403.37299 -305.923982) (xy 403.36903 -305.874928) (xy 403.030182 -305.874928)
			(xy 403.029687 -305.899535) (xy 403.021792 -305.948112) (xy 403.006208 -305.994793) (xy 402.983337 -306.03837)
			(xy 402.953772 -306.077714) (xy 402.918279 -306.111806) (xy 402.877776 -306.139762) (xy 402.833314 -306.16086)
			(xy 402.786043 -306.174552) (xy 402.737188 -306.180484) (xy 402.688013 -306.178503) (xy 402.639794 -306.168659)
			(xy 402.593778 -306.151207) (xy 402.551157 -306.1266) (xy 402.513036 -306.095475) (xy 402.480401 -306.058638)
			(xy 402.454098 -306.017042) (xy 402.434807 -305.971766) (xy 402.42303 -305.923982) (xy 402.41907 -305.874928)
			(xy 402.080222 -305.874928) (xy 402.079727 -305.899535) (xy 402.071832 -305.948112) (xy 402.056248 -305.994793)
			(xy 402.033377 -306.03837) (xy 402.003812 -306.077714) (xy 401.968319 -306.111806) (xy 401.927816 -306.139762)
			(xy 401.883354 -306.16086) (xy 401.836083 -306.174552) (xy 401.787228 -306.180484) (xy 401.738053 -306.178503)
			(xy 401.689834 -306.168659) (xy 401.643818 -306.151207) (xy 401.601197 -306.1266) (xy 401.563076 -306.095475)
			(xy 401.530441 -306.058638) (xy 401.504138 -306.017042) (xy 401.484847 -305.971766) (xy 401.47307 -305.923982)
			(xy 401.46911 -305.874928) (xy 401.130262 -305.874928) (xy 401.129767 -305.899535) (xy 401.121872 -305.948112)
			(xy 401.106288 -305.994793) (xy 401.083417 -306.03837) (xy 401.053852 -306.077714) (xy 401.018359 -306.111806)
			(xy 400.977856 -306.139762) (xy 400.933394 -306.16086) (xy 400.886123 -306.174552) (xy 400.837268 -306.180484)
			(xy 400.788093 -306.178503) (xy 400.739874 -306.168659) (xy 400.693858 -306.151207) (xy 400.651237 -306.1266)
			(xy 400.613116 -306.095475) (xy 400.580481 -306.058638) (xy 400.554178 -306.017042) (xy 400.534887 -305.971766)
			(xy 400.52311 -305.923982) (xy 400.51915 -305.874928) (xy 400.180302 -305.874928) (xy 400.179807 -305.899535)
			(xy 400.171912 -305.948112) (xy 400.156328 -305.994793) (xy 400.133457 -306.03837) (xy 400.103892 -306.077714)
			(xy 400.068399 -306.111806) (xy 400.027896 -306.139762) (xy 399.983434 -306.16086) (xy 399.936163 -306.174552)
			(xy 399.887308 -306.180484) (xy 399.838133 -306.178503) (xy 399.789914 -306.168659) (xy 399.743898 -306.151207)
			(xy 399.701277 -306.1266) (xy 399.663156 -306.095475) (xy 399.630521 -306.058638) (xy 399.604218 -306.017042)
			(xy 399.584927 -305.971766) (xy 399.57315 -305.923982) (xy 399.56919 -305.874928) (xy 399.230342 -305.874928)
			(xy 399.229847 -305.899535) (xy 399.221952 -305.948112) (xy 399.206368 -305.994793) (xy 399.183497 -306.03837)
			(xy 399.153932 -306.077714) (xy 399.118439 -306.111806) (xy 399.077936 -306.139762) (xy 399.033474 -306.16086)
			(xy 398.986203 -306.174552) (xy 398.937348 -306.180484) (xy 398.888173 -306.178503) (xy 398.839954 -306.168659)
			(xy 398.793938 -306.151207) (xy 398.751317 -306.1266) (xy 398.713196 -306.095475) (xy 398.680561 -306.058638)
			(xy 398.654258 -306.017042) (xy 398.634967 -305.971766) (xy 398.62319 -305.923982) (xy 398.61923 -305.874928)
			(xy 398.280128 -305.874928) (xy 398.279633 -305.899535) (xy 398.271738 -305.948112) (xy 398.256154 -305.994793)
			(xy 398.233283 -306.03837) (xy 398.203718 -306.077714) (xy 398.168225 -306.111806) (xy 398.127722 -306.139762)
			(xy 398.08326 -306.16086) (xy 398.035989 -306.174552) (xy 397.987134 -306.180484) (xy 397.937959 -306.178503)
			(xy 397.88974 -306.168659) (xy 397.843724 -306.151207) (xy 397.801103 -306.1266) (xy 397.762982 -306.095475)
			(xy 397.730347 -306.058638) (xy 397.704044 -306.017042) (xy 397.684753 -305.971766) (xy 397.672976 -305.923982)
			(xy 397.669016 -305.874928) (xy 397.355119 -305.874928) (xy 397.355119 -305.901263) (xy 397.346755 -305.953315)
			(xy 397.33024 -306.00338) (xy 397.305991 -306.050191) (xy 397.274624 -306.092563) (xy 397.236932 -306.129423)
			(xy 397.19387 -306.159836) (xy 397.146529 -306.183033) (xy 397.096107 -306.198426) (xy 397.070072 -306.202588)
			(xy 397.066008 -306.203096) (xy 397.054578 -306.206652) (xy 397.05026 -306.207922) (xy 397.02613 -306.219098)
			(xy 397.019526 -306.22621) (xy 397.004794 -306.241704) (xy 396.996666 -306.25288) (xy 396.993972 -306.258412)
			(xy 396.991019 -306.270352) (xy 396.990824 -306.276502) (xy 396.990824 -306.423314) (xy 396.990999 -306.429466)
			(xy 396.993961 -306.441407) (xy 396.996666 -306.446936) (xy 397.004794 -306.458112) (xy 397.019526 -306.473606)
			(xy 397.02613 -306.480718) (xy 397.05026 -306.491894) (xy 397.054578 -306.493164) (xy 397.066008 -306.49672)
			(xy 397.070072 -306.497228) (xy 397.096118 -306.501336) (xy 397.146545 -306.516731) (xy 397.193892 -306.539931)
			(xy 397.236959 -306.570348) (xy 397.274655 -306.607212) (xy 397.306026 -306.649589) (xy 397.330277 -306.696407)
			(xy 397.346794 -306.746478) (xy 397.355158 -306.798536) (xy 397.355158 -306.824888) (xy 397.669016 -306.824888)
			(xy 397.672976 -306.775834) (xy 397.684753 -306.72805) (xy 397.704044 -306.682774) (xy 397.730347 -306.641178)
			(xy 397.762982 -306.604341) (xy 397.801103 -306.573216) (xy 397.843724 -306.548609) (xy 397.88974 -306.531157)
			(xy 397.937959 -306.521313) (xy 397.987134 -306.519332) (xy 398.035989 -306.525264) (xy 398.08326 -306.538956)
			(xy 398.127722 -306.560054) (xy 398.168225 -306.58801) (xy 398.203718 -306.622102) (xy 398.233283 -306.661446)
			(xy 398.256154 -306.705023) (xy 398.271738 -306.751704) (xy 398.279633 -306.800281) (xy 398.280128 -306.824888)
			(xy 398.61923 -306.824888) (xy 398.62319 -306.775834) (xy 398.634967 -306.72805) (xy 398.654258 -306.682774)
			(xy 398.680561 -306.641178) (xy 398.713196 -306.604341) (xy 398.751317 -306.573216) (xy 398.793938 -306.548609)
			(xy 398.839954 -306.531157) (xy 398.888173 -306.521313) (xy 398.937348 -306.519332) (xy 398.986203 -306.525264)
			(xy 399.033474 -306.538956) (xy 399.077936 -306.560054) (xy 399.118439 -306.58801) (xy 399.153932 -306.622102)
			(xy 399.183497 -306.661446) (xy 399.206368 -306.705023) (xy 399.221952 -306.751704) (xy 399.229847 -306.800281)
			(xy 399.230342 -306.824888) (xy 399.56919 -306.824888) (xy 399.57315 -306.775834) (xy 399.584927 -306.72805)
			(xy 399.604218 -306.682774) (xy 399.630521 -306.641178) (xy 399.663156 -306.604341) (xy 399.701277 -306.573216)
			(xy 399.743898 -306.548609) (xy 399.789914 -306.531157) (xy 399.838133 -306.521313) (xy 399.887308 -306.519332)
			(xy 399.936163 -306.525264) (xy 399.983434 -306.538956) (xy 400.027896 -306.560054) (xy 400.068399 -306.58801)
			(xy 400.103892 -306.622102) (xy 400.133457 -306.661446) (xy 400.156328 -306.705023) (xy 400.171912 -306.751704)
			(xy 400.179807 -306.800281) (xy 400.180302 -306.824888) (xy 400.51915 -306.824888) (xy 400.52311 -306.775834)
			(xy 400.534887 -306.72805) (xy 400.554178 -306.682774) (xy 400.580481 -306.641178) (xy 400.613116 -306.604341)
			(xy 400.651237 -306.573216) (xy 400.693858 -306.548609) (xy 400.739874 -306.531157) (xy 400.788093 -306.521313)
			(xy 400.837268 -306.519332) (xy 400.886123 -306.525264) (xy 400.933394 -306.538956) (xy 400.977856 -306.560054)
			(xy 401.018359 -306.58801) (xy 401.053852 -306.622102) (xy 401.083417 -306.661446) (xy 401.106288 -306.705023)
			(xy 401.121872 -306.751704) (xy 401.129767 -306.800281) (xy 401.130262 -306.824888) (xy 401.46911 -306.824888)
			(xy 401.47307 -306.775834) (xy 401.484847 -306.72805) (xy 401.504138 -306.682774) (xy 401.530441 -306.641178)
			(xy 401.563076 -306.604341) (xy 401.601197 -306.573216) (xy 401.643818 -306.548609) (xy 401.689834 -306.531157)
			(xy 401.738053 -306.521313) (xy 401.787228 -306.519332) (xy 401.836083 -306.525264) (xy 401.883354 -306.538956)
			(xy 401.927816 -306.560054) (xy 401.968319 -306.58801) (xy 402.003812 -306.622102) (xy 402.033377 -306.661446)
			(xy 402.056248 -306.705023) (xy 402.071832 -306.751704) (xy 402.079727 -306.800281) (xy 402.080222 -306.824888)
			(xy 402.41907 -306.824888) (xy 402.42303 -306.775834) (xy 402.434807 -306.72805) (xy 402.454098 -306.682774)
			(xy 402.480401 -306.641178) (xy 402.513036 -306.604341) (xy 402.551157 -306.573216) (xy 402.593778 -306.548609)
			(xy 402.639794 -306.531157) (xy 402.688013 -306.521313) (xy 402.737188 -306.519332) (xy 402.786043 -306.525264)
			(xy 402.833314 -306.538956) (xy 402.877776 -306.560054) (xy 402.918279 -306.58801) (xy 402.953772 -306.622102)
			(xy 402.983337 -306.661446) (xy 403.006208 -306.705023) (xy 403.021792 -306.751704) (xy 403.029687 -306.800281)
			(xy 403.030182 -306.824888) (xy 403.36903 -306.824888) (xy 403.37299 -306.775834) (xy 403.384767 -306.72805)
			(xy 403.404058 -306.682774) (xy 403.430361 -306.641178) (xy 403.462996 -306.604341) (xy 403.501117 -306.573216)
			(xy 403.543738 -306.548609) (xy 403.589754 -306.531157) (xy 403.637973 -306.521313) (xy 403.687148 -306.519332)
			(xy 403.736003 -306.525264) (xy 403.783274 -306.538956) (xy 403.827736 -306.560054) (xy 403.868239 -306.58801)
			(xy 403.903732 -306.622102) (xy 403.933297 -306.661446) (xy 403.956168 -306.705023) (xy 403.971752 -306.751704)
			(xy 403.979647 -306.800281) (xy 403.980142 -306.824888) (xy 404.31899 -306.824888) (xy 404.32295 -306.775834)
			(xy 404.334727 -306.72805) (xy 404.354018 -306.682774) (xy 404.380321 -306.641178) (xy 404.412956 -306.604341)
			(xy 404.451077 -306.573216) (xy 404.493698 -306.548609) (xy 404.539714 -306.531157) (xy 404.587933 -306.521313)
			(xy 404.637108 -306.519332) (xy 404.685963 -306.525264) (xy 404.733234 -306.538956) (xy 404.777696 -306.560054)
			(xy 404.818199 -306.58801) (xy 404.853692 -306.622102) (xy 404.883257 -306.661446) (xy 404.906128 -306.705023)
			(xy 404.921712 -306.751704) (xy 404.929607 -306.800281) (xy 404.930102 -306.824888) (xy 405.269204 -306.824888)
			(xy 405.273164 -306.775834) (xy 405.284941 -306.72805) (xy 405.304232 -306.682774) (xy 405.330535 -306.641178)
			(xy 405.36317 -306.604341) (xy 405.401291 -306.573216) (xy 405.443912 -306.548609) (xy 405.489928 -306.531157)
			(xy 405.538147 -306.521313) (xy 405.587322 -306.519332) (xy 405.636177 -306.525264) (xy 405.683448 -306.538956)
			(xy 405.72791 -306.560054) (xy 405.768413 -306.58801) (xy 405.803906 -306.622102) (xy 405.833471 -306.661446)
			(xy 405.856342 -306.705023) (xy 405.871926 -306.751704) (xy 405.879821 -306.800281) (xy 405.880316 -306.824888)
			(xy 406.219164 -306.824888) (xy 406.223124 -306.775834) (xy 406.234901 -306.72805) (xy 406.254192 -306.682774)
			(xy 406.280495 -306.641178) (xy 406.31313 -306.604341) (xy 406.351251 -306.573216) (xy 406.393872 -306.548609)
			(xy 406.439888 -306.531157) (xy 406.488107 -306.521313) (xy 406.537282 -306.519332) (xy 406.586137 -306.525264)
			(xy 406.633408 -306.538956) (xy 406.67787 -306.560054) (xy 406.718373 -306.58801) (xy 406.753866 -306.622102)
			(xy 406.783431 -306.661446) (xy 406.806302 -306.705023) (xy 406.821886 -306.751704) (xy 406.829781 -306.800281)
			(xy 406.830276 -306.824888) (xy 408.119084 -306.824888) (xy 408.123044 -306.775834) (xy 408.134821 -306.72805)
			(xy 408.154112 -306.682774) (xy 408.180415 -306.641178) (xy 408.21305 -306.604341) (xy 408.251171 -306.573216)
			(xy 408.293792 -306.548609) (xy 408.339808 -306.531157) (xy 408.388027 -306.521313) (xy 408.437202 -306.519332)
			(xy 408.486057 -306.525264) (xy 408.533328 -306.538956) (xy 408.57779 -306.560054) (xy 408.618293 -306.58801)
			(xy 408.653786 -306.622102) (xy 408.683351 -306.661446) (xy 408.706222 -306.705023) (xy 408.721806 -306.751704)
			(xy 408.729701 -306.800281) (xy 408.730196 -306.824888) (xy 409.069044 -306.824888) (xy 409.073004 -306.775834)
			(xy 409.084781 -306.72805) (xy 409.104072 -306.682774) (xy 409.130375 -306.641178) (xy 409.16301 -306.604341)
			(xy 409.201131 -306.573216) (xy 409.243752 -306.548609) (xy 409.289768 -306.531157) (xy 409.337987 -306.521313)
			(xy 409.387162 -306.519332) (xy 409.436017 -306.525264) (xy 409.483288 -306.538956) (xy 409.52775 -306.560054)
			(xy 409.568253 -306.58801) (xy 409.603746 -306.622102) (xy 409.633311 -306.661446) (xy 409.656182 -306.705023)
			(xy 409.671766 -306.751704) (xy 409.679661 -306.800281) (xy 409.680156 -306.824888) (xy 410.019004 -306.824888)
			(xy 410.022964 -306.775834) (xy 410.034741 -306.72805) (xy 410.054032 -306.682774) (xy 410.080335 -306.641178)
			(xy 410.11297 -306.604341) (xy 410.151091 -306.573216) (xy 410.193712 -306.548609) (xy 410.239728 -306.531157)
			(xy 410.287947 -306.521313) (xy 410.337122 -306.519332) (xy 410.385977 -306.525264) (xy 410.433248 -306.538956)
			(xy 410.47771 -306.560054) (xy 410.518213 -306.58801) (xy 410.553706 -306.622102) (xy 410.583271 -306.661446)
			(xy 410.606142 -306.705023) (xy 410.621726 -306.751704) (xy 410.629621 -306.800281) (xy 410.630116 -306.824888)
			(xy 410.969218 -306.824888) (xy 410.973178 -306.775834) (xy 410.984955 -306.72805) (xy 411.004246 -306.682774)
			(xy 411.030549 -306.641178) (xy 411.063184 -306.604341) (xy 411.101305 -306.573216) (xy 411.143926 -306.548609)
			(xy 411.189942 -306.531157) (xy 411.238161 -306.521313) (xy 411.287336 -306.519332) (xy 411.336191 -306.525264)
			(xy 411.383462 -306.538956) (xy 411.427924 -306.560054) (xy 411.468427 -306.58801) (xy 411.50392 -306.622102)
			(xy 411.533485 -306.661446) (xy 411.556356 -306.705023) (xy 411.57194 -306.751704) (xy 411.579835 -306.800281)
			(xy 411.58033 -306.824888) (xy 411.919178 -306.824888) (xy 411.923138 -306.775834) (xy 411.934915 -306.72805)
			(xy 411.954206 -306.682774) (xy 411.980509 -306.641178) (xy 412.013144 -306.604341) (xy 412.051265 -306.573216)
			(xy 412.093886 -306.548609) (xy 412.139902 -306.531157) (xy 412.188121 -306.521313) (xy 412.237296 -306.519332)
			(xy 412.286151 -306.525264) (xy 412.333422 -306.538956) (xy 412.377884 -306.560054) (xy 412.418387 -306.58801)
			(xy 412.45388 -306.622102) (xy 412.483445 -306.661446) (xy 412.506316 -306.705023) (xy 412.5219 -306.751704)
			(xy 412.529795 -306.800281) (xy 412.53029 -306.824888) (xy 412.869138 -306.824888) (xy 412.873098 -306.775834)
			(xy 412.884875 -306.72805) (xy 412.904166 -306.682774) (xy 412.930469 -306.641178) (xy 412.963104 -306.604341)
			(xy 413.001225 -306.573216) (xy 413.043846 -306.548609) (xy 413.089862 -306.531157) (xy 413.138081 -306.521313)
			(xy 413.187256 -306.519332) (xy 413.236111 -306.525264) (xy 413.283382 -306.538956) (xy 413.327844 -306.560054)
			(xy 413.368347 -306.58801) (xy 413.40384 -306.622102) (xy 413.433405 -306.661446) (xy 413.456276 -306.705023)
			(xy 413.47186 -306.751704) (xy 413.479755 -306.800281) (xy 413.48025 -306.824888) (xy 413.819098 -306.824888)
			(xy 413.823058 -306.775834) (xy 413.834835 -306.72805) (xy 413.854126 -306.682774) (xy 413.880429 -306.641178)
			(xy 413.913064 -306.604341) (xy 413.951185 -306.573216) (xy 413.993806 -306.548609) (xy 414.039822 -306.531157)
			(xy 414.088041 -306.521313) (xy 414.137216 -306.519332) (xy 414.186071 -306.525264) (xy 414.233342 -306.538956)
			(xy 414.277804 -306.560054) (xy 414.318307 -306.58801) (xy 414.3538 -306.622102) (xy 414.383365 -306.661446)
			(xy 414.406236 -306.705023) (xy 414.42182 -306.751704) (xy 414.429715 -306.800281) (xy 414.43021 -306.824888)
			(xy 414.769058 -306.824888) (xy 414.773018 -306.775834) (xy 414.784795 -306.72805) (xy 414.804086 -306.682774)
			(xy 414.830389 -306.641178) (xy 414.863024 -306.604341) (xy 414.901145 -306.573216) (xy 414.943766 -306.548609)
			(xy 414.989782 -306.531157) (xy 415.038001 -306.521313) (xy 415.087176 -306.519332) (xy 415.136031 -306.525264)
			(xy 415.183302 -306.538956) (xy 415.227764 -306.560054) (xy 415.268267 -306.58801) (xy 415.30376 -306.622102)
			(xy 415.333325 -306.661446) (xy 415.356196 -306.705023) (xy 415.37178 -306.751704) (xy 415.379675 -306.800281)
			(xy 415.38017 -306.824888) (xy 415.719018 -306.824888) (xy 415.722978 -306.775834) (xy 415.734755 -306.72805)
			(xy 415.754046 -306.682774) (xy 415.780349 -306.641178) (xy 415.812984 -306.604341) (xy 415.851105 -306.573216)
			(xy 415.893726 -306.548609) (xy 415.939742 -306.531157) (xy 415.987961 -306.521313) (xy 416.037136 -306.519332)
			(xy 416.085991 -306.525264) (xy 416.133262 -306.538956) (xy 416.177724 -306.560054) (xy 416.218227 -306.58801)
			(xy 416.25372 -306.622102) (xy 416.283285 -306.661446) (xy 416.306156 -306.705023) (xy 416.32174 -306.751704)
			(xy 416.329635 -306.800281) (xy 416.33013 -306.824888) (xy 416.668978 -306.824888) (xy 416.672938 -306.775834)
			(xy 416.684715 -306.72805) (xy 416.704006 -306.682774) (xy 416.730309 -306.641178) (xy 416.762944 -306.604341)
			(xy 416.801065 -306.573216) (xy 416.843686 -306.548609) (xy 416.889702 -306.531157) (xy 416.937921 -306.521313)
			(xy 416.987096 -306.519332) (xy 417.035951 -306.525264) (xy 417.083222 -306.538956) (xy 417.127684 -306.560054)
			(xy 417.168187 -306.58801) (xy 417.20368 -306.622102) (xy 417.233245 -306.661446) (xy 417.256116 -306.705023)
			(xy 417.2717 -306.751704) (xy 417.279595 -306.800281) (xy 417.28009 -306.824888) (xy 417.619192 -306.824888)
			(xy 417.623152 -306.775834) (xy 417.634929 -306.72805) (xy 417.65422 -306.682774) (xy 417.680523 -306.641178)
			(xy 417.713158 -306.604341) (xy 417.751279 -306.573216) (xy 417.7939 -306.548609) (xy 417.839916 -306.531157)
			(xy 417.888135 -306.521313) (xy 417.93731 -306.519332) (xy 417.986165 -306.525264) (xy 418.033436 -306.538956)
			(xy 418.077898 -306.560054) (xy 418.118401 -306.58801) (xy 418.153894 -306.622102) (xy 418.183459 -306.661446)
			(xy 418.20633 -306.705023) (xy 418.221914 -306.751704) (xy 418.229809 -306.800281) (xy 418.230304 -306.824888)
			(xy 418.569152 -306.824888) (xy 418.573112 -306.775834) (xy 418.584889 -306.72805) (xy 418.60418 -306.682774)
			(xy 418.630483 -306.641178) (xy 418.663118 -306.604341) (xy 418.701239 -306.573216) (xy 418.74386 -306.548609)
			(xy 418.789876 -306.531157) (xy 418.838095 -306.521313) (xy 418.88727 -306.519332) (xy 418.936125 -306.525264)
			(xy 418.983396 -306.538956) (xy 419.027858 -306.560054) (xy 419.068361 -306.58801) (xy 419.103854 -306.622102)
			(xy 419.133419 -306.661446) (xy 419.15629 -306.705023) (xy 419.171874 -306.751704) (xy 419.179769 -306.800281)
			(xy 419.180264 -306.824888) (xy 419.179769 -306.849495) (xy 419.171874 -306.898072) (xy 419.15629 -306.944753)
			(xy 419.133419 -306.98833) (xy 419.103854 -307.027674) (xy 419.068361 -307.061766) (xy 419.027858 -307.089722)
			(xy 418.983396 -307.11082) (xy 418.936125 -307.124512) (xy 418.88727 -307.130444) (xy 418.838095 -307.128463)
			(xy 418.789876 -307.118619) (xy 418.74386 -307.101167) (xy 418.701239 -307.07656) (xy 418.663118 -307.045435)
			(xy 418.630483 -307.008598) (xy 418.60418 -306.967002) (xy 418.584889 -306.921726) (xy 418.573112 -306.873942)
			(xy 418.569152 -306.824888) (xy 418.230304 -306.824888) (xy 418.229809 -306.849495) (xy 418.221914 -306.898072)
			(xy 418.20633 -306.944753) (xy 418.183459 -306.98833) (xy 418.153894 -307.027674) (xy 418.118401 -307.061766)
			(xy 418.077898 -307.089722) (xy 418.033436 -307.11082) (xy 417.986165 -307.124512) (xy 417.93731 -307.130444)
			(xy 417.888135 -307.128463) (xy 417.839916 -307.118619) (xy 417.7939 -307.101167) (xy 417.751279 -307.07656)
			(xy 417.713158 -307.045435) (xy 417.680523 -307.008598) (xy 417.65422 -306.967002) (xy 417.634929 -306.921726)
			(xy 417.623152 -306.873942) (xy 417.619192 -306.824888) (xy 417.28009 -306.824888) (xy 417.279595 -306.849495)
			(xy 417.2717 -306.898072) (xy 417.256116 -306.944753) (xy 417.233245 -306.98833) (xy 417.20368 -307.027674)
			(xy 417.168187 -307.061766) (xy 417.127684 -307.089722) (xy 417.083222 -307.11082) (xy 417.035951 -307.124512)
			(xy 416.987096 -307.130444) (xy 416.937921 -307.128463) (xy 416.889702 -307.118619) (xy 416.843686 -307.101167)
			(xy 416.801065 -307.07656) (xy 416.762944 -307.045435) (xy 416.730309 -307.008598) (xy 416.704006 -306.967002)
			(xy 416.684715 -306.921726) (xy 416.672938 -306.873942) (xy 416.668978 -306.824888) (xy 416.33013 -306.824888)
			(xy 416.329635 -306.849495) (xy 416.32174 -306.898072) (xy 416.306156 -306.944753) (xy 416.283285 -306.98833)
			(xy 416.25372 -307.027674) (xy 416.218227 -307.061766) (xy 416.177724 -307.089722) (xy 416.133262 -307.11082)
			(xy 416.085991 -307.124512) (xy 416.037136 -307.130444) (xy 415.987961 -307.128463) (xy 415.939742 -307.118619)
			(xy 415.893726 -307.101167) (xy 415.851105 -307.07656) (xy 415.812984 -307.045435) (xy 415.780349 -307.008598)
			(xy 415.754046 -306.967002) (xy 415.734755 -306.921726) (xy 415.722978 -306.873942) (xy 415.719018 -306.824888)
			(xy 415.38017 -306.824888) (xy 415.379675 -306.849495) (xy 415.37178 -306.898072) (xy 415.356196 -306.944753)
			(xy 415.333325 -306.98833) (xy 415.30376 -307.027674) (xy 415.268267 -307.061766) (xy 415.227764 -307.089722)
			(xy 415.183302 -307.11082) (xy 415.136031 -307.124512) (xy 415.087176 -307.130444) (xy 415.038001 -307.128463)
			(xy 414.989782 -307.118619) (xy 414.943766 -307.101167) (xy 414.901145 -307.07656) (xy 414.863024 -307.045435)
			(xy 414.830389 -307.008598) (xy 414.804086 -306.967002) (xy 414.784795 -306.921726) (xy 414.773018 -306.873942)
			(xy 414.769058 -306.824888) (xy 414.43021 -306.824888) (xy 414.429715 -306.849495) (xy 414.42182 -306.898072)
			(xy 414.406236 -306.944753) (xy 414.383365 -306.98833) (xy 414.3538 -307.027674) (xy 414.318307 -307.061766)
			(xy 414.277804 -307.089722) (xy 414.233342 -307.11082) (xy 414.186071 -307.124512) (xy 414.137216 -307.130444)
			(xy 414.088041 -307.128463) (xy 414.039822 -307.118619) (xy 413.993806 -307.101167) (xy 413.951185 -307.07656)
			(xy 413.913064 -307.045435) (xy 413.880429 -307.008598) (xy 413.854126 -306.967002) (xy 413.834835 -306.921726)
			(xy 413.823058 -306.873942) (xy 413.819098 -306.824888) (xy 413.48025 -306.824888) (xy 413.479755 -306.849495)
			(xy 413.47186 -306.898072) (xy 413.456276 -306.944753) (xy 413.433405 -306.98833) (xy 413.40384 -307.027674)
			(xy 413.368347 -307.061766) (xy 413.327844 -307.089722) (xy 413.283382 -307.11082) (xy 413.236111 -307.124512)
			(xy 413.187256 -307.130444) (xy 413.138081 -307.128463) (xy 413.089862 -307.118619) (xy 413.043846 -307.101167)
			(xy 413.001225 -307.07656) (xy 412.963104 -307.045435) (xy 412.930469 -307.008598) (xy 412.904166 -306.967002)
			(xy 412.884875 -306.921726) (xy 412.873098 -306.873942) (xy 412.869138 -306.824888) (xy 412.53029 -306.824888)
			(xy 412.529795 -306.849495) (xy 412.5219 -306.898072) (xy 412.506316 -306.944753) (xy 412.483445 -306.98833)
			(xy 412.45388 -307.027674) (xy 412.418387 -307.061766) (xy 412.377884 -307.089722) (xy 412.333422 -307.11082)
			(xy 412.286151 -307.124512) (xy 412.237296 -307.130444) (xy 412.188121 -307.128463) (xy 412.139902 -307.118619)
			(xy 412.093886 -307.101167) (xy 412.051265 -307.07656) (xy 412.013144 -307.045435) (xy 411.980509 -307.008598)
			(xy 411.954206 -306.967002) (xy 411.934915 -306.921726) (xy 411.923138 -306.873942) (xy 411.919178 -306.824888)
			(xy 411.58033 -306.824888) (xy 411.579835 -306.849495) (xy 411.57194 -306.898072) (xy 411.556356 -306.944753)
			(xy 411.533485 -306.98833) (xy 411.50392 -307.027674) (xy 411.468427 -307.061766) (xy 411.427924 -307.089722)
			(xy 411.383462 -307.11082) (xy 411.336191 -307.124512) (xy 411.287336 -307.130444) (xy 411.238161 -307.128463)
			(xy 411.189942 -307.118619) (xy 411.143926 -307.101167) (xy 411.101305 -307.07656) (xy 411.063184 -307.045435)
			(xy 411.030549 -307.008598) (xy 411.004246 -306.967002) (xy 410.984955 -306.921726) (xy 410.973178 -306.873942)
			(xy 410.969218 -306.824888) (xy 410.630116 -306.824888) (xy 410.629621 -306.849495) (xy 410.621726 -306.898072)
			(xy 410.606142 -306.944753) (xy 410.583271 -306.98833) (xy 410.553706 -307.027674) (xy 410.518213 -307.061766)
			(xy 410.47771 -307.089722) (xy 410.433248 -307.11082) (xy 410.385977 -307.124512) (xy 410.337122 -307.130444)
			(xy 410.287947 -307.128463) (xy 410.239728 -307.118619) (xy 410.193712 -307.101167) (xy 410.151091 -307.07656)
			(xy 410.11297 -307.045435) (xy 410.080335 -307.008598) (xy 410.054032 -306.967002) (xy 410.034741 -306.921726)
			(xy 410.022964 -306.873942) (xy 410.019004 -306.824888) (xy 409.680156 -306.824888) (xy 409.679661 -306.849495)
			(xy 409.671766 -306.898072) (xy 409.656182 -306.944753) (xy 409.633311 -306.98833) (xy 409.603746 -307.027674)
			(xy 409.568253 -307.061766) (xy 409.52775 -307.089722) (xy 409.483288 -307.11082) (xy 409.436017 -307.124512)
			(xy 409.387162 -307.130444) (xy 409.337987 -307.128463) (xy 409.289768 -307.118619) (xy 409.243752 -307.101167)
			(xy 409.201131 -307.07656) (xy 409.16301 -307.045435) (xy 409.130375 -307.008598) (xy 409.104072 -306.967002)
			(xy 409.084781 -306.921726) (xy 409.073004 -306.873942) (xy 409.069044 -306.824888) (xy 408.730196 -306.824888)
			(xy 408.729701 -306.849495) (xy 408.721806 -306.898072) (xy 408.706222 -306.944753) (xy 408.683351 -306.98833)
			(xy 408.653786 -307.027674) (xy 408.618293 -307.061766) (xy 408.57779 -307.089722) (xy 408.533328 -307.11082)
			(xy 408.486057 -307.124512) (xy 408.437202 -307.130444) (xy 408.388027 -307.128463) (xy 408.339808 -307.118619)
			(xy 408.293792 -307.101167) (xy 408.251171 -307.07656) (xy 408.21305 -307.045435) (xy 408.180415 -307.008598)
			(xy 408.154112 -306.967002) (xy 408.134821 -306.921726) (xy 408.123044 -306.873942) (xy 408.119084 -306.824888)
			(xy 406.830276 -306.824888) (xy 406.829781 -306.849495) (xy 406.821886 -306.898072) (xy 406.806302 -306.944753)
			(xy 406.783431 -306.98833) (xy 406.753866 -307.027674) (xy 406.718373 -307.061766) (xy 406.67787 -307.089722)
			(xy 406.633408 -307.11082) (xy 406.586137 -307.124512) (xy 406.537282 -307.130444) (xy 406.488107 -307.128463)
			(xy 406.439888 -307.118619) (xy 406.393872 -307.101167) (xy 406.351251 -307.07656) (xy 406.31313 -307.045435)
			(xy 406.280495 -307.008598) (xy 406.254192 -306.967002) (xy 406.234901 -306.921726) (xy 406.223124 -306.873942)
			(xy 406.219164 -306.824888) (xy 405.880316 -306.824888) (xy 405.879821 -306.849495) (xy 405.871926 -306.898072)
			(xy 405.856342 -306.944753) (xy 405.833471 -306.98833) (xy 405.803906 -307.027674) (xy 405.768413 -307.061766)
			(xy 405.72791 -307.089722) (xy 405.683448 -307.11082) (xy 405.636177 -307.124512) (xy 405.587322 -307.130444)
			(xy 405.538147 -307.128463) (xy 405.489928 -307.118619) (xy 405.443912 -307.101167) (xy 405.401291 -307.07656)
			(xy 405.36317 -307.045435) (xy 405.330535 -307.008598) (xy 405.304232 -306.967002) (xy 405.284941 -306.921726)
			(xy 405.273164 -306.873942) (xy 405.269204 -306.824888) (xy 404.930102 -306.824888) (xy 404.929607 -306.849495)
			(xy 404.921712 -306.898072) (xy 404.906128 -306.944753) (xy 404.883257 -306.98833) (xy 404.853692 -307.027674)
			(xy 404.818199 -307.061766) (xy 404.777696 -307.089722) (xy 404.733234 -307.11082) (xy 404.685963 -307.124512)
			(xy 404.637108 -307.130444) (xy 404.587933 -307.128463) (xy 404.539714 -307.118619) (xy 404.493698 -307.101167)
			(xy 404.451077 -307.07656) (xy 404.412956 -307.045435) (xy 404.380321 -307.008598) (xy 404.354018 -306.967002)
			(xy 404.334727 -306.921726) (xy 404.32295 -306.873942) (xy 404.31899 -306.824888) (xy 403.980142 -306.824888)
			(xy 403.979647 -306.849495) (xy 403.971752 -306.898072) (xy 403.956168 -306.944753) (xy 403.933297 -306.98833)
			(xy 403.903732 -307.027674) (xy 403.868239 -307.061766) (xy 403.827736 -307.089722) (xy 403.783274 -307.11082)
			(xy 403.736003 -307.124512) (xy 403.687148 -307.130444) (xy 403.637973 -307.128463) (xy 403.589754 -307.118619)
			(xy 403.543738 -307.101167) (xy 403.501117 -307.07656) (xy 403.462996 -307.045435) (xy 403.430361 -307.008598)
			(xy 403.404058 -306.967002) (xy 403.384767 -306.921726) (xy 403.37299 -306.873942) (xy 403.36903 -306.824888)
			(xy 403.030182 -306.824888) (xy 403.029687 -306.849495) (xy 403.021792 -306.898072) (xy 403.006208 -306.944753)
			(xy 402.983337 -306.98833) (xy 402.953772 -307.027674) (xy 402.918279 -307.061766) (xy 402.877776 -307.089722)
			(xy 402.833314 -307.11082) (xy 402.786043 -307.124512) (xy 402.737188 -307.130444) (xy 402.688013 -307.128463)
			(xy 402.639794 -307.118619) (xy 402.593778 -307.101167) (xy 402.551157 -307.07656) (xy 402.513036 -307.045435)
			(xy 402.480401 -307.008598) (xy 402.454098 -306.967002) (xy 402.434807 -306.921726) (xy 402.42303 -306.873942)
			(xy 402.41907 -306.824888) (xy 402.080222 -306.824888) (xy 402.079727 -306.849495) (xy 402.071832 -306.898072)
			(xy 402.056248 -306.944753) (xy 402.033377 -306.98833) (xy 402.003812 -307.027674) (xy 401.968319 -307.061766)
			(xy 401.927816 -307.089722) (xy 401.883354 -307.11082) (xy 401.836083 -307.124512) (xy 401.787228 -307.130444)
			(xy 401.738053 -307.128463) (xy 401.689834 -307.118619) (xy 401.643818 -307.101167) (xy 401.601197 -307.07656)
			(xy 401.563076 -307.045435) (xy 401.530441 -307.008598) (xy 401.504138 -306.967002) (xy 401.484847 -306.921726)
			(xy 401.47307 -306.873942) (xy 401.46911 -306.824888) (xy 401.130262 -306.824888) (xy 401.129767 -306.849495)
			(xy 401.121872 -306.898072) (xy 401.106288 -306.944753) (xy 401.083417 -306.98833) (xy 401.053852 -307.027674)
			(xy 401.018359 -307.061766) (xy 400.977856 -307.089722) (xy 400.933394 -307.11082) (xy 400.886123 -307.124512)
			(xy 400.837268 -307.130444) (xy 400.788093 -307.128463) (xy 400.739874 -307.118619) (xy 400.693858 -307.101167)
			(xy 400.651237 -307.07656) (xy 400.613116 -307.045435) (xy 400.580481 -307.008598) (xy 400.554178 -306.967002)
			(xy 400.534887 -306.921726) (xy 400.52311 -306.873942) (xy 400.51915 -306.824888) (xy 400.180302 -306.824888)
			(xy 400.179807 -306.849495) (xy 400.171912 -306.898072) (xy 400.156328 -306.944753) (xy 400.133457 -306.98833)
			(xy 400.103892 -307.027674) (xy 400.068399 -307.061766) (xy 400.027896 -307.089722) (xy 399.983434 -307.11082)
			(xy 399.936163 -307.124512) (xy 399.887308 -307.130444) (xy 399.838133 -307.128463) (xy 399.789914 -307.118619)
			(xy 399.743898 -307.101167) (xy 399.701277 -307.07656) (xy 399.663156 -307.045435) (xy 399.630521 -307.008598)
			(xy 399.604218 -306.967002) (xy 399.584927 -306.921726) (xy 399.57315 -306.873942) (xy 399.56919 -306.824888)
			(xy 399.230342 -306.824888) (xy 399.229847 -306.849495) (xy 399.221952 -306.898072) (xy 399.206368 -306.944753)
			(xy 399.183497 -306.98833) (xy 399.153932 -307.027674) (xy 399.118439 -307.061766) (xy 399.077936 -307.089722)
			(xy 399.033474 -307.11082) (xy 398.986203 -307.124512) (xy 398.937348 -307.130444) (xy 398.888173 -307.128463)
			(xy 398.839954 -307.118619) (xy 398.793938 -307.101167) (xy 398.751317 -307.07656) (xy 398.713196 -307.045435)
			(xy 398.680561 -307.008598) (xy 398.654258 -306.967002) (xy 398.634967 -306.921726) (xy 398.62319 -306.873942)
			(xy 398.61923 -306.824888) (xy 398.280128 -306.824888) (xy 398.279633 -306.849495) (xy 398.271738 -306.898072)
			(xy 398.256154 -306.944753) (xy 398.233283 -306.98833) (xy 398.203718 -307.027674) (xy 398.168225 -307.061766)
			(xy 398.127722 -307.089722) (xy 398.08326 -307.11082) (xy 398.035989 -307.124512) (xy 397.987134 -307.130444)
			(xy 397.937959 -307.128463) (xy 397.88974 -307.118619) (xy 397.843724 -307.101167) (xy 397.801103 -307.07656)
			(xy 397.762982 -307.045435) (xy 397.730347 -307.008598) (xy 397.704044 -306.967002) (xy 397.684753 -306.921726)
			(xy 397.672976 -306.873942) (xy 397.669016 -306.824888) (xy 397.355158 -306.824888) (xy 397.355159 -306.851261)
			(xy 397.346795 -306.903319) (xy 397.330278 -306.95339) (xy 397.306028 -307.000208) (xy 397.274657 -307.042585)
			(xy 397.236962 -307.07945) (xy 397.193895 -307.109867) (xy 397.146548 -307.133068) (xy 397.096121 -307.148463)
			(xy 397.070072 -307.152548) (xy 397.066008 -307.153056) (xy 397.054578 -307.156612) (xy 397.05026 -307.157882)
			(xy 397.02613 -307.169058) (xy 397.019526 -307.17617) (xy 397.004794 -307.191664) (xy 396.996666 -307.20284)
			(xy 396.993967 -307.208371) (xy 396.991005 -307.220311) (xy 396.990824 -307.226462) (xy 396.990824 -307.373274)
			(xy 396.990994 -307.379427) (xy 396.993948 -307.391373) (xy 396.996666 -307.396896) (xy 397.004794 -307.408072)
			(xy 397.019526 -307.423566) (xy 397.02613 -307.430678) (xy 397.05026 -307.441854) (xy 397.054578 -307.443124)
			(xy 397.066008 -307.44668) (xy 397.070072 -307.447188) (xy 397.096113 -307.451296) (xy 397.146531 -307.466689)
			(xy 397.193869 -307.489886) (xy 397.236927 -307.520299) (xy 397.274616 -307.557157) (xy 397.30598 -307.599528)
			(xy 397.330225 -307.646337) (xy 397.346738 -307.6964) (xy 397.3551 -307.748449) (xy 397.355099 -307.774848)
			(xy 397.669016 -307.774848) (xy 397.672976 -307.725794) (xy 397.684753 -307.67801) (xy 397.704044 -307.632734)
			(xy 397.730347 -307.591138) (xy 397.762982 -307.554301) (xy 397.801103 -307.523176) (xy 397.843724 -307.498569)
			(xy 397.88974 -307.481117) (xy 397.937959 -307.471273) (xy 397.987134 -307.469292) (xy 398.035989 -307.475224)
			(xy 398.08326 -307.488916) (xy 398.127722 -307.510014) (xy 398.168225 -307.53797) (xy 398.203718 -307.572062)
			(xy 398.233283 -307.611406) (xy 398.256154 -307.654983) (xy 398.271738 -307.701664) (xy 398.279633 -307.750241)
			(xy 398.280128 -307.774848) (xy 398.61923 -307.774848) (xy 398.62319 -307.725794) (xy 398.634967 -307.67801)
			(xy 398.654258 -307.632734) (xy 398.680561 -307.591138) (xy 398.713196 -307.554301) (xy 398.751317 -307.523176)
			(xy 398.793938 -307.498569) (xy 398.839954 -307.481117) (xy 398.888173 -307.471273) (xy 398.937348 -307.469292)
			(xy 398.986203 -307.475224) (xy 399.033474 -307.488916) (xy 399.077936 -307.510014) (xy 399.118439 -307.53797)
			(xy 399.153932 -307.572062) (xy 399.183497 -307.611406) (xy 399.206368 -307.654983) (xy 399.221952 -307.701664)
			(xy 399.229847 -307.750241) (xy 399.230342 -307.774848) (xy 399.56919 -307.774848) (xy 399.57315 -307.725794)
			(xy 399.584927 -307.67801) (xy 399.604218 -307.632734) (xy 399.630521 -307.591138) (xy 399.663156 -307.554301)
			(xy 399.701277 -307.523176) (xy 399.743898 -307.498569) (xy 399.789914 -307.481117) (xy 399.838133 -307.471273)
			(xy 399.887308 -307.469292) (xy 399.936163 -307.475224) (xy 399.983434 -307.488916) (xy 400.027896 -307.510014)
			(xy 400.068399 -307.53797) (xy 400.103892 -307.572062) (xy 400.133457 -307.611406) (xy 400.156328 -307.654983)
			(xy 400.171912 -307.701664) (xy 400.179807 -307.750241) (xy 400.180302 -307.774848) (xy 400.51915 -307.774848)
			(xy 400.52311 -307.725794) (xy 400.534887 -307.67801) (xy 400.554178 -307.632734) (xy 400.580481 -307.591138)
			(xy 400.613116 -307.554301) (xy 400.651237 -307.523176) (xy 400.693858 -307.498569) (xy 400.739874 -307.481117)
			(xy 400.788093 -307.471273) (xy 400.837268 -307.469292) (xy 400.886123 -307.475224) (xy 400.933394 -307.488916)
			(xy 400.977856 -307.510014) (xy 401.018359 -307.53797) (xy 401.053852 -307.572062) (xy 401.083417 -307.611406)
			(xy 401.106288 -307.654983) (xy 401.121872 -307.701664) (xy 401.129767 -307.750241) (xy 401.130262 -307.774848)
			(xy 401.46911 -307.774848) (xy 401.47307 -307.725794) (xy 401.484847 -307.67801) (xy 401.504138 -307.632734)
			(xy 401.530441 -307.591138) (xy 401.563076 -307.554301) (xy 401.601197 -307.523176) (xy 401.643818 -307.498569)
			(xy 401.689834 -307.481117) (xy 401.738053 -307.471273) (xy 401.787228 -307.469292) (xy 401.836083 -307.475224)
			(xy 401.883354 -307.488916) (xy 401.927816 -307.510014) (xy 401.968319 -307.53797) (xy 402.003812 -307.572062)
			(xy 402.033377 -307.611406) (xy 402.056248 -307.654983) (xy 402.071832 -307.701664) (xy 402.079727 -307.750241)
			(xy 402.080222 -307.774848) (xy 402.41907 -307.774848) (xy 402.42303 -307.725794) (xy 402.434807 -307.67801)
			(xy 402.454098 -307.632734) (xy 402.480401 -307.591138) (xy 402.513036 -307.554301) (xy 402.551157 -307.523176)
			(xy 402.593778 -307.498569) (xy 402.639794 -307.481117) (xy 402.688013 -307.471273) (xy 402.737188 -307.469292)
			(xy 402.786043 -307.475224) (xy 402.833314 -307.488916) (xy 402.877776 -307.510014) (xy 402.918279 -307.53797)
			(xy 402.953772 -307.572062) (xy 402.983337 -307.611406) (xy 403.006208 -307.654983) (xy 403.021792 -307.701664)
			(xy 403.029687 -307.750241) (xy 403.030182 -307.774848) (xy 403.36903 -307.774848) (xy 403.37299 -307.725794)
			(xy 403.384767 -307.67801) (xy 403.404058 -307.632734) (xy 403.430361 -307.591138) (xy 403.462996 -307.554301)
			(xy 403.501117 -307.523176) (xy 403.543738 -307.498569) (xy 403.589754 -307.481117) (xy 403.637973 -307.471273)
			(xy 403.687148 -307.469292) (xy 403.736003 -307.475224) (xy 403.783274 -307.488916) (xy 403.827736 -307.510014)
			(xy 403.868239 -307.53797) (xy 403.903732 -307.572062) (xy 403.933297 -307.611406) (xy 403.956168 -307.654983)
			(xy 403.971752 -307.701664) (xy 403.979647 -307.750241) (xy 403.980142 -307.774848) (xy 404.319244 -307.774848)
			(xy 404.323204 -307.725794) (xy 404.334981 -307.67801) (xy 404.354272 -307.632734) (xy 404.380575 -307.591138)
			(xy 404.41321 -307.554301) (xy 404.451331 -307.523176) (xy 404.493952 -307.498569) (xy 404.539968 -307.481117)
			(xy 404.588187 -307.471273) (xy 404.637362 -307.469292) (xy 404.686217 -307.475224) (xy 404.733488 -307.488916)
			(xy 404.77795 -307.510014) (xy 404.818453 -307.53797) (xy 404.853946 -307.572062) (xy 404.883511 -307.611406)
			(xy 404.906382 -307.654983) (xy 404.921966 -307.701664) (xy 404.929861 -307.750241) (xy 404.930356 -307.774848)
			(xy 405.269204 -307.774848) (xy 405.273164 -307.725794) (xy 405.284941 -307.67801) (xy 405.304232 -307.632734)
			(xy 405.330535 -307.591138) (xy 405.36317 -307.554301) (xy 405.401291 -307.523176) (xy 405.443912 -307.498569)
			(xy 405.489928 -307.481117) (xy 405.538147 -307.471273) (xy 405.587322 -307.469292) (xy 405.636177 -307.475224)
			(xy 405.683448 -307.488916) (xy 405.72791 -307.510014) (xy 405.768413 -307.53797) (xy 405.803906 -307.572062)
			(xy 405.833471 -307.611406) (xy 405.856342 -307.654983) (xy 405.871926 -307.701664) (xy 405.879821 -307.750241)
			(xy 405.880316 -307.774848) (xy 406.219164 -307.774848) (xy 406.223124 -307.725794) (xy 406.234901 -307.67801)
			(xy 406.254192 -307.632734) (xy 406.280495 -307.591138) (xy 406.31313 -307.554301) (xy 406.351251 -307.523176)
			(xy 406.393872 -307.498569) (xy 406.439888 -307.481117) (xy 406.488107 -307.471273) (xy 406.537282 -307.469292)
			(xy 406.586137 -307.475224) (xy 406.633408 -307.488916) (xy 406.67787 -307.510014) (xy 406.718373 -307.53797)
			(xy 406.753866 -307.572062) (xy 406.783431 -307.611406) (xy 406.806302 -307.654983) (xy 406.821886 -307.701664)
			(xy 406.829781 -307.750241) (xy 406.830276 -307.774848) (xy 408.119084 -307.774848) (xy 408.123044 -307.725794)
			(xy 408.134821 -307.67801) (xy 408.154112 -307.632734) (xy 408.180415 -307.591138) (xy 408.21305 -307.554301)
			(xy 408.251171 -307.523176) (xy 408.293792 -307.498569) (xy 408.339808 -307.481117) (xy 408.388027 -307.471273)
			(xy 408.437202 -307.469292) (xy 408.486057 -307.475224) (xy 408.533328 -307.488916) (xy 408.57779 -307.510014)
			(xy 408.618293 -307.53797) (xy 408.653786 -307.572062) (xy 408.683351 -307.611406) (xy 408.706222 -307.654983)
			(xy 408.721806 -307.701664) (xy 408.729701 -307.750241) (xy 408.730196 -307.774848) (xy 409.069044 -307.774848)
			(xy 409.073004 -307.725794) (xy 409.084781 -307.67801) (xy 409.104072 -307.632734) (xy 409.130375 -307.591138)
			(xy 409.16301 -307.554301) (xy 409.201131 -307.523176) (xy 409.243752 -307.498569) (xy 409.289768 -307.481117)
			(xy 409.337987 -307.471273) (xy 409.387162 -307.469292) (xy 409.436017 -307.475224) (xy 409.483288 -307.488916)
			(xy 409.52775 -307.510014) (xy 409.568253 -307.53797) (xy 409.603746 -307.572062) (xy 409.633311 -307.611406)
			(xy 409.656182 -307.654983) (xy 409.671766 -307.701664) (xy 409.679661 -307.750241) (xy 409.680156 -307.774848)
			(xy 410.019004 -307.774848) (xy 410.022964 -307.725794) (xy 410.034741 -307.67801) (xy 410.054032 -307.632734)
			(xy 410.080335 -307.591138) (xy 410.11297 -307.554301) (xy 410.151091 -307.523176) (xy 410.193712 -307.498569)
			(xy 410.239728 -307.481117) (xy 410.287947 -307.471273) (xy 410.337122 -307.469292) (xy 410.385977 -307.475224)
			(xy 410.433248 -307.488916) (xy 410.47771 -307.510014) (xy 410.518213 -307.53797) (xy 410.553706 -307.572062)
			(xy 410.583271 -307.611406) (xy 410.606142 -307.654983) (xy 410.621726 -307.701664) (xy 410.629621 -307.750241)
			(xy 410.630111 -307.774594) (xy 410.968964 -307.774594) (xy 410.972924 -307.72554) (xy 410.984701 -307.677756)
			(xy 411.003992 -307.63248) (xy 411.030295 -307.590884) (xy 411.06293 -307.554047) (xy 411.101051 -307.522922)
			(xy 411.143672 -307.498315) (xy 411.189688 -307.480863) (xy 411.237907 -307.471019) (xy 411.287082 -307.469038)
			(xy 411.335937 -307.47497) (xy 411.383208 -307.488662) (xy 411.42767 -307.50976) (xy 411.468173 -307.537716)
			(xy 411.503666 -307.571808) (xy 411.533231 -307.611152) (xy 411.556102 -307.654729) (xy 411.571686 -307.70141)
			(xy 411.579581 -307.749987) (xy 411.580076 -307.774594) (xy 411.919178 -307.774594) (xy 411.923138 -307.72554)
			(xy 411.934915 -307.677756) (xy 411.954206 -307.63248) (xy 411.980509 -307.590884) (xy 412.013144 -307.554047)
			(xy 412.051265 -307.522922) (xy 412.093886 -307.498315) (xy 412.139902 -307.480863) (xy 412.188121 -307.471019)
			(xy 412.237296 -307.469038) (xy 412.286151 -307.47497) (xy 412.333422 -307.488662) (xy 412.377884 -307.50976)
			(xy 412.418387 -307.537716) (xy 412.45388 -307.571808) (xy 412.483445 -307.611152) (xy 412.506316 -307.654729)
			(xy 412.5219 -307.70141) (xy 412.529795 -307.749987) (xy 412.53029 -307.774594) (xy 412.530285 -307.774848)
			(xy 412.869138 -307.774848) (xy 412.873098 -307.725794) (xy 412.884875 -307.67801) (xy 412.904166 -307.632734)
			(xy 412.930469 -307.591138) (xy 412.963104 -307.554301) (xy 413.001225 -307.523176) (xy 413.043846 -307.498569)
			(xy 413.089862 -307.481117) (xy 413.138081 -307.471273) (xy 413.187256 -307.469292) (xy 413.236111 -307.475224)
			(xy 413.283382 -307.488916) (xy 413.327844 -307.510014) (xy 413.368347 -307.53797) (xy 413.40384 -307.572062)
			(xy 413.433405 -307.611406) (xy 413.456276 -307.654983) (xy 413.47186 -307.701664) (xy 413.479755 -307.750241)
			(xy 413.48025 -307.774848) (xy 413.819098 -307.774848) (xy 413.823058 -307.725794) (xy 413.834835 -307.67801)
			(xy 413.854126 -307.632734) (xy 413.880429 -307.591138) (xy 413.913064 -307.554301) (xy 413.951185 -307.523176)
			(xy 413.993806 -307.498569) (xy 414.039822 -307.481117) (xy 414.088041 -307.471273) (xy 414.137216 -307.469292)
			(xy 414.186071 -307.475224) (xy 414.233342 -307.488916) (xy 414.277804 -307.510014) (xy 414.318307 -307.53797)
			(xy 414.3538 -307.572062) (xy 414.383365 -307.611406) (xy 414.406236 -307.654983) (xy 414.42182 -307.701664)
			(xy 414.429715 -307.750241) (xy 414.43021 -307.774848) (xy 414.769058 -307.774848) (xy 414.773018 -307.725794)
			(xy 414.784795 -307.67801) (xy 414.804086 -307.632734) (xy 414.830389 -307.591138) (xy 414.863024 -307.554301)
			(xy 414.901145 -307.523176) (xy 414.943766 -307.498569) (xy 414.989782 -307.481117) (xy 415.038001 -307.471273)
			(xy 415.087176 -307.469292) (xy 415.136031 -307.475224) (xy 415.183302 -307.488916) (xy 415.227764 -307.510014)
			(xy 415.268267 -307.53797) (xy 415.30376 -307.572062) (xy 415.333325 -307.611406) (xy 415.356196 -307.654983)
			(xy 415.37178 -307.701664) (xy 415.379675 -307.750241) (xy 415.38017 -307.774848) (xy 415.719018 -307.774848)
			(xy 415.722978 -307.725794) (xy 415.734755 -307.67801) (xy 415.754046 -307.632734) (xy 415.780349 -307.591138)
			(xy 415.812984 -307.554301) (xy 415.851105 -307.523176) (xy 415.893726 -307.498569) (xy 415.939742 -307.481117)
			(xy 415.987961 -307.471273) (xy 416.037136 -307.469292) (xy 416.085991 -307.475224) (xy 416.133262 -307.488916)
			(xy 416.177724 -307.510014) (xy 416.218227 -307.53797) (xy 416.25372 -307.572062) (xy 416.283285 -307.611406)
			(xy 416.306156 -307.654983) (xy 416.32174 -307.701664) (xy 416.329635 -307.750241) (xy 416.33013 -307.774848)
			(xy 416.329635 -307.799455) (xy 416.32174 -307.848032) (xy 416.306156 -307.894713) (xy 416.283285 -307.93829)
			(xy 416.25372 -307.977634) (xy 416.218227 -308.011726) (xy 416.177724 -308.039682) (xy 416.133262 -308.06078)
			(xy 416.085991 -308.074472) (xy 416.037136 -308.080404) (xy 415.987961 -308.078423) (xy 415.939742 -308.068579)
			(xy 415.893726 -308.051127) (xy 415.851105 -308.02652) (xy 415.812984 -307.995395) (xy 415.780349 -307.958558)
			(xy 415.754046 -307.916962) (xy 415.734755 -307.871686) (xy 415.722978 -307.823902) (xy 415.719018 -307.774848)
			(xy 415.38017 -307.774848) (xy 415.379675 -307.799455) (xy 415.37178 -307.848032) (xy 415.356196 -307.894713)
			(xy 415.333325 -307.93829) (xy 415.30376 -307.977634) (xy 415.268267 -308.011726) (xy 415.227764 -308.039682)
			(xy 415.183302 -308.06078) (xy 415.136031 -308.074472) (xy 415.087176 -308.080404) (xy 415.038001 -308.078423)
			(xy 414.989782 -308.068579) (xy 414.943766 -308.051127) (xy 414.901145 -308.02652) (xy 414.863024 -307.995395)
			(xy 414.830389 -307.958558) (xy 414.804086 -307.916962) (xy 414.784795 -307.871686) (xy 414.773018 -307.823902)
			(xy 414.769058 -307.774848) (xy 414.43021 -307.774848) (xy 414.429715 -307.799455) (xy 414.42182 -307.848032)
			(xy 414.406236 -307.894713) (xy 414.383365 -307.93829) (xy 414.3538 -307.977634) (xy 414.318307 -308.011726)
			(xy 414.277804 -308.039682) (xy 414.233342 -308.06078) (xy 414.186071 -308.074472) (xy 414.137216 -308.080404)
			(xy 414.088041 -308.078423) (xy 414.039822 -308.068579) (xy 413.993806 -308.051127) (xy 413.951185 -308.02652)
			(xy 413.913064 -307.995395) (xy 413.880429 -307.958558) (xy 413.854126 -307.916962) (xy 413.834835 -307.871686)
			(xy 413.823058 -307.823902) (xy 413.819098 -307.774848) (xy 413.48025 -307.774848) (xy 413.479755 -307.799455)
			(xy 413.47186 -307.848032) (xy 413.456276 -307.894713) (xy 413.433405 -307.93829) (xy 413.40384 -307.977634)
			(xy 413.368347 -308.011726) (xy 413.327844 -308.039682) (xy 413.283382 -308.06078) (xy 413.236111 -308.074472)
			(xy 413.187256 -308.080404) (xy 413.138081 -308.078423) (xy 413.089862 -308.068579) (xy 413.043846 -308.051127)
			(xy 413.001225 -308.02652) (xy 412.963104 -307.995395) (xy 412.930469 -307.958558) (xy 412.904166 -307.916962)
			(xy 412.884875 -307.871686) (xy 412.873098 -307.823902) (xy 412.869138 -307.774848) (xy 412.530285 -307.774848)
			(xy 412.529795 -307.799201) (xy 412.5219 -307.847778) (xy 412.506316 -307.894459) (xy 412.483445 -307.938036)
			(xy 412.45388 -307.97738) (xy 412.418387 -308.011472) (xy 412.377884 -308.039428) (xy 412.333422 -308.060526)
			(xy 412.286151 -308.074218) (xy 412.237296 -308.08015) (xy 412.188121 -308.078169) (xy 412.139902 -308.068325)
			(xy 412.093886 -308.050873) (xy 412.051265 -308.026266) (xy 412.013144 -307.995141) (xy 411.980509 -307.958304)
			(xy 411.954206 -307.916708) (xy 411.934915 -307.871432) (xy 411.923138 -307.823648) (xy 411.919178 -307.774594)
			(xy 411.580076 -307.774594) (xy 411.579581 -307.799201) (xy 411.571686 -307.847778) (xy 411.556102 -307.894459)
			(xy 411.533231 -307.938036) (xy 411.503666 -307.97738) (xy 411.468173 -308.011472) (xy 411.42767 -308.039428)
			(xy 411.383208 -308.060526) (xy 411.335937 -308.074218) (xy 411.287082 -308.08015) (xy 411.237907 -308.078169)
			(xy 411.189688 -308.068325) (xy 411.143672 -308.050873) (xy 411.101051 -308.026266) (xy 411.06293 -307.995141)
			(xy 411.030295 -307.958304) (xy 411.003992 -307.916708) (xy 410.984701 -307.871432) (xy 410.972924 -307.823648)
			(xy 410.968964 -307.774594) (xy 410.630111 -307.774594) (xy 410.630116 -307.774848) (xy 410.629621 -307.799455)
			(xy 410.621726 -307.848032) (xy 410.606142 -307.894713) (xy 410.583271 -307.93829) (xy 410.553706 -307.977634)
			(xy 410.518213 -308.011726) (xy 410.47771 -308.039682) (xy 410.433248 -308.06078) (xy 410.385977 -308.074472)
			(xy 410.337122 -308.080404) (xy 410.287947 -308.078423) (xy 410.239728 -308.068579) (xy 410.193712 -308.051127)
			(xy 410.151091 -308.02652) (xy 410.11297 -307.995395) (xy 410.080335 -307.958558) (xy 410.054032 -307.916962)
			(xy 410.034741 -307.871686) (xy 410.022964 -307.823902) (xy 410.019004 -307.774848) (xy 409.680156 -307.774848)
			(xy 409.679661 -307.799455) (xy 409.671766 -307.848032) (xy 409.656182 -307.894713) (xy 409.633311 -307.93829)
			(xy 409.603746 -307.977634) (xy 409.568253 -308.011726) (xy 409.52775 -308.039682) (xy 409.483288 -308.06078)
			(xy 409.436017 -308.074472) (xy 409.387162 -308.080404) (xy 409.337987 -308.078423) (xy 409.289768 -308.068579)
			(xy 409.243752 -308.051127) (xy 409.201131 -308.02652) (xy 409.16301 -307.995395) (xy 409.130375 -307.958558)
			(xy 409.104072 -307.916962) (xy 409.084781 -307.871686) (xy 409.073004 -307.823902) (xy 409.069044 -307.774848)
			(xy 408.730196 -307.774848) (xy 408.729701 -307.799455) (xy 408.721806 -307.848032) (xy 408.706222 -307.894713)
			(xy 408.683351 -307.93829) (xy 408.653786 -307.977634) (xy 408.618293 -308.011726) (xy 408.57779 -308.039682)
			(xy 408.533328 -308.06078) (xy 408.486057 -308.074472) (xy 408.437202 -308.080404) (xy 408.388027 -308.078423)
			(xy 408.339808 -308.068579) (xy 408.293792 -308.051127) (xy 408.251171 -308.02652) (xy 408.21305 -307.995395)
			(xy 408.180415 -307.958558) (xy 408.154112 -307.916962) (xy 408.134821 -307.871686) (xy 408.123044 -307.823902)
			(xy 408.119084 -307.774848) (xy 406.830276 -307.774848) (xy 406.829781 -307.799455) (xy 406.821886 -307.848032)
			(xy 406.806302 -307.894713) (xy 406.783431 -307.93829) (xy 406.753866 -307.977634) (xy 406.718373 -308.011726)
			(xy 406.67787 -308.039682) (xy 406.633408 -308.06078) (xy 406.586137 -308.074472) (xy 406.537282 -308.080404)
			(xy 406.488107 -308.078423) (xy 406.439888 -308.068579) (xy 406.393872 -308.051127) (xy 406.351251 -308.02652)
			(xy 406.31313 -307.995395) (xy 406.280495 -307.958558) (xy 406.254192 -307.916962) (xy 406.234901 -307.871686)
			(xy 406.223124 -307.823902) (xy 406.219164 -307.774848) (xy 405.880316 -307.774848) (xy 405.879821 -307.799455)
			(xy 405.871926 -307.848032) (xy 405.856342 -307.894713) (xy 405.833471 -307.93829) (xy 405.803906 -307.977634)
			(xy 405.768413 -308.011726) (xy 405.72791 -308.039682) (xy 405.683448 -308.06078) (xy 405.636177 -308.074472)
			(xy 405.587322 -308.080404) (xy 405.538147 -308.078423) (xy 405.489928 -308.068579) (xy 405.443912 -308.051127)
			(xy 405.401291 -308.02652) (xy 405.36317 -307.995395) (xy 405.330535 -307.958558) (xy 405.304232 -307.916962)
			(xy 405.284941 -307.871686) (xy 405.273164 -307.823902) (xy 405.269204 -307.774848) (xy 404.930356 -307.774848)
			(xy 404.929861 -307.799455) (xy 404.921966 -307.848032) (xy 404.906382 -307.894713) (xy 404.883511 -307.93829)
			(xy 404.853946 -307.977634) (xy 404.818453 -308.011726) (xy 404.77795 -308.039682) (xy 404.733488 -308.06078)
			(xy 404.686217 -308.074472) (xy 404.637362 -308.080404) (xy 404.588187 -308.078423) (xy 404.539968 -308.068579)
			(xy 404.493952 -308.051127) (xy 404.451331 -308.02652) (xy 404.41321 -307.995395) (xy 404.380575 -307.958558)
			(xy 404.354272 -307.916962) (xy 404.334981 -307.871686) (xy 404.323204 -307.823902) (xy 404.319244 -307.774848)
			(xy 403.980142 -307.774848) (xy 403.979647 -307.799455) (xy 403.971752 -307.848032) (xy 403.956168 -307.894713)
			(xy 403.933297 -307.93829) (xy 403.903732 -307.977634) (xy 403.868239 -308.011726) (xy 403.827736 -308.039682)
			(xy 403.783274 -308.06078) (xy 403.736003 -308.074472) (xy 403.687148 -308.080404) (xy 403.637973 -308.078423)
			(xy 403.589754 -308.068579) (xy 403.543738 -308.051127) (xy 403.501117 -308.02652) (xy 403.462996 -307.995395)
			(xy 403.430361 -307.958558) (xy 403.404058 -307.916962) (xy 403.384767 -307.871686) (xy 403.37299 -307.823902)
			(xy 403.36903 -307.774848) (xy 403.030182 -307.774848) (xy 403.029687 -307.799455) (xy 403.021792 -307.848032)
			(xy 403.006208 -307.894713) (xy 402.983337 -307.93829) (xy 402.953772 -307.977634) (xy 402.918279 -308.011726)
			(xy 402.877776 -308.039682) (xy 402.833314 -308.06078) (xy 402.786043 -308.074472) (xy 402.737188 -308.080404)
			(xy 402.688013 -308.078423) (xy 402.639794 -308.068579) (xy 402.593778 -308.051127) (xy 402.551157 -308.02652)
			(xy 402.513036 -307.995395) (xy 402.480401 -307.958558) (xy 402.454098 -307.916962) (xy 402.434807 -307.871686)
			(xy 402.42303 -307.823902) (xy 402.41907 -307.774848) (xy 402.080222 -307.774848) (xy 402.079727 -307.799455)
			(xy 402.071832 -307.848032) (xy 402.056248 -307.894713) (xy 402.033377 -307.93829) (xy 402.003812 -307.977634)
			(xy 401.968319 -308.011726) (xy 401.927816 -308.039682) (xy 401.883354 -308.06078) (xy 401.836083 -308.074472)
			(xy 401.787228 -308.080404) (xy 401.738053 -308.078423) (xy 401.689834 -308.068579) (xy 401.643818 -308.051127)
			(xy 401.601197 -308.02652) (xy 401.563076 -307.995395) (xy 401.530441 -307.958558) (xy 401.504138 -307.916962)
			(xy 401.484847 -307.871686) (xy 401.47307 -307.823902) (xy 401.46911 -307.774848) (xy 401.130262 -307.774848)
			(xy 401.129767 -307.799455) (xy 401.121872 -307.848032) (xy 401.106288 -307.894713) (xy 401.083417 -307.93829)
			(xy 401.053852 -307.977634) (xy 401.018359 -308.011726) (xy 400.977856 -308.039682) (xy 400.933394 -308.06078)
			(xy 400.886123 -308.074472) (xy 400.837268 -308.080404) (xy 400.788093 -308.078423) (xy 400.739874 -308.068579)
			(xy 400.693858 -308.051127) (xy 400.651237 -308.02652) (xy 400.613116 -307.995395) (xy 400.580481 -307.958558)
			(xy 400.554178 -307.916962) (xy 400.534887 -307.871686) (xy 400.52311 -307.823902) (xy 400.51915 -307.774848)
			(xy 400.180302 -307.774848) (xy 400.179807 -307.799455) (xy 400.171912 -307.848032) (xy 400.156328 -307.894713)
			(xy 400.133457 -307.93829) (xy 400.103892 -307.977634) (xy 400.068399 -308.011726) (xy 400.027896 -308.039682)
			(xy 399.983434 -308.06078) (xy 399.936163 -308.074472) (xy 399.887308 -308.080404) (xy 399.838133 -308.078423)
			(xy 399.789914 -308.068579) (xy 399.743898 -308.051127) (xy 399.701277 -308.02652) (xy 399.663156 -307.995395)
			(xy 399.630521 -307.958558) (xy 399.604218 -307.916962) (xy 399.584927 -307.871686) (xy 399.57315 -307.823902)
			(xy 399.56919 -307.774848) (xy 399.230342 -307.774848) (xy 399.229847 -307.799455) (xy 399.221952 -307.848032)
			(xy 399.206368 -307.894713) (xy 399.183497 -307.93829) (xy 399.153932 -307.977634) (xy 399.118439 -308.011726)
			(xy 399.077936 -308.039682) (xy 399.033474 -308.06078) (xy 398.986203 -308.074472) (xy 398.937348 -308.080404)
			(xy 398.888173 -308.078423) (xy 398.839954 -308.068579) (xy 398.793938 -308.051127) (xy 398.751317 -308.02652)
			(xy 398.713196 -307.995395) (xy 398.680561 -307.958558) (xy 398.654258 -307.916962) (xy 398.634967 -307.871686)
			(xy 398.62319 -307.823902) (xy 398.61923 -307.774848) (xy 398.280128 -307.774848) (xy 398.279633 -307.799455)
			(xy 398.271738 -307.848032) (xy 398.256154 -307.894713) (xy 398.233283 -307.93829) (xy 398.203718 -307.977634)
			(xy 398.168225 -308.011726) (xy 398.127722 -308.039682) (xy 398.08326 -308.06078) (xy 398.035989 -308.074472)
			(xy 397.987134 -308.080404) (xy 397.937959 -308.078423) (xy 397.88974 -308.068579) (xy 397.843724 -308.051127)
			(xy 397.801103 -308.02652) (xy 397.762982 -307.995395) (xy 397.730347 -307.958558) (xy 397.704044 -307.916962)
			(xy 397.684753 -307.871686) (xy 397.672976 -307.823902) (xy 397.669016 -307.774848) (xy 397.355099 -307.774848)
			(xy 397.355099 -307.801164) (xy 397.346735 -307.853213) (xy 397.33022 -307.903275) (xy 397.305973 -307.950083)
			(xy 397.274607 -307.992452) (xy 397.236917 -308.029309) (xy 397.193858 -308.05972) (xy 397.146519 -308.082915)
			(xy 397.0961 -308.098307) (xy 397.070072 -308.102508) (xy 397.066008 -308.103016) (xy 397.054578 -308.106572)
			(xy 397.05026 -308.107842) (xy 397.02613 -308.119018) (xy 397.019526 -308.12613) (xy 397.004794 -308.141624)
			(xy 396.996666 -308.1528) (xy 396.993974 -308.158332) (xy 396.991026 -308.170273) (xy 396.990824 -308.176422)
			(xy 396.990824 -308.323234) (xy 396.990989 -308.329388) (xy 396.993935 -308.341339) (xy 396.996666 -308.346856)
			(xy 397.004794 -308.358032) (xy 397.019526 -308.373526) (xy 397.02613 -308.380638) (xy 397.05026 -308.391814)
			(xy 397.054578 -308.393084) (xy 397.066008 -308.39664) (xy 397.070072 -308.397148) (xy 397.096116 -308.401256)
			(xy 397.146541 -308.416651) (xy 397.193884 -308.439849) (xy 397.236948 -308.470265) (xy 397.274642 -308.507127)
			(xy 397.306011 -308.549502) (xy 397.33026 -308.596317) (xy 397.346775 -308.646385) (xy 397.355139 -308.69844)
			(xy 397.355139 -308.724808) (xy 397.669016 -308.724808) (xy 397.672976 -308.675754) (xy 397.684753 -308.62797)
			(xy 397.704044 -308.582694) (xy 397.730347 -308.541098) (xy 397.762982 -308.504261) (xy 397.801103 -308.473136)
			(xy 397.843724 -308.448529) (xy 397.88974 -308.431077) (xy 397.937959 -308.421233) (xy 397.987134 -308.419252)
			(xy 398.035989 -308.425184) (xy 398.08326 -308.438876) (xy 398.127722 -308.459974) (xy 398.168225 -308.48793)
			(xy 398.203718 -308.522022) (xy 398.233283 -308.561366) (xy 398.256154 -308.604943) (xy 398.271738 -308.651624)
			(xy 398.279633 -308.700201) (xy 398.280128 -308.724808) (xy 398.61923 -308.724808) (xy 398.62319 -308.675754)
			(xy 398.634967 -308.62797) (xy 398.654258 -308.582694) (xy 398.680561 -308.541098) (xy 398.713196 -308.504261)
			(xy 398.751317 -308.473136) (xy 398.793938 -308.448529) (xy 398.839954 -308.431077) (xy 398.888173 -308.421233)
			(xy 398.937348 -308.419252) (xy 398.986203 -308.425184) (xy 399.033474 -308.438876) (xy 399.077936 -308.459974)
			(xy 399.118439 -308.48793) (xy 399.153932 -308.522022) (xy 399.183497 -308.561366) (xy 399.206368 -308.604943)
			(xy 399.221952 -308.651624) (xy 399.229847 -308.700201) (xy 399.230342 -308.724808) (xy 399.56919 -308.724808)
			(xy 399.57315 -308.675754) (xy 399.584927 -308.62797) (xy 399.604218 -308.582694) (xy 399.630521 -308.541098)
			(xy 399.663156 -308.504261) (xy 399.701277 -308.473136) (xy 399.743898 -308.448529) (xy 399.789914 -308.431077)
			(xy 399.838133 -308.421233) (xy 399.887308 -308.419252) (xy 399.936163 -308.425184) (xy 399.983434 -308.438876)
			(xy 400.027896 -308.459974) (xy 400.068399 -308.48793) (xy 400.103892 -308.522022) (xy 400.133457 -308.561366)
			(xy 400.156328 -308.604943) (xy 400.171912 -308.651624) (xy 400.179807 -308.700201) (xy 400.180302 -308.724808)
			(xy 400.51915 -308.724808) (xy 400.52311 -308.675754) (xy 400.534887 -308.62797) (xy 400.554178 -308.582694)
			(xy 400.580481 -308.541098) (xy 400.613116 -308.504261) (xy 400.651237 -308.473136) (xy 400.693858 -308.448529)
			(xy 400.739874 -308.431077) (xy 400.788093 -308.421233) (xy 400.837268 -308.419252) (xy 400.886123 -308.425184)
			(xy 400.933394 -308.438876) (xy 400.977856 -308.459974) (xy 401.018359 -308.48793) (xy 401.053852 -308.522022)
			(xy 401.083417 -308.561366) (xy 401.106288 -308.604943) (xy 401.121872 -308.651624) (xy 401.129767 -308.700201)
			(xy 401.130262 -308.724808) (xy 401.46911 -308.724808) (xy 401.47307 -308.675754) (xy 401.484847 -308.62797)
			(xy 401.504138 -308.582694) (xy 401.530441 -308.541098) (xy 401.563076 -308.504261) (xy 401.601197 -308.473136)
			(xy 401.643818 -308.448529) (xy 401.689834 -308.431077) (xy 401.738053 -308.421233) (xy 401.787228 -308.419252)
			(xy 401.836083 -308.425184) (xy 401.883354 -308.438876) (xy 401.927816 -308.459974) (xy 401.968319 -308.48793)
			(xy 402.003812 -308.522022) (xy 402.033377 -308.561366) (xy 402.056248 -308.604943) (xy 402.071832 -308.651624)
			(xy 402.079727 -308.700201) (xy 402.080222 -308.724808) (xy 402.41907 -308.724808) (xy 402.42303 -308.675754)
			(xy 402.434807 -308.62797) (xy 402.454098 -308.582694) (xy 402.480401 -308.541098) (xy 402.513036 -308.504261)
			(xy 402.551157 -308.473136) (xy 402.593778 -308.448529) (xy 402.639794 -308.431077) (xy 402.688013 -308.421233)
			(xy 402.737188 -308.419252) (xy 402.786043 -308.425184) (xy 402.833314 -308.438876) (xy 402.877776 -308.459974)
			(xy 402.918279 -308.48793) (xy 402.953772 -308.522022) (xy 402.983337 -308.561366) (xy 403.006208 -308.604943)
			(xy 403.021792 -308.651624) (xy 403.029687 -308.700201) (xy 403.030182 -308.724808) (xy 403.030015 -308.733103)
			(xy 403.369048 -308.733103) (xy 403.371732 -308.683527) (xy 403.382403 -308.635038) (xy 403.400777 -308.588915)
			(xy 403.426371 -308.546372) (xy 403.458512 -308.50853) (xy 403.496351 -308.476387) (xy 403.538892 -308.450789)
			(xy 403.585013 -308.43241) (xy 403.633501 -308.421736) (xy 403.683077 -308.419047) (xy 403.732435 -308.424414)
			(xy 403.780274 -308.437696) (xy 403.825334 -308.458543) (xy 403.866428 -308.486405) (xy 403.902472 -308.520548)
			(xy 403.932518 -308.560073) (xy 403.955773 -308.603939) (xy 403.971625 -308.650989) (xy 403.979657 -308.699984)
			(xy 403.980142 -308.724808) (xy 403.979966 -308.738991) (xy 403.977293 -308.767231) (xy 403.974808 -308.781196)
			(xy 403.972522 -308.793642) (xy 403.979888 -308.817264) (xy 404.057358 -308.894734) (xy 404.08098 -308.9021)
			(xy 404.093426 -308.899814) (xy 404.107392 -308.897338) (xy 404.135631 -308.894666) (xy 404.149814 -308.89448)
			(xy 404.164061 -308.894646) (xy 404.192429 -308.897316) (xy 404.206456 -308.899814) (xy 404.218648 -308.9021)
			(xy 404.242778 -308.894734) (xy 404.319994 -308.817518) (xy 404.32736 -308.793642) (xy 404.325074 -308.781196)
			(xy 404.322601 -308.76723) (xy 404.319927 -308.73899) (xy 404.31974 -308.724808) (xy 404.320169 -308.699987)
			(xy 404.328199 -308.650999) (xy 404.344048 -308.603956) (xy 404.367299 -308.560096) (xy 404.397339 -308.520575)
			(xy 404.433377 -308.486435) (xy 404.474463 -308.458574) (xy 404.519515 -308.437728) (xy 404.567347 -308.424444)
			(xy 404.616697 -308.419074) (xy 404.666266 -308.421758) (xy 404.714748 -308.432426) (xy 404.760865 -308.450796)
			(xy 404.803403 -308.476385) (xy 404.841241 -308.508519) (xy 404.873382 -308.546351) (xy 404.898979 -308.588885)
			(xy 404.917358 -308.634999) (xy 404.928035 -308.683478) (xy 404.93028 -308.724808) (xy 406.219164 -308.724808)
			(xy 406.223124 -308.675754) (xy 406.234901 -308.62797) (xy 406.254192 -308.582694) (xy 406.280495 -308.541098)
			(xy 406.31313 -308.504261) (xy 406.351251 -308.473136) (xy 406.393872 -308.448529) (xy 406.439888 -308.431077)
			(xy 406.488107 -308.421233) (xy 406.537282 -308.419252) (xy 406.586137 -308.425184) (xy 406.633408 -308.438876)
			(xy 406.67787 -308.459974) (xy 406.718373 -308.48793) (xy 406.753866 -308.522022) (xy 406.783431 -308.561366)
			(xy 406.806302 -308.604943) (xy 406.821886 -308.651624) (xy 406.829781 -308.700201) (xy 406.830276 -308.724808)
			(xy 406.83011 -308.733071) (xy 408.119193 -308.733071) (xy 408.121882 -308.683504) (xy 408.132555 -308.635025)
			(xy 408.15093 -308.588912) (xy 408.176523 -308.546379) (xy 408.20866 -308.508546) (xy 408.246495 -308.476411)
			(xy 408.28903 -308.450821) (xy 408.335144 -308.432449) (xy 408.383624 -308.421779) (xy 408.433191 -308.419093)
			(xy 408.482539 -308.424462) (xy 408.530369 -308.437743) (xy 408.57542 -308.458588) (xy 408.616505 -308.486446)
			(xy 408.652543 -308.520584) (xy 408.682582 -308.560103) (xy 408.705833 -308.603961) (xy 408.721681 -308.651002)
			(xy 408.729711 -308.699988) (xy 408.730196 -308.724808) (xy 408.730021 -308.738991) (xy 408.727348 -308.767231)
			(xy 408.724862 -308.781196) (xy 408.722576 -308.793642) (xy 408.729942 -308.817264) (xy 408.807412 -308.894734)
			(xy 408.831034 -308.9021) (xy 408.84348 -308.899814) (xy 408.857445 -308.897331) (xy 408.885685 -308.894663)
			(xy 408.899868 -308.89448) (xy 408.914051 -308.894661) (xy 408.942291 -308.89733) (xy 408.956256 -308.899814)
			(xy 408.968702 -308.9021) (xy 408.992324 -308.894734) (xy 409.069794 -308.817264) (xy 409.07716 -308.793642)
			(xy 409.074874 -308.781196) (xy 409.072401 -308.76723) (xy 409.069727 -308.73899) (xy 409.06954 -308.724808)
			(xy 409.070062 -308.699553) (xy 409.078375 -308.649731) (xy 409.094776 -308.601957) (xy 409.118817 -308.557534)
			(xy 409.149841 -308.517674) (xy 409.187003 -308.483464) (xy 409.229289 -308.455838) (xy 409.275545 -308.435548)
			(xy 409.32451 -308.423148) (xy 409.374848 -308.418977) (xy 409.425186 -308.423148) (xy 409.474151 -308.435548)
			(xy 409.520407 -308.455838) (xy 409.562693 -308.483464) (xy 409.599855 -308.517674) (xy 409.630879 -308.557534)
			(xy 409.65492 -308.601957) (xy 409.671321 -308.649731) (xy 409.679634 -308.699553) (xy 409.680156 -308.724808)
			(xy 409.679981 -308.738991) (xy 409.677308 -308.767231) (xy 409.674822 -308.781196) (xy 409.672536 -308.793642)
			(xy 409.679902 -308.817264) (xy 409.757372 -308.894734) (xy 409.780994 -308.9021) (xy 409.79344 -308.899814)
			(xy 409.807406 -308.897336) (xy 409.835645 -308.894665) (xy 409.849828 -308.89448) (xy 409.864011 -308.894653)
			(xy 409.892251 -308.897328) (xy 409.906216 -308.899814) (xy 409.918662 -308.9021) (xy 409.942284 -308.894734)
			(xy 410.019754 -308.817264) (xy 410.02712 -308.793642) (xy 410.024834 -308.781196) (xy 410.022361 -308.76723)
			(xy 410.019687 -308.73899) (xy 410.0195 -308.724808) (xy 410.019969 -308.699986) (xy 410.027999 -308.650997)
			(xy 410.043849 -308.603952) (xy 410.067101 -308.560092) (xy 410.097143 -308.52057) (xy 410.133183 -308.48643)
			(xy 410.174271 -308.45857) (xy 410.219325 -308.437724) (xy 410.267158 -308.424442) (xy 410.31651 -308.419073)
			(xy 410.36608 -308.42176) (xy 410.414563 -308.43243) (xy 410.460681 -308.450804) (xy 410.503218 -308.476396)
			(xy 410.541055 -308.508534) (xy 410.573194 -308.546369) (xy 410.598789 -308.588905) (xy 410.617165 -308.635022)
			(xy 410.627838 -308.683504) (xy 410.630065 -308.724554) (xy 410.968964 -308.724554) (xy 410.972924 -308.6755)
			(xy 410.984701 -308.627716) (xy 411.003992 -308.58244) (xy 411.030295 -308.540844) (xy 411.06293 -308.504007)
			(xy 411.101051 -308.472882) (xy 411.143672 -308.448275) (xy 411.189688 -308.430823) (xy 411.237907 -308.420979)
			(xy 411.287082 -308.418998) (xy 411.335937 -308.42493) (xy 411.383208 -308.438622) (xy 411.42767 -308.45972)
			(xy 411.468173 -308.487676) (xy 411.503666 -308.521768) (xy 411.533231 -308.561112) (xy 411.556102 -308.604689)
			(xy 411.571686 -308.65137) (xy 411.579581 -308.699947) (xy 411.580076 -308.724554) (xy 411.580071 -308.724808)
			(xy 411.919178 -308.724808) (xy 411.923138 -308.675754) (xy 411.934915 -308.62797) (xy 411.954206 -308.582694)
			(xy 411.980509 -308.541098) (xy 412.013144 -308.504261) (xy 412.051265 -308.473136) (xy 412.093886 -308.448529)
			(xy 412.139902 -308.431077) (xy 412.188121 -308.421233) (xy 412.237296 -308.419252) (xy 412.286151 -308.425184)
			(xy 412.333422 -308.438876) (xy 412.377884 -308.459974) (xy 412.418387 -308.48793) (xy 412.45388 -308.522022)
			(xy 412.483445 -308.561366) (xy 412.506316 -308.604943) (xy 412.5219 -308.651624) (xy 412.529795 -308.700201)
			(xy 412.53029 -308.724808) (xy 412.869138 -308.724808) (xy 412.873098 -308.675754) (xy 412.884875 -308.62797)
			(xy 412.904166 -308.582694) (xy 412.930469 -308.541098) (xy 412.963104 -308.504261) (xy 413.001225 -308.473136)
			(xy 413.043846 -308.448529) (xy 413.089862 -308.431077) (xy 413.138081 -308.421233) (xy 413.187256 -308.419252)
			(xy 413.236111 -308.425184) (xy 413.283382 -308.438876) (xy 413.327844 -308.459974) (xy 413.368347 -308.48793)
			(xy 413.40384 -308.522022) (xy 413.433405 -308.561366) (xy 413.456276 -308.604943) (xy 413.47186 -308.651624)
			(xy 413.479755 -308.700201) (xy 413.48025 -308.724808) (xy 413.819098 -308.724808) (xy 413.823058 -308.675754)
			(xy 413.834835 -308.62797) (xy 413.854126 -308.582694) (xy 413.880429 -308.541098) (xy 413.913064 -308.504261)
			(xy 413.951185 -308.473136) (xy 413.993806 -308.448529) (xy 414.039822 -308.431077) (xy 414.088041 -308.421233)
			(xy 414.137216 -308.419252) (xy 414.186071 -308.425184) (xy 414.233342 -308.438876) (xy 414.277804 -308.459974)
			(xy 414.318307 -308.48793) (xy 414.3538 -308.522022) (xy 414.383365 -308.561366) (xy 414.406236 -308.604943)
			(xy 414.42182 -308.651624) (xy 414.429715 -308.700201) (xy 414.43021 -308.724808) (xy 414.769058 -308.724808)
			(xy 414.773018 -308.675754) (xy 414.784795 -308.62797) (xy 414.804086 -308.582694) (xy 414.830389 -308.541098)
			(xy 414.863024 -308.504261) (xy 414.901145 -308.473136) (xy 414.943766 -308.448529) (xy 414.989782 -308.431077)
			(xy 415.038001 -308.421233) (xy 415.087176 -308.419252) (xy 415.136031 -308.425184) (xy 415.183302 -308.438876)
			(xy 415.227764 -308.459974) (xy 415.268267 -308.48793) (xy 415.30376 -308.522022) (xy 415.333325 -308.561366)
			(xy 415.356196 -308.604943) (xy 415.37178 -308.651624) (xy 415.379675 -308.700201) (xy 415.38017 -308.724808)
			(xy 415.719018 -308.724808) (xy 415.722978 -308.675754) (xy 415.734755 -308.62797) (xy 415.754046 -308.582694)
			(xy 415.780349 -308.541098) (xy 415.812984 -308.504261) (xy 415.851105 -308.473136) (xy 415.893726 -308.448529)
			(xy 415.939742 -308.431077) (xy 415.987961 -308.421233) (xy 416.037136 -308.419252) (xy 416.085991 -308.425184)
			(xy 416.133262 -308.438876) (xy 416.177724 -308.459974) (xy 416.218227 -308.48793) (xy 416.25372 -308.522022)
			(xy 416.283285 -308.561366) (xy 416.306156 -308.604943) (xy 416.32174 -308.651624) (xy 416.329635 -308.700201)
			(xy 416.33013 -308.724808) (xy 416.643312 -308.724808) (xy 416.643794 -308.698731) (xy 416.651909 -308.647214)
			(xy 416.667985 -308.597602) (xy 416.691629 -308.551116) (xy 416.722256 -308.508904) (xy 416.74034 -308.490112)
			(xy 416.982148 -308.248558) (xy 416.988425 -308.241654) (xy 416.995999 -308.224618) (xy 416.997031 -308.206003)
			(xy 416.994594 -308.196996) (xy 416.962336 -308.097174) (xy 416.940492 -308.078632) (xy 416.926268 -308.076346)
			(xy 416.9027 -308.072055) (xy 416.857182 -308.05714) (xy 416.814549 -308.035302) (xy 416.775849 -308.007076)
			(xy 416.742029 -307.973155) (xy 416.713919 -307.93437) (xy 416.692209 -307.891673) (xy 416.67743 -307.84611)
			(xy 416.669945 -307.798798) (xy 416.669474 -307.774848) (xy 416.669996 -307.749593) (xy 416.678309 -307.699771)
			(xy 416.69471 -307.651997) (xy 416.718751 -307.607574) (xy 416.749775 -307.567714) (xy 416.786937 -307.533504)
			(xy 416.829223 -307.505878) (xy 416.875479 -307.485588) (xy 416.924444 -307.473188) (xy 416.974782 -307.469017)
			(xy 417.02512 -307.473188) (xy 417.074085 -307.485588) (xy 417.120341 -307.505878) (xy 417.162627 -307.533504)
			(xy 417.199789 -307.567714) (xy 417.230813 -307.607574) (xy 417.254854 -307.651997) (xy 417.271255 -307.699771)
			(xy 417.279568 -307.749593) (xy 417.28009 -307.774848) (xy 417.279836 -307.788818) (xy 417.279328 -307.80101)
			(xy 417.288726 -307.8226) (xy 417.370768 -307.889656) (xy 417.393882 -307.89499) (xy 417.40582 -307.891942)
			(xy 417.425503 -307.887341) (xy 417.465619 -307.882369) (xy 417.48583 -307.882036) (xy 417.518088 -307.882036)
			(xy 417.528227 -307.881687) (xy 417.546961 -307.873939) (xy 417.55441 -307.86705) (xy 417.612322 -307.808122)
			(xy 417.619942 -307.78958) (xy 417.619688 -307.779166) (xy 417.619688 -307.774848) (xy 417.62021 -307.749593)
			(xy 417.628523 -307.699771) (xy 417.644924 -307.651997) (xy 417.668965 -307.607574) (xy 417.699989 -307.567714)
			(xy 417.737151 -307.533504) (xy 417.779437 -307.505878) (xy 417.825693 -307.485588) (xy 417.874658 -307.473188)
			(xy 417.924996 -307.469017) (xy 417.975334 -307.473188) (xy 418.024299 -307.485588) (xy 418.070555 -307.505878)
			(xy 418.112841 -307.533504) (xy 418.150003 -307.567714) (xy 418.181027 -307.607574) (xy 418.205068 -307.651997)
			(xy 418.221469 -307.699771) (xy 418.229782 -307.749593) (xy 418.230304 -307.774848) (xy 418.230304 -307.779166)
			(xy 418.23005 -307.78958) (xy 418.23767 -307.808122) (xy 418.295582 -307.86705) (xy 418.303053 -307.873904)
			(xy 418.321774 -307.88164) (xy 418.331904 -307.882036) (xy 418.468048 -307.882036) (xy 418.478185 -307.881666)
			(xy 418.496919 -307.873933) (xy 418.50437 -307.86705) (xy 418.562282 -307.808122) (xy 418.569902 -307.78958)
			(xy 418.569648 -307.779166) (xy 418.569648 -307.774848) (xy 418.57017 -307.749593) (xy 418.578483 -307.699771)
			(xy 418.594884 -307.651997) (xy 418.618925 -307.607574) (xy 418.649949 -307.567714) (xy 418.687111 -307.533504)
			(xy 418.729397 -307.505878) (xy 418.775653 -307.485588) (xy 418.824618 -307.473188) (xy 418.874956 -307.469017)
			(xy 418.925294 -307.473188) (xy 418.974259 -307.485588) (xy 419.020515 -307.505878) (xy 419.062801 -307.533504)
			(xy 419.099963 -307.567714) (xy 419.130987 -307.607574) (xy 419.155028 -307.651997) (xy 419.171429 -307.699771)
			(xy 419.179742 -307.749593) (xy 419.180264 -307.774848) (xy 419.180264 -307.779166) (xy 419.18001 -307.78958)
			(xy 419.18763 -307.808122) (xy 419.245542 -307.86705) (xy 419.252992 -307.87393) (xy 419.271729 -307.881651)
			(xy 419.281864 -307.882036) (xy 419.391592 -307.882036) (xy 419.401663 -307.881623) (xy 419.420262 -307.873895)
			(xy 419.42766 -307.86705) (xy 419.485826 -307.808122) (xy 419.493192 -307.78958) (xy 419.493192 -307.774848)
			(xy 419.493642 -307.74877) (xy 419.501765 -307.697252) (xy 419.51785 -307.647639) (xy 419.5415 -307.601155)
			(xy 419.572133 -307.558944) (xy 419.59022 -307.540152) (xy 419.832028 -307.298344) (xy 419.838313 -307.291446)
			(xy 419.845887 -307.274407) (xy 419.846914 -307.255789) (xy 419.844474 -307.246782) (xy 419.812216 -307.147214)
			(xy 419.790372 -307.128672) (xy 419.776402 -307.126386) (xy 419.752833 -307.122107) (xy 419.707317 -307.107185)
			(xy 419.664688 -307.085342) (xy 419.62599 -307.057113) (xy 419.592172 -307.023191) (xy 419.564063 -306.984406)
			(xy 419.542352 -306.94171) (xy 419.527571 -306.896148) (xy 419.520081 -306.848838) (xy 419.519608 -306.824888)
			(xy 419.52013 -306.799633) (xy 419.528443 -306.749811) (xy 419.544844 -306.702037) (xy 419.568885 -306.657614)
			(xy 419.599909 -306.617754) (xy 419.637071 -306.583544) (xy 419.679357 -306.555918) (xy 419.725613 -306.535628)
			(xy 419.774578 -306.523228) (xy 419.824916 -306.519057) (xy 419.875254 -306.523228) (xy 419.924219 -306.535628)
			(xy 419.970475 -306.555918) (xy 420.012761 -306.583544) (xy 420.049923 -306.617754) (xy 420.080947 -306.657614)
			(xy 420.104988 -306.702037) (xy 420.121389 -306.749811) (xy 420.129702 -306.799633) (xy 420.130224 -306.824888)
			(xy 420.130159 -306.833735) (xy 420.129143 -306.851398) (xy 420.128192 -306.860194) (xy 420.126668 -306.872132)
			(xy 420.134796 -306.894484) (xy 420.21125 -306.967128) (xy 420.233856 -306.973986) (xy 420.245794 -306.971954)
			(xy 420.25935 -306.969881) (xy 420.286691 -306.96772) (xy 420.300404 -306.967636) (xy 420.37 -306.967636)
			(xy 420.380726 -306.967237) (xy 420.400331 -306.958538) (xy 420.407846 -306.950872) (xy 420.465504 -306.886864)
			(xy 420.472108 -306.866544) (xy 420.471092 -306.855622) (xy 420.469568 -306.824888) (xy 420.47009 -306.799633)
			(xy 420.478403 -306.749811) (xy 420.494804 -306.702037) (xy 420.518845 -306.657614) (xy 420.549869 -306.617754)
			(xy 420.587031 -306.583544) (xy 420.629317 -306.555918) (xy 420.675573 -306.535628) (xy 420.724538 -306.523228)
			(xy 420.774876 -306.519057) (xy 420.825214 -306.523228) (xy 420.874179 -306.535628) (xy 420.920435 -306.555918)
			(xy 420.962721 -306.583544) (xy 420.999883 -306.617754) (xy 421.030907 -306.657614) (xy 421.054948 -306.702037)
			(xy 421.071349 -306.749811) (xy 421.079662 -306.799633) (xy 421.080184 -306.824888) (xy 421.07866 -306.855622)
			(xy 421.077644 -306.866544) (xy 421.084248 -306.886864) (xy 421.141906 -306.950872) (xy 421.149523 -306.958393)
			(xy 421.169064 -306.967066) (xy 421.179752 -306.967636) (xy 421.31996 -306.967636) (xy 421.330684 -306.967215)
			(xy 421.350288 -306.958531) (xy 421.357806 -306.950872) (xy 421.415464 -306.886864) (xy 421.422068 -306.866544)
			(xy 421.421052 -306.855622) (xy 421.419528 -306.824888) (xy 421.42005 -306.799633) (xy 421.428363 -306.749811)
			(xy 421.444764 -306.702037) (xy 421.468805 -306.657614) (xy 421.499829 -306.617754) (xy 421.536991 -306.583544)
			(xy 421.579277 -306.555918) (xy 421.625533 -306.535628) (xy 421.674498 -306.523228) (xy 421.724836 -306.519057)
			(xy 421.775174 -306.523228) (xy 421.824139 -306.535628) (xy 421.870395 -306.555918) (xy 421.912681 -306.583544)
			(xy 421.949843 -306.617754) (xy 421.980867 -306.657614) (xy 422.004908 -306.702037) (xy 422.021309 -306.749811)
			(xy 422.029622 -306.799633) (xy 422.030144 -306.824888) (xy 422.02862 -306.855622) (xy 422.027604 -306.866544)
			(xy 422.034208 -306.886864) (xy 422.091866 -306.950872) (xy 422.09946 -306.95842) (xy 422.119019 -306.967078)
			(xy 422.129712 -306.967636) (xy 422.5036 -306.967636) (xy 422.529677 -306.968106) (xy 422.581195 -306.976222)
			(xy 422.630808 -306.992302) (xy 422.677293 -307.015948) (xy 422.719504 -307.046578) (xy 422.738296 -307.064664)
			(xy 422.774364 -307.100986) (xy 422.782117 -307.10797) (xy 422.801523 -307.115579) (xy 422.811956 -307.115718)
			(xy 422.896284 -307.113432) (xy 422.91508 -307.104796) (xy 422.922192 -307.096668) (xy 422.939725 -307.077818)
			(xy 422.979935 -307.045682) (xy 423.024968 -307.020748) (xy 423.073547 -307.003723) (xy 423.124293 -306.995091)
			(xy 423.15003 -306.99456) (xy 423.173555 -306.995027) (xy 423.220045 -307.002278) (xy 423.264872 -307.016572)
			(xy 423.306977 -307.037572) (xy 423.345364 -307.064781) (xy 423.379123 -307.097555) (xy 423.407457 -307.135119)
			(xy 423.429695 -307.176584) (xy 423.445311 -307.220968) (xy 423.453936 -307.267222) (xy 423.455084 -307.290724)
			(xy 423.455592 -307.30063) (xy 423.463466 -307.318664) (xy 423.521378 -307.374798) (xy 423.528726 -307.381316)
			(xy 423.546876 -307.388771) (xy 423.556684 -307.389276) (xy 423.693336 -307.389276) (xy 423.703152 -307.388805)
			(xy 423.721317 -307.38135) (xy 423.728642 -307.374798) (xy 423.786554 -307.318664) (xy 423.794428 -307.30063)
			(xy 423.794936 -307.290724) (xy 423.79616 -307.265984) (xy 423.805619 -307.217366) (xy 423.822805 -307.170913)
			(xy 423.847267 -307.127845) (xy 423.878362 -307.089292) (xy 423.915275 -307.056267) (xy 423.957037 -307.029636)
			(xy 424.002551 -307.010098) (xy 424.050623 -306.998166) (xy 424.09999 -306.994154) (xy 424.149357 -306.998166)
			(xy 424.197429 -307.010098) (xy 424.242943 -307.029636) (xy 424.284705 -307.056267) (xy 424.321618 -307.089292)
			(xy 424.352713 -307.127845) (xy 424.377175 -307.170913) (xy 424.394361 -307.217366) (xy 424.40382 -307.265984)
			(xy 424.405044 -307.290724) (xy 424.405552 -307.30063) (xy 424.413426 -307.318664) (xy 424.471338 -307.374798)
			(xy 424.478666 -307.381342) (xy 424.496831 -307.388782) (xy 424.506644 -307.389276) (xy 424.621452 -307.389276)
			(xy 424.631332 -307.388827) (xy 424.649632 -307.381381) (xy 424.657012 -307.374798) (xy 424.714924 -307.31841)
			(xy 424.722798 -307.300376) (xy 424.723052 -307.29047) (xy 424.724244 -307.265265) (xy 424.733424 -307.215649)
			(xy 424.750116 -307.168031) (xy 424.773923 -307.123542) (xy 424.804281 -307.083238) (xy 424.84047 -307.048075)
			(xy 424.881629 -307.018888) (xy 424.926784 -306.996369) (xy 424.974861 -306.981053) (xy 425.024721 -306.973303)
			(xy 425.075179 -306.973303) (xy 425.125039 -306.981053) (xy 425.173116 -306.996369) (xy 425.218271 -307.018888)
			(xy 425.25943 -307.048075) (xy 425.295619 -307.083238) (xy 425.325977 -307.123542) (xy 425.349784 -307.168031)
			(xy 425.366476 -307.215649) (xy 425.375656 -307.265265) (xy 425.376848 -307.29047) (xy 425.377102 -307.300376)
			(xy 425.384976 -307.31841) (xy 425.442888 -307.374798) (xy 425.450286 -307.381355) (xy 425.468574 -307.388809)
			(xy 425.478448 -307.389276) (xy 425.571412 -307.389276) (xy 425.581295 -307.388858) (xy 425.599595 -307.38139)
			(xy 425.606972 -307.374798) (xy 425.664884 -307.31841) (xy 425.672758 -307.300376) (xy 425.673012 -307.29047)
			(xy 425.674204 -307.265265) (xy 425.683384 -307.215649) (xy 425.700076 -307.168031) (xy 425.723883 -307.123542)
			(xy 425.754241 -307.083238) (xy 425.79043 -307.048075) (xy 425.831589 -307.018888) (xy 425.876744 -306.996369)
			(xy 425.924821 -306.981053) (xy 425.974681 -306.973303) (xy 426.025139 -306.973303) (xy 426.074999 -306.981053)
			(xy 426.123076 -306.996369) (xy 426.168231 -307.018888) (xy 426.20939 -307.048075) (xy 426.245579 -307.083238)
			(xy 426.275937 -307.123542) (xy 426.299744 -307.168031) (xy 426.316436 -307.215649) (xy 426.325616 -307.265265)
			(xy 426.326808 -307.29047) (xy 426.327062 -307.300376) (xy 426.334936 -307.31841) (xy 426.392848 -307.374798)
			(xy 426.40026 -307.381337) (xy 426.418537 -307.388802) (xy 426.428408 -307.389276) (xy 426.543216 -307.389276)
			(xy 426.553031 -307.388795) (xy 426.571196 -307.381347) (xy 426.578522 -307.374798) (xy 426.636434 -307.318664)
			(xy 426.644308 -307.30063) (xy 426.644816 -307.290724) (xy 426.64604 -307.265984) (xy 426.655499 -307.217366)
			(xy 426.672685 -307.170913) (xy 426.697147 -307.127845) (xy 426.728242 -307.089292) (xy 426.765155 -307.056267)
			(xy 426.806917 -307.029636) (xy 426.852431 -307.010098) (xy 426.900503 -306.998166) (xy 426.94987 -306.994154)
			(xy 426.999237 -306.998166) (xy 427.047309 -307.010098) (xy 427.092823 -307.029636) (xy 427.134585 -307.056267)
			(xy 427.171498 -307.089292) (xy 427.202593 -307.127845) (xy 427.227055 -307.170913) (xy 427.244241 -307.217366)
			(xy 427.2537 -307.265984) (xy 427.254924 -307.290724) (xy 427.255432 -307.30063) (xy 427.263306 -307.318664)
			(xy 427.321218 -307.374798) (xy 427.328552 -307.381333) (xy 427.346713 -307.388778) (xy 427.356524 -307.389276)
			(xy 427.471332 -307.389276) (xy 427.481216 -307.388868) (xy 427.499516 -307.381393) (xy 427.506892 -307.374798)
			(xy 427.564804 -307.31841) (xy 427.572678 -307.300376) (xy 427.572932 -307.29047) (xy 427.574124 -307.265265)
			(xy 427.583304 -307.215649) (xy 427.599996 -307.168031) (xy 427.623803 -307.123542) (xy 427.654161 -307.083238)
			(xy 427.69035 -307.048075) (xy 427.731509 -307.018888) (xy 427.776664 -306.996369) (xy 427.824741 -306.981053)
			(xy 427.874601 -306.973303) (xy 427.925059 -306.973303) (xy 427.974919 -306.981053) (xy 428.022996 -306.996369)
			(xy 428.068151 -307.018888) (xy 428.10931 -307.048075) (xy 428.145499 -307.083238) (xy 428.175857 -307.123542)
			(xy 428.199664 -307.168031) (xy 428.216356 -307.215649) (xy 428.225536 -307.265265) (xy 428.226728 -307.29047)
			(xy 428.226982 -307.300376) (xy 428.234856 -307.31841) (xy 428.292768 -307.374798) (xy 428.300173 -307.381346)
			(xy 428.318456 -307.388806) (xy 428.328328 -307.389276) (xy 428.421292 -307.389276) (xy 428.431174 -307.388847)
			(xy 428.449474 -307.381387) (xy 428.456852 -307.374798) (xy 428.514764 -307.31841) (xy 428.522638 -307.300376)
			(xy 428.522892 -307.29047) (xy 428.524084 -307.265265) (xy 428.533264 -307.215649) (xy 428.549956 -307.168031)
			(xy 428.573763 -307.123542) (xy 428.604121 -307.083238) (xy 428.64031 -307.048075) (xy 428.681469 -307.018888)
			(xy 428.726624 -306.996369) (xy 428.774701 -306.981053) (xy 428.824561 -306.973303) (xy 428.875019 -306.973303)
			(xy 428.924879 -306.981053) (xy 428.972956 -306.996369) (xy 429.018111 -307.018888) (xy 429.05927 -307.048075)
			(xy 429.095459 -307.083238) (xy 429.125817 -307.123542) (xy 429.149624 -307.168031) (xy 429.166316 -307.215649)
			(xy 429.175496 -307.265265) (xy 429.176688 -307.29047) (xy 429.176942 -307.300376) (xy 429.184816 -307.31841)
			(xy 429.242728 -307.374798) (xy 429.250113 -307.381372) (xy 429.268411 -307.388817) (xy 429.278288 -307.389276)
			(xy 429.39335 -307.389276) (xy 429.403167 -307.388812) (xy 429.421331 -307.381352) (xy 429.428656 -307.374798)
			(xy 429.486568 -307.318664) (xy 429.494442 -307.30063) (xy 429.49495 -307.290724) (xy 429.496174 -307.265984)
			(xy 429.505633 -307.217366) (xy 429.522819 -307.170913) (xy 429.547281 -307.127845) (xy 429.578376 -307.089292)
			(xy 429.615289 -307.056267) (xy 429.657051 -307.029636) (xy 429.702565 -307.010098) (xy 429.750637 -306.998166)
			(xy 429.800004 -306.994154) (xy 429.849371 -306.998166) (xy 429.897443 -307.010098) (xy 429.942957 -307.029636)
			(xy 429.984719 -307.056267) (xy 430.021632 -307.089292) (xy 430.052727 -307.127845) (xy 430.077189 -307.170913)
			(xy 430.094375 -307.217366) (xy 430.103834 -307.265984) (xy 430.105058 -307.290724) (xy 430.105566 -307.30063)
			(xy 430.11344 -307.318664) (xy 430.171352 -307.374798) (xy 430.178708 -307.381305) (xy 430.196852 -307.388766)
			(xy 430.206658 -307.389276) (xy 430.34331 -307.389276) (xy 430.353125 -307.388792) (xy 430.371289 -307.381346)
			(xy 430.378616 -307.374798) (xy 430.436528 -307.318664) (xy 430.444402 -307.30063) (xy 430.44491 -307.290724)
			(xy 430.446134 -307.265984) (xy 430.455593 -307.217366) (xy 430.472779 -307.170913) (xy 430.497241 -307.127845)
			(xy 430.528336 -307.089292) (xy 430.565249 -307.056267) (xy 430.607011 -307.029636) (xy 430.652525 -307.010098)
			(xy 430.700597 -306.998166) (xy 430.749964 -306.994154) (xy 430.799331 -306.998166) (xy 430.847403 -307.010098)
			(xy 430.892917 -307.029636) (xy 430.934679 -307.056267) (xy 430.971592 -307.089292) (xy 431.002687 -307.127845)
			(xy 431.027149 -307.170913) (xy 431.044335 -307.217366) (xy 431.053794 -307.265984) (xy 431.055018 -307.290724)
			(xy 431.055526 -307.30063) (xy 431.0634 -307.318664) (xy 431.080625 -307.33536) (xy 439.450128 -307.33536)
			(xy 439.457883 -307.281404) (xy 439.473239 -307.229101) (xy 439.495882 -307.179516) (xy 439.525351 -307.133658)
			(xy 439.561047 -307.092461) (xy 439.602242 -307.056763) (xy 439.648098 -307.027291) (xy 439.697682 -307.004646)
			(xy 439.749985 -306.989288) (xy 439.80394 -306.981529) (xy 439.858451 -306.981529) (xy 439.912406 -306.989286)
			(xy 439.964709 -307.004643) (xy 440.014293 -307.027287) (xy 440.06015 -307.056757) (xy 440.091847 -307.084222)
			(xy 441.014356 -307.084222) (xy 441.018427 -307.0286) (xy 441.030553 -306.974163) (xy 441.050476 -306.922072)
			(xy 441.077772 -306.873437) (xy 441.111858 -306.829294) (xy 441.152007 -306.790585) (xy 441.197365 -306.758134)
			(xy 441.246965 -306.732633) (xy 441.299749 -306.714626) (xy 441.354592 -306.704496) (xy 441.410326 -306.702459)
			(xy 441.465763 -306.708559) (xy 441.51972 -306.722665) (xy 441.571049 -306.744477) (xy 441.618655 -306.773531)
			(xy 441.661523 -306.809206) (xy 441.69874 -306.850743) (xy 441.729513 -306.897256) (xy 441.753185 -306.947753)
			(xy 441.769253 -307.00116) (xy 441.777373 -307.056336) (xy 441.777882 -307.084222) (xy 441.777373 -307.112108)
			(xy 441.769253 -307.167284) (xy 441.753185 -307.220691) (xy 441.729513 -307.271188) (xy 441.69874 -307.317701)
			(xy 441.661523 -307.359238) (xy 441.618655 -307.394913) (xy 441.571049 -307.423967) (xy 441.51972 -307.445779)
			(xy 441.465763 -307.459885) (xy 441.410326 -307.465985) (xy 441.354592 -307.463948) (xy 441.299749 -307.453818)
			(xy 441.246965 -307.435811) (xy 441.197365 -307.41031) (xy 441.152007 -307.377859) (xy 441.111858 -307.33915)
			(xy 441.077772 -307.295007) (xy 441.050476 -307.246372) (xy 441.030553 -307.194281) (xy 441.018427 -307.139844)
			(xy 441.014356 -307.084222) (xy 440.091847 -307.084222) (xy 440.101347 -307.092454) (xy 440.137043 -307.133651)
			(xy 440.166514 -307.179508) (xy 440.189158 -307.229092) (xy 440.204515 -307.281395) (xy 440.212271 -307.335351)
			(xy 440.212734 -307.362606) (xy 440.210956 -307.399182) (xy 440.20994 -307.410612) (xy 440.21756 -307.431694)
			(xy 440.289188 -307.503322) (xy 440.310524 -307.510942) (xy 440.321954 -307.509926) (xy 440.35853 -307.508148)
			(xy 440.38578 -307.50865) (xy 440.439725 -307.516409) (xy 440.492017 -307.531766) (xy 440.541591 -307.554407)
			(xy 440.587439 -307.583873) (xy 440.628628 -307.619562) (xy 440.664319 -307.66075) (xy 440.693786 -307.706597)
			(xy 440.716429 -307.75617) (xy 440.731788 -307.808461) (xy 440.739549 -307.862406) (xy 440.740038 -307.889656)
			(xy 440.739682 -307.912162) (xy 440.734339 -307.956856) (xy 440.72937 -307.97881) (xy 440.726322 -307.992018)
			(xy 440.733434 -308.017164) (xy 440.813698 -308.097428) (xy 440.838844 -308.10454) (xy 440.852052 -308.101492)
			(xy 440.874008 -308.096534) (xy 440.918701 -308.091184) (xy 440.941206 -308.090824) (xy 440.968456 -308.091284)
			(xy 441.022402 -308.099041) (xy 441.074695 -308.114396) (xy 441.12427 -308.137037) (xy 441.170118 -308.166502)
			(xy 441.211307 -308.202192) (xy 441.246997 -308.243381) (xy 441.276463 -308.28923) (xy 441.299104 -308.338805)
			(xy 441.314459 -308.391097) (xy 441.322216 -308.445043) (xy 441.322217 -308.499544) (xy 441.314462 -308.553489)
			(xy 441.299108 -308.605783) (xy 441.276469 -308.655359) (xy 441.247005 -308.701208) (xy 441.211317 -308.742398)
			(xy 441.170129 -308.77809) (xy 441.124282 -308.807557) (xy 441.074707 -308.830199) (xy 441.022415 -308.845556)
			(xy 440.96847 -308.853315) (xy 440.913969 -308.853318) (xy 440.860023 -308.845564) (xy 440.807729 -308.830213)
			(xy 440.758152 -308.807575) (xy 440.712302 -308.778113) (xy 440.671111 -308.742426) (xy 440.635418 -308.701239)
			(xy 440.605949 -308.655393) (xy 440.583305 -308.605819) (xy 440.567947 -308.553527) (xy 440.560186 -308.499582)
			(xy 440.559698 -308.472332) (xy 440.560053 -308.449826) (xy 440.565397 -308.405132) (xy 440.570366 -308.383178)
			(xy 440.573414 -308.36997) (xy 440.566302 -308.344824) (xy 440.486038 -308.26456) (xy 440.460892 -308.257448)
			(xy 440.447684 -308.260496) (xy 440.425731 -308.265464) (xy 440.381036 -308.270807) (xy 440.35853 -308.271164)
			(xy 440.331276 -308.270717) (xy 440.277322 -308.262963) (xy 440.225021 -308.247608) (xy 440.175438 -308.224966)
			(xy 440.129583 -308.195497) (xy 440.088389 -308.159801) (xy 440.052695 -308.118606) (xy 440.023227 -308.072749)
			(xy 440.000587 -308.023166) (xy 439.985234 -307.970864) (xy 439.977482 -307.91691) (xy 439.977022 -307.889656)
			(xy 439.9788 -307.85308) (xy 439.979816 -307.84165) (xy 439.972196 -307.820568) (xy 439.900568 -307.74894)
			(xy 439.879232 -307.74132) (xy 439.867802 -307.742336) (xy 439.831226 -307.744114) (xy 439.803971 -307.743673)
			(xy 439.750015 -307.735919) (xy 439.697711 -307.720565) (xy 439.648125 -307.697923) (xy 439.602267 -307.668455)
			(xy 439.561068 -307.632761) (xy 439.525369 -307.591567) (xy 439.495897 -307.545711) (xy 439.47325 -307.496128)
			(xy 439.45789 -307.443826) (xy 439.45013 -307.389871) (xy 439.450128 -307.33536) (xy 431.080625 -307.33536)
			(xy 431.121312 -307.374798) (xy 431.128648 -307.381331) (xy 431.146807 -307.388777) (xy 431.156618 -307.389276)
			(xy 433.233576 -307.389276) (xy 433.259652 -307.389779) (xy 433.311168 -307.39789) (xy 433.360779 -307.413962)
			(xy 433.407265 -307.437601) (xy 433.449478 -307.468222) (xy 433.468272 -307.486304) (xy 435.15788 -309.175912)
			(xy 436.634126 -309.175912) (xy 436.638197 -309.12029) (xy 436.650323 -309.065853) (xy 436.670246 -309.013762)
			(xy 436.697542 -308.965127) (xy 436.731628 -308.920984) (xy 436.771777 -308.882275) (xy 436.817135 -308.849824)
			(xy 436.866735 -308.824323) (xy 436.919519 -308.806316) (xy 436.974362 -308.796186) (xy 437.030096 -308.794149)
			(xy 437.085533 -308.800249) (xy 437.13949 -308.814355) (xy 437.190819 -308.836167) (xy 437.238425 -308.865221)
			(xy 437.281293 -308.900896) (xy 437.31851 -308.942433) (xy 437.349283 -308.988946) (xy 437.372955 -309.039443)
			(xy 437.389023 -309.09285) (xy 437.397143 -309.148026) (xy 437.397652 -309.175912) (xy 437.397143 -309.203798)
			(xy 437.389023 -309.258974) (xy 437.372955 -309.312381) (xy 437.349283 -309.362878) (xy 437.31851 -309.409391)
			(xy 437.281293 -309.450928) (xy 437.238425 -309.486603) (xy 437.190819 -309.515657) (xy 437.13949 -309.537469)
			(xy 437.085533 -309.551575) (xy 437.030096 -309.557675) (xy 436.974362 -309.555638) (xy 436.919519 -309.545508)
			(xy 436.866735 -309.527501) (xy 436.817135 -309.502) (xy 436.771777 -309.469549) (xy 436.731628 -309.43084)
			(xy 436.697542 -309.386697) (xy 436.670246 -309.338062) (xy 436.650323 -309.285971) (xy 436.638197 -309.231534)
			(xy 436.634126 -309.175912) (xy 435.15788 -309.175912) (xy 435.32806 -309.346092) (xy 435.346168 -309.364863)
			(xy 435.376792 -309.407082) (xy 435.400433 -309.453572) (xy 435.41651 -309.503189) (xy 435.424625 -309.55471)
			(xy 435.425088 -309.580788) (xy 435.425088 -309.85333) (xy 437.310782 -309.85333) (xy 437.314853 -309.797708)
			(xy 437.326979 -309.743271) (xy 437.346902 -309.69118) (xy 437.374198 -309.642545) (xy 437.408284 -309.598402)
			(xy 437.448433 -309.559693) (xy 437.493791 -309.527242) (xy 437.543391 -309.501741) (xy 437.596175 -309.483734)
			(xy 437.651018 -309.473604) (xy 437.706752 -309.471567) (xy 437.762189 -309.477667) (xy 437.816146 -309.491773)
			(xy 437.867475 -309.513585) (xy 437.915081 -309.542639) (xy 437.957949 -309.578314) (xy 437.995166 -309.619851)
			(xy 438.025939 -309.666364) (xy 438.037261 -309.690516) (xy 441.777372 -309.690516) (xy 441.781443 -309.634894)
			(xy 441.793569 -309.580457) (xy 441.813492 -309.528366) (xy 441.840788 -309.479731) (xy 441.874874 -309.435588)
			(xy 441.915023 -309.396879) (xy 441.960381 -309.364428) (xy 442.009981 -309.338927) (xy 442.062765 -309.32092)
			(xy 442.117608 -309.31079) (xy 442.173342 -309.308753) (xy 442.228779 -309.314853) (xy 442.282736 -309.328959)
			(xy 442.334065 -309.350771) (xy 442.381671 -309.379825) (xy 442.424539 -309.4155) (xy 442.461756 -309.457037)
			(xy 442.492529 -309.50355) (xy 442.516201 -309.554047) (xy 442.532269 -309.607454) (xy 442.540389 -309.66263)
			(xy 442.540898 -309.690516) (xy 442.540389 -309.718402) (xy 442.532269 -309.773578) (xy 442.516201 -309.826985)
			(xy 442.492529 -309.877482) (xy 442.461756 -309.923995) (xy 442.424539 -309.965532) (xy 442.381671 -310.001207)
			(xy 442.334065 -310.030261) (xy 442.282736 -310.052073) (xy 442.228779 -310.066179) (xy 442.173342 -310.072279)
			(xy 442.117608 -310.070242) (xy 442.062765 -310.060112) (xy 442.009981 -310.042105) (xy 441.960381 -310.016604)
			(xy 441.915023 -309.984153) (xy 441.874874 -309.945444) (xy 441.840788 -309.901301) (xy 441.813492 -309.852666)
			(xy 441.793569 -309.800575) (xy 441.781443 -309.746138) (xy 441.777372 -309.690516) (xy 438.037261 -309.690516)
			(xy 438.049611 -309.716861) (xy 438.065679 -309.770268) (xy 438.073799 -309.825444) (xy 438.074308 -309.85333)
			(xy 438.073799 -309.881216) (xy 438.065679 -309.936392) (xy 438.049611 -309.989799) (xy 438.025939 -310.040296)
			(xy 437.995166 -310.086809) (xy 437.957949 -310.128346) (xy 437.915081 -310.164021) (xy 437.867475 -310.193075)
			(xy 437.816146 -310.214887) (xy 437.762189 -310.228993) (xy 437.706752 -310.235093) (xy 437.651018 -310.233056)
			(xy 437.596175 -310.222926) (xy 437.543391 -310.204919) (xy 437.493791 -310.179418) (xy 437.448433 -310.146967)
			(xy 437.408284 -310.108258) (xy 437.374198 -310.064115) (xy 437.346902 -310.01548) (xy 437.326979 -309.963389)
			(xy 437.314853 -309.908952) (xy 437.310782 -309.85333) (xy 435.425088 -309.85333) (xy 435.425088 -310.455056)
			(xy 435.425555 -310.465073) (xy 435.433209 -310.483587) (xy 435.447366 -310.49776) (xy 435.465872 -310.505434)
			(xy 435.475888 -310.505856) (xy 437.66867 -310.505856) (xy 437.694758 -310.506331) (xy 437.746291 -310.514496)
			(xy 437.79591 -310.53063) (xy 437.842391 -310.554333) (xy 437.884587 -310.585023) (xy 437.903366 -310.603138)
			(xy 438.032144 -310.731916) (xy 438.05475 -310.757062) (xy 438.06192 -310.765248) (xy 438.081381 -310.774956)
			(xy 438.103115 -310.775757) (xy 438.123238 -310.767507) (xy 438.138155 -310.751681) (xy 438.145201 -310.731105)
			(xy 438.144666 -310.720232) (xy 438.143142 -310.68518) (xy 438.143677 -310.657928) (xy 438.151436 -310.60398)
			(xy 438.166795 -310.551684) (xy 438.18944 -310.502107) (xy 438.218909 -310.456258) (xy 438.254604 -310.415069)
			(xy 438.295798 -310.379379) (xy 438.341651 -310.349916) (xy 438.391231 -310.327277) (xy 438.443529 -310.311926)
			(xy 438.497478 -310.304173) (xy 438.551982 -310.304177) (xy 438.60593 -310.311939) (xy 438.658225 -310.327298)
			(xy 438.707801 -310.349944) (xy 438.75365 -310.379415) (xy 438.794838 -310.415111) (xy 438.830527 -310.456306)
			(xy 438.859989 -310.50216) (xy 438.882626 -310.551741) (xy 438.897976 -310.604038) (xy 438.905728 -310.657988)
			(xy 438.905722 -310.712492) (xy 438.897959 -310.76644) (xy 438.882598 -310.818734) (xy 438.859951 -310.86831)
			(xy 438.830479 -310.914158) (xy 438.794782 -310.955345) (xy 438.753586 -310.991033) (xy 438.707731 -311.020494)
			(xy 438.65815 -311.04313) (xy 438.605852 -311.058479) (xy 438.551902 -311.066228) (xy 438.52465 -311.066688)
			(xy 438.495238 -311.066094) (xy 438.437111 -311.057066) (xy 438.38106 -311.039217) (xy 438.328417 -311.01297)
			(xy 438.280429 -310.978949) (xy 438.238237 -310.93796) (xy 438.220104 -310.914796) (xy 438.213104 -310.906503)
			(xy 438.194056 -310.896161) (xy 438.172438 -310.894588) (xy 438.152093 -310.902064) (xy 438.136637 -310.91726)
			(xy 438.128817 -310.937475) (xy 438.128918 -310.948324) (xy 438.129172 -310.966612) (xy 438.129172 -311.148476)
			(xy 438.128684 -311.174552) (xy 438.120572 -311.22607) (xy 438.104497 -311.275682) (xy 438.080855 -311.322168)
			(xy 438.050228 -311.36438) (xy 438.032144 -311.383172) (xy 437.979962 -311.435354) (xy 438.86679 -311.435354)
			(xy 438.86679 -311.380854) (xy 438.874545 -311.32691) (xy 438.889898 -311.274618) (xy 438.912537 -311.225043)
			(xy 438.942001 -311.179195) (xy 438.977689 -311.138006) (xy 439.018875 -311.102315) (xy 439.064722 -311.072849)
			(xy 439.114295 -311.050207) (xy 439.166586 -311.03485) (xy 439.22053 -311.027092) (xy 439.27503 -311.027089)
			(xy 439.328975 -311.034842) (xy 439.381267 -311.050193) (xy 439.430843 -311.07283) (xy 439.476693 -311.102291)
			(xy 439.517883 -311.137977) (xy 439.553575 -311.179163) (xy 439.583044 -311.225008) (xy 439.605688 -311.27458)
			(xy 439.621046 -311.326871) (xy 439.628807 -311.380814) (xy 439.629296 -311.408064) (xy 439.6291 -311.425112)
			(xy 439.626045 -311.459072) (xy 439.6232 -311.475882) (xy 439.621161 -311.489766) (xy 439.623883 -311.517684)
			(xy 439.634091 -311.543811) (xy 439.651016 -311.56618) (xy 439.673383 -311.583106) (xy 439.69951 -311.593316)
			(xy 439.727428 -311.596039) (xy 439.74131 -311.593992) (xy 439.758181 -311.591119) (xy 439.792269 -311.588068)
			(xy 439.809382 -311.587896) (xy 439.836636 -311.588336) (xy 439.890591 -311.596091) (xy 439.942892 -311.611445)
			(xy 439.992476 -311.634087) (xy 440.038333 -311.663554) (xy 440.07953 -311.699248) (xy 440.115227 -311.740442)
			(xy 440.144698 -311.786296) (xy 440.167344 -311.835878) (xy 440.182703 -311.888179) (xy 440.190462 -311.942132)
			(xy 440.190464 -311.996641) (xy 440.182708 -312.050595) (xy 440.167353 -312.102897) (xy 440.144711 -312.15248)
			(xy 440.115243 -312.198337) (xy 440.079548 -312.239533) (xy 440.038354 -312.27523) (xy 439.9925 -312.304701)
			(xy 439.942917 -312.327346) (xy 439.890617 -312.342704) (xy 439.836663 -312.350462) (xy 439.782154 -312.350464)
			(xy 439.7282 -312.342707) (xy 439.675899 -312.327352) (xy 439.626316 -312.304709) (xy 439.580459 -312.27524)
			(xy 439.539264 -312.239545) (xy 439.503568 -312.198351) (xy 439.474097 -312.152495) (xy 439.451453 -312.102913)
			(xy 439.436095 -312.050612) (xy 439.428337 -311.996658) (xy 439.427874 -311.969404) (xy 439.428079 -311.952356)
			(xy 439.431128 -311.918397) (xy 439.43397 -311.901586) (xy 439.436077 -311.88771) (xy 439.433347 -311.859783)
			(xy 439.423129 -311.833649) (xy 439.406193 -311.811276) (xy 439.383813 -311.794349) (xy 439.357675 -311.784143)
			(xy 439.329746 -311.781425) (xy 439.31586 -311.783476) (xy 439.298988 -311.78634) (xy 439.2649 -311.789396)
			(xy 439.247788 -311.789572) (xy 439.220538 -311.789109) (xy 439.166594 -311.781351) (xy 439.114303 -311.765996)
			(xy 439.064729 -311.743355) (xy 439.018882 -311.71389) (xy 438.977694 -311.6782) (xy 438.942005 -311.637012)
			(xy 438.912541 -311.591164) (xy 438.889901 -311.54159) (xy 438.874547 -311.489298) (xy 438.86679 -311.435354)
			(xy 437.979962 -311.435354) (xy 437.903366 -311.51195) (xy 437.884595 -311.530074) (xy 437.842395 -311.560757)
			(xy 437.795912 -311.584455) (xy 437.746291 -311.600585) (xy 437.694758 -311.608748) (xy 437.66867 -311.609232)
			(xy 435.475888 -311.609232) (xy 435.465862 -311.609611) (xy 435.447339 -311.61729) (xy 435.433166 -311.631476)
			(xy 435.425502 -311.650006) (xy 435.425088 -311.660032) (xy 435.425088 -312.184542) (xy 435.428136 -312.19648)
			(xy 435.43093 -312.202068) (xy 435.444761 -312.229597) (xy 435.464326 -312.288013) (xy 435.474261 -312.348812)
			(xy 435.474872 -312.379614) (xy 435.474458 -312.406869) (xy 435.466698 -312.460823) (xy 435.451339 -312.513125)
			(xy 435.428692 -312.562707) (xy 435.399219 -312.608562) (xy 435.36352 -312.649755) (xy 435.322322 -312.685449)
			(xy 435.276463 -312.714916) (xy 435.226878 -312.737556) (xy 435.174575 -312.752909) (xy 435.120619 -312.760662)
			(xy 435.093364 -312.761122) (xy 435.08133 -312.761016) (xy 435.057309 -312.759492) (xy 435.045358 -312.758074)
			(xy 435.034436 -312.756804) (xy 435.014116 -312.7629) (xy 434.940202 -312.8264) (xy 434.931312 -312.845704)
			(xy 434.931058 -312.856626) (xy 434.93005 -312.883506) (xy 434.921379 -312.936593) (xy 434.90534 -312.987937)
			(xy 434.88225 -313.036521) (xy 434.852568 -313.08138) (xy 434.816881 -313.121628) (xy 434.775896 -313.156466)
			(xy 434.730425 -313.185205) (xy 434.68137 -313.207274) (xy 434.629702 -313.222237) (xy 434.576445 -313.229796)
			(xy 434.54955 -313.23026) (xy 434.522296 -313.229798) (xy 434.468343 -313.222047) (xy 434.416042 -313.206695)
			(xy 434.366459 -313.184054) (xy 434.320603 -313.154587) (xy 434.279409 -313.118893) (xy 434.243714 -313.077699)
			(xy 434.214247 -313.031843) (xy 434.191606 -312.98226) (xy 434.176254 -312.929959) (xy 434.168502 -312.876006)
			(xy 434.168042 -312.848752) (xy 434.168635 -312.817948) (xy 434.178566 -312.757147) (xy 434.198147 -312.698734)
			(xy 434.211984 -312.671206) (xy 434.214778 -312.665618) (xy 434.217572 -312.65368) (xy 434.217572 -310.063134)
			(xy 434.217085 -310.053168) (xy 434.209517 -310.034733) (xy 434.20284 -310.02732) (xy 433.28463 -309.10911)
			(xy 433.277227 -309.102385) (xy 433.258802 -309.094665) (xy 433.248816 -309.094124) (xy 431.156872 -309.094124)
			(xy 431.146779 -309.09461) (xy 431.128179 -309.102458) (xy 431.120804 -309.109364) (xy 431.062638 -309.167784)
			(xy 431.055272 -309.18658) (xy 431.055272 -309.199788) (xy 431.05475 -309.225043) (xy 431.046437 -309.274865)
			(xy 431.030036 -309.322639) (xy 431.005995 -309.367062) (xy 430.974971 -309.406922) (xy 430.937809 -309.441132)
			(xy 430.895523 -309.468758) (xy 430.849267 -309.489048) (xy 430.800302 -309.501448) (xy 430.749964 -309.505619)
			(xy 430.699626 -309.501448) (xy 430.650661 -309.489048) (xy 430.604405 -309.468758) (xy 430.562119 -309.441132)
			(xy 430.524957 -309.406922) (xy 430.493933 -309.367062) (xy 430.469892 -309.322639) (xy 430.453491 -309.274865)
			(xy 430.445178 -309.225043) (xy 430.444656 -309.199788) (xy 430.444656 -309.19674) (xy 430.444656 -309.18658)
			(xy 430.43729 -309.167784) (xy 430.379124 -309.109364) (xy 430.371753 -309.102453) (xy 430.35315 -309.094604)
			(xy 430.343056 -309.094124) (xy 430.206912 -309.094124) (xy 430.196815 -309.094579) (xy 430.178216 -309.102448)
			(xy 430.170844 -309.109364) (xy 430.112678 -309.167784) (xy 430.105312 -309.18658) (xy 430.105312 -309.199788)
			(xy 430.10479 -309.225043) (xy 430.096477 -309.274865) (xy 430.080076 -309.322639) (xy 430.056035 -309.367062)
			(xy 430.025011 -309.406922) (xy 429.987849 -309.441132) (xy 429.945563 -309.468758) (xy 429.899307 -309.489048)
			(xy 429.850342 -309.501448) (xy 429.800004 -309.505619) (xy 429.749666 -309.501448) (xy 429.700701 -309.489048)
			(xy 429.654445 -309.468758) (xy 429.612159 -309.441132) (xy 429.574997 -309.406922) (xy 429.543973 -309.367062)
			(xy 429.519932 -309.322639) (xy 429.503531 -309.274865) (xy 429.495218 -309.225043) (xy 429.494696 -309.199788)
			(xy 429.494696 -309.19674) (xy 429.494696 -309.18658) (xy 429.48733 -309.167784) (xy 429.429164 -309.109364)
			(xy 429.421779 -309.102471) (xy 429.403186 -309.094611) (xy 429.393096 -309.094124) (xy 429.278288 -309.094124)
			(xy 429.268196 -309.094619) (xy 429.249596 -309.102461) (xy 429.24222 -309.109364) (xy 429.184308 -309.167784)
			(xy 429.176688 -309.18658) (xy 429.176688 -309.199788) (xy 429.176184 -309.225476) (xy 429.168147 -309.276219)
			(xy 429.152271 -309.32508) (xy 429.128947 -309.370856) (xy 429.09875 -309.41242) (xy 429.062422 -309.448748)
			(xy 429.020858 -309.478945) (xy 428.975082 -309.502269) (xy 428.926221 -309.518145) (xy 428.875478 -309.526182)
			(xy 428.824102 -309.526182) (xy 428.773359 -309.518145) (xy 428.724498 -309.502269) (xy 428.678722 -309.478945)
			(xy 428.637158 -309.448748) (xy 428.60083 -309.41242) (xy 428.570633 -309.370856) (xy 428.547309 -309.32508)
			(xy 428.531433 -309.276219) (xy 428.523396 -309.225476) (xy 428.522892 -309.199788) (xy 428.522892 -309.19674)
			(xy 428.522892 -309.18658) (xy 428.515272 -309.167784) (xy 428.45736 -309.109364) (xy 428.449976 -309.102469)
			(xy 428.431383 -309.09461) (xy 428.421292 -309.094124) (xy 428.328328 -309.094124) (xy 428.318233 -309.094587)
			(xy 428.299633 -309.102451) (xy 428.29226 -309.109364) (xy 428.234348 -309.167784) (xy 428.226728 -309.18658)
			(xy 428.226728 -309.199788) (xy 428.226224 -309.225476) (xy 428.218187 -309.276219) (xy 428.202311 -309.32508)
			(xy 428.178987 -309.370856) (xy 428.14879 -309.41242) (xy 428.112462 -309.448748) (xy 428.070898 -309.478945)
			(xy 428.025122 -309.502269) (xy 427.976261 -309.518145) (xy 427.925518 -309.526182) (xy 427.874142 -309.526182)
			(xy 427.823399 -309.518145) (xy 427.774538 -309.502269) (xy 427.728762 -309.478945) (xy 427.687198 -309.448748)
			(xy 427.65087 -309.41242) (xy 427.620673 -309.370856) (xy 427.597349 -309.32508) (xy 427.581473 -309.276219)
			(xy 427.573436 -309.225476) (xy 427.572932 -309.199788) (xy 427.572932 -309.19674) (xy 427.572932 -309.18658)
			(xy 427.565312 -309.167784) (xy 427.5074 -309.109364) (xy 427.500002 -309.102486) (xy 427.481419 -309.094617)
			(xy 427.471332 -309.094124) (xy 427.356778 -309.094124) (xy 427.346685 -309.094613) (xy 427.328085 -309.102459)
			(xy 427.32071 -309.109364) (xy 427.262544 -309.167784) (xy 427.255178 -309.18658) (xy 427.255178 -309.199788)
			(xy 427.254656 -309.225043) (xy 427.246343 -309.274865) (xy 427.229942 -309.322639) (xy 427.205901 -309.367062)
			(xy 427.174877 -309.406922) (xy 427.137715 -309.441132) (xy 427.095429 -309.468758) (xy 427.049173 -309.489048)
			(xy 427.000208 -309.501448) (xy 426.94987 -309.505619) (xy 426.899532 -309.501448) (xy 426.850567 -309.489048)
			(xy 426.804311 -309.468758) (xy 426.762025 -309.441132) (xy 426.724863 -309.406922) (xy 426.693839 -309.367062)
			(xy 426.669798 -309.322639) (xy 426.653397 -309.274865) (xy 426.645084 -309.225043) (xy 426.644562 -309.199788)
			(xy 426.644562 -309.19674) (xy 426.644562 -309.18658) (xy 426.637196 -309.167784) (xy 426.57903 -309.109364)
			(xy 426.571657 -309.102456) (xy 426.553055 -309.094605) (xy 426.542962 -309.094124) (xy 426.428408 -309.094124)
			(xy 426.418317 -309.094629) (xy 426.399717 -309.102464) (xy 426.39234 -309.109364) (xy 426.334428 -309.167784)
			(xy 426.326808 -309.18658) (xy 426.326808 -309.199788) (xy 426.326304 -309.225476) (xy 426.318267 -309.276219)
			(xy 426.302391 -309.32508) (xy 426.279067 -309.370856) (xy 426.24887 -309.41242) (xy 426.212542 -309.448748)
			(xy 426.170978 -309.478945) (xy 426.125202 -309.502269) (xy 426.076341 -309.518145) (xy 426.025598 -309.526182)
			(xy 425.974222 -309.526182) (xy 425.923479 -309.518145) (xy 425.874618 -309.502269) (xy 425.828842 -309.478945)
			(xy 425.787278 -309.448748) (xy 425.75095 -309.41242) (xy 425.720753 -309.370856) (xy 425.697429 -309.32508)
			(xy 425.681553 -309.276219) (xy 425.673516 -309.225476) (xy 425.673012 -309.199788) (xy 425.673012 -309.19674)
			(xy 425.673012 -309.18658) (xy 425.665392 -309.167784) (xy 425.60748 -309.109364) (xy 425.600089 -309.102478)
			(xy 425.581501 -309.094614) (xy 425.571412 -309.094124) (xy 425.478448 -309.094124) (xy 425.468354 -309.094597)
			(xy 425.449754 -309.102454) (xy 425.44238 -309.109364) (xy 425.384468 -309.167784) (xy 425.376848 -309.18658)
			(xy 425.376848 -309.199788) (xy 425.376344 -309.225476) (xy 425.368307 -309.276219) (xy 425.352431 -309.32508)
			(xy 425.329107 -309.370856) (xy 425.29891 -309.41242) (xy 425.262582 -309.448748) (xy 425.221018 -309.478945)
			(xy 425.175242 -309.502269) (xy 425.126381 -309.518145) (xy 425.075638 -309.526182) (xy 425.024262 -309.526182)
			(xy 424.973519 -309.518145) (xy 424.924658 -309.502269) (xy 424.878882 -309.478945) (xy 424.837318 -309.448748)
			(xy 424.80099 -309.41242) (xy 424.770793 -309.370856) (xy 424.747469 -309.32508) (xy 424.731593 -309.276219)
			(xy 424.723556 -309.225476) (xy 424.723052 -309.199788) (xy 424.723052 -309.19674) (xy 424.723052 -309.18658)
			(xy 424.715432 -309.167784) (xy 424.65752 -309.109364) (xy 424.65015 -309.102452) (xy 424.631546 -309.094603)
			(xy 424.621452 -309.094124) (xy 424.506898 -309.094124) (xy 424.496807 -309.094624) (xy 424.478206 -309.102462)
			(xy 424.47083 -309.109364) (xy 424.412664 -309.167784) (xy 424.405298 -309.18658) (xy 424.405298 -309.199788)
			(xy 424.404776 -309.225043) (xy 424.396463 -309.274865) (xy 424.380062 -309.322639) (xy 424.356021 -309.367062)
			(xy 424.324997 -309.406922) (xy 424.287835 -309.441132) (xy 424.245549 -309.468758) (xy 424.199293 -309.489048)
			(xy 424.150328 -309.501448) (xy 424.09999 -309.505619) (xy 424.049652 -309.501448) (xy 424.000687 -309.489048)
			(xy 423.954431 -309.468758) (xy 423.912145 -309.441132) (xy 423.874983 -309.406922) (xy 423.843959 -309.367062)
			(xy 423.819918 -309.322639) (xy 423.803517 -309.274865) (xy 423.795204 -309.225043) (xy 423.794682 -309.199788)
			(xy 423.794682 -309.19674) (xy 423.794682 -309.18658) (xy 423.787316 -309.167784) (xy 423.72915 -309.109364)
			(xy 423.72177 -309.102465) (xy 423.703173 -309.094608) (xy 423.693082 -309.094124) (xy 423.556938 -309.094124)
			(xy 423.546843 -309.094592) (xy 423.528243 -309.102453) (xy 423.52087 -309.109364) (xy 423.462704 -309.167784)
			(xy 423.455338 -309.18658) (xy 423.455338 -309.199788) (xy 423.454816 -309.225043) (xy 423.446503 -309.274865)
			(xy 423.430102 -309.322639) (xy 423.406061 -309.367062) (xy 423.375037 -309.406922) (xy 423.337875 -309.441132)
			(xy 423.295589 -309.468758) (xy 423.249333 -309.489048) (xy 423.200368 -309.501448) (xy 423.15003 -309.505619)
			(xy 423.099692 -309.501448) (xy 423.050727 -309.489048) (xy 423.004471 -309.468758) (xy 422.962185 -309.441132)
			(xy 422.925023 -309.406922) (xy 422.893999 -309.367062) (xy 422.869958 -309.322639) (xy 422.853557 -309.274865)
			(xy 422.845244 -309.225043) (xy 422.844722 -309.199788) (xy 422.844907 -309.184894) (xy 422.847838 -309.15525)
			(xy 422.850564 -309.140606) (xy 422.851854 -309.132473) (xy 422.849793 -309.116148) (xy 422.8465 -309.108602)
			(xy 422.833292 -309.081678) (xy 422.82943 -309.074384) (xy 422.817888 -309.062597) (xy 422.810686 -309.058564)
			(xy 422.787435 -309.046228) (xy 422.744815 -309.015348) (xy 422.72585 -308.997096) (xy 422.289478 -308.560724)
			(xy 422.282052 -308.554064) (xy 422.263626 -308.546478) (xy 422.253664 -308.545992) (xy 422.124378 -308.545992)
			(xy 422.113104 -308.546498) (xy 422.092664 -308.55599) (xy 422.085008 -308.56428) (xy 422.027858 -308.633622)
			(xy 422.02227 -308.655466) (xy 422.024556 -308.666896) (xy 422.02716 -308.681233) (xy 422.029961 -308.710238)
			(xy 422.030144 -308.724808) (xy 422.029622 -308.750063) (xy 422.021309 -308.799885) (xy 422.004908 -308.847659)
			(xy 421.980867 -308.892082) (xy 421.949843 -308.931942) (xy 421.912681 -308.966152) (xy 421.870395 -308.993778)
			(xy 421.824139 -309.014068) (xy 421.775174 -309.026468) (xy 421.724836 -309.030639) (xy 421.674498 -309.026468)
			(xy 421.625533 -309.014068) (xy 421.579277 -308.993778) (xy 421.536991 -308.966152) (xy 421.499829 -308.931942)
			(xy 421.468805 -308.892082) (xy 421.444764 -308.847659) (xy 421.428363 -308.799885) (xy 421.42005 -308.750063)
			(xy 421.419528 -308.724808) (xy 421.419706 -308.710238) (xy 421.422505 -308.681232) (xy 421.425116 -308.666896)
			(xy 421.427402 -308.655466) (xy 421.421814 -308.633622) (xy 421.364664 -308.56428) (xy 421.356991 -308.556015)
			(xy 421.336559 -308.54653) (xy 421.325294 -308.545992) (xy 421.174418 -308.545992) (xy 421.16314 -308.546464)
			(xy 421.142701 -308.55598) (xy 421.135048 -308.56428) (xy 421.077898 -308.633622) (xy 421.07231 -308.655466)
			(xy 421.074596 -308.666896) (xy 421.077201 -308.681233) (xy 421.080001 -308.710238) (xy 421.080184 -308.724808)
			(xy 421.079662 -308.750063) (xy 421.071349 -308.799885) (xy 421.054948 -308.847659) (xy 421.030907 -308.892082)
			(xy 420.999883 -308.931942) (xy 420.962721 -308.966152) (xy 420.920435 -308.993778) (xy 420.874179 -309.014068)
			(xy 420.825214 -309.026468) (xy 420.774876 -309.030639) (xy 420.724538 -309.026468) (xy 420.675573 -309.014068)
			(xy 420.629317 -308.993778) (xy 420.587031 -308.966152) (xy 420.549869 -308.931942) (xy 420.518845 -308.892082)
			(xy 420.494804 -308.847659) (xy 420.478403 -308.799885) (xy 420.47009 -308.750063) (xy 420.469568 -308.724808)
			(xy 420.469747 -308.710238) (xy 420.472546 -308.681232) (xy 420.475156 -308.666896) (xy 420.477442 -308.655466)
			(xy 420.471854 -308.633622) (xy 420.414704 -308.56428) (xy 420.407014 -308.556033) (xy 420.386595 -308.546538)
			(xy 420.375334 -308.545992) (xy 420.224458 -308.545992) (xy 420.213183 -308.546487) (xy 420.192743 -308.555987)
			(xy 420.185088 -308.56428) (xy 420.127938 -308.633622) (xy 420.12235 -308.655466) (xy 420.124636 -308.666896)
			(xy 420.127241 -308.681232) (xy 420.130041 -308.710238) (xy 420.130224 -308.724808) (xy 420.129702 -308.750063)
			(xy 420.121389 -308.799885) (xy 420.104988 -308.847659) (xy 420.080947 -308.892082) (xy 420.049923 -308.931942)
			(xy 420.012761 -308.966152) (xy 419.970475 -308.993778) (xy 419.924219 -309.014068) (xy 419.875254 -309.026468)
			(xy 419.824916 -309.030639) (xy 419.774578 -309.026468) (xy 419.725613 -309.014068) (xy 419.679357 -308.993778)
			(xy 419.637071 -308.966152) (xy 419.599909 -308.931942) (xy 419.568885 -308.892082) (xy 419.544844 -308.847659)
			(xy 419.528443 -308.799885) (xy 419.52013 -308.750063) (xy 419.519608 -308.724808) (xy 419.519786 -308.710238)
			(xy 419.522586 -308.681232) (xy 419.525196 -308.666896) (xy 419.527482 -308.655466) (xy 419.521894 -308.633622)
			(xy 419.464744 -308.56428) (xy 419.457079 -308.556006) (xy 419.436641 -308.546526) (xy 419.425374 -308.545992)
			(xy 419.274498 -308.545992) (xy 419.263226 -308.54651) (xy 419.242786 -308.555993) (xy 419.235128 -308.56428)
			(xy 419.177978 -308.633622) (xy 419.17239 -308.655466) (xy 419.174676 -308.666896) (xy 419.17728 -308.681233)
			(xy 419.180081 -308.710238) (xy 419.180264 -308.724808) (xy 419.179742 -308.750063) (xy 419.171429 -308.799885)
			(xy 419.155028 -308.847659) (xy 419.130987 -308.892082) (xy 419.099963 -308.931942) (xy 419.062801 -308.966152)
			(xy 419.020515 -308.993778) (xy 418.974259 -309.014068) (xy 418.925294 -309.026468) (xy 418.874956 -309.030639)
			(xy 418.824618 -309.026468) (xy 418.775653 -309.014068) (xy 418.729397 -308.993778) (xy 418.687111 -308.966152)
			(xy 418.649949 -308.931942) (xy 418.618925 -308.892082) (xy 418.594884 -308.847659) (xy 418.578483 -308.799885)
			(xy 418.57017 -308.750063) (xy 418.569648 -308.724808) (xy 418.569825 -308.710238) (xy 418.572625 -308.681232)
			(xy 418.575236 -308.666896) (xy 418.577522 -308.655466) (xy 418.571934 -308.633622) (xy 418.514784 -308.56428)
			(xy 418.507103 -308.556024) (xy 418.486677 -308.546534) (xy 418.475414 -308.545992) (xy 418.324538 -308.545992)
			(xy 418.313262 -308.546475) (xy 418.292822 -308.555983) (xy 418.285168 -308.56428) (xy 418.228018 -308.633622)
			(xy 418.22243 -308.655466) (xy 418.224716 -308.666896) (xy 418.227321 -308.681233) (xy 418.230121 -308.710238)
			(xy 418.230304 -308.724808) (xy 418.229845 -308.7488) (xy 418.222337 -308.796192) (xy 418.207509 -308.841826)
			(xy 418.185724 -308.884579) (xy 418.157519 -308.923398) (xy 418.123589 -308.957327) (xy 418.084769 -308.98553)
			(xy 418.042015 -309.007313) (xy 417.99638 -309.02214) (xy 417.948988 -309.029646) (xy 417.924996 -309.030116)
			(xy 417.90104 -309.029706) (xy 417.853714 -309.022236) (xy 417.808137 -309.007464) (xy 417.765427 -308.985753)
			(xy 417.726633 -308.957637) (xy 417.692708 -308.923804) (xy 417.664485 -308.885088) (xy 417.642657 -308.842437)
			(xy 417.62776 -308.7969) (xy 417.623498 -308.773322) (xy 417.621212 -308.759352) (xy 417.60267 -308.737508)
			(xy 417.503102 -308.70525) (xy 417.494111 -308.702659) (xy 417.475435 -308.703641) (xy 417.458375 -308.711304)
			(xy 417.45154 -308.717696) (xy 417.209732 -308.959504) (xy 417.190941 -308.977591) (xy 417.148729 -309.00822)
			(xy 417.102244 -309.031866) (xy 417.052631 -309.047948) (xy 417.001113 -309.056067) (xy 416.975036 -309.056532)
			(xy 416.948968 -309.056006) (xy 416.897474 -309.047855) (xy 416.847889 -309.031749) (xy 416.801434 -309.008084)
			(xy 416.759253 -308.977443) (xy 416.722386 -308.94058) (xy 416.691739 -308.898404) (xy 416.668068 -308.851952)
			(xy 416.651955 -308.802369) (xy 416.643797 -308.750876) (xy 416.643312 -308.724808) (xy 416.33013 -308.724808)
			(xy 416.329635 -308.749415) (xy 416.32174 -308.797992) (xy 416.306156 -308.844673) (xy 416.283285 -308.88825)
			(xy 416.25372 -308.927594) (xy 416.218227 -308.961686) (xy 416.177724 -308.989642) (xy 416.133262 -309.01074)
			(xy 416.085991 -309.024432) (xy 416.037136 -309.030364) (xy 415.987961 -309.028383) (xy 415.939742 -309.018539)
			(xy 415.893726 -309.001087) (xy 415.851105 -308.97648) (xy 415.812984 -308.945355) (xy 415.780349 -308.908518)
			(xy 415.754046 -308.866922) (xy 415.734755 -308.821646) (xy 415.722978 -308.773862) (xy 415.719018 -308.724808)
			(xy 415.38017 -308.724808) (xy 415.379675 -308.749415) (xy 415.37178 -308.797992) (xy 415.356196 -308.844673)
			(xy 415.333325 -308.88825) (xy 415.30376 -308.927594) (xy 415.268267 -308.961686) (xy 415.227764 -308.989642)
			(xy 415.183302 -309.01074) (xy 415.136031 -309.024432) (xy 415.087176 -309.030364) (xy 415.038001 -309.028383)
			(xy 414.989782 -309.018539) (xy 414.943766 -309.001087) (xy 414.901145 -308.97648) (xy 414.863024 -308.945355)
			(xy 414.830389 -308.908518) (xy 414.804086 -308.866922) (xy 414.784795 -308.821646) (xy 414.773018 -308.773862)
			(xy 414.769058 -308.724808) (xy 414.43021 -308.724808) (xy 414.429715 -308.749415) (xy 414.42182 -308.797992)
			(xy 414.406236 -308.844673) (xy 414.383365 -308.88825) (xy 414.3538 -308.927594) (xy 414.318307 -308.961686)
			(xy 414.277804 -308.989642) (xy 414.233342 -309.01074) (xy 414.186071 -309.024432) (xy 414.137216 -309.030364)
			(xy 414.088041 -309.028383) (xy 414.039822 -309.018539) (xy 413.993806 -309.001087) (xy 413.951185 -308.97648)
			(xy 413.913064 -308.945355) (xy 413.880429 -308.908518) (xy 413.854126 -308.866922) (xy 413.834835 -308.821646)
			(xy 413.823058 -308.773862) (xy 413.819098 -308.724808) (xy 413.48025 -308.724808) (xy 413.479755 -308.749415)
			(xy 413.47186 -308.797992) (xy 413.456276 -308.844673) (xy 413.433405 -308.88825) (xy 413.40384 -308.927594)
			(xy 413.368347 -308.961686) (xy 413.327844 -308.989642) (xy 413.283382 -309.01074) (xy 413.236111 -309.024432)
			(xy 413.187256 -309.030364) (xy 413.138081 -309.028383) (xy 413.089862 -309.018539) (xy 413.043846 -309.001087)
			(xy 413.001225 -308.97648) (xy 412.963104 -308.945355) (xy 412.930469 -308.908518) (xy 412.904166 -308.866922)
			(xy 412.884875 -308.821646) (xy 412.873098 -308.773862) (xy 412.869138 -308.724808) (xy 412.53029 -308.724808)
			(xy 412.529795 -308.749415) (xy 412.5219 -308.797992) (xy 412.506316 -308.844673) (xy 412.483445 -308.88825)
			(xy 412.45388 -308.927594) (xy 412.418387 -308.961686) (xy 412.377884 -308.989642) (xy 412.333422 -309.01074)
			(xy 412.286151 -309.024432) (xy 412.237296 -309.030364) (xy 412.188121 -309.028383) (xy 412.139902 -309.018539)
			(xy 412.093886 -309.001087) (xy 412.051265 -308.97648) (xy 412.013144 -308.945355) (xy 411.980509 -308.908518)
			(xy 411.954206 -308.866922) (xy 411.934915 -308.821646) (xy 411.923138 -308.773862) (xy 411.919178 -308.724808)
			(xy 411.580071 -308.724808) (xy 411.579581 -308.749161) (xy 411.571686 -308.797738) (xy 411.556102 -308.844419)
			(xy 411.533231 -308.887996) (xy 411.503666 -308.92734) (xy 411.468173 -308.961432) (xy 411.42767 -308.989388)
			(xy 411.383208 -309.010486) (xy 411.335937 -309.024178) (xy 411.287082 -309.03011) (xy 411.237907 -309.028129)
			(xy 411.189688 -309.018285) (xy 411.143672 -309.000833) (xy 411.101051 -308.976226) (xy 411.06293 -308.945101)
			(xy 411.030295 -308.908264) (xy 411.003992 -308.866668) (xy 410.984701 -308.821392) (xy 410.972924 -308.773608)
			(xy 410.968964 -308.724554) (xy 410.630065 -308.724554) (xy 410.630527 -308.733074) (xy 410.625161 -308.782426)
			(xy 410.611881 -308.83026) (xy 410.591038 -308.875315) (xy 410.56318 -308.916405) (xy 410.529042 -308.952446)
			(xy 410.489522 -308.98249) (xy 410.445662 -309.005744) (xy 410.398618 -309.021597) (xy 410.349629 -309.029629)
			(xy 410.324808 -309.030116) (xy 410.310625 -309.029938) (xy 410.282385 -309.027267) (xy 410.26842 -309.024782)
			(xy 410.255974 -309.022496) (xy 410.232352 -309.029862) (xy 410.154882 -309.107332) (xy 410.147516 -309.130954)
			(xy 410.149802 -309.1434) (xy 410.152275 -309.157367) (xy 410.154949 -309.185606) (xy 410.155136 -309.199788)
			(xy 410.154614 -309.225043) (xy 410.146301 -309.274865) (xy 410.1299 -309.322639) (xy 410.105859 -309.367062)
			(xy 410.074835 -309.406922) (xy 410.037673 -309.441132) (xy 409.995387 -309.468758) (xy 409.949131 -309.489048)
			(xy 409.900166 -309.501448) (xy 409.849828 -309.505619) (xy 409.79949 -309.501448) (xy 409.750525 -309.489048)
			(xy 409.704269 -309.468758) (xy 409.661983 -309.441132) (xy 409.624821 -309.406922) (xy 409.593797 -309.367062)
			(xy 409.569756 -309.322639) (xy 409.553355 -309.274865) (xy 409.545042 -309.225043) (xy 409.54452 -309.199788)
			(xy 409.544695 -309.185605) (xy 409.547368 -309.157365) (xy 409.549854 -309.1434) (xy 409.55214 -309.130954)
			(xy 409.544774 -309.107332) (xy 409.467304 -309.029862) (xy 409.443682 -309.022496) (xy 409.431236 -309.024782)
			(xy 409.417271 -309.027263) (xy 409.389031 -309.029932) (xy 409.374848 -309.030116) (xy 409.360665 -309.029933)
			(xy 409.332425 -309.027265) (xy 409.31846 -309.024782) (xy 409.306014 -309.022496) (xy 409.282392 -309.029862)
			(xy 409.204922 -309.107332) (xy 409.197556 -309.130954) (xy 409.199842 -309.1434) (xy 409.202314 -309.157367)
			(xy 409.204989 -309.185606) (xy 409.205176 -309.199788) (xy 409.204654 -309.225043) (xy 409.196341 -309.274865)
			(xy 409.17994 -309.322639) (xy 409.155899 -309.367062) (xy 409.124875 -309.406922) (xy 409.087713 -309.441132)
			(xy 409.045427 -309.468758) (xy 408.999171 -309.489048) (xy 408.950206 -309.501448) (xy 408.899868 -309.505619)
			(xy 408.84953 -309.501448) (xy 408.800565 -309.489048) (xy 408.754309 -309.468758) (xy 408.712023 -309.441132)
			(xy 408.674861 -309.406922) (xy 408.643837 -309.367062) (xy 408.619796 -309.322639) (xy 408.603395 -309.274865)
			(xy 408.595082 -309.225043) (xy 408.59456 -309.199788) (xy 408.594736 -309.185605) (xy 408.597408 -309.157365)
			(xy 408.599894 -309.1434) (xy 408.60218 -309.130954) (xy 408.594814 -309.107332) (xy 408.517344 -309.029862)
			(xy 408.493722 -309.022496) (xy 408.481276 -309.024782) (xy 408.46731 -309.027258) (xy 408.43907 -309.02993)
			(xy 408.424888 -309.030116) (xy 408.400068 -309.029609) (xy 408.351083 -309.021576) (xy 408.304042 -309.005725)
			(xy 408.260186 -308.982471) (xy 408.220669 -308.952429) (xy 408.186534 -308.91639) (xy 408.158678 -308.875303)
			(xy 408.137836 -308.83025) (xy 408.124558 -308.78242) (xy 408.119193 -308.733071) (xy 406.83011 -308.733071)
			(xy 406.829781 -308.749415) (xy 406.821886 -308.797992) (xy 406.806302 -308.844673) (xy 406.783431 -308.88825)
			(xy 406.753866 -308.927594) (xy 406.718373 -308.961686) (xy 406.67787 -308.989642) (xy 406.633408 -309.01074)
			(xy 406.586137 -309.024432) (xy 406.537282 -309.030364) (xy 406.488107 -309.028383) (xy 406.439888 -309.018539)
			(xy 406.393872 -309.001087) (xy 406.351251 -308.97648) (xy 406.31313 -308.945355) (xy 406.280495 -308.908518)
			(xy 406.254192 -308.866922) (xy 406.234901 -308.821646) (xy 406.223124 -308.773862) (xy 406.219164 -308.724808)
			(xy 404.93028 -308.724808) (xy 404.930728 -308.733047) (xy 404.925366 -308.782398) (xy 404.912092 -308.830232)
			(xy 404.891253 -308.875288) (xy 404.8634 -308.91638) (xy 404.829267 -308.952424) (xy 404.789752 -308.982471)
			(xy 404.745896 -309.00573) (xy 404.698855 -309.021588) (xy 404.649869 -309.029626) (xy 404.625048 -309.030116)
			(xy 404.610801 -309.029949) (xy 404.582434 -309.027276) (xy 404.568406 -309.024782) (xy 404.556214 -309.022496)
			(xy 404.532084 -309.029862) (xy 404.454868 -309.107078) (xy 404.447502 -309.130954) (xy 404.449788 -309.1434)
			(xy 404.45226 -309.157367) (xy 404.454935 -309.185606) (xy 404.455122 -309.199788) (xy 404.454943 -309.213971)
			(xy 404.452273 -309.242211) (xy 404.449788 -309.256176) (xy 404.447502 -309.268622) (xy 404.454868 -309.292244)
			(xy 404.532338 -309.369714) (xy 404.55596 -309.37708) (xy 404.568406 -309.374794) (xy 404.582372 -309.372321)
			(xy 404.610612 -309.369647) (xy 404.624794 -309.36946) (xy 404.648783 -309.369968) (xy 404.696172 -309.377472)
			(xy 404.741803 -309.392297) (xy 404.784554 -309.414077) (xy 404.823371 -309.442276) (xy 404.857299 -309.4762)
			(xy 404.885503 -309.515014) (xy 404.907289 -309.557762) (xy 404.922119 -309.603391) (xy 404.929629 -309.650779)
			(xy 404.930102 -309.674768) (xy 404.929921 -309.688951) (xy 404.927252 -309.717191) (xy 404.924768 -309.731156)
			(xy 404.922482 -309.743602) (xy 404.929848 -309.767478) (xy 405.007064 -309.844694) (xy 405.031194 -309.85206)
			(xy 405.043386 -309.849774) (xy 405.057416 -309.847294) (xy 405.085782 -309.844619) (xy 405.100028 -309.84444)
			(xy 405.114211 -309.844612) (xy 405.142451 -309.847287) (xy 405.156416 -309.849774) (xy 405.168862 -309.85206)
			(xy 405.192484 -309.844694) (xy 405.269954 -309.767224) (xy 405.27732 -309.743602) (xy 405.275034 -309.731156)
			(xy 405.272556 -309.71719) (xy 405.269885 -309.688951) (xy 405.2697 -309.674768) (xy 405.270222 -309.649513)
			(xy 405.278535 -309.599691) (xy 405.294936 -309.551917) (xy 405.318977 -309.507494) (xy 405.350001 -309.467634)
			(xy 405.387163 -309.433424) (xy 405.429449 -309.405798) (xy 405.475705 -309.385508) (xy 405.52467 -309.373108)
			(xy 405.575008 -309.368937) (xy 405.625346 -309.373108) (xy 405.674311 -309.385508) (xy 405.720567 -309.405798)
			(xy 405.762853 -309.433424) (xy 405.800015 -309.467634) (xy 405.831039 -309.507494) (xy 405.85508 -309.551917)
			(xy 405.871481 -309.599691) (xy 405.879794 -309.649513) (xy 405.880316 -309.674768) (xy 405.880135 -309.688951)
			(xy 405.877466 -309.717191) (xy 405.874982 -309.731156) (xy 405.872696 -309.743602) (xy 405.880062 -309.767224)
			(xy 405.957532 -309.844694) (xy 405.981154 -309.85206) (xy 405.9936 -309.849774) (xy 406.007566 -309.847301)
			(xy 406.035806 -309.844627) (xy 406.049988 -309.84444) (xy 406.074809 -309.844865) (xy 406.123798 -309.852894)
			(xy 406.170843 -309.868743) (xy 406.214703 -309.891993) (xy 406.254225 -309.922033) (xy 406.288366 -309.958072)
			(xy 406.316228 -309.999158) (xy 406.337075 -310.044211) (xy 406.350359 -310.092043) (xy 406.35573 -310.141394)
			(xy 406.355278 -310.149748) (xy 406.694144 -310.149748) (xy 406.698104 -310.100694) (xy 406.709881 -310.05291)
			(xy 406.729172 -310.007634) (xy 406.755475 -309.966038) (xy 406.78811 -309.929201) (xy 406.826231 -309.898076)
			(xy 406.868852 -309.873469) (xy 406.914868 -309.856017) (xy 406.963087 -309.846173) (xy 407.012262 -309.844192)
			(xy 407.061117 -309.850124) (xy 407.108388 -309.863816) (xy 407.15285 -309.884914) (xy 407.193353 -309.91287)
			(xy 407.228846 -309.946962) (xy 407.258411 -309.986306) (xy 407.281282 -310.029883) (xy 407.296866 -310.076564)
			(xy 407.304761 -310.125141) (xy 407.305256 -310.149748) (xy 407.644104 -310.149748) (xy 407.648064 -310.100694)
			(xy 407.659841 -310.05291) (xy 407.679132 -310.007634) (xy 407.705435 -309.966038) (xy 407.73807 -309.929201)
			(xy 407.776191 -309.898076) (xy 407.818812 -309.873469) (xy 407.864828 -309.856017) (xy 407.913047 -309.846173)
			(xy 407.962222 -309.844192) (xy 408.011077 -309.850124) (xy 408.058348 -309.863816) (xy 408.10281 -309.884914)
			(xy 408.143313 -309.91287) (xy 408.178806 -309.946962) (xy 408.208371 -309.986306) (xy 408.231242 -310.029883)
			(xy 408.246826 -310.076564) (xy 408.254721 -310.125141) (xy 408.255216 -310.149748) (xy 408.594064 -310.149748)
			(xy 408.598024 -310.100694) (xy 408.609801 -310.05291) (xy 408.629092 -310.007634) (xy 408.655395 -309.966038)
			(xy 408.68803 -309.929201) (xy 408.726151 -309.898076) (xy 408.768772 -309.873469) (xy 408.814788 -309.856017)
			(xy 408.863007 -309.846173) (xy 408.912182 -309.844192) (xy 408.961037 -309.850124) (xy 409.008308 -309.863816)
			(xy 409.05277 -309.884914) (xy 409.093273 -309.91287) (xy 409.128766 -309.946962) (xy 409.158331 -309.986306)
			(xy 409.181202 -310.029883) (xy 409.196786 -310.076564) (xy 409.204681 -310.125141) (xy 409.205176 -310.149748)
			(xy 409.544024 -310.149748) (xy 409.547984 -310.100694) (xy 409.559761 -310.05291) (xy 409.579052 -310.007634)
			(xy 409.605355 -309.966038) (xy 409.63799 -309.929201) (xy 409.676111 -309.898076) (xy 409.718732 -309.873469)
			(xy 409.764748 -309.856017) (xy 409.812967 -309.846173) (xy 409.862142 -309.844192) (xy 409.910997 -309.850124)
			(xy 409.958268 -309.863816) (xy 410.00273 -309.884914) (xy 410.043233 -309.91287) (xy 410.078726 -309.946962)
			(xy 410.108291 -309.986306) (xy 410.131162 -310.029883) (xy 410.146746 -310.076564) (xy 410.154641 -310.125141)
			(xy 410.155136 -310.149748) (xy 410.493984 -310.149748) (xy 410.497944 -310.100694) (xy 410.509721 -310.05291)
			(xy 410.529012 -310.007634) (xy 410.555315 -309.966038) (xy 410.58795 -309.929201) (xy 410.626071 -309.898076)
			(xy 410.668692 -309.873469) (xy 410.714708 -309.856017) (xy 410.762927 -309.846173) (xy 410.812102 -309.844192)
			(xy 410.860957 -309.850124) (xy 410.908228 -309.863816) (xy 410.95269 -309.884914) (xy 410.993193 -309.91287)
			(xy 411.028686 -309.946962) (xy 411.058251 -309.986306) (xy 411.081122 -310.029883) (xy 411.096706 -310.076564)
			(xy 411.104601 -310.125141) (xy 411.105096 -310.149748) (xy 411.444198 -310.149748) (xy 411.448158 -310.100694)
			(xy 411.459935 -310.05291) (xy 411.479226 -310.007634) (xy 411.505529 -309.966038) (xy 411.538164 -309.929201)
			(xy 411.576285 -309.898076) (xy 411.618906 -309.873469) (xy 411.664922 -309.856017) (xy 411.713141 -309.846173)
			(xy 411.762316 -309.844192) (xy 411.811171 -309.850124) (xy 411.858442 -309.863816) (xy 411.902904 -309.884914)
			(xy 411.943407 -309.91287) (xy 411.9789 -309.946962) (xy 412.008465 -309.986306) (xy 412.031336 -310.029883)
			(xy 412.04692 -310.076564) (xy 412.054815 -310.125141) (xy 412.05531 -310.149748) (xy 412.394158 -310.149748)
			(xy 412.398118 -310.100694) (xy 412.409895 -310.05291) (xy 412.429186 -310.007634) (xy 412.455489 -309.966038)
			(xy 412.488124 -309.929201) (xy 412.526245 -309.898076) (xy 412.568866 -309.873469) (xy 412.614882 -309.856017)
			(xy 412.663101 -309.846173) (xy 412.712276 -309.844192) (xy 412.761131 -309.850124) (xy 412.808402 -309.863816)
			(xy 412.852864 -309.884914) (xy 412.893367 -309.91287) (xy 412.92886 -309.946962) (xy 412.958425 -309.986306)
			(xy 412.981296 -310.029883) (xy 412.99688 -310.076564) (xy 413.004775 -310.125141) (xy 413.00527 -310.149748)
			(xy 413.344118 -310.149748) (xy 413.348078 -310.100694) (xy 413.359855 -310.05291) (xy 413.379146 -310.007634)
			(xy 413.405449 -309.966038) (xy 413.438084 -309.929201) (xy 413.476205 -309.898076) (xy 413.518826 -309.873469)
			(xy 413.564842 -309.856017) (xy 413.613061 -309.846173) (xy 413.662236 -309.844192) (xy 413.711091 -309.850124)
			(xy 413.758362 -309.863816) (xy 413.802824 -309.884914) (xy 413.843327 -309.91287) (xy 413.87882 -309.946962)
			(xy 413.908385 -309.986306) (xy 413.931256 -310.029883) (xy 413.94684 -310.076564) (xy 413.954735 -310.125141)
			(xy 413.95523 -310.149748) (xy 414.294078 -310.149748) (xy 414.298038 -310.100694) (xy 414.309815 -310.05291)
			(xy 414.329106 -310.007634) (xy 414.355409 -309.966038) (xy 414.388044 -309.929201) (xy 414.426165 -309.898076)
			(xy 414.468786 -309.873469) (xy 414.514802 -309.856017) (xy 414.563021 -309.846173) (xy 414.612196 -309.844192)
			(xy 414.661051 -309.850124) (xy 414.708322 -309.863816) (xy 414.752784 -309.884914) (xy 414.793287 -309.91287)
			(xy 414.82878 -309.946962) (xy 414.858345 -309.986306) (xy 414.881216 -310.029883) (xy 414.8968 -310.076564)
			(xy 414.904695 -310.125141) (xy 414.90519 -310.149748) (xy 415.244038 -310.149748) (xy 415.247998 -310.100694)
			(xy 415.259775 -310.05291) (xy 415.279066 -310.007634) (xy 415.305369 -309.966038) (xy 415.338004 -309.929201)
			(xy 415.376125 -309.898076) (xy 415.418746 -309.873469) (xy 415.464762 -309.856017) (xy 415.512981 -309.846173)
			(xy 415.562156 -309.844192) (xy 415.611011 -309.850124) (xy 415.658282 -309.863816) (xy 415.702744 -309.884914)
			(xy 415.743247 -309.91287) (xy 415.77874 -309.946962) (xy 415.808305 -309.986306) (xy 415.831176 -310.029883)
			(xy 415.84676 -310.076564) (xy 415.854655 -310.125141) (xy 415.85515 -310.149748) (xy 416.193998 -310.149748)
			(xy 416.197958 -310.100694) (xy 416.209735 -310.05291) (xy 416.229026 -310.007634) (xy 416.255329 -309.966038)
			(xy 416.287964 -309.929201) (xy 416.326085 -309.898076) (xy 416.368706 -309.873469) (xy 416.414722 -309.856017)
			(xy 416.462941 -309.846173) (xy 416.512116 -309.844192) (xy 416.560971 -309.850124) (xy 416.608242 -309.863816)
			(xy 416.652704 -309.884914) (xy 416.693207 -309.91287) (xy 416.7287 -309.946962) (xy 416.758265 -309.986306)
			(xy 416.781136 -310.029883) (xy 416.79672 -310.076564) (xy 416.804615 -310.125141) (xy 416.80511 -310.149748)
			(xy 417.144212 -310.149748) (xy 417.148172 -310.100694) (xy 417.159949 -310.05291) (xy 417.17924 -310.007634)
			(xy 417.205543 -309.966038) (xy 417.238178 -309.929201) (xy 417.276299 -309.898076) (xy 417.31892 -309.873469)
			(xy 417.364936 -309.856017) (xy 417.413155 -309.846173) (xy 417.46233 -309.844192) (xy 417.511185 -309.850124)
			(xy 417.558456 -309.863816) (xy 417.602918 -309.884914) (xy 417.643421 -309.91287) (xy 417.678914 -309.946962)
			(xy 417.708479 -309.986306) (xy 417.73135 -310.029883) (xy 417.746934 -310.076564) (xy 417.754829 -310.125141)
			(xy 417.755324 -310.149748) (xy 418.094172 -310.149748) (xy 418.098132 -310.100694) (xy 418.109909 -310.05291)
			(xy 418.1292 -310.007634) (xy 418.155503 -309.966038) (xy 418.188138 -309.929201) (xy 418.226259 -309.898076)
			(xy 418.26888 -309.873469) (xy 418.314896 -309.856017) (xy 418.363115 -309.846173) (xy 418.41229 -309.844192)
			(xy 418.461145 -309.850124) (xy 418.508416 -309.863816) (xy 418.552878 -309.884914) (xy 418.593381 -309.91287)
			(xy 418.628874 -309.946962) (xy 418.658439 -309.986306) (xy 418.68131 -310.029883) (xy 418.696894 -310.076564)
			(xy 418.704789 -310.125141) (xy 418.705284 -310.149748) (xy 419.044132 -310.149748) (xy 419.048092 -310.100694)
			(xy 419.059869 -310.05291) (xy 419.07916 -310.007634) (xy 419.105463 -309.966038) (xy 419.138098 -309.929201)
			(xy 419.176219 -309.898076) (xy 419.21884 -309.873469) (xy 419.264856 -309.856017) (xy 419.313075 -309.846173)
			(xy 419.36225 -309.844192) (xy 419.411105 -309.850124) (xy 419.458376 -309.863816) (xy 419.502838 -309.884914)
			(xy 419.543341 -309.91287) (xy 419.578834 -309.946962) (xy 419.608399 -309.986306) (xy 419.63127 -310.029883)
			(xy 419.646854 -310.076564) (xy 419.654749 -310.125141) (xy 419.655244 -310.149748) (xy 419.994092 -310.149748)
			(xy 419.998052 -310.100694) (xy 420.009829 -310.05291) (xy 420.02912 -310.007634) (xy 420.055423 -309.966038)
			(xy 420.088058 -309.929201) (xy 420.126179 -309.898076) (xy 420.1688 -309.873469) (xy 420.214816 -309.856017)
			(xy 420.263035 -309.846173) (xy 420.31221 -309.844192) (xy 420.361065 -309.850124) (xy 420.408336 -309.863816)
			(xy 420.452798 -309.884914) (xy 420.493301 -309.91287) (xy 420.528794 -309.946962) (xy 420.558359 -309.986306)
			(xy 420.58123 -310.029883) (xy 420.596814 -310.076564) (xy 420.604709 -310.125141) (xy 420.605204 -310.149748)
			(xy 420.944052 -310.149748) (xy 420.948012 -310.100694) (xy 420.959789 -310.05291) (xy 420.97908 -310.007634)
			(xy 421.005383 -309.966038) (xy 421.038018 -309.929201) (xy 421.076139 -309.898076) (xy 421.11876 -309.873469)
			(xy 421.164776 -309.856017) (xy 421.212995 -309.846173) (xy 421.26217 -309.844192) (xy 421.311025 -309.850124)
			(xy 421.358296 -309.863816) (xy 421.402758 -309.884914) (xy 421.443261 -309.91287) (xy 421.478754 -309.946962)
			(xy 421.508319 -309.986306) (xy 421.53119 -310.029883) (xy 421.546774 -310.076564) (xy 421.554669 -310.125141)
			(xy 421.555164 -310.149748) (xy 421.894012 -310.149748) (xy 421.897972 -310.100694) (xy 421.909749 -310.05291)
			(xy 421.92904 -310.007634) (xy 421.955343 -309.966038) (xy 421.987978 -309.929201) (xy 422.026099 -309.898076)
			(xy 422.06872 -309.873469) (xy 422.114736 -309.856017) (xy 422.162955 -309.846173) (xy 422.21213 -309.844192)
			(xy 422.260985 -309.850124) (xy 422.308256 -309.863816) (xy 422.352718 -309.884914) (xy 422.393221 -309.91287)
			(xy 422.428714 -309.946962) (xy 422.458279 -309.986306) (xy 422.48115 -310.029883) (xy 422.496734 -310.076564)
			(xy 422.504629 -310.125141) (xy 422.505124 -310.149748) (xy 422.844226 -310.149748) (xy 422.848186 -310.100694)
			(xy 422.859963 -310.05291) (xy 422.879254 -310.007634) (xy 422.905557 -309.966038) (xy 422.938192 -309.929201)
			(xy 422.976313 -309.898076) (xy 423.018934 -309.873469) (xy 423.06495 -309.856017) (xy 423.113169 -309.846173)
			(xy 423.162344 -309.844192) (xy 423.211199 -309.850124) (xy 423.25847 -309.863816) (xy 423.302932 -309.884914)
			(xy 423.343435 -309.91287) (xy 423.378928 -309.946962) (xy 423.408493 -309.986306) (xy 423.431364 -310.029883)
			(xy 423.446948 -310.076564) (xy 423.454843 -310.125141) (xy 423.455338 -310.149748) (xy 423.794186 -310.149748)
			(xy 423.798146 -310.100694) (xy 423.809923 -310.05291) (xy 423.829214 -310.007634) (xy 423.855517 -309.966038)
			(xy 423.888152 -309.929201) (xy 423.926273 -309.898076) (xy 423.968894 -309.873469) (xy 424.01491 -309.856017)
			(xy 424.063129 -309.846173) (xy 424.112304 -309.844192) (xy 424.161159 -309.850124) (xy 424.20843 -309.863816)
			(xy 424.252892 -309.884914) (xy 424.293395 -309.91287) (xy 424.328888 -309.946962) (xy 424.358453 -309.986306)
			(xy 424.381324 -310.029883) (xy 424.396908 -310.076564) (xy 424.404803 -310.125141) (xy 424.405298 -310.149748)
			(xy 424.744146 -310.149748) (xy 424.748106 -310.100694) (xy 424.759883 -310.05291) (xy 424.779174 -310.007634)
			(xy 424.805477 -309.966038) (xy 424.838112 -309.929201) (xy 424.876233 -309.898076) (xy 424.918854 -309.873469)
			(xy 424.96487 -309.856017) (xy 425.013089 -309.846173) (xy 425.062264 -309.844192) (xy 425.111119 -309.850124)
			(xy 425.15839 -309.863816) (xy 425.202852 -309.884914) (xy 425.243355 -309.91287) (xy 425.278848 -309.946962)
			(xy 425.308413 -309.986306) (xy 425.331284 -310.029883) (xy 425.346868 -310.076564) (xy 425.354763 -310.125141)
			(xy 425.355258 -310.149748) (xy 425.694106 -310.149748) (xy 425.698066 -310.100694) (xy 425.709843 -310.05291)
			(xy 425.729134 -310.007634) (xy 425.755437 -309.966038) (xy 425.788072 -309.929201) (xy 425.826193 -309.898076)
			(xy 425.868814 -309.873469) (xy 425.91483 -309.856017) (xy 425.963049 -309.846173) (xy 426.012224 -309.844192)
			(xy 426.061079 -309.850124) (xy 426.10835 -309.863816) (xy 426.152812 -309.884914) (xy 426.193315 -309.91287)
			(xy 426.228808 -309.946962) (xy 426.258373 -309.986306) (xy 426.281244 -310.029883) (xy 426.296828 -310.076564)
			(xy 426.304723 -310.125141) (xy 426.305218 -310.149748) (xy 426.644066 -310.149748) (xy 426.648026 -310.100694)
			(xy 426.659803 -310.05291) (xy 426.679094 -310.007634) (xy 426.705397 -309.966038) (xy 426.738032 -309.929201)
			(xy 426.776153 -309.898076) (xy 426.818774 -309.873469) (xy 426.86479 -309.856017) (xy 426.913009 -309.846173)
			(xy 426.962184 -309.844192) (xy 427.011039 -309.850124) (xy 427.05831 -309.863816) (xy 427.102772 -309.884914)
			(xy 427.143275 -309.91287) (xy 427.178768 -309.946962) (xy 427.208333 -309.986306) (xy 427.231204 -310.029883)
			(xy 427.246788 -310.076564) (xy 427.254683 -310.125141) (xy 427.255178 -310.149748) (xy 427.594026 -310.149748)
			(xy 427.597986 -310.100694) (xy 427.609763 -310.05291) (xy 427.629054 -310.007634) (xy 427.655357 -309.966038)
			(xy 427.687992 -309.929201) (xy 427.726113 -309.898076) (xy 427.768734 -309.873469) (xy 427.81475 -309.856017)
			(xy 427.862969 -309.846173) (xy 427.912144 -309.844192) (xy 427.960999 -309.850124) (xy 428.00827 -309.863816)
			(xy 428.052732 -309.884914) (xy 428.093235 -309.91287) (xy 428.128728 -309.946962) (xy 428.158293 -309.986306)
			(xy 428.181164 -310.029883) (xy 428.196748 -310.076564) (xy 428.204643 -310.125141) (xy 428.205138 -310.149748)
			(xy 428.543986 -310.149748) (xy 428.547946 -310.100694) (xy 428.559723 -310.05291) (xy 428.579014 -310.007634)
			(xy 428.605317 -309.966038) (xy 428.637952 -309.929201) (xy 428.676073 -309.898076) (xy 428.718694 -309.873469)
			(xy 428.76471 -309.856017) (xy 428.812929 -309.846173) (xy 428.862104 -309.844192) (xy 428.910959 -309.850124)
			(xy 428.95823 -309.863816) (xy 429.002692 -309.884914) (xy 429.043195 -309.91287) (xy 429.078688 -309.946962)
			(xy 429.108253 -309.986306) (xy 429.131124 -310.029883) (xy 429.146708 -310.076564) (xy 429.154603 -310.125141)
			(xy 429.155098 -310.149748) (xy 429.154603 -310.174355) (xy 429.154424 -310.175456) (xy 429.473356 -310.175456)
			(xy 429.473356 -310.12404) (xy 429.481399 -310.073258) (xy 429.497287 -310.024359) (xy 429.52063 -309.978547)
			(xy 429.550851 -309.936951) (xy 429.587207 -309.900595) (xy 429.628803 -309.870374) (xy 429.674615 -309.847031)
			(xy 429.723514 -309.831143) (xy 429.774296 -309.8231) (xy 429.825712 -309.8231) (xy 429.876494 -309.831143)
			(xy 429.925393 -309.847031) (xy 429.971205 -309.870374) (xy 430.012801 -309.900595) (xy 430.049157 -309.936951)
			(xy 430.079378 -309.978547) (xy 430.102721 -310.024359) (xy 430.118609 -310.073258) (xy 430.126652 -310.12404)
			(xy 430.127156 -310.149748) (xy 430.126652 -310.175456) (xy 430.423316 -310.175456) (xy 430.423316 -310.12404)
			(xy 430.431359 -310.073258) (xy 430.447247 -310.024359) (xy 430.47059 -309.978547) (xy 430.500811 -309.936951)
			(xy 430.537167 -309.900595) (xy 430.578763 -309.870374) (xy 430.624575 -309.847031) (xy 430.673474 -309.831143)
			(xy 430.724256 -309.8231) (xy 430.775672 -309.8231) (xy 430.826454 -309.831143) (xy 430.875353 -309.847031)
			(xy 430.921165 -309.870374) (xy 430.962761 -309.900595) (xy 430.999117 -309.936951) (xy 431.029338 -309.978547)
			(xy 431.052681 -310.024359) (xy 431.068569 -310.073258) (xy 431.076612 -310.12404) (xy 431.077116 -310.149748)
			(xy 431.394374 -310.149748) (xy 431.398334 -310.100694) (xy 431.410111 -310.05291) (xy 431.429402 -310.007634)
			(xy 431.455705 -309.966038) (xy 431.48834 -309.929201) (xy 431.526461 -309.898076) (xy 431.569082 -309.873469)
			(xy 431.615098 -309.856017) (xy 431.663317 -309.846173) (xy 431.712492 -309.844192) (xy 431.761347 -309.850124)
			(xy 431.808618 -309.863816) (xy 431.85308 -309.884914) (xy 431.893583 -309.91287) (xy 431.929076 -309.946962)
			(xy 431.958641 -309.986306) (xy 431.981512 -310.029883) (xy 431.997096 -310.076564) (xy 432.004991 -310.125141)
			(xy 432.005486 -310.149748) (xy 432.004991 -310.174355) (xy 431.997096 -310.222932) (xy 431.981512 -310.269613)
			(xy 431.958641 -310.31319) (xy 431.929076 -310.352534) (xy 431.893583 -310.386626) (xy 431.85308 -310.414582)
			(xy 431.808618 -310.43568) (xy 431.761347 -310.449372) (xy 431.712492 -310.455304) (xy 431.663317 -310.453323)
			(xy 431.615098 -310.443479) (xy 431.569082 -310.426027) (xy 431.526461 -310.40142) (xy 431.48834 -310.370295)
			(xy 431.455705 -310.333458) (xy 431.429402 -310.291862) (xy 431.410111 -310.246586) (xy 431.398334 -310.198802)
			(xy 431.394374 -310.149748) (xy 431.077116 -310.149748) (xy 431.076612 -310.175456) (xy 431.068569 -310.226238)
			(xy 431.052681 -310.275137) (xy 431.029338 -310.320949) (xy 430.999117 -310.362545) (xy 430.962761 -310.398901)
			(xy 430.921165 -310.429122) (xy 430.875353 -310.452465) (xy 430.826454 -310.468353) (xy 430.775672 -310.476396)
			(xy 430.724256 -310.476396) (xy 430.673474 -310.468353) (xy 430.624575 -310.452465) (xy 430.578763 -310.429122)
			(xy 430.537167 -310.398901) (xy 430.500811 -310.362545) (xy 430.47059 -310.320949) (xy 430.447247 -310.275137)
			(xy 430.431359 -310.226238) (xy 430.423316 -310.175456) (xy 430.126652 -310.175456) (xy 430.118609 -310.226238)
			(xy 430.102721 -310.275137) (xy 430.079378 -310.320949) (xy 430.049157 -310.362545) (xy 430.012801 -310.398901)
			(xy 429.971205 -310.429122) (xy 429.925393 -310.452465) (xy 429.876494 -310.468353) (xy 429.825712 -310.476396)
			(xy 429.774296 -310.476396) (xy 429.723514 -310.468353) (xy 429.674615 -310.452465) (xy 429.628803 -310.429122)
			(xy 429.587207 -310.398901) (xy 429.550851 -310.362545) (xy 429.52063 -310.320949) (xy 429.497287 -310.275137)
			(xy 429.481399 -310.226238) (xy 429.473356 -310.175456) (xy 429.154424 -310.175456) (xy 429.146708 -310.222932)
			(xy 429.131124 -310.269613) (xy 429.108253 -310.31319) (xy 429.078688 -310.352534) (xy 429.043195 -310.386626)
			(xy 429.002692 -310.414582) (xy 428.95823 -310.43568) (xy 428.910959 -310.449372) (xy 428.862104 -310.455304)
			(xy 428.812929 -310.453323) (xy 428.76471 -310.443479) (xy 428.718694 -310.426027) (xy 428.676073 -310.40142)
			(xy 428.637952 -310.370295) (xy 428.605317 -310.333458) (xy 428.579014 -310.291862) (xy 428.559723 -310.246586)
			(xy 428.547946 -310.198802) (xy 428.543986 -310.149748) (xy 428.205138 -310.149748) (xy 428.204643 -310.174355)
			(xy 428.196748 -310.222932) (xy 428.181164 -310.269613) (xy 428.158293 -310.31319) (xy 428.128728 -310.352534)
			(xy 428.093235 -310.386626) (xy 428.052732 -310.414582) (xy 428.00827 -310.43568) (xy 427.960999 -310.449372)
			(xy 427.912144 -310.455304) (xy 427.862969 -310.453323) (xy 427.81475 -310.443479) (xy 427.768734 -310.426027)
			(xy 427.726113 -310.40142) (xy 427.687992 -310.370295) (xy 427.655357 -310.333458) (xy 427.629054 -310.291862)
			(xy 427.609763 -310.246586) (xy 427.597986 -310.198802) (xy 427.594026 -310.149748) (xy 427.255178 -310.149748)
			(xy 427.254683 -310.174355) (xy 427.246788 -310.222932) (xy 427.231204 -310.269613) (xy 427.208333 -310.31319)
			(xy 427.178768 -310.352534) (xy 427.143275 -310.386626) (xy 427.102772 -310.414582) (xy 427.05831 -310.43568)
			(xy 427.011039 -310.449372) (xy 426.962184 -310.455304) (xy 426.913009 -310.453323) (xy 426.86479 -310.443479)
			(xy 426.818774 -310.426027) (xy 426.776153 -310.40142) (xy 426.738032 -310.370295) (xy 426.705397 -310.333458)
			(xy 426.679094 -310.291862) (xy 426.659803 -310.246586) (xy 426.648026 -310.198802) (xy 426.644066 -310.149748)
			(xy 426.305218 -310.149748) (xy 426.304723 -310.174355) (xy 426.296828 -310.222932) (xy 426.281244 -310.269613)
			(xy 426.258373 -310.31319) (xy 426.228808 -310.352534) (xy 426.193315 -310.386626) (xy 426.152812 -310.414582)
			(xy 426.10835 -310.43568) (xy 426.061079 -310.449372) (xy 426.012224 -310.455304) (xy 425.963049 -310.453323)
			(xy 425.91483 -310.443479) (xy 425.868814 -310.426027) (xy 425.826193 -310.40142) (xy 425.788072 -310.370295)
			(xy 425.755437 -310.333458) (xy 425.729134 -310.291862) (xy 425.709843 -310.246586) (xy 425.698066 -310.198802)
			(xy 425.694106 -310.149748) (xy 425.355258 -310.149748) (xy 425.354763 -310.174355) (xy 425.346868 -310.222932)
			(xy 425.331284 -310.269613) (xy 425.308413 -310.31319) (xy 425.278848 -310.352534) (xy 425.243355 -310.386626)
			(xy 425.202852 -310.414582) (xy 425.15839 -310.43568) (xy 425.111119 -310.449372) (xy 425.062264 -310.455304)
			(xy 425.013089 -310.453323) (xy 424.96487 -310.443479) (xy 424.918854 -310.426027) (xy 424.876233 -310.40142)
			(xy 424.838112 -310.370295) (xy 424.805477 -310.333458) (xy 424.779174 -310.291862) (xy 424.759883 -310.246586)
			(xy 424.748106 -310.198802) (xy 424.744146 -310.149748) (xy 424.405298 -310.149748) (xy 424.404803 -310.174355)
			(xy 424.396908 -310.222932) (xy 424.381324 -310.269613) (xy 424.358453 -310.31319) (xy 424.328888 -310.352534)
			(xy 424.293395 -310.386626) (xy 424.252892 -310.414582) (xy 424.20843 -310.43568) (xy 424.161159 -310.449372)
			(xy 424.112304 -310.455304) (xy 424.063129 -310.453323) (xy 424.01491 -310.443479) (xy 423.968894 -310.426027)
			(xy 423.926273 -310.40142) (xy 423.888152 -310.370295) (xy 423.855517 -310.333458) (xy 423.829214 -310.291862)
			(xy 423.809923 -310.246586) (xy 423.798146 -310.198802) (xy 423.794186 -310.149748) (xy 423.455338 -310.149748)
			(xy 423.454843 -310.174355) (xy 423.446948 -310.222932) (xy 423.431364 -310.269613) (xy 423.408493 -310.31319)
			(xy 423.378928 -310.352534) (xy 423.343435 -310.386626) (xy 423.302932 -310.414582) (xy 423.25847 -310.43568)
			(xy 423.211199 -310.449372) (xy 423.162344 -310.455304) (xy 423.113169 -310.453323) (xy 423.06495 -310.443479)
			(xy 423.018934 -310.426027) (xy 422.976313 -310.40142) (xy 422.938192 -310.370295) (xy 422.905557 -310.333458)
			(xy 422.879254 -310.291862) (xy 422.859963 -310.246586) (xy 422.848186 -310.198802) (xy 422.844226 -310.149748)
			(xy 422.505124 -310.149748) (xy 422.504629 -310.174355) (xy 422.496734 -310.222932) (xy 422.48115 -310.269613)
			(xy 422.458279 -310.31319) (xy 422.428714 -310.352534) (xy 422.393221 -310.386626) (xy 422.352718 -310.414582)
			(xy 422.308256 -310.43568) (xy 422.260985 -310.449372) (xy 422.21213 -310.455304) (xy 422.162955 -310.453323)
			(xy 422.114736 -310.443479) (xy 422.06872 -310.426027) (xy 422.026099 -310.40142) (xy 421.987978 -310.370295)
			(xy 421.955343 -310.333458) (xy 421.92904 -310.291862) (xy 421.909749 -310.246586) (xy 421.897972 -310.198802)
			(xy 421.894012 -310.149748) (xy 421.555164 -310.149748) (xy 421.554669 -310.174355) (xy 421.546774 -310.222932)
			(xy 421.53119 -310.269613) (xy 421.508319 -310.31319) (xy 421.478754 -310.352534) (xy 421.443261 -310.386626)
			(xy 421.402758 -310.414582) (xy 421.358296 -310.43568) (xy 421.311025 -310.449372) (xy 421.26217 -310.455304)
			(xy 421.212995 -310.453323) (xy 421.164776 -310.443479) (xy 421.11876 -310.426027) (xy 421.076139 -310.40142)
			(xy 421.038018 -310.370295) (xy 421.005383 -310.333458) (xy 420.97908 -310.291862) (xy 420.959789 -310.246586)
			(xy 420.948012 -310.198802) (xy 420.944052 -310.149748) (xy 420.605204 -310.149748) (xy 420.604709 -310.174355)
			(xy 420.596814 -310.222932) (xy 420.58123 -310.269613) (xy 420.558359 -310.31319) (xy 420.528794 -310.352534)
			(xy 420.493301 -310.386626) (xy 420.452798 -310.414582) (xy 420.408336 -310.43568) (xy 420.361065 -310.449372)
			(xy 420.31221 -310.455304) (xy 420.263035 -310.453323) (xy 420.214816 -310.443479) (xy 420.1688 -310.426027)
			(xy 420.126179 -310.40142) (xy 420.088058 -310.370295) (xy 420.055423 -310.333458) (xy 420.02912 -310.291862)
			(xy 420.009829 -310.246586) (xy 419.998052 -310.198802) (xy 419.994092 -310.149748) (xy 419.655244 -310.149748)
			(xy 419.654749 -310.174355) (xy 419.646854 -310.222932) (xy 419.63127 -310.269613) (xy 419.608399 -310.31319)
			(xy 419.578834 -310.352534) (xy 419.543341 -310.386626) (xy 419.502838 -310.414582) (xy 419.458376 -310.43568)
			(xy 419.411105 -310.449372) (xy 419.36225 -310.455304) (xy 419.313075 -310.453323) (xy 419.264856 -310.443479)
			(xy 419.21884 -310.426027) (xy 419.176219 -310.40142) (xy 419.138098 -310.370295) (xy 419.105463 -310.333458)
			(xy 419.07916 -310.291862) (xy 419.059869 -310.246586) (xy 419.048092 -310.198802) (xy 419.044132 -310.149748)
			(xy 418.705284 -310.149748) (xy 418.704789 -310.174355) (xy 418.696894 -310.222932) (xy 418.68131 -310.269613)
			(xy 418.658439 -310.31319) (xy 418.628874 -310.352534) (xy 418.593381 -310.386626) (xy 418.552878 -310.414582)
			(xy 418.508416 -310.43568) (xy 418.461145 -310.449372) (xy 418.41229 -310.455304) (xy 418.363115 -310.453323)
			(xy 418.314896 -310.443479) (xy 418.26888 -310.426027) (xy 418.226259 -310.40142) (xy 418.188138 -310.370295)
			(xy 418.155503 -310.333458) (xy 418.1292 -310.291862) (xy 418.109909 -310.246586) (xy 418.098132 -310.198802)
			(xy 418.094172 -310.149748) (xy 417.755324 -310.149748) (xy 417.754829 -310.174355) (xy 417.746934 -310.222932)
			(xy 417.73135 -310.269613) (xy 417.708479 -310.31319) (xy 417.678914 -310.352534) (xy 417.643421 -310.386626)
			(xy 417.602918 -310.414582) (xy 417.558456 -310.43568) (xy 417.511185 -310.449372) (xy 417.46233 -310.455304)
			(xy 417.413155 -310.453323) (xy 417.364936 -310.443479) (xy 417.31892 -310.426027) (xy 417.276299 -310.40142)
			(xy 417.238178 -310.370295) (xy 417.205543 -310.333458) (xy 417.17924 -310.291862) (xy 417.159949 -310.246586)
			(xy 417.148172 -310.198802) (xy 417.144212 -310.149748) (xy 416.80511 -310.149748) (xy 416.804615 -310.174355)
			(xy 416.79672 -310.222932) (xy 416.781136 -310.269613) (xy 416.758265 -310.31319) (xy 416.7287 -310.352534)
			(xy 416.693207 -310.386626) (xy 416.652704 -310.414582) (xy 416.608242 -310.43568) (xy 416.560971 -310.449372)
			(xy 416.512116 -310.455304) (xy 416.462941 -310.453323) (xy 416.414722 -310.443479) (xy 416.368706 -310.426027)
			(xy 416.326085 -310.40142) (xy 416.287964 -310.370295) (xy 416.255329 -310.333458) (xy 416.229026 -310.291862)
			(xy 416.209735 -310.246586) (xy 416.197958 -310.198802) (xy 416.193998 -310.149748) (xy 415.85515 -310.149748)
			(xy 415.854655 -310.174355) (xy 415.84676 -310.222932) (xy 415.831176 -310.269613) (xy 415.808305 -310.31319)
			(xy 415.77874 -310.352534) (xy 415.743247 -310.386626) (xy 415.702744 -310.414582) (xy 415.658282 -310.43568)
			(xy 415.611011 -310.449372) (xy 415.562156 -310.455304) (xy 415.512981 -310.453323) (xy 415.464762 -310.443479)
			(xy 415.418746 -310.426027) (xy 415.376125 -310.40142) (xy 415.338004 -310.370295) (xy 415.305369 -310.333458)
			(xy 415.279066 -310.291862) (xy 415.259775 -310.246586) (xy 415.247998 -310.198802) (xy 415.244038 -310.149748)
			(xy 414.90519 -310.149748) (xy 414.904695 -310.174355) (xy 414.8968 -310.222932) (xy 414.881216 -310.269613)
			(xy 414.858345 -310.31319) (xy 414.82878 -310.352534) (xy 414.793287 -310.386626) (xy 414.752784 -310.414582)
			(xy 414.708322 -310.43568) (xy 414.661051 -310.449372) (xy 414.612196 -310.455304) (xy 414.563021 -310.453323)
			(xy 414.514802 -310.443479) (xy 414.468786 -310.426027) (xy 414.426165 -310.40142) (xy 414.388044 -310.370295)
			(xy 414.355409 -310.333458) (xy 414.329106 -310.291862) (xy 414.309815 -310.246586) (xy 414.298038 -310.198802)
			(xy 414.294078 -310.149748) (xy 413.95523 -310.149748) (xy 413.954735 -310.174355) (xy 413.94684 -310.222932)
			(xy 413.931256 -310.269613) (xy 413.908385 -310.31319) (xy 413.87882 -310.352534) (xy 413.843327 -310.386626)
			(xy 413.802824 -310.414582) (xy 413.758362 -310.43568) (xy 413.711091 -310.449372) (xy 413.662236 -310.455304)
			(xy 413.613061 -310.453323) (xy 413.564842 -310.443479) (xy 413.518826 -310.426027) (xy 413.476205 -310.40142)
			(xy 413.438084 -310.370295) (xy 413.405449 -310.333458) (xy 413.379146 -310.291862) (xy 413.359855 -310.246586)
			(xy 413.348078 -310.198802) (xy 413.344118 -310.149748) (xy 413.00527 -310.149748) (xy 413.004775 -310.174355)
			(xy 412.99688 -310.222932) (xy 412.981296 -310.269613) (xy 412.958425 -310.31319) (xy 412.92886 -310.352534)
			(xy 412.893367 -310.386626) (xy 412.852864 -310.414582) (xy 412.808402 -310.43568) (xy 412.761131 -310.449372)
			(xy 412.712276 -310.455304) (xy 412.663101 -310.453323) (xy 412.614882 -310.443479) (xy 412.568866 -310.426027)
			(xy 412.526245 -310.40142) (xy 412.488124 -310.370295) (xy 412.455489 -310.333458) (xy 412.429186 -310.291862)
			(xy 412.409895 -310.246586) (xy 412.398118 -310.198802) (xy 412.394158 -310.149748) (xy 412.05531 -310.149748)
			(xy 412.054815 -310.174355) (xy 412.04692 -310.222932) (xy 412.031336 -310.269613) (xy 412.008465 -310.31319)
			(xy 411.9789 -310.352534) (xy 411.943407 -310.386626) (xy 411.902904 -310.414582) (xy 411.858442 -310.43568)
			(xy 411.811171 -310.449372) (xy 411.762316 -310.455304) (xy 411.713141 -310.453323) (xy 411.664922 -310.443479)
			(xy 411.618906 -310.426027) (xy 411.576285 -310.40142) (xy 411.538164 -310.370295) (xy 411.505529 -310.333458)
			(xy 411.479226 -310.291862) (xy 411.459935 -310.246586) (xy 411.448158 -310.198802) (xy 411.444198 -310.149748)
			(xy 411.105096 -310.149748) (xy 411.104601 -310.174355) (xy 411.096706 -310.222932) (xy 411.081122 -310.269613)
			(xy 411.058251 -310.31319) (xy 411.028686 -310.352534) (xy 410.993193 -310.386626) (xy 410.95269 -310.414582)
			(xy 410.908228 -310.43568) (xy 410.860957 -310.449372) (xy 410.812102 -310.455304) (xy 410.762927 -310.453323)
			(xy 410.714708 -310.443479) (xy 410.668692 -310.426027) (xy 410.626071 -310.40142) (xy 410.58795 -310.370295)
			(xy 410.555315 -310.333458) (xy 410.529012 -310.291862) (xy 410.509721 -310.246586) (xy 410.497944 -310.198802)
			(xy 410.493984 -310.149748) (xy 410.155136 -310.149748) (xy 410.154641 -310.174355) (xy 410.146746 -310.222932)
			(xy 410.131162 -310.269613) (xy 410.108291 -310.31319) (xy 410.078726 -310.352534) (xy 410.043233 -310.386626)
			(xy 410.00273 -310.414582) (xy 409.958268 -310.43568) (xy 409.910997 -310.449372) (xy 409.862142 -310.455304)
			(xy 409.812967 -310.453323) (xy 409.764748 -310.443479) (xy 409.718732 -310.426027) (xy 409.676111 -310.40142)
			(xy 409.63799 -310.370295) (xy 409.605355 -310.333458) (xy 409.579052 -310.291862) (xy 409.559761 -310.246586)
			(xy 409.547984 -310.198802) (xy 409.544024 -310.149748) (xy 409.205176 -310.149748) (xy 409.204681 -310.174355)
			(xy 409.196786 -310.222932) (xy 409.181202 -310.269613) (xy 409.158331 -310.31319) (xy 409.128766 -310.352534)
			(xy 409.093273 -310.386626) (xy 409.05277 -310.414582) (xy 409.008308 -310.43568) (xy 408.961037 -310.449372)
			(xy 408.912182 -310.455304) (xy 408.863007 -310.453323) (xy 408.814788 -310.443479) (xy 408.768772 -310.426027)
			(xy 408.726151 -310.40142) (xy 408.68803 -310.370295) (xy 408.655395 -310.333458) (xy 408.629092 -310.291862)
			(xy 408.609801 -310.246586) (xy 408.598024 -310.198802) (xy 408.594064 -310.149748) (xy 408.255216 -310.149748)
			(xy 408.254721 -310.174355) (xy 408.246826 -310.222932) (xy 408.231242 -310.269613) (xy 408.208371 -310.31319)
			(xy 408.178806 -310.352534) (xy 408.143313 -310.386626) (xy 408.10281 -310.414582) (xy 408.058348 -310.43568)
			(xy 408.011077 -310.449372) (xy 407.962222 -310.455304) (xy 407.913047 -310.453323) (xy 407.864828 -310.443479)
			(xy 407.818812 -310.426027) (xy 407.776191 -310.40142) (xy 407.73807 -310.370295) (xy 407.705435 -310.333458)
			(xy 407.679132 -310.291862) (xy 407.659841 -310.246586) (xy 407.648064 -310.198802) (xy 407.644104 -310.149748)
			(xy 407.305256 -310.149748) (xy 407.304761 -310.174355) (xy 407.296866 -310.222932) (xy 407.281282 -310.269613)
			(xy 407.258411 -310.31319) (xy 407.228846 -310.352534) (xy 407.193353 -310.386626) (xy 407.15285 -310.414582)
			(xy 407.108388 -310.43568) (xy 407.061117 -310.449372) (xy 407.012262 -310.455304) (xy 406.963087 -310.453323)
			(xy 406.914868 -310.443479) (xy 406.868852 -310.426027) (xy 406.826231 -310.40142) (xy 406.78811 -310.370295)
			(xy 406.755475 -310.333458) (xy 406.729172 -310.291862) (xy 406.709881 -310.246586) (xy 406.698104 -310.198802)
			(xy 406.694144 -310.149748) (xy 406.355278 -310.149748) (xy 406.353047 -310.190964) (xy 406.342379 -310.239447)
			(xy 406.324009 -310.285565) (xy 406.298419 -310.328104) (xy 406.266285 -310.365942) (xy 406.228453 -310.398084)
			(xy 406.185919 -310.423682) (xy 406.139804 -310.442061) (xy 406.091324 -310.452738) (xy 406.041754 -310.455432)
			(xy 405.992402 -310.45007) (xy 405.944568 -310.436796) (xy 405.899511 -310.415957) (xy 405.858418 -310.388104)
			(xy 405.822374 -310.35397) (xy 405.792326 -310.314454) (xy 405.769066 -310.270598) (xy 405.753209 -310.223556)
			(xy 405.74517 -310.174569) (xy 405.74468 -310.149748) (xy 405.744864 -310.135565) (xy 405.747531 -310.107325)
			(xy 405.750014 -310.09336) (xy 405.7523 -310.080914) (xy 405.744934 -310.057292) (xy 405.667464 -309.979822)
			(xy 405.643842 -309.972456) (xy 405.631396 -309.974742) (xy 405.617429 -309.977215) (xy 405.58919 -309.979889)
			(xy 405.575008 -309.980076) (xy 405.560825 -309.979899) (xy 405.532585 -309.977227) (xy 405.51862 -309.974742)
			(xy 405.506174 -309.972456) (xy 405.482552 -309.979822) (xy 405.405082 -310.057292) (xy 405.397716 -310.080914)
			(xy 405.400002 -310.09336) (xy 405.402483 -310.107325) (xy 405.405152 -310.135565) (xy 405.405336 -310.149748)
			(xy 405.404814 -310.175003) (xy 405.396501 -310.224825) (xy 405.3801 -310.272599) (xy 405.356059 -310.317022)
			(xy 405.325035 -310.356882) (xy 405.287873 -310.391092) (xy 405.245587 -310.418718) (xy 405.199331 -310.439008)
			(xy 405.150366 -310.451408) (xy 405.100028 -310.455579) (xy 405.04969 -310.451408) (xy 405.000725 -310.439008)
			(xy 404.954469 -310.418718) (xy 404.912183 -310.391092) (xy 404.875021 -310.356882) (xy 404.843997 -310.317022)
			(xy 404.819956 -310.272599) (xy 404.803555 -310.224825) (xy 404.795242 -310.175003) (xy 404.79472 -310.149748)
			(xy 404.794903 -310.135565) (xy 404.797571 -310.107325) (xy 404.800054 -310.09336) (xy 404.80234 -310.080914)
			(xy 404.794974 -310.057038) (xy 404.717758 -309.979822) (xy 404.693628 -309.972456) (xy 404.681436 -309.974742)
			(xy 404.667408 -309.977233) (xy 404.63904 -309.979901) (xy 404.624794 -309.980076) (xy 404.610611 -309.979901)
			(xy 404.582371 -309.977228) (xy 404.568406 -309.974742) (xy 404.55596 -309.972456) (xy 404.532338 -309.979822)
			(xy 404.454868 -310.057292) (xy 404.447502 -310.080914) (xy 404.449788 -310.09336) (xy 404.452269 -310.107325)
			(xy 404.454938 -310.135565) (xy 404.455122 -310.149748) (xy 404.45457 -310.174564) (xy 404.446533 -310.223542)
			(xy 404.430678 -310.270574) (xy 404.407424 -310.314422) (xy 404.377382 -310.35393) (xy 404.341344 -310.388057)
			(xy 404.300259 -310.415905) (xy 404.255211 -310.43674) (xy 404.207386 -310.450012) (xy 404.158044 -310.455372)
			(xy 404.108484 -310.452679) (xy 404.060013 -310.442004) (xy 404.013907 -310.423628) (xy 403.971382 -310.398035)
			(xy 403.933557 -310.365899) (xy 403.901429 -310.328068) (xy 403.875845 -310.285537) (xy 403.857478 -310.239428)
			(xy 403.846813 -310.190955) (xy 403.84413 -310.141394) (xy 403.8495 -310.092053) (xy 403.862782 -310.04423)
			(xy 403.883625 -309.999186) (xy 403.911481 -309.958108) (xy 403.945616 -309.922077) (xy 403.98513 -309.892043)
			(xy 404.028983 -309.868797) (xy 404.076018 -309.852952) (xy 404.124998 -309.844925) (xy 404.149814 -309.84444)
			(xy 404.163997 -309.844614) (xy 404.192237 -309.847288) (xy 404.206202 -309.849774) (xy 404.218648 -309.85206)
			(xy 404.24227 -309.844694) (xy 404.31974 -309.767224) (xy 404.327106 -309.743602) (xy 404.32482 -309.731156)
			(xy 404.322342 -309.71719) (xy 404.319671 -309.688951) (xy 404.319486 -309.674768) (xy 404.319658 -309.660585)
			(xy 404.322333 -309.632345) (xy 404.32482 -309.61838) (xy 404.327106 -309.605934) (xy 404.31974 -309.582312)
			(xy 404.24227 -309.504842) (xy 404.218648 -309.497476) (xy 404.206202 -309.499762) (xy 404.192235 -309.502234)
			(xy 404.163996 -309.504909) (xy 404.149814 -309.505096) (xy 404.125821 -309.504649) (xy 404.078424 -309.497144)
			(xy 404.032786 -309.482316) (xy 403.990029 -309.460532) (xy 403.951207 -309.432326) (xy 403.917275 -309.398395)
			(xy 403.889069 -309.359573) (xy 403.867284 -309.316816) (xy 403.852457 -309.271177) (xy 403.844951 -309.223781)
			(xy 403.844506 -309.199788) (xy 403.844681 -309.185605) (xy 403.847354 -309.157365) (xy 403.84984 -309.1434)
			(xy 403.852126 -309.130954) (xy 403.84476 -309.107332) (xy 403.76729 -309.029862) (xy 403.743668 -309.022496)
			(xy 403.731222 -309.024782) (xy 403.717257 -309.027265) (xy 403.689017 -309.029933) (xy 403.674834 -309.030116)
			(xy 403.65001 -309.029659) (xy 403.601014 -309.021632) (xy 403.553963 -309.005784) (xy 403.510095 -308.982532)
			(xy 403.470568 -308.95249) (xy 403.436421 -308.916448) (xy 403.408555 -308.875356) (xy 403.387705 -308.830298)
			(xy 403.374419 -308.78246) (xy 403.369048 -308.733103) (xy 403.030015 -308.733103) (xy 403.029687 -308.749415)
			(xy 403.021792 -308.797992) (xy 403.006208 -308.844673) (xy 402.983337 -308.88825) (xy 402.953772 -308.927594)
			(xy 402.918279 -308.961686) (xy 402.877776 -308.989642) (xy 402.833314 -309.01074) (xy 402.786043 -309.024432)
			(xy 402.737188 -309.030364) (xy 402.688013 -309.028383) (xy 402.639794 -309.018539) (xy 402.593778 -309.001087)
			(xy 402.551157 -308.97648) (xy 402.513036 -308.945355) (xy 402.480401 -308.908518) (xy 402.454098 -308.866922)
			(xy 402.434807 -308.821646) (xy 402.42303 -308.773862) (xy 402.41907 -308.724808) (xy 402.080222 -308.724808)
			(xy 402.079727 -308.749415) (xy 402.071832 -308.797992) (xy 402.056248 -308.844673) (xy 402.033377 -308.88825)
			(xy 402.003812 -308.927594) (xy 401.968319 -308.961686) (xy 401.927816 -308.989642) (xy 401.883354 -309.01074)
			(xy 401.836083 -309.024432) (xy 401.787228 -309.030364) (xy 401.738053 -309.028383) (xy 401.689834 -309.018539)
			(xy 401.643818 -309.001087) (xy 401.601197 -308.97648) (xy 401.563076 -308.945355) (xy 401.530441 -308.908518)
			(xy 401.504138 -308.866922) (xy 401.484847 -308.821646) (xy 401.47307 -308.773862) (xy 401.46911 -308.724808)
			(xy 401.130262 -308.724808) (xy 401.129767 -308.749415) (xy 401.121872 -308.797992) (xy 401.106288 -308.844673)
			(xy 401.083417 -308.88825) (xy 401.053852 -308.927594) (xy 401.018359 -308.961686) (xy 400.977856 -308.989642)
			(xy 400.933394 -309.01074) (xy 400.886123 -309.024432) (xy 400.837268 -309.030364) (xy 400.788093 -309.028383)
			(xy 400.739874 -309.018539) (xy 400.693858 -309.001087) (xy 400.651237 -308.97648) (xy 400.613116 -308.945355)
			(xy 400.580481 -308.908518) (xy 400.554178 -308.866922) (xy 400.534887 -308.821646) (xy 400.52311 -308.773862)
			(xy 400.51915 -308.724808) (xy 400.180302 -308.724808) (xy 400.179807 -308.749415) (xy 400.171912 -308.797992)
			(xy 400.156328 -308.844673) (xy 400.133457 -308.88825) (xy 400.103892 -308.927594) (xy 400.068399 -308.961686)
			(xy 400.027896 -308.989642) (xy 399.983434 -309.01074) (xy 399.936163 -309.024432) (xy 399.887308 -309.030364)
			(xy 399.838133 -309.028383) (xy 399.789914 -309.018539) (xy 399.743898 -309.001087) (xy 399.701277 -308.97648)
			(xy 399.663156 -308.945355) (xy 399.630521 -308.908518) (xy 399.604218 -308.866922) (xy 399.584927 -308.821646)
			(xy 399.57315 -308.773862) (xy 399.56919 -308.724808) (xy 399.230342 -308.724808) (xy 399.229847 -308.749415)
			(xy 399.221952 -308.797992) (xy 399.206368 -308.844673) (xy 399.183497 -308.88825) (xy 399.153932 -308.927594)
			(xy 399.118439 -308.961686) (xy 399.077936 -308.989642) (xy 399.033474 -309.01074) (xy 398.986203 -309.024432)
			(xy 398.937348 -309.030364) (xy 398.888173 -309.028383) (xy 398.839954 -309.018539) (xy 398.793938 -309.001087)
			(xy 398.751317 -308.97648) (xy 398.713196 -308.945355) (xy 398.680561 -308.908518) (xy 398.654258 -308.866922)
			(xy 398.634967 -308.821646) (xy 398.62319 -308.773862) (xy 398.61923 -308.724808) (xy 398.280128 -308.724808)
			(xy 398.279633 -308.749415) (xy 398.271738 -308.797992) (xy 398.256154 -308.844673) (xy 398.233283 -308.88825)
			(xy 398.203718 -308.927594) (xy 398.168225 -308.961686) (xy 398.127722 -308.989642) (xy 398.08326 -309.01074)
			(xy 398.035989 -309.024432) (xy 397.987134 -309.030364) (xy 397.937959 -309.028383) (xy 397.88974 -309.018539)
			(xy 397.843724 -309.001087) (xy 397.801103 -308.97648) (xy 397.762982 -308.945355) (xy 397.730347 -308.908518)
			(xy 397.704044 -308.866922) (xy 397.684753 -308.821646) (xy 397.672976 -308.773862) (xy 397.669016 -308.724808)
			(xy 397.355139 -308.724808) (xy 397.355139 -308.751162) (xy 397.346775 -308.803217) (xy 397.330259 -308.853285)
			(xy 397.30601 -308.9001) (xy 397.274641 -308.942474) (xy 397.236947 -308.979336) (xy 397.193883 -309.009752)
			(xy 397.146539 -309.03295) (xy 397.096114 -309.048345) (xy 397.070072 -309.052468) (xy 397.066008 -309.052976)
			(xy 397.054578 -309.056532) (xy 397.05026 -309.057802) (xy 397.02613 -309.068978) (xy 397.019526 -309.07609)
			(xy 397.004794 -309.091584) (xy 396.996666 -309.10276) (xy 396.99397 -309.108291) (xy 396.991012 -309.120232)
			(xy 396.990824 -309.126382) (xy 396.990824 -309.273194) (xy 396.990996 -309.279346) (xy 396.993955 -309.29129)
			(xy 396.996666 -309.296816) (xy 397.004794 -309.307992) (xy 397.019526 -309.323486) (xy 397.02613 -309.330598)
			(xy 397.05026 -309.341774) (xy 397.054578 -309.343044) (xy 397.066008 -309.3466) (xy 397.070072 -309.347108)
			(xy 397.096211 -309.351232) (xy 397.146812 -309.366704) (xy 397.194302 -309.390039) (xy 397.237469 -309.420641)
			(xy 397.27521 -309.457729) (xy 397.306561 -309.500355) (xy 397.330722 -309.547431) (xy 397.347076 -309.597754)
			(xy 397.355204 -309.65004) (xy 397.3549 -309.702953) (xy 397.350996 -309.729124) (xy 397.348964 -309.741062)
			(xy 397.35252 -309.752492) (xy 397.354035 -309.757022) (xy 397.358513 -309.765458) (xy 397.36141 -309.769256)
			(xy 397.364204 -309.772304) (xy 397.420592 -309.831232) (xy 397.424821 -309.835463) (xy 397.434832 -309.842008)
			(xy 397.440404 -309.844186) (xy 397.451326 -309.847996) (xy 397.463264 -309.846726) (xy 397.472371 -309.845671)
			(xy 397.490672 -309.844525) (xy 397.49984 -309.84444) (xy 397.514023 -309.844624) (xy 397.542263 -309.847291)
			(xy 397.556228 -309.849774) (xy 397.568674 -309.85206) (xy 397.57985 -309.848758) (xy 397.584937 -309.847052)
			(xy 397.594294 -309.841807) (xy 397.598392 -309.838344) (xy 397.601186 -309.835804) (xy 397.660876 -309.776114)
			(xy 397.663416 -309.77332) (xy 397.666848 -309.7692) (xy 397.672097 -309.759852) (xy 397.67383 -309.754778)
			(xy 397.677132 -309.743602) (xy 397.674846 -309.731156) (xy 397.672362 -309.717191) (xy 397.669693 -309.688951)
			(xy 397.669512 -309.674768) (xy 397.670034 -309.649513) (xy 397.678347 -309.599691) (xy 397.694748 -309.551917)
			(xy 397.718789 -309.507494) (xy 397.749813 -309.467634) (xy 397.786975 -309.433424) (xy 397.829261 -309.405798)
			(xy 397.875517 -309.385508) (xy 397.924482 -309.373108) (xy 397.97482 -309.368937) (xy 398.025158 -309.373108)
			(xy 398.074123 -309.385508) (xy 398.120379 -309.405798) (xy 398.162665 -309.433424) (xy 398.199827 -309.467634)
			(xy 398.230851 -309.507494) (xy 398.254892 -309.551917) (xy 398.271293 -309.599691) (xy 398.279606 -309.649513)
			(xy 398.280128 -309.674768) (xy 398.279943 -309.688951) (xy 398.277273 -309.71719) (xy 398.274794 -309.731156)
			(xy 398.272508 -309.743602) (xy 398.27581 -309.754778) (xy 398.27752 -309.759862) (xy 398.282775 -309.769211)
			(xy 398.286224 -309.77332) (xy 398.288764 -309.776114) (xy 398.348454 -309.835804) (xy 398.351248 -309.838344)
			(xy 398.355367 -309.841777) (xy 398.364714 -309.847029) (xy 398.36979 -309.848758) (xy 398.380966 -309.85206)
			(xy 398.393412 -309.849774) (xy 398.407377 -309.847288) (xy 398.435617 -309.844616) (xy 398.4498 -309.84444)
			(xy 398.474616 -309.844926) (xy 398.523595 -309.852955) (xy 398.570629 -309.868802) (xy 398.61448 -309.89205)
			(xy 398.653993 -309.922085) (xy 398.688126 -309.958117) (xy 398.71598 -309.999196) (xy 398.736822 -310.04424)
			(xy 398.750102 -310.092063) (xy 398.75547 -310.141404) (xy 398.755018 -310.149748) (xy 399.09421 -310.149748)
			(xy 399.09817 -310.100694) (xy 399.109947 -310.05291) (xy 399.129238 -310.007634) (xy 399.155541 -309.966038)
			(xy 399.188176 -309.929201) (xy 399.226297 -309.898076) (xy 399.268918 -309.873469) (xy 399.314934 -309.856017)
			(xy 399.363153 -309.846173) (xy 399.412328 -309.844192) (xy 399.461183 -309.850124) (xy 399.508454 -309.863816)
			(xy 399.552916 -309.884914) (xy 399.593419 -309.91287) (xy 399.628912 -309.946962) (xy 399.658477 -309.986306)
			(xy 399.681348 -310.029883) (xy 399.696932 -310.076564) (xy 399.704827 -310.125141) (xy 399.705322 -310.149748)
			(xy 400.04417 -310.149748) (xy 400.04813 -310.100694) (xy 400.059907 -310.05291) (xy 400.079198 -310.007634)
			(xy 400.105501 -309.966038) (xy 400.138136 -309.929201) (xy 400.176257 -309.898076) (xy 400.218878 -309.873469)
			(xy 400.264894 -309.856017) (xy 400.313113 -309.846173) (xy 400.362288 -309.844192) (xy 400.411143 -309.850124)
			(xy 400.458414 -309.863816) (xy 400.502876 -309.884914) (xy 400.543379 -309.91287) (xy 400.578872 -309.946962)
			(xy 400.608437 -309.986306) (xy 400.631308 -310.029883) (xy 400.646892 -310.076564) (xy 400.654787 -310.125141)
			(xy 400.655282 -310.149748) (xy 400.99413 -310.149748) (xy 400.99809 -310.100694) (xy 401.009867 -310.05291)
			(xy 401.029158 -310.007634) (xy 401.055461 -309.966038) (xy 401.088096 -309.929201) (xy 401.126217 -309.898076)
			(xy 401.168838 -309.873469) (xy 401.214854 -309.856017) (xy 401.263073 -309.846173) (xy 401.312248 -309.844192)
			(xy 401.361103 -309.850124) (xy 401.408374 -309.863816) (xy 401.452836 -309.884914) (xy 401.493339 -309.91287)
			(xy 401.528832 -309.946962) (xy 401.558397 -309.986306) (xy 401.581268 -310.029883) (xy 401.596852 -310.076564)
			(xy 401.604747 -310.125141) (xy 401.605242 -310.149748) (xy 401.94409 -310.149748) (xy 401.94805 -310.100694)
			(xy 401.959827 -310.05291) (xy 401.979118 -310.007634) (xy 402.005421 -309.966038) (xy 402.038056 -309.929201)
			(xy 402.076177 -309.898076) (xy 402.118798 -309.873469) (xy 402.164814 -309.856017) (xy 402.213033 -309.846173)
			(xy 402.262208 -309.844192) (xy 402.311063 -309.850124) (xy 402.358334 -309.863816) (xy 402.402796 -309.884914)
			(xy 402.443299 -309.91287) (xy 402.478792 -309.946962) (xy 402.508357 -309.986306) (xy 402.531228 -310.029883)
			(xy 402.546812 -310.076564) (xy 402.554707 -310.125141) (xy 402.555202 -310.149748) (xy 402.89405 -310.149748)
			(xy 402.89801 -310.100694) (xy 402.909787 -310.05291) (xy 402.929078 -310.007634) (xy 402.955381 -309.966038)
			(xy 402.988016 -309.929201) (xy 403.026137 -309.898076) (xy 403.068758 -309.873469) (xy 403.114774 -309.856017)
			(xy 403.162993 -309.846173) (xy 403.212168 -309.844192) (xy 403.261023 -309.850124) (xy 403.308294 -309.863816)
			(xy 403.352756 -309.884914) (xy 403.393259 -309.91287) (xy 403.428752 -309.946962) (xy 403.458317 -309.986306)
			(xy 403.481188 -310.029883) (xy 403.496772 -310.076564) (xy 403.504667 -310.125141) (xy 403.505162 -310.149748)
			(xy 403.504667 -310.174355) (xy 403.496772 -310.222932) (xy 403.481188 -310.269613) (xy 403.458317 -310.31319)
			(xy 403.428752 -310.352534) (xy 403.393259 -310.386626) (xy 403.352756 -310.414582) (xy 403.308294 -310.43568)
			(xy 403.261023 -310.449372) (xy 403.212168 -310.455304) (xy 403.162993 -310.453323) (xy 403.114774 -310.443479)
			(xy 403.068758 -310.426027) (xy 403.026137 -310.40142) (xy 402.988016 -310.370295) (xy 402.955381 -310.333458)
			(xy 402.929078 -310.291862) (xy 402.909787 -310.246586) (xy 402.89801 -310.198802) (xy 402.89405 -310.149748)
			(xy 402.555202 -310.149748) (xy 402.554707 -310.174355) (xy 402.546812 -310.222932) (xy 402.531228 -310.269613)
			(xy 402.508357 -310.31319) (xy 402.478792 -310.352534) (xy 402.443299 -310.386626) (xy 402.402796 -310.414582)
			(xy 402.358334 -310.43568) (xy 402.311063 -310.449372) (xy 402.262208 -310.455304) (xy 402.213033 -310.453323)
			(xy 402.164814 -310.443479) (xy 402.118798 -310.426027) (xy 402.076177 -310.40142) (xy 402.038056 -310.370295)
			(xy 402.005421 -310.333458) (xy 401.979118 -310.291862) (xy 401.959827 -310.246586) (xy 401.94805 -310.198802)
			(xy 401.94409 -310.149748) (xy 401.605242 -310.149748) (xy 401.604747 -310.174355) (xy 401.596852 -310.222932)
			(xy 401.581268 -310.269613) (xy 401.558397 -310.31319) (xy 401.528832 -310.352534) (xy 401.493339 -310.386626)
			(xy 401.452836 -310.414582) (xy 401.408374 -310.43568) (xy 401.361103 -310.449372) (xy 401.312248 -310.455304)
			(xy 401.263073 -310.453323) (xy 401.214854 -310.443479) (xy 401.168838 -310.426027) (xy 401.126217 -310.40142)
			(xy 401.088096 -310.370295) (xy 401.055461 -310.333458) (xy 401.029158 -310.291862) (xy 401.009867 -310.246586)
			(xy 400.99809 -310.198802) (xy 400.99413 -310.149748) (xy 400.655282 -310.149748) (xy 400.654787 -310.174355)
			(xy 400.646892 -310.222932) (xy 400.631308 -310.269613) (xy 400.608437 -310.31319) (xy 400.578872 -310.352534)
			(xy 400.543379 -310.386626) (xy 400.502876 -310.414582) (xy 400.458414 -310.43568) (xy 400.411143 -310.449372)
			(xy 400.362288 -310.455304) (xy 400.313113 -310.453323) (xy 400.264894 -310.443479) (xy 400.218878 -310.426027)
			(xy 400.176257 -310.40142) (xy 400.138136 -310.370295) (xy 400.105501 -310.333458) (xy 400.079198 -310.291862)
			(xy 400.059907 -310.246586) (xy 400.04813 -310.198802) (xy 400.04417 -310.149748) (xy 399.705322 -310.149748)
			(xy 399.704827 -310.174355) (xy 399.696932 -310.222932) (xy 399.681348 -310.269613) (xy 399.658477 -310.31319)
			(xy 399.628912 -310.352534) (xy 399.593419 -310.386626) (xy 399.552916 -310.414582) (xy 399.508454 -310.43568)
			(xy 399.461183 -310.449372) (xy 399.412328 -310.455304) (xy 399.363153 -310.453323) (xy 399.314934 -310.443479)
			(xy 399.268918 -310.426027) (xy 399.226297 -310.40142) (xy 399.188176 -310.370295) (xy 399.155541 -310.333458)
			(xy 399.129238 -310.291862) (xy 399.109947 -310.246586) (xy 399.09817 -310.198802) (xy 399.09421 -310.149748)
			(xy 398.755018 -310.149748) (xy 398.752786 -310.190963) (xy 398.74212 -310.239436) (xy 398.723752 -310.285544)
			(xy 398.698167 -310.328074) (xy 398.666038 -310.365904) (xy 398.628213 -310.398039) (xy 398.585687 -310.42363)
			(xy 398.539582 -310.442005) (xy 398.491111 -310.45268) (xy 398.441552 -310.455372) (xy 398.39221 -310.450011)
			(xy 398.344385 -310.436738) (xy 398.299338 -310.415904) (xy 398.258254 -310.388056) (xy 398.222217 -310.353928)
			(xy 398.192175 -310.314421) (xy 398.168921 -310.270573) (xy 398.153067 -310.223541) (xy 398.14503 -310.174564)
			(xy 398.144492 -310.149748) (xy 398.144676 -310.135565) (xy 398.147345 -310.107325) (xy 398.149826 -310.09336)
			(xy 398.152112 -310.080914) (xy 398.14881 -310.069738) (xy 398.147102 -310.064653) (xy 398.14185 -310.0553)
			(xy 398.138396 -310.051196) (xy 398.135856 -310.048402) (xy 398.076166 -309.988712) (xy 398.073372 -309.986172)
			(xy 398.069254 -309.982736) (xy 398.059909 -309.97748) (xy 398.05483 -309.975758) (xy 398.043654 -309.972456)
			(xy 398.031208 -309.974742) (xy 398.017243 -309.977228) (xy 397.989003 -309.979903) (xy 397.97482 -309.980076)
			(xy 397.960637 -309.97989) (xy 397.932398 -309.977218) (xy 397.918432 -309.974742) (xy 397.905986 -309.972456)
			(xy 397.89481 -309.975758) (xy 397.889725 -309.977468) (xy 397.880374 -309.98272) (xy 397.876268 -309.986172)
			(xy 397.873474 -309.988712) (xy 397.813784 -310.048402) (xy 397.811244 -310.051196) (xy 397.807815 -310.055318)
			(xy 397.802573 -310.064668) (xy 397.80083 -310.069738) (xy 397.797528 -310.080914) (xy 397.799814 -310.09336)
			(xy 397.802297 -310.107325) (xy 397.804964 -310.135565) (xy 397.805148 -310.149748) (xy 397.804674 -310.173738)
			(xy 397.797162 -310.221126) (xy 397.782331 -310.266756) (xy 397.760545 -310.309505) (xy 397.732342 -310.348321)
			(xy 397.698415 -310.382247) (xy 397.659598 -310.41045) (xy 397.616849 -310.432234) (xy 397.571218 -310.447064)
			(xy 397.52383 -310.454574) (xy 397.49984 -310.455056) (xy 397.490736 -310.454958) (xy 397.472563 -310.453813)
			(xy 397.463518 -310.45277) (xy 397.451326 -310.4515) (xy 397.440404 -310.45531) (xy 397.434822 -310.45747)
			(xy 397.424802 -310.46401) (xy 397.420592 -310.468264) (xy 397.364204 -310.527192) (xy 397.36141 -310.53024)
			(xy 397.358507 -310.534034) (xy 397.354027 -310.542471) (xy 397.35252 -310.547004) (xy 397.348964 -310.558434)
			(xy 397.350996 -310.570372) (xy 397.353125 -310.58386) (xy 397.355411 -310.611074) (xy 397.355568 -310.624728)
			(xy 397.355568 -310.69534) (xy 397.355822 -310.69915) (xy 397.355822 -310.699658) (xy 397.35678 -310.707762)
			(xy 397.363123 -310.722788) (xy 397.368268 -310.729122) (xy 397.372332 -310.733186) (xy 397.42872 -310.783732)
			(xy 397.432724 -310.787127) (xy 397.441812 -310.792376) (xy 397.446754 -310.794146) (xy 397.456914 -310.797448)
			(xy 397.467836 -310.796432) (xy 397.49984 -310.794654) (xy 397.525096 -310.795179) (xy 397.574919 -310.803499)
			(xy 397.622693 -310.819905) (xy 397.667116 -310.843951) (xy 397.706975 -310.874979) (xy 397.741184 -310.912145)
			(xy 397.76881 -310.954434) (xy 397.789099 -311.000692) (xy 397.801498 -311.04966) (xy 397.805666 -311.099962)
			(xy 398.143996 -311.099962) (xy 398.147956 -311.050908) (xy 398.159733 -311.003124) (xy 398.179024 -310.957848)
			(xy 398.205327 -310.916252) (xy 398.237962 -310.879415) (xy 398.276083 -310.84829) (xy 398.318704 -310.823683)
			(xy 398.36472 -310.806231) (xy 398.412939 -310.796387) (xy 398.462114 -310.794406) (xy 398.510969 -310.800338)
			(xy 398.55824 -310.81403) (xy 398.602702 -310.835128) (xy 398.643205 -310.863084) (xy 398.678698 -310.897176)
			(xy 398.708263 -310.93652) (xy 398.731134 -310.980097) (xy 398.746718 -311.026778) (xy 398.754613 -311.075355)
			(xy 398.755108 -311.099962) (xy 398.754613 -311.124569) (xy 398.754434 -311.12567) (xy 399.073366 -311.12567)
			(xy 399.073366 -311.074254) (xy 399.081409 -311.023472) (xy 399.097297 -310.974573) (xy 399.12064 -310.928761)
			(xy 399.150861 -310.887165) (xy 399.187217 -310.850809) (xy 399.228813 -310.820588) (xy 399.274625 -310.797245)
			(xy 399.323524 -310.781357) (xy 399.374306 -310.773314) (xy 399.425722 -310.773314) (xy 399.476504 -310.781357)
			(xy 399.525403 -310.797245) (xy 399.571215 -310.820588) (xy 399.612811 -310.850809) (xy 399.649167 -310.887165)
			(xy 399.679388 -310.928761) (xy 399.702731 -310.974573) (xy 399.718619 -311.023472) (xy 399.726662 -311.074254)
			(xy 399.727166 -311.099962) (xy 400.04417 -311.099962) (xy 400.04813 -311.050908) (xy 400.059907 -311.003124)
			(xy 400.079198 -310.957848) (xy 400.105501 -310.916252) (xy 400.138136 -310.879415) (xy 400.176257 -310.84829)
			(xy 400.218878 -310.823683) (xy 400.264894 -310.806231) (xy 400.313113 -310.796387) (xy 400.362288 -310.794406)
			(xy 400.411143 -310.800338) (xy 400.458414 -310.81403) (xy 400.502876 -310.835128) (xy 400.543379 -310.863084)
			(xy 400.578872 -310.897176) (xy 400.608437 -310.93652) (xy 400.631308 -310.980097) (xy 400.646892 -311.026778)
			(xy 400.654787 -311.075355) (xy 400.655282 -311.099962) (xy 400.654787 -311.124569) (xy 400.654608 -311.12567)
			(xy 400.973286 -311.12567) (xy 400.973286 -311.074254) (xy 400.981329 -311.023472) (xy 400.997217 -310.974573)
			(xy 401.02056 -310.928761) (xy 401.050781 -310.887165) (xy 401.087137 -310.850809) (xy 401.128733 -310.820588)
			(xy 401.174545 -310.797245) (xy 401.223444 -310.781357) (xy 401.274226 -310.773314) (xy 401.325642 -310.773314)
			(xy 401.376424 -310.781357) (xy 401.425323 -310.797245) (xy 401.471135 -310.820588) (xy 401.512731 -310.850809)
			(xy 401.549087 -310.887165) (xy 401.579308 -310.928761) (xy 401.602651 -310.974573) (xy 401.618539 -311.023472)
			(xy 401.626582 -311.074254) (xy 401.627086 -311.099962) (xy 401.94409 -311.099962) (xy 401.94805 -311.050908)
			(xy 401.959827 -311.003124) (xy 401.979118 -310.957848) (xy 402.005421 -310.916252) (xy 402.038056 -310.879415)
			(xy 402.076177 -310.84829) (xy 402.118798 -310.823683) (xy 402.164814 -310.806231) (xy 402.213033 -310.796387)
			(xy 402.262208 -310.794406) (xy 402.311063 -310.800338) (xy 402.358334 -310.81403) (xy 402.402796 -310.835128)
			(xy 402.443299 -310.863084) (xy 402.478792 -310.897176) (xy 402.508357 -310.93652) (xy 402.531228 -310.980097)
			(xy 402.546812 -311.026778) (xy 402.554707 -311.075355) (xy 402.555202 -311.099962) (xy 402.554707 -311.124569)
			(xy 402.554528 -311.12567) (xy 402.873206 -311.12567) (xy 402.873206 -311.074254) (xy 402.881249 -311.023472)
			(xy 402.897137 -310.974573) (xy 402.92048 -310.928761) (xy 402.950701 -310.887165) (xy 402.987057 -310.850809)
			(xy 403.028653 -310.820588) (xy 403.074465 -310.797245) (xy 403.123364 -310.781357) (xy 403.174146 -310.773314)
			(xy 403.225562 -310.773314) (xy 403.276344 -310.781357) (xy 403.325243 -310.797245) (xy 403.371055 -310.820588)
			(xy 403.412651 -310.850809) (xy 403.449007 -310.887165) (xy 403.479228 -310.928761) (xy 403.502571 -310.974573)
			(xy 403.518459 -311.023472) (xy 403.526502 -311.074254) (xy 403.527006 -311.099962) (xy 403.84401 -311.099962)
			(xy 403.84797 -311.050908) (xy 403.859747 -311.003124) (xy 403.879038 -310.957848) (xy 403.905341 -310.916252)
			(xy 403.937976 -310.879415) (xy 403.976097 -310.84829) (xy 404.018718 -310.823683) (xy 404.064734 -310.806231)
			(xy 404.112953 -310.796387) (xy 404.162128 -310.794406) (xy 404.210983 -310.800338) (xy 404.258254 -310.81403)
			(xy 404.302716 -310.835128) (xy 404.343219 -310.863084) (xy 404.378712 -310.897176) (xy 404.408277 -310.93652)
			(xy 404.431148 -310.980097) (xy 404.446732 -311.026778) (xy 404.454627 -311.075355) (xy 404.455122 -311.099962)
			(xy 404.454627 -311.124569) (xy 404.454448 -311.12567) (xy 404.77338 -311.12567) (xy 404.77338 -311.074254)
			(xy 404.781423 -311.023472) (xy 404.797311 -310.974573) (xy 404.820654 -310.928761) (xy 404.850875 -310.887165)
			(xy 404.887231 -310.850809) (xy 404.928827 -310.820588) (xy 404.974639 -310.797245) (xy 405.023538 -310.781357)
			(xy 405.07432 -310.773314) (xy 405.125736 -310.773314) (xy 405.176518 -310.781357) (xy 405.225417 -310.797245)
			(xy 405.271229 -310.820588) (xy 405.312825 -310.850809) (xy 405.349181 -310.887165) (xy 405.379402 -310.928761)
			(xy 405.402745 -310.974573) (xy 405.418633 -311.023472) (xy 405.426676 -311.074254) (xy 405.42718 -311.099962)
			(xy 405.744184 -311.099962) (xy 405.748144 -311.050908) (xy 405.759921 -311.003124) (xy 405.779212 -310.957848)
			(xy 405.805515 -310.916252) (xy 405.83815 -310.879415) (xy 405.876271 -310.84829) (xy 405.918892 -310.823683)
			(xy 405.964908 -310.806231) (xy 406.013127 -310.796387) (xy 406.062302 -310.794406) (xy 406.111157 -310.800338)
			(xy 406.158428 -310.81403) (xy 406.20289 -310.835128) (xy 406.243393 -310.863084) (xy 406.278886 -310.897176)
			(xy 406.308451 -310.93652) (xy 406.331322 -310.980097) (xy 406.346906 -311.026778) (xy 406.354801 -311.075355)
			(xy 406.355296 -311.099962) (xy 406.354801 -311.124569) (xy 406.354622 -311.12567) (xy 406.6733 -311.12567)
			(xy 406.6733 -311.074254) (xy 406.681343 -311.023472) (xy 406.697231 -310.974573) (xy 406.720574 -310.928761)
			(xy 406.750795 -310.887165) (xy 406.787151 -310.850809) (xy 406.828747 -310.820588) (xy 406.874559 -310.797245)
			(xy 406.923458 -310.781357) (xy 406.97424 -310.773314) (xy 407.025656 -310.773314) (xy 407.076438 -310.781357)
			(xy 407.125337 -310.797245) (xy 407.171149 -310.820588) (xy 407.212745 -310.850809) (xy 407.249101 -310.887165)
			(xy 407.279322 -310.928761) (xy 407.302665 -310.974573) (xy 407.318553 -311.023472) (xy 407.326596 -311.074254)
			(xy 407.3271 -311.099962) (xy 407.644104 -311.099962) (xy 407.648064 -311.050908) (xy 407.659841 -311.003124)
			(xy 407.679132 -310.957848) (xy 407.705435 -310.916252) (xy 407.73807 -310.879415) (xy 407.776191 -310.84829)
			(xy 407.818812 -310.823683) (xy 407.864828 -310.806231) (xy 407.913047 -310.796387) (xy 407.962222 -310.794406)
			(xy 408.011077 -310.800338) (xy 408.058348 -310.81403) (xy 408.10281 -310.835128) (xy 408.143313 -310.863084)
			(xy 408.178806 -310.897176) (xy 408.208371 -310.93652) (xy 408.231242 -310.980097) (xy 408.246826 -311.026778)
			(xy 408.254721 -311.075355) (xy 408.255216 -311.099962) (xy 408.254721 -311.124569) (xy 408.254542 -311.12567)
			(xy 408.57322 -311.12567) (xy 408.57322 -311.074254) (xy 408.581263 -311.023472) (xy 408.597151 -310.974573)
			(xy 408.620494 -310.928761) (xy 408.650715 -310.887165) (xy 408.687071 -310.850809) (xy 408.728667 -310.820588)
			(xy 408.774479 -310.797245) (xy 408.823378 -310.781357) (xy 408.87416 -310.773314) (xy 408.925576 -310.773314)
			(xy 408.976358 -310.781357) (xy 409.025257 -310.797245) (xy 409.071069 -310.820588) (xy 409.112665 -310.850809)
			(xy 409.149021 -310.887165) (xy 409.179242 -310.928761) (xy 409.202585 -310.974573) (xy 409.218473 -311.023472)
			(xy 409.226516 -311.074254) (xy 409.22702 -311.099962) (xy 409.544024 -311.099962) (xy 409.547984 -311.050908)
			(xy 409.559761 -311.003124) (xy 409.579052 -310.957848) (xy 409.605355 -310.916252) (xy 409.63799 -310.879415)
			(xy 409.676111 -310.84829) (xy 409.718732 -310.823683) (xy 409.764748 -310.806231) (xy 409.812967 -310.796387)
			(xy 409.862142 -310.794406) (xy 409.910997 -310.800338) (xy 409.958268 -310.81403) (xy 410.00273 -310.835128)
			(xy 410.043233 -310.863084) (xy 410.078726 -310.897176) (xy 410.108291 -310.93652) (xy 410.131162 -310.980097)
			(xy 410.146746 -311.026778) (xy 410.154641 -311.075355) (xy 410.155136 -311.099962) (xy 410.154641 -311.124569)
			(xy 410.154462 -311.12567) (xy 410.47314 -311.12567) (xy 410.47314 -311.074254) (xy 410.481183 -311.023472)
			(xy 410.497071 -310.974573) (xy 410.520414 -310.928761) (xy 410.550635 -310.887165) (xy 410.586991 -310.850809)
			(xy 410.628587 -310.820588) (xy 410.674399 -310.797245) (xy 410.723298 -310.781357) (xy 410.77408 -310.773314)
			(xy 410.825496 -310.773314) (xy 410.876278 -310.781357) (xy 410.925177 -310.797245) (xy 410.970989 -310.820588)
			(xy 411.012585 -310.850809) (xy 411.048941 -310.887165) (xy 411.079162 -310.928761) (xy 411.102505 -310.974573)
			(xy 411.118393 -311.023472) (xy 411.126436 -311.074254) (xy 411.12694 -311.099962) (xy 411.444198 -311.099962)
			(xy 411.448158 -311.050908) (xy 411.459935 -311.003124) (xy 411.479226 -310.957848) (xy 411.505529 -310.916252)
			(xy 411.538164 -310.879415) (xy 411.576285 -310.84829) (xy 411.618906 -310.823683) (xy 411.664922 -310.806231)
			(xy 411.713141 -310.796387) (xy 411.762316 -310.794406) (xy 411.811171 -310.800338) (xy 411.858442 -310.81403)
			(xy 411.902904 -310.835128) (xy 411.943407 -310.863084) (xy 411.9789 -310.897176) (xy 412.008465 -310.93652)
			(xy 412.031336 -310.980097) (xy 412.04692 -311.026778) (xy 412.054815 -311.075355) (xy 412.05531 -311.099962)
			(xy 412.054815 -311.124569) (xy 412.054636 -311.12567) (xy 412.373314 -311.12567) (xy 412.373314 -311.074254)
			(xy 412.381357 -311.023472) (xy 412.397245 -310.974573) (xy 412.420588 -310.928761) (xy 412.450809 -310.887165)
			(xy 412.487165 -310.850809) (xy 412.528761 -310.820588) (xy 412.574573 -310.797245) (xy 412.623472 -310.781357)
			(xy 412.674254 -310.773314) (xy 412.72567 -310.773314) (xy 412.776452 -310.781357) (xy 412.825351 -310.797245)
			(xy 412.871163 -310.820588) (xy 412.912759 -310.850809) (xy 412.949115 -310.887165) (xy 412.979336 -310.928761)
			(xy 413.002679 -310.974573) (xy 413.018567 -311.023472) (xy 413.02661 -311.074254) (xy 413.027114 -311.099962)
			(xy 413.344118 -311.099962) (xy 413.348078 -311.050908) (xy 413.359855 -311.003124) (xy 413.379146 -310.957848)
			(xy 413.405449 -310.916252) (xy 413.438084 -310.879415) (xy 413.476205 -310.84829) (xy 413.518826 -310.823683)
			(xy 413.564842 -310.806231) (xy 413.613061 -310.796387) (xy 413.662236 -310.794406) (xy 413.711091 -310.800338)
			(xy 413.758362 -310.81403) (xy 413.802824 -310.835128) (xy 413.843327 -310.863084) (xy 413.87882 -310.897176)
			(xy 413.908385 -310.93652) (xy 413.931256 -310.980097) (xy 413.94684 -311.026778) (xy 413.954735 -311.075355)
			(xy 413.95523 -311.099962) (xy 414.294078 -311.099962) (xy 414.298038 -311.050908) (xy 414.309815 -311.003124)
			(xy 414.329106 -310.957848) (xy 414.355409 -310.916252) (xy 414.388044 -310.879415) (xy 414.426165 -310.84829)
			(xy 414.468786 -310.823683) (xy 414.514802 -310.806231) (xy 414.563021 -310.796387) (xy 414.612196 -310.794406)
			(xy 414.661051 -310.800338) (xy 414.708322 -310.81403) (xy 414.752784 -310.835128) (xy 414.793287 -310.863084)
			(xy 414.82878 -310.897176) (xy 414.858345 -310.93652) (xy 414.881216 -310.980097) (xy 414.8968 -311.026778)
			(xy 414.904695 -311.075355) (xy 414.90519 -311.099962) (xy 415.244038 -311.099962) (xy 415.247998 -311.050908)
			(xy 415.259775 -311.003124) (xy 415.279066 -310.957848) (xy 415.305369 -310.916252) (xy 415.338004 -310.879415)
			(xy 415.376125 -310.84829) (xy 415.418746 -310.823683) (xy 415.464762 -310.806231) (xy 415.512981 -310.796387)
			(xy 415.562156 -310.794406) (xy 415.611011 -310.800338) (xy 415.658282 -310.81403) (xy 415.702744 -310.835128)
			(xy 415.743247 -310.863084) (xy 415.77874 -310.897176) (xy 415.808305 -310.93652) (xy 415.831176 -310.980097)
			(xy 415.84676 -311.026778) (xy 415.854655 -311.075355) (xy 415.85515 -311.099962) (xy 416.193998 -311.099962)
			(xy 416.197958 -311.050908) (xy 416.209735 -311.003124) (xy 416.229026 -310.957848) (xy 416.255329 -310.916252)
			(xy 416.287964 -310.879415) (xy 416.326085 -310.84829) (xy 416.368706 -310.823683) (xy 416.414722 -310.806231)
			(xy 416.462941 -310.796387) (xy 416.512116 -310.794406) (xy 416.560971 -310.800338) (xy 416.608242 -310.81403)
			(xy 416.652704 -310.835128) (xy 416.693207 -310.863084) (xy 416.7287 -310.897176) (xy 416.758265 -310.93652)
			(xy 416.781136 -310.980097) (xy 416.79672 -311.026778) (xy 416.804615 -311.075355) (xy 416.80511 -311.099962)
			(xy 417.144212 -311.099962) (xy 417.148172 -311.050908) (xy 417.159949 -311.003124) (xy 417.17924 -310.957848)
			(xy 417.205543 -310.916252) (xy 417.238178 -310.879415) (xy 417.276299 -310.84829) (xy 417.31892 -310.823683)
			(xy 417.364936 -310.806231) (xy 417.413155 -310.796387) (xy 417.46233 -310.794406) (xy 417.511185 -310.800338)
			(xy 417.558456 -310.81403) (xy 417.602918 -310.835128) (xy 417.643421 -310.863084) (xy 417.678914 -310.897176)
			(xy 417.708479 -310.93652) (xy 417.73135 -310.980097) (xy 417.746934 -311.026778) (xy 417.754829 -311.075355)
			(xy 417.755324 -311.099962) (xy 418.094172 -311.099962) (xy 418.098132 -311.050908) (xy 418.109909 -311.003124)
			(xy 418.1292 -310.957848) (xy 418.155503 -310.916252) (xy 418.188138 -310.879415) (xy 418.226259 -310.84829)
			(xy 418.26888 -310.823683) (xy 418.314896 -310.806231) (xy 418.363115 -310.796387) (xy 418.41229 -310.794406)
			(xy 418.461145 -310.800338) (xy 418.508416 -310.81403) (xy 418.552878 -310.835128) (xy 418.593381 -310.863084)
			(xy 418.628874 -310.897176) (xy 418.658439 -310.93652) (xy 418.68131 -310.980097) (xy 418.696894 -311.026778)
			(xy 418.704789 -311.075355) (xy 418.705284 -311.099962) (xy 419.044132 -311.099962) (xy 419.048092 -311.050908)
			(xy 419.059869 -311.003124) (xy 419.07916 -310.957848) (xy 419.105463 -310.916252) (xy 419.138098 -310.879415)
			(xy 419.176219 -310.84829) (xy 419.21884 -310.823683) (xy 419.264856 -310.806231) (xy 419.313075 -310.796387)
			(xy 419.36225 -310.794406) (xy 419.411105 -310.800338) (xy 419.458376 -310.81403) (xy 419.502838 -310.835128)
			(xy 419.543341 -310.863084) (xy 419.578834 -310.897176) (xy 419.608399 -310.93652) (xy 419.63127 -310.980097)
			(xy 419.646854 -311.026778) (xy 419.654749 -311.075355) (xy 419.655244 -311.099962) (xy 419.994092 -311.099962)
			(xy 419.998052 -311.050908) (xy 420.009829 -311.003124) (xy 420.02912 -310.957848) (xy 420.055423 -310.916252)
			(xy 420.088058 -310.879415) (xy 420.126179 -310.84829) (xy 420.1688 -310.823683) (xy 420.214816 -310.806231)
			(xy 420.263035 -310.796387) (xy 420.31221 -310.794406) (xy 420.361065 -310.800338) (xy 420.408336 -310.81403)
			(xy 420.452798 -310.835128) (xy 420.493301 -310.863084) (xy 420.528794 -310.897176) (xy 420.558359 -310.93652)
			(xy 420.58123 -310.980097) (xy 420.596814 -311.026778) (xy 420.604709 -311.075355) (xy 420.605204 -311.099962)
			(xy 420.944052 -311.099962) (xy 420.948012 -311.050908) (xy 420.959789 -311.003124) (xy 420.97908 -310.957848)
			(xy 421.005383 -310.916252) (xy 421.038018 -310.879415) (xy 421.076139 -310.84829) (xy 421.11876 -310.823683)
			(xy 421.164776 -310.806231) (xy 421.212995 -310.796387) (xy 421.26217 -310.794406) (xy 421.311025 -310.800338)
			(xy 421.358296 -310.81403) (xy 421.402758 -310.835128) (xy 421.443261 -310.863084) (xy 421.478754 -310.897176)
			(xy 421.508319 -310.93652) (xy 421.53119 -310.980097) (xy 421.546774 -311.026778) (xy 421.554669 -311.075355)
			(xy 421.555164 -311.099962) (xy 421.554669 -311.124569) (xy 421.55449 -311.12567) (xy 421.873168 -311.12567)
			(xy 421.873168 -311.074254) (xy 421.881211 -311.023472) (xy 421.897099 -310.974573) (xy 421.920442 -310.928761)
			(xy 421.950663 -310.887165) (xy 421.987019 -310.850809) (xy 422.028615 -310.820588) (xy 422.074427 -310.797245)
			(xy 422.123326 -310.781357) (xy 422.174108 -310.773314) (xy 422.225524 -310.773314) (xy 422.276306 -310.781357)
			(xy 422.325205 -310.797245) (xy 422.371017 -310.820588) (xy 422.412613 -310.850809) (xy 422.448969 -310.887165)
			(xy 422.47919 -310.928761) (xy 422.502533 -310.974573) (xy 422.518421 -311.023472) (xy 422.526464 -311.074254)
			(xy 422.526968 -311.099962) (xy 422.844226 -311.099962) (xy 422.848186 -311.050908) (xy 422.859963 -311.003124)
			(xy 422.879254 -310.957848) (xy 422.905557 -310.916252) (xy 422.938192 -310.879415) (xy 422.976313 -310.84829)
			(xy 423.018934 -310.823683) (xy 423.06495 -310.806231) (xy 423.113169 -310.796387) (xy 423.162344 -310.794406)
			(xy 423.211199 -310.800338) (xy 423.25847 -310.81403) (xy 423.302932 -310.835128) (xy 423.343435 -310.863084)
			(xy 423.378928 -310.897176) (xy 423.408493 -310.93652) (xy 423.431364 -310.980097) (xy 423.446948 -311.026778)
			(xy 423.454843 -311.075355) (xy 423.455338 -311.099962) (xy 423.454843 -311.124569) (xy 423.454664 -311.12567)
			(xy 423.773342 -311.12567) (xy 423.773342 -311.074254) (xy 423.781385 -311.023472) (xy 423.797273 -310.974573)
			(xy 423.820616 -310.928761) (xy 423.850837 -310.887165) (xy 423.887193 -310.850809) (xy 423.928789 -310.820588)
			(xy 423.974601 -310.797245) (xy 424.0235 -310.781357) (xy 424.074282 -310.773314) (xy 424.125698 -310.773314)
			(xy 424.17648 -310.781357) (xy 424.225379 -310.797245) (xy 424.271191 -310.820588) (xy 424.312787 -310.850809)
			(xy 424.349143 -310.887165) (xy 424.379364 -310.928761) (xy 424.402707 -310.974573) (xy 424.418595 -311.023472)
			(xy 424.426638 -311.074254) (xy 424.427142 -311.099962) (xy 424.744146 -311.099962) (xy 424.748106 -311.050908)
			(xy 424.759883 -311.003124) (xy 424.779174 -310.957848) (xy 424.805477 -310.916252) (xy 424.838112 -310.879415)
			(xy 424.876233 -310.84829) (xy 424.918854 -310.823683) (xy 424.96487 -310.806231) (xy 425.013089 -310.796387)
			(xy 425.062264 -310.794406) (xy 425.111119 -310.800338) (xy 425.15839 -310.81403) (xy 425.202852 -310.835128)
			(xy 425.243355 -310.863084) (xy 425.278848 -310.897176) (xy 425.308413 -310.93652) (xy 425.331284 -310.980097)
			(xy 425.346868 -311.026778) (xy 425.354763 -311.075355) (xy 425.355258 -311.099962) (xy 425.354763 -311.124569)
			(xy 425.354584 -311.12567) (xy 425.673262 -311.12567) (xy 425.673262 -311.074254) (xy 425.681305 -311.023472)
			(xy 425.697193 -310.974573) (xy 425.720536 -310.928761) (xy 425.750757 -310.887165) (xy 425.787113 -310.850809)
			(xy 425.828709 -310.820588) (xy 425.874521 -310.797245) (xy 425.92342 -310.781357) (xy 425.974202 -310.773314)
			(xy 426.025618 -310.773314) (xy 426.0764 -310.781357) (xy 426.125299 -310.797245) (xy 426.171111 -310.820588)
			(xy 426.212707 -310.850809) (xy 426.249063 -310.887165) (xy 426.279284 -310.928761) (xy 426.302627 -310.974573)
			(xy 426.318515 -311.023472) (xy 426.326558 -311.074254) (xy 426.327062 -311.099962) (xy 426.644066 -311.099962)
			(xy 426.648026 -311.050908) (xy 426.659803 -311.003124) (xy 426.679094 -310.957848) (xy 426.705397 -310.916252)
			(xy 426.738032 -310.879415) (xy 426.776153 -310.84829) (xy 426.818774 -310.823683) (xy 426.86479 -310.806231)
			(xy 426.913009 -310.796387) (xy 426.962184 -310.794406) (xy 427.011039 -310.800338) (xy 427.05831 -310.81403)
			(xy 427.102772 -310.835128) (xy 427.143275 -310.863084) (xy 427.178768 -310.897176) (xy 427.208333 -310.93652)
			(xy 427.231204 -310.980097) (xy 427.246788 -311.026778) (xy 427.254683 -311.075355) (xy 427.255178 -311.099962)
			(xy 427.254683 -311.124569) (xy 427.254504 -311.12567) (xy 427.573182 -311.12567) (xy 427.573182 -311.074254)
			(xy 427.581225 -311.023472) (xy 427.597113 -310.974573) (xy 427.620456 -310.928761) (xy 427.650677 -310.887165)
			(xy 427.687033 -310.850809) (xy 427.728629 -310.820588) (xy 427.774441 -310.797245) (xy 427.82334 -310.781357)
			(xy 427.874122 -310.773314) (xy 427.925538 -310.773314) (xy 427.97632 -310.781357) (xy 428.025219 -310.797245)
			(xy 428.071031 -310.820588) (xy 428.112627 -310.850809) (xy 428.148983 -310.887165) (xy 428.179204 -310.928761)
			(xy 428.202547 -310.974573) (xy 428.218435 -311.023472) (xy 428.226478 -311.074254) (xy 428.226982 -311.099962)
			(xy 428.543986 -311.099962) (xy 428.547946 -311.050908) (xy 428.559723 -311.003124) (xy 428.579014 -310.957848)
			(xy 428.605317 -310.916252) (xy 428.637952 -310.879415) (xy 428.676073 -310.84829) (xy 428.718694 -310.823683)
			(xy 428.76471 -310.806231) (xy 428.812929 -310.796387) (xy 428.862104 -310.794406) (xy 428.910959 -310.800338)
			(xy 428.95823 -310.81403) (xy 429.002692 -310.835128) (xy 429.043195 -310.863084) (xy 429.078688 -310.897176)
			(xy 429.108253 -310.93652) (xy 429.131124 -310.980097) (xy 429.146708 -311.026778) (xy 429.154603 -311.075355)
			(xy 429.155098 -311.099962) (xy 429.4942 -311.099962) (xy 429.49816 -311.050908) (xy 429.509937 -311.003124)
			(xy 429.529228 -310.957848) (xy 429.555531 -310.916252) (xy 429.588166 -310.879415) (xy 429.626287 -310.84829)
			(xy 429.668908 -310.823683) (xy 429.714924 -310.806231) (xy 429.763143 -310.796387) (xy 429.812318 -310.794406)
			(xy 429.861173 -310.800338) (xy 429.908444 -310.81403) (xy 429.952906 -310.835128) (xy 429.993409 -310.863084)
			(xy 430.028902 -310.897176) (xy 430.058467 -310.93652) (xy 430.081338 -310.980097) (xy 430.096922 -311.026778)
			(xy 430.104817 -311.075355) (xy 430.105312 -311.099962) (xy 430.44416 -311.099962) (xy 430.44812 -311.050908)
			(xy 430.459897 -311.003124) (xy 430.479188 -310.957848) (xy 430.505491 -310.916252) (xy 430.538126 -310.879415)
			(xy 430.576247 -310.84829) (xy 430.618868 -310.823683) (xy 430.664884 -310.806231) (xy 430.713103 -310.796387)
			(xy 430.762278 -310.794406) (xy 430.811133 -310.800338) (xy 430.858404 -310.81403) (xy 430.902866 -310.835128)
			(xy 430.943369 -310.863084) (xy 430.978862 -310.897176) (xy 431.008427 -310.93652) (xy 431.031298 -310.980097)
			(xy 431.046882 -311.026778) (xy 431.054777 -311.075355) (xy 431.055272 -311.099962) (xy 431.054777 -311.124569)
			(xy 431.046882 -311.173146) (xy 431.031298 -311.219827) (xy 431.008427 -311.263404) (xy 430.978862 -311.302748)
			(xy 430.943369 -311.33684) (xy 430.902866 -311.364796) (xy 430.858404 -311.385894) (xy 430.811133 -311.399586)
			(xy 430.762278 -311.405518) (xy 430.713103 -311.403537) (xy 430.664884 -311.393693) (xy 430.618868 -311.376241)
			(xy 430.576247 -311.351634) (xy 430.538126 -311.320509) (xy 430.505491 -311.283672) (xy 430.479188 -311.242076)
			(xy 430.459897 -311.1968) (xy 430.44812 -311.149016) (xy 430.44416 -311.099962) (xy 430.105312 -311.099962)
			(xy 430.104817 -311.124569) (xy 430.096922 -311.173146) (xy 430.081338 -311.219827) (xy 430.058467 -311.263404)
			(xy 430.028902 -311.302748) (xy 429.993409 -311.33684) (xy 429.952906 -311.364796) (xy 429.908444 -311.385894)
			(xy 429.861173 -311.399586) (xy 429.812318 -311.405518) (xy 429.763143 -311.403537) (xy 429.714924 -311.393693)
			(xy 429.668908 -311.376241) (xy 429.626287 -311.351634) (xy 429.588166 -311.320509) (xy 429.555531 -311.283672)
			(xy 429.529228 -311.242076) (xy 429.509937 -311.1968) (xy 429.49816 -311.149016) (xy 429.4942 -311.099962)
			(xy 429.155098 -311.099962) (xy 429.154603 -311.124569) (xy 429.146708 -311.173146) (xy 429.131124 -311.219827)
			(xy 429.108253 -311.263404) (xy 429.078688 -311.302748) (xy 429.043195 -311.33684) (xy 429.002692 -311.364796)
			(xy 428.95823 -311.385894) (xy 428.910959 -311.399586) (xy 428.862104 -311.405518) (xy 428.812929 -311.403537)
			(xy 428.76471 -311.393693) (xy 428.718694 -311.376241) (xy 428.676073 -311.351634) (xy 428.637952 -311.320509)
			(xy 428.605317 -311.283672) (xy 428.579014 -311.242076) (xy 428.559723 -311.1968) (xy 428.547946 -311.149016)
			(xy 428.543986 -311.099962) (xy 428.226982 -311.099962) (xy 428.226478 -311.12567) (xy 428.218435 -311.176452)
			(xy 428.202547 -311.225351) (xy 428.179204 -311.271163) (xy 428.148983 -311.312759) (xy 428.112627 -311.349115)
			(xy 428.071031 -311.379336) (xy 428.025219 -311.402679) (xy 427.97632 -311.418567) (xy 427.925538 -311.42661)
			(xy 427.874122 -311.42661) (xy 427.82334 -311.418567) (xy 427.774441 -311.402679) (xy 427.728629 -311.379336)
			(xy 427.687033 -311.349115) (xy 427.650677 -311.312759) (xy 427.620456 -311.271163) (xy 427.597113 -311.225351)
			(xy 427.581225 -311.176452) (xy 427.573182 -311.12567) (xy 427.254504 -311.12567) (xy 427.246788 -311.173146)
			(xy 427.231204 -311.219827) (xy 427.208333 -311.263404) (xy 427.178768 -311.302748) (xy 427.143275 -311.33684)
			(xy 427.102772 -311.364796) (xy 427.05831 -311.385894) (xy 427.011039 -311.399586) (xy 426.962184 -311.405518)
			(xy 426.913009 -311.403537) (xy 426.86479 -311.393693) (xy 426.818774 -311.376241) (xy 426.776153 -311.351634)
			(xy 426.738032 -311.320509) (xy 426.705397 -311.283672) (xy 426.679094 -311.242076) (xy 426.659803 -311.1968)
			(xy 426.648026 -311.149016) (xy 426.644066 -311.099962) (xy 426.327062 -311.099962) (xy 426.326558 -311.12567)
			(xy 426.318515 -311.176452) (xy 426.302627 -311.225351) (xy 426.279284 -311.271163) (xy 426.249063 -311.312759)
			(xy 426.212707 -311.349115) (xy 426.171111 -311.379336) (xy 426.125299 -311.402679) (xy 426.0764 -311.418567)
			(xy 426.025618 -311.42661) (xy 425.974202 -311.42661) (xy 425.92342 -311.418567) (xy 425.874521 -311.402679)
			(xy 425.828709 -311.379336) (xy 425.787113 -311.349115) (xy 425.750757 -311.312759) (xy 425.720536 -311.271163)
			(xy 425.697193 -311.225351) (xy 425.681305 -311.176452) (xy 425.673262 -311.12567) (xy 425.354584 -311.12567)
			(xy 425.346868 -311.173146) (xy 425.331284 -311.219827) (xy 425.308413 -311.263404) (xy 425.278848 -311.302748)
			(xy 425.243355 -311.33684) (xy 425.202852 -311.364796) (xy 425.15839 -311.385894) (xy 425.111119 -311.399586)
			(xy 425.062264 -311.405518) (xy 425.013089 -311.403537) (xy 424.96487 -311.393693) (xy 424.918854 -311.376241)
			(xy 424.876233 -311.351634) (xy 424.838112 -311.320509) (xy 424.805477 -311.283672) (xy 424.779174 -311.242076)
			(xy 424.759883 -311.1968) (xy 424.748106 -311.149016) (xy 424.744146 -311.099962) (xy 424.427142 -311.099962)
			(xy 424.426638 -311.12567) (xy 424.418595 -311.176452) (xy 424.402707 -311.225351) (xy 424.379364 -311.271163)
			(xy 424.349143 -311.312759) (xy 424.312787 -311.349115) (xy 424.271191 -311.379336) (xy 424.225379 -311.402679)
			(xy 424.17648 -311.418567) (xy 424.125698 -311.42661) (xy 424.074282 -311.42661) (xy 424.0235 -311.418567)
			(xy 423.974601 -311.402679) (xy 423.928789 -311.379336) (xy 423.887193 -311.349115) (xy 423.850837 -311.312759)
			(xy 423.820616 -311.271163) (xy 423.797273 -311.225351) (xy 423.781385 -311.176452) (xy 423.773342 -311.12567)
			(xy 423.454664 -311.12567) (xy 423.446948 -311.173146) (xy 423.431364 -311.219827) (xy 423.408493 -311.263404)
			(xy 423.378928 -311.302748) (xy 423.343435 -311.33684) (xy 423.302932 -311.364796) (xy 423.25847 -311.385894)
			(xy 423.211199 -311.399586) (xy 423.162344 -311.405518) (xy 423.113169 -311.403537) (xy 423.06495 -311.393693)
			(xy 423.018934 -311.376241) (xy 422.976313 -311.351634) (xy 422.938192 -311.320509) (xy 422.905557 -311.283672)
			(xy 422.879254 -311.242076) (xy 422.859963 -311.1968) (xy 422.848186 -311.149016) (xy 422.844226 -311.099962)
			(xy 422.526968 -311.099962) (xy 422.526464 -311.12567) (xy 422.518421 -311.176452) (xy 422.502533 -311.225351)
			(xy 422.47919 -311.271163) (xy 422.448969 -311.312759) (xy 422.412613 -311.349115) (xy 422.371017 -311.379336)
			(xy 422.325205 -311.402679) (xy 422.276306 -311.418567) (xy 422.225524 -311.42661) (xy 422.174108 -311.42661)
			(xy 422.123326 -311.418567) (xy 422.074427 -311.402679) (xy 422.028615 -311.379336) (xy 421.987019 -311.349115)
			(xy 421.950663 -311.312759) (xy 421.920442 -311.271163) (xy 421.897099 -311.225351) (xy 421.881211 -311.176452)
			(xy 421.873168 -311.12567) (xy 421.55449 -311.12567) (xy 421.546774 -311.173146) (xy 421.53119 -311.219827)
			(xy 421.508319 -311.263404) (xy 421.478754 -311.302748) (xy 421.443261 -311.33684) (xy 421.402758 -311.364796)
			(xy 421.358296 -311.385894) (xy 421.311025 -311.399586) (xy 421.26217 -311.405518) (xy 421.212995 -311.403537)
			(xy 421.164776 -311.393693) (xy 421.11876 -311.376241) (xy 421.076139 -311.351634) (xy 421.038018 -311.320509)
			(xy 421.005383 -311.283672) (xy 420.97908 -311.242076) (xy 420.959789 -311.1968) (xy 420.948012 -311.149016)
			(xy 420.944052 -311.099962) (xy 420.605204 -311.099962) (xy 420.604709 -311.124569) (xy 420.596814 -311.173146)
			(xy 420.58123 -311.219827) (xy 420.558359 -311.263404) (xy 420.528794 -311.302748) (xy 420.493301 -311.33684)
			(xy 420.452798 -311.364796) (xy 420.408336 -311.385894) (xy 420.361065 -311.399586) (xy 420.31221 -311.405518)
			(xy 420.263035 -311.403537) (xy 420.214816 -311.393693) (xy 420.1688 -311.376241) (xy 420.126179 -311.351634)
			(xy 420.088058 -311.320509) (xy 420.055423 -311.283672) (xy 420.02912 -311.242076) (xy 420.009829 -311.1968)
			(xy 419.998052 -311.149016) (xy 419.994092 -311.099962) (xy 419.655244 -311.099962) (xy 419.654749 -311.124569)
			(xy 419.646854 -311.173146) (xy 419.63127 -311.219827) (xy 419.608399 -311.263404) (xy 419.578834 -311.302748)
			(xy 419.543341 -311.33684) (xy 419.502838 -311.364796) (xy 419.458376 -311.385894) (xy 419.411105 -311.399586)
			(xy 419.36225 -311.405518) (xy 419.313075 -311.403537) (xy 419.264856 -311.393693) (xy 419.21884 -311.376241)
			(xy 419.176219 -311.351634) (xy 419.138098 -311.320509) (xy 419.105463 -311.283672) (xy 419.07916 -311.242076)
			(xy 419.059869 -311.1968) (xy 419.048092 -311.149016) (xy 419.044132 -311.099962) (xy 418.705284 -311.099962)
			(xy 418.704789 -311.124569) (xy 418.696894 -311.173146) (xy 418.68131 -311.219827) (xy 418.658439 -311.263404)
			(xy 418.628874 -311.302748) (xy 418.593381 -311.33684) (xy 418.552878 -311.364796) (xy 418.508416 -311.385894)
			(xy 418.461145 -311.399586) (xy 418.41229 -311.405518) (xy 418.363115 -311.403537) (xy 418.314896 -311.393693)
			(xy 418.26888 -311.376241) (xy 418.226259 -311.351634) (xy 418.188138 -311.320509) (xy 418.155503 -311.283672)
			(xy 418.1292 -311.242076) (xy 418.109909 -311.1968) (xy 418.098132 -311.149016) (xy 418.094172 -311.099962)
			(xy 417.755324 -311.099962) (xy 417.754829 -311.124569) (xy 417.746934 -311.173146) (xy 417.73135 -311.219827)
			(xy 417.708479 -311.263404) (xy 417.678914 -311.302748) (xy 417.643421 -311.33684) (xy 417.602918 -311.364796)
			(xy 417.558456 -311.385894) (xy 417.511185 -311.399586) (xy 417.46233 -311.405518) (xy 417.413155 -311.403537)
			(xy 417.364936 -311.393693) (xy 417.31892 -311.376241) (xy 417.276299 -311.351634) (xy 417.238178 -311.320509)
			(xy 417.205543 -311.283672) (xy 417.17924 -311.242076) (xy 417.159949 -311.1968) (xy 417.148172 -311.149016)
			(xy 417.144212 -311.099962) (xy 416.80511 -311.099962) (xy 416.804615 -311.124569) (xy 416.79672 -311.173146)
			(xy 416.781136 -311.219827) (xy 416.758265 -311.263404) (xy 416.7287 -311.302748) (xy 416.693207 -311.33684)
			(xy 416.652704 -311.364796) (xy 416.608242 -311.385894) (xy 416.560971 -311.399586) (xy 416.512116 -311.405518)
			(xy 416.462941 -311.403537) (xy 416.414722 -311.393693) (xy 416.368706 -311.376241) (xy 416.326085 -311.351634)
			(xy 416.287964 -311.320509) (xy 416.255329 -311.283672) (xy 416.229026 -311.242076) (xy 416.209735 -311.1968)
			(xy 416.197958 -311.149016) (xy 416.193998 -311.099962) (xy 415.85515 -311.099962) (xy 415.854655 -311.124569)
			(xy 415.84676 -311.173146) (xy 415.831176 -311.219827) (xy 415.808305 -311.263404) (xy 415.77874 -311.302748)
			(xy 415.743247 -311.33684) (xy 415.702744 -311.364796) (xy 415.658282 -311.385894) (xy 415.611011 -311.399586)
			(xy 415.562156 -311.405518) (xy 415.512981 -311.403537) (xy 415.464762 -311.393693) (xy 415.418746 -311.376241)
			(xy 415.376125 -311.351634) (xy 415.338004 -311.320509) (xy 415.305369 -311.283672) (xy 415.279066 -311.242076)
			(xy 415.259775 -311.1968) (xy 415.247998 -311.149016) (xy 415.244038 -311.099962) (xy 414.90519 -311.099962)
			(xy 414.904695 -311.124569) (xy 414.8968 -311.173146) (xy 414.881216 -311.219827) (xy 414.858345 -311.263404)
			(xy 414.82878 -311.302748) (xy 414.793287 -311.33684) (xy 414.752784 -311.364796) (xy 414.708322 -311.385894)
			(xy 414.661051 -311.399586) (xy 414.612196 -311.405518) (xy 414.563021 -311.403537) (xy 414.514802 -311.393693)
			(xy 414.468786 -311.376241) (xy 414.426165 -311.351634) (xy 414.388044 -311.320509) (xy 414.355409 -311.283672)
			(xy 414.329106 -311.242076) (xy 414.309815 -311.1968) (xy 414.298038 -311.149016) (xy 414.294078 -311.099962)
			(xy 413.95523 -311.099962) (xy 413.954735 -311.124569) (xy 413.94684 -311.173146) (xy 413.931256 -311.219827)
			(xy 413.908385 -311.263404) (xy 413.87882 -311.302748) (xy 413.843327 -311.33684) (xy 413.802824 -311.364796)
			(xy 413.758362 -311.385894) (xy 413.711091 -311.399586) (xy 413.662236 -311.405518) (xy 413.613061 -311.403537)
			(xy 413.564842 -311.393693) (xy 413.518826 -311.376241) (xy 413.476205 -311.351634) (xy 413.438084 -311.320509)
			(xy 413.405449 -311.283672) (xy 413.379146 -311.242076) (xy 413.359855 -311.1968) (xy 413.348078 -311.149016)
			(xy 413.344118 -311.099962) (xy 413.027114 -311.099962) (xy 413.02661 -311.12567) (xy 413.018567 -311.176452)
			(xy 413.002679 -311.225351) (xy 412.979336 -311.271163) (xy 412.949115 -311.312759) (xy 412.912759 -311.349115)
			(xy 412.871163 -311.379336) (xy 412.825351 -311.402679) (xy 412.776452 -311.418567) (xy 412.72567 -311.42661)
			(xy 412.674254 -311.42661) (xy 412.623472 -311.418567) (xy 412.574573 -311.402679) (xy 412.528761 -311.379336)
			(xy 412.487165 -311.349115) (xy 412.450809 -311.312759) (xy 412.420588 -311.271163) (xy 412.397245 -311.225351)
			(xy 412.381357 -311.176452) (xy 412.373314 -311.12567) (xy 412.054636 -311.12567) (xy 412.04692 -311.173146)
			(xy 412.031336 -311.219827) (xy 412.008465 -311.263404) (xy 411.9789 -311.302748) (xy 411.943407 -311.33684)
			(xy 411.902904 -311.364796) (xy 411.858442 -311.385894) (xy 411.811171 -311.399586) (xy 411.762316 -311.405518)
			(xy 411.713141 -311.403537) (xy 411.664922 -311.393693) (xy 411.618906 -311.376241) (xy 411.576285 -311.351634)
			(xy 411.538164 -311.320509) (xy 411.505529 -311.283672) (xy 411.479226 -311.242076) (xy 411.459935 -311.1968)
			(xy 411.448158 -311.149016) (xy 411.444198 -311.099962) (xy 411.12694 -311.099962) (xy 411.126436 -311.12567)
			(xy 411.118393 -311.176452) (xy 411.102505 -311.225351) (xy 411.079162 -311.271163) (xy 411.048941 -311.312759)
			(xy 411.012585 -311.349115) (xy 410.970989 -311.379336) (xy 410.925177 -311.402679) (xy 410.876278 -311.418567)
			(xy 410.825496 -311.42661) (xy 410.77408 -311.42661) (xy 410.723298 -311.418567) (xy 410.674399 -311.402679)
			(xy 410.628587 -311.379336) (xy 410.586991 -311.349115) (xy 410.550635 -311.312759) (xy 410.520414 -311.271163)
			(xy 410.497071 -311.225351) (xy 410.481183 -311.176452) (xy 410.47314 -311.12567) (xy 410.154462 -311.12567)
			(xy 410.146746 -311.173146) (xy 410.131162 -311.219827) (xy 410.108291 -311.263404) (xy 410.078726 -311.302748)
			(xy 410.043233 -311.33684) (xy 410.00273 -311.364796) (xy 409.958268 -311.385894) (xy 409.910997 -311.399586)
			(xy 409.862142 -311.405518) (xy 409.812967 -311.403537) (xy 409.764748 -311.393693) (xy 409.718732 -311.376241)
			(xy 409.676111 -311.351634) (xy 409.63799 -311.320509) (xy 409.605355 -311.283672) (xy 409.579052 -311.242076)
			(xy 409.559761 -311.1968) (xy 409.547984 -311.149016) (xy 409.544024 -311.099962) (xy 409.22702 -311.099962)
			(xy 409.226516 -311.12567) (xy 409.218473 -311.176452) (xy 409.202585 -311.225351) (xy 409.179242 -311.271163)
			(xy 409.149021 -311.312759) (xy 409.112665 -311.349115) (xy 409.071069 -311.379336) (xy 409.025257 -311.402679)
			(xy 408.976358 -311.418567) (xy 408.925576 -311.42661) (xy 408.87416 -311.42661) (xy 408.823378 -311.418567)
			(xy 408.774479 -311.402679) (xy 408.728667 -311.379336) (xy 408.687071 -311.349115) (xy 408.650715 -311.312759)
			(xy 408.620494 -311.271163) (xy 408.597151 -311.225351) (xy 408.581263 -311.176452) (xy 408.57322 -311.12567)
			(xy 408.254542 -311.12567) (xy 408.246826 -311.173146) (xy 408.231242 -311.219827) (xy 408.208371 -311.263404)
			(xy 408.178806 -311.302748) (xy 408.143313 -311.33684) (xy 408.10281 -311.364796) (xy 408.058348 -311.385894)
			(xy 408.011077 -311.399586) (xy 407.962222 -311.405518) (xy 407.913047 -311.403537) (xy 407.864828 -311.393693)
			(xy 407.818812 -311.376241) (xy 407.776191 -311.351634) (xy 407.73807 -311.320509) (xy 407.705435 -311.283672)
			(xy 407.679132 -311.242076) (xy 407.659841 -311.1968) (xy 407.648064 -311.149016) (xy 407.644104 -311.099962)
			(xy 407.3271 -311.099962) (xy 407.326596 -311.12567) (xy 407.318553 -311.176452) (xy 407.302665 -311.225351)
			(xy 407.279322 -311.271163) (xy 407.249101 -311.312759) (xy 407.212745 -311.349115) (xy 407.171149 -311.379336)
			(xy 407.125337 -311.402679) (xy 407.076438 -311.418567) (xy 407.025656 -311.42661) (xy 406.97424 -311.42661)
			(xy 406.923458 -311.418567) (xy 406.874559 -311.402679) (xy 406.828747 -311.379336) (xy 406.787151 -311.349115)
			(xy 406.750795 -311.312759) (xy 406.720574 -311.271163) (xy 406.697231 -311.225351) (xy 406.681343 -311.176452)
			(xy 406.6733 -311.12567) (xy 406.354622 -311.12567) (xy 406.346906 -311.173146) (xy 406.331322 -311.219827)
			(xy 406.308451 -311.263404) (xy 406.278886 -311.302748) (xy 406.243393 -311.33684) (xy 406.20289 -311.364796)
			(xy 406.158428 -311.385894) (xy 406.111157 -311.399586) (xy 406.062302 -311.405518) (xy 406.013127 -311.403537)
			(xy 405.964908 -311.393693) (xy 405.918892 -311.376241) (xy 405.876271 -311.351634) (xy 405.83815 -311.320509)
			(xy 405.805515 -311.283672) (xy 405.779212 -311.242076) (xy 405.759921 -311.1968) (xy 405.748144 -311.149016)
			(xy 405.744184 -311.099962) (xy 405.42718 -311.099962) (xy 405.426676 -311.12567) (xy 405.418633 -311.176452)
			(xy 405.402745 -311.225351) (xy 405.379402 -311.271163) (xy 405.349181 -311.312759) (xy 405.312825 -311.349115)
			(xy 405.271229 -311.379336) (xy 405.225417 -311.402679) (xy 405.176518 -311.418567) (xy 405.125736 -311.42661)
			(xy 405.07432 -311.42661) (xy 405.023538 -311.418567) (xy 404.974639 -311.402679) (xy 404.928827 -311.379336)
			(xy 404.887231 -311.349115) (xy 404.850875 -311.312759) (xy 404.820654 -311.271163) (xy 404.797311 -311.225351)
			(xy 404.781423 -311.176452) (xy 404.77338 -311.12567) (xy 404.454448 -311.12567) (xy 404.446732 -311.173146)
			(xy 404.431148 -311.219827) (xy 404.408277 -311.263404) (xy 404.378712 -311.302748) (xy 404.343219 -311.33684)
			(xy 404.302716 -311.364796) (xy 404.258254 -311.385894) (xy 404.210983 -311.399586) (xy 404.162128 -311.405518)
			(xy 404.112953 -311.403537) (xy 404.064734 -311.393693) (xy 404.018718 -311.376241) (xy 403.976097 -311.351634)
			(xy 403.937976 -311.320509) (xy 403.905341 -311.283672) (xy 403.879038 -311.242076) (xy 403.859747 -311.1968)
			(xy 403.84797 -311.149016) (xy 403.84401 -311.099962) (xy 403.527006 -311.099962) (xy 403.526502 -311.12567)
			(xy 403.518459 -311.176452) (xy 403.502571 -311.225351) (xy 403.479228 -311.271163) (xy 403.449007 -311.312759)
			(xy 403.412651 -311.349115) (xy 403.371055 -311.379336) (xy 403.325243 -311.402679) (xy 403.276344 -311.418567)
			(xy 403.225562 -311.42661) (xy 403.174146 -311.42661) (xy 403.123364 -311.418567) (xy 403.074465 -311.402679)
			(xy 403.028653 -311.379336) (xy 402.987057 -311.349115) (xy 402.950701 -311.312759) (xy 402.92048 -311.271163)
			(xy 402.897137 -311.225351) (xy 402.881249 -311.176452) (xy 402.873206 -311.12567) (xy 402.554528 -311.12567)
			(xy 402.546812 -311.173146) (xy 402.531228 -311.219827) (xy 402.508357 -311.263404) (xy 402.478792 -311.302748)
			(xy 402.443299 -311.33684) (xy 402.402796 -311.364796) (xy 402.358334 -311.385894) (xy 402.311063 -311.399586)
			(xy 402.262208 -311.405518) (xy 402.213033 -311.403537) (xy 402.164814 -311.393693) (xy 402.118798 -311.376241)
			(xy 402.076177 -311.351634) (xy 402.038056 -311.320509) (xy 402.005421 -311.283672) (xy 401.979118 -311.242076)
			(xy 401.959827 -311.1968) (xy 401.94805 -311.149016) (xy 401.94409 -311.099962) (xy 401.627086 -311.099962)
			(xy 401.626582 -311.12567) (xy 401.618539 -311.176452) (xy 401.602651 -311.225351) (xy 401.579308 -311.271163)
			(xy 401.549087 -311.312759) (xy 401.512731 -311.349115) (xy 401.471135 -311.379336) (xy 401.425323 -311.402679)
			(xy 401.376424 -311.418567) (xy 401.325642 -311.42661) (xy 401.274226 -311.42661) (xy 401.223444 -311.418567)
			(xy 401.174545 -311.402679) (xy 401.128733 -311.379336) (xy 401.087137 -311.349115) (xy 401.050781 -311.312759)
			(xy 401.02056 -311.271163) (xy 400.997217 -311.225351) (xy 400.981329 -311.176452) (xy 400.973286 -311.12567)
			(xy 400.654608 -311.12567) (xy 400.646892 -311.173146) (xy 400.631308 -311.219827) (xy 400.608437 -311.263404)
			(xy 400.578872 -311.302748) (xy 400.543379 -311.33684) (xy 400.502876 -311.364796) (xy 400.458414 -311.385894)
			(xy 400.411143 -311.399586) (xy 400.362288 -311.405518) (xy 400.313113 -311.403537) (xy 400.264894 -311.393693)
			(xy 400.218878 -311.376241) (xy 400.176257 -311.351634) (xy 400.138136 -311.320509) (xy 400.105501 -311.283672)
			(xy 400.079198 -311.242076) (xy 400.059907 -311.1968) (xy 400.04813 -311.149016) (xy 400.04417 -311.099962)
			(xy 399.727166 -311.099962) (xy 399.726662 -311.12567) (xy 399.718619 -311.176452) (xy 399.702731 -311.225351)
			(xy 399.679388 -311.271163) (xy 399.649167 -311.312759) (xy 399.612811 -311.349115) (xy 399.571215 -311.379336)
			(xy 399.525403 -311.402679) (xy 399.476504 -311.418567) (xy 399.425722 -311.42661) (xy 399.374306 -311.42661)
			(xy 399.323524 -311.418567) (xy 399.274625 -311.402679) (xy 399.228813 -311.379336) (xy 399.187217 -311.349115)
			(xy 399.150861 -311.312759) (xy 399.12064 -311.271163) (xy 399.097297 -311.225351) (xy 399.081409 -311.176452)
			(xy 399.073366 -311.12567) (xy 398.754434 -311.12567) (xy 398.746718 -311.173146) (xy 398.731134 -311.219827)
			(xy 398.708263 -311.263404) (xy 398.678698 -311.302748) (xy 398.643205 -311.33684) (xy 398.602702 -311.364796)
			(xy 398.55824 -311.385894) (xy 398.510969 -311.399586) (xy 398.462114 -311.405518) (xy 398.412939 -311.403537)
			(xy 398.36472 -311.393693) (xy 398.318704 -311.376241) (xy 398.276083 -311.351634) (xy 398.237962 -311.320509)
			(xy 398.205327 -311.283672) (xy 398.179024 -311.242076) (xy 398.159733 -311.1968) (xy 398.147956 -311.149016)
			(xy 398.143996 -311.099962) (xy 397.805666 -311.099962) (xy 397.805669 -311.1) (xy 397.801498 -311.15034)
			(xy 397.789099 -311.199308) (xy 397.76881 -311.245566) (xy 397.741184 -311.287855) (xy 397.706975 -311.325021)
			(xy 397.667116 -311.356049) (xy 397.622693 -311.380095) (xy 397.574919 -311.396501) (xy 397.525096 -311.404821)
			(xy 397.49984 -311.40527) (xy 397.467836 -311.403492) (xy 397.456914 -311.402476) (xy 397.446754 -311.405778)
			(xy 397.441801 -311.407523) (xy 397.432711 -311.412778) (xy 397.42872 -311.416192) (xy 397.372332 -311.466738)
			(xy 397.368268 -311.470802) (xy 397.363105 -311.477126) (xy 397.356756 -311.492156) (xy 397.355822 -311.500266)
			(xy 397.355822 -311.500774) (xy 397.355568 -311.504584) (xy 397.355568 -311.574942) (xy 397.355407 -311.588596)
			(xy 397.35312 -311.615809) (xy 397.350996 -311.629298) (xy 397.348964 -311.641236) (xy 397.35252 -311.652666)
			(xy 397.354033 -311.657197) (xy 397.358507 -311.665636) (xy 397.36141 -311.66943) (xy 397.364204 -311.672478)
			(xy 397.420592 -311.731406) (xy 397.42482 -311.735639) (xy 397.43483 -311.742187) (xy 397.440404 -311.74436)
			(xy 397.451326 -311.74817) (xy 397.463518 -311.7469) (xy 397.472562 -311.745853) (xy 397.490736 -311.744711)
			(xy 397.49984 -311.744614) (xy 397.525091 -311.745139) (xy 397.574904 -311.753457) (xy 397.622669 -311.76986)
			(xy 397.667083 -311.793901) (xy 397.706934 -311.824923) (xy 397.741137 -311.862082) (xy 397.768757 -311.904362)
			(xy 397.789042 -311.950612) (xy 397.801439 -311.99957) (xy 397.805609 -312.0499) (xy 397.805607 -312.049922)
			(xy 398.143996 -312.049922) (xy 398.147956 -312.000868) (xy 398.159733 -311.953084) (xy 398.179024 -311.907808)
			(xy 398.205327 -311.866212) (xy 398.237962 -311.829375) (xy 398.276083 -311.79825) (xy 398.318704 -311.773643)
			(xy 398.36472 -311.756191) (xy 398.412939 -311.746347) (xy 398.462114 -311.744366) (xy 398.510969 -311.750298)
			(xy 398.55824 -311.76399) (xy 398.602702 -311.785088) (xy 398.643205 -311.813044) (xy 398.678698 -311.847136)
			(xy 398.708263 -311.88648) (xy 398.731134 -311.930057) (xy 398.746718 -311.976738) (xy 398.754613 -312.025315)
			(xy 398.755108 -312.049922) (xy 398.754613 -312.074529) (xy 398.754434 -312.07563) (xy 399.073366 -312.07563)
			(xy 399.073366 -312.024214) (xy 399.081409 -311.973432) (xy 399.097297 -311.924533) (xy 399.12064 -311.878721)
			(xy 399.150861 -311.837125) (xy 399.187217 -311.800769) (xy 399.228813 -311.770548) (xy 399.274625 -311.747205)
			(xy 399.323524 -311.731317) (xy 399.374306 -311.723274) (xy 399.425722 -311.723274) (xy 399.476504 -311.731317)
			(xy 399.525403 -311.747205) (xy 399.571215 -311.770548) (xy 399.612811 -311.800769) (xy 399.649167 -311.837125)
			(xy 399.679388 -311.878721) (xy 399.702731 -311.924533) (xy 399.718619 -311.973432) (xy 399.726662 -312.024214)
			(xy 399.727166 -312.049922) (xy 400.04417 -312.049922) (xy 400.04813 -312.000868) (xy 400.059907 -311.953084)
			(xy 400.079198 -311.907808) (xy 400.105501 -311.866212) (xy 400.138136 -311.829375) (xy 400.176257 -311.79825)
			(xy 400.218878 -311.773643) (xy 400.264894 -311.756191) (xy 400.313113 -311.746347) (xy 400.362288 -311.744366)
			(xy 400.411143 -311.750298) (xy 400.458414 -311.76399) (xy 400.502876 -311.785088) (xy 400.543379 -311.813044)
			(xy 400.578872 -311.847136) (xy 400.608437 -311.88648) (xy 400.631308 -311.930057) (xy 400.646892 -311.976738)
			(xy 400.654787 -312.025315) (xy 400.655282 -312.049922) (xy 400.654787 -312.074529) (xy 400.654608 -312.07563)
			(xy 400.973286 -312.07563) (xy 400.973286 -312.024214) (xy 400.981329 -311.973432) (xy 400.997217 -311.924533)
			(xy 401.02056 -311.878721) (xy 401.050781 -311.837125) (xy 401.087137 -311.800769) (xy 401.128733 -311.770548)
			(xy 401.174545 -311.747205) (xy 401.223444 -311.731317) (xy 401.274226 -311.723274) (xy 401.325642 -311.723274)
			(xy 401.376424 -311.731317) (xy 401.425323 -311.747205) (xy 401.471135 -311.770548) (xy 401.512731 -311.800769)
			(xy 401.549087 -311.837125) (xy 401.579308 -311.878721) (xy 401.602651 -311.924533) (xy 401.618539 -311.973432)
			(xy 401.626582 -312.024214) (xy 401.627086 -312.049922) (xy 401.94409 -312.049922) (xy 401.94805 -312.000868)
			(xy 401.959827 -311.953084) (xy 401.979118 -311.907808) (xy 402.005421 -311.866212) (xy 402.038056 -311.829375)
			(xy 402.076177 -311.79825) (xy 402.118798 -311.773643) (xy 402.164814 -311.756191) (xy 402.213033 -311.746347)
			(xy 402.262208 -311.744366) (xy 402.311063 -311.750298) (xy 402.358334 -311.76399) (xy 402.402796 -311.785088)
			(xy 402.443299 -311.813044) (xy 402.478792 -311.847136) (xy 402.508357 -311.88648) (xy 402.531228 -311.930057)
			(xy 402.546812 -311.976738) (xy 402.554707 -312.025315) (xy 402.555202 -312.049922) (xy 402.554707 -312.074529)
			(xy 402.554528 -312.07563) (xy 402.873206 -312.07563) (xy 402.873206 -312.024214) (xy 402.881249 -311.973432)
			(xy 402.897137 -311.924533) (xy 402.92048 -311.878721) (xy 402.950701 -311.837125) (xy 402.987057 -311.800769)
			(xy 403.028653 -311.770548) (xy 403.074465 -311.747205) (xy 403.123364 -311.731317) (xy 403.174146 -311.723274)
			(xy 403.225562 -311.723274) (xy 403.276344 -311.731317) (xy 403.325243 -311.747205) (xy 403.371055 -311.770548)
			(xy 403.412651 -311.800769) (xy 403.449007 -311.837125) (xy 403.479228 -311.878721) (xy 403.502571 -311.924533)
			(xy 403.518459 -311.973432) (xy 403.526502 -312.024214) (xy 403.527006 -312.049922) (xy 403.84401 -312.049922)
			(xy 403.84797 -312.000868) (xy 403.859747 -311.953084) (xy 403.879038 -311.907808) (xy 403.905341 -311.866212)
			(xy 403.937976 -311.829375) (xy 403.976097 -311.79825) (xy 404.018718 -311.773643) (xy 404.064734 -311.756191)
			(xy 404.112953 -311.746347) (xy 404.162128 -311.744366) (xy 404.210983 -311.750298) (xy 404.258254 -311.76399)
			(xy 404.302716 -311.785088) (xy 404.343219 -311.813044) (xy 404.378712 -311.847136) (xy 404.408277 -311.88648)
			(xy 404.431148 -311.930057) (xy 404.446732 -311.976738) (xy 404.454627 -312.025315) (xy 404.455122 -312.049922)
			(xy 404.454627 -312.074529) (xy 404.454448 -312.07563) (xy 404.77338 -312.07563) (xy 404.77338 -312.024214)
			(xy 404.781423 -311.973432) (xy 404.797311 -311.924533) (xy 404.820654 -311.878721) (xy 404.850875 -311.837125)
			(xy 404.887231 -311.800769) (xy 404.928827 -311.770548) (xy 404.974639 -311.747205) (xy 405.023538 -311.731317)
			(xy 405.07432 -311.723274) (xy 405.125736 -311.723274) (xy 405.176518 -311.731317) (xy 405.225417 -311.747205)
			(xy 405.271229 -311.770548) (xy 405.312825 -311.800769) (xy 405.349181 -311.837125) (xy 405.379402 -311.878721)
			(xy 405.402745 -311.924533) (xy 405.418633 -311.973432) (xy 405.426676 -312.024214) (xy 405.42718 -312.049922)
			(xy 405.744184 -312.049922) (xy 405.748144 -312.000868) (xy 405.759921 -311.953084) (xy 405.779212 -311.907808)
			(xy 405.805515 -311.866212) (xy 405.83815 -311.829375) (xy 405.876271 -311.79825) (xy 405.918892 -311.773643)
			(xy 405.964908 -311.756191) (xy 406.013127 -311.746347) (xy 406.062302 -311.744366) (xy 406.111157 -311.750298)
			(xy 406.158428 -311.76399) (xy 406.20289 -311.785088) (xy 406.243393 -311.813044) (xy 406.278886 -311.847136)
			(xy 406.308451 -311.88648) (xy 406.331322 -311.930057) (xy 406.346906 -311.976738) (xy 406.354801 -312.025315)
			(xy 406.355296 -312.049922) (xy 406.354801 -312.074529) (xy 406.354622 -312.07563) (xy 406.6733 -312.07563)
			(xy 406.6733 -312.024214) (xy 406.681343 -311.973432) (xy 406.697231 -311.924533) (xy 406.720574 -311.878721)
			(xy 406.750795 -311.837125) (xy 406.787151 -311.800769) (xy 406.828747 -311.770548) (xy 406.874559 -311.747205)
			(xy 406.923458 -311.731317) (xy 406.97424 -311.723274) (xy 407.025656 -311.723274) (xy 407.076438 -311.731317)
			(xy 407.125337 -311.747205) (xy 407.171149 -311.770548) (xy 407.212745 -311.800769) (xy 407.249101 -311.837125)
			(xy 407.279322 -311.878721) (xy 407.302665 -311.924533) (xy 407.318553 -311.973432) (xy 407.326596 -312.024214)
			(xy 407.3271 -312.049922) (xy 407.644104 -312.049922) (xy 407.648064 -312.000868) (xy 407.659841 -311.953084)
			(xy 407.679132 -311.907808) (xy 407.705435 -311.866212) (xy 407.73807 -311.829375) (xy 407.776191 -311.79825)
			(xy 407.818812 -311.773643) (xy 407.864828 -311.756191) (xy 407.913047 -311.746347) (xy 407.962222 -311.744366)
			(xy 408.011077 -311.750298) (xy 408.058348 -311.76399) (xy 408.10281 -311.785088) (xy 408.143313 -311.813044)
			(xy 408.178806 -311.847136) (xy 408.208371 -311.88648) (xy 408.231242 -311.930057) (xy 408.246826 -311.976738)
			(xy 408.254721 -312.025315) (xy 408.255216 -312.049922) (xy 408.254721 -312.074529) (xy 408.254542 -312.07563)
			(xy 408.57322 -312.07563) (xy 408.57322 -312.024214) (xy 408.581263 -311.973432) (xy 408.597151 -311.924533)
			(xy 408.620494 -311.878721) (xy 408.650715 -311.837125) (xy 408.687071 -311.800769) (xy 408.728667 -311.770548)
			(xy 408.774479 -311.747205) (xy 408.823378 -311.731317) (xy 408.87416 -311.723274) (xy 408.925576 -311.723274)
			(xy 408.976358 -311.731317) (xy 409.025257 -311.747205) (xy 409.071069 -311.770548) (xy 409.112665 -311.800769)
			(xy 409.149021 -311.837125) (xy 409.179242 -311.878721) (xy 409.202585 -311.924533) (xy 409.218473 -311.973432)
			(xy 409.226516 -312.024214) (xy 409.22702 -312.049922) (xy 409.544024 -312.049922) (xy 409.547984 -312.000868)
			(xy 409.559761 -311.953084) (xy 409.579052 -311.907808) (xy 409.605355 -311.866212) (xy 409.63799 -311.829375)
			(xy 409.676111 -311.79825) (xy 409.718732 -311.773643) (xy 409.764748 -311.756191) (xy 409.812967 -311.746347)
			(xy 409.862142 -311.744366) (xy 409.910997 -311.750298) (xy 409.958268 -311.76399) (xy 410.00273 -311.785088)
			(xy 410.043233 -311.813044) (xy 410.078726 -311.847136) (xy 410.108291 -311.88648) (xy 410.131162 -311.930057)
			(xy 410.146746 -311.976738) (xy 410.154641 -312.025315) (xy 410.155136 -312.049922) (xy 410.154641 -312.074529)
			(xy 410.154462 -312.07563) (xy 410.47314 -312.07563) (xy 410.47314 -312.024214) (xy 410.481183 -311.973432)
			(xy 410.497071 -311.924533) (xy 410.520414 -311.878721) (xy 410.550635 -311.837125) (xy 410.586991 -311.800769)
			(xy 410.628587 -311.770548) (xy 410.674399 -311.747205) (xy 410.723298 -311.731317) (xy 410.77408 -311.723274)
			(xy 410.825496 -311.723274) (xy 410.876278 -311.731317) (xy 410.925177 -311.747205) (xy 410.970989 -311.770548)
			(xy 411.012585 -311.800769) (xy 411.048941 -311.837125) (xy 411.079162 -311.878721) (xy 411.102505 -311.924533)
			(xy 411.118393 -311.973432) (xy 411.126436 -312.024214) (xy 411.12694 -312.049922) (xy 411.444198 -312.049922)
			(xy 411.448158 -312.000868) (xy 411.459935 -311.953084) (xy 411.479226 -311.907808) (xy 411.505529 -311.866212)
			(xy 411.538164 -311.829375) (xy 411.576285 -311.79825) (xy 411.618906 -311.773643) (xy 411.664922 -311.756191)
			(xy 411.713141 -311.746347) (xy 411.762316 -311.744366) (xy 411.811171 -311.750298) (xy 411.858442 -311.76399)
			(xy 411.902904 -311.785088) (xy 411.943407 -311.813044) (xy 411.9789 -311.847136) (xy 412.008465 -311.88648)
			(xy 412.031336 -311.930057) (xy 412.04692 -311.976738) (xy 412.054815 -312.025315) (xy 412.05531 -312.049922)
			(xy 412.054815 -312.074529) (xy 412.054636 -312.07563) (xy 412.373314 -312.07563) (xy 412.373314 -312.024214)
			(xy 412.381357 -311.973432) (xy 412.397245 -311.924533) (xy 412.420588 -311.878721) (xy 412.450809 -311.837125)
			(xy 412.487165 -311.800769) (xy 412.528761 -311.770548) (xy 412.574573 -311.747205) (xy 412.623472 -311.731317)
			(xy 412.674254 -311.723274) (xy 412.72567 -311.723274) (xy 412.776452 -311.731317) (xy 412.825351 -311.747205)
			(xy 412.871163 -311.770548) (xy 412.912759 -311.800769) (xy 412.949115 -311.837125) (xy 412.979336 -311.878721)
			(xy 413.002679 -311.924533) (xy 413.018567 -311.973432) (xy 413.02661 -312.024214) (xy 413.027114 -312.049922)
			(xy 413.344118 -312.049922) (xy 413.348078 -312.000868) (xy 413.359855 -311.953084) (xy 413.379146 -311.907808)
			(xy 413.405449 -311.866212) (xy 413.438084 -311.829375) (xy 413.476205 -311.79825) (xy 413.518826 -311.773643)
			(xy 413.564842 -311.756191) (xy 413.613061 -311.746347) (xy 413.662236 -311.744366) (xy 413.711091 -311.750298)
			(xy 413.758362 -311.76399) (xy 413.802824 -311.785088) (xy 413.843327 -311.813044) (xy 413.87882 -311.847136)
			(xy 413.908385 -311.88648) (xy 413.931256 -311.930057) (xy 413.94684 -311.976738) (xy 413.954735 -312.025315)
			(xy 413.95523 -312.049922) (xy 414.294078 -312.049922) (xy 414.298038 -312.000868) (xy 414.309815 -311.953084)
			(xy 414.329106 -311.907808) (xy 414.355409 -311.866212) (xy 414.388044 -311.829375) (xy 414.426165 -311.79825)
			(xy 414.468786 -311.773643) (xy 414.514802 -311.756191) (xy 414.563021 -311.746347) (xy 414.612196 -311.744366)
			(xy 414.661051 -311.750298) (xy 414.708322 -311.76399) (xy 414.752784 -311.785088) (xy 414.793287 -311.813044)
			(xy 414.82878 -311.847136) (xy 414.858345 -311.88648) (xy 414.881216 -311.930057) (xy 414.8968 -311.976738)
			(xy 414.904695 -312.025315) (xy 414.90519 -312.049922) (xy 415.244038 -312.049922) (xy 415.247998 -312.000868)
			(xy 415.259775 -311.953084) (xy 415.279066 -311.907808) (xy 415.305369 -311.866212) (xy 415.338004 -311.829375)
			(xy 415.376125 -311.79825) (xy 415.418746 -311.773643) (xy 415.464762 -311.756191) (xy 415.512981 -311.746347)
			(xy 415.562156 -311.744366) (xy 415.611011 -311.750298) (xy 415.658282 -311.76399) (xy 415.702744 -311.785088)
			(xy 415.743247 -311.813044) (xy 415.77874 -311.847136) (xy 415.808305 -311.88648) (xy 415.831176 -311.930057)
			(xy 415.84676 -311.976738) (xy 415.854655 -312.025315) (xy 415.85515 -312.049922) (xy 416.193998 -312.049922)
			(xy 416.197958 -312.000868) (xy 416.209735 -311.953084) (xy 416.229026 -311.907808) (xy 416.255329 -311.866212)
			(xy 416.287964 -311.829375) (xy 416.326085 -311.79825) (xy 416.368706 -311.773643) (xy 416.414722 -311.756191)
			(xy 416.462941 -311.746347) (xy 416.512116 -311.744366) (xy 416.560971 -311.750298) (xy 416.608242 -311.76399)
			(xy 416.652704 -311.785088) (xy 416.693207 -311.813044) (xy 416.7287 -311.847136) (xy 416.758265 -311.88648)
			(xy 416.781136 -311.930057) (xy 416.79672 -311.976738) (xy 416.804615 -312.025315) (xy 416.80511 -312.049922)
			(xy 417.144212 -312.049922) (xy 417.148172 -312.000868) (xy 417.159949 -311.953084) (xy 417.17924 -311.907808)
			(xy 417.205543 -311.866212) (xy 417.238178 -311.829375) (xy 417.276299 -311.79825) (xy 417.31892 -311.773643)
			(xy 417.364936 -311.756191) (xy 417.413155 -311.746347) (xy 417.46233 -311.744366) (xy 417.511185 -311.750298)
			(xy 417.558456 -311.76399) (xy 417.602918 -311.785088) (xy 417.643421 -311.813044) (xy 417.678914 -311.847136)
			(xy 417.708479 -311.88648) (xy 417.73135 -311.930057) (xy 417.746934 -311.976738) (xy 417.754829 -312.025315)
			(xy 417.755324 -312.049922) (xy 418.094172 -312.049922) (xy 418.098132 -312.000868) (xy 418.109909 -311.953084)
			(xy 418.1292 -311.907808) (xy 418.155503 -311.866212) (xy 418.188138 -311.829375) (xy 418.226259 -311.79825)
			(xy 418.26888 -311.773643) (xy 418.314896 -311.756191) (xy 418.363115 -311.746347) (xy 418.41229 -311.744366)
			(xy 418.461145 -311.750298) (xy 418.508416 -311.76399) (xy 418.552878 -311.785088) (xy 418.593381 -311.813044)
			(xy 418.628874 -311.847136) (xy 418.658439 -311.88648) (xy 418.68131 -311.930057) (xy 418.696894 -311.976738)
			(xy 418.704789 -312.025315) (xy 418.705284 -312.049922) (xy 419.044132 -312.049922) (xy 419.048092 -312.000868)
			(xy 419.059869 -311.953084) (xy 419.07916 -311.907808) (xy 419.105463 -311.866212) (xy 419.138098 -311.829375)
			(xy 419.176219 -311.79825) (xy 419.21884 -311.773643) (xy 419.264856 -311.756191) (xy 419.313075 -311.746347)
			(xy 419.36225 -311.744366) (xy 419.411105 -311.750298) (xy 419.458376 -311.76399) (xy 419.502838 -311.785088)
			(xy 419.543341 -311.813044) (xy 419.578834 -311.847136) (xy 419.608399 -311.88648) (xy 419.63127 -311.930057)
			(xy 419.646854 -311.976738) (xy 419.654749 -312.025315) (xy 419.655244 -312.049922) (xy 419.994092 -312.049922)
			(xy 419.998052 -312.000868) (xy 420.009829 -311.953084) (xy 420.02912 -311.907808) (xy 420.055423 -311.866212)
			(xy 420.088058 -311.829375) (xy 420.126179 -311.79825) (xy 420.1688 -311.773643) (xy 420.214816 -311.756191)
			(xy 420.263035 -311.746347) (xy 420.31221 -311.744366) (xy 420.361065 -311.750298) (xy 420.408336 -311.76399)
			(xy 420.452798 -311.785088) (xy 420.493301 -311.813044) (xy 420.528794 -311.847136) (xy 420.558359 -311.88648)
			(xy 420.58123 -311.930057) (xy 420.596814 -311.976738) (xy 420.604709 -312.025315) (xy 420.605204 -312.049922)
			(xy 420.944052 -312.049922) (xy 420.948012 -312.000868) (xy 420.959789 -311.953084) (xy 420.97908 -311.907808)
			(xy 421.005383 -311.866212) (xy 421.038018 -311.829375) (xy 421.076139 -311.79825) (xy 421.11876 -311.773643)
			(xy 421.164776 -311.756191) (xy 421.212995 -311.746347) (xy 421.26217 -311.744366) (xy 421.311025 -311.750298)
			(xy 421.358296 -311.76399) (xy 421.402758 -311.785088) (xy 421.443261 -311.813044) (xy 421.478754 -311.847136)
			(xy 421.508319 -311.88648) (xy 421.53119 -311.930057) (xy 421.546774 -311.976738) (xy 421.554669 -312.025315)
			(xy 421.555164 -312.049922) (xy 421.554669 -312.074529) (xy 421.55449 -312.07563) (xy 421.873168 -312.07563)
			(xy 421.873168 -312.024214) (xy 421.881211 -311.973432) (xy 421.897099 -311.924533) (xy 421.920442 -311.878721)
			(xy 421.950663 -311.837125) (xy 421.987019 -311.800769) (xy 422.028615 -311.770548) (xy 422.074427 -311.747205)
			(xy 422.123326 -311.731317) (xy 422.174108 -311.723274) (xy 422.225524 -311.723274) (xy 422.276306 -311.731317)
			(xy 422.325205 -311.747205) (xy 422.371017 -311.770548) (xy 422.412613 -311.800769) (xy 422.448969 -311.837125)
			(xy 422.47919 -311.878721) (xy 422.502533 -311.924533) (xy 422.518421 -311.973432) (xy 422.526464 -312.024214)
			(xy 422.526968 -312.049922) (xy 422.844226 -312.049922) (xy 422.848186 -312.000868) (xy 422.859963 -311.953084)
			(xy 422.879254 -311.907808) (xy 422.905557 -311.866212) (xy 422.938192 -311.829375) (xy 422.976313 -311.79825)
			(xy 423.018934 -311.773643) (xy 423.06495 -311.756191) (xy 423.113169 -311.746347) (xy 423.162344 -311.744366)
			(xy 423.211199 -311.750298) (xy 423.25847 -311.76399) (xy 423.302932 -311.785088) (xy 423.343435 -311.813044)
			(xy 423.378928 -311.847136) (xy 423.408493 -311.88648) (xy 423.431364 -311.930057) (xy 423.446948 -311.976738)
			(xy 423.454843 -312.025315) (xy 423.455338 -312.049922) (xy 423.454843 -312.074529) (xy 423.454664 -312.07563)
			(xy 423.773342 -312.07563) (xy 423.773342 -312.024214) (xy 423.781385 -311.973432) (xy 423.797273 -311.924533)
			(xy 423.820616 -311.878721) (xy 423.850837 -311.837125) (xy 423.887193 -311.800769) (xy 423.928789 -311.770548)
			(xy 423.974601 -311.747205) (xy 424.0235 -311.731317) (xy 424.074282 -311.723274) (xy 424.125698 -311.723274)
			(xy 424.17648 -311.731317) (xy 424.225379 -311.747205) (xy 424.271191 -311.770548) (xy 424.312787 -311.800769)
			(xy 424.349143 -311.837125) (xy 424.379364 -311.878721) (xy 424.402707 -311.924533) (xy 424.418595 -311.973432)
			(xy 424.426638 -312.024214) (xy 424.427142 -312.049922) (xy 424.744146 -312.049922) (xy 424.748106 -312.000868)
			(xy 424.759883 -311.953084) (xy 424.779174 -311.907808) (xy 424.805477 -311.866212) (xy 424.838112 -311.829375)
			(xy 424.876233 -311.79825) (xy 424.918854 -311.773643) (xy 424.96487 -311.756191) (xy 425.013089 -311.746347)
			(xy 425.062264 -311.744366) (xy 425.111119 -311.750298) (xy 425.15839 -311.76399) (xy 425.202852 -311.785088)
			(xy 425.243355 -311.813044) (xy 425.278848 -311.847136) (xy 425.308413 -311.88648) (xy 425.331284 -311.930057)
			(xy 425.346868 -311.976738) (xy 425.354763 -312.025315) (xy 425.355258 -312.049922) (xy 425.354763 -312.074529)
			(xy 425.354584 -312.07563) (xy 425.673262 -312.07563) (xy 425.673262 -312.024214) (xy 425.681305 -311.973432)
			(xy 425.697193 -311.924533) (xy 425.720536 -311.878721) (xy 425.750757 -311.837125) (xy 425.787113 -311.800769)
			(xy 425.828709 -311.770548) (xy 425.874521 -311.747205) (xy 425.92342 -311.731317) (xy 425.974202 -311.723274)
			(xy 426.025618 -311.723274) (xy 426.0764 -311.731317) (xy 426.125299 -311.747205) (xy 426.171111 -311.770548)
			(xy 426.212707 -311.800769) (xy 426.249063 -311.837125) (xy 426.279284 -311.878721) (xy 426.302627 -311.924533)
			(xy 426.318515 -311.973432) (xy 426.326558 -312.024214) (xy 426.327062 -312.049922) (xy 426.644066 -312.049922)
			(xy 426.648026 -312.000868) (xy 426.659803 -311.953084) (xy 426.679094 -311.907808) (xy 426.705397 -311.866212)
			(xy 426.738032 -311.829375) (xy 426.776153 -311.79825) (xy 426.818774 -311.773643) (xy 426.86479 -311.756191)
			(xy 426.913009 -311.746347) (xy 426.962184 -311.744366) (xy 427.011039 -311.750298) (xy 427.05831 -311.76399)
			(xy 427.102772 -311.785088) (xy 427.143275 -311.813044) (xy 427.178768 -311.847136) (xy 427.208333 -311.88648)
			(xy 427.231204 -311.930057) (xy 427.246788 -311.976738) (xy 427.254683 -312.025315) (xy 427.255178 -312.049922)
			(xy 427.254683 -312.074529) (xy 427.254504 -312.07563) (xy 427.573182 -312.07563) (xy 427.573182 -312.024214)
			(xy 427.581225 -311.973432) (xy 427.597113 -311.924533) (xy 427.620456 -311.878721) (xy 427.650677 -311.837125)
			(xy 427.687033 -311.800769) (xy 427.728629 -311.770548) (xy 427.774441 -311.747205) (xy 427.82334 -311.731317)
			(xy 427.874122 -311.723274) (xy 427.925538 -311.723274) (xy 427.97632 -311.731317) (xy 428.025219 -311.747205)
			(xy 428.071031 -311.770548) (xy 428.112627 -311.800769) (xy 428.148983 -311.837125) (xy 428.179204 -311.878721)
			(xy 428.202547 -311.924533) (xy 428.218435 -311.973432) (xy 428.226478 -312.024214) (xy 428.226982 -312.049922)
			(xy 428.543986 -312.049922) (xy 428.547946 -312.000868) (xy 428.559723 -311.953084) (xy 428.579014 -311.907808)
			(xy 428.605317 -311.866212) (xy 428.637952 -311.829375) (xy 428.676073 -311.79825) (xy 428.718694 -311.773643)
			(xy 428.76471 -311.756191) (xy 428.812929 -311.746347) (xy 428.862104 -311.744366) (xy 428.910959 -311.750298)
			(xy 428.95823 -311.76399) (xy 429.002692 -311.785088) (xy 429.043195 -311.813044) (xy 429.078688 -311.847136)
			(xy 429.108253 -311.88648) (xy 429.131124 -311.930057) (xy 429.146708 -311.976738) (xy 429.154603 -312.025315)
			(xy 429.155098 -312.049922) (xy 429.154603 -312.074529) (xy 429.154424 -312.07563) (xy 429.473356 -312.07563)
			(xy 429.473356 -312.024214) (xy 429.481399 -311.973432) (xy 429.497287 -311.924533) (xy 429.52063 -311.878721)
			(xy 429.550851 -311.837125) (xy 429.587207 -311.800769) (xy 429.628803 -311.770548) (xy 429.674615 -311.747205)
			(xy 429.723514 -311.731317) (xy 429.774296 -311.723274) (xy 429.825712 -311.723274) (xy 429.876494 -311.731317)
			(xy 429.925393 -311.747205) (xy 429.971205 -311.770548) (xy 430.012801 -311.800769) (xy 430.049157 -311.837125)
			(xy 430.079378 -311.878721) (xy 430.102721 -311.924533) (xy 430.118609 -311.973432) (xy 430.126652 -312.024214)
			(xy 430.127156 -312.049922) (xy 430.126652 -312.07563) (xy 430.423316 -312.07563) (xy 430.423316 -312.024214)
			(xy 430.431359 -311.973432) (xy 430.447247 -311.924533) (xy 430.47059 -311.878721) (xy 430.500811 -311.837125)
			(xy 430.537167 -311.800769) (xy 430.578763 -311.770548) (xy 430.624575 -311.747205) (xy 430.673474 -311.731317)
			(xy 430.724256 -311.723274) (xy 430.775672 -311.723274) (xy 430.826454 -311.731317) (xy 430.875353 -311.747205)
			(xy 430.921165 -311.770548) (xy 430.962761 -311.800769) (xy 430.999117 -311.837125) (xy 431.029338 -311.878721)
			(xy 431.052681 -311.924533) (xy 431.068569 -311.973432) (xy 431.076612 -312.024214) (xy 431.077116 -312.049922)
			(xy 431.394374 -312.049922) (xy 431.398334 -312.000868) (xy 431.410111 -311.953084) (xy 431.429402 -311.907808)
			(xy 431.455705 -311.866212) (xy 431.48834 -311.829375) (xy 431.526461 -311.79825) (xy 431.569082 -311.773643)
			(xy 431.615098 -311.756191) (xy 431.663317 -311.746347) (xy 431.712492 -311.744366) (xy 431.761347 -311.750298)
			(xy 431.808618 -311.76399) (xy 431.85308 -311.785088) (xy 431.893583 -311.813044) (xy 431.929076 -311.847136)
			(xy 431.958641 -311.88648) (xy 431.981512 -311.930057) (xy 431.997096 -311.976738) (xy 432.004991 -312.025315)
			(xy 432.005486 -312.049922) (xy 432.004991 -312.074529) (xy 431.997096 -312.123106) (xy 431.981512 -312.169787)
			(xy 431.958641 -312.213364) (xy 431.929076 -312.252708) (xy 431.893583 -312.2868) (xy 431.85308 -312.314756)
			(xy 431.808618 -312.335854) (xy 431.761347 -312.349546) (xy 431.712492 -312.355478) (xy 431.663317 -312.353497)
			(xy 431.615098 -312.343653) (xy 431.569082 -312.326201) (xy 431.526461 -312.301594) (xy 431.48834 -312.270469)
			(xy 431.455705 -312.233632) (xy 431.429402 -312.192036) (xy 431.410111 -312.14676) (xy 431.398334 -312.098976)
			(xy 431.394374 -312.049922) (xy 431.077116 -312.049922) (xy 431.076612 -312.07563) (xy 431.068569 -312.126412)
			(xy 431.052681 -312.175311) (xy 431.029338 -312.221123) (xy 430.999117 -312.262719) (xy 430.962761 -312.299075)
			(xy 430.921165 -312.329296) (xy 430.875353 -312.352639) (xy 430.826454 -312.368527) (xy 430.775672 -312.37657)
			(xy 430.724256 -312.37657) (xy 430.673474 -312.368527) (xy 430.624575 -312.352639) (xy 430.578763 -312.329296)
			(xy 430.537167 -312.299075) (xy 430.500811 -312.262719) (xy 430.47059 -312.221123) (xy 430.447247 -312.175311)
			(xy 430.431359 -312.126412) (xy 430.423316 -312.07563) (xy 430.126652 -312.07563) (xy 430.118609 -312.126412)
			(xy 430.102721 -312.175311) (xy 430.079378 -312.221123) (xy 430.049157 -312.262719) (xy 430.012801 -312.299075)
			(xy 429.971205 -312.329296) (xy 429.925393 -312.352639) (xy 429.876494 -312.368527) (xy 429.825712 -312.37657)
			(xy 429.774296 -312.37657) (xy 429.723514 -312.368527) (xy 429.674615 -312.352639) (xy 429.628803 -312.329296)
			(xy 429.587207 -312.299075) (xy 429.550851 -312.262719) (xy 429.52063 -312.221123) (xy 429.497287 -312.175311)
			(xy 429.481399 -312.126412) (xy 429.473356 -312.07563) (xy 429.154424 -312.07563) (xy 429.146708 -312.123106)
			(xy 429.131124 -312.169787) (xy 429.108253 -312.213364) (xy 429.078688 -312.252708) (xy 429.043195 -312.2868)
			(xy 429.002692 -312.314756) (xy 428.95823 -312.335854) (xy 428.910959 -312.349546) (xy 428.862104 -312.355478)
			(xy 428.812929 -312.353497) (xy 428.76471 -312.343653) (xy 428.718694 -312.326201) (xy 428.676073 -312.301594)
			(xy 428.637952 -312.270469) (xy 428.605317 -312.233632) (xy 428.579014 -312.192036) (xy 428.559723 -312.14676)
			(xy 428.547946 -312.098976) (xy 428.543986 -312.049922) (xy 428.226982 -312.049922) (xy 428.226478 -312.07563)
			(xy 428.218435 -312.126412) (xy 428.202547 -312.175311) (xy 428.179204 -312.221123) (xy 428.148983 -312.262719)
			(xy 428.112627 -312.299075) (xy 428.071031 -312.329296) (xy 428.025219 -312.352639) (xy 427.97632 -312.368527)
			(xy 427.925538 -312.37657) (xy 427.874122 -312.37657) (xy 427.82334 -312.368527) (xy 427.774441 -312.352639)
			(xy 427.728629 -312.329296) (xy 427.687033 -312.299075) (xy 427.650677 -312.262719) (xy 427.620456 -312.221123)
			(xy 427.597113 -312.175311) (xy 427.581225 -312.126412) (xy 427.573182 -312.07563) (xy 427.254504 -312.07563)
			(xy 427.246788 -312.123106) (xy 427.231204 -312.169787) (xy 427.208333 -312.213364) (xy 427.178768 -312.252708)
			(xy 427.143275 -312.2868) (xy 427.102772 -312.314756) (xy 427.05831 -312.335854) (xy 427.011039 -312.349546)
			(xy 426.962184 -312.355478) (xy 426.913009 -312.353497) (xy 426.86479 -312.343653) (xy 426.818774 -312.326201)
			(xy 426.776153 -312.301594) (xy 426.738032 -312.270469) (xy 426.705397 -312.233632) (xy 426.679094 -312.192036)
			(xy 426.659803 -312.14676) (xy 426.648026 -312.098976) (xy 426.644066 -312.049922) (xy 426.327062 -312.049922)
			(xy 426.326558 -312.07563) (xy 426.318515 -312.126412) (xy 426.302627 -312.175311) (xy 426.279284 -312.221123)
			(xy 426.249063 -312.262719) (xy 426.212707 -312.299075) (xy 426.171111 -312.329296) (xy 426.125299 -312.352639)
			(xy 426.0764 -312.368527) (xy 426.025618 -312.37657) (xy 425.974202 -312.37657) (xy 425.92342 -312.368527)
			(xy 425.874521 -312.352639) (xy 425.828709 -312.329296) (xy 425.787113 -312.299075) (xy 425.750757 -312.262719)
			(xy 425.720536 -312.221123) (xy 425.697193 -312.175311) (xy 425.681305 -312.126412) (xy 425.673262 -312.07563)
			(xy 425.354584 -312.07563) (xy 425.346868 -312.123106) (xy 425.331284 -312.169787) (xy 425.308413 -312.213364)
			(xy 425.278848 -312.252708) (xy 425.243355 -312.2868) (xy 425.202852 -312.314756) (xy 425.15839 -312.335854)
			(xy 425.111119 -312.349546) (xy 425.062264 -312.355478) (xy 425.013089 -312.353497) (xy 424.96487 -312.343653)
			(xy 424.918854 -312.326201) (xy 424.876233 -312.301594) (xy 424.838112 -312.270469) (xy 424.805477 -312.233632)
			(xy 424.779174 -312.192036) (xy 424.759883 -312.14676) (xy 424.748106 -312.098976) (xy 424.744146 -312.049922)
			(xy 424.427142 -312.049922) (xy 424.426638 -312.07563) (xy 424.418595 -312.126412) (xy 424.402707 -312.175311)
			(xy 424.379364 -312.221123) (xy 424.349143 -312.262719) (xy 424.312787 -312.299075) (xy 424.271191 -312.329296)
			(xy 424.225379 -312.352639) (xy 424.17648 -312.368527) (xy 424.125698 -312.37657) (xy 424.074282 -312.37657)
			(xy 424.0235 -312.368527) (xy 423.974601 -312.352639) (xy 423.928789 -312.329296) (xy 423.887193 -312.299075)
			(xy 423.850837 -312.262719) (xy 423.820616 -312.221123) (xy 423.797273 -312.175311) (xy 423.781385 -312.126412)
			(xy 423.773342 -312.07563) (xy 423.454664 -312.07563) (xy 423.446948 -312.123106) (xy 423.431364 -312.169787)
			(xy 423.408493 -312.213364) (xy 423.378928 -312.252708) (xy 423.343435 -312.2868) (xy 423.302932 -312.314756)
			(xy 423.25847 -312.335854) (xy 423.211199 -312.349546) (xy 423.162344 -312.355478) (xy 423.113169 -312.353497)
			(xy 423.06495 -312.343653) (xy 423.018934 -312.326201) (xy 422.976313 -312.301594) (xy 422.938192 -312.270469)
			(xy 422.905557 -312.233632) (xy 422.879254 -312.192036) (xy 422.859963 -312.14676) (xy 422.848186 -312.098976)
			(xy 422.844226 -312.049922) (xy 422.526968 -312.049922) (xy 422.526464 -312.07563) (xy 422.518421 -312.126412)
			(xy 422.502533 -312.175311) (xy 422.47919 -312.221123) (xy 422.448969 -312.262719) (xy 422.412613 -312.299075)
			(xy 422.371017 -312.329296) (xy 422.325205 -312.352639) (xy 422.276306 -312.368527) (xy 422.225524 -312.37657)
			(xy 422.174108 -312.37657) (xy 422.123326 -312.368527) (xy 422.074427 -312.352639) (xy 422.028615 -312.329296)
			(xy 421.987019 -312.299075) (xy 421.950663 -312.262719) (xy 421.920442 -312.221123) (xy 421.897099 -312.175311)
			(xy 421.881211 -312.126412) (xy 421.873168 -312.07563) (xy 421.55449 -312.07563) (xy 421.546774 -312.123106)
			(xy 421.53119 -312.169787) (xy 421.508319 -312.213364) (xy 421.478754 -312.252708) (xy 421.443261 -312.2868)
			(xy 421.402758 -312.314756) (xy 421.358296 -312.335854) (xy 421.311025 -312.349546) (xy 421.26217 -312.355478)
			(xy 421.212995 -312.353497) (xy 421.164776 -312.343653) (xy 421.11876 -312.326201) (xy 421.076139 -312.301594)
			(xy 421.038018 -312.270469) (xy 421.005383 -312.233632) (xy 420.97908 -312.192036) (xy 420.959789 -312.14676)
			(xy 420.948012 -312.098976) (xy 420.944052 -312.049922) (xy 420.605204 -312.049922) (xy 420.604709 -312.074529)
			(xy 420.596814 -312.123106) (xy 420.58123 -312.169787) (xy 420.558359 -312.213364) (xy 420.528794 -312.252708)
			(xy 420.493301 -312.2868) (xy 420.452798 -312.314756) (xy 420.408336 -312.335854) (xy 420.361065 -312.349546)
			(xy 420.31221 -312.355478) (xy 420.263035 -312.353497) (xy 420.214816 -312.343653) (xy 420.1688 -312.326201)
			(xy 420.126179 -312.301594) (xy 420.088058 -312.270469) (xy 420.055423 -312.233632) (xy 420.02912 -312.192036)
			(xy 420.009829 -312.14676) (xy 419.998052 -312.098976) (xy 419.994092 -312.049922) (xy 419.655244 -312.049922)
			(xy 419.654749 -312.074529) (xy 419.646854 -312.123106) (xy 419.63127 -312.169787) (xy 419.608399 -312.213364)
			(xy 419.578834 -312.252708) (xy 419.543341 -312.2868) (xy 419.502838 -312.314756) (xy 419.458376 -312.335854)
			(xy 419.411105 -312.349546) (xy 419.36225 -312.355478) (xy 419.313075 -312.353497) (xy 419.264856 -312.343653)
			(xy 419.21884 -312.326201) (xy 419.176219 -312.301594) (xy 419.138098 -312.270469) (xy 419.105463 -312.233632)
			(xy 419.07916 -312.192036) (xy 419.059869 -312.14676) (xy 419.048092 -312.098976) (xy 419.044132 -312.049922)
			(xy 418.705284 -312.049922) (xy 418.704789 -312.074529) (xy 418.696894 -312.123106) (xy 418.68131 -312.169787)
			(xy 418.658439 -312.213364) (xy 418.628874 -312.252708) (xy 418.593381 -312.2868) (xy 418.552878 -312.314756)
			(xy 418.508416 -312.335854) (xy 418.461145 -312.349546) (xy 418.41229 -312.355478) (xy 418.363115 -312.353497)
			(xy 418.314896 -312.343653) (xy 418.26888 -312.326201) (xy 418.226259 -312.301594) (xy 418.188138 -312.270469)
			(xy 418.155503 -312.233632) (xy 418.1292 -312.192036) (xy 418.109909 -312.14676) (xy 418.098132 -312.098976)
			(xy 418.094172 -312.049922) (xy 417.755324 -312.049922) (xy 417.754829 -312.074529) (xy 417.746934 -312.123106)
			(xy 417.73135 -312.169787) (xy 417.708479 -312.213364) (xy 417.678914 -312.252708) (xy 417.643421 -312.2868)
			(xy 417.602918 -312.314756) (xy 417.558456 -312.335854) (xy 417.511185 -312.349546) (xy 417.46233 -312.355478)
			(xy 417.413155 -312.353497) (xy 417.364936 -312.343653) (xy 417.31892 -312.326201) (xy 417.276299 -312.301594)
			(xy 417.238178 -312.270469) (xy 417.205543 -312.233632) (xy 417.17924 -312.192036) (xy 417.159949 -312.14676)
			(xy 417.148172 -312.098976) (xy 417.144212 -312.049922) (xy 416.80511 -312.049922) (xy 416.804615 -312.074529)
			(xy 416.79672 -312.123106) (xy 416.781136 -312.169787) (xy 416.758265 -312.213364) (xy 416.7287 -312.252708)
			(xy 416.693207 -312.2868) (xy 416.652704 -312.314756) (xy 416.608242 -312.335854) (xy 416.560971 -312.349546)
			(xy 416.512116 -312.355478) (xy 416.462941 -312.353497) (xy 416.414722 -312.343653) (xy 416.368706 -312.326201)
			(xy 416.326085 -312.301594) (xy 416.287964 -312.270469) (xy 416.255329 -312.233632) (xy 416.229026 -312.192036)
			(xy 416.209735 -312.14676) (xy 416.197958 -312.098976) (xy 416.193998 -312.049922) (xy 415.85515 -312.049922)
			(xy 415.854655 -312.074529) (xy 415.84676 -312.123106) (xy 415.831176 -312.169787) (xy 415.808305 -312.213364)
			(xy 415.77874 -312.252708) (xy 415.743247 -312.2868) (xy 415.702744 -312.314756) (xy 415.658282 -312.335854)
			(xy 415.611011 -312.349546) (xy 415.562156 -312.355478) (xy 415.512981 -312.353497) (xy 415.464762 -312.343653)
			(xy 415.418746 -312.326201) (xy 415.376125 -312.301594) (xy 415.338004 -312.270469) (xy 415.305369 -312.233632)
			(xy 415.279066 -312.192036) (xy 415.259775 -312.14676) (xy 415.247998 -312.098976) (xy 415.244038 -312.049922)
			(xy 414.90519 -312.049922) (xy 414.904695 -312.074529) (xy 414.8968 -312.123106) (xy 414.881216 -312.169787)
			(xy 414.858345 -312.213364) (xy 414.82878 -312.252708) (xy 414.793287 -312.2868) (xy 414.752784 -312.314756)
			(xy 414.708322 -312.335854) (xy 414.661051 -312.349546) (xy 414.612196 -312.355478) (xy 414.563021 -312.353497)
			(xy 414.514802 -312.343653) (xy 414.468786 -312.326201) (xy 414.426165 -312.301594) (xy 414.388044 -312.270469)
			(xy 414.355409 -312.233632) (xy 414.329106 -312.192036) (xy 414.309815 -312.14676) (xy 414.298038 -312.098976)
			(xy 414.294078 -312.049922) (xy 413.95523 -312.049922) (xy 413.954735 -312.074529) (xy 413.94684 -312.123106)
			(xy 413.931256 -312.169787) (xy 413.908385 -312.213364) (xy 413.87882 -312.252708) (xy 413.843327 -312.2868)
			(xy 413.802824 -312.314756) (xy 413.758362 -312.335854) (xy 413.711091 -312.349546) (xy 413.662236 -312.355478)
			(xy 413.613061 -312.353497) (xy 413.564842 -312.343653) (xy 413.518826 -312.326201) (xy 413.476205 -312.301594)
			(xy 413.438084 -312.270469) (xy 413.405449 -312.233632) (xy 413.379146 -312.192036) (xy 413.359855 -312.14676)
			(xy 413.348078 -312.098976) (xy 413.344118 -312.049922) (xy 413.027114 -312.049922) (xy 413.02661 -312.07563)
			(xy 413.018567 -312.126412) (xy 413.002679 -312.175311) (xy 412.979336 -312.221123) (xy 412.949115 -312.262719)
			(xy 412.912759 -312.299075) (xy 412.871163 -312.329296) (xy 412.825351 -312.352639) (xy 412.776452 -312.368527)
			(xy 412.72567 -312.37657) (xy 412.674254 -312.37657) (xy 412.623472 -312.368527) (xy 412.574573 -312.352639)
			(xy 412.528761 -312.329296) (xy 412.487165 -312.299075) (xy 412.450809 -312.262719) (xy 412.420588 -312.221123)
			(xy 412.397245 -312.175311) (xy 412.381357 -312.126412) (xy 412.373314 -312.07563) (xy 412.054636 -312.07563)
			(xy 412.04692 -312.123106) (xy 412.031336 -312.169787) (xy 412.008465 -312.213364) (xy 411.9789 -312.252708)
			(xy 411.943407 -312.2868) (xy 411.902904 -312.314756) (xy 411.858442 -312.335854) (xy 411.811171 -312.349546)
			(xy 411.762316 -312.355478) (xy 411.713141 -312.353497) (xy 411.664922 -312.343653) (xy 411.618906 -312.326201)
			(xy 411.576285 -312.301594) (xy 411.538164 -312.270469) (xy 411.505529 -312.233632) (xy 411.479226 -312.192036)
			(xy 411.459935 -312.14676) (xy 411.448158 -312.098976) (xy 411.444198 -312.049922) (xy 411.12694 -312.049922)
			(xy 411.126436 -312.07563) (xy 411.118393 -312.126412) (xy 411.102505 -312.175311) (xy 411.079162 -312.221123)
			(xy 411.048941 -312.262719) (xy 411.012585 -312.299075) (xy 410.970989 -312.329296) (xy 410.925177 -312.352639)
			(xy 410.876278 -312.368527) (xy 410.825496 -312.37657) (xy 410.77408 -312.37657) (xy 410.723298 -312.368527)
			(xy 410.674399 -312.352639) (xy 410.628587 -312.329296) (xy 410.586991 -312.299075) (xy 410.550635 -312.262719)
			(xy 410.520414 -312.221123) (xy 410.497071 -312.175311) (xy 410.481183 -312.126412) (xy 410.47314 -312.07563)
			(xy 410.154462 -312.07563) (xy 410.146746 -312.123106) (xy 410.131162 -312.169787) (xy 410.108291 -312.213364)
			(xy 410.078726 -312.252708) (xy 410.043233 -312.2868) (xy 410.00273 -312.314756) (xy 409.958268 -312.335854)
			(xy 409.910997 -312.349546) (xy 409.862142 -312.355478) (xy 409.812967 -312.353497) (xy 409.764748 -312.343653)
			(xy 409.718732 -312.326201) (xy 409.676111 -312.301594) (xy 409.63799 -312.270469) (xy 409.605355 -312.233632)
			(xy 409.579052 -312.192036) (xy 409.559761 -312.14676) (xy 409.547984 -312.098976) (xy 409.544024 -312.049922)
			(xy 409.22702 -312.049922) (xy 409.226516 -312.07563) (xy 409.218473 -312.126412) (xy 409.202585 -312.175311)
			(xy 409.179242 -312.221123) (xy 409.149021 -312.262719) (xy 409.112665 -312.299075) (xy 409.071069 -312.329296)
			(xy 409.025257 -312.352639) (xy 408.976358 -312.368527) (xy 408.925576 -312.37657) (xy 408.87416 -312.37657)
			(xy 408.823378 -312.368527) (xy 408.774479 -312.352639) (xy 408.728667 -312.329296) (xy 408.687071 -312.299075)
			(xy 408.650715 -312.262719) (xy 408.620494 -312.221123) (xy 408.597151 -312.175311) (xy 408.581263 -312.126412)
			(xy 408.57322 -312.07563) (xy 408.254542 -312.07563) (xy 408.246826 -312.123106) (xy 408.231242 -312.169787)
			(xy 408.208371 -312.213364) (xy 408.178806 -312.252708) (xy 408.143313 -312.2868) (xy 408.10281 -312.314756)
			(xy 408.058348 -312.335854) (xy 408.011077 -312.349546) (xy 407.962222 -312.355478) (xy 407.913047 -312.353497)
			(xy 407.864828 -312.343653) (xy 407.818812 -312.326201) (xy 407.776191 -312.301594) (xy 407.73807 -312.270469)
			(xy 407.705435 -312.233632) (xy 407.679132 -312.192036) (xy 407.659841 -312.14676) (xy 407.648064 -312.098976)
			(xy 407.644104 -312.049922) (xy 407.3271 -312.049922) (xy 407.326596 -312.07563) (xy 407.318553 -312.126412)
			(xy 407.302665 -312.175311) (xy 407.279322 -312.221123) (xy 407.249101 -312.262719) (xy 407.212745 -312.299075)
			(xy 407.171149 -312.329296) (xy 407.125337 -312.352639) (xy 407.076438 -312.368527) (xy 407.025656 -312.37657)
			(xy 406.97424 -312.37657) (xy 406.923458 -312.368527) (xy 406.874559 -312.352639) (xy 406.828747 -312.329296)
			(xy 406.787151 -312.299075) (xy 406.750795 -312.262719) (xy 406.720574 -312.221123) (xy 406.697231 -312.175311)
			(xy 406.681343 -312.126412) (xy 406.6733 -312.07563) (xy 406.354622 -312.07563) (xy 406.346906 -312.123106)
			(xy 406.331322 -312.169787) (xy 406.308451 -312.213364) (xy 406.278886 -312.252708) (xy 406.243393 -312.2868)
			(xy 406.20289 -312.314756) (xy 406.158428 -312.335854) (xy 406.111157 -312.349546) (xy 406.062302 -312.355478)
			(xy 406.013127 -312.353497) (xy 405.964908 -312.343653) (xy 405.918892 -312.326201) (xy 405.876271 -312.301594)
			(xy 405.83815 -312.270469) (xy 405.805515 -312.233632) (xy 405.779212 -312.192036) (xy 405.759921 -312.14676)
			(xy 405.748144 -312.098976) (xy 405.744184 -312.049922) (xy 405.42718 -312.049922) (xy 405.426676 -312.07563)
			(xy 405.418633 -312.126412) (xy 405.402745 -312.175311) (xy 405.379402 -312.221123) (xy 405.349181 -312.262719)
			(xy 405.312825 -312.299075) (xy 405.271229 -312.329296) (xy 405.225417 -312.352639) (xy 405.176518 -312.368527)
			(xy 405.125736 -312.37657) (xy 405.07432 -312.37657) (xy 405.023538 -312.368527) (xy 404.974639 -312.352639)
			(xy 404.928827 -312.329296) (xy 404.887231 -312.299075) (xy 404.850875 -312.262719) (xy 404.820654 -312.221123)
			(xy 404.797311 -312.175311) (xy 404.781423 -312.126412) (xy 404.77338 -312.07563) (xy 404.454448 -312.07563)
			(xy 404.446732 -312.123106) (xy 404.431148 -312.169787) (xy 404.408277 -312.213364) (xy 404.378712 -312.252708)
			(xy 404.343219 -312.2868) (xy 404.302716 -312.314756) (xy 404.258254 -312.335854) (xy 404.210983 -312.349546)
			(xy 404.162128 -312.355478) (xy 404.112953 -312.353497) (xy 404.064734 -312.343653) (xy 404.018718 -312.326201)
			(xy 403.976097 -312.301594) (xy 403.937976 -312.270469) (xy 403.905341 -312.233632) (xy 403.879038 -312.192036)
			(xy 403.859747 -312.14676) (xy 403.84797 -312.098976) (xy 403.84401 -312.049922) (xy 403.527006 -312.049922)
			(xy 403.526502 -312.07563) (xy 403.518459 -312.126412) (xy 403.502571 -312.175311) (xy 403.479228 -312.221123)
			(xy 403.449007 -312.262719) (xy 403.412651 -312.299075) (xy 403.371055 -312.329296) (xy 403.325243 -312.352639)
			(xy 403.276344 -312.368527) (xy 403.225562 -312.37657) (xy 403.174146 -312.37657) (xy 403.123364 -312.368527)
			(xy 403.074465 -312.352639) (xy 403.028653 -312.329296) (xy 402.987057 -312.299075) (xy 402.950701 -312.262719)
			(xy 402.92048 -312.221123) (xy 402.897137 -312.175311) (xy 402.881249 -312.126412) (xy 402.873206 -312.07563)
			(xy 402.554528 -312.07563) (xy 402.546812 -312.123106) (xy 402.531228 -312.169787) (xy 402.508357 -312.213364)
			(xy 402.478792 -312.252708) (xy 402.443299 -312.2868) (xy 402.402796 -312.314756) (xy 402.358334 -312.335854)
			(xy 402.311063 -312.349546) (xy 402.262208 -312.355478) (xy 402.213033 -312.353497) (xy 402.164814 -312.343653)
			(xy 402.118798 -312.326201) (xy 402.076177 -312.301594) (xy 402.038056 -312.270469) (xy 402.005421 -312.233632)
			(xy 401.979118 -312.192036) (xy 401.959827 -312.14676) (xy 401.94805 -312.098976) (xy 401.94409 -312.049922)
			(xy 401.627086 -312.049922) (xy 401.626582 -312.07563) (xy 401.618539 -312.126412) (xy 401.602651 -312.175311)
			(xy 401.579308 -312.221123) (xy 401.549087 -312.262719) (xy 401.512731 -312.299075) (xy 401.471135 -312.329296)
			(xy 401.425323 -312.352639) (xy 401.376424 -312.368527) (xy 401.325642 -312.37657) (xy 401.274226 -312.37657)
			(xy 401.223444 -312.368527) (xy 401.174545 -312.352639) (xy 401.128733 -312.329296) (xy 401.087137 -312.299075)
			(xy 401.050781 -312.262719) (xy 401.02056 -312.221123) (xy 400.997217 -312.175311) (xy 400.981329 -312.126412)
			(xy 400.973286 -312.07563) (xy 400.654608 -312.07563) (xy 400.646892 -312.123106) (xy 400.631308 -312.169787)
			(xy 400.608437 -312.213364) (xy 400.578872 -312.252708) (xy 400.543379 -312.2868) (xy 400.502876 -312.314756)
			(xy 400.458414 -312.335854) (xy 400.411143 -312.349546) (xy 400.362288 -312.355478) (xy 400.313113 -312.353497)
			(xy 400.264894 -312.343653) (xy 400.218878 -312.326201) (xy 400.176257 -312.301594) (xy 400.138136 -312.270469)
			(xy 400.105501 -312.233632) (xy 400.079198 -312.192036) (xy 400.059907 -312.14676) (xy 400.04813 -312.098976)
			(xy 400.04417 -312.049922) (xy 399.727166 -312.049922) (xy 399.726662 -312.07563) (xy 399.718619 -312.126412)
			(xy 399.702731 -312.175311) (xy 399.679388 -312.221123) (xy 399.649167 -312.262719) (xy 399.612811 -312.299075)
			(xy 399.571215 -312.329296) (xy 399.525403 -312.352639) (xy 399.476504 -312.368527) (xy 399.425722 -312.37657)
			(xy 399.374306 -312.37657) (xy 399.323524 -312.368527) (xy 399.274625 -312.352639) (xy 399.228813 -312.329296)
			(xy 399.187217 -312.299075) (xy 399.150861 -312.262719) (xy 399.12064 -312.221123) (xy 399.097297 -312.175311)
			(xy 399.081409 -312.126412) (xy 399.073366 -312.07563) (xy 398.754434 -312.07563) (xy 398.746718 -312.123106)
			(xy 398.731134 -312.169787) (xy 398.708263 -312.213364) (xy 398.678698 -312.252708) (xy 398.643205 -312.2868)
			(xy 398.602702 -312.314756) (xy 398.55824 -312.335854) (xy 398.510969 -312.349546) (xy 398.462114 -312.355478)
			(xy 398.412939 -312.353497) (xy 398.36472 -312.343653) (xy 398.318704 -312.326201) (xy 398.276083 -312.301594)
			(xy 398.237962 -312.270469) (xy 398.205327 -312.233632) (xy 398.179024 -312.192036) (xy 398.159733 -312.14676)
			(xy 398.147956 -312.098976) (xy 398.143996 -312.049922) (xy 397.805607 -312.049922) (xy 397.801439 -312.10023)
			(xy 397.789042 -312.149188) (xy 397.768757 -312.195438) (xy 397.741137 -312.237718) (xy 397.706934 -312.274877)
			(xy 397.667083 -312.305899) (xy 397.622669 -312.32994) (xy 397.574904 -312.346343) (xy 397.525091 -312.354661)
			(xy 397.49984 -312.35523) (xy 397.490672 -312.355139) (xy 397.472372 -312.353998) (xy 397.463264 -312.352944)
			(xy 397.451326 -312.351674) (xy 397.440404 -312.355484) (xy 397.434824 -312.357647) (xy 397.424811 -312.364194)
			(xy 397.420592 -312.368438) (xy 397.364204 -312.427366) (xy 397.36141 -312.430414) (xy 397.358505 -312.434207)
			(xy 397.354022 -312.442643) (xy 397.35252 -312.447178) (xy 397.348964 -312.458608) (xy 397.350996 -312.470546)
			(xy 397.354933 -312.497584) (xy 397.354933 -312.55222) (xy 397.350996 -312.579258) (xy 397.348964 -312.591196)
			(xy 397.35252 -312.602626) (xy 397.354038 -312.607155) (xy 397.35852 -312.615587) (xy 397.36141 -312.61939)
			(xy 397.364204 -312.622438) (xy 397.420592 -312.681366) (xy 397.424823 -312.685595) (xy 397.434835 -312.692135)
			(xy 397.440404 -312.69432) (xy 397.451326 -312.69813) (xy 397.463264 -312.69686) (xy 397.472371 -312.695805)
			(xy 397.490672 -312.694659) (xy 397.49984 -312.694574) (xy 397.525095 -312.695099) (xy 397.574914 -312.703418)
			(xy 397.622685 -312.719824) (xy 397.667105 -312.743867) (xy 397.706961 -312.774894) (xy 397.741168 -312.812057)
			(xy 397.768792 -312.854343) (xy 397.78908 -312.900599) (xy 397.801478 -312.949563) (xy 397.805648 -312.999882)
			(xy 398.143996 -312.999882) (xy 398.147956 -312.950828) (xy 398.159733 -312.903044) (xy 398.179024 -312.857768)
			(xy 398.205327 -312.816172) (xy 398.237962 -312.779335) (xy 398.276083 -312.74821) (xy 398.318704 -312.723603)
			(xy 398.36472 -312.706151) (xy 398.412939 -312.696307) (xy 398.462114 -312.694326) (xy 398.510969 -312.700258)
			(xy 398.55824 -312.71395) (xy 398.602702 -312.735048) (xy 398.643205 -312.763004) (xy 398.678698 -312.797096)
			(xy 398.708263 -312.83644) (xy 398.731134 -312.880017) (xy 398.746718 -312.926698) (xy 398.754613 -312.975275)
			(xy 398.755108 -312.999882) (xy 399.09421 -312.999882) (xy 399.09817 -312.950828) (xy 399.109947 -312.903044)
			(xy 399.129238 -312.857768) (xy 399.155541 -312.816172) (xy 399.188176 -312.779335) (xy 399.226297 -312.74821)
			(xy 399.268918 -312.723603) (xy 399.314934 -312.706151) (xy 399.363153 -312.696307) (xy 399.412328 -312.694326)
			(xy 399.461183 -312.700258) (xy 399.508454 -312.71395) (xy 399.552916 -312.735048) (xy 399.593419 -312.763004)
			(xy 399.628912 -312.797096) (xy 399.658477 -312.83644) (xy 399.681348 -312.880017) (xy 399.696932 -312.926698)
			(xy 399.704827 -312.975275) (xy 399.705322 -312.999882) (xy 399.704827 -313.024489) (xy 399.704648 -313.02559)
			(xy 400.023326 -313.02559) (xy 400.023326 -312.974174) (xy 400.031369 -312.923392) (xy 400.047257 -312.874493)
			(xy 400.0706 -312.828681) (xy 400.100821 -312.787085) (xy 400.137177 -312.750729) (xy 400.178773 -312.720508)
			(xy 400.224585 -312.697165) (xy 400.273484 -312.681277) (xy 400.324266 -312.673234) (xy 400.375682 -312.673234)
			(xy 400.426464 -312.681277) (xy 400.475363 -312.697165) (xy 400.521175 -312.720508) (xy 400.562771 -312.750729)
			(xy 400.599127 -312.787085) (xy 400.629348 -312.828681) (xy 400.652691 -312.874493) (xy 400.668579 -312.923392)
			(xy 400.676622 -312.974174) (xy 400.677126 -312.999882) (xy 400.99413 -312.999882) (xy 400.99809 -312.950828)
			(xy 401.009867 -312.903044) (xy 401.029158 -312.857768) (xy 401.055461 -312.816172) (xy 401.088096 -312.779335)
			(xy 401.126217 -312.74821) (xy 401.168838 -312.723603) (xy 401.214854 -312.706151) (xy 401.263073 -312.696307)
			(xy 401.312248 -312.694326) (xy 401.361103 -312.700258) (xy 401.408374 -312.71395) (xy 401.452836 -312.735048)
			(xy 401.493339 -312.763004) (xy 401.528832 -312.797096) (xy 401.558397 -312.83644) (xy 401.581268 -312.880017)
			(xy 401.596852 -312.926698) (xy 401.604747 -312.975275) (xy 401.605242 -312.999882) (xy 401.604747 -313.024489)
			(xy 401.604568 -313.02559) (xy 401.923246 -313.02559) (xy 401.923246 -312.974174) (xy 401.931289 -312.923392)
			(xy 401.947177 -312.874493) (xy 401.97052 -312.828681) (xy 402.000741 -312.787085) (xy 402.037097 -312.750729)
			(xy 402.078693 -312.720508) (xy 402.124505 -312.697165) (xy 402.173404 -312.681277) (xy 402.224186 -312.673234)
			(xy 402.275602 -312.673234) (xy 402.326384 -312.681277) (xy 402.375283 -312.697165) (xy 402.421095 -312.720508)
			(xy 402.462691 -312.750729) (xy 402.499047 -312.787085) (xy 402.529268 -312.828681) (xy 402.552611 -312.874493)
			(xy 402.568499 -312.923392) (xy 402.576542 -312.974174) (xy 402.577046 -312.999882) (xy 402.89405 -312.999882)
			(xy 402.89801 -312.950828) (xy 402.909787 -312.903044) (xy 402.929078 -312.857768) (xy 402.955381 -312.816172)
			(xy 402.988016 -312.779335) (xy 403.026137 -312.74821) (xy 403.068758 -312.723603) (xy 403.114774 -312.706151)
			(xy 403.162993 -312.696307) (xy 403.212168 -312.694326) (xy 403.261023 -312.700258) (xy 403.308294 -312.71395)
			(xy 403.352756 -312.735048) (xy 403.393259 -312.763004) (xy 403.428752 -312.797096) (xy 403.458317 -312.83644)
			(xy 403.481188 -312.880017) (xy 403.496772 -312.926698) (xy 403.504667 -312.975275) (xy 403.505162 -312.999882)
			(xy 403.504667 -313.024489) (xy 403.504488 -313.02559) (xy 403.823166 -313.02559) (xy 403.823166 -312.974174)
			(xy 403.831209 -312.923392) (xy 403.847097 -312.874493) (xy 403.87044 -312.828681) (xy 403.900661 -312.787085)
			(xy 403.937017 -312.750729) (xy 403.978613 -312.720508) (xy 404.024425 -312.697165) (xy 404.073324 -312.681277)
			(xy 404.124106 -312.673234) (xy 404.175522 -312.673234) (xy 404.226304 -312.681277) (xy 404.275203 -312.697165)
			(xy 404.321015 -312.720508) (xy 404.362611 -312.750729) (xy 404.398967 -312.787085) (xy 404.429188 -312.828681)
			(xy 404.452531 -312.874493) (xy 404.468419 -312.923392) (xy 404.476462 -312.974174) (xy 404.476966 -312.999882)
			(xy 404.794224 -312.999882) (xy 404.798184 -312.950828) (xy 404.809961 -312.903044) (xy 404.829252 -312.857768)
			(xy 404.855555 -312.816172) (xy 404.88819 -312.779335) (xy 404.926311 -312.74821) (xy 404.968932 -312.723603)
			(xy 405.014948 -312.706151) (xy 405.063167 -312.696307) (xy 405.112342 -312.694326) (xy 405.161197 -312.700258)
			(xy 405.208468 -312.71395) (xy 405.25293 -312.735048) (xy 405.293433 -312.763004) (xy 405.328926 -312.797096)
			(xy 405.358491 -312.83644) (xy 405.381362 -312.880017) (xy 405.396946 -312.926698) (xy 405.404841 -312.975275)
			(xy 405.405336 -312.999882) (xy 405.404841 -313.024489) (xy 405.404662 -313.02559) (xy 405.72334 -313.02559)
			(xy 405.72334 -312.974174) (xy 405.731383 -312.923392) (xy 405.747271 -312.874493) (xy 405.770614 -312.828681)
			(xy 405.800835 -312.787085) (xy 405.837191 -312.750729) (xy 405.878787 -312.720508) (xy 405.924599 -312.697165)
			(xy 405.973498 -312.681277) (xy 406.02428 -312.673234) (xy 406.075696 -312.673234) (xy 406.126478 -312.681277)
			(xy 406.175377 -312.697165) (xy 406.221189 -312.720508) (xy 406.262785 -312.750729) (xy 406.299141 -312.787085)
			(xy 406.329362 -312.828681) (xy 406.352705 -312.874493) (xy 406.368593 -312.923392) (xy 406.376636 -312.974174)
			(xy 406.37714 -312.999882) (xy 406.694144 -312.999882) (xy 406.698104 -312.950828) (xy 406.709881 -312.903044)
			(xy 406.729172 -312.857768) (xy 406.755475 -312.816172) (xy 406.78811 -312.779335) (xy 406.826231 -312.74821)
			(xy 406.868852 -312.723603) (xy 406.914868 -312.706151) (xy 406.963087 -312.696307) (xy 407.012262 -312.694326)
			(xy 407.061117 -312.700258) (xy 407.108388 -312.71395) (xy 407.15285 -312.735048) (xy 407.193353 -312.763004)
			(xy 407.228846 -312.797096) (xy 407.258411 -312.83644) (xy 407.281282 -312.880017) (xy 407.296866 -312.926698)
			(xy 407.304761 -312.975275) (xy 407.305256 -312.999882) (xy 407.304761 -313.024489) (xy 407.304582 -313.02559)
			(xy 407.62326 -313.02559) (xy 407.62326 -312.974174) (xy 407.631303 -312.923392) (xy 407.647191 -312.874493)
			(xy 407.670534 -312.828681) (xy 407.700755 -312.787085) (xy 407.737111 -312.750729) (xy 407.778707 -312.720508)
			(xy 407.824519 -312.697165) (xy 407.873418 -312.681277) (xy 407.9242 -312.673234) (xy 407.975616 -312.673234)
			(xy 408.026398 -312.681277) (xy 408.075297 -312.697165) (xy 408.121109 -312.720508) (xy 408.162705 -312.750729)
			(xy 408.199061 -312.787085) (xy 408.229282 -312.828681) (xy 408.252625 -312.874493) (xy 408.268513 -312.923392)
			(xy 408.276556 -312.974174) (xy 408.27706 -312.999882) (xy 408.594064 -312.999882) (xy 408.598024 -312.950828)
			(xy 408.609801 -312.903044) (xy 408.629092 -312.857768) (xy 408.655395 -312.816172) (xy 408.68803 -312.779335)
			(xy 408.726151 -312.74821) (xy 408.768772 -312.723603) (xy 408.814788 -312.706151) (xy 408.863007 -312.696307)
			(xy 408.912182 -312.694326) (xy 408.961037 -312.700258) (xy 409.008308 -312.71395) (xy 409.05277 -312.735048)
			(xy 409.093273 -312.763004) (xy 409.128766 -312.797096) (xy 409.158331 -312.83644) (xy 409.181202 -312.880017)
			(xy 409.196786 -312.926698) (xy 409.204681 -312.975275) (xy 409.205176 -312.999882) (xy 409.204681 -313.024489)
			(xy 409.204502 -313.02559) (xy 409.52318 -313.02559) (xy 409.52318 -312.974174) (xy 409.531223 -312.923392)
			(xy 409.547111 -312.874493) (xy 409.570454 -312.828681) (xy 409.600675 -312.787085) (xy 409.637031 -312.750729)
			(xy 409.678627 -312.720508) (xy 409.724439 -312.697165) (xy 409.773338 -312.681277) (xy 409.82412 -312.673234)
			(xy 409.875536 -312.673234) (xy 409.926318 -312.681277) (xy 409.975217 -312.697165) (xy 410.021029 -312.720508)
			(xy 410.062625 -312.750729) (xy 410.098981 -312.787085) (xy 410.129202 -312.828681) (xy 410.152545 -312.874493)
			(xy 410.168433 -312.923392) (xy 410.176476 -312.974174) (xy 410.17698 -312.999882) (xy 410.493984 -312.999882)
			(xy 410.497944 -312.950828) (xy 410.509721 -312.903044) (xy 410.529012 -312.857768) (xy 410.555315 -312.816172)
			(xy 410.58795 -312.779335) (xy 410.626071 -312.74821) (xy 410.668692 -312.723603) (xy 410.714708 -312.706151)
			(xy 410.762927 -312.696307) (xy 410.812102 -312.694326) (xy 410.860957 -312.700258) (xy 410.908228 -312.71395)
			(xy 410.95269 -312.735048) (xy 410.993193 -312.763004) (xy 411.028686 -312.797096) (xy 411.058251 -312.83644)
			(xy 411.081122 -312.880017) (xy 411.096706 -312.926698) (xy 411.104601 -312.975275) (xy 411.105096 -312.999882)
			(xy 411.104601 -313.024489) (xy 411.104422 -313.02559) (xy 411.423354 -313.02559) (xy 411.423354 -312.974174)
			(xy 411.431397 -312.923392) (xy 411.447285 -312.874493) (xy 411.470628 -312.828681) (xy 411.500849 -312.787085)
			(xy 411.537205 -312.750729) (xy 411.578801 -312.720508) (xy 411.624613 -312.697165) (xy 411.673512 -312.681277)
			(xy 411.724294 -312.673234) (xy 411.77571 -312.673234) (xy 411.826492 -312.681277) (xy 411.875391 -312.697165)
			(xy 411.921203 -312.720508) (xy 411.962799 -312.750729) (xy 411.999155 -312.787085) (xy 412.029376 -312.828681)
			(xy 412.052719 -312.874493) (xy 412.068607 -312.923392) (xy 412.07665 -312.974174) (xy 412.077154 -312.999882)
			(xy 412.394158 -312.999882) (xy 412.398118 -312.950828) (xy 412.409895 -312.903044) (xy 412.429186 -312.857768)
			(xy 412.455489 -312.816172) (xy 412.488124 -312.779335) (xy 412.526245 -312.74821) (xy 412.568866 -312.723603)
			(xy 412.614882 -312.706151) (xy 412.663101 -312.696307) (xy 412.712276 -312.694326) (xy 412.761131 -312.700258)
			(xy 412.808402 -312.71395) (xy 412.852864 -312.735048) (xy 412.893367 -312.763004) (xy 412.92886 -312.797096)
			(xy 412.958425 -312.83644) (xy 412.981296 -312.880017) (xy 412.99688 -312.926698) (xy 413.004775 -312.975275)
			(xy 413.00527 -312.999882) (xy 413.004775 -313.024489) (xy 413.004596 -313.02559) (xy 413.323274 -313.02559)
			(xy 413.323274 -312.974174) (xy 413.331317 -312.923392) (xy 413.347205 -312.874493) (xy 413.370548 -312.828681)
			(xy 413.400769 -312.787085) (xy 413.437125 -312.750729) (xy 413.478721 -312.720508) (xy 413.524533 -312.697165)
			(xy 413.573432 -312.681277) (xy 413.624214 -312.673234) (xy 413.67563 -312.673234) (xy 413.726412 -312.681277)
			(xy 413.775311 -312.697165) (xy 413.821123 -312.720508) (xy 413.862719 -312.750729) (xy 413.899075 -312.787085)
			(xy 413.929296 -312.828681) (xy 413.952639 -312.874493) (xy 413.968527 -312.923392) (xy 413.97657 -312.974174)
			(xy 413.977074 -312.999882) (xy 414.294078 -312.999882) (xy 414.298038 -312.950828) (xy 414.309815 -312.903044)
			(xy 414.329106 -312.857768) (xy 414.355409 -312.816172) (xy 414.388044 -312.779335) (xy 414.426165 -312.74821)
			(xy 414.468786 -312.723603) (xy 414.514802 -312.706151) (xy 414.563021 -312.696307) (xy 414.612196 -312.694326)
			(xy 414.661051 -312.700258) (xy 414.708322 -312.71395) (xy 414.752784 -312.735048) (xy 414.793287 -312.763004)
			(xy 414.82878 -312.797096) (xy 414.858345 -312.83644) (xy 414.881216 -312.880017) (xy 414.8968 -312.926698)
			(xy 414.904695 -312.975275) (xy 414.90519 -312.999882) (xy 415.244038 -312.999882) (xy 415.247998 -312.950828)
			(xy 415.259775 -312.903044) (xy 415.279066 -312.857768) (xy 415.305369 -312.816172) (xy 415.338004 -312.779335)
			(xy 415.376125 -312.74821) (xy 415.418746 -312.723603) (xy 415.464762 -312.706151) (xy 415.512981 -312.696307)
			(xy 415.562156 -312.694326) (xy 415.611011 -312.700258) (xy 415.658282 -312.71395) (xy 415.702744 -312.735048)
			(xy 415.743247 -312.763004) (xy 415.77874 -312.797096) (xy 415.808305 -312.83644) (xy 415.831176 -312.880017)
			(xy 415.84676 -312.926698) (xy 415.854655 -312.975275) (xy 415.85515 -312.999882) (xy 416.193998 -312.999882)
			(xy 416.197958 -312.950828) (xy 416.209735 -312.903044) (xy 416.229026 -312.857768) (xy 416.255329 -312.816172)
			(xy 416.287964 -312.779335) (xy 416.326085 -312.74821) (xy 416.368706 -312.723603) (xy 416.414722 -312.706151)
			(xy 416.462941 -312.696307) (xy 416.512116 -312.694326) (xy 416.560971 -312.700258) (xy 416.608242 -312.71395)
			(xy 416.652704 -312.735048) (xy 416.693207 -312.763004) (xy 416.7287 -312.797096) (xy 416.758265 -312.83644)
			(xy 416.781136 -312.880017) (xy 416.79672 -312.926698) (xy 416.804615 -312.975275) (xy 416.80511 -312.999882)
			(xy 417.144212 -312.999882) (xy 417.148172 -312.950828) (xy 417.159949 -312.903044) (xy 417.17924 -312.857768)
			(xy 417.205543 -312.816172) (xy 417.238178 -312.779335) (xy 417.276299 -312.74821) (xy 417.31892 -312.723603)
			(xy 417.364936 -312.706151) (xy 417.413155 -312.696307) (xy 417.46233 -312.694326) (xy 417.511185 -312.700258)
			(xy 417.558456 -312.71395) (xy 417.602918 -312.735048) (xy 417.643421 -312.763004) (xy 417.678914 -312.797096)
			(xy 417.708479 -312.83644) (xy 417.73135 -312.880017) (xy 417.746934 -312.926698) (xy 417.754829 -312.975275)
			(xy 417.755324 -312.999882) (xy 418.094172 -312.999882) (xy 418.098132 -312.950828) (xy 418.109909 -312.903044)
			(xy 418.1292 -312.857768) (xy 418.155503 -312.816172) (xy 418.188138 -312.779335) (xy 418.226259 -312.74821)
			(xy 418.26888 -312.723603) (xy 418.314896 -312.706151) (xy 418.363115 -312.696307) (xy 418.41229 -312.694326)
			(xy 418.461145 -312.700258) (xy 418.508416 -312.71395) (xy 418.552878 -312.735048) (xy 418.593381 -312.763004)
			(xy 418.628874 -312.797096) (xy 418.658439 -312.83644) (xy 418.68131 -312.880017) (xy 418.696894 -312.926698)
			(xy 418.704789 -312.975275) (xy 418.705284 -312.999882) (xy 419.044132 -312.999882) (xy 419.048092 -312.950828)
			(xy 419.059869 -312.903044) (xy 419.07916 -312.857768) (xy 419.105463 -312.816172) (xy 419.138098 -312.779335)
			(xy 419.176219 -312.74821) (xy 419.21884 -312.723603) (xy 419.264856 -312.706151) (xy 419.313075 -312.696307)
			(xy 419.36225 -312.694326) (xy 419.411105 -312.700258) (xy 419.458376 -312.71395) (xy 419.502838 -312.735048)
			(xy 419.543341 -312.763004) (xy 419.578834 -312.797096) (xy 419.608399 -312.83644) (xy 419.63127 -312.880017)
			(xy 419.646854 -312.926698) (xy 419.654749 -312.975275) (xy 419.655244 -312.999882) (xy 419.994092 -312.999882)
			(xy 419.998052 -312.950828) (xy 420.009829 -312.903044) (xy 420.02912 -312.857768) (xy 420.055423 -312.816172)
			(xy 420.088058 -312.779335) (xy 420.126179 -312.74821) (xy 420.1688 -312.723603) (xy 420.214816 -312.706151)
			(xy 420.263035 -312.696307) (xy 420.31221 -312.694326) (xy 420.361065 -312.700258) (xy 420.408336 -312.71395)
			(xy 420.452798 -312.735048) (xy 420.493301 -312.763004) (xy 420.528794 -312.797096) (xy 420.558359 -312.83644)
			(xy 420.58123 -312.880017) (xy 420.596814 -312.926698) (xy 420.604709 -312.975275) (xy 420.605204 -312.999882)
			(xy 420.944052 -312.999882) (xy 420.948012 -312.950828) (xy 420.959789 -312.903044) (xy 420.97908 -312.857768)
			(xy 421.005383 -312.816172) (xy 421.038018 -312.779335) (xy 421.076139 -312.74821) (xy 421.11876 -312.723603)
			(xy 421.164776 -312.706151) (xy 421.212995 -312.696307) (xy 421.26217 -312.694326) (xy 421.311025 -312.700258)
			(xy 421.358296 -312.71395) (xy 421.402758 -312.735048) (xy 421.443261 -312.763004) (xy 421.478754 -312.797096)
			(xy 421.508319 -312.83644) (xy 421.53119 -312.880017) (xy 421.546774 -312.926698) (xy 421.554669 -312.975275)
			(xy 421.555164 -312.999882) (xy 421.894012 -312.999882) (xy 421.897972 -312.950828) (xy 421.909749 -312.903044)
			(xy 421.92904 -312.857768) (xy 421.955343 -312.816172) (xy 421.987978 -312.779335) (xy 422.026099 -312.74821)
			(xy 422.06872 -312.723603) (xy 422.114736 -312.706151) (xy 422.162955 -312.696307) (xy 422.21213 -312.694326)
			(xy 422.260985 -312.700258) (xy 422.308256 -312.71395) (xy 422.352718 -312.735048) (xy 422.393221 -312.763004)
			(xy 422.428714 -312.797096) (xy 422.458279 -312.83644) (xy 422.48115 -312.880017) (xy 422.496734 -312.926698)
			(xy 422.504629 -312.975275) (xy 422.505124 -312.999882) (xy 422.504629 -313.024489) (xy 422.50445 -313.02559)
			(xy 422.823382 -313.02559) (xy 422.823382 -312.974174) (xy 422.831425 -312.923392) (xy 422.847313 -312.874493)
			(xy 422.870656 -312.828681) (xy 422.900877 -312.787085) (xy 422.937233 -312.750729) (xy 422.978829 -312.720508)
			(xy 423.024641 -312.697165) (xy 423.07354 -312.681277) (xy 423.124322 -312.673234) (xy 423.175738 -312.673234)
			(xy 423.22652 -312.681277) (xy 423.275419 -312.697165) (xy 423.321231 -312.720508) (xy 423.362827 -312.750729)
			(xy 423.399183 -312.787085) (xy 423.429404 -312.828681) (xy 423.452747 -312.874493) (xy 423.468635 -312.923392)
			(xy 423.476678 -312.974174) (xy 423.477182 -312.999882) (xy 423.794186 -312.999882) (xy 423.798146 -312.950828)
			(xy 423.809923 -312.903044) (xy 423.829214 -312.857768) (xy 423.855517 -312.816172) (xy 423.888152 -312.779335)
			(xy 423.926273 -312.74821) (xy 423.968894 -312.723603) (xy 424.01491 -312.706151) (xy 424.063129 -312.696307)
			(xy 424.112304 -312.694326) (xy 424.161159 -312.700258) (xy 424.20843 -312.71395) (xy 424.252892 -312.735048)
			(xy 424.293395 -312.763004) (xy 424.328888 -312.797096) (xy 424.358453 -312.83644) (xy 424.381324 -312.880017)
			(xy 424.396908 -312.926698) (xy 424.404803 -312.975275) (xy 424.405298 -312.999882) (xy 424.404803 -313.024489)
			(xy 424.404624 -313.02559) (xy 424.723302 -313.02559) (xy 424.723302 -312.974174) (xy 424.731345 -312.923392)
			(xy 424.747233 -312.874493) (xy 424.770576 -312.828681) (xy 424.800797 -312.787085) (xy 424.837153 -312.750729)
			(xy 424.878749 -312.720508) (xy 424.924561 -312.697165) (xy 424.97346 -312.681277) (xy 425.024242 -312.673234)
			(xy 425.075658 -312.673234) (xy 425.12644 -312.681277) (xy 425.175339 -312.697165) (xy 425.221151 -312.720508)
			(xy 425.262747 -312.750729) (xy 425.299103 -312.787085) (xy 425.329324 -312.828681) (xy 425.352667 -312.874493)
			(xy 425.368555 -312.923392) (xy 425.376598 -312.974174) (xy 425.377102 -312.999882) (xy 425.694106 -312.999882)
			(xy 425.698066 -312.950828) (xy 425.709843 -312.903044) (xy 425.729134 -312.857768) (xy 425.755437 -312.816172)
			(xy 425.788072 -312.779335) (xy 425.826193 -312.74821) (xy 425.868814 -312.723603) (xy 425.91483 -312.706151)
			(xy 425.963049 -312.696307) (xy 426.012224 -312.694326) (xy 426.061079 -312.700258) (xy 426.10835 -312.71395)
			(xy 426.152812 -312.735048) (xy 426.193315 -312.763004) (xy 426.228808 -312.797096) (xy 426.258373 -312.83644)
			(xy 426.281244 -312.880017) (xy 426.296828 -312.926698) (xy 426.304723 -312.975275) (xy 426.305218 -312.999882)
			(xy 426.304723 -313.024489) (xy 426.304544 -313.02559) (xy 426.623222 -313.02559) (xy 426.623222 -312.974174)
			(xy 426.631265 -312.923392) (xy 426.647153 -312.874493) (xy 426.670496 -312.828681) (xy 426.700717 -312.787085)
			(xy 426.737073 -312.750729) (xy 426.778669 -312.720508) (xy 426.824481 -312.697165) (xy 426.87338 -312.681277)
			(xy 426.924162 -312.673234) (xy 426.975578 -312.673234) (xy 427.02636 -312.681277) (xy 427.075259 -312.697165)
			(xy 427.121071 -312.720508) (xy 427.162667 -312.750729) (xy 427.199023 -312.787085) (xy 427.229244 -312.828681)
			(xy 427.252587 -312.874493) (xy 427.268475 -312.923392) (xy 427.276518 -312.974174) (xy 427.277022 -312.999882)
			(xy 427.594026 -312.999882) (xy 427.597986 -312.950828) (xy 427.609763 -312.903044) (xy 427.629054 -312.857768)
			(xy 427.655357 -312.816172) (xy 427.687992 -312.779335) (xy 427.726113 -312.74821) (xy 427.768734 -312.723603)
			(xy 427.81475 -312.706151) (xy 427.862969 -312.696307) (xy 427.912144 -312.694326) (xy 427.960999 -312.700258)
			(xy 428.00827 -312.71395) (xy 428.052732 -312.735048) (xy 428.093235 -312.763004) (xy 428.128728 -312.797096)
			(xy 428.158293 -312.83644) (xy 428.181164 -312.880017) (xy 428.196748 -312.926698) (xy 428.204643 -312.975275)
			(xy 428.205138 -312.999882) (xy 428.204643 -313.024489) (xy 428.204464 -313.02559) (xy 428.523142 -313.02559)
			(xy 428.523142 -312.974174) (xy 428.531185 -312.923392) (xy 428.547073 -312.874493) (xy 428.570416 -312.828681)
			(xy 428.600637 -312.787085) (xy 428.636993 -312.750729) (xy 428.678589 -312.720508) (xy 428.724401 -312.697165)
			(xy 428.7733 -312.681277) (xy 428.824082 -312.673234) (xy 428.875498 -312.673234) (xy 428.92628 -312.681277)
			(xy 428.975179 -312.697165) (xy 429.020991 -312.720508) (xy 429.062587 -312.750729) (xy 429.098943 -312.787085)
			(xy 429.129164 -312.828681) (xy 429.152507 -312.874493) (xy 429.168395 -312.923392) (xy 429.176438 -312.974174)
			(xy 429.176942 -312.999882) (xy 429.4942 -312.999882) (xy 429.49816 -312.950828) (xy 429.509937 -312.903044)
			(xy 429.529228 -312.857768) (xy 429.555531 -312.816172) (xy 429.588166 -312.779335) (xy 429.626287 -312.74821)
			(xy 429.668908 -312.723603) (xy 429.714924 -312.706151) (xy 429.763143 -312.696307) (xy 429.812318 -312.694326)
			(xy 429.861173 -312.700258) (xy 429.908444 -312.71395) (xy 429.952906 -312.735048) (xy 429.993409 -312.763004)
			(xy 430.028902 -312.797096) (xy 430.058467 -312.83644) (xy 430.081338 -312.880017) (xy 430.096922 -312.926698)
			(xy 430.104817 -312.975275) (xy 430.105312 -312.999882) (xy 430.44416 -312.999882) (xy 430.44812 -312.950828)
			(xy 430.459897 -312.903044) (xy 430.479188 -312.857768) (xy 430.505491 -312.816172) (xy 430.538126 -312.779335)
			(xy 430.576247 -312.74821) (xy 430.618868 -312.723603) (xy 430.664884 -312.706151) (xy 430.713103 -312.696307)
			(xy 430.762278 -312.694326) (xy 430.811133 -312.700258) (xy 430.858404 -312.71395) (xy 430.902866 -312.735048)
			(xy 430.943369 -312.763004) (xy 430.978862 -312.797096) (xy 431.008427 -312.83644) (xy 431.031298 -312.880017)
			(xy 431.046882 -312.926698) (xy 431.054777 -312.975275) (xy 431.055272 -312.999882) (xy 431.054777 -313.024489)
			(xy 431.046882 -313.073066) (xy 431.031298 -313.119747) (xy 431.008427 -313.163324) (xy 430.978862 -313.202668)
			(xy 430.943369 -313.23676) (xy 430.902866 -313.264716) (xy 430.858404 -313.285814) (xy 430.811133 -313.299506)
			(xy 430.762278 -313.305438) (xy 430.713103 -313.303457) (xy 430.664884 -313.293613) (xy 430.618868 -313.276161)
			(xy 430.576247 -313.251554) (xy 430.538126 -313.220429) (xy 430.505491 -313.183592) (xy 430.479188 -313.141996)
			(xy 430.459897 -313.09672) (xy 430.44812 -313.048936) (xy 430.44416 -312.999882) (xy 430.105312 -312.999882)
			(xy 430.104817 -313.024489) (xy 430.096922 -313.073066) (xy 430.081338 -313.119747) (xy 430.058467 -313.163324)
			(xy 430.028902 -313.202668) (xy 429.993409 -313.23676) (xy 429.952906 -313.264716) (xy 429.908444 -313.285814)
			(xy 429.861173 -313.299506) (xy 429.812318 -313.305438) (xy 429.763143 -313.303457) (xy 429.714924 -313.293613)
			(xy 429.668908 -313.276161) (xy 429.626287 -313.251554) (xy 429.588166 -313.220429) (xy 429.555531 -313.183592)
			(xy 429.529228 -313.141996) (xy 429.509937 -313.09672) (xy 429.49816 -313.048936) (xy 429.4942 -312.999882)
			(xy 429.176942 -312.999882) (xy 429.176438 -313.02559) (xy 429.168395 -313.076372) (xy 429.152507 -313.125271)
			(xy 429.129164 -313.171083) (xy 429.098943 -313.212679) (xy 429.062587 -313.249035) (xy 429.020991 -313.279256)
			(xy 428.975179 -313.302599) (xy 428.92628 -313.318487) (xy 428.875498 -313.32653) (xy 428.824082 -313.32653)
			(xy 428.7733 -313.318487) (xy 428.724401 -313.302599) (xy 428.678589 -313.279256) (xy 428.636993 -313.249035)
			(xy 428.600637 -313.212679) (xy 428.570416 -313.171083) (xy 428.547073 -313.125271) (xy 428.531185 -313.076372)
			(xy 428.523142 -313.02559) (xy 428.204464 -313.02559) (xy 428.196748 -313.073066) (xy 428.181164 -313.119747)
			(xy 428.158293 -313.163324) (xy 428.128728 -313.202668) (xy 428.093235 -313.23676) (xy 428.052732 -313.264716)
			(xy 428.00827 -313.285814) (xy 427.960999 -313.299506) (xy 427.912144 -313.305438) (xy 427.862969 -313.303457)
			(xy 427.81475 -313.293613) (xy 427.768734 -313.276161) (xy 427.726113 -313.251554) (xy 427.687992 -313.220429)
			(xy 427.655357 -313.183592) (xy 427.629054 -313.141996) (xy 427.609763 -313.09672) (xy 427.597986 -313.048936)
			(xy 427.594026 -312.999882) (xy 427.277022 -312.999882) (xy 427.276518 -313.02559) (xy 427.268475 -313.076372)
			(xy 427.252587 -313.125271) (xy 427.229244 -313.171083) (xy 427.199023 -313.212679) (xy 427.162667 -313.249035)
			(xy 427.121071 -313.279256) (xy 427.075259 -313.302599) (xy 427.02636 -313.318487) (xy 426.975578 -313.32653)
			(xy 426.924162 -313.32653) (xy 426.87338 -313.318487) (xy 426.824481 -313.302599) (xy 426.778669 -313.279256)
			(xy 426.737073 -313.249035) (xy 426.700717 -313.212679) (xy 426.670496 -313.171083) (xy 426.647153 -313.125271)
			(xy 426.631265 -313.076372) (xy 426.623222 -313.02559) (xy 426.304544 -313.02559) (xy 426.296828 -313.073066)
			(xy 426.281244 -313.119747) (xy 426.258373 -313.163324) (xy 426.228808 -313.202668) (xy 426.193315 -313.23676)
			(xy 426.152812 -313.264716) (xy 426.10835 -313.285814) (xy 426.061079 -313.299506) (xy 426.012224 -313.305438)
			(xy 425.963049 -313.303457) (xy 425.91483 -313.293613) (xy 425.868814 -313.276161) (xy 425.826193 -313.251554)
			(xy 425.788072 -313.220429) (xy 425.755437 -313.183592) (xy 425.729134 -313.141996) (xy 425.709843 -313.09672)
			(xy 425.698066 -313.048936) (xy 425.694106 -312.999882) (xy 425.377102 -312.999882) (xy 425.376598 -313.02559)
			(xy 425.368555 -313.076372) (xy 425.352667 -313.125271) (xy 425.329324 -313.171083) (xy 425.299103 -313.212679)
			(xy 425.262747 -313.249035) (xy 425.221151 -313.279256) (xy 425.175339 -313.302599) (xy 425.12644 -313.318487)
			(xy 425.075658 -313.32653) (xy 425.024242 -313.32653) (xy 424.97346 -313.318487) (xy 424.924561 -313.302599)
			(xy 424.878749 -313.279256) (xy 424.837153 -313.249035) (xy 424.800797 -313.212679) (xy 424.770576 -313.171083)
			(xy 424.747233 -313.125271) (xy 424.731345 -313.076372) (xy 424.723302 -313.02559) (xy 424.404624 -313.02559)
			(xy 424.396908 -313.073066) (xy 424.381324 -313.119747) (xy 424.358453 -313.163324) (xy 424.328888 -313.202668)
			(xy 424.293395 -313.23676) (xy 424.252892 -313.264716) (xy 424.20843 -313.285814) (xy 424.161159 -313.299506)
			(xy 424.112304 -313.305438) (xy 424.063129 -313.303457) (xy 424.01491 -313.293613) (xy 423.968894 -313.276161)
			(xy 423.926273 -313.251554) (xy 423.888152 -313.220429) (xy 423.855517 -313.183592) (xy 423.829214 -313.141996)
			(xy 423.809923 -313.09672) (xy 423.798146 -313.048936) (xy 423.794186 -312.999882) (xy 423.477182 -312.999882)
			(xy 423.476678 -313.02559) (xy 423.468635 -313.076372) (xy 423.452747 -313.125271) (xy 423.429404 -313.171083)
			(xy 423.399183 -313.212679) (xy 423.362827 -313.249035) (xy 423.321231 -313.279256) (xy 423.275419 -313.302599)
			(xy 423.22652 -313.318487) (xy 423.175738 -313.32653) (xy 423.124322 -313.32653) (xy 423.07354 -313.318487)
			(xy 423.024641 -313.302599) (xy 422.978829 -313.279256) (xy 422.937233 -313.249035) (xy 422.900877 -313.212679)
			(xy 422.870656 -313.171083) (xy 422.847313 -313.125271) (xy 422.831425 -313.076372) (xy 422.823382 -313.02559)
			(xy 422.50445 -313.02559) (xy 422.496734 -313.073066) (xy 422.48115 -313.119747) (xy 422.458279 -313.163324)
			(xy 422.428714 -313.202668) (xy 422.393221 -313.23676) (xy 422.352718 -313.264716) (xy 422.308256 -313.285814)
			(xy 422.260985 -313.299506) (xy 422.21213 -313.305438) (xy 422.162955 -313.303457) (xy 422.114736 -313.293613)
			(xy 422.06872 -313.276161) (xy 422.026099 -313.251554) (xy 421.987978 -313.220429) (xy 421.955343 -313.183592)
			(xy 421.92904 -313.141996) (xy 421.909749 -313.09672) (xy 421.897972 -313.048936) (xy 421.894012 -312.999882)
			(xy 421.555164 -312.999882) (xy 421.554669 -313.024489) (xy 421.546774 -313.073066) (xy 421.53119 -313.119747)
			(xy 421.508319 -313.163324) (xy 421.478754 -313.202668) (xy 421.443261 -313.23676) (xy 421.402758 -313.264716)
			(xy 421.358296 -313.285814) (xy 421.311025 -313.299506) (xy 421.26217 -313.305438) (xy 421.212995 -313.303457)
			(xy 421.164776 -313.293613) (xy 421.11876 -313.276161) (xy 421.076139 -313.251554) (xy 421.038018 -313.220429)
			(xy 421.005383 -313.183592) (xy 420.97908 -313.141996) (xy 420.959789 -313.09672) (xy 420.948012 -313.048936)
			(xy 420.944052 -312.999882) (xy 420.605204 -312.999882) (xy 420.604709 -313.024489) (xy 420.596814 -313.073066)
			(xy 420.58123 -313.119747) (xy 420.558359 -313.163324) (xy 420.528794 -313.202668) (xy 420.493301 -313.23676)
			(xy 420.452798 -313.264716) (xy 420.408336 -313.285814) (xy 420.361065 -313.299506) (xy 420.31221 -313.305438)
			(xy 420.263035 -313.303457) (xy 420.214816 -313.293613) (xy 420.1688 -313.276161) (xy 420.126179 -313.251554)
			(xy 420.088058 -313.220429) (xy 420.055423 -313.183592) (xy 420.02912 -313.141996) (xy 420.009829 -313.09672)
			(xy 419.998052 -313.048936) (xy 419.994092 -312.999882) (xy 419.655244 -312.999882) (xy 419.654749 -313.024489)
			(xy 419.646854 -313.073066) (xy 419.63127 -313.119747) (xy 419.608399 -313.163324) (xy 419.578834 -313.202668)
			(xy 419.543341 -313.23676) (xy 419.502838 -313.264716) (xy 419.458376 -313.285814) (xy 419.411105 -313.299506)
			(xy 419.36225 -313.305438) (xy 419.313075 -313.303457) (xy 419.264856 -313.293613) (xy 419.21884 -313.276161)
			(xy 419.176219 -313.251554) (xy 419.138098 -313.220429) (xy 419.105463 -313.183592) (xy 419.07916 -313.141996)
			(xy 419.059869 -313.09672) (xy 419.048092 -313.048936) (xy 419.044132 -312.999882) (xy 418.705284 -312.999882)
			(xy 418.704789 -313.024489) (xy 418.696894 -313.073066) (xy 418.68131 -313.119747) (xy 418.658439 -313.163324)
			(xy 418.628874 -313.202668) (xy 418.593381 -313.23676) (xy 418.552878 -313.264716) (xy 418.508416 -313.285814)
			(xy 418.461145 -313.299506) (xy 418.41229 -313.305438) (xy 418.363115 -313.303457) (xy 418.314896 -313.293613)
			(xy 418.26888 -313.276161) (xy 418.226259 -313.251554) (xy 418.188138 -313.220429) (xy 418.155503 -313.183592)
			(xy 418.1292 -313.141996) (xy 418.109909 -313.09672) (xy 418.098132 -313.048936) (xy 418.094172 -312.999882)
			(xy 417.755324 -312.999882) (xy 417.754829 -313.024489) (xy 417.746934 -313.073066) (xy 417.73135 -313.119747)
			(xy 417.708479 -313.163324) (xy 417.678914 -313.202668) (xy 417.643421 -313.23676) (xy 417.602918 -313.264716)
			(xy 417.558456 -313.285814) (xy 417.511185 -313.299506) (xy 417.46233 -313.305438) (xy 417.413155 -313.303457)
			(xy 417.364936 -313.293613) (xy 417.31892 -313.276161) (xy 417.276299 -313.251554) (xy 417.238178 -313.220429)
			(xy 417.205543 -313.183592) (xy 417.17924 -313.141996) (xy 417.159949 -313.09672) (xy 417.148172 -313.048936)
			(xy 417.144212 -312.999882) (xy 416.80511 -312.999882) (xy 416.804615 -313.024489) (xy 416.79672 -313.073066)
			(xy 416.781136 -313.119747) (xy 416.758265 -313.163324) (xy 416.7287 -313.202668) (xy 416.693207 -313.23676)
			(xy 416.652704 -313.264716) (xy 416.608242 -313.285814) (xy 416.560971 -313.299506) (xy 416.512116 -313.305438)
			(xy 416.462941 -313.303457) (xy 416.414722 -313.293613) (xy 416.368706 -313.276161) (xy 416.326085 -313.251554)
			(xy 416.287964 -313.220429) (xy 416.255329 -313.183592) (xy 416.229026 -313.141996) (xy 416.209735 -313.09672)
			(xy 416.197958 -313.048936) (xy 416.193998 -312.999882) (xy 415.85515 -312.999882) (xy 415.854655 -313.024489)
			(xy 415.84676 -313.073066) (xy 415.831176 -313.119747) (xy 415.808305 -313.163324) (xy 415.77874 -313.202668)
			(xy 415.743247 -313.23676) (xy 415.702744 -313.264716) (xy 415.658282 -313.285814) (xy 415.611011 -313.299506)
			(xy 415.562156 -313.305438) (xy 415.512981 -313.303457) (xy 415.464762 -313.293613) (xy 415.418746 -313.276161)
			(xy 415.376125 -313.251554) (xy 415.338004 -313.220429) (xy 415.305369 -313.183592) (xy 415.279066 -313.141996)
			(xy 415.259775 -313.09672) (xy 415.247998 -313.048936) (xy 415.244038 -312.999882) (xy 414.90519 -312.999882)
			(xy 414.904695 -313.024489) (xy 414.8968 -313.073066) (xy 414.881216 -313.119747) (xy 414.858345 -313.163324)
			(xy 414.82878 -313.202668) (xy 414.793287 -313.23676) (xy 414.752784 -313.264716) (xy 414.708322 -313.285814)
			(xy 414.661051 -313.299506) (xy 414.612196 -313.305438) (xy 414.563021 -313.303457) (xy 414.514802 -313.293613)
			(xy 414.468786 -313.276161) (xy 414.426165 -313.251554) (xy 414.388044 -313.220429) (xy 414.355409 -313.183592)
			(xy 414.329106 -313.141996) (xy 414.309815 -313.09672) (xy 414.298038 -313.048936) (xy 414.294078 -312.999882)
			(xy 413.977074 -312.999882) (xy 413.97657 -313.02559) (xy 413.968527 -313.076372) (xy 413.952639 -313.125271)
			(xy 413.929296 -313.171083) (xy 413.899075 -313.212679) (xy 413.862719 -313.249035) (xy 413.821123 -313.279256)
			(xy 413.775311 -313.302599) (xy 413.726412 -313.318487) (xy 413.67563 -313.32653) (xy 413.624214 -313.32653)
			(xy 413.573432 -313.318487) (xy 413.524533 -313.302599) (xy 413.478721 -313.279256) (xy 413.437125 -313.249035)
			(xy 413.400769 -313.212679) (xy 413.370548 -313.171083) (xy 413.347205 -313.125271) (xy 413.331317 -313.076372)
			(xy 413.323274 -313.02559) (xy 413.004596 -313.02559) (xy 412.99688 -313.073066) (xy 412.981296 -313.119747)
			(xy 412.958425 -313.163324) (xy 412.92886 -313.202668) (xy 412.893367 -313.23676) (xy 412.852864 -313.264716)
			(xy 412.808402 -313.285814) (xy 412.761131 -313.299506) (xy 412.712276 -313.305438) (xy 412.663101 -313.303457)
			(xy 412.614882 -313.293613) (xy 412.568866 -313.276161) (xy 412.526245 -313.251554) (xy 412.488124 -313.220429)
			(xy 412.455489 -313.183592) (xy 412.429186 -313.141996) (xy 412.409895 -313.09672) (xy 412.398118 -313.048936)
			(xy 412.394158 -312.999882) (xy 412.077154 -312.999882) (xy 412.07665 -313.02559) (xy 412.068607 -313.076372)
			(xy 412.052719 -313.125271) (xy 412.029376 -313.171083) (xy 411.999155 -313.212679) (xy 411.962799 -313.249035)
			(xy 411.921203 -313.279256) (xy 411.875391 -313.302599) (xy 411.826492 -313.318487) (xy 411.77571 -313.32653)
			(xy 411.724294 -313.32653) (xy 411.673512 -313.318487) (xy 411.624613 -313.302599) (xy 411.578801 -313.279256)
			(xy 411.537205 -313.249035) (xy 411.500849 -313.212679) (xy 411.470628 -313.171083) (xy 411.447285 -313.125271)
			(xy 411.431397 -313.076372) (xy 411.423354 -313.02559) (xy 411.104422 -313.02559) (xy 411.096706 -313.073066)
			(xy 411.081122 -313.119747) (xy 411.058251 -313.163324) (xy 411.028686 -313.202668) (xy 410.993193 -313.23676)
			(xy 410.95269 -313.264716) (xy 410.908228 -313.285814) (xy 410.860957 -313.299506) (xy 410.812102 -313.305438)
			(xy 410.762927 -313.303457) (xy 410.714708 -313.293613) (xy 410.668692 -313.276161) (xy 410.626071 -313.251554)
			(xy 410.58795 -313.220429) (xy 410.555315 -313.183592) (xy 410.529012 -313.141996) (xy 410.509721 -313.09672)
			(xy 410.497944 -313.048936) (xy 410.493984 -312.999882) (xy 410.17698 -312.999882) (xy 410.176476 -313.02559)
			(xy 410.168433 -313.076372) (xy 410.152545 -313.125271) (xy 410.129202 -313.171083) (xy 410.098981 -313.212679)
			(xy 410.062625 -313.249035) (xy 410.021029 -313.279256) (xy 409.975217 -313.302599) (xy 409.926318 -313.318487)
			(xy 409.875536 -313.32653) (xy 409.82412 -313.32653) (xy 409.773338 -313.318487) (xy 409.724439 -313.302599)
			(xy 409.678627 -313.279256) (xy 409.637031 -313.249035) (xy 409.600675 -313.212679) (xy 409.570454 -313.171083)
			(xy 409.547111 -313.125271) (xy 409.531223 -313.076372) (xy 409.52318 -313.02559) (xy 409.204502 -313.02559)
			(xy 409.196786 -313.073066) (xy 409.181202 -313.119747) (xy 409.158331 -313.163324) (xy 409.128766 -313.202668)
			(xy 409.093273 -313.23676) (xy 409.05277 -313.264716) (xy 409.008308 -313.285814) (xy 408.961037 -313.299506)
			(xy 408.912182 -313.305438) (xy 408.863007 -313.303457) (xy 408.814788 -313.293613) (xy 408.768772 -313.276161)
			(xy 408.726151 -313.251554) (xy 408.68803 -313.220429) (xy 408.655395 -313.183592) (xy 408.629092 -313.141996)
			(xy 408.609801 -313.09672) (xy 408.598024 -313.048936) (xy 408.594064 -312.999882) (xy 408.27706 -312.999882)
			(xy 408.276556 -313.02559) (xy 408.268513 -313.076372) (xy 408.252625 -313.125271) (xy 408.229282 -313.171083)
			(xy 408.199061 -313.212679) (xy 408.162705 -313.249035) (xy 408.121109 -313.279256) (xy 408.075297 -313.302599)
			(xy 408.026398 -313.318487) (xy 407.975616 -313.32653) (xy 407.9242 -313.32653) (xy 407.873418 -313.318487)
			(xy 407.824519 -313.302599) (xy 407.778707 -313.279256) (xy 407.737111 -313.249035) (xy 407.700755 -313.212679)
			(xy 407.670534 -313.171083) (xy 407.647191 -313.125271) (xy 407.631303 -313.076372) (xy 407.62326 -313.02559)
			(xy 407.304582 -313.02559) (xy 407.296866 -313.073066) (xy 407.281282 -313.119747) (xy 407.258411 -313.163324)
			(xy 407.228846 -313.202668) (xy 407.193353 -313.23676) (xy 407.15285 -313.264716) (xy 407.108388 -313.285814)
			(xy 407.061117 -313.299506) (xy 407.012262 -313.305438) (xy 406.963087 -313.303457) (xy 406.914868 -313.293613)
			(xy 406.868852 -313.276161) (xy 406.826231 -313.251554) (xy 406.78811 -313.220429) (xy 406.755475 -313.183592)
			(xy 406.729172 -313.141996) (xy 406.709881 -313.09672) (xy 406.698104 -313.048936) (xy 406.694144 -312.999882)
			(xy 406.37714 -312.999882) (xy 406.376636 -313.02559) (xy 406.368593 -313.076372) (xy 406.352705 -313.125271)
			(xy 406.329362 -313.171083) (xy 406.299141 -313.212679) (xy 406.262785 -313.249035) (xy 406.221189 -313.279256)
			(xy 406.175377 -313.302599) (xy 406.126478 -313.318487) (xy 406.075696 -313.32653) (xy 406.02428 -313.32653)
			(xy 405.973498 -313.318487) (xy 405.924599 -313.302599) (xy 405.878787 -313.279256) (xy 405.837191 -313.249035)
			(xy 405.800835 -313.212679) (xy 405.770614 -313.171083) (xy 405.747271 -313.125271) (xy 405.731383 -313.076372)
			(xy 405.72334 -313.02559) (xy 405.404662 -313.02559) (xy 405.396946 -313.073066) (xy 405.381362 -313.119747)
			(xy 405.358491 -313.163324) (xy 405.328926 -313.202668) (xy 405.293433 -313.23676) (xy 405.25293 -313.264716)
			(xy 405.208468 -313.285814) (xy 405.161197 -313.299506) (xy 405.112342 -313.305438) (xy 405.063167 -313.303457)
			(xy 405.014948 -313.293613) (xy 404.968932 -313.276161) (xy 404.926311 -313.251554) (xy 404.88819 -313.220429)
			(xy 404.855555 -313.183592) (xy 404.829252 -313.141996) (xy 404.809961 -313.09672) (xy 404.798184 -313.048936)
			(xy 404.794224 -312.999882) (xy 404.476966 -312.999882) (xy 404.476462 -313.02559) (xy 404.468419 -313.076372)
			(xy 404.452531 -313.125271) (xy 404.429188 -313.171083) (xy 404.398967 -313.212679) (xy 404.362611 -313.249035)
			(xy 404.321015 -313.279256) (xy 404.275203 -313.302599) (xy 404.226304 -313.318487) (xy 404.175522 -313.32653)
			(xy 404.124106 -313.32653) (xy 404.073324 -313.318487) (xy 404.024425 -313.302599) (xy 403.978613 -313.279256)
			(xy 403.937017 -313.249035) (xy 403.900661 -313.212679) (xy 403.87044 -313.171083) (xy 403.847097 -313.125271)
			(xy 403.831209 -313.076372) (xy 403.823166 -313.02559) (xy 403.504488 -313.02559) (xy 403.496772 -313.073066)
			(xy 403.481188 -313.119747) (xy 403.458317 -313.163324) (xy 403.428752 -313.202668) (xy 403.393259 -313.23676)
			(xy 403.352756 -313.264716) (xy 403.308294 -313.285814) (xy 403.261023 -313.299506) (xy 403.212168 -313.305438)
			(xy 403.162993 -313.303457) (xy 403.114774 -313.293613) (xy 403.068758 -313.276161) (xy 403.026137 -313.251554)
			(xy 402.988016 -313.220429) (xy 402.955381 -313.183592) (xy 402.929078 -313.141996) (xy 402.909787 -313.09672)
			(xy 402.89801 -313.048936) (xy 402.89405 -312.999882) (xy 402.577046 -312.999882) (xy 402.576542 -313.02559)
			(xy 402.568499 -313.076372) (xy 402.552611 -313.125271) (xy 402.529268 -313.171083) (xy 402.499047 -313.212679)
			(xy 402.462691 -313.249035) (xy 402.421095 -313.279256) (xy 402.375283 -313.302599) (xy 402.326384 -313.318487)
			(xy 402.275602 -313.32653) (xy 402.224186 -313.32653) (xy 402.173404 -313.318487) (xy 402.124505 -313.302599)
			(xy 402.078693 -313.279256) (xy 402.037097 -313.249035) (xy 402.000741 -313.212679) (xy 401.97052 -313.171083)
			(xy 401.947177 -313.125271) (xy 401.931289 -313.076372) (xy 401.923246 -313.02559) (xy 401.604568 -313.02559)
			(xy 401.596852 -313.073066) (xy 401.581268 -313.119747) (xy 401.558397 -313.163324) (xy 401.528832 -313.202668)
			(xy 401.493339 -313.23676) (xy 401.452836 -313.264716) (xy 401.408374 -313.285814) (xy 401.361103 -313.299506)
			(xy 401.312248 -313.305438) (xy 401.263073 -313.303457) (xy 401.214854 -313.293613) (xy 401.168838 -313.276161)
			(xy 401.126217 -313.251554) (xy 401.088096 -313.220429) (xy 401.055461 -313.183592) (xy 401.029158 -313.141996)
			(xy 401.009867 -313.09672) (xy 400.99809 -313.048936) (xy 400.99413 -312.999882) (xy 400.677126 -312.999882)
			(xy 400.676622 -313.02559) (xy 400.668579 -313.076372) (xy 400.652691 -313.125271) (xy 400.629348 -313.171083)
			(xy 400.599127 -313.212679) (xy 400.562771 -313.249035) (xy 400.521175 -313.279256) (xy 400.475363 -313.302599)
			(xy 400.426464 -313.318487) (xy 400.375682 -313.32653) (xy 400.324266 -313.32653) (xy 400.273484 -313.318487)
			(xy 400.224585 -313.302599) (xy 400.178773 -313.279256) (xy 400.137177 -313.249035) (xy 400.100821 -313.212679)
			(xy 400.0706 -313.171083) (xy 400.047257 -313.125271) (xy 400.031369 -313.076372) (xy 400.023326 -313.02559)
			(xy 399.704648 -313.02559) (xy 399.696932 -313.073066) (xy 399.681348 -313.119747) (xy 399.658477 -313.163324)
			(xy 399.628912 -313.202668) (xy 399.593419 -313.23676) (xy 399.552916 -313.264716) (xy 399.508454 -313.285814)
			(xy 399.461183 -313.299506) (xy 399.412328 -313.305438) (xy 399.363153 -313.303457) (xy 399.314934 -313.293613)
			(xy 399.268918 -313.276161) (xy 399.226297 -313.251554) (xy 399.188176 -313.220429) (xy 399.155541 -313.183592)
			(xy 399.129238 -313.141996) (xy 399.109947 -313.09672) (xy 399.09817 -313.048936) (xy 399.09421 -312.999882)
			(xy 398.755108 -312.999882) (xy 398.754613 -313.024489) (xy 398.746718 -313.073066) (xy 398.731134 -313.119747)
			(xy 398.708263 -313.163324) (xy 398.678698 -313.202668) (xy 398.643205 -313.23676) (xy 398.602702 -313.264716)
			(xy 398.55824 -313.285814) (xy 398.510969 -313.299506) (xy 398.462114 -313.305438) (xy 398.412939 -313.303457)
			(xy 398.36472 -313.293613) (xy 398.318704 -313.276161) (xy 398.276083 -313.251554) (xy 398.237962 -313.220429)
			(xy 398.205327 -313.183592) (xy 398.179024 -313.141996) (xy 398.159733 -313.09672) (xy 398.147956 -313.048936)
			(xy 398.143996 -312.999882) (xy 397.805648 -312.999882) (xy 397.805649 -312.9999) (xy 397.801478 -313.050237)
			(xy 397.78908 -313.099201) (xy 397.768792 -313.145457) (xy 397.741168 -313.187743) (xy 397.706961 -313.224906)
			(xy 397.667105 -313.255933) (xy 397.622685 -313.279976) (xy 397.574914 -313.296382) (xy 397.525095 -313.304701)
			(xy 397.49984 -313.30519) (xy 397.490672 -313.305099) (xy 397.472372 -313.303957) (xy 397.463264 -313.302904)
			(xy 397.451326 -313.301634) (xy 397.440404 -313.305444) (xy 397.434823 -313.307605) (xy 397.424806 -313.314149)
			(xy 397.420592 -313.318398) (xy 397.364204 -313.377326) (xy 397.36141 -313.380374) (xy 397.358509 -313.384169)
			(xy 397.354035 -313.392608) (xy 397.35252 -313.397138) (xy 397.348964 -313.408568) (xy 397.350996 -313.420506)
			(xy 397.354936 -313.447544) (xy 397.354942 -313.502181) (xy 397.350996 -313.529218) (xy 397.348964 -313.541156)
			(xy 397.35252 -313.552586) (xy 397.354035 -313.557116) (xy 397.358512 -313.565553) (xy 397.36141 -313.56935)
			(xy 397.364204 -313.572398) (xy 397.420592 -313.631326) (xy 397.424821 -313.635557) (xy 397.434832 -313.642103)
			(xy 397.440404 -313.64428) (xy 397.451326 -313.64809) (xy 397.463264 -313.64682) (xy 397.472371 -313.645765)
			(xy 397.490672 -313.644619) (xy 397.49984 -313.644534) (xy 397.52509 -313.645059) (xy 397.574899 -313.653376)
			(xy 397.622661 -313.669778) (xy 397.667072 -313.693818) (xy 397.706921 -313.724838) (xy 397.741121 -313.761994)
			(xy 397.768739 -313.804272) (xy 397.789023 -313.850518) (xy 397.801419 -313.899473) (xy 397.805589 -313.9498)
			(xy 397.805586 -313.949842) (xy 398.143996 -313.949842) (xy 398.147956 -313.900788) (xy 398.159733 -313.853004)
			(xy 398.179024 -313.807728) (xy 398.205327 -313.766132) (xy 398.237962 -313.729295) (xy 398.276083 -313.69817)
			(xy 398.318704 -313.673563) (xy 398.36472 -313.656111) (xy 398.412939 -313.646267) (xy 398.462114 -313.644286)
			(xy 398.510969 -313.650218) (xy 398.55824 -313.66391) (xy 398.602702 -313.685008) (xy 398.643205 -313.712964)
			(xy 398.678698 -313.747056) (xy 398.708263 -313.7864) (xy 398.731134 -313.829977) (xy 398.746718 -313.876658)
			(xy 398.754613 -313.925235) (xy 398.755108 -313.949842) (xy 399.09421 -313.949842) (xy 399.09817 -313.900788)
			(xy 399.109947 -313.853004) (xy 399.129238 -313.807728) (xy 399.155541 -313.766132) (xy 399.188176 -313.729295)
			(xy 399.226297 -313.69817) (xy 399.268918 -313.673563) (xy 399.314934 -313.656111) (xy 399.363153 -313.646267)
			(xy 399.412328 -313.644286) (xy 399.461183 -313.650218) (xy 399.508454 -313.66391) (xy 399.552916 -313.685008)
			(xy 399.593419 -313.712964) (xy 399.628912 -313.747056) (xy 399.658477 -313.7864) (xy 399.681348 -313.829977)
			(xy 399.696932 -313.876658) (xy 399.704827 -313.925235) (xy 399.705322 -313.949842) (xy 399.704827 -313.974449)
			(xy 399.704648 -313.97555) (xy 400.023326 -313.97555) (xy 400.023326 -313.924134) (xy 400.031369 -313.873352)
			(xy 400.047257 -313.824453) (xy 400.0706 -313.778641) (xy 400.100821 -313.737045) (xy 400.137177 -313.700689)
			(xy 400.178773 -313.670468) (xy 400.224585 -313.647125) (xy 400.273484 -313.631237) (xy 400.324266 -313.623194)
			(xy 400.375682 -313.623194) (xy 400.426464 -313.631237) (xy 400.475363 -313.647125) (xy 400.521175 -313.670468)
			(xy 400.562771 -313.700689) (xy 400.599127 -313.737045) (xy 400.629348 -313.778641) (xy 400.652691 -313.824453)
			(xy 400.668579 -313.873352) (xy 400.676622 -313.924134) (xy 400.677126 -313.949842) (xy 400.99413 -313.949842)
			(xy 400.99809 -313.900788) (xy 401.009867 -313.853004) (xy 401.029158 -313.807728) (xy 401.055461 -313.766132)
			(xy 401.088096 -313.729295) (xy 401.126217 -313.69817) (xy 401.168838 -313.673563) (xy 401.214854 -313.656111)
			(xy 401.263073 -313.646267) (xy 401.312248 -313.644286) (xy 401.361103 -313.650218) (xy 401.408374 -313.66391)
			(xy 401.452836 -313.685008) (xy 401.493339 -313.712964) (xy 401.528832 -313.747056) (xy 401.558397 -313.7864)
			(xy 401.581268 -313.829977) (xy 401.596852 -313.876658) (xy 401.604747 -313.925235) (xy 401.605242 -313.949842)
			(xy 401.604747 -313.974449) (xy 401.604568 -313.97555) (xy 401.923246 -313.97555) (xy 401.923246 -313.924134)
			(xy 401.931289 -313.873352) (xy 401.947177 -313.824453) (xy 401.97052 -313.778641) (xy 402.000741 -313.737045)
			(xy 402.037097 -313.700689) (xy 402.078693 -313.670468) (xy 402.124505 -313.647125) (xy 402.173404 -313.631237)
			(xy 402.224186 -313.623194) (xy 402.275602 -313.623194) (xy 402.326384 -313.631237) (xy 402.375283 -313.647125)
			(xy 402.421095 -313.670468) (xy 402.462691 -313.700689) (xy 402.499047 -313.737045) (xy 402.529268 -313.778641)
			(xy 402.552611 -313.824453) (xy 402.568499 -313.873352) (xy 402.576542 -313.924134) (xy 402.577046 -313.949842)
			(xy 402.89405 -313.949842) (xy 402.89801 -313.900788) (xy 402.909787 -313.853004) (xy 402.929078 -313.807728)
			(xy 402.955381 -313.766132) (xy 402.988016 -313.729295) (xy 403.026137 -313.69817) (xy 403.068758 -313.673563)
			(xy 403.114774 -313.656111) (xy 403.162993 -313.646267) (xy 403.212168 -313.644286) (xy 403.261023 -313.650218)
			(xy 403.308294 -313.66391) (xy 403.352756 -313.685008) (xy 403.393259 -313.712964) (xy 403.428752 -313.747056)
			(xy 403.458317 -313.7864) (xy 403.481188 -313.829977) (xy 403.496772 -313.876658) (xy 403.504667 -313.925235)
			(xy 403.505162 -313.949842) (xy 403.504667 -313.974449) (xy 403.504488 -313.97555) (xy 403.823166 -313.97555)
			(xy 403.823166 -313.924134) (xy 403.831209 -313.873352) (xy 403.847097 -313.824453) (xy 403.87044 -313.778641)
			(xy 403.900661 -313.737045) (xy 403.937017 -313.700689) (xy 403.978613 -313.670468) (xy 404.024425 -313.647125)
			(xy 404.073324 -313.631237) (xy 404.124106 -313.623194) (xy 404.175522 -313.623194) (xy 404.226304 -313.631237)
			(xy 404.275203 -313.647125) (xy 404.321015 -313.670468) (xy 404.362611 -313.700689) (xy 404.398967 -313.737045)
			(xy 404.429188 -313.778641) (xy 404.452531 -313.824453) (xy 404.468419 -313.873352) (xy 404.476462 -313.924134)
			(xy 404.476966 -313.949842) (xy 404.794224 -313.949842) (xy 404.798184 -313.900788) (xy 404.809961 -313.853004)
			(xy 404.829252 -313.807728) (xy 404.855555 -313.766132) (xy 404.88819 -313.729295) (xy 404.926311 -313.69817)
			(xy 404.968932 -313.673563) (xy 405.014948 -313.656111) (xy 405.063167 -313.646267) (xy 405.112342 -313.644286)
			(xy 405.161197 -313.650218) (xy 405.208468 -313.66391) (xy 405.25293 -313.685008) (xy 405.293433 -313.712964)
			(xy 405.328926 -313.747056) (xy 405.358491 -313.7864) (xy 405.381362 -313.829977) (xy 405.396946 -313.876658)
			(xy 405.404841 -313.925235) (xy 405.405336 -313.949842) (xy 405.404841 -313.974449) (xy 405.404662 -313.97555)
			(xy 405.72334 -313.97555) (xy 405.72334 -313.924134) (xy 405.731383 -313.873352) (xy 405.747271 -313.824453)
			(xy 405.770614 -313.778641) (xy 405.800835 -313.737045) (xy 405.837191 -313.700689) (xy 405.878787 -313.670468)
			(xy 405.924599 -313.647125) (xy 405.973498 -313.631237) (xy 406.02428 -313.623194) (xy 406.075696 -313.623194)
			(xy 406.126478 -313.631237) (xy 406.175377 -313.647125) (xy 406.221189 -313.670468) (xy 406.262785 -313.700689)
			(xy 406.299141 -313.737045) (xy 406.329362 -313.778641) (xy 406.352705 -313.824453) (xy 406.368593 -313.873352)
			(xy 406.376636 -313.924134) (xy 406.37714 -313.949842) (xy 406.694144 -313.949842) (xy 406.698104 -313.900788)
			(xy 406.709881 -313.853004) (xy 406.729172 -313.807728) (xy 406.755475 -313.766132) (xy 406.78811 -313.729295)
			(xy 406.826231 -313.69817) (xy 406.868852 -313.673563) (xy 406.914868 -313.656111) (xy 406.963087 -313.646267)
			(xy 407.012262 -313.644286) (xy 407.061117 -313.650218) (xy 407.108388 -313.66391) (xy 407.15285 -313.685008)
			(xy 407.193353 -313.712964) (xy 407.228846 -313.747056) (xy 407.258411 -313.7864) (xy 407.281282 -313.829977)
			(xy 407.296866 -313.876658) (xy 407.304761 -313.925235) (xy 407.305256 -313.949842) (xy 407.304761 -313.974449)
			(xy 407.304582 -313.97555) (xy 407.62326 -313.97555) (xy 407.62326 -313.924134) (xy 407.631303 -313.873352)
			(xy 407.647191 -313.824453) (xy 407.670534 -313.778641) (xy 407.700755 -313.737045) (xy 407.737111 -313.700689)
			(xy 407.778707 -313.670468) (xy 407.824519 -313.647125) (xy 407.873418 -313.631237) (xy 407.9242 -313.623194)
			(xy 407.975616 -313.623194) (xy 408.026398 -313.631237) (xy 408.075297 -313.647125) (xy 408.121109 -313.670468)
			(xy 408.162705 -313.700689) (xy 408.199061 -313.737045) (xy 408.229282 -313.778641) (xy 408.252625 -313.824453)
			(xy 408.268513 -313.873352) (xy 408.276556 -313.924134) (xy 408.27706 -313.949842) (xy 408.594064 -313.949842)
			(xy 408.598024 -313.900788) (xy 408.609801 -313.853004) (xy 408.629092 -313.807728) (xy 408.655395 -313.766132)
			(xy 408.68803 -313.729295) (xy 408.726151 -313.69817) (xy 408.768772 -313.673563) (xy 408.814788 -313.656111)
			(xy 408.863007 -313.646267) (xy 408.912182 -313.644286) (xy 408.961037 -313.650218) (xy 409.008308 -313.66391)
			(xy 409.05277 -313.685008) (xy 409.093273 -313.712964) (xy 409.128766 -313.747056) (xy 409.158331 -313.7864)
			(xy 409.181202 -313.829977) (xy 409.196786 -313.876658) (xy 409.204681 -313.925235) (xy 409.205176 -313.949842)
			(xy 409.204681 -313.974449) (xy 409.204502 -313.97555) (xy 409.52318 -313.97555) (xy 409.52318 -313.924134)
			(xy 409.531223 -313.873352) (xy 409.547111 -313.824453) (xy 409.570454 -313.778641) (xy 409.600675 -313.737045)
			(xy 409.637031 -313.700689) (xy 409.678627 -313.670468) (xy 409.724439 -313.647125) (xy 409.773338 -313.631237)
			(xy 409.82412 -313.623194) (xy 409.875536 -313.623194) (xy 409.926318 -313.631237) (xy 409.975217 -313.647125)
			(xy 410.021029 -313.670468) (xy 410.062625 -313.700689) (xy 410.098981 -313.737045) (xy 410.129202 -313.778641)
			(xy 410.152545 -313.824453) (xy 410.168433 -313.873352) (xy 410.176476 -313.924134) (xy 410.17698 -313.949842)
			(xy 410.493984 -313.949842) (xy 410.497944 -313.900788) (xy 410.509721 -313.853004) (xy 410.529012 -313.807728)
			(xy 410.555315 -313.766132) (xy 410.58795 -313.729295) (xy 410.626071 -313.69817) (xy 410.668692 -313.673563)
			(xy 410.714708 -313.656111) (xy 410.762927 -313.646267) (xy 410.812102 -313.644286) (xy 410.860957 -313.650218)
			(xy 410.908228 -313.66391) (xy 410.95269 -313.685008) (xy 410.993193 -313.712964) (xy 411.028686 -313.747056)
			(xy 411.058251 -313.7864) (xy 411.081122 -313.829977) (xy 411.096706 -313.876658) (xy 411.104601 -313.925235)
			(xy 411.105096 -313.949842) (xy 411.104601 -313.974449) (xy 411.104422 -313.97555) (xy 411.423354 -313.97555)
			(xy 411.423354 -313.924134) (xy 411.431397 -313.873352) (xy 411.447285 -313.824453) (xy 411.470628 -313.778641)
			(xy 411.500849 -313.737045) (xy 411.537205 -313.700689) (xy 411.578801 -313.670468) (xy 411.624613 -313.647125)
			(xy 411.673512 -313.631237) (xy 411.724294 -313.623194) (xy 411.77571 -313.623194) (xy 411.826492 -313.631237)
			(xy 411.875391 -313.647125) (xy 411.921203 -313.670468) (xy 411.962799 -313.700689) (xy 411.999155 -313.737045)
			(xy 412.029376 -313.778641) (xy 412.052719 -313.824453) (xy 412.068607 -313.873352) (xy 412.07665 -313.924134)
			(xy 412.077154 -313.949842) (xy 412.394158 -313.949842) (xy 412.398118 -313.900788) (xy 412.409895 -313.853004)
			(xy 412.429186 -313.807728) (xy 412.455489 -313.766132) (xy 412.488124 -313.729295) (xy 412.526245 -313.69817)
			(xy 412.568866 -313.673563) (xy 412.614882 -313.656111) (xy 412.663101 -313.646267) (xy 412.712276 -313.644286)
			(xy 412.761131 -313.650218) (xy 412.808402 -313.66391) (xy 412.852864 -313.685008) (xy 412.893367 -313.712964)
			(xy 412.92886 -313.747056) (xy 412.958425 -313.7864) (xy 412.981296 -313.829977) (xy 412.99688 -313.876658)
			(xy 413.004775 -313.925235) (xy 413.00527 -313.949842) (xy 413.004775 -313.974449) (xy 413.004596 -313.97555)
			(xy 413.323274 -313.97555) (xy 413.323274 -313.924134) (xy 413.331317 -313.873352) (xy 413.347205 -313.824453)
			(xy 413.370548 -313.778641) (xy 413.400769 -313.737045) (xy 413.437125 -313.700689) (xy 413.478721 -313.670468)
			(xy 413.524533 -313.647125) (xy 413.573432 -313.631237) (xy 413.624214 -313.623194) (xy 413.67563 -313.623194)
			(xy 413.726412 -313.631237) (xy 413.775311 -313.647125) (xy 413.821123 -313.670468) (xy 413.862719 -313.700689)
			(xy 413.899075 -313.737045) (xy 413.929296 -313.778641) (xy 413.952639 -313.824453) (xy 413.968527 -313.873352)
			(xy 413.97657 -313.924134) (xy 413.977074 -313.949842) (xy 414.294078 -313.949842) (xy 414.298038 -313.900788)
			(xy 414.309815 -313.853004) (xy 414.329106 -313.807728) (xy 414.355409 -313.766132) (xy 414.388044 -313.729295)
			(xy 414.426165 -313.69817) (xy 414.468786 -313.673563) (xy 414.514802 -313.656111) (xy 414.563021 -313.646267)
			(xy 414.612196 -313.644286) (xy 414.661051 -313.650218) (xy 414.708322 -313.66391) (xy 414.752784 -313.685008)
			(xy 414.793287 -313.712964) (xy 414.82878 -313.747056) (xy 414.858345 -313.7864) (xy 414.881216 -313.829977)
			(xy 414.8968 -313.876658) (xy 414.904695 -313.925235) (xy 414.90519 -313.949842) (xy 415.244038 -313.949842)
			(xy 415.247998 -313.900788) (xy 415.259775 -313.853004) (xy 415.279066 -313.807728) (xy 415.305369 -313.766132)
			(xy 415.338004 -313.729295) (xy 415.376125 -313.69817) (xy 415.418746 -313.673563) (xy 415.464762 -313.656111)
			(xy 415.512981 -313.646267) (xy 415.562156 -313.644286) (xy 415.611011 -313.650218) (xy 415.658282 -313.66391)
			(xy 415.702744 -313.685008) (xy 415.743247 -313.712964) (xy 415.77874 -313.747056) (xy 415.808305 -313.7864)
			(xy 415.831176 -313.829977) (xy 415.84676 -313.876658) (xy 415.854655 -313.925235) (xy 415.85515 -313.949842)
			(xy 416.193998 -313.949842) (xy 416.197958 -313.900788) (xy 416.209735 -313.853004) (xy 416.229026 -313.807728)
			(xy 416.255329 -313.766132) (xy 416.287964 -313.729295) (xy 416.326085 -313.69817) (xy 416.368706 -313.673563)
			(xy 416.414722 -313.656111) (xy 416.462941 -313.646267) (xy 416.512116 -313.644286) (xy 416.560971 -313.650218)
			(xy 416.608242 -313.66391) (xy 416.652704 -313.685008) (xy 416.693207 -313.712964) (xy 416.7287 -313.747056)
			(xy 416.758265 -313.7864) (xy 416.781136 -313.829977) (xy 416.79672 -313.876658) (xy 416.804615 -313.925235)
			(xy 416.80511 -313.949842) (xy 417.144212 -313.949842) (xy 417.148172 -313.900788) (xy 417.159949 -313.853004)
			(xy 417.17924 -313.807728) (xy 417.205543 -313.766132) (xy 417.238178 -313.729295) (xy 417.276299 -313.69817)
			(xy 417.31892 -313.673563) (xy 417.364936 -313.656111) (xy 417.413155 -313.646267) (xy 417.46233 -313.644286)
			(xy 417.511185 -313.650218) (xy 417.558456 -313.66391) (xy 417.602918 -313.685008) (xy 417.643421 -313.712964)
			(xy 417.678914 -313.747056) (xy 417.708479 -313.7864) (xy 417.73135 -313.829977) (xy 417.746934 -313.876658)
			(xy 417.754829 -313.925235) (xy 417.755324 -313.949842) (xy 418.094172 -313.949842) (xy 418.098132 -313.900788)
			(xy 418.109909 -313.853004) (xy 418.1292 -313.807728) (xy 418.155503 -313.766132) (xy 418.188138 -313.729295)
			(xy 418.226259 -313.69817) (xy 418.26888 -313.673563) (xy 418.314896 -313.656111) (xy 418.363115 -313.646267)
			(xy 418.41229 -313.644286) (xy 418.461145 -313.650218) (xy 418.508416 -313.66391) (xy 418.552878 -313.685008)
			(xy 418.593381 -313.712964) (xy 418.628874 -313.747056) (xy 418.658439 -313.7864) (xy 418.68131 -313.829977)
			(xy 418.696894 -313.876658) (xy 418.704789 -313.925235) (xy 418.705284 -313.949842) (xy 419.044132 -313.949842)
			(xy 419.048092 -313.900788) (xy 419.059869 -313.853004) (xy 419.07916 -313.807728) (xy 419.105463 -313.766132)
			(xy 419.138098 -313.729295) (xy 419.176219 -313.69817) (xy 419.21884 -313.673563) (xy 419.264856 -313.656111)
			(xy 419.313075 -313.646267) (xy 419.36225 -313.644286) (xy 419.411105 -313.650218) (xy 419.458376 -313.66391)
			(xy 419.502838 -313.685008) (xy 419.543341 -313.712964) (xy 419.578834 -313.747056) (xy 419.608399 -313.7864)
			(xy 419.63127 -313.829977) (xy 419.646854 -313.876658) (xy 419.654749 -313.925235) (xy 419.655244 -313.949842)
			(xy 419.994092 -313.949842) (xy 419.998052 -313.900788) (xy 420.009829 -313.853004) (xy 420.02912 -313.807728)
			(xy 420.055423 -313.766132) (xy 420.088058 -313.729295) (xy 420.126179 -313.69817) (xy 420.1688 -313.673563)
			(xy 420.214816 -313.656111) (xy 420.263035 -313.646267) (xy 420.31221 -313.644286) (xy 420.361065 -313.650218)
			(xy 420.408336 -313.66391) (xy 420.452798 -313.685008) (xy 420.493301 -313.712964) (xy 420.528794 -313.747056)
			(xy 420.558359 -313.7864) (xy 420.58123 -313.829977) (xy 420.596814 -313.876658) (xy 420.604709 -313.925235)
			(xy 420.605204 -313.949842) (xy 420.944052 -313.949842) (xy 420.948012 -313.900788) (xy 420.959789 -313.853004)
			(xy 420.97908 -313.807728) (xy 421.005383 -313.766132) (xy 421.038018 -313.729295) (xy 421.076139 -313.69817)
			(xy 421.11876 -313.673563) (xy 421.164776 -313.656111) (xy 421.212995 -313.646267) (xy 421.26217 -313.644286)
			(xy 421.311025 -313.650218) (xy 421.358296 -313.66391) (xy 421.402758 -313.685008) (xy 421.443261 -313.712964)
			(xy 421.478754 -313.747056) (xy 421.508319 -313.7864) (xy 421.53119 -313.829977) (xy 421.546774 -313.876658)
			(xy 421.554669 -313.925235) (xy 421.555164 -313.949842) (xy 421.894012 -313.949842) (xy 421.897972 -313.900788)
			(xy 421.909749 -313.853004) (xy 421.92904 -313.807728) (xy 421.955343 -313.766132) (xy 421.987978 -313.729295)
			(xy 422.026099 -313.69817) (xy 422.06872 -313.673563) (xy 422.114736 -313.656111) (xy 422.162955 -313.646267)
			(xy 422.21213 -313.644286) (xy 422.260985 -313.650218) (xy 422.308256 -313.66391) (xy 422.352718 -313.685008)
			(xy 422.393221 -313.712964) (xy 422.428714 -313.747056) (xy 422.458279 -313.7864) (xy 422.48115 -313.829977)
			(xy 422.496734 -313.876658) (xy 422.504629 -313.925235) (xy 422.505124 -313.949842) (xy 422.504629 -313.974449)
			(xy 422.50445 -313.97555) (xy 422.823382 -313.97555) (xy 422.823382 -313.924134) (xy 422.831425 -313.873352)
			(xy 422.847313 -313.824453) (xy 422.870656 -313.778641) (xy 422.900877 -313.737045) (xy 422.937233 -313.700689)
			(xy 422.978829 -313.670468) (xy 423.024641 -313.647125) (xy 423.07354 -313.631237) (xy 423.124322 -313.623194)
			(xy 423.175738 -313.623194) (xy 423.22652 -313.631237) (xy 423.275419 -313.647125) (xy 423.321231 -313.670468)
			(xy 423.362827 -313.700689) (xy 423.399183 -313.737045) (xy 423.429404 -313.778641) (xy 423.452747 -313.824453)
			(xy 423.468635 -313.873352) (xy 423.476678 -313.924134) (xy 423.477182 -313.949842) (xy 423.794186 -313.949842)
			(xy 423.798146 -313.900788) (xy 423.809923 -313.853004) (xy 423.829214 -313.807728) (xy 423.855517 -313.766132)
			(xy 423.888152 -313.729295) (xy 423.926273 -313.69817) (xy 423.968894 -313.673563) (xy 424.01491 -313.656111)
			(xy 424.063129 -313.646267) (xy 424.112304 -313.644286) (xy 424.161159 -313.650218) (xy 424.20843 -313.66391)
			(xy 424.252892 -313.685008) (xy 424.293395 -313.712964) (xy 424.328888 -313.747056) (xy 424.358453 -313.7864)
			(xy 424.381324 -313.829977) (xy 424.396908 -313.876658) (xy 424.404803 -313.925235) (xy 424.405298 -313.949842)
			(xy 424.404803 -313.974449) (xy 424.404624 -313.97555) (xy 424.723302 -313.97555) (xy 424.723302 -313.924134)
			(xy 424.731345 -313.873352) (xy 424.747233 -313.824453) (xy 424.770576 -313.778641) (xy 424.800797 -313.737045)
			(xy 424.837153 -313.700689) (xy 424.878749 -313.670468) (xy 424.924561 -313.647125) (xy 424.97346 -313.631237)
			(xy 425.024242 -313.623194) (xy 425.075658 -313.623194) (xy 425.12644 -313.631237) (xy 425.175339 -313.647125)
			(xy 425.221151 -313.670468) (xy 425.262747 -313.700689) (xy 425.299103 -313.737045) (xy 425.329324 -313.778641)
			(xy 425.352667 -313.824453) (xy 425.368555 -313.873352) (xy 425.376598 -313.924134) (xy 425.377102 -313.949842)
			(xy 425.694106 -313.949842) (xy 425.698066 -313.900788) (xy 425.709843 -313.853004) (xy 425.729134 -313.807728)
			(xy 425.755437 -313.766132) (xy 425.788072 -313.729295) (xy 425.826193 -313.69817) (xy 425.868814 -313.673563)
			(xy 425.91483 -313.656111) (xy 425.963049 -313.646267) (xy 426.012224 -313.644286) (xy 426.061079 -313.650218)
			(xy 426.10835 -313.66391) (xy 426.152812 -313.685008) (xy 426.193315 -313.712964) (xy 426.228808 -313.747056)
			(xy 426.258373 -313.7864) (xy 426.281244 -313.829977) (xy 426.296828 -313.876658) (xy 426.304723 -313.925235)
			(xy 426.305218 -313.949842) (xy 426.304723 -313.974449) (xy 426.304544 -313.97555) (xy 426.623222 -313.97555)
			(xy 426.623222 -313.924134) (xy 426.631265 -313.873352) (xy 426.647153 -313.824453) (xy 426.670496 -313.778641)
			(xy 426.700717 -313.737045) (xy 426.737073 -313.700689) (xy 426.778669 -313.670468) (xy 426.824481 -313.647125)
			(xy 426.87338 -313.631237) (xy 426.924162 -313.623194) (xy 426.975578 -313.623194) (xy 427.02636 -313.631237)
			(xy 427.075259 -313.647125) (xy 427.121071 -313.670468) (xy 427.162667 -313.700689) (xy 427.199023 -313.737045)
			(xy 427.229244 -313.778641) (xy 427.252587 -313.824453) (xy 427.268475 -313.873352) (xy 427.276518 -313.924134)
			(xy 427.277022 -313.949842) (xy 427.594026 -313.949842) (xy 427.597986 -313.900788) (xy 427.609763 -313.853004)
			(xy 427.629054 -313.807728) (xy 427.655357 -313.766132) (xy 427.687992 -313.729295) (xy 427.726113 -313.69817)
			(xy 427.768734 -313.673563) (xy 427.81475 -313.656111) (xy 427.862969 -313.646267) (xy 427.912144 -313.644286)
			(xy 427.960999 -313.650218) (xy 428.00827 -313.66391) (xy 428.052732 -313.685008) (xy 428.093235 -313.712964)
			(xy 428.128728 -313.747056) (xy 428.158293 -313.7864) (xy 428.181164 -313.829977) (xy 428.196748 -313.876658)
			(xy 428.204643 -313.925235) (xy 428.205138 -313.949842) (xy 428.204643 -313.974449) (xy 428.204464 -313.97555)
			(xy 428.523142 -313.97555) (xy 428.523142 -313.924134) (xy 428.531185 -313.873352) (xy 428.547073 -313.824453)
			(xy 428.570416 -313.778641) (xy 428.600637 -313.737045) (xy 428.636993 -313.700689) (xy 428.678589 -313.670468)
			(xy 428.724401 -313.647125) (xy 428.7733 -313.631237) (xy 428.824082 -313.623194) (xy 428.875498 -313.623194)
			(xy 428.92628 -313.631237) (xy 428.975179 -313.647125) (xy 429.020991 -313.670468) (xy 429.062587 -313.700689)
			(xy 429.098943 -313.737045) (xy 429.129164 -313.778641) (xy 429.152507 -313.824453) (xy 429.168395 -313.873352)
			(xy 429.176438 -313.924134) (xy 429.176942 -313.949842) (xy 429.4942 -313.949842) (xy 429.49816 -313.900788)
			(xy 429.509937 -313.853004) (xy 429.529228 -313.807728) (xy 429.555531 -313.766132) (xy 429.588166 -313.729295)
			(xy 429.626287 -313.69817) (xy 429.668908 -313.673563) (xy 429.714924 -313.656111) (xy 429.763143 -313.646267)
			(xy 429.812318 -313.644286) (xy 429.861173 -313.650218) (xy 429.908444 -313.66391) (xy 429.952906 -313.685008)
			(xy 429.993409 -313.712964) (xy 430.028902 -313.747056) (xy 430.058467 -313.7864) (xy 430.081338 -313.829977)
			(xy 430.096922 -313.876658) (xy 430.104817 -313.925235) (xy 430.105312 -313.949842) (xy 430.44416 -313.949842)
			(xy 430.44812 -313.900788) (xy 430.459897 -313.853004) (xy 430.479188 -313.807728) (xy 430.505491 -313.766132)
			(xy 430.538126 -313.729295) (xy 430.576247 -313.69817) (xy 430.618868 -313.673563) (xy 430.664884 -313.656111)
			(xy 430.713103 -313.646267) (xy 430.762278 -313.644286) (xy 430.811133 -313.650218) (xy 430.858404 -313.66391)
			(xy 430.902866 -313.685008) (xy 430.943369 -313.712964) (xy 430.978862 -313.747056) (xy 431.008427 -313.7864)
			(xy 431.031298 -313.829977) (xy 431.046882 -313.876658) (xy 431.054777 -313.925235) (xy 431.055272 -313.949842)
			(xy 431.054777 -313.974449) (xy 431.046882 -314.023026) (xy 431.031298 -314.069707) (xy 431.008427 -314.113284)
			(xy 430.978862 -314.152628) (xy 430.943369 -314.18672) (xy 430.902866 -314.214676) (xy 430.858404 -314.235774)
			(xy 430.811133 -314.249466) (xy 430.762278 -314.255398) (xy 430.713103 -314.253417) (xy 430.664884 -314.243573)
			(xy 430.618868 -314.226121) (xy 430.576247 -314.201514) (xy 430.538126 -314.170389) (xy 430.505491 -314.133552)
			(xy 430.479188 -314.091956) (xy 430.459897 -314.04668) (xy 430.44812 -313.998896) (xy 430.44416 -313.949842)
			(xy 430.105312 -313.949842) (xy 430.104817 -313.974449) (xy 430.096922 -314.023026) (xy 430.081338 -314.069707)
			(xy 430.058467 -314.113284) (xy 430.028902 -314.152628) (xy 429.993409 -314.18672) (xy 429.952906 -314.214676)
			(xy 429.908444 -314.235774) (xy 429.861173 -314.249466) (xy 429.812318 -314.255398) (xy 429.763143 -314.253417)
			(xy 429.714924 -314.243573) (xy 429.668908 -314.226121) (xy 429.626287 -314.201514) (xy 429.588166 -314.170389)
			(xy 429.555531 -314.133552) (xy 429.529228 -314.091956) (xy 429.509937 -314.04668) (xy 429.49816 -313.998896)
			(xy 429.4942 -313.949842) (xy 429.176942 -313.949842) (xy 429.176438 -313.97555) (xy 429.168395 -314.026332)
			(xy 429.152507 -314.075231) (xy 429.129164 -314.121043) (xy 429.098943 -314.162639) (xy 429.062587 -314.198995)
			(xy 429.020991 -314.229216) (xy 428.975179 -314.252559) (xy 428.92628 -314.268447) (xy 428.875498 -314.27649)
			(xy 428.824082 -314.27649) (xy 428.7733 -314.268447) (xy 428.724401 -314.252559) (xy 428.678589 -314.229216)
			(xy 428.636993 -314.198995) (xy 428.600637 -314.162639) (xy 428.570416 -314.121043) (xy 428.547073 -314.075231)
			(xy 428.531185 -314.026332) (xy 428.523142 -313.97555) (xy 428.204464 -313.97555) (xy 428.196748 -314.023026)
			(xy 428.181164 -314.069707) (xy 428.158293 -314.113284) (xy 428.128728 -314.152628) (xy 428.093235 -314.18672)
			(xy 428.052732 -314.214676) (xy 428.00827 -314.235774) (xy 427.960999 -314.249466) (xy 427.912144 -314.255398)
			(xy 427.862969 -314.253417) (xy 427.81475 -314.243573) (xy 427.768734 -314.226121) (xy 427.726113 -314.201514)
			(xy 427.687992 -314.170389) (xy 427.655357 -314.133552) (xy 427.629054 -314.091956) (xy 427.609763 -314.04668)
			(xy 427.597986 -313.998896) (xy 427.594026 -313.949842) (xy 427.277022 -313.949842) (xy 427.276518 -313.97555)
			(xy 427.268475 -314.026332) (xy 427.252587 -314.075231) (xy 427.229244 -314.121043) (xy 427.199023 -314.162639)
			(xy 427.162667 -314.198995) (xy 427.121071 -314.229216) (xy 427.075259 -314.252559) (xy 427.02636 -314.268447)
			(xy 426.975578 -314.27649) (xy 426.924162 -314.27649) (xy 426.87338 -314.268447) (xy 426.824481 -314.252559)
			(xy 426.778669 -314.229216) (xy 426.737073 -314.198995) (xy 426.700717 -314.162639) (xy 426.670496 -314.121043)
			(xy 426.647153 -314.075231) (xy 426.631265 -314.026332) (xy 426.623222 -313.97555) (xy 426.304544 -313.97555)
			(xy 426.296828 -314.023026) (xy 426.281244 -314.069707) (xy 426.258373 -314.113284) (xy 426.228808 -314.152628)
			(xy 426.193315 -314.18672) (xy 426.152812 -314.214676) (xy 426.10835 -314.235774) (xy 426.061079 -314.249466)
			(xy 426.012224 -314.255398) (xy 425.963049 -314.253417) (xy 425.91483 -314.243573) (xy 425.868814 -314.226121)
			(xy 425.826193 -314.201514) (xy 425.788072 -314.170389) (xy 425.755437 -314.133552) (xy 425.729134 -314.091956)
			(xy 425.709843 -314.04668) (xy 425.698066 -313.998896) (xy 425.694106 -313.949842) (xy 425.377102 -313.949842)
			(xy 425.376598 -313.97555) (xy 425.368555 -314.026332) (xy 425.352667 -314.075231) (xy 425.329324 -314.121043)
			(xy 425.299103 -314.162639) (xy 425.262747 -314.198995) (xy 425.221151 -314.229216) (xy 425.175339 -314.252559)
			(xy 425.12644 -314.268447) (xy 425.075658 -314.27649) (xy 425.024242 -314.27649) (xy 424.97346 -314.268447)
			(xy 424.924561 -314.252559) (xy 424.878749 -314.229216) (xy 424.837153 -314.198995) (xy 424.800797 -314.162639)
			(xy 424.770576 -314.121043) (xy 424.747233 -314.075231) (xy 424.731345 -314.026332) (xy 424.723302 -313.97555)
			(xy 424.404624 -313.97555) (xy 424.396908 -314.023026) (xy 424.381324 -314.069707) (xy 424.358453 -314.113284)
			(xy 424.328888 -314.152628) (xy 424.293395 -314.18672) (xy 424.252892 -314.214676) (xy 424.20843 -314.235774)
			(xy 424.161159 -314.249466) (xy 424.112304 -314.255398) (xy 424.063129 -314.253417) (xy 424.01491 -314.243573)
			(xy 423.968894 -314.226121) (xy 423.926273 -314.201514) (xy 423.888152 -314.170389) (xy 423.855517 -314.133552)
			(xy 423.829214 -314.091956) (xy 423.809923 -314.04668) (xy 423.798146 -313.998896) (xy 423.794186 -313.949842)
			(xy 423.477182 -313.949842) (xy 423.476678 -313.97555) (xy 423.468635 -314.026332) (xy 423.452747 -314.075231)
			(xy 423.429404 -314.121043) (xy 423.399183 -314.162639) (xy 423.362827 -314.198995) (xy 423.321231 -314.229216)
			(xy 423.275419 -314.252559) (xy 423.22652 -314.268447) (xy 423.175738 -314.27649) (xy 423.124322 -314.27649)
			(xy 423.07354 -314.268447) (xy 423.024641 -314.252559) (xy 422.978829 -314.229216) (xy 422.937233 -314.198995)
			(xy 422.900877 -314.162639) (xy 422.870656 -314.121043) (xy 422.847313 -314.075231) (xy 422.831425 -314.026332)
			(xy 422.823382 -313.97555) (xy 422.50445 -313.97555) (xy 422.496734 -314.023026) (xy 422.48115 -314.069707)
			(xy 422.458279 -314.113284) (xy 422.428714 -314.152628) (xy 422.393221 -314.18672) (xy 422.352718 -314.214676)
			(xy 422.308256 -314.235774) (xy 422.260985 -314.249466) (xy 422.21213 -314.255398) (xy 422.162955 -314.253417)
			(xy 422.114736 -314.243573) (xy 422.06872 -314.226121) (xy 422.026099 -314.201514) (xy 421.987978 -314.170389)
			(xy 421.955343 -314.133552) (xy 421.92904 -314.091956) (xy 421.909749 -314.04668) (xy 421.897972 -313.998896)
			(xy 421.894012 -313.949842) (xy 421.555164 -313.949842) (xy 421.554669 -313.974449) (xy 421.546774 -314.023026)
			(xy 421.53119 -314.069707) (xy 421.508319 -314.113284) (xy 421.478754 -314.152628) (xy 421.443261 -314.18672)
			(xy 421.402758 -314.214676) (xy 421.358296 -314.235774) (xy 421.311025 -314.249466) (xy 421.26217 -314.255398)
			(xy 421.212995 -314.253417) (xy 421.164776 -314.243573) (xy 421.11876 -314.226121) (xy 421.076139 -314.201514)
			(xy 421.038018 -314.170389) (xy 421.005383 -314.133552) (xy 420.97908 -314.091956) (xy 420.959789 -314.04668)
			(xy 420.948012 -313.998896) (xy 420.944052 -313.949842) (xy 420.605204 -313.949842) (xy 420.604709 -313.974449)
			(xy 420.596814 -314.023026) (xy 420.58123 -314.069707) (xy 420.558359 -314.113284) (xy 420.528794 -314.152628)
			(xy 420.493301 -314.18672) (xy 420.452798 -314.214676) (xy 420.408336 -314.235774) (xy 420.361065 -314.249466)
			(xy 420.31221 -314.255398) (xy 420.263035 -314.253417) (xy 420.214816 -314.243573) (xy 420.1688 -314.226121)
			(xy 420.126179 -314.201514) (xy 420.088058 -314.170389) (xy 420.055423 -314.133552) (xy 420.02912 -314.091956)
			(xy 420.009829 -314.04668) (xy 419.998052 -313.998896) (xy 419.994092 -313.949842) (xy 419.655244 -313.949842)
			(xy 419.654749 -313.974449) (xy 419.646854 -314.023026) (xy 419.63127 -314.069707) (xy 419.608399 -314.113284)
			(xy 419.578834 -314.152628) (xy 419.543341 -314.18672) (xy 419.502838 -314.214676) (xy 419.458376 -314.235774)
			(xy 419.411105 -314.249466) (xy 419.36225 -314.255398) (xy 419.313075 -314.253417) (xy 419.264856 -314.243573)
			(xy 419.21884 -314.226121) (xy 419.176219 -314.201514) (xy 419.138098 -314.170389) (xy 419.105463 -314.133552)
			(xy 419.07916 -314.091956) (xy 419.059869 -314.04668) (xy 419.048092 -313.998896) (xy 419.044132 -313.949842)
			(xy 418.705284 -313.949842) (xy 418.704789 -313.974449) (xy 418.696894 -314.023026) (xy 418.68131 -314.069707)
			(xy 418.658439 -314.113284) (xy 418.628874 -314.152628) (xy 418.593381 -314.18672) (xy 418.552878 -314.214676)
			(xy 418.508416 -314.235774) (xy 418.461145 -314.249466) (xy 418.41229 -314.255398) (xy 418.363115 -314.253417)
			(xy 418.314896 -314.243573) (xy 418.26888 -314.226121) (xy 418.226259 -314.201514) (xy 418.188138 -314.170389)
			(xy 418.155503 -314.133552) (xy 418.1292 -314.091956) (xy 418.109909 -314.04668) (xy 418.098132 -313.998896)
			(xy 418.094172 -313.949842) (xy 417.755324 -313.949842) (xy 417.754829 -313.974449) (xy 417.746934 -314.023026)
			(xy 417.73135 -314.069707) (xy 417.708479 -314.113284) (xy 417.678914 -314.152628) (xy 417.643421 -314.18672)
			(xy 417.602918 -314.214676) (xy 417.558456 -314.235774) (xy 417.511185 -314.249466) (xy 417.46233 -314.255398)
			(xy 417.413155 -314.253417) (xy 417.364936 -314.243573) (xy 417.31892 -314.226121) (xy 417.276299 -314.201514)
			(xy 417.238178 -314.170389) (xy 417.205543 -314.133552) (xy 417.17924 -314.091956) (xy 417.159949 -314.04668)
			(xy 417.148172 -313.998896) (xy 417.144212 -313.949842) (xy 416.80511 -313.949842) (xy 416.804615 -313.974449)
			(xy 416.79672 -314.023026) (xy 416.781136 -314.069707) (xy 416.758265 -314.113284) (xy 416.7287 -314.152628)
			(xy 416.693207 -314.18672) (xy 416.652704 -314.214676) (xy 416.608242 -314.235774) (xy 416.560971 -314.249466)
			(xy 416.512116 -314.255398) (xy 416.462941 -314.253417) (xy 416.414722 -314.243573) (xy 416.368706 -314.226121)
			(xy 416.326085 -314.201514) (xy 416.287964 -314.170389) (xy 416.255329 -314.133552) (xy 416.229026 -314.091956)
			(xy 416.209735 -314.04668) (xy 416.197958 -313.998896) (xy 416.193998 -313.949842) (xy 415.85515 -313.949842)
			(xy 415.854655 -313.974449) (xy 415.84676 -314.023026) (xy 415.831176 -314.069707) (xy 415.808305 -314.113284)
			(xy 415.77874 -314.152628) (xy 415.743247 -314.18672) (xy 415.702744 -314.214676) (xy 415.658282 -314.235774)
			(xy 415.611011 -314.249466) (xy 415.562156 -314.255398) (xy 415.512981 -314.253417) (xy 415.464762 -314.243573)
			(xy 415.418746 -314.226121) (xy 415.376125 -314.201514) (xy 415.338004 -314.170389) (xy 415.305369 -314.133552)
			(xy 415.279066 -314.091956) (xy 415.259775 -314.04668) (xy 415.247998 -313.998896) (xy 415.244038 -313.949842)
			(xy 414.90519 -313.949842) (xy 414.904695 -313.974449) (xy 414.8968 -314.023026) (xy 414.881216 -314.069707)
			(xy 414.858345 -314.113284) (xy 414.82878 -314.152628) (xy 414.793287 -314.18672) (xy 414.752784 -314.214676)
			(xy 414.708322 -314.235774) (xy 414.661051 -314.249466) (xy 414.612196 -314.255398) (xy 414.563021 -314.253417)
			(xy 414.514802 -314.243573) (xy 414.468786 -314.226121) (xy 414.426165 -314.201514) (xy 414.388044 -314.170389)
			(xy 414.355409 -314.133552) (xy 414.329106 -314.091956) (xy 414.309815 -314.04668) (xy 414.298038 -313.998896)
			(xy 414.294078 -313.949842) (xy 413.977074 -313.949842) (xy 413.97657 -313.97555) (xy 413.968527 -314.026332)
			(xy 413.952639 -314.075231) (xy 413.929296 -314.121043) (xy 413.899075 -314.162639) (xy 413.862719 -314.198995)
			(xy 413.821123 -314.229216) (xy 413.775311 -314.252559) (xy 413.726412 -314.268447) (xy 413.67563 -314.27649)
			(xy 413.624214 -314.27649) (xy 413.573432 -314.268447) (xy 413.524533 -314.252559) (xy 413.478721 -314.229216)
			(xy 413.437125 -314.198995) (xy 413.400769 -314.162639) (xy 413.370548 -314.121043) (xy 413.347205 -314.075231)
			(xy 413.331317 -314.026332) (xy 413.323274 -313.97555) (xy 413.004596 -313.97555) (xy 412.99688 -314.023026)
			(xy 412.981296 -314.069707) (xy 412.958425 -314.113284) (xy 412.92886 -314.152628) (xy 412.893367 -314.18672)
			(xy 412.852864 -314.214676) (xy 412.808402 -314.235774) (xy 412.761131 -314.249466) (xy 412.712276 -314.255398)
			(xy 412.663101 -314.253417) (xy 412.614882 -314.243573) (xy 412.568866 -314.226121) (xy 412.526245 -314.201514)
			(xy 412.488124 -314.170389) (xy 412.455489 -314.133552) (xy 412.429186 -314.091956) (xy 412.409895 -314.04668)
			(xy 412.398118 -313.998896) (xy 412.394158 -313.949842) (xy 412.077154 -313.949842) (xy 412.07665 -313.97555)
			(xy 412.068607 -314.026332) (xy 412.052719 -314.075231) (xy 412.029376 -314.121043) (xy 411.999155 -314.162639)
			(xy 411.962799 -314.198995) (xy 411.921203 -314.229216) (xy 411.875391 -314.252559) (xy 411.826492 -314.268447)
			(xy 411.77571 -314.27649) (xy 411.724294 -314.27649) (xy 411.673512 -314.268447) (xy 411.624613 -314.252559)
			(xy 411.578801 -314.229216) (xy 411.537205 -314.198995) (xy 411.500849 -314.162639) (xy 411.470628 -314.121043)
			(xy 411.447285 -314.075231) (xy 411.431397 -314.026332) (xy 411.423354 -313.97555) (xy 411.104422 -313.97555)
			(xy 411.096706 -314.023026) (xy 411.081122 -314.069707) (xy 411.058251 -314.113284) (xy 411.028686 -314.152628)
			(xy 410.993193 -314.18672) (xy 410.95269 -314.214676) (xy 410.908228 -314.235774) (xy 410.860957 -314.249466)
			(xy 410.812102 -314.255398) (xy 410.762927 -314.253417) (xy 410.714708 -314.243573) (xy 410.668692 -314.226121)
			(xy 410.626071 -314.201514) (xy 410.58795 -314.170389) (xy 410.555315 -314.133552) (xy 410.529012 -314.091956)
			(xy 410.509721 -314.04668) (xy 410.497944 -313.998896) (xy 410.493984 -313.949842) (xy 410.17698 -313.949842)
			(xy 410.176476 -313.97555) (xy 410.168433 -314.026332) (xy 410.152545 -314.075231) (xy 410.129202 -314.121043)
			(xy 410.098981 -314.162639) (xy 410.062625 -314.198995) (xy 410.021029 -314.229216) (xy 409.975217 -314.252559)
			(xy 409.926318 -314.268447) (xy 409.875536 -314.27649) (xy 409.82412 -314.27649) (xy 409.773338 -314.268447)
			(xy 409.724439 -314.252559) (xy 409.678627 -314.229216) (xy 409.637031 -314.198995) (xy 409.600675 -314.162639)
			(xy 409.570454 -314.121043) (xy 409.547111 -314.075231) (xy 409.531223 -314.026332) (xy 409.52318 -313.97555)
			(xy 409.204502 -313.97555) (xy 409.196786 -314.023026) (xy 409.181202 -314.069707) (xy 409.158331 -314.113284)
			(xy 409.128766 -314.152628) (xy 409.093273 -314.18672) (xy 409.05277 -314.214676) (xy 409.008308 -314.235774)
			(xy 408.961037 -314.249466) (xy 408.912182 -314.255398) (xy 408.863007 -314.253417) (xy 408.814788 -314.243573)
			(xy 408.768772 -314.226121) (xy 408.726151 -314.201514) (xy 408.68803 -314.170389) (xy 408.655395 -314.133552)
			(xy 408.629092 -314.091956) (xy 408.609801 -314.04668) (xy 408.598024 -313.998896) (xy 408.594064 -313.949842)
			(xy 408.27706 -313.949842) (xy 408.276556 -313.97555) (xy 408.268513 -314.026332) (xy 408.252625 -314.075231)
			(xy 408.229282 -314.121043) (xy 408.199061 -314.162639) (xy 408.162705 -314.198995) (xy 408.121109 -314.229216)
			(xy 408.075297 -314.252559) (xy 408.026398 -314.268447) (xy 407.975616 -314.27649) (xy 407.9242 -314.27649)
			(xy 407.873418 -314.268447) (xy 407.824519 -314.252559) (xy 407.778707 -314.229216) (xy 407.737111 -314.198995)
			(xy 407.700755 -314.162639) (xy 407.670534 -314.121043) (xy 407.647191 -314.075231) (xy 407.631303 -314.026332)
			(xy 407.62326 -313.97555) (xy 407.304582 -313.97555) (xy 407.296866 -314.023026) (xy 407.281282 -314.069707)
			(xy 407.258411 -314.113284) (xy 407.228846 -314.152628) (xy 407.193353 -314.18672) (xy 407.15285 -314.214676)
			(xy 407.108388 -314.235774) (xy 407.061117 -314.249466) (xy 407.012262 -314.255398) (xy 406.963087 -314.253417)
			(xy 406.914868 -314.243573) (xy 406.868852 -314.226121) (xy 406.826231 -314.201514) (xy 406.78811 -314.170389)
			(xy 406.755475 -314.133552) (xy 406.729172 -314.091956) (xy 406.709881 -314.04668) (xy 406.698104 -313.998896)
			(xy 406.694144 -313.949842) (xy 406.37714 -313.949842) (xy 406.376636 -313.97555) (xy 406.368593 -314.026332)
			(xy 406.352705 -314.075231) (xy 406.329362 -314.121043) (xy 406.299141 -314.162639) (xy 406.262785 -314.198995)
			(xy 406.221189 -314.229216) (xy 406.175377 -314.252559) (xy 406.126478 -314.268447) (xy 406.075696 -314.27649)
			(xy 406.02428 -314.27649) (xy 405.973498 -314.268447) (xy 405.924599 -314.252559) (xy 405.878787 -314.229216)
			(xy 405.837191 -314.198995) (xy 405.800835 -314.162639) (xy 405.770614 -314.121043) (xy 405.747271 -314.075231)
			(xy 405.731383 -314.026332) (xy 405.72334 -313.97555) (xy 405.404662 -313.97555) (xy 405.396946 -314.023026)
			(xy 405.381362 -314.069707) (xy 405.358491 -314.113284) (xy 405.328926 -314.152628) (xy 405.293433 -314.18672)
			(xy 405.25293 -314.214676) (xy 405.208468 -314.235774) (xy 405.161197 -314.249466) (xy 405.112342 -314.255398)
			(xy 405.063167 -314.253417) (xy 405.014948 -314.243573) (xy 404.968932 -314.226121) (xy 404.926311 -314.201514)
			(xy 404.88819 -314.170389) (xy 404.855555 -314.133552) (xy 404.829252 -314.091956) (xy 404.809961 -314.04668)
			(xy 404.798184 -313.998896) (xy 404.794224 -313.949842) (xy 404.476966 -313.949842) (xy 404.476462 -313.97555)
			(xy 404.468419 -314.026332) (xy 404.452531 -314.075231) (xy 404.429188 -314.121043) (xy 404.398967 -314.162639)
			(xy 404.362611 -314.198995) (xy 404.321015 -314.229216) (xy 404.275203 -314.252559) (xy 404.226304 -314.268447)
			(xy 404.175522 -314.27649) (xy 404.124106 -314.27649) (xy 404.073324 -314.268447) (xy 404.024425 -314.252559)
			(xy 403.978613 -314.229216) (xy 403.937017 -314.198995) (xy 403.900661 -314.162639) (xy 403.87044 -314.121043)
			(xy 403.847097 -314.075231) (xy 403.831209 -314.026332) (xy 403.823166 -313.97555) (xy 403.504488 -313.97555)
			(xy 403.496772 -314.023026) (xy 403.481188 -314.069707) (xy 403.458317 -314.113284) (xy 403.428752 -314.152628)
			(xy 403.393259 -314.18672) (xy 403.352756 -314.214676) (xy 403.308294 -314.235774) (xy 403.261023 -314.249466)
			(xy 403.212168 -314.255398) (xy 403.162993 -314.253417) (xy 403.114774 -314.243573) (xy 403.068758 -314.226121)
			(xy 403.026137 -314.201514) (xy 402.988016 -314.170389) (xy 402.955381 -314.133552) (xy 402.929078 -314.091956)
			(xy 402.909787 -314.04668) (xy 402.89801 -313.998896) (xy 402.89405 -313.949842) (xy 402.577046 -313.949842)
			(xy 402.576542 -313.97555) (xy 402.568499 -314.026332) (xy 402.552611 -314.075231) (xy 402.529268 -314.121043)
			(xy 402.499047 -314.162639) (xy 402.462691 -314.198995) (xy 402.421095 -314.229216) (xy 402.375283 -314.252559)
			(xy 402.326384 -314.268447) (xy 402.275602 -314.27649) (xy 402.224186 -314.27649) (xy 402.173404 -314.268447)
			(xy 402.124505 -314.252559) (xy 402.078693 -314.229216) (xy 402.037097 -314.198995) (xy 402.000741 -314.162639)
			(xy 401.97052 -314.121043) (xy 401.947177 -314.075231) (xy 401.931289 -314.026332) (xy 401.923246 -313.97555)
			(xy 401.604568 -313.97555) (xy 401.596852 -314.023026) (xy 401.581268 -314.069707) (xy 401.558397 -314.113284)
			(xy 401.528832 -314.152628) (xy 401.493339 -314.18672) (xy 401.452836 -314.214676) (xy 401.408374 -314.235774)
			(xy 401.361103 -314.249466) (xy 401.312248 -314.255398) (xy 401.263073 -314.253417) (xy 401.214854 -314.243573)
			(xy 401.168838 -314.226121) (xy 401.126217 -314.201514) (xy 401.088096 -314.170389) (xy 401.055461 -314.133552)
			(xy 401.029158 -314.091956) (xy 401.009867 -314.04668) (xy 400.99809 -313.998896) (xy 400.99413 -313.949842)
			(xy 400.677126 -313.949842) (xy 400.676622 -313.97555) (xy 400.668579 -314.026332) (xy 400.652691 -314.075231)
			(xy 400.629348 -314.121043) (xy 400.599127 -314.162639) (xy 400.562771 -314.198995) (xy 400.521175 -314.229216)
			(xy 400.475363 -314.252559) (xy 400.426464 -314.268447) (xy 400.375682 -314.27649) (xy 400.324266 -314.27649)
			(xy 400.273484 -314.268447) (xy 400.224585 -314.252559) (xy 400.178773 -314.229216) (xy 400.137177 -314.198995)
			(xy 400.100821 -314.162639) (xy 400.0706 -314.121043) (xy 400.047257 -314.075231) (xy 400.031369 -314.026332)
			(xy 400.023326 -313.97555) (xy 399.704648 -313.97555) (xy 399.696932 -314.023026) (xy 399.681348 -314.069707)
			(xy 399.658477 -314.113284) (xy 399.628912 -314.152628) (xy 399.593419 -314.18672) (xy 399.552916 -314.214676)
			(xy 399.508454 -314.235774) (xy 399.461183 -314.249466) (xy 399.412328 -314.255398) (xy 399.363153 -314.253417)
			(xy 399.314934 -314.243573) (xy 399.268918 -314.226121) (xy 399.226297 -314.201514) (xy 399.188176 -314.170389)
			(xy 399.155541 -314.133552) (xy 399.129238 -314.091956) (xy 399.109947 -314.04668) (xy 399.09817 -313.998896)
			(xy 399.09421 -313.949842) (xy 398.755108 -313.949842) (xy 398.754613 -313.974449) (xy 398.746718 -314.023026)
			(xy 398.731134 -314.069707) (xy 398.708263 -314.113284) (xy 398.678698 -314.152628) (xy 398.643205 -314.18672)
			(xy 398.602702 -314.214676) (xy 398.55824 -314.235774) (xy 398.510969 -314.249466) (xy 398.462114 -314.255398)
			(xy 398.412939 -314.253417) (xy 398.36472 -314.243573) (xy 398.318704 -314.226121) (xy 398.276083 -314.201514)
			(xy 398.237962 -314.170389) (xy 398.205327 -314.133552) (xy 398.179024 -314.091956) (xy 398.159733 -314.04668)
			(xy 398.147956 -313.998896) (xy 398.143996 -313.949842) (xy 397.805586 -313.949842) (xy 397.801419 -314.000127)
			(xy 397.789023 -314.049082) (xy 397.768739 -314.095328) (xy 397.741121 -314.137606) (xy 397.706921 -314.174762)
			(xy 397.667072 -314.205782) (xy 397.622661 -314.229822) (xy 397.574899 -314.246224) (xy 397.52509 -314.254541)
			(xy 397.49984 -314.25515) (xy 397.490672 -314.255059) (xy 397.472372 -314.253917) (xy 397.463264 -314.252864)
			(xy 397.451326 -314.251594) (xy 397.440404 -314.255404) (xy 397.434822 -314.257564) (xy 397.424801 -314.264104)
			(xy 397.420592 -314.268358) (xy 397.364204 -314.327286) (xy 397.36141 -314.330334) (xy 397.358506 -314.334128)
			(xy 397.354026 -314.342564) (xy 397.35252 -314.347098) (xy 397.348964 -314.358528) (xy 397.350996 -314.370466)
			(xy 397.354931 -314.397504) (xy 397.354928 -314.452139) (xy 397.350996 -314.479178) (xy 397.348964 -314.491116)
			(xy 397.35252 -314.502546) (xy 397.354032 -314.507078) (xy 397.358503 -314.515519) (xy 397.36141 -314.51931)
			(xy 397.364204 -314.522358) (xy 397.420592 -314.581286) (xy 397.424823 -314.585514) (xy 397.434837 -314.592052)
			(xy 397.440404 -314.59424) (xy 397.451326 -314.59805) (xy 397.463264 -314.59678) (xy 397.472371 -314.595725)
			(xy 397.490672 -314.594579) (xy 397.49984 -314.594494) (xy 397.525093 -314.595019) (xy 397.574909 -314.603338)
			(xy 397.622677 -314.619742) (xy 397.667094 -314.643784) (xy 397.706948 -314.674809) (xy 397.741152 -314.711969)
			(xy 397.768775 -314.754253) (xy 397.789061 -314.800505) (xy 397.801459 -314.849466) (xy 397.805629 -314.8998)
			(xy 397.805629 -314.899802) (xy 398.143996 -314.899802) (xy 398.147956 -314.850748) (xy 398.159733 -314.802964)
			(xy 398.179024 -314.757688) (xy 398.205327 -314.716092) (xy 398.237962 -314.679255) (xy 398.276083 -314.64813)
			(xy 398.318704 -314.623523) (xy 398.36472 -314.606071) (xy 398.412939 -314.596227) (xy 398.462114 -314.594246)
			(xy 398.510969 -314.600178) (xy 398.55824 -314.61387) (xy 398.602702 -314.634968) (xy 398.643205 -314.662924)
			(xy 398.678698 -314.697016) (xy 398.708263 -314.73636) (xy 398.731134 -314.779937) (xy 398.746718 -314.826618)
			(xy 398.754613 -314.875195) (xy 398.755108 -314.899802) (xy 399.09421 -314.899802) (xy 399.09817 -314.850748)
			(xy 399.109947 -314.802964) (xy 399.129238 -314.757688) (xy 399.155541 -314.716092) (xy 399.188176 -314.679255)
			(xy 399.226297 -314.64813) (xy 399.268918 -314.623523) (xy 399.314934 -314.606071) (xy 399.363153 -314.596227)
			(xy 399.412328 -314.594246) (xy 399.461183 -314.600178) (xy 399.508454 -314.61387) (xy 399.552916 -314.634968)
			(xy 399.593419 -314.662924) (xy 399.628912 -314.697016) (xy 399.658477 -314.73636) (xy 399.681348 -314.779937)
			(xy 399.696932 -314.826618) (xy 399.704827 -314.875195) (xy 399.705322 -314.899802) (xy 400.04417 -314.899802)
			(xy 400.04813 -314.850748) (xy 400.059907 -314.802964) (xy 400.079198 -314.757688) (xy 400.105501 -314.716092)
			(xy 400.138136 -314.679255) (xy 400.176257 -314.64813) (xy 400.218878 -314.623523) (xy 400.264894 -314.606071)
			(xy 400.313113 -314.596227) (xy 400.362288 -314.594246) (xy 400.411143 -314.600178) (xy 400.458414 -314.61387)
			(xy 400.502876 -314.634968) (xy 400.543379 -314.662924) (xy 400.578872 -314.697016) (xy 400.608437 -314.73636)
			(xy 400.631308 -314.779937) (xy 400.646892 -314.826618) (xy 400.654787 -314.875195) (xy 400.655282 -314.899802)
			(xy 400.99413 -314.899802) (xy 400.99809 -314.850748) (xy 401.009867 -314.802964) (xy 401.029158 -314.757688)
			(xy 401.055461 -314.716092) (xy 401.088096 -314.679255) (xy 401.126217 -314.64813) (xy 401.168838 -314.623523)
			(xy 401.214854 -314.606071) (xy 401.263073 -314.596227) (xy 401.312248 -314.594246) (xy 401.361103 -314.600178)
			(xy 401.408374 -314.61387) (xy 401.452836 -314.634968) (xy 401.493339 -314.662924) (xy 401.528832 -314.697016)
			(xy 401.558397 -314.73636) (xy 401.581268 -314.779937) (xy 401.596852 -314.826618) (xy 401.604747 -314.875195)
			(xy 401.605242 -314.899802) (xy 401.94409 -314.899802) (xy 401.94805 -314.850748) (xy 401.959827 -314.802964)
			(xy 401.979118 -314.757688) (xy 402.005421 -314.716092) (xy 402.038056 -314.679255) (xy 402.076177 -314.64813)
			(xy 402.118798 -314.623523) (xy 402.164814 -314.606071) (xy 402.213033 -314.596227) (xy 402.262208 -314.594246)
			(xy 402.311063 -314.600178) (xy 402.358334 -314.61387) (xy 402.402796 -314.634968) (xy 402.443299 -314.662924)
			(xy 402.478792 -314.697016) (xy 402.508357 -314.73636) (xy 402.531228 -314.779937) (xy 402.546812 -314.826618)
			(xy 402.554707 -314.875195) (xy 402.555202 -314.899802) (xy 402.89405 -314.899802) (xy 402.89801 -314.850748)
			(xy 402.909787 -314.802964) (xy 402.929078 -314.757688) (xy 402.955381 -314.716092) (xy 402.988016 -314.679255)
			(xy 403.026137 -314.64813) (xy 403.068758 -314.623523) (xy 403.114774 -314.606071) (xy 403.162993 -314.596227)
			(xy 403.212168 -314.594246) (xy 403.261023 -314.600178) (xy 403.308294 -314.61387) (xy 403.352756 -314.634968)
			(xy 403.393259 -314.662924) (xy 403.428752 -314.697016) (xy 403.458317 -314.73636) (xy 403.481188 -314.779937)
			(xy 403.496772 -314.826618) (xy 403.504667 -314.875195) (xy 403.505162 -314.899802) (xy 403.84401 -314.899802)
			(xy 403.84797 -314.850748) (xy 403.859747 -314.802964) (xy 403.879038 -314.757688) (xy 403.905341 -314.716092)
			(xy 403.937976 -314.679255) (xy 403.976097 -314.64813) (xy 404.018718 -314.623523) (xy 404.064734 -314.606071)
			(xy 404.112953 -314.596227) (xy 404.162128 -314.594246) (xy 404.210983 -314.600178) (xy 404.258254 -314.61387)
			(xy 404.302716 -314.634968) (xy 404.343219 -314.662924) (xy 404.378712 -314.697016) (xy 404.408277 -314.73636)
			(xy 404.431148 -314.779937) (xy 404.446732 -314.826618) (xy 404.454627 -314.875195) (xy 404.455122 -314.899802)
			(xy 404.794224 -314.899802) (xy 404.798184 -314.850748) (xy 404.809961 -314.802964) (xy 404.829252 -314.757688)
			(xy 404.855555 -314.716092) (xy 404.88819 -314.679255) (xy 404.926311 -314.64813) (xy 404.968932 -314.623523)
			(xy 405.014948 -314.606071) (xy 405.063167 -314.596227) (xy 405.112342 -314.594246) (xy 405.161197 -314.600178)
			(xy 405.208468 -314.61387) (xy 405.25293 -314.634968) (xy 405.293433 -314.662924) (xy 405.328926 -314.697016)
			(xy 405.358491 -314.73636) (xy 405.381362 -314.779937) (xy 405.396946 -314.826618) (xy 405.404841 -314.875195)
			(xy 405.405336 -314.899802) (xy 405.744184 -314.899802) (xy 405.748144 -314.850748) (xy 405.759921 -314.802964)
			(xy 405.779212 -314.757688) (xy 405.805515 -314.716092) (xy 405.83815 -314.679255) (xy 405.876271 -314.64813)
			(xy 405.918892 -314.623523) (xy 405.964908 -314.606071) (xy 406.013127 -314.596227) (xy 406.062302 -314.594246)
			(xy 406.111157 -314.600178) (xy 406.158428 -314.61387) (xy 406.20289 -314.634968) (xy 406.243393 -314.662924)
			(xy 406.278886 -314.697016) (xy 406.308451 -314.73636) (xy 406.331322 -314.779937) (xy 406.346906 -314.826618)
			(xy 406.354801 -314.875195) (xy 406.355296 -314.899802) (xy 406.694144 -314.899802) (xy 406.698104 -314.850748)
			(xy 406.709881 -314.802964) (xy 406.729172 -314.757688) (xy 406.755475 -314.716092) (xy 406.78811 -314.679255)
			(xy 406.826231 -314.64813) (xy 406.868852 -314.623523) (xy 406.914868 -314.606071) (xy 406.963087 -314.596227)
			(xy 407.012262 -314.594246) (xy 407.061117 -314.600178) (xy 407.108388 -314.61387) (xy 407.15285 -314.634968)
			(xy 407.193353 -314.662924) (xy 407.228846 -314.697016) (xy 407.258411 -314.73636) (xy 407.281282 -314.779937)
			(xy 407.296866 -314.826618) (xy 407.304761 -314.875195) (xy 407.305256 -314.899802) (xy 407.644104 -314.899802)
			(xy 407.648064 -314.850748) (xy 407.659841 -314.802964) (xy 407.679132 -314.757688) (xy 407.705435 -314.716092)
			(xy 407.73807 -314.679255) (xy 407.776191 -314.64813) (xy 407.818812 -314.623523) (xy 407.864828 -314.606071)
			(xy 407.913047 -314.596227) (xy 407.962222 -314.594246) (xy 408.011077 -314.600178) (xy 408.058348 -314.61387)
			(xy 408.10281 -314.634968) (xy 408.143313 -314.662924) (xy 408.178806 -314.697016) (xy 408.208371 -314.73636)
			(xy 408.231242 -314.779937) (xy 408.246826 -314.826618) (xy 408.254721 -314.875195) (xy 408.255216 -314.899802)
			(xy 408.594064 -314.899802) (xy 408.598024 -314.850748) (xy 408.609801 -314.802964) (xy 408.629092 -314.757688)
			(xy 408.655395 -314.716092) (xy 408.68803 -314.679255) (xy 408.726151 -314.64813) (xy 408.768772 -314.623523)
			(xy 408.814788 -314.606071) (xy 408.863007 -314.596227) (xy 408.912182 -314.594246) (xy 408.961037 -314.600178)
			(xy 409.008308 -314.61387) (xy 409.05277 -314.634968) (xy 409.093273 -314.662924) (xy 409.128766 -314.697016)
			(xy 409.158331 -314.73636) (xy 409.181202 -314.779937) (xy 409.196786 -314.826618) (xy 409.204681 -314.875195)
			(xy 409.205176 -314.899802) (xy 409.544024 -314.899802) (xy 409.547984 -314.850748) (xy 409.559761 -314.802964)
			(xy 409.579052 -314.757688) (xy 409.605355 -314.716092) (xy 409.63799 -314.679255) (xy 409.676111 -314.64813)
			(xy 409.718732 -314.623523) (xy 409.764748 -314.606071) (xy 409.812967 -314.596227) (xy 409.862142 -314.594246)
			(xy 409.910997 -314.600178) (xy 409.958268 -314.61387) (xy 410.00273 -314.634968) (xy 410.043233 -314.662924)
			(xy 410.078726 -314.697016) (xy 410.108291 -314.73636) (xy 410.131162 -314.779937) (xy 410.146746 -314.826618)
			(xy 410.154641 -314.875195) (xy 410.155136 -314.899802) (xy 410.493984 -314.899802) (xy 410.497944 -314.850748)
			(xy 410.509721 -314.802964) (xy 410.529012 -314.757688) (xy 410.555315 -314.716092) (xy 410.58795 -314.679255)
			(xy 410.626071 -314.64813) (xy 410.668692 -314.623523) (xy 410.714708 -314.606071) (xy 410.762927 -314.596227)
			(xy 410.812102 -314.594246) (xy 410.860957 -314.600178) (xy 410.908228 -314.61387) (xy 410.95269 -314.634968)
			(xy 410.993193 -314.662924) (xy 411.028686 -314.697016) (xy 411.058251 -314.73636) (xy 411.081122 -314.779937)
			(xy 411.096706 -314.826618) (xy 411.104601 -314.875195) (xy 411.105096 -314.899802) (xy 411.444198 -314.899802)
			(xy 411.448158 -314.850748) (xy 411.459935 -314.802964) (xy 411.479226 -314.757688) (xy 411.505529 -314.716092)
			(xy 411.538164 -314.679255) (xy 411.576285 -314.64813) (xy 411.618906 -314.623523) (xy 411.664922 -314.606071)
			(xy 411.713141 -314.596227) (xy 411.762316 -314.594246) (xy 411.811171 -314.600178) (xy 411.858442 -314.61387)
			(xy 411.902904 -314.634968) (xy 411.943407 -314.662924) (xy 411.9789 -314.697016) (xy 412.008465 -314.73636)
			(xy 412.031336 -314.779937) (xy 412.04692 -314.826618) (xy 412.054815 -314.875195) (xy 412.05531 -314.899802)
			(xy 412.394158 -314.899802) (xy 412.398118 -314.850748) (xy 412.409895 -314.802964) (xy 412.429186 -314.757688)
			(xy 412.455489 -314.716092) (xy 412.488124 -314.679255) (xy 412.526245 -314.64813) (xy 412.568866 -314.623523)
			(xy 412.614882 -314.606071) (xy 412.663101 -314.596227) (xy 412.712276 -314.594246) (xy 412.761131 -314.600178)
			(xy 412.808402 -314.61387) (xy 412.852864 -314.634968) (xy 412.893367 -314.662924) (xy 412.92886 -314.697016)
			(xy 412.958425 -314.73636) (xy 412.981296 -314.779937) (xy 412.99688 -314.826618) (xy 413.004775 -314.875195)
			(xy 413.00527 -314.899802) (xy 413.344118 -314.899802) (xy 413.348078 -314.850748) (xy 413.359855 -314.802964)
			(xy 413.379146 -314.757688) (xy 413.405449 -314.716092) (xy 413.438084 -314.679255) (xy 413.476205 -314.64813)
			(xy 413.518826 -314.623523) (xy 413.564842 -314.606071) (xy 413.613061 -314.596227) (xy 413.662236 -314.594246)
			(xy 413.711091 -314.600178) (xy 413.758362 -314.61387) (xy 413.802824 -314.634968) (xy 413.843327 -314.662924)
			(xy 413.87882 -314.697016) (xy 413.908385 -314.73636) (xy 413.931256 -314.779937) (xy 413.94684 -314.826618)
			(xy 413.954735 -314.875195) (xy 413.95523 -314.899802) (xy 414.294078 -314.899802) (xy 414.298038 -314.850748)
			(xy 414.309815 -314.802964) (xy 414.329106 -314.757688) (xy 414.355409 -314.716092) (xy 414.388044 -314.679255)
			(xy 414.426165 -314.64813) (xy 414.468786 -314.623523) (xy 414.514802 -314.606071) (xy 414.563021 -314.596227)
			(xy 414.612196 -314.594246) (xy 414.661051 -314.600178) (xy 414.708322 -314.61387) (xy 414.752784 -314.634968)
			(xy 414.793287 -314.662924) (xy 414.82878 -314.697016) (xy 414.858345 -314.73636) (xy 414.881216 -314.779937)
			(xy 414.8968 -314.826618) (xy 414.904695 -314.875195) (xy 414.90519 -314.899802) (xy 415.244038 -314.899802)
			(xy 415.247998 -314.850748) (xy 415.259775 -314.802964) (xy 415.279066 -314.757688) (xy 415.305369 -314.716092)
			(xy 415.338004 -314.679255) (xy 415.376125 -314.64813) (xy 415.418746 -314.623523) (xy 415.464762 -314.606071)
			(xy 415.512981 -314.596227) (xy 415.562156 -314.594246) (xy 415.611011 -314.600178) (xy 415.658282 -314.61387)
			(xy 415.702744 -314.634968) (xy 415.743247 -314.662924) (xy 415.77874 -314.697016) (xy 415.808305 -314.73636)
			(xy 415.831176 -314.779937) (xy 415.84676 -314.826618) (xy 415.854655 -314.875195) (xy 415.85515 -314.899802)
			(xy 416.193998 -314.899802) (xy 416.197958 -314.850748) (xy 416.209735 -314.802964) (xy 416.229026 -314.757688)
			(xy 416.255329 -314.716092) (xy 416.287964 -314.679255) (xy 416.326085 -314.64813) (xy 416.368706 -314.623523)
			(xy 416.414722 -314.606071) (xy 416.462941 -314.596227) (xy 416.512116 -314.594246) (xy 416.560971 -314.600178)
			(xy 416.608242 -314.61387) (xy 416.652704 -314.634968) (xy 416.693207 -314.662924) (xy 416.7287 -314.697016)
			(xy 416.758265 -314.73636) (xy 416.781136 -314.779937) (xy 416.79672 -314.826618) (xy 416.804615 -314.875195)
			(xy 416.80511 -314.899802) (xy 417.144212 -314.899802) (xy 417.148172 -314.850748) (xy 417.159949 -314.802964)
			(xy 417.17924 -314.757688) (xy 417.205543 -314.716092) (xy 417.238178 -314.679255) (xy 417.276299 -314.64813)
			(xy 417.31892 -314.623523) (xy 417.364936 -314.606071) (xy 417.413155 -314.596227) (xy 417.46233 -314.594246)
			(xy 417.511185 -314.600178) (xy 417.558456 -314.61387) (xy 417.602918 -314.634968) (xy 417.643421 -314.662924)
			(xy 417.678914 -314.697016) (xy 417.708479 -314.73636) (xy 417.73135 -314.779937) (xy 417.746934 -314.826618)
			(xy 417.754829 -314.875195) (xy 417.755324 -314.899802) (xy 418.094172 -314.899802) (xy 418.098132 -314.850748)
			(xy 418.109909 -314.802964) (xy 418.1292 -314.757688) (xy 418.155503 -314.716092) (xy 418.188138 -314.679255)
			(xy 418.226259 -314.64813) (xy 418.26888 -314.623523) (xy 418.314896 -314.606071) (xy 418.363115 -314.596227)
			(xy 418.41229 -314.594246) (xy 418.461145 -314.600178) (xy 418.508416 -314.61387) (xy 418.552878 -314.634968)
			(xy 418.593381 -314.662924) (xy 418.628874 -314.697016) (xy 418.658439 -314.73636) (xy 418.68131 -314.779937)
			(xy 418.696894 -314.826618) (xy 418.704789 -314.875195) (xy 418.705284 -314.899802) (xy 419.044132 -314.899802)
			(xy 419.048092 -314.850748) (xy 419.059869 -314.802964) (xy 419.07916 -314.757688) (xy 419.105463 -314.716092)
			(xy 419.138098 -314.679255) (xy 419.176219 -314.64813) (xy 419.21884 -314.623523) (xy 419.264856 -314.606071)
			(xy 419.313075 -314.596227) (xy 419.36225 -314.594246) (xy 419.411105 -314.600178) (xy 419.458376 -314.61387)
			(xy 419.502838 -314.634968) (xy 419.543341 -314.662924) (xy 419.578834 -314.697016) (xy 419.608399 -314.73636)
			(xy 419.63127 -314.779937) (xy 419.646854 -314.826618) (xy 419.654749 -314.875195) (xy 419.655244 -314.899802)
			(xy 419.994092 -314.899802) (xy 419.998052 -314.850748) (xy 420.009829 -314.802964) (xy 420.02912 -314.757688)
			(xy 420.055423 -314.716092) (xy 420.088058 -314.679255) (xy 420.126179 -314.64813) (xy 420.1688 -314.623523)
			(xy 420.214816 -314.606071) (xy 420.263035 -314.596227) (xy 420.31221 -314.594246) (xy 420.361065 -314.600178)
			(xy 420.408336 -314.61387) (xy 420.452798 -314.634968) (xy 420.493301 -314.662924) (xy 420.528794 -314.697016)
			(xy 420.558359 -314.73636) (xy 420.58123 -314.779937) (xy 420.596814 -314.826618) (xy 420.604709 -314.875195)
			(xy 420.605204 -314.899802) (xy 420.944052 -314.899802) (xy 420.948012 -314.850748) (xy 420.959789 -314.802964)
			(xy 420.97908 -314.757688) (xy 421.005383 -314.716092) (xy 421.038018 -314.679255) (xy 421.076139 -314.64813)
			(xy 421.11876 -314.623523) (xy 421.164776 -314.606071) (xy 421.212995 -314.596227) (xy 421.26217 -314.594246)
			(xy 421.311025 -314.600178) (xy 421.358296 -314.61387) (xy 421.402758 -314.634968) (xy 421.443261 -314.662924)
			(xy 421.478754 -314.697016) (xy 421.508319 -314.73636) (xy 421.53119 -314.779937) (xy 421.546774 -314.826618)
			(xy 421.554669 -314.875195) (xy 421.555164 -314.899802) (xy 421.894012 -314.899802) (xy 421.897972 -314.850748)
			(xy 421.909749 -314.802964) (xy 421.92904 -314.757688) (xy 421.955343 -314.716092) (xy 421.987978 -314.679255)
			(xy 422.026099 -314.64813) (xy 422.06872 -314.623523) (xy 422.114736 -314.606071) (xy 422.162955 -314.596227)
			(xy 422.21213 -314.594246) (xy 422.260985 -314.600178) (xy 422.308256 -314.61387) (xy 422.352718 -314.634968)
			(xy 422.393221 -314.662924) (xy 422.428714 -314.697016) (xy 422.458279 -314.73636) (xy 422.48115 -314.779937)
			(xy 422.496734 -314.826618) (xy 422.504629 -314.875195) (xy 422.505124 -314.899802) (xy 422.844226 -314.899802)
			(xy 422.848186 -314.850748) (xy 422.859963 -314.802964) (xy 422.879254 -314.757688) (xy 422.905557 -314.716092)
			(xy 422.938192 -314.679255) (xy 422.976313 -314.64813) (xy 423.018934 -314.623523) (xy 423.06495 -314.606071)
			(xy 423.113169 -314.596227) (xy 423.162344 -314.594246) (xy 423.211199 -314.600178) (xy 423.25847 -314.61387)
			(xy 423.302932 -314.634968) (xy 423.343435 -314.662924) (xy 423.378928 -314.697016) (xy 423.408493 -314.73636)
			(xy 423.431364 -314.779937) (xy 423.446948 -314.826618) (xy 423.454843 -314.875195) (xy 423.455338 -314.899802)
			(xy 423.794186 -314.899802) (xy 423.798146 -314.850748) (xy 423.809923 -314.802964) (xy 423.829214 -314.757688)
			(xy 423.855517 -314.716092) (xy 423.888152 -314.679255) (xy 423.926273 -314.64813) (xy 423.968894 -314.623523)
			(xy 424.01491 -314.606071) (xy 424.063129 -314.596227) (xy 424.112304 -314.594246) (xy 424.161159 -314.600178)
			(xy 424.20843 -314.61387) (xy 424.252892 -314.634968) (xy 424.293395 -314.662924) (xy 424.328888 -314.697016)
			(xy 424.358453 -314.73636) (xy 424.381324 -314.779937) (xy 424.396908 -314.826618) (xy 424.404803 -314.875195)
			(xy 424.405298 -314.899802) (xy 424.744146 -314.899802) (xy 424.748106 -314.850748) (xy 424.759883 -314.802964)
			(xy 424.779174 -314.757688) (xy 424.805477 -314.716092) (xy 424.838112 -314.679255) (xy 424.876233 -314.64813)
			(xy 424.918854 -314.623523) (xy 424.96487 -314.606071) (xy 425.013089 -314.596227) (xy 425.062264 -314.594246)
			(xy 425.111119 -314.600178) (xy 425.15839 -314.61387) (xy 425.202852 -314.634968) (xy 425.243355 -314.662924)
			(xy 425.278848 -314.697016) (xy 425.308413 -314.73636) (xy 425.331284 -314.779937) (xy 425.346868 -314.826618)
			(xy 425.354763 -314.875195) (xy 425.355258 -314.899802) (xy 425.694106 -314.899802) (xy 425.698066 -314.850748)
			(xy 425.709843 -314.802964) (xy 425.729134 -314.757688) (xy 425.755437 -314.716092) (xy 425.788072 -314.679255)
			(xy 425.826193 -314.64813) (xy 425.868814 -314.623523) (xy 425.91483 -314.606071) (xy 425.963049 -314.596227)
			(xy 426.012224 -314.594246) (xy 426.061079 -314.600178) (xy 426.10835 -314.61387) (xy 426.152812 -314.634968)
			(xy 426.193315 -314.662924) (xy 426.228808 -314.697016) (xy 426.258373 -314.73636) (xy 426.281244 -314.779937)
			(xy 426.296828 -314.826618) (xy 426.304723 -314.875195) (xy 426.305218 -314.899802) (xy 426.644066 -314.899802)
			(xy 426.648026 -314.850748) (xy 426.659803 -314.802964) (xy 426.679094 -314.757688) (xy 426.705397 -314.716092)
			(xy 426.738032 -314.679255) (xy 426.776153 -314.64813) (xy 426.818774 -314.623523) (xy 426.86479 -314.606071)
			(xy 426.913009 -314.596227) (xy 426.962184 -314.594246) (xy 427.011039 -314.600178) (xy 427.05831 -314.61387)
			(xy 427.102772 -314.634968) (xy 427.143275 -314.662924) (xy 427.178768 -314.697016) (xy 427.208333 -314.73636)
			(xy 427.231204 -314.779937) (xy 427.246788 -314.826618) (xy 427.254683 -314.875195) (xy 427.255178 -314.899802)
			(xy 427.594026 -314.899802) (xy 427.597986 -314.850748) (xy 427.609763 -314.802964) (xy 427.629054 -314.757688)
			(xy 427.655357 -314.716092) (xy 427.687992 -314.679255) (xy 427.726113 -314.64813) (xy 427.768734 -314.623523)
			(xy 427.81475 -314.606071) (xy 427.862969 -314.596227) (xy 427.912144 -314.594246) (xy 427.960999 -314.600178)
			(xy 428.00827 -314.61387) (xy 428.052732 -314.634968) (xy 428.093235 -314.662924) (xy 428.128728 -314.697016)
			(xy 428.158293 -314.73636) (xy 428.181164 -314.779937) (xy 428.196748 -314.826618) (xy 428.204643 -314.875195)
			(xy 428.205138 -314.899802) (xy 428.543986 -314.899802) (xy 428.547946 -314.850748) (xy 428.559723 -314.802964)
			(xy 428.579014 -314.757688) (xy 428.605317 -314.716092) (xy 428.637952 -314.679255) (xy 428.676073 -314.64813)
			(xy 428.718694 -314.623523) (xy 428.76471 -314.606071) (xy 428.812929 -314.596227) (xy 428.862104 -314.594246)
			(xy 428.910959 -314.600178) (xy 428.95823 -314.61387) (xy 429.002692 -314.634968) (xy 429.043195 -314.662924)
			(xy 429.078688 -314.697016) (xy 429.108253 -314.73636) (xy 429.131124 -314.779937) (xy 429.146708 -314.826618)
			(xy 429.154603 -314.875195) (xy 429.155098 -314.899802) (xy 429.154603 -314.924409) (xy 429.154424 -314.92551)
			(xy 429.473356 -314.92551) (xy 429.473356 -314.874094) (xy 429.481399 -314.823312) (xy 429.497287 -314.774413)
			(xy 429.52063 -314.728601) (xy 429.550851 -314.687005) (xy 429.587207 -314.650649) (xy 429.628803 -314.620428)
			(xy 429.674615 -314.597085) (xy 429.723514 -314.581197) (xy 429.774296 -314.573154) (xy 429.825712 -314.573154)
			(xy 429.876494 -314.581197) (xy 429.925393 -314.597085) (xy 429.971205 -314.620428) (xy 430.012801 -314.650649)
			(xy 430.049157 -314.687005) (xy 430.079378 -314.728601) (xy 430.102721 -314.774413) (xy 430.118609 -314.823312)
			(xy 430.126652 -314.874094) (xy 430.127156 -314.899802) (xy 430.126652 -314.92551) (xy 430.423316 -314.92551)
			(xy 430.423316 -314.874094) (xy 430.431359 -314.823312) (xy 430.447247 -314.774413) (xy 430.47059 -314.728601)
			(xy 430.500811 -314.687005) (xy 430.537167 -314.650649) (xy 430.578763 -314.620428) (xy 430.624575 -314.597085)
			(xy 430.673474 -314.581197) (xy 430.724256 -314.573154) (xy 430.775672 -314.573154) (xy 430.826454 -314.581197)
			(xy 430.875353 -314.597085) (xy 430.921165 -314.620428) (xy 430.962761 -314.650649) (xy 430.999117 -314.687005)
			(xy 431.029338 -314.728601) (xy 431.052681 -314.774413) (xy 431.068569 -314.823312) (xy 431.076612 -314.874094)
			(xy 431.077111 -314.899548) (xy 431.394374 -314.899548) (xy 431.398334 -314.850494) (xy 431.410111 -314.80271)
			(xy 431.429402 -314.757434) (xy 431.455705 -314.715838) (xy 431.48834 -314.679001) (xy 431.526461 -314.647876)
			(xy 431.569082 -314.623269) (xy 431.615098 -314.605817) (xy 431.663317 -314.595973) (xy 431.712492 -314.593992)
			(xy 431.761347 -314.599924) (xy 431.808618 -314.613616) (xy 431.85308 -314.634714) (xy 431.893583 -314.66267)
			(xy 431.929076 -314.696762) (xy 431.958641 -314.736106) (xy 431.981512 -314.779683) (xy 431.997096 -314.826364)
			(xy 432.004991 -314.874941) (xy 432.005486 -314.899548) (xy 432.004991 -314.924155) (xy 431.997096 -314.972732)
			(xy 431.981512 -315.019413) (xy 431.958641 -315.06299) (xy 431.929076 -315.102334) (xy 431.893583 -315.136426)
			(xy 431.85308 -315.164382) (xy 431.808618 -315.18548) (xy 431.761347 -315.199172) (xy 431.712492 -315.205104)
			(xy 431.663317 -315.203123) (xy 431.615098 -315.193279) (xy 431.569082 -315.175827) (xy 431.526461 -315.15122)
			(xy 431.48834 -315.120095) (xy 431.455705 -315.083258) (xy 431.429402 -315.041662) (xy 431.410111 -314.996386)
			(xy 431.398334 -314.948602) (xy 431.394374 -314.899548) (xy 431.077111 -314.899548) (xy 431.077116 -314.899802)
			(xy 431.076612 -314.92551) (xy 431.068569 -314.976292) (xy 431.052681 -315.025191) (xy 431.029338 -315.071003)
			(xy 430.999117 -315.112599) (xy 430.962761 -315.148955) (xy 430.921165 -315.179176) (xy 430.875353 -315.202519)
			(xy 430.826454 -315.218407) (xy 430.775672 -315.22645) (xy 430.724256 -315.22645) (xy 430.673474 -315.218407)
			(xy 430.624575 -315.202519) (xy 430.578763 -315.179176) (xy 430.537167 -315.148955) (xy 430.500811 -315.112599)
			(xy 430.47059 -315.071003) (xy 430.447247 -315.025191) (xy 430.431359 -314.976292) (xy 430.423316 -314.92551)
			(xy 430.126652 -314.92551) (xy 430.118609 -314.976292) (xy 430.102721 -315.025191) (xy 430.079378 -315.071003)
			(xy 430.049157 -315.112599) (xy 430.012801 -315.148955) (xy 429.971205 -315.179176) (xy 429.925393 -315.202519)
			(xy 429.876494 -315.218407) (xy 429.825712 -315.22645) (xy 429.774296 -315.22645) (xy 429.723514 -315.218407)
			(xy 429.674615 -315.202519) (xy 429.628803 -315.179176) (xy 429.587207 -315.148955) (xy 429.550851 -315.112599)
			(xy 429.52063 -315.071003) (xy 429.497287 -315.025191) (xy 429.481399 -314.976292) (xy 429.473356 -314.92551)
			(xy 429.154424 -314.92551) (xy 429.146708 -314.972986) (xy 429.131124 -315.019667) (xy 429.108253 -315.063244)
			(xy 429.078688 -315.102588) (xy 429.043195 -315.13668) (xy 429.002692 -315.164636) (xy 428.95823 -315.185734)
			(xy 428.910959 -315.199426) (xy 428.862104 -315.205358) (xy 428.812929 -315.203377) (xy 428.76471 -315.193533)
			(xy 428.718694 -315.176081) (xy 428.676073 -315.151474) (xy 428.637952 -315.120349) (xy 428.605317 -315.083512)
			(xy 428.579014 -315.041916) (xy 428.559723 -314.99664) (xy 428.547946 -314.948856) (xy 428.543986 -314.899802)
			(xy 428.205138 -314.899802) (xy 428.204643 -314.924409) (xy 428.196748 -314.972986) (xy 428.181164 -315.019667)
			(xy 428.158293 -315.063244) (xy 428.128728 -315.102588) (xy 428.093235 -315.13668) (xy 428.052732 -315.164636)
			(xy 428.00827 -315.185734) (xy 427.960999 -315.199426) (xy 427.912144 -315.205358) (xy 427.862969 -315.203377)
			(xy 427.81475 -315.193533) (xy 427.768734 -315.176081) (xy 427.726113 -315.151474) (xy 427.687992 -315.120349)
			(xy 427.655357 -315.083512) (xy 427.629054 -315.041916) (xy 427.609763 -314.99664) (xy 427.597986 -314.948856)
			(xy 427.594026 -314.899802) (xy 427.255178 -314.899802) (xy 427.254683 -314.924409) (xy 427.246788 -314.972986)
			(xy 427.231204 -315.019667) (xy 427.208333 -315.063244) (xy 427.178768 -315.102588) (xy 427.143275 -315.13668)
			(xy 427.102772 -315.164636) (xy 427.05831 -315.185734) (xy 427.011039 -315.199426) (xy 426.962184 -315.205358)
			(xy 426.913009 -315.203377) (xy 426.86479 -315.193533) (xy 426.818774 -315.176081) (xy 426.776153 -315.151474)
			(xy 426.738032 -315.120349) (xy 426.705397 -315.083512) (xy 426.679094 -315.041916) (xy 426.659803 -314.99664)
			(xy 426.648026 -314.948856) (xy 426.644066 -314.899802) (xy 426.305218 -314.899802) (xy 426.304723 -314.924409)
			(xy 426.296828 -314.972986) (xy 426.281244 -315.019667) (xy 426.258373 -315.063244) (xy 426.228808 -315.102588)
			(xy 426.193315 -315.13668) (xy 426.152812 -315.164636) (xy 426.10835 -315.185734) (xy 426.061079 -315.199426)
			(xy 426.012224 -315.205358) (xy 425.963049 -315.203377) (xy 425.91483 -315.193533) (xy 425.868814 -315.176081)
			(xy 425.826193 -315.151474) (xy 425.788072 -315.120349) (xy 425.755437 -315.083512) (xy 425.729134 -315.041916)
			(xy 425.709843 -314.99664) (xy 425.698066 -314.948856) (xy 425.694106 -314.899802) (xy 425.355258 -314.899802)
			(xy 425.354763 -314.924409) (xy 425.346868 -314.972986) (xy 425.331284 -315.019667) (xy 425.308413 -315.063244)
			(xy 425.278848 -315.102588) (xy 425.243355 -315.13668) (xy 425.202852 -315.164636) (xy 425.15839 -315.185734)
			(xy 425.111119 -315.199426) (xy 425.062264 -315.205358) (xy 425.013089 -315.203377) (xy 424.96487 -315.193533)
			(xy 424.918854 -315.176081) (xy 424.876233 -315.151474) (xy 424.838112 -315.120349) (xy 424.805477 -315.083512)
			(xy 424.779174 -315.041916) (xy 424.759883 -314.99664) (xy 424.748106 -314.948856) (xy 424.744146 -314.899802)
			(xy 424.405298 -314.899802) (xy 424.404803 -314.924409) (xy 424.396908 -314.972986) (xy 424.381324 -315.019667)
			(xy 424.358453 -315.063244) (xy 424.328888 -315.102588) (xy 424.293395 -315.13668) (xy 424.252892 -315.164636)
			(xy 424.20843 -315.185734) (xy 424.161159 -315.199426) (xy 424.112304 -315.205358) (xy 424.063129 -315.203377)
			(xy 424.01491 -315.193533) (xy 423.968894 -315.176081) (xy 423.926273 -315.151474) (xy 423.888152 -315.120349)
			(xy 423.855517 -315.083512) (xy 423.829214 -315.041916) (xy 423.809923 -314.99664) (xy 423.798146 -314.948856)
			(xy 423.794186 -314.899802) (xy 423.455338 -314.899802) (xy 423.454843 -314.924409) (xy 423.446948 -314.972986)
			(xy 423.431364 -315.019667) (xy 423.408493 -315.063244) (xy 423.378928 -315.102588) (xy 423.343435 -315.13668)
			(xy 423.302932 -315.164636) (xy 423.25847 -315.185734) (xy 423.211199 -315.199426) (xy 423.162344 -315.205358)
			(xy 423.113169 -315.203377) (xy 423.06495 -315.193533) (xy 423.018934 -315.176081) (xy 422.976313 -315.151474)
			(xy 422.938192 -315.120349) (xy 422.905557 -315.083512) (xy 422.879254 -315.041916) (xy 422.859963 -314.99664)
			(xy 422.848186 -314.948856) (xy 422.844226 -314.899802) (xy 422.505124 -314.899802) (xy 422.504629 -314.924409)
			(xy 422.496734 -314.972986) (xy 422.48115 -315.019667) (xy 422.458279 -315.063244) (xy 422.428714 -315.102588)
			(xy 422.393221 -315.13668) (xy 422.352718 -315.164636) (xy 422.308256 -315.185734) (xy 422.260985 -315.199426)
			(xy 422.21213 -315.205358) (xy 422.162955 -315.203377) (xy 422.114736 -315.193533) (xy 422.06872 -315.176081)
			(xy 422.026099 -315.151474) (xy 421.987978 -315.120349) (xy 421.955343 -315.083512) (xy 421.92904 -315.041916)
			(xy 421.909749 -314.99664) (xy 421.897972 -314.948856) (xy 421.894012 -314.899802) (xy 421.555164 -314.899802)
			(xy 421.554669 -314.924409) (xy 421.546774 -314.972986) (xy 421.53119 -315.019667) (xy 421.508319 -315.063244)
			(xy 421.478754 -315.102588) (xy 421.443261 -315.13668) (xy 421.402758 -315.164636) (xy 421.358296 -315.185734)
			(xy 421.311025 -315.199426) (xy 421.26217 -315.205358) (xy 421.212995 -315.203377) (xy 421.164776 -315.193533)
			(xy 421.11876 -315.176081) (xy 421.076139 -315.151474) (xy 421.038018 -315.120349) (xy 421.005383 -315.083512)
			(xy 420.97908 -315.041916) (xy 420.959789 -314.99664) (xy 420.948012 -314.948856) (xy 420.944052 -314.899802)
			(xy 420.605204 -314.899802) (xy 420.604709 -314.924409) (xy 420.596814 -314.972986) (xy 420.58123 -315.019667)
			(xy 420.558359 -315.063244) (xy 420.528794 -315.102588) (xy 420.493301 -315.13668) (xy 420.452798 -315.164636)
			(xy 420.408336 -315.185734) (xy 420.361065 -315.199426) (xy 420.31221 -315.205358) (xy 420.263035 -315.203377)
			(xy 420.214816 -315.193533) (xy 420.1688 -315.176081) (xy 420.126179 -315.151474) (xy 420.088058 -315.120349)
			(xy 420.055423 -315.083512) (xy 420.02912 -315.041916) (xy 420.009829 -314.99664) (xy 419.998052 -314.948856)
			(xy 419.994092 -314.899802) (xy 419.655244 -314.899802) (xy 419.654749 -314.924409) (xy 419.646854 -314.972986)
			(xy 419.63127 -315.019667) (xy 419.608399 -315.063244) (xy 419.578834 -315.102588) (xy 419.543341 -315.13668)
			(xy 419.502838 -315.164636) (xy 419.458376 -315.185734) (xy 419.411105 -315.199426) (xy 419.36225 -315.205358)
			(xy 419.313075 -315.203377) (xy 419.264856 -315.193533) (xy 419.21884 -315.176081) (xy 419.176219 -315.151474)
			(xy 419.138098 -315.120349) (xy 419.105463 -315.083512) (xy 419.07916 -315.041916) (xy 419.059869 -314.99664)
			(xy 419.048092 -314.948856) (xy 419.044132 -314.899802) (xy 418.705284 -314.899802) (xy 418.704789 -314.924409)
			(xy 418.696894 -314.972986) (xy 418.68131 -315.019667) (xy 418.658439 -315.063244) (xy 418.628874 -315.102588)
			(xy 418.593381 -315.13668) (xy 418.552878 -315.164636) (xy 418.508416 -315.185734) (xy 418.461145 -315.199426)
			(xy 418.41229 -315.205358) (xy 418.363115 -315.203377) (xy 418.314896 -315.193533) (xy 418.26888 -315.176081)
			(xy 418.226259 -315.151474) (xy 418.188138 -315.120349) (xy 418.155503 -315.083512) (xy 418.1292 -315.041916)
			(xy 418.109909 -314.99664) (xy 418.098132 -314.948856) (xy 418.094172 -314.899802) (xy 417.755324 -314.899802)
			(xy 417.754829 -314.924409) (xy 417.746934 -314.972986) (xy 417.73135 -315.019667) (xy 417.708479 -315.063244)
			(xy 417.678914 -315.102588) (xy 417.643421 -315.13668) (xy 417.602918 -315.164636) (xy 417.558456 -315.185734)
			(xy 417.511185 -315.199426) (xy 417.46233 -315.205358) (xy 417.413155 -315.203377) (xy 417.364936 -315.193533)
			(xy 417.31892 -315.176081) (xy 417.276299 -315.151474) (xy 417.238178 -315.120349) (xy 417.205543 -315.083512)
			(xy 417.17924 -315.041916) (xy 417.159949 -314.99664) (xy 417.148172 -314.948856) (xy 417.144212 -314.899802)
			(xy 416.80511 -314.899802) (xy 416.804615 -314.924409) (xy 416.79672 -314.972986) (xy 416.781136 -315.019667)
			(xy 416.758265 -315.063244) (xy 416.7287 -315.102588) (xy 416.693207 -315.13668) (xy 416.652704 -315.164636)
			(xy 416.608242 -315.185734) (xy 416.560971 -315.199426) (xy 416.512116 -315.205358) (xy 416.462941 -315.203377)
			(xy 416.414722 -315.193533) (xy 416.368706 -315.176081) (xy 416.326085 -315.151474) (xy 416.287964 -315.120349)
			(xy 416.255329 -315.083512) (xy 416.229026 -315.041916) (xy 416.209735 -314.99664) (xy 416.197958 -314.948856)
			(xy 416.193998 -314.899802) (xy 415.85515 -314.899802) (xy 415.854655 -314.924409) (xy 415.84676 -314.972986)
			(xy 415.831176 -315.019667) (xy 415.808305 -315.063244) (xy 415.77874 -315.102588) (xy 415.743247 -315.13668)
			(xy 415.702744 -315.164636) (xy 415.658282 -315.185734) (xy 415.611011 -315.199426) (xy 415.562156 -315.205358)
			(xy 415.512981 -315.203377) (xy 415.464762 -315.193533) (xy 415.418746 -315.176081) (xy 415.376125 -315.151474)
			(xy 415.338004 -315.120349) (xy 415.305369 -315.083512) (xy 415.279066 -315.041916) (xy 415.259775 -314.99664)
			(xy 415.247998 -314.948856) (xy 415.244038 -314.899802) (xy 414.90519 -314.899802) (xy 414.904695 -314.924409)
			(xy 414.8968 -314.972986) (xy 414.881216 -315.019667) (xy 414.858345 -315.063244) (xy 414.82878 -315.102588)
			(xy 414.793287 -315.13668) (xy 414.752784 -315.164636) (xy 414.708322 -315.185734) (xy 414.661051 -315.199426)
			(xy 414.612196 -315.205358) (xy 414.563021 -315.203377) (xy 414.514802 -315.193533) (xy 414.468786 -315.176081)
			(xy 414.426165 -315.151474) (xy 414.388044 -315.120349) (xy 414.355409 -315.083512) (xy 414.329106 -315.041916)
			(xy 414.309815 -314.99664) (xy 414.298038 -314.948856) (xy 414.294078 -314.899802) (xy 413.95523 -314.899802)
			(xy 413.954735 -314.924409) (xy 413.94684 -314.972986) (xy 413.931256 -315.019667) (xy 413.908385 -315.063244)
			(xy 413.87882 -315.102588) (xy 413.843327 -315.13668) (xy 413.802824 -315.164636) (xy 413.758362 -315.185734)
			(xy 413.711091 -315.199426) (xy 413.662236 -315.205358) (xy 413.613061 -315.203377) (xy 413.564842 -315.193533)
			(xy 413.518826 -315.176081) (xy 413.476205 -315.151474) (xy 413.438084 -315.120349) (xy 413.405449 -315.083512)
			(xy 413.379146 -315.041916) (xy 413.359855 -314.99664) (xy 413.348078 -314.948856) (xy 413.344118 -314.899802)
			(xy 413.00527 -314.899802) (xy 413.004775 -314.924409) (xy 412.99688 -314.972986) (xy 412.981296 -315.019667)
			(xy 412.958425 -315.063244) (xy 412.92886 -315.102588) (xy 412.893367 -315.13668) (xy 412.852864 -315.164636)
			(xy 412.808402 -315.185734) (xy 412.761131 -315.199426) (xy 412.712276 -315.205358) (xy 412.663101 -315.203377)
			(xy 412.614882 -315.193533) (xy 412.568866 -315.176081) (xy 412.526245 -315.151474) (xy 412.488124 -315.120349)
			(xy 412.455489 -315.083512) (xy 412.429186 -315.041916) (xy 412.409895 -314.99664) (xy 412.398118 -314.948856)
			(xy 412.394158 -314.899802) (xy 412.05531 -314.899802) (xy 412.054815 -314.924409) (xy 412.04692 -314.972986)
			(xy 412.031336 -315.019667) (xy 412.008465 -315.063244) (xy 411.9789 -315.102588) (xy 411.943407 -315.13668)
			(xy 411.902904 -315.164636) (xy 411.858442 -315.185734) (xy 411.811171 -315.199426) (xy 411.762316 -315.205358)
			(xy 411.713141 -315.203377) (xy 411.664922 -315.193533) (xy 411.618906 -315.176081) (xy 411.576285 -315.151474)
			(xy 411.538164 -315.120349) (xy 411.505529 -315.083512) (xy 411.479226 -315.041916) (xy 411.459935 -314.99664)
			(xy 411.448158 -314.948856) (xy 411.444198 -314.899802) (xy 411.105096 -314.899802) (xy 411.104601 -314.924409)
			(xy 411.096706 -314.972986) (xy 411.081122 -315.019667) (xy 411.058251 -315.063244) (xy 411.028686 -315.102588)
			(xy 410.993193 -315.13668) (xy 410.95269 -315.164636) (xy 410.908228 -315.185734) (xy 410.860957 -315.199426)
			(xy 410.812102 -315.205358) (xy 410.762927 -315.203377) (xy 410.714708 -315.193533) (xy 410.668692 -315.176081)
			(xy 410.626071 -315.151474) (xy 410.58795 -315.120349) (xy 410.555315 -315.083512) (xy 410.529012 -315.041916)
			(xy 410.509721 -314.99664) (xy 410.497944 -314.948856) (xy 410.493984 -314.899802) (xy 410.155136 -314.899802)
			(xy 410.154641 -314.924409) (xy 410.146746 -314.972986) (xy 410.131162 -315.019667) (xy 410.108291 -315.063244)
			(xy 410.078726 -315.102588) (xy 410.043233 -315.13668) (xy 410.00273 -315.164636) (xy 409.958268 -315.185734)
			(xy 409.910997 -315.199426) (xy 409.862142 -315.205358) (xy 409.812967 -315.203377) (xy 409.764748 -315.193533)
			(xy 409.718732 -315.176081) (xy 409.676111 -315.151474) (xy 409.63799 -315.120349) (xy 409.605355 -315.083512)
			(xy 409.579052 -315.041916) (xy 409.559761 -314.99664) (xy 409.547984 -314.948856) (xy 409.544024 -314.899802)
			(xy 409.205176 -314.899802) (xy 409.204681 -314.924409) (xy 409.196786 -314.972986) (xy 409.181202 -315.019667)
			(xy 409.158331 -315.063244) (xy 409.128766 -315.102588) (xy 409.093273 -315.13668) (xy 409.05277 -315.164636)
			(xy 409.008308 -315.185734) (xy 408.961037 -315.199426) (xy 408.912182 -315.205358) (xy 408.863007 -315.203377)
			(xy 408.814788 -315.193533) (xy 408.768772 -315.176081) (xy 408.726151 -315.151474) (xy 408.68803 -315.120349)
			(xy 408.655395 -315.083512) (xy 408.629092 -315.041916) (xy 408.609801 -314.99664) (xy 408.598024 -314.948856)
			(xy 408.594064 -314.899802) (xy 408.255216 -314.899802) (xy 408.254721 -314.924409) (xy 408.246826 -314.972986)
			(xy 408.231242 -315.019667) (xy 408.208371 -315.063244) (xy 408.178806 -315.102588) (xy 408.143313 -315.13668)
			(xy 408.10281 -315.164636) (xy 408.058348 -315.185734) (xy 408.011077 -315.199426) (xy 407.962222 -315.205358)
			(xy 407.913047 -315.203377) (xy 407.864828 -315.193533) (xy 407.818812 -315.176081) (xy 407.776191 -315.151474)
			(xy 407.73807 -315.120349) (xy 407.705435 -315.083512) (xy 407.679132 -315.041916) (xy 407.659841 -314.99664)
			(xy 407.648064 -314.948856) (xy 407.644104 -314.899802) (xy 407.305256 -314.899802) (xy 407.304761 -314.924409)
			(xy 407.296866 -314.972986) (xy 407.281282 -315.019667) (xy 407.258411 -315.063244) (xy 407.228846 -315.102588)
			(xy 407.193353 -315.13668) (xy 407.15285 -315.164636) (xy 407.108388 -315.185734) (xy 407.061117 -315.199426)
			(xy 407.012262 -315.205358) (xy 406.963087 -315.203377) (xy 406.914868 -315.193533) (xy 406.868852 -315.176081)
			(xy 406.826231 -315.151474) (xy 406.78811 -315.120349) (xy 406.755475 -315.083512) (xy 406.729172 -315.041916)
			(xy 406.709881 -314.99664) (xy 406.698104 -314.948856) (xy 406.694144 -314.899802) (xy 406.355296 -314.899802)
			(xy 406.354801 -314.924409) (xy 406.346906 -314.972986) (xy 406.331322 -315.019667) (xy 406.308451 -315.063244)
			(xy 406.278886 -315.102588) (xy 406.243393 -315.13668) (xy 406.20289 -315.164636) (xy 406.158428 -315.185734)
			(xy 406.111157 -315.199426) (xy 406.062302 -315.205358) (xy 406.013127 -315.203377) (xy 405.964908 -315.193533)
			(xy 405.918892 -315.176081) (xy 405.876271 -315.151474) (xy 405.83815 -315.120349) (xy 405.805515 -315.083512)
			(xy 405.779212 -315.041916) (xy 405.759921 -314.99664) (xy 405.748144 -314.948856) (xy 405.744184 -314.899802)
			(xy 405.405336 -314.899802) (xy 405.404841 -314.924409) (xy 405.396946 -314.972986) (xy 405.381362 -315.019667)
			(xy 405.358491 -315.063244) (xy 405.328926 -315.102588) (xy 405.293433 -315.13668) (xy 405.25293 -315.164636)
			(xy 405.208468 -315.185734) (xy 405.161197 -315.199426) (xy 405.112342 -315.205358) (xy 405.063167 -315.203377)
			(xy 405.014948 -315.193533) (xy 404.968932 -315.176081) (xy 404.926311 -315.151474) (xy 404.88819 -315.120349)
			(xy 404.855555 -315.083512) (xy 404.829252 -315.041916) (xy 404.809961 -314.99664) (xy 404.798184 -314.948856)
			(xy 404.794224 -314.899802) (xy 404.455122 -314.899802) (xy 404.454627 -314.924409) (xy 404.446732 -314.972986)
			(xy 404.431148 -315.019667) (xy 404.408277 -315.063244) (xy 404.378712 -315.102588) (xy 404.343219 -315.13668)
			(xy 404.302716 -315.164636) (xy 404.258254 -315.185734) (xy 404.210983 -315.199426) (xy 404.162128 -315.205358)
			(xy 404.112953 -315.203377) (xy 404.064734 -315.193533) (xy 404.018718 -315.176081) (xy 403.976097 -315.151474)
			(xy 403.937976 -315.120349) (xy 403.905341 -315.083512) (xy 403.879038 -315.041916) (xy 403.859747 -314.99664)
			(xy 403.84797 -314.948856) (xy 403.84401 -314.899802) (xy 403.505162 -314.899802) (xy 403.504667 -314.924409)
			(xy 403.496772 -314.972986) (xy 403.481188 -315.019667) (xy 403.458317 -315.063244) (xy 403.428752 -315.102588)
			(xy 403.393259 -315.13668) (xy 403.352756 -315.164636) (xy 403.308294 -315.185734) (xy 403.261023 -315.199426)
			(xy 403.212168 -315.205358) (xy 403.162993 -315.203377) (xy 403.114774 -315.193533) (xy 403.068758 -315.176081)
			(xy 403.026137 -315.151474) (xy 402.988016 -315.120349) (xy 402.955381 -315.083512) (xy 402.929078 -315.041916)
			(xy 402.909787 -314.99664) (xy 402.89801 -314.948856) (xy 402.89405 -314.899802) (xy 402.555202 -314.899802)
			(xy 402.554707 -314.924409) (xy 402.546812 -314.972986) (xy 402.531228 -315.019667) (xy 402.508357 -315.063244)
			(xy 402.478792 -315.102588) (xy 402.443299 -315.13668) (xy 402.402796 -315.164636) (xy 402.358334 -315.185734)
			(xy 402.311063 -315.199426) (xy 402.262208 -315.205358) (xy 402.213033 -315.203377) (xy 402.164814 -315.193533)
			(xy 402.118798 -315.176081) (xy 402.076177 -315.151474) (xy 402.038056 -315.120349) (xy 402.005421 -315.083512)
			(xy 401.979118 -315.041916) (xy 401.959827 -314.99664) (xy 401.94805 -314.948856) (xy 401.94409 -314.899802)
			(xy 401.605242 -314.899802) (xy 401.604747 -314.924409) (xy 401.596852 -314.972986) (xy 401.581268 -315.019667)
			(xy 401.558397 -315.063244) (xy 401.528832 -315.102588) (xy 401.493339 -315.13668) (xy 401.452836 -315.164636)
			(xy 401.408374 -315.185734) (xy 401.361103 -315.199426) (xy 401.312248 -315.205358) (xy 401.263073 -315.203377)
			(xy 401.214854 -315.193533) (xy 401.168838 -315.176081) (xy 401.126217 -315.151474) (xy 401.088096 -315.120349)
			(xy 401.055461 -315.083512) (xy 401.029158 -315.041916) (xy 401.009867 -314.99664) (xy 400.99809 -314.948856)
			(xy 400.99413 -314.899802) (xy 400.655282 -314.899802) (xy 400.654787 -314.924409) (xy 400.646892 -314.972986)
			(xy 400.631308 -315.019667) (xy 400.608437 -315.063244) (xy 400.578872 -315.102588) (xy 400.543379 -315.13668)
			(xy 400.502876 -315.164636) (xy 400.458414 -315.185734) (xy 400.411143 -315.199426) (xy 400.362288 -315.205358)
			(xy 400.313113 -315.203377) (xy 400.264894 -315.193533) (xy 400.218878 -315.176081) (xy 400.176257 -315.151474)
			(xy 400.138136 -315.120349) (xy 400.105501 -315.083512) (xy 400.079198 -315.041916) (xy 400.059907 -314.99664)
			(xy 400.04813 -314.948856) (xy 400.04417 -314.899802) (xy 399.705322 -314.899802) (xy 399.704827 -314.924409)
			(xy 399.696932 -314.972986) (xy 399.681348 -315.019667) (xy 399.658477 -315.063244) (xy 399.628912 -315.102588)
			(xy 399.593419 -315.13668) (xy 399.552916 -315.164636) (xy 399.508454 -315.185734) (xy 399.461183 -315.199426)
			(xy 399.412328 -315.205358) (xy 399.363153 -315.203377) (xy 399.314934 -315.193533) (xy 399.268918 -315.176081)
			(xy 399.226297 -315.151474) (xy 399.188176 -315.120349) (xy 399.155541 -315.083512) (xy 399.129238 -315.041916)
			(xy 399.109947 -314.99664) (xy 399.09817 -314.948856) (xy 399.09421 -314.899802) (xy 398.755108 -314.899802)
			(xy 398.754613 -314.924409) (xy 398.746718 -314.972986) (xy 398.731134 -315.019667) (xy 398.708263 -315.063244)
			(xy 398.678698 -315.102588) (xy 398.643205 -315.13668) (xy 398.602702 -315.164636) (xy 398.55824 -315.185734)
			(xy 398.510969 -315.199426) (xy 398.462114 -315.205358) (xy 398.412939 -315.203377) (xy 398.36472 -315.193533)
			(xy 398.318704 -315.176081) (xy 398.276083 -315.151474) (xy 398.237962 -315.120349) (xy 398.205327 -315.083512)
			(xy 398.179024 -315.041916) (xy 398.159733 -314.99664) (xy 398.147956 -314.948856) (xy 398.143996 -314.899802)
			(xy 397.805629 -314.899802) (xy 397.801459 -314.950134) (xy 397.789061 -314.999095) (xy 397.768775 -315.045347)
			(xy 397.741152 -315.087631) (xy 397.706948 -315.124791) (xy 397.667094 -315.155816) (xy 397.622677 -315.179858)
			(xy 397.574909 -315.196262) (xy 397.525093 -315.204581) (xy 397.49984 -315.20511) (xy 397.490736 -315.205012)
			(xy 397.472563 -315.203867) (xy 397.463518 -315.202824) (xy 397.451326 -315.201554) (xy 397.440404 -315.205364)
			(xy 397.434824 -315.207526) (xy 397.424809 -315.214071) (xy 397.420592 -315.218318) (xy 397.364204 -315.277246)
			(xy 397.36141 -315.280294) (xy 397.35851 -315.28409) (xy 397.35404 -315.292529) (xy 397.35252 -315.297058)
			(xy 397.348964 -315.308488) (xy 397.350996 -315.320426) (xy 397.353127 -315.333914) (xy 397.355416 -315.361127)
			(xy 397.355568 -315.374782) (xy 397.355406 -315.388436) (xy 397.353117 -315.415649) (xy 397.350996 -315.429138)
			(xy 397.348964 -315.441076) (xy 397.35252 -315.452506) (xy 397.354036 -315.457035) (xy 397.358516 -315.46547)
			(xy 397.36141 -315.46927) (xy 397.364204 -315.472318) (xy 397.420592 -315.531246) (xy 397.424822 -315.535476)
			(xy 397.434833 -315.542019) (xy 397.440404 -315.5442) (xy 397.451326 -315.54801) (xy 397.463518 -315.54674)
			(xy 397.472562 -315.545693) (xy 397.490736 -315.544552) (xy 397.49984 -315.544454) (xy 397.525096 -315.544979)
			(xy 397.574919 -315.553299) (xy 397.622693 -315.569705) (xy 397.667116 -315.593751) (xy 397.706975 -315.624779)
			(xy 397.741184 -315.661945) (xy 397.76881 -315.704234) (xy 397.789099 -315.750492) (xy 397.801498 -315.79946)
			(xy 397.805666 -315.849762) (xy 398.143996 -315.849762) (xy 398.147956 -315.800708) (xy 398.159733 -315.752924)
			(xy 398.179024 -315.707648) (xy 398.205327 -315.666052) (xy 398.237962 -315.629215) (xy 398.276083 -315.59809)
			(xy 398.318704 -315.573483) (xy 398.36472 -315.556031) (xy 398.412939 -315.546187) (xy 398.462114 -315.544206)
			(xy 398.510969 -315.550138) (xy 398.55824 -315.56383) (xy 398.602702 -315.584928) (xy 398.643205 -315.612884)
			(xy 398.678698 -315.646976) (xy 398.708263 -315.68632) (xy 398.731134 -315.729897) (xy 398.746718 -315.776578)
			(xy 398.754613 -315.825155) (xy 398.755108 -315.849762) (xy 398.754613 -315.874369) (xy 398.754434 -315.87547)
			(xy 399.073366 -315.87547) (xy 399.073366 -315.824054) (xy 399.081409 -315.773272) (xy 399.097297 -315.724373)
			(xy 399.12064 -315.678561) (xy 399.150861 -315.636965) (xy 399.187217 -315.600609) (xy 399.228813 -315.570388)
			(xy 399.274625 -315.547045) (xy 399.323524 -315.531157) (xy 399.374306 -315.523114) (xy 399.425722 -315.523114)
			(xy 399.476504 -315.531157) (xy 399.525403 -315.547045) (xy 399.571215 -315.570388) (xy 399.612811 -315.600609)
			(xy 399.649167 -315.636965) (xy 399.679388 -315.678561) (xy 399.702731 -315.724373) (xy 399.718619 -315.773272)
			(xy 399.726662 -315.824054) (xy 399.727166 -315.849762) (xy 400.04417 -315.849762) (xy 400.04813 -315.800708)
			(xy 400.059907 -315.752924) (xy 400.079198 -315.707648) (xy 400.105501 -315.666052) (xy 400.138136 -315.629215)
			(xy 400.176257 -315.59809) (xy 400.218878 -315.573483) (xy 400.264894 -315.556031) (xy 400.313113 -315.546187)
			(xy 400.362288 -315.544206) (xy 400.411143 -315.550138) (xy 400.458414 -315.56383) (xy 400.502876 -315.584928)
			(xy 400.543379 -315.612884) (xy 400.578872 -315.646976) (xy 400.608437 -315.68632) (xy 400.631308 -315.729897)
			(xy 400.646892 -315.776578) (xy 400.654787 -315.825155) (xy 400.655282 -315.849762) (xy 400.654787 -315.874369)
			(xy 400.654608 -315.87547) (xy 400.973286 -315.87547) (xy 400.973286 -315.824054) (xy 400.981329 -315.773272)
			(xy 400.997217 -315.724373) (xy 401.02056 -315.678561) (xy 401.050781 -315.636965) (xy 401.087137 -315.600609)
			(xy 401.128733 -315.570388) (xy 401.174545 -315.547045) (xy 401.223444 -315.531157) (xy 401.274226 -315.523114)
			(xy 401.325642 -315.523114) (xy 401.376424 -315.531157) (xy 401.425323 -315.547045) (xy 401.471135 -315.570388)
			(xy 401.512731 -315.600609) (xy 401.549087 -315.636965) (xy 401.579308 -315.678561) (xy 401.602651 -315.724373)
			(xy 401.618539 -315.773272) (xy 401.626582 -315.824054) (xy 401.627086 -315.849762) (xy 401.94409 -315.849762)
			(xy 401.94805 -315.800708) (xy 401.959827 -315.752924) (xy 401.979118 -315.707648) (xy 402.005421 -315.666052)
			(xy 402.038056 -315.629215) (xy 402.076177 -315.59809) (xy 402.118798 -315.573483) (xy 402.164814 -315.556031)
			(xy 402.213033 -315.546187) (xy 402.262208 -315.544206) (xy 402.311063 -315.550138) (xy 402.358334 -315.56383)
			(xy 402.402796 -315.584928) (xy 402.443299 -315.612884) (xy 402.478792 -315.646976) (xy 402.508357 -315.68632)
			(xy 402.531228 -315.729897) (xy 402.546812 -315.776578) (xy 402.554707 -315.825155) (xy 402.555202 -315.849762)
			(xy 402.554707 -315.874369) (xy 402.554528 -315.87547) (xy 402.873206 -315.87547) (xy 402.873206 -315.824054)
			(xy 402.881249 -315.773272) (xy 402.897137 -315.724373) (xy 402.92048 -315.678561) (xy 402.950701 -315.636965)
			(xy 402.987057 -315.600609) (xy 403.028653 -315.570388) (xy 403.074465 -315.547045) (xy 403.123364 -315.531157)
			(xy 403.174146 -315.523114) (xy 403.225562 -315.523114) (xy 403.276344 -315.531157) (xy 403.325243 -315.547045)
			(xy 403.371055 -315.570388) (xy 403.412651 -315.600609) (xy 403.449007 -315.636965) (xy 403.479228 -315.678561)
			(xy 403.502571 -315.724373) (xy 403.518459 -315.773272) (xy 403.526502 -315.824054) (xy 403.527006 -315.849762)
			(xy 403.84401 -315.849762) (xy 403.84797 -315.800708) (xy 403.859747 -315.752924) (xy 403.879038 -315.707648)
			(xy 403.905341 -315.666052) (xy 403.937976 -315.629215) (xy 403.976097 -315.59809) (xy 404.018718 -315.573483)
			(xy 404.064734 -315.556031) (xy 404.112953 -315.546187) (xy 404.162128 -315.544206) (xy 404.210983 -315.550138)
			(xy 404.258254 -315.56383) (xy 404.302716 -315.584928) (xy 404.343219 -315.612884) (xy 404.378712 -315.646976)
			(xy 404.408277 -315.68632) (xy 404.431148 -315.729897) (xy 404.446732 -315.776578) (xy 404.454627 -315.825155)
			(xy 404.455122 -315.849762) (xy 404.454627 -315.874369) (xy 404.454448 -315.87547) (xy 404.77338 -315.87547)
			(xy 404.77338 -315.824054) (xy 404.781423 -315.773272) (xy 404.797311 -315.724373) (xy 404.820654 -315.678561)
			(xy 404.850875 -315.636965) (xy 404.887231 -315.600609) (xy 404.928827 -315.570388) (xy 404.974639 -315.547045)
			(xy 405.023538 -315.531157) (xy 405.07432 -315.523114) (xy 405.125736 -315.523114) (xy 405.176518 -315.531157)
			(xy 405.225417 -315.547045) (xy 405.271229 -315.570388) (xy 405.312825 -315.600609) (xy 405.349181 -315.636965)
			(xy 405.379402 -315.678561) (xy 405.402745 -315.724373) (xy 405.418633 -315.773272) (xy 405.426676 -315.824054)
			(xy 405.42718 -315.849762) (xy 405.744184 -315.849762) (xy 405.748144 -315.800708) (xy 405.759921 -315.752924)
			(xy 405.779212 -315.707648) (xy 405.805515 -315.666052) (xy 405.83815 -315.629215) (xy 405.876271 -315.59809)
			(xy 405.918892 -315.573483) (xy 405.964908 -315.556031) (xy 406.013127 -315.546187) (xy 406.062302 -315.544206)
			(xy 406.111157 -315.550138) (xy 406.158428 -315.56383) (xy 406.20289 -315.584928) (xy 406.243393 -315.612884)
			(xy 406.278886 -315.646976) (xy 406.308451 -315.68632) (xy 406.331322 -315.729897) (xy 406.346906 -315.776578)
			(xy 406.354801 -315.825155) (xy 406.355296 -315.849762) (xy 406.354801 -315.874369) (xy 406.354622 -315.87547)
			(xy 406.6733 -315.87547) (xy 406.6733 -315.824054) (xy 406.681343 -315.773272) (xy 406.697231 -315.724373)
			(xy 406.720574 -315.678561) (xy 406.750795 -315.636965) (xy 406.787151 -315.600609) (xy 406.828747 -315.570388)
			(xy 406.874559 -315.547045) (xy 406.923458 -315.531157) (xy 406.97424 -315.523114) (xy 407.025656 -315.523114)
			(xy 407.076438 -315.531157) (xy 407.125337 -315.547045) (xy 407.171149 -315.570388) (xy 407.212745 -315.600609)
			(xy 407.249101 -315.636965) (xy 407.279322 -315.678561) (xy 407.302665 -315.724373) (xy 407.318553 -315.773272)
			(xy 407.326596 -315.824054) (xy 407.3271 -315.849762) (xy 407.644104 -315.849762) (xy 407.648064 -315.800708)
			(xy 407.659841 -315.752924) (xy 407.679132 -315.707648) (xy 407.705435 -315.666052) (xy 407.73807 -315.629215)
			(xy 407.776191 -315.59809) (xy 407.818812 -315.573483) (xy 407.864828 -315.556031) (xy 407.913047 -315.546187)
			(xy 407.962222 -315.544206) (xy 408.011077 -315.550138) (xy 408.058348 -315.56383) (xy 408.10281 -315.584928)
			(xy 408.143313 -315.612884) (xy 408.178806 -315.646976) (xy 408.208371 -315.68632) (xy 408.231242 -315.729897)
			(xy 408.246826 -315.776578) (xy 408.254721 -315.825155) (xy 408.255216 -315.849762) (xy 408.254721 -315.874369)
			(xy 408.254542 -315.87547) (xy 408.57322 -315.87547) (xy 408.57322 -315.824054) (xy 408.581263 -315.773272)
			(xy 408.597151 -315.724373) (xy 408.620494 -315.678561) (xy 408.650715 -315.636965) (xy 408.687071 -315.600609)
			(xy 408.728667 -315.570388) (xy 408.774479 -315.547045) (xy 408.823378 -315.531157) (xy 408.87416 -315.523114)
			(xy 408.925576 -315.523114) (xy 408.976358 -315.531157) (xy 409.025257 -315.547045) (xy 409.071069 -315.570388)
			(xy 409.112665 -315.600609) (xy 409.149021 -315.636965) (xy 409.179242 -315.678561) (xy 409.202585 -315.724373)
			(xy 409.218473 -315.773272) (xy 409.226516 -315.824054) (xy 409.22702 -315.849762) (xy 409.544024 -315.849762)
			(xy 409.547984 -315.800708) (xy 409.559761 -315.752924) (xy 409.579052 -315.707648) (xy 409.605355 -315.666052)
			(xy 409.63799 -315.629215) (xy 409.676111 -315.59809) (xy 409.718732 -315.573483) (xy 409.764748 -315.556031)
			(xy 409.812967 -315.546187) (xy 409.862142 -315.544206) (xy 409.910997 -315.550138) (xy 409.958268 -315.56383)
			(xy 410.00273 -315.584928) (xy 410.043233 -315.612884) (xy 410.078726 -315.646976) (xy 410.108291 -315.68632)
			(xy 410.131162 -315.729897) (xy 410.146746 -315.776578) (xy 410.154641 -315.825155) (xy 410.155136 -315.849762)
			(xy 410.154641 -315.874369) (xy 410.154462 -315.87547) (xy 410.47314 -315.87547) (xy 410.47314 -315.824054)
			(xy 410.481183 -315.773272) (xy 410.497071 -315.724373) (xy 410.520414 -315.678561) (xy 410.550635 -315.636965)
			(xy 410.586991 -315.600609) (xy 410.628587 -315.570388) (xy 410.674399 -315.547045) (xy 410.723298 -315.531157)
			(xy 410.77408 -315.523114) (xy 410.825496 -315.523114) (xy 410.876278 -315.531157) (xy 410.925177 -315.547045)
			(xy 410.970989 -315.570388) (xy 411.012585 -315.600609) (xy 411.048941 -315.636965) (xy 411.079162 -315.678561)
			(xy 411.102505 -315.724373) (xy 411.118393 -315.773272) (xy 411.126436 -315.824054) (xy 411.12694 -315.849762)
			(xy 411.444198 -315.849762) (xy 411.448158 -315.800708) (xy 411.459935 -315.752924) (xy 411.479226 -315.707648)
			(xy 411.505529 -315.666052) (xy 411.538164 -315.629215) (xy 411.576285 -315.59809) (xy 411.618906 -315.573483)
			(xy 411.664922 -315.556031) (xy 411.713141 -315.546187) (xy 411.762316 -315.544206) (xy 411.811171 -315.550138)
			(xy 411.858442 -315.56383) (xy 411.902904 -315.584928) (xy 411.943407 -315.612884) (xy 411.9789 -315.646976)
			(xy 412.008465 -315.68632) (xy 412.031336 -315.729897) (xy 412.04692 -315.776578) (xy 412.054815 -315.825155)
			(xy 412.05531 -315.849762) (xy 412.054815 -315.874369) (xy 412.054636 -315.87547) (xy 412.373314 -315.87547)
			(xy 412.373314 -315.824054) (xy 412.381357 -315.773272) (xy 412.397245 -315.724373) (xy 412.420588 -315.678561)
			(xy 412.450809 -315.636965) (xy 412.487165 -315.600609) (xy 412.528761 -315.570388) (xy 412.574573 -315.547045)
			(xy 412.623472 -315.531157) (xy 412.674254 -315.523114) (xy 412.72567 -315.523114) (xy 412.776452 -315.531157)
			(xy 412.825351 -315.547045) (xy 412.871163 -315.570388) (xy 412.912759 -315.600609) (xy 412.949115 -315.636965)
			(xy 412.979336 -315.678561) (xy 413.002679 -315.724373) (xy 413.018567 -315.773272) (xy 413.02661 -315.824054)
			(xy 413.027114 -315.849762) (xy 413.344118 -315.849762) (xy 413.348078 -315.800708) (xy 413.359855 -315.752924)
			(xy 413.379146 -315.707648) (xy 413.405449 -315.666052) (xy 413.438084 -315.629215) (xy 413.476205 -315.59809)
			(xy 413.518826 -315.573483) (xy 413.564842 -315.556031) (xy 413.613061 -315.546187) (xy 413.662236 -315.544206)
			(xy 413.711091 -315.550138) (xy 413.758362 -315.56383) (xy 413.802824 -315.584928) (xy 413.843327 -315.612884)
			(xy 413.87882 -315.646976) (xy 413.908385 -315.68632) (xy 413.931256 -315.729897) (xy 413.94684 -315.776578)
			(xy 413.954735 -315.825155) (xy 413.95523 -315.849762) (xy 414.294078 -315.849762) (xy 414.298038 -315.800708)
			(xy 414.309815 -315.752924) (xy 414.329106 -315.707648) (xy 414.355409 -315.666052) (xy 414.388044 -315.629215)
			(xy 414.426165 -315.59809) (xy 414.468786 -315.573483) (xy 414.514802 -315.556031) (xy 414.563021 -315.546187)
			(xy 414.612196 -315.544206) (xy 414.661051 -315.550138) (xy 414.708322 -315.56383) (xy 414.752784 -315.584928)
			(xy 414.793287 -315.612884) (xy 414.82878 -315.646976) (xy 414.858345 -315.68632) (xy 414.881216 -315.729897)
			(xy 414.8968 -315.776578) (xy 414.904695 -315.825155) (xy 414.90519 -315.849762) (xy 415.244038 -315.849762)
			(xy 415.247998 -315.800708) (xy 415.259775 -315.752924) (xy 415.279066 -315.707648) (xy 415.305369 -315.666052)
			(xy 415.338004 -315.629215) (xy 415.376125 -315.59809) (xy 415.418746 -315.573483) (xy 415.464762 -315.556031)
			(xy 415.512981 -315.546187) (xy 415.562156 -315.544206) (xy 415.611011 -315.550138) (xy 415.658282 -315.56383)
			(xy 415.702744 -315.584928) (xy 415.743247 -315.612884) (xy 415.77874 -315.646976) (xy 415.808305 -315.68632)
			(xy 415.831176 -315.729897) (xy 415.84676 -315.776578) (xy 415.854655 -315.825155) (xy 415.85515 -315.849762)
			(xy 416.193998 -315.849762) (xy 416.197958 -315.800708) (xy 416.209735 -315.752924) (xy 416.229026 -315.707648)
			(xy 416.255329 -315.666052) (xy 416.287964 -315.629215) (xy 416.326085 -315.59809) (xy 416.368706 -315.573483)
			(xy 416.414722 -315.556031) (xy 416.462941 -315.546187) (xy 416.512116 -315.544206) (xy 416.560971 -315.550138)
			(xy 416.608242 -315.56383) (xy 416.652704 -315.584928) (xy 416.693207 -315.612884) (xy 416.7287 -315.646976)
			(xy 416.758265 -315.68632) (xy 416.781136 -315.729897) (xy 416.79672 -315.776578) (xy 416.804615 -315.825155)
			(xy 416.80511 -315.849762) (xy 417.144212 -315.849762) (xy 417.148172 -315.800708) (xy 417.159949 -315.752924)
			(xy 417.17924 -315.707648) (xy 417.205543 -315.666052) (xy 417.238178 -315.629215) (xy 417.276299 -315.59809)
			(xy 417.31892 -315.573483) (xy 417.364936 -315.556031) (xy 417.413155 -315.546187) (xy 417.46233 -315.544206)
			(xy 417.511185 -315.550138) (xy 417.558456 -315.56383) (xy 417.602918 -315.584928) (xy 417.643421 -315.612884)
			(xy 417.678914 -315.646976) (xy 417.708479 -315.68632) (xy 417.73135 -315.729897) (xy 417.746934 -315.776578)
			(xy 417.754829 -315.825155) (xy 417.755324 -315.849762) (xy 418.094172 -315.849762) (xy 418.098132 -315.800708)
			(xy 418.109909 -315.752924) (xy 418.1292 -315.707648) (xy 418.155503 -315.666052) (xy 418.188138 -315.629215)
			(xy 418.226259 -315.59809) (xy 418.26888 -315.573483) (xy 418.314896 -315.556031) (xy 418.363115 -315.546187)
			(xy 418.41229 -315.544206) (xy 418.461145 -315.550138) (xy 418.508416 -315.56383) (xy 418.552878 -315.584928)
			(xy 418.593381 -315.612884) (xy 418.628874 -315.646976) (xy 418.658439 -315.68632) (xy 418.68131 -315.729897)
			(xy 418.696894 -315.776578) (xy 418.704789 -315.825155) (xy 418.705284 -315.849762) (xy 419.044132 -315.849762)
			(xy 419.048092 -315.800708) (xy 419.059869 -315.752924) (xy 419.07916 -315.707648) (xy 419.105463 -315.666052)
			(xy 419.138098 -315.629215) (xy 419.176219 -315.59809) (xy 419.21884 -315.573483) (xy 419.264856 -315.556031)
			(xy 419.313075 -315.546187) (xy 419.36225 -315.544206) (xy 419.411105 -315.550138) (xy 419.458376 -315.56383)
			(xy 419.502838 -315.584928) (xy 419.543341 -315.612884) (xy 419.578834 -315.646976) (xy 419.608399 -315.68632)
			(xy 419.63127 -315.729897) (xy 419.646854 -315.776578) (xy 419.654749 -315.825155) (xy 419.655244 -315.849762)
			(xy 419.994092 -315.849762) (xy 419.998052 -315.800708) (xy 420.009829 -315.752924) (xy 420.02912 -315.707648)
			(xy 420.055423 -315.666052) (xy 420.088058 -315.629215) (xy 420.126179 -315.59809) (xy 420.1688 -315.573483)
			(xy 420.214816 -315.556031) (xy 420.263035 -315.546187) (xy 420.31221 -315.544206) (xy 420.361065 -315.550138)
			(xy 420.408336 -315.56383) (xy 420.452798 -315.584928) (xy 420.493301 -315.612884) (xy 420.528794 -315.646976)
			(xy 420.558359 -315.68632) (xy 420.58123 -315.729897) (xy 420.596814 -315.776578) (xy 420.604709 -315.825155)
			(xy 420.605204 -315.849762) (xy 420.944052 -315.849762) (xy 420.948012 -315.800708) (xy 420.959789 -315.752924)
			(xy 420.97908 -315.707648) (xy 421.005383 -315.666052) (xy 421.038018 -315.629215) (xy 421.076139 -315.59809)
			(xy 421.11876 -315.573483) (xy 421.164776 -315.556031) (xy 421.212995 -315.546187) (xy 421.26217 -315.544206)
			(xy 421.311025 -315.550138) (xy 421.358296 -315.56383) (xy 421.402758 -315.584928) (xy 421.443261 -315.612884)
			(xy 421.478754 -315.646976) (xy 421.508319 -315.68632) (xy 421.53119 -315.729897) (xy 421.546774 -315.776578)
			(xy 421.554669 -315.825155) (xy 421.555164 -315.849762) (xy 421.554669 -315.874369) (xy 421.55449 -315.87547)
			(xy 421.873168 -315.87547) (xy 421.873168 -315.824054) (xy 421.881211 -315.773272) (xy 421.897099 -315.724373)
			(xy 421.920442 -315.678561) (xy 421.950663 -315.636965) (xy 421.987019 -315.600609) (xy 422.028615 -315.570388)
			(xy 422.074427 -315.547045) (xy 422.123326 -315.531157) (xy 422.174108 -315.523114) (xy 422.225524 -315.523114)
			(xy 422.276306 -315.531157) (xy 422.325205 -315.547045) (xy 422.371017 -315.570388) (xy 422.412613 -315.600609)
			(xy 422.448969 -315.636965) (xy 422.47919 -315.678561) (xy 422.502533 -315.724373) (xy 422.518421 -315.773272)
			(xy 422.526464 -315.824054) (xy 422.526968 -315.849762) (xy 422.844226 -315.849762) (xy 422.848186 -315.800708)
			(xy 422.859963 -315.752924) (xy 422.879254 -315.707648) (xy 422.905557 -315.666052) (xy 422.938192 -315.629215)
			(xy 422.976313 -315.59809) (xy 423.018934 -315.573483) (xy 423.06495 -315.556031) (xy 423.113169 -315.546187)
			(xy 423.162344 -315.544206) (xy 423.211199 -315.550138) (xy 423.25847 -315.56383) (xy 423.302932 -315.584928)
			(xy 423.343435 -315.612884) (xy 423.378928 -315.646976) (xy 423.408493 -315.68632) (xy 423.431364 -315.729897)
			(xy 423.446948 -315.776578) (xy 423.454843 -315.825155) (xy 423.455338 -315.849762) (xy 423.454843 -315.874369)
			(xy 423.454664 -315.87547) (xy 423.773342 -315.87547) (xy 423.773342 -315.824054) (xy 423.781385 -315.773272)
			(xy 423.797273 -315.724373) (xy 423.820616 -315.678561) (xy 423.850837 -315.636965) (xy 423.887193 -315.600609)
			(xy 423.928789 -315.570388) (xy 423.974601 -315.547045) (xy 424.0235 -315.531157) (xy 424.074282 -315.523114)
			(xy 424.125698 -315.523114) (xy 424.17648 -315.531157) (xy 424.225379 -315.547045) (xy 424.271191 -315.570388)
			(xy 424.312787 -315.600609) (xy 424.349143 -315.636965) (xy 424.379364 -315.678561) (xy 424.402707 -315.724373)
			(xy 424.418595 -315.773272) (xy 424.426638 -315.824054) (xy 424.427142 -315.849762) (xy 424.744146 -315.849762)
			(xy 424.748106 -315.800708) (xy 424.759883 -315.752924) (xy 424.779174 -315.707648) (xy 424.805477 -315.666052)
			(xy 424.838112 -315.629215) (xy 424.876233 -315.59809) (xy 424.918854 -315.573483) (xy 424.96487 -315.556031)
			(xy 425.013089 -315.546187) (xy 425.062264 -315.544206) (xy 425.111119 -315.550138) (xy 425.15839 -315.56383)
			(xy 425.202852 -315.584928) (xy 425.243355 -315.612884) (xy 425.278848 -315.646976) (xy 425.308413 -315.68632)
			(xy 425.331284 -315.729897) (xy 425.346868 -315.776578) (xy 425.354763 -315.825155) (xy 425.355258 -315.849762)
			(xy 425.354763 -315.874369) (xy 425.354584 -315.87547) (xy 425.673262 -315.87547) (xy 425.673262 -315.824054)
			(xy 425.681305 -315.773272) (xy 425.697193 -315.724373) (xy 425.720536 -315.678561) (xy 425.750757 -315.636965)
			(xy 425.787113 -315.600609) (xy 425.828709 -315.570388) (xy 425.874521 -315.547045) (xy 425.92342 -315.531157)
			(xy 425.974202 -315.523114) (xy 426.025618 -315.523114) (xy 426.0764 -315.531157) (xy 426.125299 -315.547045)
			(xy 426.171111 -315.570388) (xy 426.212707 -315.600609) (xy 426.249063 -315.636965) (xy 426.279284 -315.678561)
			(xy 426.302627 -315.724373) (xy 426.318515 -315.773272) (xy 426.326558 -315.824054) (xy 426.327062 -315.849762)
			(xy 426.644066 -315.849762) (xy 426.648026 -315.800708) (xy 426.659803 -315.752924) (xy 426.679094 -315.707648)
			(xy 426.705397 -315.666052) (xy 426.738032 -315.629215) (xy 426.776153 -315.59809) (xy 426.818774 -315.573483)
			(xy 426.86479 -315.556031) (xy 426.913009 -315.546187) (xy 426.962184 -315.544206) (xy 427.011039 -315.550138)
			(xy 427.05831 -315.56383) (xy 427.102772 -315.584928) (xy 427.143275 -315.612884) (xy 427.178768 -315.646976)
			(xy 427.208333 -315.68632) (xy 427.231204 -315.729897) (xy 427.246788 -315.776578) (xy 427.254683 -315.825155)
			(xy 427.255178 -315.849762) (xy 427.254683 -315.874369) (xy 427.254504 -315.87547) (xy 427.573182 -315.87547)
			(xy 427.573182 -315.824054) (xy 427.581225 -315.773272) (xy 427.597113 -315.724373) (xy 427.620456 -315.678561)
			(xy 427.650677 -315.636965) (xy 427.687033 -315.600609) (xy 427.728629 -315.570388) (xy 427.774441 -315.547045)
			(xy 427.82334 -315.531157) (xy 427.874122 -315.523114) (xy 427.925538 -315.523114) (xy 427.97632 -315.531157)
			(xy 428.025219 -315.547045) (xy 428.071031 -315.570388) (xy 428.112627 -315.600609) (xy 428.148983 -315.636965)
			(xy 428.179204 -315.678561) (xy 428.202547 -315.724373) (xy 428.218435 -315.773272) (xy 428.226478 -315.824054)
			(xy 428.226982 -315.849762) (xy 428.543986 -315.849762) (xy 428.547946 -315.800708) (xy 428.559723 -315.752924)
			(xy 428.579014 -315.707648) (xy 428.605317 -315.666052) (xy 428.637952 -315.629215) (xy 428.676073 -315.59809)
			(xy 428.718694 -315.573483) (xy 428.76471 -315.556031) (xy 428.812929 -315.546187) (xy 428.862104 -315.544206)
			(xy 428.910959 -315.550138) (xy 428.95823 -315.56383) (xy 429.002692 -315.584928) (xy 429.043195 -315.612884)
			(xy 429.078688 -315.646976) (xy 429.108253 -315.68632) (xy 429.131124 -315.729897) (xy 429.146708 -315.776578)
			(xy 429.154603 -315.825155) (xy 429.155098 -315.849762) (xy 429.4942 -315.849762) (xy 429.49816 -315.800708)
			(xy 429.509937 -315.752924) (xy 429.529228 -315.707648) (xy 429.555531 -315.666052) (xy 429.588166 -315.629215)
			(xy 429.626287 -315.59809) (xy 429.668908 -315.573483) (xy 429.714924 -315.556031) (xy 429.763143 -315.546187)
			(xy 429.812318 -315.544206) (xy 429.861173 -315.550138) (xy 429.908444 -315.56383) (xy 429.952906 -315.584928)
			(xy 429.993409 -315.612884) (xy 430.028902 -315.646976) (xy 430.058467 -315.68632) (xy 430.081338 -315.729897)
			(xy 430.096922 -315.776578) (xy 430.104817 -315.825155) (xy 430.105312 -315.849762) (xy 430.44416 -315.849762)
			(xy 430.44812 -315.800708) (xy 430.459897 -315.752924) (xy 430.479188 -315.707648) (xy 430.505491 -315.666052)
			(xy 430.538126 -315.629215) (xy 430.576247 -315.59809) (xy 430.618868 -315.573483) (xy 430.664884 -315.556031)
			(xy 430.713103 -315.546187) (xy 430.762278 -315.544206) (xy 430.811133 -315.550138) (xy 430.858404 -315.56383)
			(xy 430.902866 -315.584928) (xy 430.943369 -315.612884) (xy 430.978862 -315.646976) (xy 431.008427 -315.68632)
			(xy 431.031298 -315.729897) (xy 431.046882 -315.776578) (xy 431.054777 -315.825155) (xy 431.055272 -315.849762)
			(xy 431.054777 -315.874369) (xy 431.046882 -315.922946) (xy 431.031298 -315.969627) (xy 431.008427 -316.013204)
			(xy 430.978862 -316.052548) (xy 430.943369 -316.08664) (xy 430.902866 -316.114596) (xy 430.858404 -316.135694)
			(xy 430.811133 -316.149386) (xy 430.762278 -316.155318) (xy 430.713103 -316.153337) (xy 430.664884 -316.143493)
			(xy 430.618868 -316.126041) (xy 430.576247 -316.101434) (xy 430.538126 -316.070309) (xy 430.505491 -316.033472)
			(xy 430.479188 -315.991876) (xy 430.459897 -315.9466) (xy 430.44812 -315.898816) (xy 430.44416 -315.849762)
			(xy 430.105312 -315.849762) (xy 430.104817 -315.874369) (xy 430.096922 -315.922946) (xy 430.081338 -315.969627)
			(xy 430.058467 -316.013204) (xy 430.028902 -316.052548) (xy 429.993409 -316.08664) (xy 429.952906 -316.114596)
			(xy 429.908444 -316.135694) (xy 429.861173 -316.149386) (xy 429.812318 -316.155318) (xy 429.763143 -316.153337)
			(xy 429.714924 -316.143493) (xy 429.668908 -316.126041) (xy 429.626287 -316.101434) (xy 429.588166 -316.070309)
			(xy 429.555531 -316.033472) (xy 429.529228 -315.991876) (xy 429.509937 -315.9466) (xy 429.49816 -315.898816)
			(xy 429.4942 -315.849762) (xy 429.155098 -315.849762) (xy 429.154603 -315.874369) (xy 429.146708 -315.922946)
			(xy 429.131124 -315.969627) (xy 429.108253 -316.013204) (xy 429.078688 -316.052548) (xy 429.043195 -316.08664)
			(xy 429.002692 -316.114596) (xy 428.95823 -316.135694) (xy 428.910959 -316.149386) (xy 428.862104 -316.155318)
			(xy 428.812929 -316.153337) (xy 428.76471 -316.143493) (xy 428.718694 -316.126041) (xy 428.676073 -316.101434)
			(xy 428.637952 -316.070309) (xy 428.605317 -316.033472) (xy 428.579014 -315.991876) (xy 428.559723 -315.9466)
			(xy 428.547946 -315.898816) (xy 428.543986 -315.849762) (xy 428.226982 -315.849762) (xy 428.226478 -315.87547)
			(xy 428.218435 -315.926252) (xy 428.202547 -315.975151) (xy 428.179204 -316.020963) (xy 428.148983 -316.062559)
			(xy 428.112627 -316.098915) (xy 428.071031 -316.129136) (xy 428.025219 -316.152479) (xy 427.97632 -316.168367)
			(xy 427.925538 -316.17641) (xy 427.874122 -316.17641) (xy 427.82334 -316.168367) (xy 427.774441 -316.152479)
			(xy 427.728629 -316.129136) (xy 427.687033 -316.098915) (xy 427.650677 -316.062559) (xy 427.620456 -316.020963)
			(xy 427.597113 -315.975151) (xy 427.581225 -315.926252) (xy 427.573182 -315.87547) (xy 427.254504 -315.87547)
			(xy 427.246788 -315.922946) (xy 427.231204 -315.969627) (xy 427.208333 -316.013204) (xy 427.178768 -316.052548)
			(xy 427.143275 -316.08664) (xy 427.102772 -316.114596) (xy 427.05831 -316.135694) (xy 427.011039 -316.149386)
			(xy 426.962184 -316.155318) (xy 426.913009 -316.153337) (xy 426.86479 -316.143493) (xy 426.818774 -316.126041)
			(xy 426.776153 -316.101434) (xy 426.738032 -316.070309) (xy 426.705397 -316.033472) (xy 426.679094 -315.991876)
			(xy 426.659803 -315.9466) (xy 426.648026 -315.898816) (xy 426.644066 -315.849762) (xy 426.327062 -315.849762)
			(xy 426.326558 -315.87547) (xy 426.318515 -315.926252) (xy 426.302627 -315.975151) (xy 426.279284 -316.020963)
			(xy 426.249063 -316.062559) (xy 426.212707 -316.098915) (xy 426.171111 -316.129136) (xy 426.125299 -316.152479)
			(xy 426.0764 -316.168367) (xy 426.025618 -316.17641) (xy 425.974202 -316.17641) (xy 425.92342 -316.168367)
			(xy 425.874521 -316.152479) (xy 425.828709 -316.129136) (xy 425.787113 -316.098915) (xy 425.750757 -316.062559)
			(xy 425.720536 -316.020963) (xy 425.697193 -315.975151) (xy 425.681305 -315.926252) (xy 425.673262 -315.87547)
			(xy 425.354584 -315.87547) (xy 425.346868 -315.922946) (xy 425.331284 -315.969627) (xy 425.308413 -316.013204)
			(xy 425.278848 -316.052548) (xy 425.243355 -316.08664) (xy 425.202852 -316.114596) (xy 425.15839 -316.135694)
			(xy 425.111119 -316.149386) (xy 425.062264 -316.155318) (xy 425.013089 -316.153337) (xy 424.96487 -316.143493)
			(xy 424.918854 -316.126041) (xy 424.876233 -316.101434) (xy 424.838112 -316.070309) (xy 424.805477 -316.033472)
			(xy 424.779174 -315.991876) (xy 424.759883 -315.9466) (xy 424.748106 -315.898816) (xy 424.744146 -315.849762)
			(xy 424.427142 -315.849762) (xy 424.426638 -315.87547) (xy 424.418595 -315.926252) (xy 424.402707 -315.975151)
			(xy 424.379364 -316.020963) (xy 424.349143 -316.062559) (xy 424.312787 -316.098915) (xy 424.271191 -316.129136)
			(xy 424.225379 -316.152479) (xy 424.17648 -316.168367) (xy 424.125698 -316.17641) (xy 424.074282 -316.17641)
			(xy 424.0235 -316.168367) (xy 423.974601 -316.152479) (xy 423.928789 -316.129136) (xy 423.887193 -316.098915)
			(xy 423.850837 -316.062559) (xy 423.820616 -316.020963) (xy 423.797273 -315.975151) (xy 423.781385 -315.926252)
			(xy 423.773342 -315.87547) (xy 423.454664 -315.87547) (xy 423.446948 -315.922946) (xy 423.431364 -315.969627)
			(xy 423.408493 -316.013204) (xy 423.378928 -316.052548) (xy 423.343435 -316.08664) (xy 423.302932 -316.114596)
			(xy 423.25847 -316.135694) (xy 423.211199 -316.149386) (xy 423.162344 -316.155318) (xy 423.113169 -316.153337)
			(xy 423.06495 -316.143493) (xy 423.018934 -316.126041) (xy 422.976313 -316.101434) (xy 422.938192 -316.070309)
			(xy 422.905557 -316.033472) (xy 422.879254 -315.991876) (xy 422.859963 -315.9466) (xy 422.848186 -315.898816)
			(xy 422.844226 -315.849762) (xy 422.526968 -315.849762) (xy 422.526464 -315.87547) (xy 422.518421 -315.926252)
			(xy 422.502533 -315.975151) (xy 422.47919 -316.020963) (xy 422.448969 -316.062559) (xy 422.412613 -316.098915)
			(xy 422.371017 -316.129136) (xy 422.325205 -316.152479) (xy 422.276306 -316.168367) (xy 422.225524 -316.17641)
			(xy 422.174108 -316.17641) (xy 422.123326 -316.168367) (xy 422.074427 -316.152479) (xy 422.028615 -316.129136)
			(xy 421.987019 -316.098915) (xy 421.950663 -316.062559) (xy 421.920442 -316.020963) (xy 421.897099 -315.975151)
			(xy 421.881211 -315.926252) (xy 421.873168 -315.87547) (xy 421.55449 -315.87547) (xy 421.546774 -315.922946)
			(xy 421.53119 -315.969627) (xy 421.508319 -316.013204) (xy 421.478754 -316.052548) (xy 421.443261 -316.08664)
			(xy 421.402758 -316.114596) (xy 421.358296 -316.135694) (xy 421.311025 -316.149386) (xy 421.26217 -316.155318)
			(xy 421.212995 -316.153337) (xy 421.164776 -316.143493) (xy 421.11876 -316.126041) (xy 421.076139 -316.101434)
			(xy 421.038018 -316.070309) (xy 421.005383 -316.033472) (xy 420.97908 -315.991876) (xy 420.959789 -315.9466)
			(xy 420.948012 -315.898816) (xy 420.944052 -315.849762) (xy 420.605204 -315.849762) (xy 420.604709 -315.874369)
			(xy 420.596814 -315.922946) (xy 420.58123 -315.969627) (xy 420.558359 -316.013204) (xy 420.528794 -316.052548)
			(xy 420.493301 -316.08664) (xy 420.452798 -316.114596) (xy 420.408336 -316.135694) (xy 420.361065 -316.149386)
			(xy 420.31221 -316.155318) (xy 420.263035 -316.153337) (xy 420.214816 -316.143493) (xy 420.1688 -316.126041)
			(xy 420.126179 -316.101434) (xy 420.088058 -316.070309) (xy 420.055423 -316.033472) (xy 420.02912 -315.991876)
			(xy 420.009829 -315.9466) (xy 419.998052 -315.898816) (xy 419.994092 -315.849762) (xy 419.655244 -315.849762)
			(xy 419.654749 -315.874369) (xy 419.646854 -315.922946) (xy 419.63127 -315.969627) (xy 419.608399 -316.013204)
			(xy 419.578834 -316.052548) (xy 419.543341 -316.08664) (xy 419.502838 -316.114596) (xy 419.458376 -316.135694)
			(xy 419.411105 -316.149386) (xy 419.36225 -316.155318) (xy 419.313075 -316.153337) (xy 419.264856 -316.143493)
			(xy 419.21884 -316.126041) (xy 419.176219 -316.101434) (xy 419.138098 -316.070309) (xy 419.105463 -316.033472)
			(xy 419.07916 -315.991876) (xy 419.059869 -315.9466) (xy 419.048092 -315.898816) (xy 419.044132 -315.849762)
			(xy 418.705284 -315.849762) (xy 418.704789 -315.874369) (xy 418.696894 -315.922946) (xy 418.68131 -315.969627)
			(xy 418.658439 -316.013204) (xy 418.628874 -316.052548) (xy 418.593381 -316.08664) (xy 418.552878 -316.114596)
			(xy 418.508416 -316.135694) (xy 418.461145 -316.149386) (xy 418.41229 -316.155318) (xy 418.363115 -316.153337)
			(xy 418.314896 -316.143493) (xy 418.26888 -316.126041) (xy 418.226259 -316.101434) (xy 418.188138 -316.070309)
			(xy 418.155503 -316.033472) (xy 418.1292 -315.991876) (xy 418.109909 -315.9466) (xy 418.098132 -315.898816)
			(xy 418.094172 -315.849762) (xy 417.755324 -315.849762) (xy 417.754829 -315.874369) (xy 417.746934 -315.922946)
			(xy 417.73135 -315.969627) (xy 417.708479 -316.013204) (xy 417.678914 -316.052548) (xy 417.643421 -316.08664)
			(xy 417.602918 -316.114596) (xy 417.558456 -316.135694) (xy 417.511185 -316.149386) (xy 417.46233 -316.155318)
			(xy 417.413155 -316.153337) (xy 417.364936 -316.143493) (xy 417.31892 -316.126041) (xy 417.276299 -316.101434)
			(xy 417.238178 -316.070309) (xy 417.205543 -316.033472) (xy 417.17924 -315.991876) (xy 417.159949 -315.9466)
			(xy 417.148172 -315.898816) (xy 417.144212 -315.849762) (xy 416.80511 -315.849762) (xy 416.804615 -315.874369)
			(xy 416.79672 -315.922946) (xy 416.781136 -315.969627) (xy 416.758265 -316.013204) (xy 416.7287 -316.052548)
			(xy 416.693207 -316.08664) (xy 416.652704 -316.114596) (xy 416.608242 -316.135694) (xy 416.560971 -316.149386)
			(xy 416.512116 -316.155318) (xy 416.462941 -316.153337) (xy 416.414722 -316.143493) (xy 416.368706 -316.126041)
			(xy 416.326085 -316.101434) (xy 416.287964 -316.070309) (xy 416.255329 -316.033472) (xy 416.229026 -315.991876)
			(xy 416.209735 -315.9466) (xy 416.197958 -315.898816) (xy 416.193998 -315.849762) (xy 415.85515 -315.849762)
			(xy 415.854655 -315.874369) (xy 415.84676 -315.922946) (xy 415.831176 -315.969627) (xy 415.808305 -316.013204)
			(xy 415.77874 -316.052548) (xy 415.743247 -316.08664) (xy 415.702744 -316.114596) (xy 415.658282 -316.135694)
			(xy 415.611011 -316.149386) (xy 415.562156 -316.155318) (xy 415.512981 -316.153337) (xy 415.464762 -316.143493)
			(xy 415.418746 -316.126041) (xy 415.376125 -316.101434) (xy 415.338004 -316.070309) (xy 415.305369 -316.033472)
			(xy 415.279066 -315.991876) (xy 415.259775 -315.9466) (xy 415.247998 -315.898816) (xy 415.244038 -315.849762)
			(xy 414.90519 -315.849762) (xy 414.904695 -315.874369) (xy 414.8968 -315.922946) (xy 414.881216 -315.969627)
			(xy 414.858345 -316.013204) (xy 414.82878 -316.052548) (xy 414.793287 -316.08664) (xy 414.752784 -316.114596)
			(xy 414.708322 -316.135694) (xy 414.661051 -316.149386) (xy 414.612196 -316.155318) (xy 414.563021 -316.153337)
			(xy 414.514802 -316.143493) (xy 414.468786 -316.126041) (xy 414.426165 -316.101434) (xy 414.388044 -316.070309)
			(xy 414.355409 -316.033472) (xy 414.329106 -315.991876) (xy 414.309815 -315.9466) (xy 414.298038 -315.898816)
			(xy 414.294078 -315.849762) (xy 413.95523 -315.849762) (xy 413.954735 -315.874369) (xy 413.94684 -315.922946)
			(xy 413.931256 -315.969627) (xy 413.908385 -316.013204) (xy 413.87882 -316.052548) (xy 413.843327 -316.08664)
			(xy 413.802824 -316.114596) (xy 413.758362 -316.135694) (xy 413.711091 -316.149386) (xy 413.662236 -316.155318)
			(xy 413.613061 -316.153337) (xy 413.564842 -316.143493) (xy 413.518826 -316.126041) (xy 413.476205 -316.101434)
			(xy 413.438084 -316.070309) (xy 413.405449 -316.033472) (xy 413.379146 -315.991876) (xy 413.359855 -315.9466)
			(xy 413.348078 -315.898816) (xy 413.344118 -315.849762) (xy 413.027114 -315.849762) (xy 413.02661 -315.87547)
			(xy 413.018567 -315.926252) (xy 413.002679 -315.975151) (xy 412.979336 -316.020963) (xy 412.949115 -316.062559)
			(xy 412.912759 -316.098915) (xy 412.871163 -316.129136) (xy 412.825351 -316.152479) (xy 412.776452 -316.168367)
			(xy 412.72567 -316.17641) (xy 412.674254 -316.17641) (xy 412.623472 -316.168367) (xy 412.574573 -316.152479)
			(xy 412.528761 -316.129136) (xy 412.487165 -316.098915) (xy 412.450809 -316.062559) (xy 412.420588 -316.020963)
			(xy 412.397245 -315.975151) (xy 412.381357 -315.926252) (xy 412.373314 -315.87547) (xy 412.054636 -315.87547)
			(xy 412.04692 -315.922946) (xy 412.031336 -315.969627) (xy 412.008465 -316.013204) (xy 411.9789 -316.052548)
			(xy 411.943407 -316.08664) (xy 411.902904 -316.114596) (xy 411.858442 -316.135694) (xy 411.811171 -316.149386)
			(xy 411.762316 -316.155318) (xy 411.713141 -316.153337) (xy 411.664922 -316.143493) (xy 411.618906 -316.126041)
			(xy 411.576285 -316.101434) (xy 411.538164 -316.070309) (xy 411.505529 -316.033472) (xy 411.479226 -315.991876)
			(xy 411.459935 -315.9466) (xy 411.448158 -315.898816) (xy 411.444198 -315.849762) (xy 411.12694 -315.849762)
			(xy 411.126436 -315.87547) (xy 411.118393 -315.926252) (xy 411.102505 -315.975151) (xy 411.079162 -316.020963)
			(xy 411.048941 -316.062559) (xy 411.012585 -316.098915) (xy 410.970989 -316.129136) (xy 410.925177 -316.152479)
			(xy 410.876278 -316.168367) (xy 410.825496 -316.17641) (xy 410.77408 -316.17641) (xy 410.723298 -316.168367)
			(xy 410.674399 -316.152479) (xy 410.628587 -316.129136) (xy 410.586991 -316.098915) (xy 410.550635 -316.062559)
			(xy 410.520414 -316.020963) (xy 410.497071 -315.975151) (xy 410.481183 -315.926252) (xy 410.47314 -315.87547)
			(xy 410.154462 -315.87547) (xy 410.146746 -315.922946) (xy 410.131162 -315.969627) (xy 410.108291 -316.013204)
			(xy 410.078726 -316.052548) (xy 410.043233 -316.08664) (xy 410.00273 -316.114596) (xy 409.958268 -316.135694)
			(xy 409.910997 -316.149386) (xy 409.862142 -316.155318) (xy 409.812967 -316.153337) (xy 409.764748 -316.143493)
			(xy 409.718732 -316.126041) (xy 409.676111 -316.101434) (xy 409.63799 -316.070309) (xy 409.605355 -316.033472)
			(xy 409.579052 -315.991876) (xy 409.559761 -315.9466) (xy 409.547984 -315.898816) (xy 409.544024 -315.849762)
			(xy 409.22702 -315.849762) (xy 409.226516 -315.87547) (xy 409.218473 -315.926252) (xy 409.202585 -315.975151)
			(xy 409.179242 -316.020963) (xy 409.149021 -316.062559) (xy 409.112665 -316.098915) (xy 409.071069 -316.129136)
			(xy 409.025257 -316.152479) (xy 408.976358 -316.168367) (xy 408.925576 -316.17641) (xy 408.87416 -316.17641)
			(xy 408.823378 -316.168367) (xy 408.774479 -316.152479) (xy 408.728667 -316.129136) (xy 408.687071 -316.098915)
			(xy 408.650715 -316.062559) (xy 408.620494 -316.020963) (xy 408.597151 -315.975151) (xy 408.581263 -315.926252)
			(xy 408.57322 -315.87547) (xy 408.254542 -315.87547) (xy 408.246826 -315.922946) (xy 408.231242 -315.969627)
			(xy 408.208371 -316.013204) (xy 408.178806 -316.052548) (xy 408.143313 -316.08664) (xy 408.10281 -316.114596)
			(xy 408.058348 -316.135694) (xy 408.011077 -316.149386) (xy 407.962222 -316.155318) (xy 407.913047 -316.153337)
			(xy 407.864828 -316.143493) (xy 407.818812 -316.126041) (xy 407.776191 -316.101434) (xy 407.73807 -316.070309)
			(xy 407.705435 -316.033472) (xy 407.679132 -315.991876) (xy 407.659841 -315.9466) (xy 407.648064 -315.898816)
			(xy 407.644104 -315.849762) (xy 407.3271 -315.849762) (xy 407.326596 -315.87547) (xy 407.318553 -315.926252)
			(xy 407.302665 -315.975151) (xy 407.279322 -316.020963) (xy 407.249101 -316.062559) (xy 407.212745 -316.098915)
			(xy 407.171149 -316.129136) (xy 407.125337 -316.152479) (xy 407.076438 -316.168367) (xy 407.025656 -316.17641)
			(xy 406.97424 -316.17641) (xy 406.923458 -316.168367) (xy 406.874559 -316.152479) (xy 406.828747 -316.129136)
			(xy 406.787151 -316.098915) (xy 406.750795 -316.062559) (xy 406.720574 -316.020963) (xy 406.697231 -315.975151)
			(xy 406.681343 -315.926252) (xy 406.6733 -315.87547) (xy 406.354622 -315.87547) (xy 406.346906 -315.922946)
			(xy 406.331322 -315.969627) (xy 406.308451 -316.013204) (xy 406.278886 -316.052548) (xy 406.243393 -316.08664)
			(xy 406.20289 -316.114596) (xy 406.158428 -316.135694) (xy 406.111157 -316.149386) (xy 406.062302 -316.155318)
			(xy 406.013127 -316.153337) (xy 405.964908 -316.143493) (xy 405.918892 -316.126041) (xy 405.876271 -316.101434)
			(xy 405.83815 -316.070309) (xy 405.805515 -316.033472) (xy 405.779212 -315.991876) (xy 405.759921 -315.9466)
			(xy 405.748144 -315.898816) (xy 405.744184 -315.849762) (xy 405.42718 -315.849762) (xy 405.426676 -315.87547)
			(xy 405.418633 -315.926252) (xy 405.402745 -315.975151) (xy 405.379402 -316.020963) (xy 405.349181 -316.062559)
			(xy 405.312825 -316.098915) (xy 405.271229 -316.129136) (xy 405.225417 -316.152479) (xy 405.176518 -316.168367)
			(xy 405.125736 -316.17641) (xy 405.07432 -316.17641) (xy 405.023538 -316.168367) (xy 404.974639 -316.152479)
			(xy 404.928827 -316.129136) (xy 404.887231 -316.098915) (xy 404.850875 -316.062559) (xy 404.820654 -316.020963)
			(xy 404.797311 -315.975151) (xy 404.781423 -315.926252) (xy 404.77338 -315.87547) (xy 404.454448 -315.87547)
			(xy 404.446732 -315.922946) (xy 404.431148 -315.969627) (xy 404.408277 -316.013204) (xy 404.378712 -316.052548)
			(xy 404.343219 -316.08664) (xy 404.302716 -316.114596) (xy 404.258254 -316.135694) (xy 404.210983 -316.149386)
			(xy 404.162128 -316.155318) (xy 404.112953 -316.153337) (xy 404.064734 -316.143493) (xy 404.018718 -316.126041)
			(xy 403.976097 -316.101434) (xy 403.937976 -316.070309) (xy 403.905341 -316.033472) (xy 403.879038 -315.991876)
			(xy 403.859747 -315.9466) (xy 403.84797 -315.898816) (xy 403.84401 -315.849762) (xy 403.527006 -315.849762)
			(xy 403.526502 -315.87547) (xy 403.518459 -315.926252) (xy 403.502571 -315.975151) (xy 403.479228 -316.020963)
			(xy 403.449007 -316.062559) (xy 403.412651 -316.098915) (xy 403.371055 -316.129136) (xy 403.325243 -316.152479)
			(xy 403.276344 -316.168367) (xy 403.225562 -316.17641) (xy 403.174146 -316.17641) (xy 403.123364 -316.168367)
			(xy 403.074465 -316.152479) (xy 403.028653 -316.129136) (xy 402.987057 -316.098915) (xy 402.950701 -316.062559)
			(xy 402.92048 -316.020963) (xy 402.897137 -315.975151) (xy 402.881249 -315.926252) (xy 402.873206 -315.87547)
			(xy 402.554528 -315.87547) (xy 402.546812 -315.922946) (xy 402.531228 -315.969627) (xy 402.508357 -316.013204)
			(xy 402.478792 -316.052548) (xy 402.443299 -316.08664) (xy 402.402796 -316.114596) (xy 402.358334 -316.135694)
			(xy 402.311063 -316.149386) (xy 402.262208 -316.155318) (xy 402.213033 -316.153337) (xy 402.164814 -316.143493)
			(xy 402.118798 -316.126041) (xy 402.076177 -316.101434) (xy 402.038056 -316.070309) (xy 402.005421 -316.033472)
			(xy 401.979118 -315.991876) (xy 401.959827 -315.9466) (xy 401.94805 -315.898816) (xy 401.94409 -315.849762)
			(xy 401.627086 -315.849762) (xy 401.626582 -315.87547) (xy 401.618539 -315.926252) (xy 401.602651 -315.975151)
			(xy 401.579308 -316.020963) (xy 401.549087 -316.062559) (xy 401.512731 -316.098915) (xy 401.471135 -316.129136)
			(xy 401.425323 -316.152479) (xy 401.376424 -316.168367) (xy 401.325642 -316.17641) (xy 401.274226 -316.17641)
			(xy 401.223444 -316.168367) (xy 401.174545 -316.152479) (xy 401.128733 -316.129136) (xy 401.087137 -316.098915)
			(xy 401.050781 -316.062559) (xy 401.02056 -316.020963) (xy 400.997217 -315.975151) (xy 400.981329 -315.926252)
			(xy 400.973286 -315.87547) (xy 400.654608 -315.87547) (xy 400.646892 -315.922946) (xy 400.631308 -315.969627)
			(xy 400.608437 -316.013204) (xy 400.578872 -316.052548) (xy 400.543379 -316.08664) (xy 400.502876 -316.114596)
			(xy 400.458414 -316.135694) (xy 400.411143 -316.149386) (xy 400.362288 -316.155318) (xy 400.313113 -316.153337)
			(xy 400.264894 -316.143493) (xy 400.218878 -316.126041) (xy 400.176257 -316.101434) (xy 400.138136 -316.070309)
			(xy 400.105501 -316.033472) (xy 400.079198 -315.991876) (xy 400.059907 -315.9466) (xy 400.04813 -315.898816)
			(xy 400.04417 -315.849762) (xy 399.727166 -315.849762) (xy 399.726662 -315.87547) (xy 399.718619 -315.926252)
			(xy 399.702731 -315.975151) (xy 399.679388 -316.020963) (xy 399.649167 -316.062559) (xy 399.612811 -316.098915)
			(xy 399.571215 -316.129136) (xy 399.525403 -316.152479) (xy 399.476504 -316.168367) (xy 399.425722 -316.17641)
			(xy 399.374306 -316.17641) (xy 399.323524 -316.168367) (xy 399.274625 -316.152479) (xy 399.228813 -316.129136)
			(xy 399.187217 -316.098915) (xy 399.150861 -316.062559) (xy 399.12064 -316.020963) (xy 399.097297 -315.975151)
			(xy 399.081409 -315.926252) (xy 399.073366 -315.87547) (xy 398.754434 -315.87547) (xy 398.746718 -315.922946)
			(xy 398.731134 -315.969627) (xy 398.708263 -316.013204) (xy 398.678698 -316.052548) (xy 398.643205 -316.08664)
			(xy 398.602702 -316.114596) (xy 398.55824 -316.135694) (xy 398.510969 -316.149386) (xy 398.462114 -316.155318)
			(xy 398.412939 -316.153337) (xy 398.36472 -316.143493) (xy 398.318704 -316.126041) (xy 398.276083 -316.101434)
			(xy 398.237962 -316.070309) (xy 398.205327 -316.033472) (xy 398.179024 -315.991876) (xy 398.159733 -315.9466)
			(xy 398.147956 -315.898816) (xy 398.143996 -315.849762) (xy 397.805666 -315.849762) (xy 397.805669 -315.8498)
			(xy 397.801498 -315.90014) (xy 397.789099 -315.949108) (xy 397.76881 -315.995366) (xy 397.741184 -316.037655)
			(xy 397.706975 -316.074821) (xy 397.667116 -316.105849) (xy 397.622693 -316.129895) (xy 397.574919 -316.146301)
			(xy 397.525096 -316.154621) (xy 397.49984 -316.15507) (xy 397.490736 -316.154972) (xy 397.472563 -316.153827)
			(xy 397.463518 -316.152784) (xy 397.451326 -316.151514) (xy 397.440404 -316.155324) (xy 397.434823 -316.157485)
			(xy 397.424804 -316.164026) (xy 397.420592 -316.168278) (xy 397.364204 -316.227206) (xy 397.36141 -316.230254)
			(xy 397.358507 -316.234048) (xy 397.354031 -316.242486) (xy 397.35252 -316.247018) (xy 397.348964 -316.258448)
			(xy 397.350996 -316.270386) (xy 397.353121 -316.283811) (xy 397.355409 -316.310897) (xy 397.355568 -316.324488)
			(xy 397.355568 -316.32525) (xy 397.35506 -316.3443) (xy 397.35506 -316.3951) (xy 397.355314 -316.400434)
			(xy 397.356178 -316.407064) (xy 397.360937 -316.419554) (xy 397.364712 -316.425072) (xy 397.372078 -316.4332)
			(xy 397.428466 -316.483492) (xy 397.43247 -316.486886) (xy 397.44156 -316.492131) (xy 397.4465 -316.493906)
			(xy 397.45666 -316.497208) (xy 397.467328 -316.496192) (xy 397.49984 -316.494414) (xy 397.525091 -316.494939)
			(xy 397.574904 -316.503257) (xy 397.622669 -316.51966) (xy 397.667083 -316.543701) (xy 397.706934 -316.574723)
			(xy 397.741137 -316.611882) (xy 397.768757 -316.654162) (xy 397.789042 -316.700412) (xy 397.801439 -316.74937)
			(xy 397.805609 -316.7997) (xy 397.805607 -316.799722) (xy 398.143996 -316.799722) (xy 398.147956 -316.750668)
			(xy 398.159733 -316.702884) (xy 398.179024 -316.657608) (xy 398.205327 -316.616012) (xy 398.237962 -316.579175)
			(xy 398.276083 -316.54805) (xy 398.318704 -316.523443) (xy 398.36472 -316.505991) (xy 398.412939 -316.496147)
			(xy 398.462114 -316.494166) (xy 398.510969 -316.500098) (xy 398.55824 -316.51379) (xy 398.602702 -316.534888)
			(xy 398.643205 -316.562844) (xy 398.678698 -316.596936) (xy 398.708263 -316.63628) (xy 398.731134 -316.679857)
			(xy 398.746718 -316.726538) (xy 398.754613 -316.775115) (xy 398.755108 -316.799722) (xy 398.754613 -316.824329)
			(xy 398.754434 -316.82543) (xy 399.073366 -316.82543) (xy 399.073366 -316.774014) (xy 399.081409 -316.723232)
			(xy 399.097297 -316.674333) (xy 399.12064 -316.628521) (xy 399.150861 -316.586925) (xy 399.187217 -316.550569)
			(xy 399.228813 -316.520348) (xy 399.274625 -316.497005) (xy 399.323524 -316.481117) (xy 399.374306 -316.473074)
			(xy 399.425722 -316.473074) (xy 399.476504 -316.481117) (xy 399.525403 -316.497005) (xy 399.571215 -316.520348)
			(xy 399.612811 -316.550569) (xy 399.649167 -316.586925) (xy 399.679388 -316.628521) (xy 399.702731 -316.674333)
			(xy 399.718619 -316.723232) (xy 399.726662 -316.774014) (xy 399.727166 -316.799722) (xy 400.04417 -316.799722)
			(xy 400.04813 -316.750668) (xy 400.059907 -316.702884) (xy 400.079198 -316.657608) (xy 400.105501 -316.616012)
			(xy 400.138136 -316.579175) (xy 400.176257 -316.54805) (xy 400.218878 -316.523443) (xy 400.264894 -316.505991)
			(xy 400.313113 -316.496147) (xy 400.362288 -316.494166) (xy 400.411143 -316.500098) (xy 400.458414 -316.51379)
			(xy 400.502876 -316.534888) (xy 400.543379 -316.562844) (xy 400.578872 -316.596936) (xy 400.608437 -316.63628)
			(xy 400.631308 -316.679857) (xy 400.646892 -316.726538) (xy 400.654787 -316.775115) (xy 400.655282 -316.799722)
			(xy 400.654787 -316.824329) (xy 400.654608 -316.82543) (xy 400.973286 -316.82543) (xy 400.973286 -316.774014)
			(xy 400.981329 -316.723232) (xy 400.997217 -316.674333) (xy 401.02056 -316.628521) (xy 401.050781 -316.586925)
			(xy 401.087137 -316.550569) (xy 401.128733 -316.520348) (xy 401.174545 -316.497005) (xy 401.223444 -316.481117)
			(xy 401.274226 -316.473074) (xy 401.325642 -316.473074) (xy 401.376424 -316.481117) (xy 401.425323 -316.497005)
			(xy 401.471135 -316.520348) (xy 401.512731 -316.550569) (xy 401.549087 -316.586925) (xy 401.579308 -316.628521)
			(xy 401.602651 -316.674333) (xy 401.618539 -316.723232) (xy 401.626582 -316.774014) (xy 401.627086 -316.799722)
			(xy 401.94409 -316.799722) (xy 401.94805 -316.750668) (xy 401.959827 -316.702884) (xy 401.979118 -316.657608)
			(xy 402.005421 -316.616012) (xy 402.038056 -316.579175) (xy 402.076177 -316.54805) (xy 402.118798 -316.523443)
			(xy 402.164814 -316.505991) (xy 402.213033 -316.496147) (xy 402.262208 -316.494166) (xy 402.311063 -316.500098)
			(xy 402.358334 -316.51379) (xy 402.402796 -316.534888) (xy 402.443299 -316.562844) (xy 402.478792 -316.596936)
			(xy 402.508357 -316.63628) (xy 402.531228 -316.679857) (xy 402.546812 -316.726538) (xy 402.554707 -316.775115)
			(xy 402.555202 -316.799722) (xy 402.554707 -316.824329) (xy 402.554528 -316.82543) (xy 402.873206 -316.82543)
			(xy 402.873206 -316.774014) (xy 402.881249 -316.723232) (xy 402.897137 -316.674333) (xy 402.92048 -316.628521)
			(xy 402.950701 -316.586925) (xy 402.987057 -316.550569) (xy 403.028653 -316.520348) (xy 403.074465 -316.497005)
			(xy 403.123364 -316.481117) (xy 403.174146 -316.473074) (xy 403.225562 -316.473074) (xy 403.276344 -316.481117)
			(xy 403.325243 -316.497005) (xy 403.371055 -316.520348) (xy 403.412651 -316.550569) (xy 403.449007 -316.586925)
			(xy 403.479228 -316.628521) (xy 403.502571 -316.674333) (xy 403.518459 -316.723232) (xy 403.526502 -316.774014)
			(xy 403.527006 -316.799722) (xy 403.84401 -316.799722) (xy 403.84797 -316.750668) (xy 403.859747 -316.702884)
			(xy 403.879038 -316.657608) (xy 403.905341 -316.616012) (xy 403.937976 -316.579175) (xy 403.976097 -316.54805)
			(xy 404.018718 -316.523443) (xy 404.064734 -316.505991) (xy 404.112953 -316.496147) (xy 404.162128 -316.494166)
			(xy 404.210983 -316.500098) (xy 404.258254 -316.51379) (xy 404.302716 -316.534888) (xy 404.343219 -316.562844)
			(xy 404.378712 -316.596936) (xy 404.408277 -316.63628) (xy 404.431148 -316.679857) (xy 404.446732 -316.726538)
			(xy 404.454627 -316.775115) (xy 404.455122 -316.799722) (xy 404.454627 -316.824329) (xy 404.454448 -316.82543)
			(xy 404.77338 -316.82543) (xy 404.77338 -316.774014) (xy 404.781423 -316.723232) (xy 404.797311 -316.674333)
			(xy 404.820654 -316.628521) (xy 404.850875 -316.586925) (xy 404.887231 -316.550569) (xy 404.928827 -316.520348)
			(xy 404.974639 -316.497005) (xy 405.023538 -316.481117) (xy 405.07432 -316.473074) (xy 405.125736 -316.473074)
			(xy 405.176518 -316.481117) (xy 405.225417 -316.497005) (xy 405.271229 -316.520348) (xy 405.312825 -316.550569)
			(xy 405.349181 -316.586925) (xy 405.379402 -316.628521) (xy 405.402745 -316.674333) (xy 405.418633 -316.723232)
			(xy 405.426676 -316.774014) (xy 405.42718 -316.799722) (xy 405.744184 -316.799722) (xy 405.748144 -316.750668)
			(xy 405.759921 -316.702884) (xy 405.779212 -316.657608) (xy 405.805515 -316.616012) (xy 405.83815 -316.579175)
			(xy 405.876271 -316.54805) (xy 405.918892 -316.523443) (xy 405.964908 -316.505991) (xy 406.013127 -316.496147)
			(xy 406.062302 -316.494166) (xy 406.111157 -316.500098) (xy 406.158428 -316.51379) (xy 406.20289 -316.534888)
			(xy 406.243393 -316.562844) (xy 406.278886 -316.596936) (xy 406.308451 -316.63628) (xy 406.331322 -316.679857)
			(xy 406.346906 -316.726538) (xy 406.354801 -316.775115) (xy 406.355296 -316.799722) (xy 406.354801 -316.824329)
			(xy 406.354622 -316.82543) (xy 406.6733 -316.82543) (xy 406.6733 -316.774014) (xy 406.681343 -316.723232)
			(xy 406.697231 -316.674333) (xy 406.720574 -316.628521) (xy 406.750795 -316.586925) (xy 406.787151 -316.550569)
			(xy 406.828747 -316.520348) (xy 406.874559 -316.497005) (xy 406.923458 -316.481117) (xy 406.97424 -316.473074)
			(xy 407.025656 -316.473074) (xy 407.076438 -316.481117) (xy 407.125337 -316.497005) (xy 407.171149 -316.520348)
			(xy 407.212745 -316.550569) (xy 407.249101 -316.586925) (xy 407.279322 -316.628521) (xy 407.302665 -316.674333)
			(xy 407.318553 -316.723232) (xy 407.326596 -316.774014) (xy 407.3271 -316.799722) (xy 407.644104 -316.799722)
			(xy 407.648064 -316.750668) (xy 407.659841 -316.702884) (xy 407.679132 -316.657608) (xy 407.705435 -316.616012)
			(xy 407.73807 -316.579175) (xy 407.776191 -316.54805) (xy 407.818812 -316.523443) (xy 407.864828 -316.505991)
			(xy 407.913047 -316.496147) (xy 407.962222 -316.494166) (xy 408.011077 -316.500098) (xy 408.058348 -316.51379)
			(xy 408.10281 -316.534888) (xy 408.143313 -316.562844) (xy 408.178806 -316.596936) (xy 408.208371 -316.63628)
			(xy 408.231242 -316.679857) (xy 408.246826 -316.726538) (xy 408.254721 -316.775115) (xy 408.255216 -316.799722)
			(xy 408.254721 -316.824329) (xy 408.254542 -316.82543) (xy 408.57322 -316.82543) (xy 408.57322 -316.774014)
			(xy 408.581263 -316.723232) (xy 408.597151 -316.674333) (xy 408.620494 -316.628521) (xy 408.650715 -316.586925)
			(xy 408.687071 -316.550569) (xy 408.728667 -316.520348) (xy 408.774479 -316.497005) (xy 408.823378 -316.481117)
			(xy 408.87416 -316.473074) (xy 408.925576 -316.473074) (xy 408.976358 -316.481117) (xy 409.025257 -316.497005)
			(xy 409.071069 -316.520348) (xy 409.112665 -316.550569) (xy 409.149021 -316.586925) (xy 409.179242 -316.628521)
			(xy 409.202585 -316.674333) (xy 409.218473 -316.723232) (xy 409.226516 -316.774014) (xy 409.22702 -316.799722)
			(xy 409.544024 -316.799722) (xy 409.547984 -316.750668) (xy 409.559761 -316.702884) (xy 409.579052 -316.657608)
			(xy 409.605355 -316.616012) (xy 409.63799 -316.579175) (xy 409.676111 -316.54805) (xy 409.718732 -316.523443)
			(xy 409.764748 -316.505991) (xy 409.812967 -316.496147) (xy 409.862142 -316.494166) (xy 409.910997 -316.500098)
			(xy 409.958268 -316.51379) (xy 410.00273 -316.534888) (xy 410.043233 -316.562844) (xy 410.078726 -316.596936)
			(xy 410.108291 -316.63628) (xy 410.131162 -316.679857) (xy 410.146746 -316.726538) (xy 410.154641 -316.775115)
			(xy 410.155136 -316.799722) (xy 410.154641 -316.824329) (xy 410.154462 -316.82543) (xy 410.47314 -316.82543)
			(xy 410.47314 -316.774014) (xy 410.481183 -316.723232) (xy 410.497071 -316.674333) (xy 410.520414 -316.628521)
			(xy 410.550635 -316.586925) (xy 410.586991 -316.550569) (xy 410.628587 -316.520348) (xy 410.674399 -316.497005)
			(xy 410.723298 -316.481117) (xy 410.77408 -316.473074) (xy 410.825496 -316.473074) (xy 410.876278 -316.481117)
			(xy 410.925177 -316.497005) (xy 410.970989 -316.520348) (xy 411.012585 -316.550569) (xy 411.048941 -316.586925)
			(xy 411.079162 -316.628521) (xy 411.102505 -316.674333) (xy 411.118393 -316.723232) (xy 411.126436 -316.774014)
			(xy 411.12694 -316.799722) (xy 411.444198 -316.799722) (xy 411.448158 -316.750668) (xy 411.459935 -316.702884)
			(xy 411.479226 -316.657608) (xy 411.505529 -316.616012) (xy 411.538164 -316.579175) (xy 411.576285 -316.54805)
			(xy 411.618906 -316.523443) (xy 411.664922 -316.505991) (xy 411.713141 -316.496147) (xy 411.762316 -316.494166)
			(xy 411.811171 -316.500098) (xy 411.858442 -316.51379) (xy 411.902904 -316.534888) (xy 411.943407 -316.562844)
			(xy 411.9789 -316.596936) (xy 412.008465 -316.63628) (xy 412.031336 -316.679857) (xy 412.04692 -316.726538)
			(xy 412.054815 -316.775115) (xy 412.05531 -316.799722) (xy 412.054815 -316.824329) (xy 412.054636 -316.82543)
			(xy 412.373314 -316.82543) (xy 412.373314 -316.774014) (xy 412.381357 -316.723232) (xy 412.397245 -316.674333)
			(xy 412.420588 -316.628521) (xy 412.450809 -316.586925) (xy 412.487165 -316.550569) (xy 412.528761 -316.520348)
			(xy 412.574573 -316.497005) (xy 412.623472 -316.481117) (xy 412.674254 -316.473074) (xy 412.72567 -316.473074)
			(xy 412.776452 -316.481117) (xy 412.825351 -316.497005) (xy 412.871163 -316.520348) (xy 412.912759 -316.550569)
			(xy 412.949115 -316.586925) (xy 412.979336 -316.628521) (xy 413.002679 -316.674333) (xy 413.018567 -316.723232)
			(xy 413.02661 -316.774014) (xy 413.027114 -316.799722) (xy 413.344118 -316.799722) (xy 413.348078 -316.750668)
			(xy 413.359855 -316.702884) (xy 413.379146 -316.657608) (xy 413.405449 -316.616012) (xy 413.438084 -316.579175)
			(xy 413.476205 -316.54805) (xy 413.518826 -316.523443) (xy 413.564842 -316.505991) (xy 413.613061 -316.496147)
			(xy 413.662236 -316.494166) (xy 413.711091 -316.500098) (xy 413.758362 -316.51379) (xy 413.802824 -316.534888)
			(xy 413.843327 -316.562844) (xy 413.87882 -316.596936) (xy 413.908385 -316.63628) (xy 413.931256 -316.679857)
			(xy 413.94684 -316.726538) (xy 413.954735 -316.775115) (xy 413.95523 -316.799722) (xy 414.294078 -316.799722)
			(xy 414.298038 -316.750668) (xy 414.309815 -316.702884) (xy 414.329106 -316.657608) (xy 414.355409 -316.616012)
			(xy 414.388044 -316.579175) (xy 414.426165 -316.54805) (xy 414.468786 -316.523443) (xy 414.514802 -316.505991)
			(xy 414.563021 -316.496147) (xy 414.612196 -316.494166) (xy 414.661051 -316.500098) (xy 414.708322 -316.51379)
			(xy 414.752784 -316.534888) (xy 414.793287 -316.562844) (xy 414.82878 -316.596936) (xy 414.858345 -316.63628)
			(xy 414.881216 -316.679857) (xy 414.8968 -316.726538) (xy 414.904695 -316.775115) (xy 414.90519 -316.799722)
			(xy 415.244038 -316.799722) (xy 415.247998 -316.750668) (xy 415.259775 -316.702884) (xy 415.279066 -316.657608)
			(xy 415.305369 -316.616012) (xy 415.338004 -316.579175) (xy 415.376125 -316.54805) (xy 415.418746 -316.523443)
			(xy 415.464762 -316.505991) (xy 415.512981 -316.496147) (xy 415.562156 -316.494166) (xy 415.611011 -316.500098)
			(xy 415.658282 -316.51379) (xy 415.702744 -316.534888) (xy 415.743247 -316.562844) (xy 415.77874 -316.596936)
			(xy 415.808305 -316.63628) (xy 415.831176 -316.679857) (xy 415.84676 -316.726538) (xy 415.854655 -316.775115)
			(xy 415.85515 -316.799722) (xy 416.193998 -316.799722) (xy 416.197958 -316.750668) (xy 416.209735 -316.702884)
			(xy 416.229026 -316.657608) (xy 416.255329 -316.616012) (xy 416.287964 -316.579175) (xy 416.326085 -316.54805)
			(xy 416.368706 -316.523443) (xy 416.414722 -316.505991) (xy 416.462941 -316.496147) (xy 416.512116 -316.494166)
			(xy 416.560971 -316.500098) (xy 416.608242 -316.51379) (xy 416.652704 -316.534888) (xy 416.693207 -316.562844)
			(xy 416.7287 -316.596936) (xy 416.758265 -316.63628) (xy 416.781136 -316.679857) (xy 416.79672 -316.726538)
			(xy 416.804615 -316.775115) (xy 416.80511 -316.799722) (xy 417.144212 -316.799722) (xy 417.148172 -316.750668)
			(xy 417.159949 -316.702884) (xy 417.17924 -316.657608) (xy 417.205543 -316.616012) (xy 417.238178 -316.579175)
			(xy 417.276299 -316.54805) (xy 417.31892 -316.523443) (xy 417.364936 -316.505991) (xy 417.413155 -316.496147)
			(xy 417.46233 -316.494166) (xy 417.511185 -316.500098) (xy 417.558456 -316.51379) (xy 417.602918 -316.534888)
			(xy 417.643421 -316.562844) (xy 417.678914 -316.596936) (xy 417.708479 -316.63628) (xy 417.73135 -316.679857)
			(xy 417.746934 -316.726538) (xy 417.754829 -316.775115) (xy 417.755324 -316.799722) (xy 418.094172 -316.799722)
			(xy 418.098132 -316.750668) (xy 418.109909 -316.702884) (xy 418.1292 -316.657608) (xy 418.155503 -316.616012)
			(xy 418.188138 -316.579175) (xy 418.226259 -316.54805) (xy 418.26888 -316.523443) (xy 418.314896 -316.505991)
			(xy 418.363115 -316.496147) (xy 418.41229 -316.494166) (xy 418.461145 -316.500098) (xy 418.508416 -316.51379)
			(xy 418.552878 -316.534888) (xy 418.593381 -316.562844) (xy 418.628874 -316.596936) (xy 418.658439 -316.63628)
			(xy 418.68131 -316.679857) (xy 418.696894 -316.726538) (xy 418.704789 -316.775115) (xy 418.705284 -316.799722)
			(xy 419.044132 -316.799722) (xy 419.048092 -316.750668) (xy 419.059869 -316.702884) (xy 419.07916 -316.657608)
			(xy 419.105463 -316.616012) (xy 419.138098 -316.579175) (xy 419.176219 -316.54805) (xy 419.21884 -316.523443)
			(xy 419.264856 -316.505991) (xy 419.313075 -316.496147) (xy 419.36225 -316.494166) (xy 419.411105 -316.500098)
			(xy 419.458376 -316.51379) (xy 419.502838 -316.534888) (xy 419.543341 -316.562844) (xy 419.578834 -316.596936)
			(xy 419.608399 -316.63628) (xy 419.63127 -316.679857) (xy 419.646854 -316.726538) (xy 419.654749 -316.775115)
			(xy 419.655244 -316.799722) (xy 419.994092 -316.799722) (xy 419.998052 -316.750668) (xy 420.009829 -316.702884)
			(xy 420.02912 -316.657608) (xy 420.055423 -316.616012) (xy 420.088058 -316.579175) (xy 420.126179 -316.54805)
			(xy 420.1688 -316.523443) (xy 420.214816 -316.505991) (xy 420.263035 -316.496147) (xy 420.31221 -316.494166)
			(xy 420.361065 -316.500098) (xy 420.408336 -316.51379) (xy 420.452798 -316.534888) (xy 420.493301 -316.562844)
			(xy 420.528794 -316.596936) (xy 420.558359 -316.63628) (xy 420.58123 -316.679857) (xy 420.596814 -316.726538)
			(xy 420.604709 -316.775115) (xy 420.605204 -316.799722) (xy 420.944052 -316.799722) (xy 420.948012 -316.750668)
			(xy 420.959789 -316.702884) (xy 420.97908 -316.657608) (xy 421.005383 -316.616012) (xy 421.038018 -316.579175)
			(xy 421.076139 -316.54805) (xy 421.11876 -316.523443) (xy 421.164776 -316.505991) (xy 421.212995 -316.496147)
			(xy 421.26217 -316.494166) (xy 421.311025 -316.500098) (xy 421.358296 -316.51379) (xy 421.402758 -316.534888)
			(xy 421.443261 -316.562844) (xy 421.478754 -316.596936) (xy 421.508319 -316.63628) (xy 421.53119 -316.679857)
			(xy 421.546774 -316.726538) (xy 421.554669 -316.775115) (xy 421.555164 -316.799722) (xy 421.554669 -316.824329)
			(xy 421.55449 -316.82543) (xy 421.873168 -316.82543) (xy 421.873168 -316.774014) (xy 421.881211 -316.723232)
			(xy 421.897099 -316.674333) (xy 421.920442 -316.628521) (xy 421.950663 -316.586925) (xy 421.987019 -316.550569)
			(xy 422.028615 -316.520348) (xy 422.074427 -316.497005) (xy 422.123326 -316.481117) (xy 422.174108 -316.473074)
			(xy 422.225524 -316.473074) (xy 422.276306 -316.481117) (xy 422.325205 -316.497005) (xy 422.371017 -316.520348)
			(xy 422.412613 -316.550569) (xy 422.448969 -316.586925) (xy 422.47919 -316.628521) (xy 422.502533 -316.674333)
			(xy 422.518421 -316.723232) (xy 422.526464 -316.774014) (xy 422.526968 -316.799722) (xy 422.844226 -316.799722)
			(xy 422.848186 -316.750668) (xy 422.859963 -316.702884) (xy 422.879254 -316.657608) (xy 422.905557 -316.616012)
			(xy 422.938192 -316.579175) (xy 422.976313 -316.54805) (xy 423.018934 -316.523443) (xy 423.06495 -316.505991)
			(xy 423.113169 -316.496147) (xy 423.162344 -316.494166) (xy 423.211199 -316.500098) (xy 423.25847 -316.51379)
			(xy 423.302932 -316.534888) (xy 423.343435 -316.562844) (xy 423.378928 -316.596936) (xy 423.408493 -316.63628)
			(xy 423.431364 -316.679857) (xy 423.446948 -316.726538) (xy 423.454843 -316.775115) (xy 423.455338 -316.799722)
			(xy 423.454843 -316.824329) (xy 423.454664 -316.82543) (xy 423.773342 -316.82543) (xy 423.773342 -316.774014)
			(xy 423.781385 -316.723232) (xy 423.797273 -316.674333) (xy 423.820616 -316.628521) (xy 423.850837 -316.586925)
			(xy 423.887193 -316.550569) (xy 423.928789 -316.520348) (xy 423.974601 -316.497005) (xy 424.0235 -316.481117)
			(xy 424.074282 -316.473074) (xy 424.125698 -316.473074) (xy 424.17648 -316.481117) (xy 424.225379 -316.497005)
			(xy 424.271191 -316.520348) (xy 424.312787 -316.550569) (xy 424.349143 -316.586925) (xy 424.379364 -316.628521)
			(xy 424.402707 -316.674333) (xy 424.418595 -316.723232) (xy 424.426638 -316.774014) (xy 424.427142 -316.799722)
			(xy 424.744146 -316.799722) (xy 424.748106 -316.750668) (xy 424.759883 -316.702884) (xy 424.779174 -316.657608)
			(xy 424.805477 -316.616012) (xy 424.838112 -316.579175) (xy 424.876233 -316.54805) (xy 424.918854 -316.523443)
			(xy 424.96487 -316.505991) (xy 425.013089 -316.496147) (xy 425.062264 -316.494166) (xy 425.111119 -316.500098)
			(xy 425.15839 -316.51379) (xy 425.202852 -316.534888) (xy 425.243355 -316.562844) (xy 425.278848 -316.596936)
			(xy 425.308413 -316.63628) (xy 425.331284 -316.679857) (xy 425.346868 -316.726538) (xy 425.354763 -316.775115)
			(xy 425.355258 -316.799722) (xy 425.354763 -316.824329) (xy 425.354584 -316.82543) (xy 425.673262 -316.82543)
			(xy 425.673262 -316.774014) (xy 425.681305 -316.723232) (xy 425.697193 -316.674333) (xy 425.720536 -316.628521)
			(xy 425.750757 -316.586925) (xy 425.787113 -316.550569) (xy 425.828709 -316.520348) (xy 425.874521 -316.497005)
			(xy 425.92342 -316.481117) (xy 425.974202 -316.473074) (xy 426.025618 -316.473074) (xy 426.0764 -316.481117)
			(xy 426.125299 -316.497005) (xy 426.171111 -316.520348) (xy 426.212707 -316.550569) (xy 426.249063 -316.586925)
			(xy 426.279284 -316.628521) (xy 426.302627 -316.674333) (xy 426.318515 -316.723232) (xy 426.326558 -316.774014)
			(xy 426.327062 -316.799722) (xy 426.644066 -316.799722) (xy 426.648026 -316.750668) (xy 426.659803 -316.702884)
			(xy 426.679094 -316.657608) (xy 426.705397 -316.616012) (xy 426.738032 -316.579175) (xy 426.776153 -316.54805)
			(xy 426.818774 -316.523443) (xy 426.86479 -316.505991) (xy 426.913009 -316.496147) (xy 426.962184 -316.494166)
			(xy 427.011039 -316.500098) (xy 427.05831 -316.51379) (xy 427.102772 -316.534888) (xy 427.143275 -316.562844)
			(xy 427.178768 -316.596936) (xy 427.208333 -316.63628) (xy 427.231204 -316.679857) (xy 427.246788 -316.726538)
			(xy 427.254683 -316.775115) (xy 427.255178 -316.799722) (xy 427.254683 -316.824329) (xy 427.254504 -316.82543)
			(xy 427.573182 -316.82543) (xy 427.573182 -316.774014) (xy 427.581225 -316.723232) (xy 427.597113 -316.674333)
			(xy 427.620456 -316.628521) (xy 427.650677 -316.586925) (xy 427.687033 -316.550569) (xy 427.728629 -316.520348)
			(xy 427.774441 -316.497005) (xy 427.82334 -316.481117) (xy 427.874122 -316.473074) (xy 427.925538 -316.473074)
			(xy 427.97632 -316.481117) (xy 428.025219 -316.497005) (xy 428.071031 -316.520348) (xy 428.112627 -316.550569)
			(xy 428.148983 -316.586925) (xy 428.179204 -316.628521) (xy 428.202547 -316.674333) (xy 428.218435 -316.723232)
			(xy 428.226478 -316.774014) (xy 428.226982 -316.799722) (xy 428.543986 -316.799722) (xy 428.547946 -316.750668)
			(xy 428.559723 -316.702884) (xy 428.579014 -316.657608) (xy 428.605317 -316.616012) (xy 428.637952 -316.579175)
			(xy 428.676073 -316.54805) (xy 428.718694 -316.523443) (xy 428.76471 -316.505991) (xy 428.812929 -316.496147)
			(xy 428.862104 -316.494166) (xy 428.910959 -316.500098) (xy 428.95823 -316.51379) (xy 429.002692 -316.534888)
			(xy 429.043195 -316.562844) (xy 429.078688 -316.596936) (xy 429.108253 -316.63628) (xy 429.131124 -316.679857)
			(xy 429.146708 -316.726538) (xy 429.154603 -316.775115) (xy 429.155098 -316.799722) (xy 429.154603 -316.824329)
			(xy 429.154424 -316.82543) (xy 429.473356 -316.82543) (xy 429.473356 -316.774014) (xy 429.481399 -316.723232)
			(xy 429.497287 -316.674333) (xy 429.52063 -316.628521) (xy 429.550851 -316.586925) (xy 429.587207 -316.550569)
			(xy 429.628803 -316.520348) (xy 429.674615 -316.497005) (xy 429.723514 -316.481117) (xy 429.774296 -316.473074)
			(xy 429.825712 -316.473074) (xy 429.876494 -316.481117) (xy 429.925393 -316.497005) (xy 429.971205 -316.520348)
			(xy 430.012801 -316.550569) (xy 430.049157 -316.586925) (xy 430.079378 -316.628521) (xy 430.102721 -316.674333)
			(xy 430.118609 -316.723232) (xy 430.126652 -316.774014) (xy 430.127156 -316.799722) (xy 430.126652 -316.82543)
			(xy 430.423316 -316.82543) (xy 430.423316 -316.774014) (xy 430.431359 -316.723232) (xy 430.447247 -316.674333)
			(xy 430.47059 -316.628521) (xy 430.500811 -316.586925) (xy 430.537167 -316.550569) (xy 430.578763 -316.520348)
			(xy 430.624575 -316.497005) (xy 430.673474 -316.481117) (xy 430.724256 -316.473074) (xy 430.775672 -316.473074)
			(xy 430.826454 -316.481117) (xy 430.875353 -316.497005) (xy 430.921165 -316.520348) (xy 430.962761 -316.550569)
			(xy 430.999117 -316.586925) (xy 431.029338 -316.628521) (xy 431.052681 -316.674333) (xy 431.068569 -316.723232)
			(xy 431.076612 -316.774014) (xy 431.077116 -316.799722) (xy 431.394374 -316.799722) (xy 431.398334 -316.750668)
			(xy 431.410111 -316.702884) (xy 431.429402 -316.657608) (xy 431.455705 -316.616012) (xy 431.48834 -316.579175)
			(xy 431.526461 -316.54805) (xy 431.569082 -316.523443) (xy 431.615098 -316.505991) (xy 431.663317 -316.496147)
			(xy 431.712492 -316.494166) (xy 431.761347 -316.500098) (xy 431.808618 -316.51379) (xy 431.85308 -316.534888)
			(xy 431.893583 -316.562844) (xy 431.929076 -316.596936) (xy 431.958641 -316.63628) (xy 431.981512 -316.679857)
			(xy 431.997096 -316.726538) (xy 432.004991 -316.775115) (xy 432.005486 -316.799722) (xy 432.004991 -316.824329)
			(xy 431.997096 -316.872906) (xy 431.981512 -316.919587) (xy 431.958641 -316.963164) (xy 431.929076 -317.002508)
			(xy 431.893583 -317.0366) (xy 431.85308 -317.064556) (xy 431.808618 -317.085654) (xy 431.761347 -317.099346)
			(xy 431.712492 -317.105278) (xy 431.663317 -317.103297) (xy 431.615098 -317.093453) (xy 431.569082 -317.076001)
			(xy 431.526461 -317.051394) (xy 431.48834 -317.020269) (xy 431.455705 -316.983432) (xy 431.429402 -316.941836)
			(xy 431.410111 -316.89656) (xy 431.398334 -316.848776) (xy 431.394374 -316.799722) (xy 431.077116 -316.799722)
			(xy 431.076612 -316.82543) (xy 431.068569 -316.876212) (xy 431.052681 -316.925111) (xy 431.029338 -316.970923)
			(xy 430.999117 -317.012519) (xy 430.962761 -317.048875) (xy 430.921165 -317.079096) (xy 430.875353 -317.102439)
			(xy 430.826454 -317.118327) (xy 430.775672 -317.12637) (xy 430.724256 -317.12637) (xy 430.673474 -317.118327)
			(xy 430.624575 -317.102439) (xy 430.578763 -317.079096) (xy 430.537167 -317.048875) (xy 430.500811 -317.012519)
			(xy 430.47059 -316.970923) (xy 430.447247 -316.925111) (xy 430.431359 -316.876212) (xy 430.423316 -316.82543)
			(xy 430.126652 -316.82543) (xy 430.118609 -316.876212) (xy 430.102721 -316.925111) (xy 430.079378 -316.970923)
			(xy 430.049157 -317.012519) (xy 430.012801 -317.048875) (xy 429.971205 -317.079096) (xy 429.925393 -317.102439)
			(xy 429.876494 -317.118327) (xy 429.825712 -317.12637) (xy 429.774296 -317.12637) (xy 429.723514 -317.118327)
			(xy 429.674615 -317.102439) (xy 429.628803 -317.079096) (xy 429.587207 -317.048875) (xy 429.550851 -317.012519)
			(xy 429.52063 -316.970923) (xy 429.497287 -316.925111) (xy 429.481399 -316.876212) (xy 429.473356 -316.82543)
			(xy 429.154424 -316.82543) (xy 429.146708 -316.872906) (xy 429.131124 -316.919587) (xy 429.108253 -316.963164)
			(xy 429.078688 -317.002508) (xy 429.043195 -317.0366) (xy 429.002692 -317.064556) (xy 428.95823 -317.085654)
			(xy 428.910959 -317.099346) (xy 428.862104 -317.105278) (xy 428.812929 -317.103297) (xy 428.76471 -317.093453)
			(xy 428.718694 -317.076001) (xy 428.676073 -317.051394) (xy 428.637952 -317.020269) (xy 428.605317 -316.983432)
			(xy 428.579014 -316.941836) (xy 428.559723 -316.89656) (xy 428.547946 -316.848776) (xy 428.543986 -316.799722)
			(xy 428.226982 -316.799722) (xy 428.226478 -316.82543) (xy 428.218435 -316.876212) (xy 428.202547 -316.925111)
			(xy 428.179204 -316.970923) (xy 428.148983 -317.012519) (xy 428.112627 -317.048875) (xy 428.071031 -317.079096)
			(xy 428.025219 -317.102439) (xy 427.97632 -317.118327) (xy 427.925538 -317.12637) (xy 427.874122 -317.12637)
			(xy 427.82334 -317.118327) (xy 427.774441 -317.102439) (xy 427.728629 -317.079096) (xy 427.687033 -317.048875)
			(xy 427.650677 -317.012519) (xy 427.620456 -316.970923) (xy 427.597113 -316.925111) (xy 427.581225 -316.876212)
			(xy 427.573182 -316.82543) (xy 427.254504 -316.82543) (xy 427.246788 -316.872906) (xy 427.231204 -316.919587)
			(xy 427.208333 -316.963164) (xy 427.178768 -317.002508) (xy 427.143275 -317.0366) (xy 427.102772 -317.064556)
			(xy 427.05831 -317.085654) (xy 427.011039 -317.099346) (xy 426.962184 -317.105278) (xy 426.913009 -317.103297)
			(xy 426.86479 -317.093453) (xy 426.818774 -317.076001) (xy 426.776153 -317.051394) (xy 426.738032 -317.020269)
			(xy 426.705397 -316.983432) (xy 426.679094 -316.941836) (xy 426.659803 -316.89656) (xy 426.648026 -316.848776)
			(xy 426.644066 -316.799722) (xy 426.327062 -316.799722) (xy 426.326558 -316.82543) (xy 426.318515 -316.876212)
			(xy 426.302627 -316.925111) (xy 426.279284 -316.970923) (xy 426.249063 -317.012519) (xy 426.212707 -317.048875)
			(xy 426.171111 -317.079096) (xy 426.125299 -317.102439) (xy 426.0764 -317.118327) (xy 426.025618 -317.12637)
			(xy 425.974202 -317.12637) (xy 425.92342 -317.118327) (xy 425.874521 -317.102439) (xy 425.828709 -317.079096)
			(xy 425.787113 -317.048875) (xy 425.750757 -317.012519) (xy 425.720536 -316.970923) (xy 425.697193 -316.925111)
			(xy 425.681305 -316.876212) (xy 425.673262 -316.82543) (xy 425.354584 -316.82543) (xy 425.346868 -316.872906)
			(xy 425.331284 -316.919587) (xy 425.308413 -316.963164) (xy 425.278848 -317.002508) (xy 425.243355 -317.0366)
			(xy 425.202852 -317.064556) (xy 425.15839 -317.085654) (xy 425.111119 -317.099346) (xy 425.062264 -317.105278)
			(xy 425.013089 -317.103297) (xy 424.96487 -317.093453) (xy 424.918854 -317.076001) (xy 424.876233 -317.051394)
			(xy 424.838112 -317.020269) (xy 424.805477 -316.983432) (xy 424.779174 -316.941836) (xy 424.759883 -316.89656)
			(xy 424.748106 -316.848776) (xy 424.744146 -316.799722) (xy 424.427142 -316.799722) (xy 424.426638 -316.82543)
			(xy 424.418595 -316.876212) (xy 424.402707 -316.925111) (xy 424.379364 -316.970923) (xy 424.349143 -317.012519)
			(xy 424.312787 -317.048875) (xy 424.271191 -317.079096) (xy 424.225379 -317.102439) (xy 424.17648 -317.118327)
			(xy 424.125698 -317.12637) (xy 424.074282 -317.12637) (xy 424.0235 -317.118327) (xy 423.974601 -317.102439)
			(xy 423.928789 -317.079096) (xy 423.887193 -317.048875) (xy 423.850837 -317.012519) (xy 423.820616 -316.970923)
			(xy 423.797273 -316.925111) (xy 423.781385 -316.876212) (xy 423.773342 -316.82543) (xy 423.454664 -316.82543)
			(xy 423.446948 -316.872906) (xy 423.431364 -316.919587) (xy 423.408493 -316.963164) (xy 423.378928 -317.002508)
			(xy 423.343435 -317.0366) (xy 423.302932 -317.064556) (xy 423.25847 -317.085654) (xy 423.211199 -317.099346)
			(xy 423.162344 -317.105278) (xy 423.113169 -317.103297) (xy 423.06495 -317.093453) (xy 423.018934 -317.076001)
			(xy 422.976313 -317.051394) (xy 422.938192 -317.020269) (xy 422.905557 -316.983432) (xy 422.879254 -316.941836)
			(xy 422.859963 -316.89656) (xy 422.848186 -316.848776) (xy 422.844226 -316.799722) (xy 422.526968 -316.799722)
			(xy 422.526464 -316.82543) (xy 422.518421 -316.876212) (xy 422.502533 -316.925111) (xy 422.47919 -316.970923)
			(xy 422.448969 -317.012519) (xy 422.412613 -317.048875) (xy 422.371017 -317.079096) (xy 422.325205 -317.102439)
			(xy 422.276306 -317.118327) (xy 422.225524 -317.12637) (xy 422.174108 -317.12637) (xy 422.123326 -317.118327)
			(xy 422.074427 -317.102439) (xy 422.028615 -317.079096) (xy 421.987019 -317.048875) (xy 421.950663 -317.012519)
			(xy 421.920442 -316.970923) (xy 421.897099 -316.925111) (xy 421.881211 -316.876212) (xy 421.873168 -316.82543)
			(xy 421.55449 -316.82543) (xy 421.546774 -316.872906) (xy 421.53119 -316.919587) (xy 421.508319 -316.963164)
			(xy 421.478754 -317.002508) (xy 421.443261 -317.0366) (xy 421.402758 -317.064556) (xy 421.358296 -317.085654)
			(xy 421.311025 -317.099346) (xy 421.26217 -317.105278) (xy 421.212995 -317.103297) (xy 421.164776 -317.093453)
			(xy 421.11876 -317.076001) (xy 421.076139 -317.051394) (xy 421.038018 -317.020269) (xy 421.005383 -316.983432)
			(xy 420.97908 -316.941836) (xy 420.959789 -316.89656) (xy 420.948012 -316.848776) (xy 420.944052 -316.799722)
			(xy 420.605204 -316.799722) (xy 420.604709 -316.824329) (xy 420.596814 -316.872906) (xy 420.58123 -316.919587)
			(xy 420.558359 -316.963164) (xy 420.528794 -317.002508) (xy 420.493301 -317.0366) (xy 420.452798 -317.064556)
			(xy 420.408336 -317.085654) (xy 420.361065 -317.099346) (xy 420.31221 -317.105278) (xy 420.263035 -317.103297)
			(xy 420.214816 -317.093453) (xy 420.1688 -317.076001) (xy 420.126179 -317.051394) (xy 420.088058 -317.020269)
			(xy 420.055423 -316.983432) (xy 420.02912 -316.941836) (xy 420.009829 -316.89656) (xy 419.998052 -316.848776)
			(xy 419.994092 -316.799722) (xy 419.655244 -316.799722) (xy 419.654749 -316.824329) (xy 419.646854 -316.872906)
			(xy 419.63127 -316.919587) (xy 419.608399 -316.963164) (xy 419.578834 -317.002508) (xy 419.543341 -317.0366)
			(xy 419.502838 -317.064556) (xy 419.458376 -317.085654) (xy 419.411105 -317.099346) (xy 419.36225 -317.105278)
			(xy 419.313075 -317.103297) (xy 419.264856 -317.093453) (xy 419.21884 -317.076001) (xy 419.176219 -317.051394)
			(xy 419.138098 -317.020269) (xy 419.105463 -316.983432) (xy 419.07916 -316.941836) (xy 419.059869 -316.89656)
			(xy 419.048092 -316.848776) (xy 419.044132 -316.799722) (xy 418.705284 -316.799722) (xy 418.704789 -316.824329)
			(xy 418.696894 -316.872906) (xy 418.68131 -316.919587) (xy 418.658439 -316.963164) (xy 418.628874 -317.002508)
			(xy 418.593381 -317.0366) (xy 418.552878 -317.064556) (xy 418.508416 -317.085654) (xy 418.461145 -317.099346)
			(xy 418.41229 -317.105278) (xy 418.363115 -317.103297) (xy 418.314896 -317.093453) (xy 418.26888 -317.076001)
			(xy 418.226259 -317.051394) (xy 418.188138 -317.020269) (xy 418.155503 -316.983432) (xy 418.1292 -316.941836)
			(xy 418.109909 -316.89656) (xy 418.098132 -316.848776) (xy 418.094172 -316.799722) (xy 417.755324 -316.799722)
			(xy 417.754829 -316.824329) (xy 417.746934 -316.872906) (xy 417.73135 -316.919587) (xy 417.708479 -316.963164)
			(xy 417.678914 -317.002508) (xy 417.643421 -317.0366) (xy 417.602918 -317.064556) (xy 417.558456 -317.085654)
			(xy 417.511185 -317.099346) (xy 417.46233 -317.105278) (xy 417.413155 -317.103297) (xy 417.364936 -317.093453)
			(xy 417.31892 -317.076001) (xy 417.276299 -317.051394) (xy 417.238178 -317.020269) (xy 417.205543 -316.983432)
			(xy 417.17924 -316.941836) (xy 417.159949 -316.89656) (xy 417.148172 -316.848776) (xy 417.144212 -316.799722)
			(xy 416.80511 -316.799722) (xy 416.804615 -316.824329) (xy 416.79672 -316.872906) (xy 416.781136 -316.919587)
			(xy 416.758265 -316.963164) (xy 416.7287 -317.002508) (xy 416.693207 -317.0366) (xy 416.652704 -317.064556)
			(xy 416.608242 -317.085654) (xy 416.560971 -317.099346) (xy 416.512116 -317.105278) (xy 416.462941 -317.103297)
			(xy 416.414722 -317.093453) (xy 416.368706 -317.076001) (xy 416.326085 -317.051394) (xy 416.287964 -317.020269)
			(xy 416.255329 -316.983432) (xy 416.229026 -316.941836) (xy 416.209735 -316.89656) (xy 416.197958 -316.848776)
			(xy 416.193998 -316.799722) (xy 415.85515 -316.799722) (xy 415.854655 -316.824329) (xy 415.84676 -316.872906)
			(xy 415.831176 -316.919587) (xy 415.808305 -316.963164) (xy 415.77874 -317.002508) (xy 415.743247 -317.0366)
			(xy 415.702744 -317.064556) (xy 415.658282 -317.085654) (xy 415.611011 -317.099346) (xy 415.562156 -317.105278)
			(xy 415.512981 -317.103297) (xy 415.464762 -317.093453) (xy 415.418746 -317.076001) (xy 415.376125 -317.051394)
			(xy 415.338004 -317.020269) (xy 415.305369 -316.983432) (xy 415.279066 -316.941836) (xy 415.259775 -316.89656)
			(xy 415.247998 -316.848776) (xy 415.244038 -316.799722) (xy 414.90519 -316.799722) (xy 414.904695 -316.824329)
			(xy 414.8968 -316.872906) (xy 414.881216 -316.919587) (xy 414.858345 -316.963164) (xy 414.82878 -317.002508)
			(xy 414.793287 -317.0366) (xy 414.752784 -317.064556) (xy 414.708322 -317.085654) (xy 414.661051 -317.099346)
			(xy 414.612196 -317.105278) (xy 414.563021 -317.103297) (xy 414.514802 -317.093453) (xy 414.468786 -317.076001)
			(xy 414.426165 -317.051394) (xy 414.388044 -317.020269) (xy 414.355409 -316.983432) (xy 414.329106 -316.941836)
			(xy 414.309815 -316.89656) (xy 414.298038 -316.848776) (xy 414.294078 -316.799722) (xy 413.95523 -316.799722)
			(xy 413.954735 -316.824329) (xy 413.94684 -316.872906) (xy 413.931256 -316.919587) (xy 413.908385 -316.963164)
			(xy 413.87882 -317.002508) (xy 413.843327 -317.0366) (xy 413.802824 -317.064556) (xy 413.758362 -317.085654)
			(xy 413.711091 -317.099346) (xy 413.662236 -317.105278) (xy 413.613061 -317.103297) (xy 413.564842 -317.093453)
			(xy 413.518826 -317.076001) (xy 413.476205 -317.051394) (xy 413.438084 -317.020269) (xy 413.405449 -316.983432)
			(xy 413.379146 -316.941836) (xy 413.359855 -316.89656) (xy 413.348078 -316.848776) (xy 413.344118 -316.799722)
			(xy 413.027114 -316.799722) (xy 413.02661 -316.82543) (xy 413.018567 -316.876212) (xy 413.002679 -316.925111)
			(xy 412.979336 -316.970923) (xy 412.949115 -317.012519) (xy 412.912759 -317.048875) (xy 412.871163 -317.079096)
			(xy 412.825351 -317.102439) (xy 412.776452 -317.118327) (xy 412.72567 -317.12637) (xy 412.674254 -317.12637)
			(xy 412.623472 -317.118327) (xy 412.574573 -317.102439) (xy 412.528761 -317.079096) (xy 412.487165 -317.048875)
			(xy 412.450809 -317.012519) (xy 412.420588 -316.970923) (xy 412.397245 -316.925111) (xy 412.381357 -316.876212)
			(xy 412.373314 -316.82543) (xy 412.054636 -316.82543) (xy 412.04692 -316.872906) (xy 412.031336 -316.919587)
			(xy 412.008465 -316.963164) (xy 411.9789 -317.002508) (xy 411.943407 -317.0366) (xy 411.902904 -317.064556)
			(xy 411.858442 -317.085654) (xy 411.811171 -317.099346) (xy 411.762316 -317.105278) (xy 411.713141 -317.103297)
			(xy 411.664922 -317.093453) (xy 411.618906 -317.076001) (xy 411.576285 -317.051394) (xy 411.538164 -317.020269)
			(xy 411.505529 -316.983432) (xy 411.479226 -316.941836) (xy 411.459935 -316.89656) (xy 411.448158 -316.848776)
			(xy 411.444198 -316.799722) (xy 411.12694 -316.799722) (xy 411.126436 -316.82543) (xy 411.118393 -316.876212)
			(xy 411.102505 -316.925111) (xy 411.079162 -316.970923) (xy 411.048941 -317.012519) (xy 411.012585 -317.048875)
			(xy 410.970989 -317.079096) (xy 410.925177 -317.102439) (xy 410.876278 -317.118327) (xy 410.825496 -317.12637)
			(xy 410.77408 -317.12637) (xy 410.723298 -317.118327) (xy 410.674399 -317.102439) (xy 410.628587 -317.079096)
			(xy 410.586991 -317.048875) (xy 410.550635 -317.012519) (xy 410.520414 -316.970923) (xy 410.497071 -316.925111)
			(xy 410.481183 -316.876212) (xy 410.47314 -316.82543) (xy 410.154462 -316.82543) (xy 410.146746 -316.872906)
			(xy 410.131162 -316.919587) (xy 410.108291 -316.963164) (xy 410.078726 -317.002508) (xy 410.043233 -317.0366)
			(xy 410.00273 -317.064556) (xy 409.958268 -317.085654) (xy 409.910997 -317.099346) (xy 409.862142 -317.105278)
			(xy 409.812967 -317.103297) (xy 409.764748 -317.093453) (xy 409.718732 -317.076001) (xy 409.676111 -317.051394)
			(xy 409.63799 -317.020269) (xy 409.605355 -316.983432) (xy 409.579052 -316.941836) (xy 409.559761 -316.89656)
			(xy 409.547984 -316.848776) (xy 409.544024 -316.799722) (xy 409.22702 -316.799722) (xy 409.226516 -316.82543)
			(xy 409.218473 -316.876212) (xy 409.202585 -316.925111) (xy 409.179242 -316.970923) (xy 409.149021 -317.012519)
			(xy 409.112665 -317.048875) (xy 409.071069 -317.079096) (xy 409.025257 -317.102439) (xy 408.976358 -317.118327)
			(xy 408.925576 -317.12637) (xy 408.87416 -317.12637) (xy 408.823378 -317.118327) (xy 408.774479 -317.102439)
			(xy 408.728667 -317.079096) (xy 408.687071 -317.048875) (xy 408.650715 -317.012519) (xy 408.620494 -316.970923)
			(xy 408.597151 -316.925111) (xy 408.581263 -316.876212) (xy 408.57322 -316.82543) (xy 408.254542 -316.82543)
			(xy 408.246826 -316.872906) (xy 408.231242 -316.919587) (xy 408.208371 -316.963164) (xy 408.178806 -317.002508)
			(xy 408.143313 -317.0366) (xy 408.10281 -317.064556) (xy 408.058348 -317.085654) (xy 408.011077 -317.099346)
			(xy 407.962222 -317.105278) (xy 407.913047 -317.103297) (xy 407.864828 -317.093453) (xy 407.818812 -317.076001)
			(xy 407.776191 -317.051394) (xy 407.73807 -317.020269) (xy 407.705435 -316.983432) (xy 407.679132 -316.941836)
			(xy 407.659841 -316.89656) (xy 407.648064 -316.848776) (xy 407.644104 -316.799722) (xy 407.3271 -316.799722)
			(xy 407.326596 -316.82543) (xy 407.318553 -316.876212) (xy 407.302665 -316.925111) (xy 407.279322 -316.970923)
			(xy 407.249101 -317.012519) (xy 407.212745 -317.048875) (xy 407.171149 -317.079096) (xy 407.125337 -317.102439)
			(xy 407.076438 -317.118327) (xy 407.025656 -317.12637) (xy 406.97424 -317.12637) (xy 406.923458 -317.118327)
			(xy 406.874559 -317.102439) (xy 406.828747 -317.079096) (xy 406.787151 -317.048875) (xy 406.750795 -317.012519)
			(xy 406.720574 -316.970923) (xy 406.697231 -316.925111) (xy 406.681343 -316.876212) (xy 406.6733 -316.82543)
			(xy 406.354622 -316.82543) (xy 406.346906 -316.872906) (xy 406.331322 -316.919587) (xy 406.308451 -316.963164)
			(xy 406.278886 -317.002508) (xy 406.243393 -317.0366) (xy 406.20289 -317.064556) (xy 406.158428 -317.085654)
			(xy 406.111157 -317.099346) (xy 406.062302 -317.105278) (xy 406.013127 -317.103297) (xy 405.964908 -317.093453)
			(xy 405.918892 -317.076001) (xy 405.876271 -317.051394) (xy 405.83815 -317.020269) (xy 405.805515 -316.983432)
			(xy 405.779212 -316.941836) (xy 405.759921 -316.89656) (xy 405.748144 -316.848776) (xy 405.744184 -316.799722)
			(xy 405.42718 -316.799722) (xy 405.426676 -316.82543) (xy 405.418633 -316.876212) (xy 405.402745 -316.925111)
			(xy 405.379402 -316.970923) (xy 405.349181 -317.012519) (xy 405.312825 -317.048875) (xy 405.271229 -317.079096)
			(xy 405.225417 -317.102439) (xy 405.176518 -317.118327) (xy 405.125736 -317.12637) (xy 405.07432 -317.12637)
			(xy 405.023538 -317.118327) (xy 404.974639 -317.102439) (xy 404.928827 -317.079096) (xy 404.887231 -317.048875)
			(xy 404.850875 -317.012519) (xy 404.820654 -316.970923) (xy 404.797311 -316.925111) (xy 404.781423 -316.876212)
			(xy 404.77338 -316.82543) (xy 404.454448 -316.82543) (xy 404.446732 -316.872906) (xy 404.431148 -316.919587)
			(xy 404.408277 -316.963164) (xy 404.378712 -317.002508) (xy 404.343219 -317.0366) (xy 404.302716 -317.064556)
			(xy 404.258254 -317.085654) (xy 404.210983 -317.099346) (xy 404.162128 -317.105278) (xy 404.112953 -317.103297)
			(xy 404.064734 -317.093453) (xy 404.018718 -317.076001) (xy 403.976097 -317.051394) (xy 403.937976 -317.020269)
			(xy 403.905341 -316.983432) (xy 403.879038 -316.941836) (xy 403.859747 -316.89656) (xy 403.84797 -316.848776)
			(xy 403.84401 -316.799722) (xy 403.527006 -316.799722) (xy 403.526502 -316.82543) (xy 403.518459 -316.876212)
			(xy 403.502571 -316.925111) (xy 403.479228 -316.970923) (xy 403.449007 -317.012519) (xy 403.412651 -317.048875)
			(xy 403.371055 -317.079096) (xy 403.325243 -317.102439) (xy 403.276344 -317.118327) (xy 403.225562 -317.12637)
			(xy 403.174146 -317.12637) (xy 403.123364 -317.118327) (xy 403.074465 -317.102439) (xy 403.028653 -317.079096)
			(xy 402.987057 -317.048875) (xy 402.950701 -317.012519) (xy 402.92048 -316.970923) (xy 402.897137 -316.925111)
			(xy 402.881249 -316.876212) (xy 402.873206 -316.82543) (xy 402.554528 -316.82543) (xy 402.546812 -316.872906)
			(xy 402.531228 -316.919587) (xy 402.508357 -316.963164) (xy 402.478792 -317.002508) (xy 402.443299 -317.0366)
			(xy 402.402796 -317.064556) (xy 402.358334 -317.085654) (xy 402.311063 -317.099346) (xy 402.262208 -317.105278)
			(xy 402.213033 -317.103297) (xy 402.164814 -317.093453) (xy 402.118798 -317.076001) (xy 402.076177 -317.051394)
			(xy 402.038056 -317.020269) (xy 402.005421 -316.983432) (xy 401.979118 -316.941836) (xy 401.959827 -316.89656)
			(xy 401.94805 -316.848776) (xy 401.94409 -316.799722) (xy 401.627086 -316.799722) (xy 401.626582 -316.82543)
			(xy 401.618539 -316.876212) (xy 401.602651 -316.925111) (xy 401.579308 -316.970923) (xy 401.549087 -317.012519)
			(xy 401.512731 -317.048875) (xy 401.471135 -317.079096) (xy 401.425323 -317.102439) (xy 401.376424 -317.118327)
			(xy 401.325642 -317.12637) (xy 401.274226 -317.12637) (xy 401.223444 -317.118327) (xy 401.174545 -317.102439)
			(xy 401.128733 -317.079096) (xy 401.087137 -317.048875) (xy 401.050781 -317.012519) (xy 401.02056 -316.970923)
			(xy 400.997217 -316.925111) (xy 400.981329 -316.876212) (xy 400.973286 -316.82543) (xy 400.654608 -316.82543)
			(xy 400.646892 -316.872906) (xy 400.631308 -316.919587) (xy 400.608437 -316.963164) (xy 400.578872 -317.002508)
			(xy 400.543379 -317.0366) (xy 400.502876 -317.064556) (xy 400.458414 -317.085654) (xy 400.411143 -317.099346)
			(xy 400.362288 -317.105278) (xy 400.313113 -317.103297) (xy 400.264894 -317.093453) (xy 400.218878 -317.076001)
			(xy 400.176257 -317.051394) (xy 400.138136 -317.020269) (xy 400.105501 -316.983432) (xy 400.079198 -316.941836)
			(xy 400.059907 -316.89656) (xy 400.04813 -316.848776) (xy 400.04417 -316.799722) (xy 399.727166 -316.799722)
			(xy 399.726662 -316.82543) (xy 399.718619 -316.876212) (xy 399.702731 -316.925111) (xy 399.679388 -316.970923)
			(xy 399.649167 -317.012519) (xy 399.612811 -317.048875) (xy 399.571215 -317.079096) (xy 399.525403 -317.102439)
			(xy 399.476504 -317.118327) (xy 399.425722 -317.12637) (xy 399.374306 -317.12637) (xy 399.323524 -317.118327)
			(xy 399.274625 -317.102439) (xy 399.228813 -317.079096) (xy 399.187217 -317.048875) (xy 399.150861 -317.012519)
			(xy 399.12064 -316.970923) (xy 399.097297 -316.925111) (xy 399.081409 -316.876212) (xy 399.073366 -316.82543)
			(xy 398.754434 -316.82543) (xy 398.746718 -316.872906) (xy 398.731134 -316.919587) (xy 398.708263 -316.963164)
			(xy 398.678698 -317.002508) (xy 398.643205 -317.0366) (xy 398.602702 -317.064556) (xy 398.55824 -317.085654)
			(xy 398.510969 -317.099346) (xy 398.462114 -317.105278) (xy 398.412939 -317.103297) (xy 398.36472 -317.093453)
			(xy 398.318704 -317.076001) (xy 398.276083 -317.051394) (xy 398.237962 -317.020269) (xy 398.205327 -316.983432)
			(xy 398.179024 -316.941836) (xy 398.159733 -316.89656) (xy 398.147956 -316.848776) (xy 398.143996 -316.799722)
			(xy 397.805607 -316.799722) (xy 397.801439 -316.85003) (xy 397.789042 -316.898988) (xy 397.768757 -316.945238)
			(xy 397.741137 -316.987518) (xy 397.706934 -317.024677) (xy 397.667083 -317.055699) (xy 397.622669 -317.07974)
			(xy 397.574904 -317.096143) (xy 397.525091 -317.104461) (xy 397.49984 -317.10503) (xy 397.467328 -317.103252)
			(xy 397.45666 -317.102236) (xy 397.4465 -317.105538) (xy 397.441544 -317.107278) (xy 397.432445 -317.112523)
			(xy 397.428466 -317.115952) (xy 397.372078 -317.166244) (xy 397.364712 -317.174372) (xy 397.360982 -317.179914)
			(xy 397.356219 -317.192391) (xy 397.355314 -317.19901) (xy 397.35506 -317.204344) (xy 397.35506 -317.25616)
			(xy 397.355314 -317.257684) (xy 397.35602 -317.275648) (xy 397.353987 -317.311544) (xy 397.35125 -317.329312)
			(xy 397.349218 -317.34125) (xy 397.35252 -317.352172) (xy 397.354197 -317.357231) (xy 397.359321 -317.366575)
			(xy 397.36268 -317.370714) (xy 397.364458 -317.372746) (xy 397.420592 -317.43142) (xy 397.426942 -317.437008)
			(xy 397.430103 -317.43931) (xy 397.436993 -317.443009) (xy 397.440658 -317.444374) (xy 397.451326 -317.448184)
			(xy 397.463518 -317.446914) (xy 397.472562 -317.445867) (xy 397.490736 -317.444726) (xy 397.49984 -317.444628)
			(xy 397.523828 -317.445102) (xy 397.571213 -317.452613) (xy 397.616839 -317.467444) (xy 397.659584 -317.489231)
			(xy 397.698394 -317.517435) (xy 397.732314 -317.551364) (xy 397.760509 -317.590181) (xy 397.782285 -317.632931)
			(xy 397.797105 -317.678561) (xy 397.804604 -317.725948) (xy 397.805148 -317.749936) (xy 397.80505 -317.75904)
			(xy 397.803907 -317.777213) (xy 397.802862 -317.786258) (xy 397.801592 -317.79845) (xy 397.805402 -317.809372)
			(xy 397.807568 -317.81495) (xy 397.814118 -317.824959) (xy 397.818356 -317.829184) (xy 397.877284 -317.885572)
			(xy 397.880332 -317.888366) (xy 397.884128 -317.891266) (xy 397.892566 -317.89574) (xy 397.897096 -317.897256)
			(xy 397.908526 -317.900812) (xy 397.920464 -317.89878) (xy 397.933952 -317.89665) (xy 397.961166 -317.894363)
			(xy 397.97482 -317.894208) (xy 397.988474 -317.894368) (xy 398.015687 -317.896654) (xy 398.029176 -317.89878)
			(xy 398.041114 -317.900812) (xy 398.052544 -317.897256) (xy 398.057077 -317.895747) (xy 398.065522 -317.89128)
			(xy 398.069308 -317.888366) (xy 398.072356 -317.885572) (xy 398.131284 -317.829184) (xy 398.13551 -317.824951)
			(xy 398.142044 -317.814937) (xy 398.144238 -317.809372) (xy 398.148048 -317.79845) (xy 398.146778 -317.786258)
			(xy 398.145729 -317.777214) (xy 398.144583 -317.75904) (xy 398.144492 -317.749936) (xy 398.144975 -317.725114)
			(xy 398.153001 -317.676125) (xy 398.168847 -317.629079) (xy 398.192095 -317.585216) (xy 398.222134 -317.545692)
			(xy 398.258171 -317.51155) (xy 398.299257 -317.483687) (xy 398.34431 -317.462838) (xy 398.392143 -317.449553)
			(xy 398.441494 -317.444182) (xy 398.491064 -317.446866) (xy 398.539547 -317.457534) (xy 398.585666 -317.475905)
			(xy 398.628204 -317.501496) (xy 398.666042 -317.533632) (xy 398.698183 -317.571466) (xy 398.723779 -317.614002)
			(xy 398.742156 -317.660118) (xy 398.75283 -317.7086) (xy 398.755519 -317.75817) (xy 398.750154 -317.807522)
			(xy 398.736874 -317.855356) (xy 398.716031 -317.900411) (xy 398.688173 -317.941501) (xy 398.654034 -317.977542)
			(xy 398.614514 -318.007585) (xy 398.570655 -318.030839) (xy 398.52361 -318.046691) (xy 398.474621 -318.054722)
			(xy 398.4498 -318.055244) (xy 398.440696 -318.055147) (xy 398.422522 -318.054006) (xy 398.413478 -318.052958)
			(xy 398.401286 -318.051688) (xy 398.390364 -318.055498) (xy 398.384784 -318.057661) (xy 398.374769 -318.064206)
			(xy 398.370552 -318.068452) (xy 398.314164 -318.12738) (xy 398.31137 -318.130428) (xy 398.308468 -318.134222)
			(xy 398.30399 -318.14266) (xy 398.30248 -318.147192) (xy 398.298924 -318.158622) (xy 398.300956 -318.17056)
			(xy 398.303086 -318.184048) (xy 398.305373 -318.211262) (xy 398.305528 -318.224916) (xy 398.305528 -318.295274)
			(xy 398.305782 -318.299084) (xy 398.305782 -318.299592) (xy 398.306747 -318.307693) (xy 398.313103 -318.322708)
			(xy 398.318228 -318.329056) (xy 398.322292 -318.33312) (xy 398.37868 -318.383666) (xy 398.382687 -318.387055)
			(xy 398.39178 -318.392291) (xy 398.396714 -318.39408) (xy 398.406874 -318.397382) (xy 398.417796 -318.396366)
			(xy 398.4498 -318.394588) (xy 398.475524 -318.39512) (xy 398.526245 -318.403746) (xy 398.574801 -318.420755)
			(xy 398.619819 -318.445664) (xy 398.660022 -318.477768) (xy 398.694274 -318.516158) (xy 398.721603 -318.559748)
			(xy 398.741238 -318.607303) (xy 398.752621 -318.657477) (xy 398.7546 -318.683132) (xy 398.755108 -318.693038)
			(xy 398.759172 -318.701674) (xy 398.761295 -318.70599) (xy 398.766926 -318.713787) (xy 398.770348 -318.717168)
			(xy 398.821148 -318.765174) (xy 398.828417 -318.771516) (xy 398.846309 -318.778687) (xy 398.855946 -318.779144)
		)
		(stroke
			(width 0)
			(type solid)
		)
		(fill yes)
		(layer "In11.Cu")
		(net "P1V25_PEX3")
	)
)
